(kicad_pcb
	(version 20260206)
	(generator "pcbnew")
	(generator_version "10.0")
	(general
		(thickness 1.6)
		(legacy_teardrops no)
	)
	(paper "A4")
	(layers
		(0 "F.Cu" signal "TOP")
		(4 "In1.Cu" signal "GND")
		(6 "In2.Cu" signal "IN1")
		(8 "In3.Cu" signal "GND1")
		(10 "In4.Cu" signal "IN2")
		(12 "In5.Cu" signal "GND2")
		(14 "In6.Cu" signal "IN3")
		(16 "In7.Cu" signal "GND3")
		(18 "In8.Cu" signal "VCC")
		(20 "In9.Cu" signal "VCC1")
		(22 "In10.Cu" signal "GND4")
		(24 "In11.Cu" signal "IN4")
		(26 "In12.Cu" signal "GND5")
		(28 "In13.Cu" signal "IN5")
		(30 "In14.Cu" signal "GND6")
		(32 "In15.Cu" signal "IN6")
		(34 "In16.Cu" signal "GND7")
		(2 "B.Cu" signal "BOTTOM")
		(9 "F.Adhes" user "F.Adhesive")
		(11 "B.Adhes" user "B.Adhesive")
		(13 "F.Paste" user "Package Geometry/Pastemask Top")
		(15 "B.Paste" user "Package Geometry/Pastemask Bottom")
		(5 "F.SilkS" user "Ref Des/Silkscreen Top")
		(7 "B.SilkS" user "Ref Des/Silkscreen Bottom")
		(1 "F.Mask" user "Board Geometry/Soldermask Top")
		(3 "B.Mask" user "Board Geometry/Soldermask Bottom")
		(17 "Dwgs.User" user "User.Drawings")
		(19 "Cmts.User" user "User.Comments")
		(21 "Eco1.User" user "User.Eco1")
		(23 "Eco2.User" user "User.Eco2")
		(25 "Edge.Cuts" user "Board Geometry/Outline")
		(27 "Margin" user)
		(31 "F.CrtYd" user "Package Geometry/Place Bound Top")
		(29 "B.CrtYd" user "Package Geometry/Place Bound Bottom")
		(35 "F.Fab" user "Ref Des/Assembly Top")
		(33 "B.Fab" user "Ref Des/Assembly Bottom")
	)
	(setup
		(pad_to_mask_clearance 0)
		(allow_soldermask_bridges_in_footprints no)
		(tenting
			(front yes)
			(back yes)
		)
		(covering
			(front no)
			(back no)
		)
		(plugging
			(front no)
			(back no)
		)
		(capping no)
		(filling no)
		(pcbplotparams
			(layerselection 0x00000000_00000000_55555555_5755f5ff)
			(plot_on_all_layers_selection 0x00000000_00000000_00000000_00000000)
			(disableapertmacros no)
			(usegerberextensions no)
			(usegerberattributes yes)
			(usegerberadvancedattributes yes)
			(creategerberjobfile yes)
			(dashed_line_dash_ratio 12)
			(dashed_line_gap_ratio 3)
			(svgprecision 4)
			(plotframeref no)
			(mode 1)
			(useauxorigin no)
			(pdf_front_fp_property_popups yes)
			(pdf_back_fp_property_popups yes)
			(pdf_metadata yes)
			(pdf_single_document no)
			(dxfpolygonmode yes)
			(dxfimperialunits yes)
			(dxfusepcbnewfont yes)
			(psnegative no)
			(psa4output no)
			(plot_black_and_white yes)
			(sketchpadsonfab no)
			(plotpadnumbers no)
			(hidednponfab no)
			(sketchdnponfab yes)
			(crossoutdnponfab yes)
			(subtractmaskfromsilk no)
			(outputformat 1)
			(mirror no)
			(drillshape 1)
			(scaleselection 1)
			(outputdirectory "")
		)
	)
	(gr_poly
		(pts
			(xy 380.366778 -263.89457) (xy 380.372724 -263.894383) (xy 380.384279 -263.891564) (xy 380.389638 -263.888982)
			(xy 380.396699 -263.885087) (xy 380.408093 -263.87369) (xy 380.41199 -263.86663) (xy 380.45009 -263.7917)
			(xy 380.452994 -263.785381) (xy 380.455568 -263.771719) (xy 380.45517 -263.764776) (xy 380.454916 -263.760966)
			(xy 380.437233 -263.739363) (xy 380.408986 -263.691214) (xy 380.389646 -263.638849) (xy 380.379815 -263.583899)
			(xy 380.379224 -263.555988) (xy 380.379711 -263.531178) (xy 380.387473 -263.48217) (xy 380.402806 -263.43498)
			(xy 380.425333 -263.390769) (xy 380.454498 -263.350626) (xy 380.489584 -263.31554) (xy 380.529727 -263.286375)
			(xy 380.573938 -263.263848) (xy 380.621128 -263.248515) (xy 380.670136 -263.240753) (xy 380.719756 -263.240753)
			(xy 380.768764 -263.248515) (xy 380.815954 -263.263848) (xy 380.860165 -263.286375) (xy 380.900308 -263.31554)
			(xy 380.935394 -263.350626) (xy 380.964559 -263.390769) (xy 380.987086 -263.43498) (xy 381.002419 -263.48217)
			(xy 381.010181 -263.531178) (xy 381.010668 -263.555988) (xy 381.010115 -263.582058) (xy 381.001505 -263.633483)
			(xy 380.984551 -263.682791) (xy 380.959714 -263.728637) (xy 380.94412 -263.749536) (xy 380.939804 -263.755546)
			(xy 380.934522 -263.769359) (xy 380.933706 -263.776714) (xy 380.933452 -263.779) (xy 380.977902 -263.86663)
			(xy 380.981795 -263.873692) (xy 380.99319 -263.885092) (xy 381.000254 -263.888982) (xy 381.011176 -263.89457)
			(xy 381.300482 -263.89457) (xy 381.311912 -263.8933) (xy 381.323342 -263.89076) (xy 381.334264 -263.886696)
			(xy 381.34417 -263.88187) (xy 381.390144 -263.790938) (xy 381.394323 -263.78186) (xy 381.395891 -263.761953)
			(xy 381.393192 -263.75233) (xy 381.387858 -263.73582) (xy 381.38354 -263.72947) (xy 381.370775 -263.710241)
			(xy 381.350562 -263.66875) (xy 381.336821 -263.62469) (xy 381.329865 -263.579064) (xy 381.329438 -263.555988)
			(xy 381.32996 -263.530733) (xy 381.338273 -263.480911) (xy 381.354674 -263.433137) (xy 381.378715 -263.388714)
			(xy 381.409739 -263.348854) (xy 381.446901 -263.314644) (xy 381.489187 -263.287018) (xy 381.535443 -263.266728)
			(xy 381.584408 -263.254328) (xy 381.634746 -263.250157) (xy 381.685084 -263.254328) (xy 381.734049 -263.266728)
			(xy 381.780305 -263.287018) (xy 381.822591 -263.314644) (xy 381.859753 -263.348854) (xy 381.890777 -263.388714)
			(xy 381.914818 -263.433137) (xy 381.931219 -263.480911) (xy 381.939532 -263.530733) (xy 381.940054 -263.555988)
			(xy 381.939631 -263.579065) (xy 381.93268 -263.624691) (xy 381.918936 -263.66875) (xy 381.898711 -263.710236)
			(xy 381.885952 -263.72947) (xy 381.881634 -263.73582) (xy 381.8763 -263.75233) (xy 381.87372 -263.761964)
			(xy 381.875286 -263.781829) (xy 381.879348 -263.790938) (xy 381.917702 -263.86663) (xy 381.921628 -263.873783)
			(xy 381.933149 -263.885323) (xy 381.940308 -263.889236) (xy 381.95123 -263.89457) (xy 382.240536 -263.89457)
			(xy 382.251966 -263.8933) (xy 382.263396 -263.89076) (xy 382.274318 -263.886696) (xy 382.284224 -263.88187)
			(xy 382.330198 -263.790938) (xy 382.33438 -263.781861) (xy 382.335949 -263.761952) (xy 382.333246 -263.75233)
			(xy 382.327912 -263.73582) (xy 382.323594 -263.72947) (xy 382.310831 -263.71024) (xy 382.290621 -263.668749)
			(xy 382.276882 -263.624689) (xy 382.269927 -263.579064) (xy 382.269492 -263.555988) (xy 382.270014 -263.530733)
			(xy 382.278327 -263.480911) (xy 382.294728 -263.433137) (xy 382.318769 -263.388714) (xy 382.349793 -263.348854)
			(xy 382.386955 -263.314644) (xy 382.429241 -263.287018) (xy 382.475497 -263.266728) (xy 382.524462 -263.254328)
			(xy 382.5748 -263.250157) (xy 382.625138 -263.254328) (xy 382.674103 -263.266728) (xy 382.720359 -263.287018)
			(xy 382.762645 -263.314644) (xy 382.799807 -263.348854) (xy 382.830831 -263.388714) (xy 382.854872 -263.433137)
			(xy 382.871273 -263.480911) (xy 382.879586 -263.530733) (xy 382.880108 -263.555988) (xy 382.879685 -263.579065)
			(xy 382.872736 -263.624692) (xy 382.858993 -263.668752) (xy 382.838771 -263.71024) (xy 382.826006 -263.72947)
			(xy 382.821688 -263.73582) (xy 382.816354 -263.75233) (xy 382.813772 -263.761964) (xy 382.815339 -263.781829)
			(xy 382.819402 -263.790938) (xy 382.857756 -263.86663) (xy 382.861685 -263.873779) (xy 382.873212 -263.885309)
			(xy 382.880362 -263.889236) (xy 382.891284 -263.89457) (xy 383.18059 -263.89457) (xy 383.19202 -263.8933)
			(xy 383.20345 -263.89076) (xy 383.214372 -263.886696) (xy 383.224278 -263.88187) (xy 383.270252 -263.790938)
			(xy 383.274431 -263.78186) (xy 383.275998 -263.761953) (xy 383.2733 -263.75233) (xy 383.267966 -263.73582)
			(xy 383.263648 -263.72947) (xy 383.250886 -263.71024) (xy 383.230679 -263.668747) (xy 383.216943 -263.624688)
			(xy 383.209989 -263.579063) (xy 383.209546 -263.555988) (xy 383.210068 -263.530733) (xy 383.218381 -263.480911)
			(xy 383.234782 -263.433137) (xy 383.258823 -263.388714) (xy 383.289847 -263.348854) (xy 383.327009 -263.314644)
			(xy 383.369295 -263.287018) (xy 383.415551 -263.266728) (xy 383.464516 -263.254328) (xy 383.514854 -263.250157)
			(xy 383.565192 -263.254328) (xy 383.614157 -263.266728) (xy 383.660413 -263.287018) (xy 383.702699 -263.314644)
			(xy 383.739861 -263.348854) (xy 383.770885 -263.388714) (xy 383.794926 -263.433137) (xy 383.811327 -263.480911)
			(xy 383.81964 -263.530733) (xy 383.820162 -263.555988) (xy 383.819739 -263.579065) (xy 383.812789 -263.624692)
			(xy 383.799044 -263.668751) (xy 383.77882 -263.710237) (xy 383.76606 -263.72947) (xy 383.761742 -263.73582)
			(xy 383.756408 -263.75233) (xy 383.753827 -263.761964) (xy 383.755394 -263.781829) (xy 383.759456 -263.790938)
			(xy 383.79781 -263.86663) (xy 383.801736 -263.873782) (xy 383.813258 -263.885321) (xy 383.820416 -263.889236)
			(xy 383.831338 -263.89457) (xy 384.120644 -263.89457) (xy 384.132074 -263.8933) (xy 384.143504 -263.89076)
			(xy 384.154426 -263.886696) (xy 384.164332 -263.88187) (xy 384.210306 -263.790938) (xy 384.214488 -263.781861)
			(xy 384.216057 -263.761952) (xy 384.213354 -263.75233) (xy 384.20802 -263.73582) (xy 384.203702 -263.72947)
			(xy 384.190938 -263.71024) (xy 384.170728 -263.668749) (xy 384.156989 -263.624689) (xy 384.150033 -263.579064)
			(xy 384.1496 -263.555988) (xy 384.150122 -263.530733) (xy 384.158435 -263.480911) (xy 384.174836 -263.433137)
			(xy 384.198877 -263.388714) (xy 384.229901 -263.348854) (xy 384.267063 -263.314644) (xy 384.309349 -263.287018)
			(xy 384.355605 -263.266728) (xy 384.40457 -263.254328) (xy 384.454908 -263.250157) (xy 384.505246 -263.254328)
			(xy 384.554211 -263.266728) (xy 384.600467 -263.287018) (xy 384.642753 -263.314644) (xy 384.679915 -263.348854)
			(xy 384.710939 -263.388714) (xy 384.73498 -263.433137) (xy 384.751381 -263.480911) (xy 384.759694 -263.530733)
			(xy 384.760216 -263.555988) (xy 384.759793 -263.579065) (xy 384.752844 -263.624692) (xy 384.739101 -263.668753)
			(xy 384.71888 -263.710241) (xy 384.706114 -263.72947) (xy 384.701796 -263.73582) (xy 384.696462 -263.75233)
			(xy 384.69388 -263.761964) (xy 384.695447 -263.781829) (xy 384.69951 -263.790938) (xy 384.737864 -263.86663)
			(xy 384.741793 -263.873778) (xy 384.753322 -263.885307) (xy 384.76047 -263.889236) (xy 384.771392 -263.89457)
			(xy 386.000498 -263.89457) (xy 386.011928 -263.8933) (xy 386.023358 -263.89076) (xy 386.03428 -263.886696)
			(xy 386.044186 -263.88187) (xy 386.09016 -263.790938) (xy 386.094339 -263.78186) (xy 386.095906 -263.761953)
			(xy 386.093208 -263.75233) (xy 386.087874 -263.73582) (xy 386.083556 -263.72947) (xy 386.070794 -263.71024)
			(xy 386.050587 -263.668748) (xy 386.03685 -263.624688) (xy 386.029895 -263.579064) (xy 386.029454 -263.555988)
			(xy 386.029976 -263.530733) (xy 386.038289 -263.480911) (xy 386.05469 -263.433137) (xy 386.078731 -263.388714)
			(xy 386.109755 -263.348854) (xy 386.146917 -263.314644) (xy 386.189203 -263.287018) (xy 386.235459 -263.266728)
			(xy 386.284424 -263.254328) (xy 386.334762 -263.250157) (xy 386.3851 -263.254328) (xy 386.434065 -263.266728)
			(xy 386.480321 -263.287018) (xy 386.522607 -263.314644) (xy 386.559769 -263.348854) (xy 386.590793 -263.388714)
			(xy 386.614834 -263.433137) (xy 386.631235 -263.480911) (xy 386.639548 -263.530733) (xy 386.64007 -263.555988)
			(xy 386.639647 -263.579065) (xy 386.632697 -263.624692) (xy 386.618953 -263.668751) (xy 386.598728 -263.710237)
			(xy 386.585968 -263.72947) (xy 386.58165 -263.73582) (xy 386.576316 -263.75233) (xy 386.573735 -263.761964)
			(xy 386.575301 -263.781829) (xy 386.579364 -263.790938) (xy 386.617718 -263.86663) (xy 386.621644 -263.873782)
			(xy 386.633168 -263.885319) (xy 386.640324 -263.889236) (xy 386.651246 -263.89457) (xy 386.940552 -263.89457)
			(xy 386.951982 -263.8933) (xy 386.963412 -263.89076) (xy 386.974334 -263.886696) (xy 386.98424 -263.88187)
			(xy 387.030214 -263.790938) (xy 387.034395 -263.781861) (xy 387.035964 -263.761952) (xy 387.033262 -263.75233)
			(xy 387.027928 -263.73582) (xy 387.02361 -263.72947) (xy 387.010846 -263.710241) (xy 386.990635 -263.668749)
			(xy 386.976895 -263.624689) (xy 386.96994 -263.579064) (xy 386.969508 -263.555988) (xy 386.97003 -263.530733)
			(xy 386.978343 -263.480911) (xy 386.994744 -263.433137) (xy 387.018785 -263.388714) (xy 387.049809 -263.348854)
			(xy 387.086971 -263.314644) (xy 387.129257 -263.287018) (xy 387.175513 -263.266728) (xy 387.224478 -263.254328)
			(xy 387.274816 -263.250157) (xy 387.325154 -263.254328) (xy 387.374119 -263.266728) (xy 387.420375 -263.287018)
			(xy 387.462661 -263.314644) (xy 387.499823 -263.348854) (xy 387.530847 -263.388714) (xy 387.554888 -263.433137)
			(xy 387.571289 -263.480911) (xy 387.579602 -263.530733) (xy 387.580124 -263.555988) (xy 387.579701 -263.579065)
			(xy 387.572752 -263.624693) (xy 387.55901 -263.668753) (xy 387.538789 -263.710241) (xy 387.526022 -263.72947)
			(xy 387.521704 -263.73582) (xy 387.51637 -263.75233) (xy 387.51379 -263.761965) (xy 387.515355 -263.781829)
			(xy 387.519418 -263.790938) (xy 387.557772 -263.86663) (xy 387.561702 -263.873778) (xy 387.573231 -263.885305)
			(xy 387.580378 -263.889236) (xy 387.5913 -263.89457) (xy 387.898386 -263.89457) (xy 387.909308 -263.889236)
			(xy 387.916449 -263.885299) (xy 387.927961 -263.873764) (xy 387.931914 -263.86663) (xy 387.970268 -263.790938)
			(xy 387.974446 -263.78186) (xy 387.976013 -263.761953) (xy 387.973316 -263.75233) (xy 387.967982 -263.73582)
			(xy 387.963664 -263.72947) (xy 387.950902 -263.71024) (xy 387.930694 -263.668748) (xy 387.916956 -263.624688)
			(xy 387.910002 -263.579064) (xy 387.909562 -263.555988) (xy 387.910033 -263.531997) (xy 387.917541 -263.484605)
			(xy 387.932369 -263.43897) (xy 387.954153 -263.396217) (xy 387.982356 -263.357398) (xy 388.016284 -263.323467)
			(xy 388.055102 -263.295262) (xy 388.097854 -263.273476) (xy 388.143487 -263.258645) (xy 388.190879 -263.251135)
			(xy 388.21487 -263.25068) (xy 388.238658 -263.25111) (xy 388.285665 -263.258443) (xy 388.330964 -263.272984)
			(xy 388.373458 -263.294379) (xy 388.412115 -263.322111) (xy 388.446 -263.355506) (xy 388.460488 -263.374378)
			(xy 388.46615 -263.381459) (xy 388.481292 -263.391406) (xy 388.49895 -263.39546) (xy 388.507986 -263.394698)
			(xy 388.607554 -263.38149) (xy 388.629398 -263.364472) (xy 388.634478 -263.351518) (xy 388.645627 -263.324178)
			(xy 388.672889 -263.2718) (xy 388.705524 -263.22259) (xy 388.743167 -263.177098) (xy 388.764018 -263.156192)
			(xy 388.764272 -263.155938) (xy 388.764526 -263.155684) (xy 388.771378 -263.148288) (xy 388.779118 -263.129689)
			(xy 388.779512 -263.119616) (xy 388.779512 -263.099296) (xy 388.779023 -263.089288) (xy 388.771363 -263.070796)
			(xy 388.757211 -263.056641) (xy 388.73872 -263.048978) (xy 388.728712 -263.048496) (xy 388.725664 -263.048496)
			(xy 388.722362 -263.049004) (xy 388.713507 -263.050031) (xy 388.695716 -263.051175) (xy 388.686802 -263.05129)
			(xy 388.6835 -263.05129) (xy 388.659576 -263.050723) (xy 388.612342 -263.043056) (xy 388.566883 -263.028113)
			(xy 388.524312 -263.006261) (xy 388.485672 -262.978034) (xy 388.451908 -262.944125) (xy 388.423849 -262.905363)
			(xy 388.402181 -262.862698) (xy 388.387434 -262.817175) (xy 388.379971 -262.769908) (xy 388.379462 -262.745982)
			(xy 388.379936 -262.721644) (xy 388.387659 -262.673584) (xy 388.402907 -262.627357) (xy 388.425294 -262.584134)
			(xy 388.454252 -262.545008) (xy 388.48905 -262.51097) (xy 388.528805 -262.482883) (xy 388.572512 -262.461456)
			(xy 388.619065 -262.447233) (xy 388.643114 -262.443468) (xy 388.655381 -262.441076) (xy 388.675593 -262.426423)
			(xy 388.681722 -262.415528) (xy 388.71779 -262.341614) (xy 388.722658 -262.330056) (xy 388.721737 -262.30502)
			(xy 388.716012 -262.293862) (xy 388.671308 -262.2169) (xy 388.660836 -262.198421) (xy 388.642397 -262.160154)
			(xy 388.634478 -262.140446) (xy 388.629398 -262.127492) (xy 388.607808 -262.110474) (xy 388.51713 -262.098536)
			(xy 388.509573 -262.097794) (xy 388.494596 -262.100256) (xy 388.487666 -262.103362) (xy 388.466076 -262.114284)
			(xy 388.457694 -262.121142) (xy 388.454138 -262.12546) (xy 388.439587 -262.143188) (xy 388.406068 -262.174492)
			(xy 388.368241 -262.200425) (xy 388.326957 -262.220403) (xy 388.283149 -262.233976) (xy 388.237802 -262.240837)
			(xy 388.21487 -262.241284) (xy 388.189618 -262.24076) (xy 388.139804 -262.232443) (xy 388.092038 -262.216041)
			(xy 388.047624 -262.192001) (xy 388.007771 -262.160979) (xy 387.973568 -262.123821) (xy 387.945946 -262.08154)
			(xy 387.92566 -262.035289) (xy 387.913263 -261.986331) (xy 387.909093 -261.936) (xy 387.913263 -261.885669)
			(xy 387.92566 -261.836711) (xy 387.945946 -261.79046) (xy 387.973568 -261.748179) (xy 388.007771 -261.711021)
			(xy 388.047624 -261.679999) (xy 388.092038 -261.655959) (xy 388.139804 -261.639557) (xy 388.189618 -261.63124)
			(xy 388.21487 -261.630668) (xy 388.238658 -261.631097) (xy 388.285666 -261.638431) (xy 388.330965 -261.652971)
			(xy 388.373459 -261.674366) (xy 388.412118 -261.702097) (xy 388.446004 -261.735491) (xy 388.460488 -261.754366)
			(xy 388.466149 -261.761448) (xy 388.481291 -261.771398) (xy 388.49895 -261.775452) (xy 388.507986 -261.774686)
			(xy 388.607554 -261.761478) (xy 388.629398 -261.74446) (xy 388.634478 -261.731506) (xy 388.645628 -261.704166)
			(xy 388.67289 -261.651789) (xy 388.705526 -261.60258) (xy 388.74317 -261.557088) (xy 388.764018 -261.53618)
			(xy 388.764272 -261.535926) (xy 388.764526 -261.535672) (xy 388.771376 -261.528276) (xy 388.779112 -261.509677)
			(xy 388.779512 -261.499604) (xy 388.779512 -261.479284) (xy 388.779021 -261.469278) (xy 388.771359 -261.450789)
			(xy 388.757207 -261.436639) (xy 388.738718 -261.428978) (xy 388.728712 -261.428484) (xy 388.725664 -261.428484)
			(xy 388.722362 -261.428992) (xy 388.713507 -261.430019) (xy 388.695716 -261.431163) (xy 388.686802 -261.431278)
			(xy 388.6835 -261.431278) (xy 388.659577 -261.430711) (xy 388.612343 -261.423043) (xy 388.566885 -261.408101)
			(xy 388.524315 -261.386248) (xy 388.485675 -261.358022) (xy 388.451913 -261.324112) (xy 388.423855 -261.28535)
			(xy 388.402188 -261.242685) (xy 388.387444 -261.197162) (xy 388.379982 -261.149896) (xy 388.379462 -261.12597)
			(xy 388.380013 -261.100046) (xy 388.388775 -261.048943) (xy 388.406041 -261.000054) (xy 388.431317 -260.954784)
			(xy 388.463875 -260.914432) (xy 388.50278 -260.88016) (xy 388.546915 -260.85295) (xy 388.595011 -260.833585)
			(xy 388.645687 -260.822621) (xy 388.671562 -260.820916) (xy 388.680706 -260.820408) (xy 388.706868 -260.809486)
			(xy 388.71139 -260.807424) (xy 388.719577 -260.801791) (xy 388.723124 -260.79831) (xy 388.76478 -260.756146)
			(xy 388.765288 -260.755384) (xy 388.765542 -260.755384) (xy 388.771927 -260.748064) (xy 388.779115 -260.730037)
			(xy 388.779512 -260.720332) (xy 388.779512 -256.913126) (xy 388.779058 -256.90299) (xy 388.771203 -256.8843)
			(xy 388.756742 -256.870092) (xy 388.747508 -256.865882) (xy 388.647432 -256.826258) (xy 388.617206 -256.832862)
			(xy 388.606284 -256.844292) (xy 388.588885 -256.861935) (xy 388.549431 -256.89191) (xy 388.505658 -256.915126)
			(xy 388.458712 -256.930975) (xy 388.409824 -256.939042) (xy 388.38505 -256.939542) (xy 388.381748 -256.939542)
			(xy 388.372068 -256.93944) (xy 388.35275 -256.938169) (xy 388.34314 -256.937002) (xy 388.327646 -256.934208)
			(xy 388.304673 -256.929398) (xy 388.260454 -256.913669) (xy 388.219164 -256.891356) (xy 388.181777 -256.862984)
			(xy 388.149175 -256.829223) (xy 388.122125 -256.790869) (xy 388.101266 -256.748826) (xy 388.087089 -256.704085)
			(xy 388.079929 -256.657701) (xy 388.079488 -256.634234) (xy 388.079955 -256.609607) (xy 388.087853 -256.56099)
			(xy 388.103451 -256.51427) (xy 388.126344 -256.47066) (xy 388.155939 -256.431288) (xy 388.191468 -256.397175)
			(xy 388.232011 -256.369206) (xy 388.276517 -256.348106) (xy 388.323832 -256.334421) (xy 388.34822 -256.330958)
			(xy 388.348982 -256.330958) (xy 388.357763 -256.32941) (xy 388.373568 -256.321184) (xy 388.385614 -256.308057)
			(xy 388.389368 -256.29997) (xy 388.427468 -256.207514) (xy 388.423658 -256.18059) (xy 388.415022 -256.169668)
			(xy 388.390466 -256.137141) (xy 388.35004 -256.066376) (xy 388.334504 -256.028698) (xy 388.329424 -256.015744)
			(xy 388.307834 -255.998726) (xy 388.217156 -255.986788) (xy 388.209598 -255.986042) (xy 388.194617 -255.988495)
			(xy 388.187692 -255.991614) (xy 388.166102 -256.002536) (xy 388.15772 -256.009394) (xy 388.154164 -256.013712)
			(xy 388.139615 -256.031444) (xy 388.106099 -256.062755) (xy 388.068273 -256.088696) (xy 388.026989 -256.108681)
			(xy 387.983179 -256.122259) (xy 387.937829 -256.129126) (xy 387.914896 -256.129536) (xy 387.889639 -256.129014)
			(xy 387.839813 -256.120699) (xy 387.792035 -256.104296) (xy 387.747609 -256.080254) (xy 387.707746 -256.049226)
			(xy 387.673533 -256.012061) (xy 387.645904 -255.969772) (xy 387.625613 -255.923511) (xy 387.613212 -255.874542)
			(xy 387.609041 -255.8242) (xy 387.613212 -255.773858) (xy 387.625613 -255.724889) (xy 387.645904 -255.678628)
			(xy 387.673533 -255.636339) (xy 387.707746 -255.599174) (xy 387.747609 -255.568146) (xy 387.792035 -255.544104)
			(xy 387.839813 -255.527701) (xy 387.889639 -255.519386) (xy 387.914896 -255.51892) (xy 387.938683 -255.519352)
			(xy 387.985687 -255.52669) (xy 388.030982 -255.541234) (xy 388.07347 -255.562634) (xy 388.112122 -255.590369)
			(xy 388.146 -255.623767) (xy 388.160514 -255.642618) (xy 388.166169 -255.649715) (xy 388.181309 -255.659697)
			(xy 388.198978 -255.663781) (xy 388.208012 -255.662938) (xy 388.307834 -255.64973) (xy 388.329424 -255.632712)
			(xy 388.334504 -255.619758) (xy 388.342426 -255.600051) (xy 388.360861 -255.561782) (xy 388.371334 -255.543304)
			(xy 388.416038 -255.466342) (xy 388.42181 -255.455193) (xy 388.422748 -255.430135) (xy 388.417816 -255.41859)
			(xy 388.37616 -255.333246) (xy 388.35584 -255.318514) (xy 388.34314 -255.316736) (xy 388.319089 -255.312952)
			(xy 388.27252 -255.298754) (xy 388.228795 -255.277343) (xy 388.189023 -255.249265) (xy 388.154211 -255.21523)
			(xy 388.125242 -255.176101) (xy 388.102851 -255.132871) (xy 388.087604 -255.086635) (xy 388.07989 -255.038565)
			(xy 388.079488 -255.014222) (xy 388.079956 -254.989595) (xy 388.087856 -254.94098) (xy 388.103455 -254.894262)
			(xy 388.126348 -254.850653) (xy 388.155943 -254.811283) (xy 388.191473 -254.777172) (xy 388.232015 -254.749204)
			(xy 388.27652 -254.728105) (xy 388.323834 -254.714421) (xy 388.34822 -254.710946) (xy 388.348982 -254.710946)
			(xy 388.357763 -254.709397) (xy 388.373566 -254.701171) (xy 388.38561 -254.688043) (xy 388.389368 -254.679958)
			(xy 388.427468 -254.587502) (xy 388.423658 -254.560578) (xy 388.415022 -254.549656) (xy 388.390466 -254.517129)
			(xy 388.350043 -254.446363) (xy 388.334504 -254.408686) (xy 388.329424 -254.395732) (xy 388.307834 -254.378714)
			(xy 388.217156 -254.366776) (xy 388.209598 -254.36603) (xy 388.194617 -254.368482) (xy 388.187692 -254.371602)
			(xy 388.166102 -254.382524) (xy 388.15772 -254.389382) (xy 388.154164 -254.3937) (xy 388.139615 -254.411433)
			(xy 388.1061 -254.442745) (xy 388.068274 -254.468687) (xy 388.02699 -254.488672) (xy 387.983179 -254.502251)
			(xy 387.937829 -254.509118) (xy 387.914896 -254.509524) (xy 387.88964 -254.509002) (xy 387.839816 -254.500687)
			(xy 387.79204 -254.484285) (xy 387.747615 -254.460243) (xy 387.707754 -254.429218) (xy 387.673543 -254.392054)
			(xy 387.645915 -254.349766) (xy 387.625624 -254.303508) (xy 387.613224 -254.25454) (xy 387.609053 -254.2042)
			(xy 387.613224 -254.15386) (xy 387.625624 -254.104892) (xy 387.645915 -254.058634) (xy 387.673543 -254.016346)
			(xy 387.707754 -253.979182) (xy 387.747615 -253.948157) (xy 387.79204 -253.924115) (xy 387.839816 -253.907713)
			(xy 387.88964 -253.899398) (xy 387.914896 -253.898908) (xy 387.938683 -253.89934) (xy 387.985687 -253.906677)
			(xy 388.030983 -253.921222) (xy 388.073471 -253.94262) (xy 388.112124 -253.970355) (xy 388.146003 -254.003753)
			(xy 388.160514 -254.022606) (xy 388.166168 -254.029705) (xy 388.181308 -254.039689) (xy 388.198978 -254.043774)
			(xy 388.208012 -254.042926) (xy 388.307834 -254.029718) (xy 388.329424 -254.0127) (xy 388.334504 -253.999746)
			(xy 388.342427 -253.980039) (xy 388.360862 -253.941771) (xy 388.371334 -253.923292) (xy 388.416038 -253.84633)
			(xy 388.421807 -253.83518) (xy 388.42274 -253.810126) (xy 388.417816 -253.798578) (xy 388.37616 -253.713234)
			(xy 388.35584 -253.698502) (xy 388.34314 -253.696724) (xy 388.319089 -253.69294) (xy 388.272521 -253.678741)
			(xy 388.228797 -253.657331) (xy 388.189026 -253.629252) (xy 388.154215 -253.595217) (xy 388.125248 -253.556088)
			(xy 388.102858 -253.512858) (xy 388.087613 -253.466622) (xy 388.079901 -253.418552) (xy 388.079488 -253.39421)
			(xy 388.079933 -253.370216) (xy 388.087439 -253.322819) (xy 388.102267 -253.27718) (xy 388.124051 -253.234422)
			(xy 388.152257 -253.195599) (xy 388.186188 -253.161666) (xy 388.22501 -253.133459) (xy 388.267767 -253.111672)
			(xy 388.313406 -253.096842) (xy 388.360802 -253.089335) (xy 388.384796 -253.088902) (xy 388.397559 -253.089039)
			(xy 388.422994 -253.091198) (xy 388.435596 -253.09322) (xy 388.459721 -253.097792) (xy 388.506204 -253.113607)
			(xy 388.549559 -253.136652) (xy 388.588672 -253.166334) (xy 388.622534 -253.201889) (xy 388.650274 -253.242401)
			(xy 388.661148 -253.264416) (xy 388.661148 -253.26467) (xy 388.661656 -253.265178) (xy 388.665978 -253.273371)
			(xy 388.679327 -253.286192) (xy 388.696364 -253.293423) (xy 388.705598 -253.294134) (xy 388.719568 -253.294642)
			(xy 388.744206 -253.280926) (xy 388.772908 -253.230888) (xy 388.776008 -253.225072) (xy 388.779359 -253.21233)
			(xy 388.779512 -253.205742) (xy 388.779512 -252.932692) (xy 388.779219 -252.925025) (xy 388.774569 -252.910411)
			(xy 388.770368 -252.90399) (xy 388.751572 -252.876304) (xy 388.74065 -252.867414) (xy 388.733792 -252.86462)
			(xy 388.710671 -252.854102) (xy 388.668001 -252.826548) (xy 388.630483 -252.792309) (xy 388.599151 -252.752331)
			(xy 388.574872 -252.707716) (xy 388.558315 -252.659698) (xy 388.549937 -252.609601) (xy 388.549388 -252.584204)
			(xy 388.54989 -252.558896) (xy 388.55824 -252.508973) (xy 388.574695 -252.461106) (xy 388.598808 -252.416602)
			(xy 388.629919 -252.376676) (xy 388.648194 -252.35916) (xy 388.651799 -252.355634) (xy 388.657682 -252.347444)
			(xy 388.659878 -252.342904) (xy 388.665466 -252.330966) (xy 388.667233 -252.326717) (xy 388.669396 -252.317772)
			(xy 388.669784 -252.313186) (xy 388.670546 -252.303534) (xy 388.659116 -252.266196) (xy 388.636764 -252.182884)
			(xy 388.633462 -252.16993) (xy 388.626096 -252.135386) (xy 388.624064 -252.123956) (xy 388.61111 -252.105668)
			(xy 388.535418 -252.06325) (xy 388.52536 -252.058189) (xy 388.502941 -252.056459) (xy 388.492238 -252.059948)
			(xy 388.466309 -252.069032) (xy 388.412263 -252.078866) (xy 388.384796 -252.079506) (xy 388.379208 -252.079506)
			(xy 388.37108 -252.079252) (xy 388.345233 -252.077542) (xy 388.294624 -252.066515) (xy 388.246603 -252.047105)
			(xy 388.202545 -252.01987) (xy 388.163717 -251.98559) (xy 388.13123 -251.945248) (xy 388.106017 -251.900003)
			(xy 388.088802 -251.851152) (xy 388.080077 -251.800096) (xy 388.079488 -251.774198) (xy 388.07989 -251.750815)
			(xy 388.086988 -251.704592) (xy 388.101062 -251.659996) (xy 388.121782 -251.618072) (xy 388.13486 -251.598684)
			(xy 388.139432 -251.592334) (xy 388.144512 -251.576586) (xy 388.147015 -251.567539) (xy 388.146042 -251.548811)
			(xy 388.138422 -251.531675) (xy 388.132066 -251.52477) (xy 387.885686 -251.27839) (xy 387.880197 -251.273207)
			(xy 387.866883 -251.266105) (xy 387.859524 -251.26442) (xy 387.858762 -251.26442) (xy 387.833087 -251.259068)
			(xy 387.78394 -251.240768) (xy 387.738639 -251.214345) (xy 387.698515 -251.180575) (xy 387.664747 -251.14045)
			(xy 387.638326 -251.095148) (xy 387.620029 -251.046) (xy 387.614668 -251.020326) (xy 387.614668 -251.019564)
			(xy 387.612932 -251.012223) (xy 387.605842 -250.998917) (xy 387.600698 -250.993402) (xy 387.491986 -250.88469)
			(xy 387.485273 -250.877452) (xy 387.477678 -250.859247) (xy 387.477254 -250.849384) (xy 387.477254 -250.529344)
			(xy 387.476826 -250.519645) (xy 387.46965 -250.501621) (xy 387.463284 -250.494292) (xy 387.449314 -250.47956)
			(xy 387.44603 -250.476245) (xy 387.438486 -250.470756) (xy 387.434328 -250.468638) (xy 387.412484 -250.458224)
			(xy 387.404356 -250.456954) (xy 387.403848 -250.456954) (xy 387.379734 -250.453219) (xy 387.33303 -250.43909)
			(xy 387.289165 -250.417718) (xy 387.249255 -250.389645) (xy 387.214315 -250.355584) (xy 387.185234 -250.316404)
			(xy 387.16275 -250.273098) (xy 387.147435 -250.226769) (xy 387.139679 -250.178595) (xy 387.13968 -250.129801)
			(xy 387.147436 -250.081627) (xy 387.162751 -250.035298) (xy 387.185236 -249.991993) (xy 387.214318 -249.952813)
			(xy 387.249258 -249.918753) (xy 387.289168 -249.89068) (xy 387.333033 -249.869308) (xy 387.379737 -249.855181)
			(xy 387.403848 -249.851418) (xy 387.404356 -249.851418) (xy 387.412484 -249.850148) (xy 387.434328 -249.839734)
			(xy 387.438493 -249.837628) (xy 387.446037 -249.832135) (xy 387.449314 -249.828812) (xy 387.463284 -249.81408)
			(xy 387.469664 -249.806758) (xy 387.476844 -249.788731) (xy 387.477254 -249.779028) (xy 387.477254 -248.909332)
			(xy 387.476823 -248.899634) (xy 387.469645 -248.881613) (xy 387.463284 -248.87428) (xy 387.449314 -248.859548)
			(xy 387.44603 -248.856233) (xy 387.438485 -248.850746) (xy 387.434328 -248.848626) (xy 387.412484 -248.838212)
			(xy 387.404356 -248.836942) (xy 387.403848 -248.836942) (xy 387.379735 -248.833207) (xy 387.333032 -248.819079)
			(xy 387.28917 -248.797707) (xy 387.249262 -248.769634) (xy 387.214323 -248.735575) (xy 387.185243 -248.696396)
			(xy 387.16276 -248.653092) (xy 387.147446 -248.606765) (xy 387.139691 -248.558593) (xy 387.139692 -248.5098)
			(xy 387.147448 -248.461628) (xy 387.162763 -248.415302) (xy 387.185247 -248.371998) (xy 387.214328 -248.332819)
			(xy 387.249267 -248.298761) (xy 387.289176 -248.27069) (xy 387.333039 -248.249319) (xy 387.379742 -248.235192)
			(xy 387.403848 -248.231406) (xy 387.404356 -248.231406) (xy 387.412484 -248.230136) (xy 387.434328 -248.219722)
			(xy 387.438493 -248.217616) (xy 387.446036 -248.212122) (xy 387.449314 -248.2088) (xy 387.463284 -248.194068)
			(xy 387.469662 -248.186745) (xy 387.476838 -248.168719) (xy 387.477254 -248.159016) (xy 387.477254 -247.28932)
			(xy 387.476821 -247.279623) (xy 387.46964 -247.261605) (xy 387.463284 -247.254268) (xy 387.449314 -247.239536)
			(xy 387.446033 -247.236217) (xy 387.438493 -247.23072) (xy 387.434328 -247.228614) (xy 387.412484 -247.2182)
			(xy 387.404356 -247.21693) (xy 387.403848 -247.21693) (xy 387.379736 -247.213195) (xy 387.333035 -247.199067)
			(xy 387.289174 -247.177696) (xy 387.249268 -247.149624) (xy 387.214331 -247.115566) (xy 387.185252 -247.076388)
			(xy 387.16277 -247.033086) (xy 387.147457 -246.986761) (xy 387.139703 -246.93859) (xy 387.139704 -246.8898)
			(xy 387.14746 -246.84163) (xy 387.162774 -246.795305) (xy 387.185257 -246.752003) (xy 387.214338 -246.712826)
			(xy 387.249276 -246.678769) (xy 387.289183 -246.650699) (xy 387.333045 -246.629329) (xy 387.379746 -246.615203)
			(xy 387.403848 -246.611394) (xy 387.404356 -246.611394) (xy 387.412484 -246.610124) (xy 387.434328 -246.59971)
			(xy 387.438493 -246.597603) (xy 387.446035 -246.592109) (xy 387.449314 -246.588788) (xy 387.463284 -246.574056)
			(xy 387.46966 -246.566732) (xy 387.476832 -246.548706) (xy 387.477254 -246.539004) (xy 387.477254 -245.669308)
			(xy 387.476819 -245.659612) (xy 387.469634 -245.641597) (xy 387.463284 -245.634256) (xy 387.449314 -245.619524)
			(xy 387.446033 -245.616205) (xy 387.438492 -245.61071) (xy 387.434328 -245.608602) (xy 387.412484 -245.598188)
			(xy 387.404356 -245.596918) (xy 387.403848 -245.596918) (xy 387.379737 -245.593183) (xy 387.333038 -245.579055)
			(xy 387.289179 -245.557685) (xy 387.249274 -245.529614) (xy 387.214339 -245.495557) (xy 387.185261 -245.456381)
			(xy 387.162781 -245.41308) (xy 387.147469 -245.366756) (xy 387.139714 -245.318588) (xy 387.139716 -245.269799)
			(xy 387.147472 -245.221631) (xy 387.162786 -245.175308) (xy 387.185268 -245.132008) (xy 387.214348 -245.092833)
			(xy 387.249285 -245.058777) (xy 387.28919 -245.030709) (xy 387.333051 -245.00934) (xy 387.37975 -244.995214)
			(xy 387.403848 -244.991382) (xy 387.404356 -244.991382) (xy 387.412484 -244.990112) (xy 387.434328 -244.979698)
			(xy 387.438492 -244.977591) (xy 387.446034 -244.972095) (xy 387.449314 -244.968776) (xy 387.463284 -244.954044)
			(xy 387.469658 -244.94672) (xy 387.476826 -244.928693) (xy 387.477254 -244.918992) (xy 387.477254 -244.049296)
			(xy 387.476817 -244.0396) (xy 387.469629 -244.021589) (xy 387.463284 -244.014244) (xy 387.449314 -243.999512)
			(xy 387.446032 -243.996194) (xy 387.438491 -243.9907) (xy 387.434328 -243.98859) (xy 387.412484 -243.978176)
			(xy 387.404356 -243.976906) (xy 387.403848 -243.976906) (xy 387.37973 -243.973171) (xy 387.333017 -243.959041)
			(xy 387.289145 -243.937666) (xy 387.249228 -243.909589) (xy 387.214281 -243.875524) (xy 387.185194 -243.836337)
			(xy 387.162705 -243.793025) (xy 387.147387 -243.746688) (xy 387.139628 -243.698506) (xy 387.139628 -243.649704)
			(xy 387.147384 -243.601522) (xy 387.162701 -243.555185) (xy 387.185188 -243.511872) (xy 387.214274 -243.472684)
			(xy 387.24922 -243.438618) (xy 387.289136 -243.410539) (xy 387.333008 -243.389163) (xy 387.37972 -243.375032)
			(xy 387.403848 -243.37137) (xy 387.404356 -243.37137) (xy 387.412484 -243.3701) (xy 387.434328 -243.359686)
			(xy 387.438492 -243.357579) (xy 387.446032 -243.352082) (xy 387.449314 -243.348764) (xy 387.463284 -243.334032)
			(xy 387.469656 -243.326707) (xy 387.47682 -243.308681) (xy 387.477254 -243.29898) (xy 387.477254 -242.429284)
			(xy 387.476833 -242.419582) (xy 387.469667 -242.401549) (xy 387.463284 -242.394232) (xy 387.449314 -242.3795)
			(xy 387.446032 -242.376183) (xy 387.43849 -242.37069) (xy 387.434328 -242.368578) (xy 387.412484 -242.358164)
			(xy 387.404356 -242.356894) (xy 387.403848 -242.356894) (xy 387.379731 -242.353159) (xy 387.33302 -242.339029)
			(xy 387.289149 -242.317655) (xy 387.249234 -242.289578) (xy 387.214289 -242.255515) (xy 387.185203 -242.216329)
			(xy 387.162715 -242.173018) (xy 387.147398 -242.126684) (xy 387.13964 -242.078504) (xy 387.13964 -242.029703)
			(xy 387.147396 -241.981523) (xy 387.162712 -241.935188) (xy 387.185199 -241.891877) (xy 387.214284 -241.852691)
			(xy 387.249229 -241.818626) (xy 387.289143 -241.790549) (xy 387.333014 -241.769173) (xy 387.379724 -241.755043)
			(xy 387.403848 -241.751358) (xy 387.404356 -241.751358) (xy 387.412484 -241.750088) (xy 387.434328 -241.739674)
			(xy 387.438492 -241.737566) (xy 387.446031 -241.732069) (xy 387.449314 -241.728752) (xy 387.463284 -241.71402)
			(xy 387.46967 -241.7067) (xy 387.476865 -241.688674) (xy 387.477254 -241.678968) (xy 387.477254 -240.809272)
			(xy 387.47683 -240.799571) (xy 387.469662 -240.78154) (xy 387.463284 -240.77422) (xy 387.449314 -240.759488)
			(xy 387.446031 -240.756171) (xy 387.438489 -240.75068) (xy 387.434328 -240.748566) (xy 387.412484 -240.738152)
			(xy 387.404356 -240.736882) (xy 387.403848 -240.736882) (xy 387.379732 -240.733147) (xy 387.333023 -240.719018)
			(xy 387.289154 -240.697644) (xy 387.24924 -240.669568) (xy 387.214297 -240.635506) (xy 387.185212 -240.596321)
			(xy 387.162725 -240.553012) (xy 387.147409 -240.50668) (xy 387.139652 -240.458501) (xy 387.139652 -240.409702)
			(xy 387.147408 -240.361524) (xy 387.162724 -240.315191) (xy 387.18521 -240.271882) (xy 387.214294 -240.232697)
			(xy 387.249238 -240.198634) (xy 387.289151 -240.170558) (xy 387.333019 -240.149184) (xy 387.379728 -240.135054)
			(xy 387.403848 -240.131346) (xy 387.404356 -240.131346) (xy 387.412484 -240.130076) (xy 387.434328 -240.119662)
			(xy 387.438491 -240.117554) (xy 387.44603 -240.112056) (xy 387.449314 -240.10874) (xy 387.463284 -240.094008)
			(xy 387.469668 -240.086687) (xy 387.476859 -240.068661) (xy 387.477254 -240.058956) (xy 387.477254 -239.18926)
			(xy 387.476828 -239.17956) (xy 387.469657 -239.161532) (xy 387.463284 -239.154208) (xy 387.449314 -239.139476)
			(xy 387.446031 -239.13616) (xy 387.438488 -239.130669) (xy 387.434328 -239.128554) (xy 387.412484 -239.11814)
			(xy 387.404356 -239.11687) (xy 387.403848 -239.11687) (xy 387.379732 -239.113135) (xy 387.333026 -239.099006)
			(xy 387.289159 -239.077633) (xy 387.249247 -239.049558) (xy 387.214305 -239.015496) (xy 387.185221 -238.976314)
			(xy 387.162736 -238.933006) (xy 387.14742 -238.886675) (xy 387.139664 -238.838499) (xy 387.139664 -238.789702)
			(xy 387.14742 -238.741525) (xy 387.162736 -238.695194) (xy 387.185221 -238.651887) (xy 387.214304 -238.612704)
			(xy 387.249246 -238.578642) (xy 387.289158 -238.550568) (xy 387.333025 -238.529194) (xy 387.379732 -238.515065)
			(xy 387.403848 -238.511334) (xy 387.404356 -238.511334) (xy 387.412484 -238.510064) (xy 387.434328 -238.49965)
			(xy 387.438491 -238.497541) (xy 387.446029 -238.492042) (xy 387.449314 -238.488728) (xy 387.463284 -238.473996)
			(xy 387.469666 -238.466674) (xy 387.476852 -238.448648) (xy 387.477254 -238.438944) (xy 387.477254 -237.569248)
			(xy 387.476826 -237.559549) (xy 387.469652 -237.541524) (xy 387.463284 -237.534196) (xy 387.449314 -237.519464)
			(xy 387.446031 -237.516149) (xy 387.438487 -237.510659) (xy 387.434328 -237.508542) (xy 387.412484 -237.498128)
			(xy 387.404356 -237.496858) (xy 387.403848 -237.496858) (xy 387.379733 -237.493123) (xy 387.333029 -237.478994)
			(xy 387.289163 -237.457621) (xy 387.249253 -237.429548) (xy 387.214313 -237.395487) (xy 387.185231 -237.356306)
			(xy 387.162746 -237.313) (xy 387.147431 -237.266671) (xy 387.139675 -237.218496) (xy 387.139676 -237.169701)
			(xy 387.147432 -237.121527) (xy 387.162747 -237.075197) (xy 387.185232 -237.031892) (xy 387.214314 -236.992711)
			(xy 387.249255 -236.95865) (xy 387.289166 -236.930577) (xy 387.333031 -236.909205) (xy 387.379736 -236.895077)
			(xy 387.403848 -236.891322) (xy 387.404356 -236.891322) (xy 387.412484 -236.890052) (xy 387.434328 -236.879638)
			(xy 387.438493 -236.877532) (xy 387.446038 -236.87204) (xy 387.449314 -236.868716) (xy 387.463284 -236.853984)
			(xy 387.469664 -236.846662) (xy 387.476846 -236.828636) (xy 387.477254 -236.818932) (xy 387.477254 -235.949236)
			(xy 387.476824 -235.939537) (xy 387.469646 -235.921516) (xy 387.463284 -235.914184) (xy 387.449314 -235.899452)
			(xy 387.44603 -235.896137) (xy 387.438486 -235.890649) (xy 387.434328 -235.88853) (xy 387.412484 -235.878116)
			(xy 387.404356 -235.876846) (xy 387.403848 -235.876846) (xy 387.379734 -235.873111) (xy 387.333031 -235.858983)
			(xy 387.289168 -235.83761) (xy 387.24926 -235.809538) (xy 387.214321 -235.775478) (xy 387.18524 -235.736298)
			(xy 387.162756 -235.692994) (xy 387.147442 -235.646666) (xy 387.139687 -235.598494) (xy 387.139688 -235.549701)
			(xy 387.147444 -235.501528) (xy 387.162759 -235.455201) (xy 387.185243 -235.411897) (xy 387.214324 -235.372717)
			(xy 387.249264 -235.338658) (xy 387.289173 -235.310587) (xy 387.333037 -235.289215) (xy 387.37974 -235.275088)
			(xy 387.403848 -235.27131) (xy 387.404356 -235.27131) (xy 387.412484 -235.27004) (xy 387.434328 -235.259626)
			(xy 387.438493 -235.25752) (xy 387.446037 -235.252027) (xy 387.449314 -235.248704) (xy 387.463284 -235.233972)
			(xy 387.469662 -235.226649) (xy 387.47684 -235.208623) (xy 387.477254 -235.19892) (xy 387.477254 -234.329224)
			(xy 387.476822 -234.319526) (xy 387.469641 -234.301508) (xy 387.463284 -234.294172) (xy 387.449314 -234.27944)
			(xy 387.446033 -234.276121) (xy 387.438493 -234.270624) (xy 387.434328 -234.268518) (xy 387.412484 -234.258104)
			(xy 387.404356 -234.256834) (xy 387.403848 -234.256834) (xy 387.379735 -234.253099) (xy 387.333034 -234.238971)
			(xy 387.289173 -234.217599) (xy 387.249266 -234.189528) (xy 387.214328 -234.155469) (xy 387.185249 -234.116291)
			(xy 387.162767 -234.072988) (xy 387.147454 -234.026662) (xy 387.139699 -233.978491) (xy 387.1397 -233.9297)
			(xy 387.147456 -233.881529) (xy 387.16277 -233.835204) (xy 387.185254 -233.791902) (xy 387.214334 -233.752724)
			(xy 387.249273 -233.718667) (xy 387.289181 -233.690596) (xy 387.333043 -233.669226) (xy 387.379744 -233.655099)
			(xy 387.403848 -233.651298) (xy 387.404356 -233.651298) (xy 387.412484 -233.650028) (xy 387.434328 -233.639614)
			(xy 387.438493 -233.637508) (xy 387.446035 -233.632013) (xy 387.449314 -233.628692) (xy 387.463284 -233.61396)
			(xy 387.469661 -233.606637) (xy 387.476834 -233.58861) (xy 387.477254 -233.578908) (xy 387.477254 -232.709212)
			(xy 387.47682 -232.699515) (xy 387.469636 -232.6815) (xy 387.463284 -232.67416) (xy 387.449314 -232.659428)
			(xy 387.446033 -232.656109) (xy 387.438492 -232.650613) (xy 387.434328 -232.648506) (xy 387.412484 -232.638092)
			(xy 387.404356 -232.636822) (xy 387.403848 -232.636822) (xy 387.379736 -232.633087) (xy 387.333037 -232.618959)
			(xy 387.289177 -232.597588) (xy 387.249272 -232.569517) (xy 387.214336 -232.53546) (xy 387.185258 -232.496283)
			(xy 387.162777 -232.452982) (xy 387.147465 -232.406658) (xy 387.139711 -232.358489) (xy 387.139712 -232.309699)
			(xy 387.147468 -232.26153) (xy 387.162782 -232.215207) (xy 387.185265 -232.171906) (xy 387.214345 -232.13273)
			(xy 387.249282 -232.098675) (xy 387.289188 -232.070605) (xy 387.333049 -232.049236) (xy 387.379748 -232.035111)
			(xy 387.403848 -232.031286) (xy 387.404356 -232.031286) (xy 387.412484 -232.030016) (xy 387.434328 -232.019602)
			(xy 387.438492 -232.017495) (xy 387.446034 -232.012) (xy 387.449314 -232.00868) (xy 387.463284 -231.993948)
			(xy 387.469659 -231.986624) (xy 387.476828 -231.968598) (xy 387.477254 -231.958896) (xy 387.477254 -231.089454)
			(xy 387.476827 -231.079754) (xy 387.469654 -231.061728) (xy 387.463284 -231.054402) (xy 387.449314 -231.03967)
			(xy 387.446031 -231.036354) (xy 387.438487 -231.030864) (xy 387.434328 -231.028748) (xy 387.412484 -231.018334)
			(xy 387.404356 -231.017064) (xy 387.403848 -231.017064) (xy 387.379733 -231.013329) (xy 387.333027 -230.9992)
			(xy 387.289161 -230.977827) (xy 387.24925 -230.949753) (xy 387.214309 -230.915692) (xy 387.185226 -230.87651)
			(xy 387.162741 -230.833203) (xy 387.147426 -230.786873) (xy 387.139669 -230.738697) (xy 387.13967 -230.689901)
			(xy 387.147426 -230.641726) (xy 387.162741 -230.595396) (xy 387.185226 -230.552089) (xy 387.214309 -230.512907)
			(xy 387.249251 -230.478846) (xy 387.289162 -230.450772) (xy 387.333028 -230.4294) (xy 387.379734 -230.415271)
			(xy 387.403848 -230.411528) (xy 387.404356 -230.411528) (xy 387.412484 -230.410258) (xy 387.434328 -230.399844)
			(xy 387.438491 -230.397735) (xy 387.446028 -230.392236) (xy 387.449314 -230.388922) (xy 387.463284 -230.37419)
			(xy 387.469665 -230.366868) (xy 387.476849 -230.348842) (xy 387.477254 -230.339138) (xy 387.477254 -229.469442)
			(xy 387.476825 -229.459743) (xy 387.469649 -229.44172) (xy 387.463284 -229.43439) (xy 387.449314 -229.419658)
			(xy 387.44603 -229.416343) (xy 387.438486 -229.410854) (xy 387.434328 -229.408736) (xy 387.412484 -229.398322)
			(xy 387.404356 -229.397052) (xy 387.403848 -229.397052) (xy 387.379734 -229.393317) (xy 387.33303 -229.379188)
			(xy 387.289166 -229.357816) (xy 387.249256 -229.329743) (xy 387.214317 -229.295683) (xy 387.185235 -229.256502)
			(xy 387.162751 -229.213197) (xy 387.147437 -229.166869) (xy 387.139681 -229.118695) (xy 387.139682 -229.069901)
			(xy 387.147438 -229.021727) (xy 387.162753 -228.975399) (xy 387.185237 -228.932094) (xy 387.214319 -228.892914)
			(xy 387.24926 -228.858854) (xy 387.289169 -228.830782) (xy 387.333034 -228.80941) (xy 387.379738 -228.795282)
			(xy 387.403848 -228.791516) (xy 387.404356 -228.791516) (xy 387.412484 -228.790246) (xy 387.434328 -228.779832)
			(xy 387.438493 -228.777726) (xy 387.446037 -228.772233) (xy 387.449314 -228.76891) (xy 387.463284 -228.754178)
			(xy 387.469663 -228.746856) (xy 387.476843 -228.728829) (xy 387.477254 -228.719126) (xy 387.477254 -227.84943)
			(xy 387.476823 -227.839732) (xy 387.469644 -227.821712) (xy 387.463284 -227.814378) (xy 387.449314 -227.799646)
			(xy 387.44603 -227.796332) (xy 387.438485 -227.790844) (xy 387.434328 -227.788724) (xy 387.412484 -227.77831)
			(xy 387.404356 -227.77704) (xy 387.403848 -227.77704) (xy 387.379735 -227.773305) (xy 387.333033 -227.759177)
			(xy 387.28917 -227.737805) (xy 387.249263 -227.709733) (xy 387.214325 -227.675674) (xy 387.185244 -227.636495)
			(xy 387.162762 -227.593191) (xy 387.147448 -227.546864) (xy 387.139693 -227.498692) (xy 387.139694 -227.4499)
			(xy 387.14745 -227.401728) (xy 387.162765 -227.355402) (xy 387.185248 -227.312099) (xy 387.214329 -227.27292)
			(xy 387.249268 -227.238863) (xy 387.289177 -227.210791) (xy 387.33304 -227.189421) (xy 387.379742 -227.175294)
			(xy 387.403848 -227.171504) (xy 387.404356 -227.171504) (xy 387.412484 -227.170234) (xy 387.434328 -227.15982)
			(xy 387.438493 -227.157714) (xy 387.446036 -227.15222) (xy 387.449314 -227.148898) (xy 387.463284 -227.134166)
			(xy 387.469661 -227.126843) (xy 387.476837 -227.108817) (xy 387.477254 -227.099114) (xy 387.477254 -226.229418)
			(xy 387.476821 -226.219721) (xy 387.469639 -226.201704) (xy 387.463284 -226.194366) (xy 387.449314 -226.179634)
			(xy 387.446033 -226.176315) (xy 387.438492 -226.170819) (xy 387.434328 -226.168712) (xy 387.412484 -226.158298)
			(xy 387.404356 -226.157028) (xy 387.403848 -226.157028) (xy 387.379736 -226.153293) (xy 387.333036 -226.139165)
			(xy 387.289175 -226.117794) (xy 387.249269 -226.089723) (xy 387.214332 -226.055665) (xy 387.185254 -226.016487)
			(xy 387.162772 -225.973185) (xy 387.147459 -225.92686) (xy 387.139705 -225.87869) (xy 387.139706 -225.8299)
			(xy 387.147462 -225.78173) (xy 387.162776 -225.735405) (xy 387.185259 -225.692104) (xy 387.214339 -225.652927)
			(xy 387.249277 -225.618871) (xy 387.289184 -225.590801) (xy 387.333046 -225.569431) (xy 387.379746 -225.555305)
			(xy 387.403848 -225.551492) (xy 387.404356 -225.551492) (xy 387.412484 -225.550222) (xy 387.434328 -225.539808)
			(xy 387.438492 -225.537701) (xy 387.446035 -225.532207) (xy 387.449314 -225.528886) (xy 387.463284 -225.514154)
			(xy 387.46966 -225.50683) (xy 387.476831 -225.488804) (xy 387.477254 -225.479102) (xy 387.477254 -224.609406)
			(xy 387.476819 -224.59971) (xy 387.469634 -224.581696) (xy 387.463284 -224.574354) (xy 387.449314 -224.559622)
			(xy 387.446033 -224.556304) (xy 387.438491 -224.550808) (xy 387.434328 -224.5487) (xy 387.412484 -224.538286)
			(xy 387.404356 -224.537016) (xy 387.403848 -224.537016) (xy 387.379729 -224.53328) (xy 387.333015 -224.519151)
			(xy 387.289141 -224.497775) (xy 387.249222 -224.469697) (xy 387.214275 -224.435631) (xy 387.185186 -224.396443)
			(xy 387.162696 -224.35313) (xy 387.147377 -224.306792) (xy 387.139619 -224.258608) (xy 387.139618 -224.209804)
			(xy 387.147374 -224.16162) (xy 387.162691 -224.115282) (xy 387.185179 -224.071968) (xy 387.214266 -224.032779)
			(xy 387.249213 -223.998711) (xy 387.28913 -223.970632) (xy 387.333003 -223.949254) (xy 387.379716 -223.935122)
			(xy 387.403848 -223.93148) (xy 387.404356 -223.93148) (xy 387.412484 -223.93021) (xy 387.44271 -223.915732)
			(xy 387.449314 -223.908874) (xy 387.461506 -223.896174) (xy 387.468813 -223.887809) (xy 387.476071 -223.866844)
			(xy 387.473821 -223.844772) (xy 387.468618 -223.83496) (xy 387.465316 -223.829372) (xy 387.303772 -223.667828)
			(xy 387.296858 -223.661548) (xy 387.279795 -223.653988) (xy 387.270498 -223.653096) (xy 387.192774 -223.649032)
			(xy 387.175248 -223.654874) (xy 387.167628 -223.66097) (xy 387.147054 -223.677039) (xy 387.101563 -223.702642)
			(xy 387.052382 -223.720139) (xy 387.000942 -223.729021) (xy 386.974842 -223.72955) (xy 386.950973 -223.729086)
			(xy 386.903818 -223.721653) (xy 386.858393 -223.706977) (xy 386.815802 -223.685415) (xy 386.777083 -223.657491)
			(xy 386.743178 -223.623886) (xy 386.714911 -223.585417) (xy 386.692971 -223.54302) (xy 386.685028 -223.520508)
			(xy 386.679694 -223.50476) (xy 386.653278 -223.48571) (xy 386.38861 -223.48571) (xy 386.380643 -223.485973)
			(xy 386.365484 -223.490882) (xy 386.358892 -223.495362) (xy 386.33146 -223.515174) (xy 386.32257 -223.526858)
			(xy 386.319776 -223.533716) (xy 386.310528 -223.556429) (xy 386.285852 -223.598807) (xy 386.25472 -223.636695)
			(xy 386.217931 -223.669119) (xy 386.176433 -223.695246) (xy 386.131291 -223.714403) (xy 386.083668 -223.726098)
			(xy 386.034788 -223.73003) (xy 385.985908 -223.726098) (xy 385.938285 -223.714403) (xy 385.893143 -223.695246)
			(xy 385.851645 -223.669119) (xy 385.814856 -223.636695) (xy 385.783724 -223.598807) (xy 385.759048 -223.556429)
			(xy 385.7498 -223.533716) (xy 385.747006 -223.526858) (xy 385.738116 -223.515174) (xy 385.710684 -223.495362)
			(xy 385.704052 -223.490959) (xy 385.688919 -223.486054) (xy 385.680966 -223.48571) (xy 385.448556 -223.48571)
			(xy 385.440592 -223.485982) (xy 385.425443 -223.490903) (xy 385.418838 -223.495362) (xy 385.391406 -223.515174)
			(xy 385.382516 -223.526858) (xy 385.379722 -223.533716) (xy 385.370474 -223.556429) (xy 385.345798 -223.598807)
			(xy 385.314666 -223.636695) (xy 385.277877 -223.669119) (xy 385.236379 -223.695246) (xy 385.191237 -223.714403)
			(xy 385.143614 -223.726098) (xy 385.094734 -223.73003) (xy 385.045854 -223.726098) (xy 384.998231 -223.714403)
			(xy 384.953089 -223.695246) (xy 384.911591 -223.669119) (xy 384.874802 -223.636695) (xy 384.84367 -223.598807)
			(xy 384.818994 -223.556429) (xy 384.809746 -223.533716) (xy 384.806952 -223.526858) (xy 384.798062 -223.515174)
			(xy 384.77063 -223.495362) (xy 384.764 -223.490953) (xy 384.748867 -223.486035) (xy 384.740912 -223.48571)
			(xy 384.476498 -223.48571) (xy 384.450082 -223.50476) (xy 384.444748 -223.520508) (xy 384.436236 -223.544516)
			(xy 384.412383 -223.58952) (xy 384.381394 -223.629942) (xy 384.344128 -223.664663) (xy 384.301618 -223.69272)
			(xy 384.255042 -223.713336) (xy 384.205692 -223.725938) (xy 384.154934 -223.730178) (xy 384.104176 -223.725938)
			(xy 384.054826 -223.713336) (xy 384.00825 -223.69272) (xy 383.96574 -223.664663) (xy 383.928474 -223.629942)
			(xy 383.897485 -223.58952) (xy 383.873632 -223.544516) (xy 383.86512 -223.520508) (xy 383.859786 -223.50476)
			(xy 383.83337 -223.48571) (xy 383.568702 -223.48571) (xy 383.560735 -223.485975) (xy 383.545578 -223.490885)
			(xy 383.538984 -223.495362) (xy 383.511552 -223.515174) (xy 383.502662 -223.526858) (xy 383.499868 -223.533716)
			(xy 383.490938 -223.555706) (xy 383.467269 -223.596843) (xy 383.43752 -223.633823) (xy 383.402409 -223.665755)
			(xy 383.36278 -223.691871) (xy 383.341372 -223.702118) (xy 383.327402 -223.708468) (xy 383.3114 -223.733106)
			(xy 383.3114 -223.931226) (xy 383.311851 -223.941034) (xy 383.319209 -223.959217) (xy 383.332843 -223.97332)
			(xy 383.341626 -223.977708) (xy 383.440178 -224.02165) (xy 383.469642 -224.017078) (xy 383.481072 -224.006918)
			(xy 383.497944 -223.992304) (xy 383.535157 -223.967656) (xy 383.575564 -223.948693) (xy 383.618304 -223.935821)
			(xy 383.662462 -223.929314) (xy 383.68478 -223.92894) (xy 383.708773 -223.929385) (xy 383.756168 -223.936889)
			(xy 383.801805 -223.951717) (xy 383.844561 -223.973502) (xy 383.883381 -224.001708) (xy 383.91731 -224.03564)
			(xy 383.945513 -224.074463) (xy 383.967294 -224.117221) (xy 383.982117 -224.162859) (xy 383.989617 -224.210255)
			(xy 383.990088 -224.234248) (xy 384.31903 -224.234248) (xy 384.32299 -224.185194) (xy 384.334767 -224.13741)
			(xy 384.354058 -224.092134) (xy 384.380361 -224.050538) (xy 384.412996 -224.013701) (xy 384.451117 -223.982576)
			(xy 384.493738 -223.957969) (xy 384.539754 -223.940517) (xy 384.587973 -223.930673) (xy 384.637148 -223.928692)
			(xy 384.686003 -223.934624) (xy 384.733274 -223.948316) (xy 384.777736 -223.969414) (xy 384.818239 -223.99737)
			(xy 384.853732 -224.031462) (xy 384.883297 -224.070806) (xy 384.906168 -224.114383) (xy 384.921752 -224.161064)
			(xy 384.929647 -224.209641) (xy 384.930142 -224.234248) (xy 386.199138 -224.234248) (xy 386.203098 -224.185194)
			(xy 386.214875 -224.13741) (xy 386.234166 -224.092134) (xy 386.260469 -224.050538) (xy 386.293104 -224.013701)
			(xy 386.331225 -223.982576) (xy 386.373846 -223.957969) (xy 386.419862 -223.940517) (xy 386.468081 -223.930673)
			(xy 386.517256 -223.928692) (xy 386.566111 -223.934624) (xy 386.613382 -223.948316) (xy 386.657844 -223.969414)
			(xy 386.698347 -223.99737) (xy 386.73384 -224.031462) (xy 386.763405 -224.070806) (xy 386.786276 -224.114383)
			(xy 386.80186 -224.161064) (xy 386.809755 -224.209641) (xy 386.81025 -224.234248) (xy 386.809755 -224.258855)
			(xy 386.80186 -224.307432) (xy 386.786276 -224.354113) (xy 386.763405 -224.39769) (xy 386.73384 -224.437034)
			(xy 386.698347 -224.471126) (xy 386.657844 -224.499082) (xy 386.613382 -224.52018) (xy 386.566111 -224.533872)
			(xy 386.517256 -224.539804) (xy 386.468081 -224.537823) (xy 386.419862 -224.527979) (xy 386.373846 -224.510527)
			(xy 386.331225 -224.48592) (xy 386.293104 -224.454795) (xy 386.260469 -224.417958) (xy 386.234166 -224.376362)
			(xy 386.214875 -224.331086) (xy 386.203098 -224.283302) (xy 386.199138 -224.234248) (xy 384.930142 -224.234248)
			(xy 384.929647 -224.258855) (xy 384.921752 -224.307432) (xy 384.906168 -224.354113) (xy 384.883297 -224.39769)
			(xy 384.853732 -224.437034) (xy 384.818239 -224.471126) (xy 384.777736 -224.499082) (xy 384.733274 -224.52018)
			(xy 384.686003 -224.533872) (xy 384.637148 -224.539804) (xy 384.587973 -224.537823) (xy 384.539754 -224.527979)
			(xy 384.493738 -224.510527) (xy 384.451117 -224.48592) (xy 384.412996 -224.454795) (xy 384.380361 -224.417958)
			(xy 384.354058 -224.376362) (xy 384.334767 -224.331086) (xy 384.32299 -224.283302) (xy 384.31903 -224.234248)
			(xy 383.990088 -224.234248) (xy 383.98962 -224.258484) (xy 383.981955 -224.306346) (xy 383.966826 -224.352397)
			(xy 383.944613 -224.395479) (xy 383.915873 -224.434512) (xy 383.881327 -224.468515) (xy 383.841845 -224.496633)
			(xy 383.798416 -224.518162) (xy 383.752132 -224.53256) (xy 383.728214 -224.536508) (xy 383.715006 -224.538286)
			(xy 383.68478 -224.53981) (xy 383.661661 -224.539391) (xy 383.615948 -224.532437) (xy 383.571805 -224.518677)
			(xy 383.530238 -224.498423) (xy 383.492197 -224.472139) (xy 383.458549 -224.440424) (xy 383.443988 -224.422462)
			(xy 383.435352 -224.41154) (xy 383.41046 -224.40138) (xy 383.296668 -224.417636) (xy 383.275332 -224.434146)
			(xy 383.270252 -224.446846) (xy 383.259365 -224.472832) (xy 383.233153 -224.522708) (xy 383.217928 -224.546414)
			(xy 383.194052 -224.579688) (xy 383.18567 -224.59061) (xy 383.182114 -224.61728) (xy 383.22504 -224.723706)
			(xy 383.246122 -224.740216) (xy 383.259584 -224.742248) (xy 383.283423 -224.746239) (xy 383.329523 -224.760756)
			(xy 383.372761 -224.782354) (xy 383.412056 -224.810494) (xy 383.446427 -224.844473) (xy 383.475017 -224.883443)
			(xy 383.49711 -224.92643) (xy 383.512155 -224.972361) (xy 383.519776 -225.020088) (xy 383.520188 -225.044254)
			(xy 383.84913 -225.044254) (xy 383.85309 -224.9952) (xy 383.864867 -224.947416) (xy 383.884158 -224.90214)
			(xy 383.910461 -224.860544) (xy 383.943096 -224.823707) (xy 383.981217 -224.792582) (xy 384.023838 -224.767975)
			(xy 384.069854 -224.750523) (xy 384.118073 -224.740679) (xy 384.167248 -224.738698) (xy 384.216103 -224.74463)
			(xy 384.263374 -224.758322) (xy 384.307836 -224.77942) (xy 384.348339 -224.807376) (xy 384.383832 -224.841468)
			(xy 384.413397 -224.880812) (xy 384.436268 -224.924389) (xy 384.451852 -224.97107) (xy 384.459747 -225.019647)
			(xy 384.460242 -225.044254) (xy 385.728984 -225.044254) (xy 385.732944 -224.9952) (xy 385.744721 -224.947416)
			(xy 385.764012 -224.90214) (xy 385.790315 -224.860544) (xy 385.82295 -224.823707) (xy 385.861071 -224.792582)
			(xy 385.903692 -224.767975) (xy 385.949708 -224.750523) (xy 385.997927 -224.740679) (xy 386.047102 -224.738698)
			(xy 386.095957 -224.74463) (xy 386.143228 -224.758322) (xy 386.18769 -224.77942) (xy 386.228193 -224.807376)
			(xy 386.263686 -224.841468) (xy 386.293251 -224.880812) (xy 386.316122 -224.924389) (xy 386.331706 -224.97107)
			(xy 386.339601 -225.019647) (xy 386.340096 -225.044254) (xy 386.669038 -225.044254) (xy 386.672998 -224.9952)
			(xy 386.684775 -224.947416) (xy 386.704066 -224.90214) (xy 386.730369 -224.860544) (xy 386.763004 -224.823707)
			(xy 386.801125 -224.792582) (xy 386.843746 -224.767975) (xy 386.889762 -224.750523) (xy 386.937981 -224.740679)
			(xy 386.987156 -224.738698) (xy 387.036011 -224.74463) (xy 387.083282 -224.758322) (xy 387.127744 -224.77942)
			(xy 387.168247 -224.807376) (xy 387.20374 -224.841468) (xy 387.233305 -224.880812) (xy 387.256176 -224.924389)
			(xy 387.27176 -224.97107) (xy 387.279655 -225.019647) (xy 387.28015 -225.044254) (xy 387.279655 -225.068861)
			(xy 387.27176 -225.117438) (xy 387.256176 -225.164119) (xy 387.233305 -225.207696) (xy 387.20374 -225.24704)
			(xy 387.168247 -225.281132) (xy 387.127744 -225.309088) (xy 387.083282 -225.330186) (xy 387.036011 -225.343878)
			(xy 386.987156 -225.34981) (xy 386.937981 -225.347829) (xy 386.889762 -225.337985) (xy 386.843746 -225.320533)
			(xy 386.801125 -225.295926) (xy 386.763004 -225.264801) (xy 386.730369 -225.227964) (xy 386.704066 -225.186368)
			(xy 386.684775 -225.141092) (xy 386.672998 -225.093308) (xy 386.669038 -225.044254) (xy 386.340096 -225.044254)
			(xy 386.339601 -225.068861) (xy 386.331706 -225.117438) (xy 386.316122 -225.164119) (xy 386.293251 -225.207696)
			(xy 386.263686 -225.24704) (xy 386.228193 -225.281132) (xy 386.18769 -225.309088) (xy 386.143228 -225.330186)
			(xy 386.095957 -225.343878) (xy 386.047102 -225.34981) (xy 385.997927 -225.347829) (xy 385.949708 -225.337985)
			(xy 385.903692 -225.320533) (xy 385.861071 -225.295926) (xy 385.82295 -225.264801) (xy 385.790315 -225.227964)
			(xy 385.764012 -225.186368) (xy 385.744721 -225.141092) (xy 385.732944 -225.093308) (xy 385.728984 -225.044254)
			(xy 384.460242 -225.044254) (xy 384.459747 -225.068861) (xy 384.451852 -225.117438) (xy 384.436268 -225.164119)
			(xy 384.413397 -225.207696) (xy 384.383832 -225.24704) (xy 384.348339 -225.281132) (xy 384.307836 -225.309088)
			(xy 384.263374 -225.330186) (xy 384.216103 -225.343878) (xy 384.167248 -225.34981) (xy 384.118073 -225.347829)
			(xy 384.069854 -225.337985) (xy 384.023838 -225.320533) (xy 383.981217 -225.295926) (xy 383.943096 -225.264801)
			(xy 383.910461 -225.227964) (xy 383.884158 -225.186368) (xy 383.864867 -225.141092) (xy 383.85309 -225.093308)
			(xy 383.84913 -225.044254) (xy 383.520188 -225.044254) (xy 383.519745 -225.068249) (xy 383.512244 -225.115649)
			(xy 383.497419 -225.161291) (xy 383.475636 -225.204052) (xy 383.447431 -225.242879) (xy 383.413499 -225.276814)
			(xy 383.374675 -225.305023) (xy 383.331915 -225.326809) (xy 383.286274 -225.341638) (xy 383.238875 -225.349143)
			(xy 383.21488 -225.349562) (xy 383.191104 -225.349107) (xy 383.144127 -225.341732) (xy 383.098861 -225.327165)
			(xy 383.0564 -225.305757) (xy 383.017771 -225.278026) (xy 382.983907 -225.244642) (xy 382.955628 -225.206412)
			(xy 382.933617 -225.16426) (xy 382.918406 -225.119207) (xy 382.910363 -225.072339) (xy 382.909572 -225.048572)
			(xy 382.909572 -225.044254) (xy 382.910174 -225.015832) (xy 382.920656 -224.959963) (xy 382.9304 -224.933256)
			(xy 382.935226 -224.920556) (xy 382.931416 -224.89414) (xy 382.860296 -224.80397) (xy 382.835404 -224.794064)
			(xy 382.821942 -224.795842) (xy 382.802734 -224.798324) (xy 382.764093 -224.800994) (xy 382.744726 -224.801176)
			(xy 382.725486 -224.800989) (xy 382.687099 -224.798318) (xy 382.668018 -224.795842) (xy 382.66751 -224.795842)
			(xy 382.658781 -224.795079) (xy 382.64167 -224.798799) (xy 382.626797 -224.80804) (xy 382.621028 -224.814638)
			(xy 382.55829 -224.89414) (xy 382.55448 -224.920556) (xy 382.559306 -224.933256) (xy 382.569031 -224.959968)
			(xy 382.579521 -225.015833) (xy 382.580134 -225.044254) (xy 382.580134 -225.048572) (xy 382.579347 -225.072341)
			(xy 382.571316 -225.119215) (xy 382.556112 -225.164275) (xy 382.534105 -225.206433) (xy 382.505826 -225.244668)
			(xy 382.47196 -225.278056) (xy 382.433327 -225.305787) (xy 382.39086 -225.327192) (xy 382.345587 -225.341752)
			(xy 382.298604 -225.349116) (xy 382.274826 -225.349562) (xy 382.250833 -225.349118) (xy 382.203437 -225.341614)
			(xy 382.157799 -225.326787) (xy 382.115042 -225.305002) (xy 382.076221 -225.276796) (xy 382.042291 -225.242864)
			(xy 382.014087 -225.204041) (xy 381.992305 -225.161283) (xy 381.977481 -225.115644) (xy 381.969981 -225.068247)
			(xy 381.969518 -225.044254) (xy 381.96998 -225.020104) (xy 381.97759 -224.972407) (xy 381.992614 -224.926502)
			(xy 382.014677 -224.883535) (xy 382.043228 -224.844576) (xy 382.077556 -224.810598) (xy 382.116804 -224.782446)
			(xy 382.159995 -224.760824) (xy 382.206051 -224.746271) (xy 382.229868 -224.742248) (xy 382.230122 -224.742248)
			(xy 382.238744 -224.740528) (xy 382.254172 -224.732123) (xy 382.265873 -224.719018) (xy 382.269492 -224.711006)
			(xy 382.307338 -224.61728) (xy 382.303782 -224.59061) (xy 382.2954 -224.579942) (xy 382.277432 -224.555932)
			(xy 382.246105 -224.504791) (xy 382.22036 -224.450625) (xy 382.210056 -224.422462) (xy 382.199877 -224.392141)
			(xy 382.185615 -224.329789) (xy 382.178458 -224.266229) (xy 382.178052 -224.234248) (xy 382.178052 -223.73336)
			(xy 382.16205 -223.708468) (xy 382.14808 -223.702118) (xy 382.125431 -223.69123) (xy 382.083742 -223.663177)
			(xy 382.04721 -223.628674) (xy 382.016823 -223.588653) (xy 381.993402 -223.544196) (xy 381.985012 -223.520508)
			(xy 381.979678 -223.50476) (xy 381.953516 -223.48571) (xy 381.688594 -223.48571) (xy 381.680628 -223.485976)
			(xy 381.665472 -223.490888) (xy 381.658876 -223.495362) (xy 381.631444 -223.515174) (xy 381.622554 -223.526858)
			(xy 381.61976 -223.533716) (xy 381.610512 -223.556429) (xy 381.585836 -223.598807) (xy 381.554704 -223.636695)
			(xy 381.517915 -223.669119) (xy 381.476417 -223.695246) (xy 381.431275 -223.714403) (xy 381.383652 -223.726098)
			(xy 381.334772 -223.73003) (xy 381.285892 -223.726098) (xy 381.238269 -223.714403) (xy 381.193127 -223.695246)
			(xy 381.151629 -223.669119) (xy 381.11484 -223.636695) (xy 381.083708 -223.598807) (xy 381.059032 -223.556429)
			(xy 381.049784 -223.533716) (xy 381.04699 -223.526858) (xy 381.0381 -223.515174) (xy 381.010668 -223.495362)
			(xy 381.004039 -223.490949) (xy 380.988906 -223.486019) (xy 380.98095 -223.48571) (xy 378.868686 -223.48571)
			(xy 378.86072 -223.485977) (xy 378.845566 -223.490891) (xy 378.838968 -223.495362) (xy 378.811536 -223.515174)
			(xy 378.802646 -223.526858) (xy 378.799852 -223.533716) (xy 378.790604 -223.556429) (xy 378.765928 -223.598807)
			(xy 378.734796 -223.636695) (xy 378.698007 -223.669119) (xy 378.656509 -223.695246) (xy 378.611367 -223.714403)
			(xy 378.563744 -223.726098) (xy 378.514864 -223.73003) (xy 378.465984 -223.726098) (xy 378.418361 -223.714403)
			(xy 378.373219 -223.695246) (xy 378.331721 -223.669119) (xy 378.294932 -223.636695) (xy 378.2638 -223.598807)
			(xy 378.239124 -223.556429) (xy 378.229876 -223.533716) (xy 378.227082 -223.526858) (xy 378.218192 -223.515174)
			(xy 378.19076 -223.495362) (xy 378.184131 -223.49095) (xy 378.168998 -223.486022) (xy 378.161042 -223.48571)
			(xy 377.939554 -223.48571) (xy 377.931523 -223.485944) (xy 377.916233 -223.490856) (xy 377.909582 -223.495362)
			(xy 377.881642 -223.515682) (xy 377.873006 -223.527112) (xy 377.870212 -223.534478) (xy 377.860826 -223.558221)
			(xy 377.835504 -223.602551) (xy 377.80337 -223.642223) (xy 377.765265 -223.676199) (xy 377.722184 -223.703591)
			(xy 377.675252 -223.723686) (xy 377.625696 -223.735956) (xy 377.57481 -223.740082) (xy 377.523924 -223.735956)
			(xy 377.474368 -223.723686) (xy 377.427436 -223.703591) (xy 377.384355 -223.676199) (xy 377.34625 -223.642223)
			(xy 377.314116 -223.602551) (xy 377.288794 -223.558221) (xy 377.279408 -223.534478) (xy 377.276614 -223.527112)
			(xy 377.267978 -223.515682) (xy 377.240038 -223.495362) (xy 377.233351 -223.490924) (xy 377.218086 -223.486001)
			(xy 377.210066 -223.48571) (xy 376.95632 -223.48571) (xy 376.929904 -223.50476) (xy 376.92457 -223.520508)
			(xy 376.916058 -223.544516) (xy 376.892205 -223.58952) (xy 376.861216 -223.629942) (xy 376.82395 -223.664663)
			(xy 376.78144 -223.69272) (xy 376.734864 -223.713336) (xy 376.685514 -223.725938) (xy 376.634756 -223.730178)
			(xy 376.583998 -223.725938) (xy 376.534648 -223.713336) (xy 376.488072 -223.69272) (xy 376.445562 -223.664663)
			(xy 376.408296 -223.629942) (xy 376.377307 -223.58952) (xy 376.353454 -223.544516) (xy 376.344942 -223.520508)
			(xy 376.339608 -223.50476) (xy 376.313192 -223.48571) (xy 376.016266 -223.48571) (xy 375.98985 -223.50476)
			(xy 375.984516 -223.520508) (xy 375.976004 -223.544516) (xy 375.952151 -223.58952) (xy 375.921162 -223.629942)
			(xy 375.883896 -223.664663) (xy 375.841386 -223.69272) (xy 375.79481 -223.713336) (xy 375.74546 -223.725938)
			(xy 375.694702 -223.730178) (xy 375.643944 -223.725938) (xy 375.594594 -223.713336) (xy 375.548018 -223.69272)
			(xy 375.505508 -223.664663) (xy 375.468242 -223.629942) (xy 375.437253 -223.58952) (xy 375.4134 -223.544516)
			(xy 375.404888 -223.520508) (xy 375.399554 -223.50476) (xy 375.373138 -223.48571) (xy 375.076466 -223.48571)
			(xy 375.05005 -223.50476) (xy 375.044716 -223.520508) (xy 375.036204 -223.544516) (xy 375.012351 -223.58952)
			(xy 374.981362 -223.629942) (xy 374.944096 -223.664663) (xy 374.901586 -223.69272) (xy 374.85501 -223.713336)
			(xy 374.80566 -223.725938) (xy 374.754902 -223.730178) (xy 374.704144 -223.725938) (xy 374.654794 -223.713336)
			(xy 374.608218 -223.69272) (xy 374.565708 -223.664663) (xy 374.528442 -223.629942) (xy 374.497453 -223.58952)
			(xy 374.4736 -223.544516) (xy 374.465088 -223.520508) (xy 374.459754 -223.50476) (xy 374.433338 -223.48571)
			(xy 373.676672 -223.48571) (xy 373.666604 -223.486139) (xy 373.648008 -223.493861) (xy 373.640604 -223.500696)
			(xy 373.623586 -223.517714) (xy 373.61622 -223.524826) (xy 373.6086 -223.543622) (xy 373.6086 -224.067624)
			(xy 373.608764 -224.073779) (xy 373.611706 -224.085731) (xy 373.614442 -224.091246) (xy 373.625634 -224.113402)
			(xy 373.641476 -224.160442) (xy 373.649499 -224.209425) (xy 373.649495 -224.234248) (xy 375.859052 -224.234248)
			(xy 375.863012 -224.185194) (xy 375.874789 -224.13741) (xy 375.89408 -224.092134) (xy 375.920383 -224.050538)
			(xy 375.953018 -224.013701) (xy 375.991139 -223.982576) (xy 376.03376 -223.957969) (xy 376.079776 -223.940517)
			(xy 376.127995 -223.930673) (xy 376.17717 -223.928692) (xy 376.226025 -223.934624) (xy 376.273296 -223.948316)
			(xy 376.317758 -223.969414) (xy 376.358261 -223.99737) (xy 376.393754 -224.031462) (xy 376.423319 -224.070806)
			(xy 376.44619 -224.114383) (xy 376.461774 -224.161064) (xy 376.469669 -224.209641) (xy 376.470164 -224.234248)
			(xy 376.799106 -224.234248) (xy 376.803066 -224.185194) (xy 376.814843 -224.13741) (xy 376.834134 -224.092134)
			(xy 376.860437 -224.050538) (xy 376.893072 -224.013701) (xy 376.931193 -223.982576) (xy 376.973814 -223.957969)
			(xy 377.01983 -223.940517) (xy 377.068049 -223.930673) (xy 377.117224 -223.928692) (xy 377.166079 -223.934624)
			(xy 377.21335 -223.948316) (xy 377.257812 -223.969414) (xy 377.298315 -223.99737) (xy 377.333808 -224.031462)
			(xy 377.363373 -224.070806) (xy 377.386244 -224.114383) (xy 377.401828 -224.161064) (xy 377.409723 -224.209641)
			(xy 377.410218 -224.234248) (xy 377.738906 -224.234248) (xy 377.742866 -224.185194) (xy 377.754643 -224.13741)
			(xy 377.773934 -224.092134) (xy 377.800237 -224.050538) (xy 377.832872 -224.013701) (xy 377.870993 -223.982576)
			(xy 377.913614 -223.957969) (xy 377.95963 -223.940517) (xy 378.007849 -223.930673) (xy 378.057024 -223.928692)
			(xy 378.105879 -223.934624) (xy 378.15315 -223.948316) (xy 378.197612 -223.969414) (xy 378.238115 -223.99737)
			(xy 378.273608 -224.031462) (xy 378.303173 -224.070806) (xy 378.326044 -224.114383) (xy 378.341628 -224.161064)
			(xy 378.349523 -224.209641) (xy 378.350018 -224.234248) (xy 378.67896 -224.234248) (xy 378.68292 -224.185194)
			(xy 378.694697 -224.13741) (xy 378.713988 -224.092134) (xy 378.740291 -224.050538) (xy 378.772926 -224.013701)
			(xy 378.811047 -223.982576) (xy 378.853668 -223.957969) (xy 378.899684 -223.940517) (xy 378.947903 -223.930673)
			(xy 378.997078 -223.928692) (xy 379.045933 -223.934624) (xy 379.093204 -223.948316) (xy 379.137666 -223.969414)
			(xy 379.178169 -223.99737) (xy 379.213662 -224.031462) (xy 379.243227 -224.070806) (xy 379.266098 -224.114383)
			(xy 379.281682 -224.161064) (xy 379.289577 -224.209641) (xy 379.290072 -224.234248) (xy 379.619014 -224.234248)
			(xy 379.622974 -224.185194) (xy 379.634751 -224.13741) (xy 379.654042 -224.092134) (xy 379.680345 -224.050538)
			(xy 379.71298 -224.013701) (xy 379.751101 -223.982576) (xy 379.793722 -223.957969) (xy 379.839738 -223.940517)
			(xy 379.887957 -223.930673) (xy 379.937132 -223.928692) (xy 379.985987 -223.934624) (xy 380.033258 -223.948316)
			(xy 380.07772 -223.969414) (xy 380.118223 -223.99737) (xy 380.153716 -224.031462) (xy 380.183281 -224.070806)
			(xy 380.206152 -224.114383) (xy 380.221736 -224.161064) (xy 380.229631 -224.209641) (xy 380.230126 -224.234248)
			(xy 380.559068 -224.234248) (xy 380.563028 -224.185194) (xy 380.574805 -224.13741) (xy 380.594096 -224.092134)
			(xy 380.620399 -224.050538) (xy 380.653034 -224.013701) (xy 380.691155 -223.982576) (xy 380.733776 -223.957969)
			(xy 380.779792 -223.940517) (xy 380.828011 -223.930673) (xy 380.877186 -223.928692) (xy 380.926041 -223.934624)
			(xy 380.973312 -223.948316) (xy 381.017774 -223.969414) (xy 381.058277 -223.99737) (xy 381.09377 -224.031462)
			(xy 381.123335 -224.070806) (xy 381.146206 -224.114383) (xy 381.16179 -224.161064) (xy 381.169685 -224.209641)
			(xy 381.17018 -224.234248) (xy 381.169685 -224.258855) (xy 381.16179 -224.307432) (xy 381.146206 -224.354113)
			(xy 381.123335 -224.39769) (xy 381.09377 -224.437034) (xy 381.058277 -224.471126) (xy 381.017774 -224.499082)
			(xy 380.973312 -224.52018) (xy 380.926041 -224.533872) (xy 380.877186 -224.539804) (xy 380.828011 -224.537823)
			(xy 380.779792 -224.527979) (xy 380.733776 -224.510527) (xy 380.691155 -224.48592) (xy 380.653034 -224.454795)
			(xy 380.620399 -224.417958) (xy 380.594096 -224.376362) (xy 380.574805 -224.331086) (xy 380.563028 -224.283302)
			(xy 380.559068 -224.234248) (xy 380.230126 -224.234248) (xy 380.229631 -224.258855) (xy 380.221736 -224.307432)
			(xy 380.206152 -224.354113) (xy 380.183281 -224.39769) (xy 380.153716 -224.437034) (xy 380.118223 -224.471126)
			(xy 380.07772 -224.499082) (xy 380.033258 -224.52018) (xy 379.985987 -224.533872) (xy 379.937132 -224.539804)
			(xy 379.887957 -224.537823) (xy 379.839738 -224.527979) (xy 379.793722 -224.510527) (xy 379.751101 -224.48592)
			(xy 379.71298 -224.454795) (xy 379.680345 -224.417958) (xy 379.654042 -224.376362) (xy 379.634751 -224.331086)
			(xy 379.622974 -224.283302) (xy 379.619014 -224.234248) (xy 379.290072 -224.234248) (xy 379.289577 -224.258855)
			(xy 379.281682 -224.307432) (xy 379.266098 -224.354113) (xy 379.243227 -224.39769) (xy 379.213662 -224.437034)
			(xy 379.178169 -224.471126) (xy 379.137666 -224.499082) (xy 379.093204 -224.52018) (xy 379.045933 -224.533872)
			(xy 378.997078 -224.539804) (xy 378.947903 -224.537823) (xy 378.899684 -224.527979) (xy 378.853668 -224.510527)
			(xy 378.811047 -224.48592) (xy 378.772926 -224.454795) (xy 378.740291 -224.417958) (xy 378.713988 -224.376362)
			(xy 378.694697 -224.331086) (xy 378.68292 -224.283302) (xy 378.67896 -224.234248) (xy 378.350018 -224.234248)
			(xy 378.349523 -224.258855) (xy 378.341628 -224.307432) (xy 378.326044 -224.354113) (xy 378.303173 -224.39769)
			(xy 378.273608 -224.437034) (xy 378.238115 -224.471126) (xy 378.197612 -224.499082) (xy 378.15315 -224.52018)
			(xy 378.105879 -224.533872) (xy 378.057024 -224.539804) (xy 378.007849 -224.537823) (xy 377.95963 -224.527979)
			(xy 377.913614 -224.510527) (xy 377.870993 -224.48592) (xy 377.832872 -224.454795) (xy 377.800237 -224.417958)
			(xy 377.773934 -224.376362) (xy 377.754643 -224.331086) (xy 377.742866 -224.283302) (xy 377.738906 -224.234248)
			(xy 377.410218 -224.234248) (xy 377.409723 -224.258855) (xy 377.401828 -224.307432) (xy 377.386244 -224.354113)
			(xy 377.363373 -224.39769) (xy 377.333808 -224.437034) (xy 377.298315 -224.471126) (xy 377.257812 -224.499082)
			(xy 377.21335 -224.52018) (xy 377.166079 -224.533872) (xy 377.117224 -224.539804) (xy 377.068049 -224.537823)
			(xy 377.01983 -224.527979) (xy 376.973814 -224.510527) (xy 376.931193 -224.48592) (xy 376.893072 -224.454795)
			(xy 376.860437 -224.417958) (xy 376.834134 -224.376362) (xy 376.814843 -224.331086) (xy 376.803066 -224.283302)
			(xy 376.799106 -224.234248) (xy 376.470164 -224.234248) (xy 376.469669 -224.258855) (xy 376.461774 -224.307432)
			(xy 376.44619 -224.354113) (xy 376.423319 -224.39769) (xy 376.393754 -224.437034) (xy 376.358261 -224.471126)
			(xy 376.317758 -224.499082) (xy 376.273296 -224.52018) (xy 376.226025 -224.533872) (xy 376.17717 -224.539804)
			(xy 376.127995 -224.537823) (xy 376.079776 -224.527979) (xy 376.03376 -224.510527) (xy 375.991139 -224.48592)
			(xy 375.953018 -224.454795) (xy 375.920383 -224.417958) (xy 375.89408 -224.376362) (xy 375.874789 -224.331086)
			(xy 375.863012 -224.283302) (xy 375.859052 -224.234248) (xy 373.649495 -224.234248) (xy 373.649492 -224.25906)
			(xy 373.641455 -224.308041) (xy 373.625601 -224.355076) (xy 373.614442 -224.37725) (xy 373.611741 -224.38278)
			(xy 373.608776 -224.394721) (xy 373.6086 -224.400872) (xy 373.6086 -224.651062) (xy 373.609166 -224.66273)
			(xy 373.61949 -224.683654) (xy 373.628412 -224.691194) (xy 373.70131 -224.747582) (xy 373.724678 -224.752154)
			(xy 373.736108 -224.749106) (xy 373.75525 -224.744349) (xy 373.794364 -224.739249) (xy 373.814086 -224.738946)
			(xy 373.814848 -224.738946) (xy 373.840105 -224.739471) (xy 373.889928 -224.747792) (xy 373.937702 -224.7642)
			(xy 373.982125 -224.788246) (xy 374.021984 -224.819276) (xy 374.056193 -224.856442) (xy 374.083818 -224.898732)
			(xy 374.104108 -224.944991) (xy 374.116507 -224.993959) (xy 374.120674 -225.044254) (xy 374.449098 -225.044254)
			(xy 374.453058 -224.9952) (xy 374.464835 -224.947416) (xy 374.484126 -224.90214) (xy 374.510429 -224.860544)
			(xy 374.543064 -224.823707) (xy 374.581185 -224.792582) (xy 374.623806 -224.767975) (xy 374.669822 -224.750523)
			(xy 374.718041 -224.740679) (xy 374.767216 -224.738698) (xy 374.816071 -224.74463) (xy 374.863342 -224.758322)
			(xy 374.907804 -224.77942) (xy 374.948307 -224.807376) (xy 374.9838 -224.841468) (xy 375.013365 -224.880812)
			(xy 375.036236 -224.924389) (xy 375.05182 -224.97107) (xy 375.059715 -225.019647) (xy 375.06021 -225.044254)
			(xy 375.388898 -225.044254) (xy 375.392858 -224.9952) (xy 375.404635 -224.947416) (xy 375.423926 -224.90214)
			(xy 375.450229 -224.860544) (xy 375.482864 -224.823707) (xy 375.520985 -224.792582) (xy 375.563606 -224.767975)
			(xy 375.609622 -224.750523) (xy 375.657841 -224.740679) (xy 375.707016 -224.738698) (xy 375.755871 -224.74463)
			(xy 375.803142 -224.758322) (xy 375.847604 -224.77942) (xy 375.888107 -224.807376) (xy 375.9236 -224.841468)
			(xy 375.953165 -224.880812) (xy 375.976036 -224.924389) (xy 375.99162 -224.97107) (xy 375.999515 -225.019647)
			(xy 376.00001 -225.044254) (xy 376.328952 -225.044254) (xy 376.332912 -224.9952) (xy 376.344689 -224.947416)
			(xy 376.36398 -224.90214) (xy 376.390283 -224.860544) (xy 376.422918 -224.823707) (xy 376.461039 -224.792582)
			(xy 376.50366 -224.767975) (xy 376.549676 -224.750523) (xy 376.597895 -224.740679) (xy 376.64707 -224.738698)
			(xy 376.695925 -224.74463) (xy 376.743196 -224.758322) (xy 376.787658 -224.77942) (xy 376.828161 -224.807376)
			(xy 376.863654 -224.841468) (xy 376.893219 -224.880812) (xy 376.91609 -224.924389) (xy 376.931674 -224.97107)
			(xy 376.939569 -225.019647) (xy 376.940064 -225.044254) (xy 377.258575 -225.044254) (xy 377.26267 -224.993526)
			(xy 377.274849 -224.944112) (xy 377.294797 -224.897292) (xy 377.321998 -224.854278) (xy 377.355746 -224.816184)
			(xy 377.395168 -224.783997) (xy 377.439242 -224.758551) (xy 377.486828 -224.740504) (xy 377.536692 -224.730324)
			(xy 377.587544 -224.728275) (xy 377.638065 -224.734409) (xy 377.686949 -224.748569) (xy 377.732928 -224.770386)
			(xy 377.774812 -224.799296) (xy 377.811516 -224.834551) (xy 377.842089 -224.875237) (xy 377.86574 -224.9203)
			(xy 377.881856 -224.968574) (xy 377.89002 -225.018808) (xy 377.890532 -225.044254) (xy 378.20906 -225.044254)
			(xy 378.21302 -224.9952) (xy 378.224797 -224.947416) (xy 378.244088 -224.90214) (xy 378.270391 -224.860544)
			(xy 378.303026 -224.823707) (xy 378.341147 -224.792582) (xy 378.383768 -224.767975) (xy 378.429784 -224.750523)
			(xy 378.478003 -224.740679) (xy 378.527178 -224.738698) (xy 378.576033 -224.74463) (xy 378.623304 -224.758322)
			(xy 378.667766 -224.77942) (xy 378.708269 -224.807376) (xy 378.743762 -224.841468) (xy 378.773327 -224.880812)
			(xy 378.796198 -224.924389) (xy 378.811782 -224.97107) (xy 378.819677 -225.019647) (xy 378.820172 -225.044254)
			(xy 379.149114 -225.044254) (xy 379.153074 -224.9952) (xy 379.164851 -224.947416) (xy 379.184142 -224.90214)
			(xy 379.210445 -224.860544) (xy 379.24308 -224.823707) (xy 379.281201 -224.792582) (xy 379.323822 -224.767975)
			(xy 379.369838 -224.750523) (xy 379.418057 -224.740679) (xy 379.467232 -224.738698) (xy 379.516087 -224.74463)
			(xy 379.563358 -224.758322) (xy 379.60782 -224.77942) (xy 379.648323 -224.807376) (xy 379.683816 -224.841468)
			(xy 379.713381 -224.880812) (xy 379.736252 -224.924389) (xy 379.751836 -224.97107) (xy 379.759731 -225.019647)
			(xy 379.760226 -225.044254) (xy 380.078483 -225.044254) (xy 380.082578 -224.993526) (xy 380.094757 -224.944112)
			(xy 380.114705 -224.897292) (xy 380.141906 -224.854278) (xy 380.175654 -224.816184) (xy 380.215076 -224.783997)
			(xy 380.25915 -224.758551) (xy 380.306736 -224.740504) (xy 380.3566 -224.730324) (xy 380.407452 -224.728275)
			(xy 380.457973 -224.734409) (xy 380.506857 -224.748569) (xy 380.552836 -224.770386) (xy 380.59472 -224.799296)
			(xy 380.631424 -224.834551) (xy 380.661997 -224.875237) (xy 380.685648 -224.9203) (xy 380.701764 -224.968574)
			(xy 380.709928 -225.018808) (xy 380.71044 -225.044254) (xy 381.028968 -225.044254) (xy 381.032928 -224.9952)
			(xy 381.044705 -224.947416) (xy 381.063996 -224.90214) (xy 381.090299 -224.860544) (xy 381.122934 -224.823707)
			(xy 381.161055 -224.792582) (xy 381.203676 -224.767975) (xy 381.249692 -224.750523) (xy 381.297911 -224.740679)
			(xy 381.347086 -224.738698) (xy 381.395941 -224.74463) (xy 381.443212 -224.758322) (xy 381.487674 -224.77942)
			(xy 381.528177 -224.807376) (xy 381.56367 -224.841468) (xy 381.593235 -224.880812) (xy 381.616106 -224.924389)
			(xy 381.63169 -224.97107) (xy 381.639585 -225.019647) (xy 381.64008 -225.044254) (xy 381.639585 -225.068861)
			(xy 381.63169 -225.117438) (xy 381.616106 -225.164119) (xy 381.593235 -225.207696) (xy 381.56367 -225.24704)
			(xy 381.528177 -225.281132) (xy 381.487674 -225.309088) (xy 381.443212 -225.330186) (xy 381.395941 -225.343878)
			(xy 381.347086 -225.34981) (xy 381.297911 -225.347829) (xy 381.249692 -225.337985) (xy 381.203676 -225.320533)
			(xy 381.161055 -225.295926) (xy 381.122934 -225.264801) (xy 381.090299 -225.227964) (xy 381.063996 -225.186368)
			(xy 381.044705 -225.141092) (xy 381.032928 -225.093308) (xy 381.028968 -225.044254) (xy 380.71044 -225.044254)
			(xy 380.709928 -225.0697) (xy 380.701764 -225.119934) (xy 380.685648 -225.168208) (xy 380.661997 -225.213271)
			(xy 380.631424 -225.253957) (xy 380.59472 -225.289212) (xy 380.552836 -225.318122) (xy 380.506857 -225.339939)
			(xy 380.457973 -225.354099) (xy 380.407452 -225.360233) (xy 380.3566 -225.358184) (xy 380.306736 -225.348004)
			(xy 380.25915 -225.329957) (xy 380.215076 -225.304511) (xy 380.175654 -225.272324) (xy 380.141906 -225.23423)
			(xy 380.114705 -225.191216) (xy 380.094757 -225.144396) (xy 380.082578 -225.094982) (xy 380.078483 -225.044254)
			(xy 379.760226 -225.044254) (xy 379.759731 -225.068861) (xy 379.751836 -225.117438) (xy 379.736252 -225.164119)
			(xy 379.713381 -225.207696) (xy 379.683816 -225.24704) (xy 379.648323 -225.281132) (xy 379.60782 -225.309088)
			(xy 379.563358 -225.330186) (xy 379.516087 -225.343878) (xy 379.467232 -225.34981) (xy 379.418057 -225.347829)
			(xy 379.369838 -225.337985) (xy 379.323822 -225.320533) (xy 379.281201 -225.295926) (xy 379.24308 -225.264801)
			(xy 379.210445 -225.227964) (xy 379.184142 -225.186368) (xy 379.164851 -225.141092) (xy 379.153074 -225.093308)
			(xy 379.149114 -225.044254) (xy 378.820172 -225.044254) (xy 378.819677 -225.068861) (xy 378.811782 -225.117438)
			(xy 378.796198 -225.164119) (xy 378.773327 -225.207696) (xy 378.743762 -225.24704) (xy 378.708269 -225.281132)
			(xy 378.667766 -225.309088) (xy 378.623304 -225.330186) (xy 378.576033 -225.343878) (xy 378.527178 -225.34981)
			(xy 378.478003 -225.347829) (xy 378.429784 -225.337985) (xy 378.383768 -225.320533) (xy 378.341147 -225.295926)
			(xy 378.303026 -225.264801) (xy 378.270391 -225.227964) (xy 378.244088 -225.186368) (xy 378.224797 -225.141092)
			(xy 378.21302 -225.093308) (xy 378.20906 -225.044254) (xy 377.890532 -225.044254) (xy 377.89002 -225.0697)
			(xy 377.881856 -225.119934) (xy 377.86574 -225.168208) (xy 377.842089 -225.213271) (xy 377.811516 -225.253957)
			(xy 377.774812 -225.289212) (xy 377.732928 -225.318122) (xy 377.686949 -225.339939) (xy 377.638065 -225.354099)
			(xy 377.587544 -225.360233) (xy 377.536692 -225.358184) (xy 377.486828 -225.348004) (xy 377.439242 -225.329957)
			(xy 377.395168 -225.304511) (xy 377.355746 -225.272324) (xy 377.321998 -225.23423) (xy 377.294797 -225.191216)
			(xy 377.274849 -225.144396) (xy 377.26267 -225.094982) (xy 377.258575 -225.044254) (xy 376.940064 -225.044254)
			(xy 376.939569 -225.068861) (xy 376.931674 -225.117438) (xy 376.91609 -225.164119) (xy 376.893219 -225.207696)
			(xy 376.863654 -225.24704) (xy 376.828161 -225.281132) (xy 376.787658 -225.309088) (xy 376.743196 -225.330186)
			(xy 376.695925 -225.343878) (xy 376.64707 -225.34981) (xy 376.597895 -225.347829) (xy 376.549676 -225.337985)
			(xy 376.50366 -225.320533) (xy 376.461039 -225.295926) (xy 376.422918 -225.264801) (xy 376.390283 -225.227964)
			(xy 376.36398 -225.186368) (xy 376.344689 -225.141092) (xy 376.332912 -225.093308) (xy 376.328952 -225.044254)
			(xy 376.00001 -225.044254) (xy 375.999515 -225.068861) (xy 375.99162 -225.117438) (xy 375.976036 -225.164119)
			(xy 375.953165 -225.207696) (xy 375.9236 -225.24704) (xy 375.888107 -225.281132) (xy 375.847604 -225.309088)
			(xy 375.803142 -225.330186) (xy 375.755871 -225.343878) (xy 375.707016 -225.34981) (xy 375.657841 -225.347829)
			(xy 375.609622 -225.337985) (xy 375.563606 -225.320533) (xy 375.520985 -225.295926) (xy 375.482864 -225.264801)
			(xy 375.450229 -225.227964) (xy 375.423926 -225.186368) (xy 375.404635 -225.141092) (xy 375.392858 -225.093308)
			(xy 375.388898 -225.044254) (xy 375.06021 -225.044254) (xy 375.059715 -225.068861) (xy 375.05182 -225.117438)
			(xy 375.036236 -225.164119) (xy 375.013365 -225.207696) (xy 374.9838 -225.24704) (xy 374.948307 -225.281132)
			(xy 374.907804 -225.309088) (xy 374.863342 -225.330186) (xy 374.816071 -225.343878) (xy 374.767216 -225.34981)
			(xy 374.718041 -225.347829) (xy 374.669822 -225.337985) (xy 374.623806 -225.320533) (xy 374.581185 -225.295926)
			(xy 374.543064 -225.264801) (xy 374.510429 -225.227964) (xy 374.484126 -225.186368) (xy 374.464835 -225.141092)
			(xy 374.453058 -225.093308) (xy 374.449098 -225.044254) (xy 374.120674 -225.044254) (xy 374.120678 -225.0443)
			(xy 374.116507 -225.094641) (xy 374.104108 -225.143609) (xy 374.083818 -225.189868) (xy 374.056193 -225.232158)
			(xy 374.021984 -225.269324) (xy 373.982125 -225.300354) (xy 373.937702 -225.3244) (xy 373.889928 -225.340808)
			(xy 373.840105 -225.349129) (xy 373.814848 -225.349562) (xy 373.814086 -225.349562) (xy 373.794366 -225.349232)
			(xy 373.755255 -225.344132) (xy 373.736108 -225.339402) (xy 373.724678 -225.336354) (xy 373.70131 -225.340926)
			(xy 373.628412 -225.397314) (xy 373.619541 -225.404896) (xy 373.609211 -225.425794) (xy 373.6086 -225.437446)
			(xy 373.6086 -225.687636) (xy 373.608765 -225.69379) (xy 373.61171 -225.705741) (xy 373.614442 -225.711258)
			(xy 373.625641 -225.733414) (xy 373.641497 -225.780456) (xy 373.649534 -225.829444) (xy 373.649536 -225.85426)
			(xy 373.978944 -225.85426) (xy 373.982904 -225.805206) (xy 373.994681 -225.757422) (xy 374.013972 -225.712146)
			(xy 374.040275 -225.67055) (xy 374.07291 -225.633713) (xy 374.111031 -225.602588) (xy 374.153652 -225.577981)
			(xy 374.199668 -225.560529) (xy 374.247887 -225.550685) (xy 374.297062 -225.548704) (xy 374.345917 -225.554636)
			(xy 374.393188 -225.568328) (xy 374.43765 -225.589426) (xy 374.478153 -225.617382) (xy 374.513646 -225.651474)
			(xy 374.543211 -225.690818) (xy 374.566082 -225.734395) (xy 374.581666 -225.781076) (xy 374.589561 -225.829653)
			(xy 374.590056 -225.85426) (xy 374.918998 -225.85426) (xy 374.922958 -225.805206) (xy 374.934735 -225.757422)
			(xy 374.954026 -225.712146) (xy 374.980329 -225.67055) (xy 375.012964 -225.633713) (xy 375.051085 -225.602588)
			(xy 375.093706 -225.577981) (xy 375.139722 -225.560529) (xy 375.187941 -225.550685) (xy 375.237116 -225.548704)
			(xy 375.285971 -225.554636) (xy 375.333242 -225.568328) (xy 375.377704 -225.589426) (xy 375.418207 -225.617382)
			(xy 375.4537 -225.651474) (xy 375.483265 -225.690818) (xy 375.506136 -225.734395) (xy 375.52172 -225.781076)
			(xy 375.529615 -225.829653) (xy 375.53011 -225.85426) (xy 375.848621 -225.85426) (xy 375.852716 -225.803532)
			(xy 375.864895 -225.754118) (xy 375.884843 -225.707298) (xy 375.912044 -225.664284) (xy 375.945792 -225.62619)
			(xy 375.985214 -225.594003) (xy 376.029288 -225.568557) (xy 376.076874 -225.55051) (xy 376.126738 -225.54033)
			(xy 376.17759 -225.538281) (xy 376.228111 -225.544415) (xy 376.276995 -225.558575) (xy 376.322974 -225.580392)
			(xy 376.364858 -225.609302) (xy 376.401562 -225.644557) (xy 376.432135 -225.685243) (xy 376.455786 -225.730306)
			(xy 376.471902 -225.77858) (xy 376.480066 -225.828814) (xy 376.480578 -225.85426) (xy 376.788675 -225.85426)
			(xy 376.79277 -225.803532) (xy 376.804949 -225.754118) (xy 376.824897 -225.707298) (xy 376.852098 -225.664284)
			(xy 376.885846 -225.62619) (xy 376.925268 -225.594003) (xy 376.969342 -225.568557) (xy 377.016928 -225.55051)
			(xy 377.066792 -225.54033) (xy 377.117644 -225.538281) (xy 377.168165 -225.544415) (xy 377.217049 -225.558575)
			(xy 377.263028 -225.580392) (xy 377.304912 -225.609302) (xy 377.341616 -225.644557) (xy 377.372189 -225.685243)
			(xy 377.39584 -225.730306) (xy 377.411956 -225.77858) (xy 377.42012 -225.828814) (xy 377.420632 -225.85426)
			(xy 377.738906 -225.85426) (xy 377.742866 -225.805206) (xy 377.754643 -225.757422) (xy 377.773934 -225.712146)
			(xy 377.800237 -225.67055) (xy 377.832872 -225.633713) (xy 377.870993 -225.602588) (xy 377.913614 -225.577981)
			(xy 377.95963 -225.560529) (xy 378.007849 -225.550685) (xy 378.057024 -225.548704) (xy 378.105879 -225.554636)
			(xy 378.15315 -225.568328) (xy 378.197612 -225.589426) (xy 378.238115 -225.617382) (xy 378.273608 -225.651474)
			(xy 378.303173 -225.690818) (xy 378.326044 -225.734395) (xy 378.341628 -225.781076) (xy 378.349523 -225.829653)
			(xy 378.350018 -225.85426) (xy 378.668529 -225.85426) (xy 378.672624 -225.803532) (xy 378.684803 -225.754118)
			(xy 378.704751 -225.707298) (xy 378.731952 -225.664284) (xy 378.7657 -225.62619) (xy 378.805122 -225.594003)
			(xy 378.849196 -225.568557) (xy 378.896782 -225.55051) (xy 378.946646 -225.54033) (xy 378.997498 -225.538281)
			(xy 379.048019 -225.544415) (xy 379.096903 -225.558575) (xy 379.142882 -225.580392) (xy 379.184766 -225.609302)
			(xy 379.22147 -225.644557) (xy 379.252043 -225.685243) (xy 379.275694 -225.730306) (xy 379.29181 -225.77858)
			(xy 379.299974 -225.828814) (xy 379.300486 -225.85426) (xy 379.619014 -225.85426) (xy 379.622974 -225.805206)
			(xy 379.634751 -225.757422) (xy 379.654042 -225.712146) (xy 379.680345 -225.67055) (xy 379.71298 -225.633713)
			(xy 379.751101 -225.602588) (xy 379.793722 -225.577981) (xy 379.839738 -225.560529) (xy 379.887957 -225.550685)
			(xy 379.937132 -225.548704) (xy 379.985987 -225.554636) (xy 380.033258 -225.568328) (xy 380.07772 -225.589426)
			(xy 380.118223 -225.617382) (xy 380.153716 -225.651474) (xy 380.183281 -225.690818) (xy 380.206152 -225.734395)
			(xy 380.221736 -225.781076) (xy 380.229631 -225.829653) (xy 380.230126 -225.85426) (xy 380.548637 -225.85426)
			(xy 380.552732 -225.803532) (xy 380.564911 -225.754118) (xy 380.584859 -225.707298) (xy 380.61206 -225.664284)
			(xy 380.645808 -225.62619) (xy 380.68523 -225.594003) (xy 380.729304 -225.568557) (xy 380.77689 -225.55051)
			(xy 380.826754 -225.54033) (xy 380.877606 -225.538281) (xy 380.928127 -225.544415) (xy 380.977011 -225.558575)
			(xy 381.02299 -225.580392) (xy 381.064874 -225.609302) (xy 381.101578 -225.644557) (xy 381.132151 -225.685243)
			(xy 381.155802 -225.730306) (xy 381.171918 -225.77858) (xy 381.180082 -225.828814) (xy 381.180594 -225.85426)
			(xy 381.499122 -225.85426) (xy 381.503082 -225.805206) (xy 381.514859 -225.757422) (xy 381.53415 -225.712146)
			(xy 381.560453 -225.67055) (xy 381.593088 -225.633713) (xy 381.631209 -225.602588) (xy 381.67383 -225.577981)
			(xy 381.719846 -225.560529) (xy 381.768065 -225.550685) (xy 381.81724 -225.548704) (xy 381.866095 -225.554636)
			(xy 381.913366 -225.568328) (xy 381.957828 -225.589426) (xy 381.998331 -225.617382) (xy 382.033824 -225.651474)
			(xy 382.063389 -225.690818) (xy 382.08626 -225.734395) (xy 382.101844 -225.781076) (xy 382.109739 -225.829653)
			(xy 382.110234 -225.85426) (xy 382.438922 -225.85426) (xy 382.442882 -225.805206) (xy 382.454659 -225.757422)
			(xy 382.47395 -225.712146) (xy 382.500253 -225.67055) (xy 382.532888 -225.633713) (xy 382.571009 -225.602588)
			(xy 382.61363 -225.577981) (xy 382.659646 -225.560529) (xy 382.707865 -225.550685) (xy 382.75704 -225.548704)
			(xy 382.805895 -225.554636) (xy 382.853166 -225.568328) (xy 382.897628 -225.589426) (xy 382.938131 -225.617382)
			(xy 382.973624 -225.651474) (xy 383.003189 -225.690818) (xy 383.02606 -225.734395) (xy 383.041644 -225.781076)
			(xy 383.049539 -225.829653) (xy 383.050034 -225.85426) (xy 383.378976 -225.85426) (xy 383.382936 -225.805206)
			(xy 383.394713 -225.757422) (xy 383.414004 -225.712146) (xy 383.440307 -225.67055) (xy 383.472942 -225.633713)
			(xy 383.511063 -225.602588) (xy 383.553684 -225.577981) (xy 383.5997 -225.560529) (xy 383.647919 -225.550685)
			(xy 383.697094 -225.548704) (xy 383.745949 -225.554636) (xy 383.79322 -225.568328) (xy 383.837682 -225.589426)
			(xy 383.878185 -225.617382) (xy 383.913678 -225.651474) (xy 383.943243 -225.690818) (xy 383.966114 -225.734395)
			(xy 383.981698 -225.781076) (xy 383.989593 -225.829653) (xy 383.990088 -225.85426) (xy 384.31903 -225.85426)
			(xy 384.32299 -225.805206) (xy 384.334767 -225.757422) (xy 384.354058 -225.712146) (xy 384.380361 -225.67055)
			(xy 384.412996 -225.633713) (xy 384.451117 -225.602588) (xy 384.493738 -225.577981) (xy 384.539754 -225.560529)
			(xy 384.587973 -225.550685) (xy 384.637148 -225.548704) (xy 384.686003 -225.554636) (xy 384.733274 -225.568328)
			(xy 384.777736 -225.589426) (xy 384.818239 -225.617382) (xy 384.853732 -225.651474) (xy 384.883297 -225.690818)
			(xy 384.906168 -225.734395) (xy 384.921752 -225.781076) (xy 384.929647 -225.829653) (xy 384.930142 -225.85426)
			(xy 385.259084 -225.85426) (xy 385.263044 -225.805206) (xy 385.274821 -225.757422) (xy 385.294112 -225.712146)
			(xy 385.320415 -225.67055) (xy 385.35305 -225.633713) (xy 385.391171 -225.602588) (xy 385.433792 -225.577981)
			(xy 385.479808 -225.560529) (xy 385.528027 -225.550685) (xy 385.577202 -225.548704) (xy 385.626057 -225.554636)
			(xy 385.673328 -225.568328) (xy 385.71779 -225.589426) (xy 385.758293 -225.617382) (xy 385.793786 -225.651474)
			(xy 385.823351 -225.690818) (xy 385.846222 -225.734395) (xy 385.861806 -225.781076) (xy 385.869701 -225.829653)
			(xy 385.870196 -225.85426) (xy 386.199138 -225.85426) (xy 386.203098 -225.805206) (xy 386.214875 -225.757422)
			(xy 386.234166 -225.712146) (xy 386.260469 -225.67055) (xy 386.293104 -225.633713) (xy 386.331225 -225.602588)
			(xy 386.373846 -225.577981) (xy 386.419862 -225.560529) (xy 386.468081 -225.550685) (xy 386.517256 -225.548704)
			(xy 386.566111 -225.554636) (xy 386.613382 -225.568328) (xy 386.657844 -225.589426) (xy 386.698347 -225.617382)
			(xy 386.73384 -225.651474) (xy 386.763405 -225.690818) (xy 386.786276 -225.734395) (xy 386.80186 -225.781076)
			(xy 386.809755 -225.829653) (xy 386.81025 -225.85426) (xy 386.809755 -225.878867) (xy 386.80186 -225.927444)
			(xy 386.786276 -225.974125) (xy 386.763405 -226.017702) (xy 386.73384 -226.057046) (xy 386.698347 -226.091138)
			(xy 386.657844 -226.119094) (xy 386.613382 -226.140192) (xy 386.566111 -226.153884) (xy 386.517256 -226.159816)
			(xy 386.468081 -226.157835) (xy 386.419862 -226.147991) (xy 386.373846 -226.130539) (xy 386.331225 -226.105932)
			(xy 386.293104 -226.074807) (xy 386.260469 -226.03797) (xy 386.234166 -225.996374) (xy 386.214875 -225.951098)
			(xy 386.203098 -225.903314) (xy 386.199138 -225.85426) (xy 385.870196 -225.85426) (xy 385.869701 -225.878867)
			(xy 385.861806 -225.927444) (xy 385.846222 -225.974125) (xy 385.823351 -226.017702) (xy 385.793786 -226.057046)
			(xy 385.758293 -226.091138) (xy 385.71779 -226.119094) (xy 385.673328 -226.140192) (xy 385.626057 -226.153884)
			(xy 385.577202 -226.159816) (xy 385.528027 -226.157835) (xy 385.479808 -226.147991) (xy 385.433792 -226.130539)
			(xy 385.391171 -226.105932) (xy 385.35305 -226.074807) (xy 385.320415 -226.03797) (xy 385.294112 -225.996374)
			(xy 385.274821 -225.951098) (xy 385.263044 -225.903314) (xy 385.259084 -225.85426) (xy 384.930142 -225.85426)
			(xy 384.929647 -225.878867) (xy 384.921752 -225.927444) (xy 384.906168 -225.974125) (xy 384.883297 -226.017702)
			(xy 384.853732 -226.057046) (xy 384.818239 -226.091138) (xy 384.777736 -226.119094) (xy 384.733274 -226.140192)
			(xy 384.686003 -226.153884) (xy 384.637148 -226.159816) (xy 384.587973 -226.157835) (xy 384.539754 -226.147991)
			(xy 384.493738 -226.130539) (xy 384.451117 -226.105932) (xy 384.412996 -226.074807) (xy 384.380361 -226.03797)
			(xy 384.354058 -225.996374) (xy 384.334767 -225.951098) (xy 384.32299 -225.903314) (xy 384.31903 -225.85426)
			(xy 383.990088 -225.85426) (xy 383.989593 -225.878867) (xy 383.981698 -225.927444) (xy 383.966114 -225.974125)
			(xy 383.943243 -226.017702) (xy 383.913678 -226.057046) (xy 383.878185 -226.091138) (xy 383.837682 -226.119094)
			(xy 383.79322 -226.140192) (xy 383.745949 -226.153884) (xy 383.697094 -226.159816) (xy 383.647919 -226.157835)
			(xy 383.5997 -226.147991) (xy 383.553684 -226.130539) (xy 383.511063 -226.105932) (xy 383.472942 -226.074807)
			(xy 383.440307 -226.03797) (xy 383.414004 -225.996374) (xy 383.394713 -225.951098) (xy 383.382936 -225.903314)
			(xy 383.378976 -225.85426) (xy 383.050034 -225.85426) (xy 383.049539 -225.878867) (xy 383.041644 -225.927444)
			(xy 383.02606 -225.974125) (xy 383.003189 -226.017702) (xy 382.973624 -226.057046) (xy 382.938131 -226.091138)
			(xy 382.897628 -226.119094) (xy 382.853166 -226.140192) (xy 382.805895 -226.153884) (xy 382.75704 -226.159816)
			(xy 382.707865 -226.157835) (xy 382.659646 -226.147991) (xy 382.61363 -226.130539) (xy 382.571009 -226.105932)
			(xy 382.532888 -226.074807) (xy 382.500253 -226.03797) (xy 382.47395 -225.996374) (xy 382.454659 -225.951098)
			(xy 382.442882 -225.903314) (xy 382.438922 -225.85426) (xy 382.110234 -225.85426) (xy 382.109739 -225.878867)
			(xy 382.101844 -225.927444) (xy 382.08626 -225.974125) (xy 382.063389 -226.017702) (xy 382.033824 -226.057046)
			(xy 381.998331 -226.091138) (xy 381.957828 -226.119094) (xy 381.913366 -226.140192) (xy 381.866095 -226.153884)
			(xy 381.81724 -226.159816) (xy 381.768065 -226.157835) (xy 381.719846 -226.147991) (xy 381.67383 -226.130539)
			(xy 381.631209 -226.105932) (xy 381.593088 -226.074807) (xy 381.560453 -226.03797) (xy 381.53415 -225.996374)
			(xy 381.514859 -225.951098) (xy 381.503082 -225.903314) (xy 381.499122 -225.85426) (xy 381.180594 -225.85426)
			(xy 381.180082 -225.879706) (xy 381.171918 -225.92994) (xy 381.155802 -225.978214) (xy 381.132151 -226.023277)
			(xy 381.101578 -226.063963) (xy 381.064874 -226.099218) (xy 381.02299 -226.128128) (xy 380.977011 -226.149945)
			(xy 380.928127 -226.164105) (xy 380.877606 -226.170239) (xy 380.826754 -226.16819) (xy 380.77689 -226.15801)
			(xy 380.729304 -226.139963) (xy 380.68523 -226.114517) (xy 380.645808 -226.08233) (xy 380.61206 -226.044236)
			(xy 380.584859 -226.001222) (xy 380.564911 -225.954402) (xy 380.552732 -225.904988) (xy 380.548637 -225.85426)
			(xy 380.230126 -225.85426) (xy 380.229631 -225.878867) (xy 380.221736 -225.927444) (xy 380.206152 -225.974125)
			(xy 380.183281 -226.017702) (xy 380.153716 -226.057046) (xy 380.118223 -226.091138) (xy 380.07772 -226.119094)
			(xy 380.033258 -226.140192) (xy 379.985987 -226.153884) (xy 379.937132 -226.159816) (xy 379.887957 -226.157835)
			(xy 379.839738 -226.147991) (xy 379.793722 -226.130539) (xy 379.751101 -226.105932) (xy 379.71298 -226.074807)
			(xy 379.680345 -226.03797) (xy 379.654042 -225.996374) (xy 379.634751 -225.951098) (xy 379.622974 -225.903314)
			(xy 379.619014 -225.85426) (xy 379.300486 -225.85426) (xy 379.299974 -225.879706) (xy 379.29181 -225.92994)
			(xy 379.275694 -225.978214) (xy 379.252043 -226.023277) (xy 379.22147 -226.063963) (xy 379.184766 -226.099218)
			(xy 379.142882 -226.128128) (xy 379.096903 -226.149945) (xy 379.048019 -226.164105) (xy 378.997498 -226.170239)
			(xy 378.946646 -226.16819) (xy 378.896782 -226.15801) (xy 378.849196 -226.139963) (xy 378.805122 -226.114517)
			(xy 378.7657 -226.08233) (xy 378.731952 -226.044236) (xy 378.704751 -226.001222) (xy 378.684803 -225.954402)
			(xy 378.672624 -225.904988) (xy 378.668529 -225.85426) (xy 378.350018 -225.85426) (xy 378.349523 -225.878867)
			(xy 378.341628 -225.927444) (xy 378.326044 -225.974125) (xy 378.303173 -226.017702) (xy 378.273608 -226.057046)
			(xy 378.238115 -226.091138) (xy 378.197612 -226.119094) (xy 378.15315 -226.140192) (xy 378.105879 -226.153884)
			(xy 378.057024 -226.159816) (xy 378.007849 -226.157835) (xy 377.95963 -226.147991) (xy 377.913614 -226.130539)
			(xy 377.870993 -226.105932) (xy 377.832872 -226.074807) (xy 377.800237 -226.03797) (xy 377.773934 -225.996374)
			(xy 377.754643 -225.951098) (xy 377.742866 -225.903314) (xy 377.738906 -225.85426) (xy 377.420632 -225.85426)
			(xy 377.42012 -225.879706) (xy 377.411956 -225.92994) (xy 377.39584 -225.978214) (xy 377.372189 -226.023277)
			(xy 377.341616 -226.063963) (xy 377.304912 -226.099218) (xy 377.263028 -226.128128) (xy 377.217049 -226.149945)
			(xy 377.168165 -226.164105) (xy 377.117644 -226.170239) (xy 377.066792 -226.16819) (xy 377.016928 -226.15801)
			(xy 376.969342 -226.139963) (xy 376.925268 -226.114517) (xy 376.885846 -226.08233) (xy 376.852098 -226.044236)
			(xy 376.824897 -226.001222) (xy 376.804949 -225.954402) (xy 376.79277 -225.904988) (xy 376.788675 -225.85426)
			(xy 376.480578 -225.85426) (xy 376.480066 -225.879706) (xy 376.471902 -225.92994) (xy 376.455786 -225.978214)
			(xy 376.432135 -226.023277) (xy 376.401562 -226.063963) (xy 376.364858 -226.099218) (xy 376.322974 -226.128128)
			(xy 376.276995 -226.149945) (xy 376.228111 -226.164105) (xy 376.17759 -226.170239) (xy 376.126738 -226.16819)
			(xy 376.076874 -226.15801) (xy 376.029288 -226.139963) (xy 375.985214 -226.114517) (xy 375.945792 -226.08233)
			(xy 375.912044 -226.044236) (xy 375.884843 -226.001222) (xy 375.864895 -225.954402) (xy 375.852716 -225.904988)
			(xy 375.848621 -225.85426) (xy 375.53011 -225.85426) (xy 375.529615 -225.878867) (xy 375.52172 -225.927444)
			(xy 375.506136 -225.974125) (xy 375.483265 -226.017702) (xy 375.4537 -226.057046) (xy 375.418207 -226.091138)
			(xy 375.377704 -226.119094) (xy 375.333242 -226.140192) (xy 375.285971 -226.153884) (xy 375.237116 -226.159816)
			(xy 375.187941 -226.157835) (xy 375.139722 -226.147991) (xy 375.093706 -226.130539) (xy 375.051085 -226.105932)
			(xy 375.012964 -226.074807) (xy 374.980329 -226.03797) (xy 374.954026 -225.996374) (xy 374.934735 -225.951098)
			(xy 374.922958 -225.903314) (xy 374.918998 -225.85426) (xy 374.590056 -225.85426) (xy 374.589561 -225.878867)
			(xy 374.581666 -225.927444) (xy 374.566082 -225.974125) (xy 374.543211 -226.017702) (xy 374.513646 -226.057046)
			(xy 374.478153 -226.091138) (xy 374.43765 -226.119094) (xy 374.393188 -226.140192) (xy 374.345917 -226.153884)
			(xy 374.297062 -226.159816) (xy 374.247887 -226.157835) (xy 374.199668 -226.147991) (xy 374.153652 -226.130539)
			(xy 374.111031 -226.105932) (xy 374.07291 -226.074807) (xy 374.040275 -226.03797) (xy 374.013972 -225.996374)
			(xy 373.994681 -225.951098) (xy 373.982904 -225.903314) (xy 373.978944 -225.85426) (xy 373.649536 -225.85426)
			(xy 373.649539 -225.879086) (xy 373.641514 -225.928075) (xy 373.625669 -225.975121) (xy 373.614442 -225.997262)
			(xy 373.611742 -226.002792) (xy 373.60878 -226.014733) (xy 373.6086 -226.020884) (xy 373.6086 -226.26701)
			(xy 373.609176 -226.278673) (xy 373.619512 -226.29958) (xy 373.628412 -226.307142) (xy 373.701564 -226.363784)
			(xy 373.711978 -226.365816) (xy 373.736938 -226.357795) (xy 373.788637 -226.349117) (xy 373.814848 -226.348544)
			(xy 373.839649 -226.34901) (xy 373.88864 -226.35678) (xy 373.935811 -226.372122) (xy 373.979999 -226.394657)
			(xy 374.020117 -226.42383) (xy 374.055174 -226.458922) (xy 374.084307 -226.499069) (xy 374.106798 -226.54328)
			(xy 374.122093 -226.590466) (xy 374.129815 -226.639464) (xy 374.130316 -226.664266) (xy 374.449098 -226.664266)
			(xy 374.453058 -226.615212) (xy 374.464835 -226.567428) (xy 374.484126 -226.522152) (xy 374.510429 -226.480556)
			(xy 374.543064 -226.443719) (xy 374.581185 -226.412594) (xy 374.623806 -226.387987) (xy 374.669822 -226.370535)
			(xy 374.718041 -226.360691) (xy 374.767216 -226.35871) (xy 374.816071 -226.364642) (xy 374.863342 -226.378334)
			(xy 374.907804 -226.399432) (xy 374.948307 -226.427388) (xy 374.9838 -226.46148) (xy 375.013365 -226.500824)
			(xy 375.036236 -226.544401) (xy 375.05182 -226.591082) (xy 375.059715 -226.639659) (xy 375.06021 -226.664266)
			(xy 375.378467 -226.664266) (xy 375.382562 -226.613538) (xy 375.394741 -226.564124) (xy 375.414689 -226.517304)
			(xy 375.44189 -226.47429) (xy 375.475638 -226.436196) (xy 375.51506 -226.404009) (xy 375.559134 -226.378563)
			(xy 375.60672 -226.360516) (xy 375.656584 -226.350336) (xy 375.707436 -226.348287) (xy 375.757957 -226.354421)
			(xy 375.806841 -226.368581) (xy 375.85282 -226.390398) (xy 375.894704 -226.419308) (xy 375.931408 -226.454563)
			(xy 375.961981 -226.495249) (xy 375.985632 -226.540312) (xy 376.001748 -226.588586) (xy 376.009912 -226.63882)
			(xy 376.010424 -226.664266) (xy 376.328952 -226.664266) (xy 376.332912 -226.615212) (xy 376.344689 -226.567428)
			(xy 376.36398 -226.522152) (xy 376.390283 -226.480556) (xy 376.422918 -226.443719) (xy 376.461039 -226.412594)
			(xy 376.50366 -226.387987) (xy 376.549676 -226.370535) (xy 376.597895 -226.360691) (xy 376.64707 -226.35871)
			(xy 376.695925 -226.364642) (xy 376.743196 -226.378334) (xy 376.787658 -226.399432) (xy 376.828161 -226.427388)
			(xy 376.863654 -226.46148) (xy 376.893219 -226.500824) (xy 376.91609 -226.544401) (xy 376.931674 -226.591082)
			(xy 376.939569 -226.639659) (xy 376.940064 -226.664266) (xy 377.258575 -226.664266) (xy 377.26267 -226.613538)
			(xy 377.274849 -226.564124) (xy 377.294797 -226.517304) (xy 377.321998 -226.47429) (xy 377.355746 -226.436196)
			(xy 377.395168 -226.404009) (xy 377.439242 -226.378563) (xy 377.486828 -226.360516) (xy 377.536692 -226.350336)
			(xy 377.587544 -226.348287) (xy 377.638065 -226.354421) (xy 377.686949 -226.368581) (xy 377.732928 -226.390398)
			(xy 377.774812 -226.419308) (xy 377.811516 -226.454563) (xy 377.842089 -226.495249) (xy 377.86574 -226.540312)
			(xy 377.881856 -226.588586) (xy 377.89002 -226.63882) (xy 377.890532 -226.664266) (xy 378.20906 -226.664266)
			(xy 378.21302 -226.615212) (xy 378.224797 -226.567428) (xy 378.244088 -226.522152) (xy 378.270391 -226.480556)
			(xy 378.303026 -226.443719) (xy 378.341147 -226.412594) (xy 378.383768 -226.387987) (xy 378.429784 -226.370535)
			(xy 378.478003 -226.360691) (xy 378.527178 -226.35871) (xy 378.576033 -226.364642) (xy 378.623304 -226.378334)
			(xy 378.667766 -226.399432) (xy 378.708269 -226.427388) (xy 378.743762 -226.46148) (xy 378.773327 -226.500824)
			(xy 378.796198 -226.544401) (xy 378.811782 -226.591082) (xy 378.819677 -226.639659) (xy 378.820172 -226.664266)
			(xy 379.138683 -226.664266) (xy 379.142778 -226.613538) (xy 379.154957 -226.564124) (xy 379.174905 -226.517304)
			(xy 379.202106 -226.47429) (xy 379.235854 -226.436196) (xy 379.275276 -226.404009) (xy 379.31935 -226.378563)
			(xy 379.366936 -226.360516) (xy 379.4168 -226.350336) (xy 379.467652 -226.348287) (xy 379.518173 -226.354421)
			(xy 379.567057 -226.368581) (xy 379.613036 -226.390398) (xy 379.65492 -226.419308) (xy 379.691624 -226.454563)
			(xy 379.722197 -226.495249) (xy 379.745848 -226.540312) (xy 379.761964 -226.588586) (xy 379.770128 -226.63882)
			(xy 379.77064 -226.664266) (xy 380.078483 -226.664266) (xy 380.082578 -226.613538) (xy 380.094757 -226.564124)
			(xy 380.114705 -226.517304) (xy 380.141906 -226.47429) (xy 380.175654 -226.436196) (xy 380.215076 -226.404009)
			(xy 380.25915 -226.378563) (xy 380.306736 -226.360516) (xy 380.3566 -226.350336) (xy 380.407452 -226.348287)
			(xy 380.457973 -226.354421) (xy 380.506857 -226.368581) (xy 380.552836 -226.390398) (xy 380.59472 -226.419308)
			(xy 380.631424 -226.454563) (xy 380.661997 -226.495249) (xy 380.685648 -226.540312) (xy 380.701764 -226.588586)
			(xy 380.709928 -226.63882) (xy 380.71044 -226.664266) (xy 381.028968 -226.664266) (xy 381.032928 -226.615212)
			(xy 381.044705 -226.567428) (xy 381.063996 -226.522152) (xy 381.090299 -226.480556) (xy 381.122934 -226.443719)
			(xy 381.161055 -226.412594) (xy 381.203676 -226.387987) (xy 381.249692 -226.370535) (xy 381.297911 -226.360691)
			(xy 381.347086 -226.35871) (xy 381.395941 -226.364642) (xy 381.443212 -226.378334) (xy 381.487674 -226.399432)
			(xy 381.528177 -226.427388) (xy 381.56367 -226.46148) (xy 381.593235 -226.500824) (xy 381.616106 -226.544401)
			(xy 381.63169 -226.591082) (xy 381.639585 -226.639659) (xy 381.64008 -226.664266) (xy 381.969022 -226.664266)
			(xy 381.972982 -226.615212) (xy 381.984759 -226.567428) (xy 382.00405 -226.522152) (xy 382.030353 -226.480556)
			(xy 382.062988 -226.443719) (xy 382.101109 -226.412594) (xy 382.14373 -226.387987) (xy 382.189746 -226.370535)
			(xy 382.237965 -226.360691) (xy 382.28714 -226.35871) (xy 382.335995 -226.364642) (xy 382.383266 -226.378334)
			(xy 382.427728 -226.399432) (xy 382.468231 -226.427388) (xy 382.503724 -226.46148) (xy 382.533289 -226.500824)
			(xy 382.55616 -226.544401) (xy 382.571744 -226.591082) (xy 382.579639 -226.639659) (xy 382.580134 -226.664266)
			(xy 382.909076 -226.664266) (xy 382.913036 -226.615212) (xy 382.924813 -226.567428) (xy 382.944104 -226.522152)
			(xy 382.970407 -226.480556) (xy 383.003042 -226.443719) (xy 383.041163 -226.412594) (xy 383.083784 -226.387987)
			(xy 383.1298 -226.370535) (xy 383.178019 -226.360691) (xy 383.227194 -226.35871) (xy 383.276049 -226.364642)
			(xy 383.32332 -226.378334) (xy 383.367782 -226.399432) (xy 383.408285 -226.427388) (xy 383.443778 -226.46148)
			(xy 383.473343 -226.500824) (xy 383.496214 -226.544401) (xy 383.511798 -226.591082) (xy 383.519693 -226.639659)
			(xy 383.520188 -226.664266) (xy 383.84913 -226.664266) (xy 383.85309 -226.615212) (xy 383.864867 -226.567428)
			(xy 383.884158 -226.522152) (xy 383.910461 -226.480556) (xy 383.943096 -226.443719) (xy 383.981217 -226.412594)
			(xy 384.023838 -226.387987) (xy 384.069854 -226.370535) (xy 384.118073 -226.360691) (xy 384.167248 -226.35871)
			(xy 384.216103 -226.364642) (xy 384.263374 -226.378334) (xy 384.307836 -226.399432) (xy 384.348339 -226.427388)
			(xy 384.383832 -226.46148) (xy 384.413397 -226.500824) (xy 384.436268 -226.544401) (xy 384.451852 -226.591082)
			(xy 384.459747 -226.639659) (xy 384.460242 -226.664266) (xy 384.78893 -226.664266) (xy 384.79289 -226.615212)
			(xy 384.804667 -226.567428) (xy 384.823958 -226.522152) (xy 384.850261 -226.480556) (xy 384.882896 -226.443719)
			(xy 384.921017 -226.412594) (xy 384.963638 -226.387987) (xy 385.009654 -226.370535) (xy 385.057873 -226.360691)
			(xy 385.107048 -226.35871) (xy 385.155903 -226.364642) (xy 385.203174 -226.378334) (xy 385.247636 -226.399432)
			(xy 385.288139 -226.427388) (xy 385.323632 -226.46148) (xy 385.353197 -226.500824) (xy 385.376068 -226.544401)
			(xy 385.391652 -226.591082) (xy 385.399547 -226.639659) (xy 385.400042 -226.664266) (xy 385.728984 -226.664266)
			(xy 385.732944 -226.615212) (xy 385.744721 -226.567428) (xy 385.764012 -226.522152) (xy 385.790315 -226.480556)
			(xy 385.82295 -226.443719) (xy 385.861071 -226.412594) (xy 385.903692 -226.387987) (xy 385.949708 -226.370535)
			(xy 385.997927 -226.360691) (xy 386.047102 -226.35871) (xy 386.095957 -226.364642) (xy 386.143228 -226.378334)
			(xy 386.18769 -226.399432) (xy 386.228193 -226.427388) (xy 386.263686 -226.46148) (xy 386.293251 -226.500824)
			(xy 386.316122 -226.544401) (xy 386.331706 -226.591082) (xy 386.339601 -226.639659) (xy 386.340096 -226.664266)
			(xy 386.669038 -226.664266) (xy 386.672998 -226.615212) (xy 386.684775 -226.567428) (xy 386.704066 -226.522152)
			(xy 386.730369 -226.480556) (xy 386.763004 -226.443719) (xy 386.801125 -226.412594) (xy 386.843746 -226.387987)
			(xy 386.889762 -226.370535) (xy 386.937981 -226.360691) (xy 386.987156 -226.35871) (xy 387.036011 -226.364642)
			(xy 387.083282 -226.378334) (xy 387.127744 -226.399432) (xy 387.168247 -226.427388) (xy 387.20374 -226.46148)
			(xy 387.233305 -226.500824) (xy 387.256176 -226.544401) (xy 387.27176 -226.591082) (xy 387.279655 -226.639659)
			(xy 387.28015 -226.664266) (xy 387.279655 -226.688873) (xy 387.27176 -226.73745) (xy 387.256176 -226.784131)
			(xy 387.233305 -226.827708) (xy 387.20374 -226.867052) (xy 387.168247 -226.901144) (xy 387.127744 -226.9291)
			(xy 387.083282 -226.950198) (xy 387.036011 -226.96389) (xy 386.987156 -226.969822) (xy 386.937981 -226.967841)
			(xy 386.889762 -226.957997) (xy 386.843746 -226.940545) (xy 386.801125 -226.915938) (xy 386.763004 -226.884813)
			(xy 386.730369 -226.847976) (xy 386.704066 -226.80638) (xy 386.684775 -226.761104) (xy 386.672998 -226.71332)
			(xy 386.669038 -226.664266) (xy 386.340096 -226.664266) (xy 386.339601 -226.688873) (xy 386.331706 -226.73745)
			(xy 386.316122 -226.784131) (xy 386.293251 -226.827708) (xy 386.263686 -226.867052) (xy 386.228193 -226.901144)
			(xy 386.18769 -226.9291) (xy 386.143228 -226.950198) (xy 386.095957 -226.96389) (xy 386.047102 -226.969822)
			(xy 385.997927 -226.967841) (xy 385.949708 -226.957997) (xy 385.903692 -226.940545) (xy 385.861071 -226.915938)
			(xy 385.82295 -226.884813) (xy 385.790315 -226.847976) (xy 385.764012 -226.80638) (xy 385.744721 -226.761104)
			(xy 385.732944 -226.71332) (xy 385.728984 -226.664266) (xy 385.400042 -226.664266) (xy 385.399547 -226.688873)
			(xy 385.391652 -226.73745) (xy 385.376068 -226.784131) (xy 385.353197 -226.827708) (xy 385.323632 -226.867052)
			(xy 385.288139 -226.901144) (xy 385.247636 -226.9291) (xy 385.203174 -226.950198) (xy 385.155903 -226.96389)
			(xy 385.107048 -226.969822) (xy 385.057873 -226.967841) (xy 385.009654 -226.957997) (xy 384.963638 -226.940545)
			(xy 384.921017 -226.915938) (xy 384.882896 -226.884813) (xy 384.850261 -226.847976) (xy 384.823958 -226.80638)
			(xy 384.804667 -226.761104) (xy 384.79289 -226.71332) (xy 384.78893 -226.664266) (xy 384.460242 -226.664266)
			(xy 384.459747 -226.688873) (xy 384.451852 -226.73745) (xy 384.436268 -226.784131) (xy 384.413397 -226.827708)
			(xy 384.383832 -226.867052) (xy 384.348339 -226.901144) (xy 384.307836 -226.9291) (xy 384.263374 -226.950198)
			(xy 384.216103 -226.96389) (xy 384.167248 -226.969822) (xy 384.118073 -226.967841) (xy 384.069854 -226.957997)
			(xy 384.023838 -226.940545) (xy 383.981217 -226.915938) (xy 383.943096 -226.884813) (xy 383.910461 -226.847976)
			(xy 383.884158 -226.80638) (xy 383.864867 -226.761104) (xy 383.85309 -226.71332) (xy 383.84913 -226.664266)
			(xy 383.520188 -226.664266) (xy 383.519693 -226.688873) (xy 383.511798 -226.73745) (xy 383.496214 -226.784131)
			(xy 383.473343 -226.827708) (xy 383.443778 -226.867052) (xy 383.408285 -226.901144) (xy 383.367782 -226.9291)
			(xy 383.32332 -226.950198) (xy 383.276049 -226.96389) (xy 383.227194 -226.969822) (xy 383.178019 -226.967841)
			(xy 383.1298 -226.957997) (xy 383.083784 -226.940545) (xy 383.041163 -226.915938) (xy 383.003042 -226.884813)
			(xy 382.970407 -226.847976) (xy 382.944104 -226.80638) (xy 382.924813 -226.761104) (xy 382.913036 -226.71332)
			(xy 382.909076 -226.664266) (xy 382.580134 -226.664266) (xy 382.579639 -226.688873) (xy 382.571744 -226.73745)
			(xy 382.55616 -226.784131) (xy 382.533289 -226.827708) (xy 382.503724 -226.867052) (xy 382.468231 -226.901144)
			(xy 382.427728 -226.9291) (xy 382.383266 -226.950198) (xy 382.335995 -226.96389) (xy 382.28714 -226.969822)
			(xy 382.237965 -226.967841) (xy 382.189746 -226.957997) (xy 382.14373 -226.940545) (xy 382.101109 -226.915938)
			(xy 382.062988 -226.884813) (xy 382.030353 -226.847976) (xy 382.00405 -226.80638) (xy 381.984759 -226.761104)
			(xy 381.972982 -226.71332) (xy 381.969022 -226.664266) (xy 381.64008 -226.664266) (xy 381.639585 -226.688873)
			(xy 381.63169 -226.73745) (xy 381.616106 -226.784131) (xy 381.593235 -226.827708) (xy 381.56367 -226.867052)
			(xy 381.528177 -226.901144) (xy 381.487674 -226.9291) (xy 381.443212 -226.950198) (xy 381.395941 -226.96389)
			(xy 381.347086 -226.969822) (xy 381.297911 -226.967841) (xy 381.249692 -226.957997) (xy 381.203676 -226.940545)
			(xy 381.161055 -226.915938) (xy 381.122934 -226.884813) (xy 381.090299 -226.847976) (xy 381.063996 -226.80638)
			(xy 381.044705 -226.761104) (xy 381.032928 -226.71332) (xy 381.028968 -226.664266) (xy 380.71044 -226.664266)
			(xy 380.709928 -226.689712) (xy 380.701764 -226.739946) (xy 380.685648 -226.78822) (xy 380.661997 -226.833283)
			(xy 380.631424 -226.873969) (xy 380.59472 -226.909224) (xy 380.552836 -226.938134) (xy 380.506857 -226.959951)
			(xy 380.457973 -226.974111) (xy 380.407452 -226.980245) (xy 380.3566 -226.978196) (xy 380.306736 -226.968016)
			(xy 380.25915 -226.949969) (xy 380.215076 -226.924523) (xy 380.175654 -226.892336) (xy 380.141906 -226.854242)
			(xy 380.114705 -226.811228) (xy 380.094757 -226.764408) (xy 380.082578 -226.714994) (xy 380.078483 -226.664266)
			(xy 379.77064 -226.664266) (xy 379.770128 -226.689712) (xy 379.761964 -226.739946) (xy 379.745848 -226.78822)
			(xy 379.722197 -226.833283) (xy 379.691624 -226.873969) (xy 379.65492 -226.909224) (xy 379.613036 -226.938134)
			(xy 379.567057 -226.959951) (xy 379.518173 -226.974111) (xy 379.467652 -226.980245) (xy 379.4168 -226.978196)
			(xy 379.366936 -226.968016) (xy 379.31935 -226.949969) (xy 379.275276 -226.924523) (xy 379.235854 -226.892336)
			(xy 379.202106 -226.854242) (xy 379.174905 -226.811228) (xy 379.154957 -226.764408) (xy 379.142778 -226.714994)
			(xy 379.138683 -226.664266) (xy 378.820172 -226.664266) (xy 378.819677 -226.688873) (xy 378.811782 -226.73745)
			(xy 378.796198 -226.784131) (xy 378.773327 -226.827708) (xy 378.743762 -226.867052) (xy 378.708269 -226.901144)
			(xy 378.667766 -226.9291) (xy 378.623304 -226.950198) (xy 378.576033 -226.96389) (xy 378.527178 -226.969822)
			(xy 378.478003 -226.967841) (xy 378.429784 -226.957997) (xy 378.383768 -226.940545) (xy 378.341147 -226.915938)
			(xy 378.303026 -226.884813) (xy 378.270391 -226.847976) (xy 378.244088 -226.80638) (xy 378.224797 -226.761104)
			(xy 378.21302 -226.71332) (xy 378.20906 -226.664266) (xy 377.890532 -226.664266) (xy 377.89002 -226.689712)
			(xy 377.881856 -226.739946) (xy 377.86574 -226.78822) (xy 377.842089 -226.833283) (xy 377.811516 -226.873969)
			(xy 377.774812 -226.909224) (xy 377.732928 -226.938134) (xy 377.686949 -226.959951) (xy 377.638065 -226.974111)
			(xy 377.587544 -226.980245) (xy 377.536692 -226.978196) (xy 377.486828 -226.968016) (xy 377.439242 -226.949969)
			(xy 377.395168 -226.924523) (xy 377.355746 -226.892336) (xy 377.321998 -226.854242) (xy 377.294797 -226.811228)
			(xy 377.274849 -226.764408) (xy 377.26267 -226.714994) (xy 377.258575 -226.664266) (xy 376.940064 -226.664266)
			(xy 376.939569 -226.688873) (xy 376.931674 -226.73745) (xy 376.91609 -226.784131) (xy 376.893219 -226.827708)
			(xy 376.863654 -226.867052) (xy 376.828161 -226.901144) (xy 376.787658 -226.9291) (xy 376.743196 -226.950198)
			(xy 376.695925 -226.96389) (xy 376.64707 -226.969822) (xy 376.597895 -226.967841) (xy 376.549676 -226.957997)
			(xy 376.50366 -226.940545) (xy 376.461039 -226.915938) (xy 376.422918 -226.884813) (xy 376.390283 -226.847976)
			(xy 376.36398 -226.80638) (xy 376.344689 -226.761104) (xy 376.332912 -226.71332) (xy 376.328952 -226.664266)
			(xy 376.010424 -226.664266) (xy 376.009912 -226.689712) (xy 376.001748 -226.739946) (xy 375.985632 -226.78822)
			(xy 375.961981 -226.833283) (xy 375.931408 -226.873969) (xy 375.894704 -226.909224) (xy 375.85282 -226.938134)
			(xy 375.806841 -226.959951) (xy 375.757957 -226.974111) (xy 375.707436 -226.980245) (xy 375.656584 -226.978196)
			(xy 375.60672 -226.968016) (xy 375.559134 -226.949969) (xy 375.51506 -226.924523) (xy 375.475638 -226.892336)
			(xy 375.44189 -226.854242) (xy 375.414689 -226.811228) (xy 375.394741 -226.764408) (xy 375.382562 -226.714994)
			(xy 375.378467 -226.664266) (xy 375.06021 -226.664266) (xy 375.059715 -226.688873) (xy 375.05182 -226.73745)
			(xy 375.036236 -226.784131) (xy 375.013365 -226.827708) (xy 374.9838 -226.867052) (xy 374.948307 -226.901144)
			(xy 374.907804 -226.9291) (xy 374.863342 -226.950198) (xy 374.816071 -226.96389) (xy 374.767216 -226.969822)
			(xy 374.718041 -226.967841) (xy 374.669822 -226.957997) (xy 374.623806 -226.940545) (xy 374.581185 -226.915938)
			(xy 374.543064 -226.884813) (xy 374.510429 -226.847976) (xy 374.484126 -226.80638) (xy 374.464835 -226.761104)
			(xy 374.453058 -226.71332) (xy 374.449098 -226.664266) (xy 374.130316 -226.664266) (xy 374.12987 -226.688855)
			(xy 374.122282 -226.737443) (xy 374.107238 -226.784262) (xy 374.085104 -226.828176) (xy 374.071134 -226.848416)
			(xy 374.060212 -226.863656) (xy 374.06326 -226.90074) (xy 374.251728 -227.089208) (xy 374.255163 -227.092824)
			(xy 374.260669 -227.10114) (xy 374.26265 -227.105718) (xy 374.266714 -227.11537) (xy 374.268478 -227.119454)
			(xy 374.273206 -227.126988) (xy 374.276112 -227.130356) (xy 374.294146 -227.149914) (xy 374.297099 -227.153012)
			(xy 374.303863 -227.158255) (xy 374.307608 -227.160328) (xy 374.329706 -227.172012) (xy 374.33758 -227.173536)
			(xy 374.362218 -227.178384) (xy 374.409581 -227.195051) (xy 374.453579 -227.219241) (xy 374.493028 -227.250303)
			(xy 374.526864 -227.287399) (xy 374.554176 -227.329531) (xy 374.574228 -227.375563) (xy 374.586479 -227.424255)
			(xy 374.590599 -227.474272) (xy 374.918998 -227.474272) (xy 374.922958 -227.425218) (xy 374.934735 -227.377434)
			(xy 374.954026 -227.332158) (xy 374.980329 -227.290562) (xy 375.012964 -227.253725) (xy 375.051085 -227.2226)
			(xy 375.093706 -227.197993) (xy 375.139722 -227.180541) (xy 375.187941 -227.170697) (xy 375.237116 -227.168716)
			(xy 375.285971 -227.174648) (xy 375.333242 -227.18834) (xy 375.377704 -227.209438) (xy 375.418207 -227.237394)
			(xy 375.4537 -227.271486) (xy 375.483265 -227.31083) (xy 375.506136 -227.354407) (xy 375.52172 -227.401088)
			(xy 375.529615 -227.449665) (xy 375.53011 -227.474272) (xy 375.848621 -227.474272) (xy 375.852716 -227.423544)
			(xy 375.864895 -227.37413) (xy 375.884843 -227.32731) (xy 375.912044 -227.284296) (xy 375.945792 -227.246202)
			(xy 375.985214 -227.214015) (xy 376.029288 -227.188569) (xy 376.076874 -227.170522) (xy 376.126738 -227.160342)
			(xy 376.17759 -227.158293) (xy 376.228111 -227.164427) (xy 376.276995 -227.178587) (xy 376.322974 -227.200404)
			(xy 376.364858 -227.229314) (xy 376.401562 -227.264569) (xy 376.432135 -227.305255) (xy 376.455786 -227.350318)
			(xy 376.471902 -227.398592) (xy 376.480066 -227.448826) (xy 376.480578 -227.474272) (xy 376.788675 -227.474272)
			(xy 376.79277 -227.423544) (xy 376.804949 -227.37413) (xy 376.824897 -227.32731) (xy 376.852098 -227.284296)
			(xy 376.885846 -227.246202) (xy 376.925268 -227.214015) (xy 376.969342 -227.188569) (xy 377.016928 -227.170522)
			(xy 377.066792 -227.160342) (xy 377.117644 -227.158293) (xy 377.168165 -227.164427) (xy 377.217049 -227.178587)
			(xy 377.263028 -227.200404) (xy 377.304912 -227.229314) (xy 377.341616 -227.264569) (xy 377.372189 -227.305255)
			(xy 377.39584 -227.350318) (xy 377.411956 -227.398592) (xy 377.42012 -227.448826) (xy 377.420632 -227.474272)
			(xy 378.668529 -227.474272) (xy 378.672624 -227.423544) (xy 378.684803 -227.37413) (xy 378.704751 -227.32731)
			(xy 378.731952 -227.284296) (xy 378.7657 -227.246202) (xy 378.805122 -227.214015) (xy 378.849196 -227.188569)
			(xy 378.896782 -227.170522) (xy 378.946646 -227.160342) (xy 378.997498 -227.158293) (xy 379.048019 -227.164427)
			(xy 379.096903 -227.178587) (xy 379.142882 -227.200404) (xy 379.184766 -227.229314) (xy 379.22147 -227.264569)
			(xy 379.252043 -227.305255) (xy 379.275694 -227.350318) (xy 379.29181 -227.398592) (xy 379.299974 -227.448826)
			(xy 379.300486 -227.474272) (xy 379.619014 -227.474272) (xy 379.622974 -227.425218) (xy 379.634751 -227.377434)
			(xy 379.654042 -227.332158) (xy 379.680345 -227.290562) (xy 379.71298 -227.253725) (xy 379.751101 -227.2226)
			(xy 379.793722 -227.197993) (xy 379.839738 -227.180541) (xy 379.887957 -227.170697) (xy 379.937132 -227.168716)
			(xy 379.985987 -227.174648) (xy 380.033258 -227.18834) (xy 380.07772 -227.209438) (xy 380.118223 -227.237394)
			(xy 380.153716 -227.271486) (xy 380.183281 -227.31083) (xy 380.206152 -227.354407) (xy 380.221736 -227.401088)
			(xy 380.229631 -227.449665) (xy 380.230126 -227.474272) (xy 380.548637 -227.474272) (xy 380.552732 -227.423544)
			(xy 380.564911 -227.37413) (xy 380.584859 -227.32731) (xy 380.61206 -227.284296) (xy 380.645808 -227.246202)
			(xy 380.68523 -227.214015) (xy 380.729304 -227.188569) (xy 380.77689 -227.170522) (xy 380.826754 -227.160342)
			(xy 380.877606 -227.158293) (xy 380.928127 -227.164427) (xy 380.977011 -227.178587) (xy 381.02299 -227.200404)
			(xy 381.064874 -227.229314) (xy 381.101578 -227.264569) (xy 381.132151 -227.305255) (xy 381.155802 -227.350318)
			(xy 381.171918 -227.398592) (xy 381.180082 -227.448826) (xy 381.180594 -227.474272) (xy 381.499122 -227.474272)
			(xy 381.503082 -227.425218) (xy 381.514859 -227.377434) (xy 381.53415 -227.332158) (xy 381.560453 -227.290562)
			(xy 381.593088 -227.253725) (xy 381.631209 -227.2226) (xy 381.67383 -227.197993) (xy 381.719846 -227.180541)
			(xy 381.768065 -227.170697) (xy 381.81724 -227.168716) (xy 381.866095 -227.174648) (xy 381.913366 -227.18834)
			(xy 381.957828 -227.209438) (xy 381.998331 -227.237394) (xy 382.033824 -227.271486) (xy 382.063389 -227.31083)
			(xy 382.08626 -227.354407) (xy 382.101844 -227.401088) (xy 382.109739 -227.449665) (xy 382.110234 -227.474272)
			(xy 382.438922 -227.474272) (xy 382.442882 -227.425218) (xy 382.454659 -227.377434) (xy 382.47395 -227.332158)
			(xy 382.500253 -227.290562) (xy 382.532888 -227.253725) (xy 382.571009 -227.2226) (xy 382.61363 -227.197993)
			(xy 382.659646 -227.180541) (xy 382.707865 -227.170697) (xy 382.75704 -227.168716) (xy 382.805895 -227.174648)
			(xy 382.853166 -227.18834) (xy 382.897628 -227.209438) (xy 382.938131 -227.237394) (xy 382.973624 -227.271486)
			(xy 383.003189 -227.31083) (xy 383.02606 -227.354407) (xy 383.041644 -227.401088) (xy 383.049539 -227.449665)
			(xy 383.050034 -227.474272) (xy 383.378976 -227.474272) (xy 383.382936 -227.425218) (xy 383.394713 -227.377434)
			(xy 383.414004 -227.332158) (xy 383.440307 -227.290562) (xy 383.472942 -227.253725) (xy 383.511063 -227.2226)
			(xy 383.553684 -227.197993) (xy 383.5997 -227.180541) (xy 383.647919 -227.170697) (xy 383.697094 -227.168716)
			(xy 383.745949 -227.174648) (xy 383.79322 -227.18834) (xy 383.837682 -227.209438) (xy 383.878185 -227.237394)
			(xy 383.913678 -227.271486) (xy 383.943243 -227.31083) (xy 383.966114 -227.354407) (xy 383.981698 -227.401088)
			(xy 383.989593 -227.449665) (xy 383.990088 -227.474272) (xy 385.259084 -227.474272) (xy 385.263044 -227.425218)
			(xy 385.274821 -227.377434) (xy 385.294112 -227.332158) (xy 385.320415 -227.290562) (xy 385.35305 -227.253725)
			(xy 385.391171 -227.2226) (xy 385.433792 -227.197993) (xy 385.479808 -227.180541) (xy 385.528027 -227.170697)
			(xy 385.577202 -227.168716) (xy 385.626057 -227.174648) (xy 385.673328 -227.18834) (xy 385.71779 -227.209438)
			(xy 385.758293 -227.237394) (xy 385.793786 -227.271486) (xy 385.823351 -227.31083) (xy 385.846222 -227.354407)
			(xy 385.861806 -227.401088) (xy 385.869701 -227.449665) (xy 385.870196 -227.474272) (xy 386.199138 -227.474272)
			(xy 386.203098 -227.425218) (xy 386.214875 -227.377434) (xy 386.234166 -227.332158) (xy 386.260469 -227.290562)
			(xy 386.293104 -227.253725) (xy 386.331225 -227.2226) (xy 386.373846 -227.197993) (xy 386.419862 -227.180541)
			(xy 386.468081 -227.170697) (xy 386.517256 -227.168716) (xy 386.566111 -227.174648) (xy 386.613382 -227.18834)
			(xy 386.657844 -227.209438) (xy 386.698347 -227.237394) (xy 386.73384 -227.271486) (xy 386.763405 -227.31083)
			(xy 386.786276 -227.354407) (xy 386.80186 -227.401088) (xy 386.809755 -227.449665) (xy 386.81025 -227.474272)
			(xy 386.809755 -227.498879) (xy 386.80186 -227.547456) (xy 386.786276 -227.594137) (xy 386.763405 -227.637714)
			(xy 386.73384 -227.677058) (xy 386.698347 -227.71115) (xy 386.657844 -227.739106) (xy 386.613382 -227.760204)
			(xy 386.566111 -227.773896) (xy 386.517256 -227.779828) (xy 386.468081 -227.777847) (xy 386.419862 -227.768003)
			(xy 386.373846 -227.750551) (xy 386.331225 -227.725944) (xy 386.293104 -227.694819) (xy 386.260469 -227.657982)
			(xy 386.234166 -227.616386) (xy 386.214875 -227.57111) (xy 386.203098 -227.523326) (xy 386.199138 -227.474272)
			(xy 385.870196 -227.474272) (xy 385.869701 -227.498879) (xy 385.861806 -227.547456) (xy 385.846222 -227.594137)
			(xy 385.823351 -227.637714) (xy 385.793786 -227.677058) (xy 385.758293 -227.71115) (xy 385.71779 -227.739106)
			(xy 385.673328 -227.760204) (xy 385.626057 -227.773896) (xy 385.577202 -227.779828) (xy 385.528027 -227.777847)
			(xy 385.479808 -227.768003) (xy 385.433792 -227.750551) (xy 385.391171 -227.725944) (xy 385.35305 -227.694819)
			(xy 385.320415 -227.657982) (xy 385.294112 -227.616386) (xy 385.274821 -227.57111) (xy 385.263044 -227.523326)
			(xy 385.259084 -227.474272) (xy 383.990088 -227.474272) (xy 383.989593 -227.498879) (xy 383.981698 -227.547456)
			(xy 383.966114 -227.594137) (xy 383.943243 -227.637714) (xy 383.913678 -227.677058) (xy 383.878185 -227.71115)
			(xy 383.837682 -227.739106) (xy 383.79322 -227.760204) (xy 383.745949 -227.773896) (xy 383.697094 -227.779828)
			(xy 383.647919 -227.777847) (xy 383.5997 -227.768003) (xy 383.553684 -227.750551) (xy 383.511063 -227.725944)
			(xy 383.472942 -227.694819) (xy 383.440307 -227.657982) (xy 383.414004 -227.616386) (xy 383.394713 -227.57111)
			(xy 383.382936 -227.523326) (xy 383.378976 -227.474272) (xy 383.050034 -227.474272) (xy 383.049539 -227.498879)
			(xy 383.041644 -227.547456) (xy 383.02606 -227.594137) (xy 383.003189 -227.637714) (xy 382.973624 -227.677058)
			(xy 382.938131 -227.71115) (xy 382.897628 -227.739106) (xy 382.853166 -227.760204) (xy 382.805895 -227.773896)
			(xy 382.75704 -227.779828) (xy 382.707865 -227.777847) (xy 382.659646 -227.768003) (xy 382.61363 -227.750551)
			(xy 382.571009 -227.725944) (xy 382.532888 -227.694819) (xy 382.500253 -227.657982) (xy 382.47395 -227.616386)
			(xy 382.454659 -227.57111) (xy 382.442882 -227.523326) (xy 382.438922 -227.474272) (xy 382.110234 -227.474272)
			(xy 382.109739 -227.498879) (xy 382.101844 -227.547456) (xy 382.08626 -227.594137) (xy 382.063389 -227.637714)
			(xy 382.033824 -227.677058) (xy 381.998331 -227.71115) (xy 381.957828 -227.739106) (xy 381.913366 -227.760204)
			(xy 381.866095 -227.773896) (xy 381.81724 -227.779828) (xy 381.768065 -227.777847) (xy 381.719846 -227.768003)
			(xy 381.67383 -227.750551) (xy 381.631209 -227.725944) (xy 381.593088 -227.694819) (xy 381.560453 -227.657982)
			(xy 381.53415 -227.616386) (xy 381.514859 -227.57111) (xy 381.503082 -227.523326) (xy 381.499122 -227.474272)
			(xy 381.180594 -227.474272) (xy 381.180082 -227.499718) (xy 381.171918 -227.549952) (xy 381.155802 -227.598226)
			(xy 381.132151 -227.643289) (xy 381.101578 -227.683975) (xy 381.064874 -227.71923) (xy 381.02299 -227.74814)
			(xy 380.977011 -227.769957) (xy 380.928127 -227.784117) (xy 380.877606 -227.790251) (xy 380.826754 -227.788202)
			(xy 380.77689 -227.778022) (xy 380.729304 -227.759975) (xy 380.68523 -227.734529) (xy 380.645808 -227.702342)
			(xy 380.61206 -227.664248) (xy 380.584859 -227.621234) (xy 380.564911 -227.574414) (xy 380.552732 -227.525)
			(xy 380.548637 -227.474272) (xy 380.230126 -227.474272) (xy 380.229631 -227.498879) (xy 380.221736 -227.547456)
			(xy 380.206152 -227.594137) (xy 380.183281 -227.637714) (xy 380.153716 -227.677058) (xy 380.118223 -227.71115)
			(xy 380.07772 -227.739106) (xy 380.033258 -227.760204) (xy 379.985987 -227.773896) (xy 379.937132 -227.779828)
			(xy 379.887957 -227.777847) (xy 379.839738 -227.768003) (xy 379.793722 -227.750551) (xy 379.751101 -227.725944)
			(xy 379.71298 -227.694819) (xy 379.680345 -227.657982) (xy 379.654042 -227.616386) (xy 379.634751 -227.57111)
			(xy 379.622974 -227.523326) (xy 379.619014 -227.474272) (xy 379.300486 -227.474272) (xy 379.299974 -227.499718)
			(xy 379.29181 -227.549952) (xy 379.275694 -227.598226) (xy 379.252043 -227.643289) (xy 379.22147 -227.683975)
			(xy 379.184766 -227.71923) (xy 379.142882 -227.74814) (xy 379.096903 -227.769957) (xy 379.048019 -227.784117)
			(xy 378.997498 -227.790251) (xy 378.946646 -227.788202) (xy 378.896782 -227.778022) (xy 378.849196 -227.759975)
			(xy 378.805122 -227.734529) (xy 378.7657 -227.702342) (xy 378.731952 -227.664248) (xy 378.704751 -227.621234)
			(xy 378.684803 -227.574414) (xy 378.672624 -227.525) (xy 378.668529 -227.474272) (xy 377.420632 -227.474272)
			(xy 377.42012 -227.499718) (xy 377.411956 -227.549952) (xy 377.39584 -227.598226) (xy 377.372189 -227.643289)
			(xy 377.341616 -227.683975) (xy 377.304912 -227.71923) (xy 377.263028 -227.74814) (xy 377.217049 -227.769957)
			(xy 377.168165 -227.784117) (xy 377.117644 -227.790251) (xy 377.066792 -227.788202) (xy 377.016928 -227.778022)
			(xy 376.969342 -227.759975) (xy 376.925268 -227.734529) (xy 376.885846 -227.702342) (xy 376.852098 -227.664248)
			(xy 376.824897 -227.621234) (xy 376.804949 -227.574414) (xy 376.79277 -227.525) (xy 376.788675 -227.474272)
			(xy 376.480578 -227.474272) (xy 376.480066 -227.499718) (xy 376.471902 -227.549952) (xy 376.455786 -227.598226)
			(xy 376.432135 -227.643289) (xy 376.401562 -227.683975) (xy 376.364858 -227.71923) (xy 376.322974 -227.74814)
			(xy 376.276995 -227.769957) (xy 376.228111 -227.784117) (xy 376.17759 -227.790251) (xy 376.126738 -227.788202)
			(xy 376.076874 -227.778022) (xy 376.029288 -227.759975) (xy 375.985214 -227.734529) (xy 375.945792 -227.702342)
			(xy 375.912044 -227.664248) (xy 375.884843 -227.621234) (xy 375.864895 -227.574414) (xy 375.852716 -227.525)
			(xy 375.848621 -227.474272) (xy 375.53011 -227.474272) (xy 375.529615 -227.498879) (xy 375.52172 -227.547456)
			(xy 375.506136 -227.594137) (xy 375.483265 -227.637714) (xy 375.4537 -227.677058) (xy 375.418207 -227.71115)
			(xy 375.377704 -227.739106) (xy 375.333242 -227.760204) (xy 375.285971 -227.773896) (xy 375.237116 -227.779828)
			(xy 375.187941 -227.777847) (xy 375.139722 -227.768003) (xy 375.093706 -227.750551) (xy 375.051085 -227.725944)
			(xy 375.012964 -227.694819) (xy 374.980329 -227.657982) (xy 374.954026 -227.616386) (xy 374.934735 -227.57111)
			(xy 374.922958 -227.523326) (xy 374.918998 -227.474272) (xy 374.590599 -227.474272) (xy 374.590601 -227.474295)
			(xy 374.586481 -227.524336) (xy 374.574231 -227.573028) (xy 374.55418 -227.619061) (xy 374.52687 -227.661193)
			(xy 374.493035 -227.698291) (xy 374.453587 -227.729354) (xy 374.409589 -227.753545) (xy 374.362227 -227.770214)
			(xy 374.33758 -227.775008) (xy 374.329706 -227.776532) (xy 374.307608 -227.788216) (xy 374.303878 -227.790311)
			(xy 374.297111 -227.795545) (xy 374.294146 -227.79863) (xy 374.279922 -227.814124) (xy 374.273734 -227.821381)
			(xy 374.266811 -227.839137) (xy 374.26646 -227.848668) (xy 374.26646 -228.284278) (xy 374.449098 -228.284278)
			(xy 374.453058 -228.235224) (xy 374.464835 -228.18744) (xy 374.484126 -228.142164) (xy 374.510429 -228.100568)
			(xy 374.543064 -228.063731) (xy 374.581185 -228.032606) (xy 374.623806 -228.007999) (xy 374.669822 -227.990547)
			(xy 374.718041 -227.980703) (xy 374.767216 -227.978722) (xy 374.816071 -227.984654) (xy 374.863342 -227.998346)
			(xy 374.907804 -228.019444) (xy 374.948307 -228.0474) (xy 374.9838 -228.081492) (xy 375.013365 -228.120836)
			(xy 375.036236 -228.164413) (xy 375.05182 -228.211094) (xy 375.059715 -228.259671) (xy 375.06021 -228.284278)
			(xy 375.378467 -228.284278) (xy 375.382562 -228.23355) (xy 375.394741 -228.184136) (xy 375.414689 -228.137316)
			(xy 375.44189 -228.094302) (xy 375.475638 -228.056208) (xy 375.51506 -228.024021) (xy 375.559134 -227.998575)
			(xy 375.60672 -227.980528) (xy 375.656584 -227.970348) (xy 375.707436 -227.968299) (xy 375.757957 -227.974433)
			(xy 375.806841 -227.988593) (xy 375.85282 -228.01041) (xy 375.894704 -228.03932) (xy 375.931408 -228.074575)
			(xy 375.961981 -228.115261) (xy 375.985632 -228.160324) (xy 376.001748 -228.208598) (xy 376.009912 -228.258832)
			(xy 376.010424 -228.284278) (xy 376.328952 -228.284278) (xy 376.332912 -228.235224) (xy 376.344689 -228.18744)
			(xy 376.36398 -228.142164) (xy 376.390283 -228.100568) (xy 376.422918 -228.063731) (xy 376.461039 -228.032606)
			(xy 376.50366 -228.007999) (xy 376.549676 -227.990547) (xy 376.597895 -227.980703) (xy 376.64707 -227.978722)
			(xy 376.695925 -227.984654) (xy 376.743196 -227.998346) (xy 376.787658 -228.019444) (xy 376.828161 -228.0474)
			(xy 376.863654 -228.081492) (xy 376.893219 -228.120836) (xy 376.91609 -228.164413) (xy 376.931674 -228.211094)
			(xy 376.939569 -228.259671) (xy 376.940064 -228.284278) (xy 377.258575 -228.284278) (xy 377.26267 -228.23355)
			(xy 377.274849 -228.184136) (xy 377.294797 -228.137316) (xy 377.321998 -228.094302) (xy 377.355746 -228.056208)
			(xy 377.395168 -228.024021) (xy 377.439242 -227.998575) (xy 377.486828 -227.980528) (xy 377.536692 -227.970348)
			(xy 377.587544 -227.968299) (xy 377.638065 -227.974433) (xy 377.686949 -227.988593) (xy 377.732928 -228.01041)
			(xy 377.774812 -228.03932) (xy 377.811516 -228.074575) (xy 377.842089 -228.115261) (xy 377.86574 -228.160324)
			(xy 377.881856 -228.208598) (xy 377.89002 -228.258832) (xy 377.890532 -228.284278) (xy 378.20906 -228.284278)
			(xy 378.21302 -228.235224) (xy 378.224797 -228.18744) (xy 378.244088 -228.142164) (xy 378.270391 -228.100568)
			(xy 378.303026 -228.063731) (xy 378.341147 -228.032606) (xy 378.383768 -228.007999) (xy 378.429784 -227.990547)
			(xy 378.478003 -227.980703) (xy 378.527178 -227.978722) (xy 378.576033 -227.984654) (xy 378.623304 -227.998346)
			(xy 378.667766 -228.019444) (xy 378.708269 -228.0474) (xy 378.743762 -228.081492) (xy 378.773327 -228.120836)
			(xy 378.796198 -228.164413) (xy 378.811782 -228.211094) (xy 378.819677 -228.259671) (xy 378.820172 -228.284278)
			(xy 379.138683 -228.284278) (xy 379.142778 -228.23355) (xy 379.154957 -228.184136) (xy 379.174905 -228.137316)
			(xy 379.202106 -228.094302) (xy 379.235854 -228.056208) (xy 379.275276 -228.024021) (xy 379.31935 -227.998575)
			(xy 379.366936 -227.980528) (xy 379.4168 -227.970348) (xy 379.467652 -227.968299) (xy 379.518173 -227.974433)
			(xy 379.567057 -227.988593) (xy 379.613036 -228.01041) (xy 379.65492 -228.03932) (xy 379.691624 -228.074575)
			(xy 379.722197 -228.115261) (xy 379.745848 -228.160324) (xy 379.761964 -228.208598) (xy 379.770128 -228.258832)
			(xy 379.77064 -228.284278) (xy 380.078483 -228.284278) (xy 380.082578 -228.23355) (xy 380.094757 -228.184136)
			(xy 380.114705 -228.137316) (xy 380.141906 -228.094302) (xy 380.175654 -228.056208) (xy 380.215076 -228.024021)
			(xy 380.25915 -227.998575) (xy 380.306736 -227.980528) (xy 380.3566 -227.970348) (xy 380.407452 -227.968299)
			(xy 380.457973 -227.974433) (xy 380.506857 -227.988593) (xy 380.552836 -228.01041) (xy 380.59472 -228.03932)
			(xy 380.631424 -228.074575) (xy 380.661997 -228.115261) (xy 380.685648 -228.160324) (xy 380.701764 -228.208598)
			(xy 380.709928 -228.258832) (xy 380.71044 -228.284278) (xy 381.028968 -228.284278) (xy 381.032928 -228.235224)
			(xy 381.044705 -228.18744) (xy 381.063996 -228.142164) (xy 381.090299 -228.100568) (xy 381.122934 -228.063731)
			(xy 381.161055 -228.032606) (xy 381.203676 -228.007999) (xy 381.249692 -227.990547) (xy 381.297911 -227.980703)
			(xy 381.347086 -227.978722) (xy 381.395941 -227.984654) (xy 381.443212 -227.998346) (xy 381.487674 -228.019444)
			(xy 381.528177 -228.0474) (xy 381.56367 -228.081492) (xy 381.593235 -228.120836) (xy 381.616106 -228.164413)
			(xy 381.63169 -228.211094) (xy 381.639585 -228.259671) (xy 381.64008 -228.284278) (xy 381.969022 -228.284278)
			(xy 381.972982 -228.235224) (xy 381.984759 -228.18744) (xy 382.00405 -228.142164) (xy 382.030353 -228.100568)
			(xy 382.062988 -228.063731) (xy 382.101109 -228.032606) (xy 382.14373 -228.007999) (xy 382.189746 -227.990547)
			(xy 382.237965 -227.980703) (xy 382.28714 -227.978722) (xy 382.335995 -227.984654) (xy 382.383266 -227.998346)
			(xy 382.427728 -228.019444) (xy 382.468231 -228.0474) (xy 382.503724 -228.081492) (xy 382.533289 -228.120836)
			(xy 382.55616 -228.164413) (xy 382.571744 -228.211094) (xy 382.579639 -228.259671) (xy 382.580134 -228.284278)
			(xy 382.909076 -228.284278) (xy 382.913036 -228.235224) (xy 382.924813 -228.18744) (xy 382.944104 -228.142164)
			(xy 382.970407 -228.100568) (xy 383.003042 -228.063731) (xy 383.041163 -228.032606) (xy 383.083784 -228.007999)
			(xy 383.1298 -227.990547) (xy 383.178019 -227.980703) (xy 383.227194 -227.978722) (xy 383.276049 -227.984654)
			(xy 383.32332 -227.998346) (xy 383.367782 -228.019444) (xy 383.408285 -228.0474) (xy 383.443778 -228.081492)
			(xy 383.473343 -228.120836) (xy 383.496214 -228.164413) (xy 383.511798 -228.211094) (xy 383.519693 -228.259671)
			(xy 383.520188 -228.284278) (xy 383.84913 -228.284278) (xy 383.85309 -228.235224) (xy 383.864867 -228.18744)
			(xy 383.884158 -228.142164) (xy 383.910461 -228.100568) (xy 383.943096 -228.063731) (xy 383.981217 -228.032606)
			(xy 384.023838 -228.007999) (xy 384.069854 -227.990547) (xy 384.118073 -227.980703) (xy 384.167248 -227.978722)
			(xy 384.216103 -227.984654) (xy 384.263374 -227.998346) (xy 384.307836 -228.019444) (xy 384.348339 -228.0474)
			(xy 384.383832 -228.081492) (xy 384.413397 -228.120836) (xy 384.436268 -228.164413) (xy 384.451852 -228.211094)
			(xy 384.459747 -228.259671) (xy 384.460242 -228.284278) (xy 384.78893 -228.284278) (xy 384.79289 -228.235224)
			(xy 384.804667 -228.18744) (xy 384.823958 -228.142164) (xy 384.850261 -228.100568) (xy 384.882896 -228.063731)
			(xy 384.921017 -228.032606) (xy 384.963638 -228.007999) (xy 385.009654 -227.990547) (xy 385.057873 -227.980703)
			(xy 385.107048 -227.978722) (xy 385.155903 -227.984654) (xy 385.203174 -227.998346) (xy 385.247636 -228.019444)
			(xy 385.288139 -228.0474) (xy 385.323632 -228.081492) (xy 385.353197 -228.120836) (xy 385.376068 -228.164413)
			(xy 385.391652 -228.211094) (xy 385.399547 -228.259671) (xy 385.400042 -228.284278) (xy 385.728984 -228.284278)
			(xy 385.732944 -228.235224) (xy 385.744721 -228.18744) (xy 385.764012 -228.142164) (xy 385.790315 -228.100568)
			(xy 385.82295 -228.063731) (xy 385.861071 -228.032606) (xy 385.903692 -228.007999) (xy 385.949708 -227.990547)
			(xy 385.997927 -227.980703) (xy 386.047102 -227.978722) (xy 386.095957 -227.984654) (xy 386.143228 -227.998346)
			(xy 386.18769 -228.019444) (xy 386.228193 -228.0474) (xy 386.263686 -228.081492) (xy 386.293251 -228.120836)
			(xy 386.316122 -228.164413) (xy 386.331706 -228.211094) (xy 386.339601 -228.259671) (xy 386.340096 -228.284278)
			(xy 386.669038 -228.284278) (xy 386.672998 -228.235224) (xy 386.684775 -228.18744) (xy 386.704066 -228.142164)
			(xy 386.730369 -228.100568) (xy 386.763004 -228.063731) (xy 386.801125 -228.032606) (xy 386.843746 -228.007999)
			(xy 386.889762 -227.990547) (xy 386.937981 -227.980703) (xy 386.987156 -227.978722) (xy 387.036011 -227.984654)
			(xy 387.083282 -227.998346) (xy 387.127744 -228.019444) (xy 387.168247 -228.0474) (xy 387.20374 -228.081492)
			(xy 387.233305 -228.120836) (xy 387.256176 -228.164413) (xy 387.27176 -228.211094) (xy 387.279655 -228.259671)
			(xy 387.28015 -228.284278) (xy 387.279655 -228.308885) (xy 387.27176 -228.357462) (xy 387.256176 -228.404143)
			(xy 387.233305 -228.44772) (xy 387.20374 -228.487064) (xy 387.168247 -228.521156) (xy 387.127744 -228.549112)
			(xy 387.083282 -228.57021) (xy 387.036011 -228.583902) (xy 386.987156 -228.589834) (xy 386.937981 -228.587853)
			(xy 386.889762 -228.578009) (xy 386.843746 -228.560557) (xy 386.801125 -228.53595) (xy 386.763004 -228.504825)
			(xy 386.730369 -228.467988) (xy 386.704066 -228.426392) (xy 386.684775 -228.381116) (xy 386.672998 -228.333332)
			(xy 386.669038 -228.284278) (xy 386.340096 -228.284278) (xy 386.339601 -228.308885) (xy 386.331706 -228.357462)
			(xy 386.316122 -228.404143) (xy 386.293251 -228.44772) (xy 386.263686 -228.487064) (xy 386.228193 -228.521156)
			(xy 386.18769 -228.549112) (xy 386.143228 -228.57021) (xy 386.095957 -228.583902) (xy 386.047102 -228.589834)
			(xy 385.997927 -228.587853) (xy 385.949708 -228.578009) (xy 385.903692 -228.560557) (xy 385.861071 -228.53595)
			(xy 385.82295 -228.504825) (xy 385.790315 -228.467988) (xy 385.764012 -228.426392) (xy 385.744721 -228.381116)
			(xy 385.732944 -228.333332) (xy 385.728984 -228.284278) (xy 385.400042 -228.284278) (xy 385.399547 -228.308885)
			(xy 385.391652 -228.357462) (xy 385.376068 -228.404143) (xy 385.353197 -228.44772) (xy 385.323632 -228.487064)
			(xy 385.288139 -228.521156) (xy 385.247636 -228.549112) (xy 385.203174 -228.57021) (xy 385.155903 -228.583902)
			(xy 385.107048 -228.589834) (xy 385.057873 -228.587853) (xy 385.009654 -228.578009) (xy 384.963638 -228.560557)
			(xy 384.921017 -228.53595) (xy 384.882896 -228.504825) (xy 384.850261 -228.467988) (xy 384.823958 -228.426392)
			(xy 384.804667 -228.381116) (xy 384.79289 -228.333332) (xy 384.78893 -228.284278) (xy 384.460242 -228.284278)
			(xy 384.459747 -228.308885) (xy 384.451852 -228.357462) (xy 384.436268 -228.404143) (xy 384.413397 -228.44772)
			(xy 384.383832 -228.487064) (xy 384.348339 -228.521156) (xy 384.307836 -228.549112) (xy 384.263374 -228.57021)
			(xy 384.216103 -228.583902) (xy 384.167248 -228.589834) (xy 384.118073 -228.587853) (xy 384.069854 -228.578009)
			(xy 384.023838 -228.560557) (xy 383.981217 -228.53595) (xy 383.943096 -228.504825) (xy 383.910461 -228.467988)
			(xy 383.884158 -228.426392) (xy 383.864867 -228.381116) (xy 383.85309 -228.333332) (xy 383.84913 -228.284278)
			(xy 383.520188 -228.284278) (xy 383.519693 -228.308885) (xy 383.511798 -228.357462) (xy 383.496214 -228.404143)
			(xy 383.473343 -228.44772) (xy 383.443778 -228.487064) (xy 383.408285 -228.521156) (xy 383.367782 -228.549112)
			(xy 383.32332 -228.57021) (xy 383.276049 -228.583902) (xy 383.227194 -228.589834) (xy 383.178019 -228.587853)
			(xy 383.1298 -228.578009) (xy 383.083784 -228.560557) (xy 383.041163 -228.53595) (xy 383.003042 -228.504825)
			(xy 382.970407 -228.467988) (xy 382.944104 -228.426392) (xy 382.924813 -228.381116) (xy 382.913036 -228.333332)
			(xy 382.909076 -228.284278) (xy 382.580134 -228.284278) (xy 382.579639 -228.308885) (xy 382.571744 -228.357462)
			(xy 382.55616 -228.404143) (xy 382.533289 -228.44772) (xy 382.503724 -228.487064) (xy 382.468231 -228.521156)
			(xy 382.427728 -228.549112) (xy 382.383266 -228.57021) (xy 382.335995 -228.583902) (xy 382.28714 -228.589834)
			(xy 382.237965 -228.587853) (xy 382.189746 -228.578009) (xy 382.14373 -228.560557) (xy 382.101109 -228.53595)
			(xy 382.062988 -228.504825) (xy 382.030353 -228.467988) (xy 382.00405 -228.426392) (xy 381.984759 -228.381116)
			(xy 381.972982 -228.333332) (xy 381.969022 -228.284278) (xy 381.64008 -228.284278) (xy 381.639585 -228.308885)
			(xy 381.63169 -228.357462) (xy 381.616106 -228.404143) (xy 381.593235 -228.44772) (xy 381.56367 -228.487064)
			(xy 381.528177 -228.521156) (xy 381.487674 -228.549112) (xy 381.443212 -228.57021) (xy 381.395941 -228.583902)
			(xy 381.347086 -228.589834) (xy 381.297911 -228.587853) (xy 381.249692 -228.578009) (xy 381.203676 -228.560557)
			(xy 381.161055 -228.53595) (xy 381.122934 -228.504825) (xy 381.090299 -228.467988) (xy 381.063996 -228.426392)
			(xy 381.044705 -228.381116) (xy 381.032928 -228.333332) (xy 381.028968 -228.284278) (xy 380.71044 -228.284278)
			(xy 380.709928 -228.309724) (xy 380.701764 -228.359958) (xy 380.685648 -228.408232) (xy 380.661997 -228.453295)
			(xy 380.631424 -228.493981) (xy 380.59472 -228.529236) (xy 380.552836 -228.558146) (xy 380.506857 -228.579963)
			(xy 380.457973 -228.594123) (xy 380.407452 -228.600257) (xy 380.3566 -228.598208) (xy 380.306736 -228.588028)
			(xy 380.25915 -228.569981) (xy 380.215076 -228.544535) (xy 380.175654 -228.512348) (xy 380.141906 -228.474254)
			(xy 380.114705 -228.43124) (xy 380.094757 -228.38442) (xy 380.082578 -228.335006) (xy 380.078483 -228.284278)
			(xy 379.77064 -228.284278) (xy 379.770128 -228.309724) (xy 379.761964 -228.359958) (xy 379.745848 -228.408232)
			(xy 379.722197 -228.453295) (xy 379.691624 -228.493981) (xy 379.65492 -228.529236) (xy 379.613036 -228.558146)
			(xy 379.567057 -228.579963) (xy 379.518173 -228.594123) (xy 379.467652 -228.600257) (xy 379.4168 -228.598208)
			(xy 379.366936 -228.588028) (xy 379.31935 -228.569981) (xy 379.275276 -228.544535) (xy 379.235854 -228.512348)
			(xy 379.202106 -228.474254) (xy 379.174905 -228.43124) (xy 379.154957 -228.38442) (xy 379.142778 -228.335006)
			(xy 379.138683 -228.284278) (xy 378.820172 -228.284278) (xy 378.819677 -228.308885) (xy 378.811782 -228.357462)
			(xy 378.796198 -228.404143) (xy 378.773327 -228.44772) (xy 378.743762 -228.487064) (xy 378.708269 -228.521156)
			(xy 378.667766 -228.549112) (xy 378.623304 -228.57021) (xy 378.576033 -228.583902) (xy 378.527178 -228.589834)
			(xy 378.478003 -228.587853) (xy 378.429784 -228.578009) (xy 378.383768 -228.560557) (xy 378.341147 -228.53595)
			(xy 378.303026 -228.504825) (xy 378.270391 -228.467988) (xy 378.244088 -228.426392) (xy 378.224797 -228.381116)
			(xy 378.21302 -228.333332) (xy 378.20906 -228.284278) (xy 377.890532 -228.284278) (xy 377.89002 -228.309724)
			(xy 377.881856 -228.359958) (xy 377.86574 -228.408232) (xy 377.842089 -228.453295) (xy 377.811516 -228.493981)
			(xy 377.774812 -228.529236) (xy 377.732928 -228.558146) (xy 377.686949 -228.579963) (xy 377.638065 -228.594123)
			(xy 377.587544 -228.600257) (xy 377.536692 -228.598208) (xy 377.486828 -228.588028) (xy 377.439242 -228.569981)
			(xy 377.395168 -228.544535) (xy 377.355746 -228.512348) (xy 377.321998 -228.474254) (xy 377.294797 -228.43124)
			(xy 377.274849 -228.38442) (xy 377.26267 -228.335006) (xy 377.258575 -228.284278) (xy 376.940064 -228.284278)
			(xy 376.939569 -228.308885) (xy 376.931674 -228.357462) (xy 376.91609 -228.404143) (xy 376.893219 -228.44772)
			(xy 376.863654 -228.487064) (xy 376.828161 -228.521156) (xy 376.787658 -228.549112) (xy 376.743196 -228.57021)
			(xy 376.695925 -228.583902) (xy 376.64707 -228.589834) (xy 376.597895 -228.587853) (xy 376.549676 -228.578009)
			(xy 376.50366 -228.560557) (xy 376.461039 -228.53595) (xy 376.422918 -228.504825) (xy 376.390283 -228.467988)
			(xy 376.36398 -228.426392) (xy 376.344689 -228.381116) (xy 376.332912 -228.333332) (xy 376.328952 -228.284278)
			(xy 376.010424 -228.284278) (xy 376.009912 -228.309724) (xy 376.001748 -228.359958) (xy 375.985632 -228.408232)
			(xy 375.961981 -228.453295) (xy 375.931408 -228.493981) (xy 375.894704 -228.529236) (xy 375.85282 -228.558146)
			(xy 375.806841 -228.579963) (xy 375.757957 -228.594123) (xy 375.707436 -228.600257) (xy 375.656584 -228.598208)
			(xy 375.60672 -228.588028) (xy 375.559134 -228.569981) (xy 375.51506 -228.544535) (xy 375.475638 -228.512348)
			(xy 375.44189 -228.474254) (xy 375.414689 -228.43124) (xy 375.394741 -228.38442) (xy 375.382562 -228.335006)
			(xy 375.378467 -228.284278) (xy 375.06021 -228.284278) (xy 375.059715 -228.308885) (xy 375.05182 -228.357462)
			(xy 375.036236 -228.404143) (xy 375.013365 -228.44772) (xy 374.9838 -228.487064) (xy 374.948307 -228.521156)
			(xy 374.907804 -228.549112) (xy 374.863342 -228.57021) (xy 374.816071 -228.583902) (xy 374.767216 -228.589834)
			(xy 374.718041 -228.587853) (xy 374.669822 -228.578009) (xy 374.623806 -228.560557) (xy 374.581185 -228.53595)
			(xy 374.543064 -228.504825) (xy 374.510429 -228.467988) (xy 374.484126 -228.426392) (xy 374.464835 -228.381116)
			(xy 374.453058 -228.333332) (xy 374.449098 -228.284278) (xy 374.26646 -228.284278) (xy 374.26646 -228.719888)
			(xy 374.266858 -228.729408) (xy 374.273777 -228.747149) (xy 374.279922 -228.754432) (xy 374.294146 -228.769926)
			(xy 374.297099 -228.773024) (xy 374.303864 -228.778266) (xy 374.307608 -228.78034) (xy 374.329706 -228.792024)
			(xy 374.33758 -228.793548) (xy 374.362217 -228.798396) (xy 374.409578 -228.815062) (xy 374.453574 -228.839252)
			(xy 374.493021 -228.870313) (xy 374.526856 -228.907408) (xy 374.554166 -228.949538) (xy 374.574217 -228.995568)
			(xy 374.586468 -229.044259) (xy 374.590588 -229.094284) (xy 375.848621 -229.094284) (xy 375.852716 -229.043556)
			(xy 375.864895 -228.994142) (xy 375.884843 -228.947322) (xy 375.912044 -228.904308) (xy 375.945792 -228.866214)
			(xy 375.985214 -228.834027) (xy 376.029288 -228.808581) (xy 376.076874 -228.790534) (xy 376.126738 -228.780354)
			(xy 376.17759 -228.778305) (xy 376.228111 -228.784439) (xy 376.276995 -228.798599) (xy 376.322974 -228.820416)
			(xy 376.364858 -228.849326) (xy 376.401562 -228.884581) (xy 376.432135 -228.925267) (xy 376.455786 -228.97033)
			(xy 376.471902 -229.018604) (xy 376.480066 -229.068838) (xy 376.480578 -229.094284) (xy 376.788675 -229.094284)
			(xy 376.79277 -229.043556) (xy 376.804949 -228.994142) (xy 376.824897 -228.947322) (xy 376.852098 -228.904308)
			(xy 376.885846 -228.866214) (xy 376.925268 -228.834027) (xy 376.969342 -228.808581) (xy 377.016928 -228.790534)
			(xy 377.066792 -228.780354) (xy 377.117644 -228.778305) (xy 377.168165 -228.784439) (xy 377.217049 -228.798599)
			(xy 377.263028 -228.820416) (xy 377.304912 -228.849326) (xy 377.341616 -228.884581) (xy 377.372189 -228.925267)
			(xy 377.39584 -228.97033) (xy 377.411956 -229.018604) (xy 377.42012 -229.068838) (xy 377.420632 -229.094284)
			(xy 377.738906 -229.094284) (xy 377.742866 -229.04523) (xy 377.754643 -228.997446) (xy 377.773934 -228.95217)
			(xy 377.800237 -228.910574) (xy 377.832872 -228.873737) (xy 377.870993 -228.842612) (xy 377.913614 -228.818005)
			(xy 377.95963 -228.800553) (xy 378.007849 -228.790709) (xy 378.057024 -228.788728) (xy 378.105879 -228.79466)
			(xy 378.15315 -228.808352) (xy 378.197612 -228.82945) (xy 378.238115 -228.857406) (xy 378.273608 -228.891498)
			(xy 378.303173 -228.930842) (xy 378.326044 -228.974419) (xy 378.341628 -229.0211) (xy 378.349523 -229.069677)
			(xy 378.350018 -229.094284) (xy 378.668529 -229.094284) (xy 378.672624 -229.043556) (xy 378.684803 -228.994142)
			(xy 378.704751 -228.947322) (xy 378.731952 -228.904308) (xy 378.7657 -228.866214) (xy 378.805122 -228.834027)
			(xy 378.849196 -228.808581) (xy 378.896782 -228.790534) (xy 378.946646 -228.780354) (xy 378.997498 -228.778305)
			(xy 379.048019 -228.784439) (xy 379.096903 -228.798599) (xy 379.142882 -228.820416) (xy 379.184766 -228.849326)
			(xy 379.22147 -228.884581) (xy 379.252043 -228.925267) (xy 379.275694 -228.97033) (xy 379.29181 -229.018604)
			(xy 379.299974 -229.068838) (xy 379.300486 -229.094284) (xy 379.619014 -229.094284) (xy 379.622974 -229.04523)
			(xy 379.634751 -228.997446) (xy 379.654042 -228.95217) (xy 379.680345 -228.910574) (xy 379.71298 -228.873737)
			(xy 379.751101 -228.842612) (xy 379.793722 -228.818005) (xy 379.839738 -228.800553) (xy 379.887957 -228.790709)
			(xy 379.937132 -228.788728) (xy 379.985987 -228.79466) (xy 380.033258 -228.808352) (xy 380.07772 -228.82945)
			(xy 380.118223 -228.857406) (xy 380.153716 -228.891498) (xy 380.183281 -228.930842) (xy 380.206152 -228.974419)
			(xy 380.221736 -229.0211) (xy 380.229631 -229.069677) (xy 380.230126 -229.094284) (xy 380.548637 -229.094284)
			(xy 380.552732 -229.043556) (xy 380.564911 -228.994142) (xy 380.584859 -228.947322) (xy 380.61206 -228.904308)
			(xy 380.645808 -228.866214) (xy 380.68523 -228.834027) (xy 380.729304 -228.808581) (xy 380.77689 -228.790534)
			(xy 380.826754 -228.780354) (xy 380.877606 -228.778305) (xy 380.928127 -228.784439) (xy 380.977011 -228.798599)
			(xy 381.02299 -228.820416) (xy 381.064874 -228.849326) (xy 381.101578 -228.884581) (xy 381.132151 -228.925267)
			(xy 381.155802 -228.97033) (xy 381.171918 -229.018604) (xy 381.180082 -229.068838) (xy 381.180594 -229.094284)
			(xy 381.499122 -229.094284) (xy 381.503082 -229.04523) (xy 381.514859 -228.997446) (xy 381.53415 -228.95217)
			(xy 381.560453 -228.910574) (xy 381.593088 -228.873737) (xy 381.631209 -228.842612) (xy 381.67383 -228.818005)
			(xy 381.719846 -228.800553) (xy 381.768065 -228.790709) (xy 381.81724 -228.788728) (xy 381.866095 -228.79466)
			(xy 381.913366 -228.808352) (xy 381.957828 -228.82945) (xy 381.998331 -228.857406) (xy 382.033824 -228.891498)
			(xy 382.063389 -228.930842) (xy 382.08626 -228.974419) (xy 382.101844 -229.0211) (xy 382.109739 -229.069677)
			(xy 382.110234 -229.094284) (xy 382.438922 -229.094284) (xy 382.442882 -229.04523) (xy 382.454659 -228.997446)
			(xy 382.47395 -228.95217) (xy 382.500253 -228.910574) (xy 382.532888 -228.873737) (xy 382.571009 -228.842612)
			(xy 382.61363 -228.818005) (xy 382.659646 -228.800553) (xy 382.707865 -228.790709) (xy 382.75704 -228.788728)
			(xy 382.805895 -228.79466) (xy 382.853166 -228.808352) (xy 382.897628 -228.82945) (xy 382.938131 -228.857406)
			(xy 382.973624 -228.891498) (xy 383.003189 -228.930842) (xy 383.02606 -228.974419) (xy 383.041644 -229.0211)
			(xy 383.049539 -229.069677) (xy 383.050034 -229.094284) (xy 383.378976 -229.094284) (xy 383.382936 -229.04523)
			(xy 383.394713 -228.997446) (xy 383.414004 -228.95217) (xy 383.440307 -228.910574) (xy 383.472942 -228.873737)
			(xy 383.511063 -228.842612) (xy 383.553684 -228.818005) (xy 383.5997 -228.800553) (xy 383.647919 -228.790709)
			(xy 383.697094 -228.788728) (xy 383.745949 -228.79466) (xy 383.79322 -228.808352) (xy 383.837682 -228.82945)
			(xy 383.878185 -228.857406) (xy 383.913678 -228.891498) (xy 383.943243 -228.930842) (xy 383.966114 -228.974419)
			(xy 383.981698 -229.0211) (xy 383.989593 -229.069677) (xy 383.990088 -229.094284) (xy 384.31903 -229.094284)
			(xy 384.32299 -229.04523) (xy 384.334767 -228.997446) (xy 384.354058 -228.95217) (xy 384.380361 -228.910574)
			(xy 384.412996 -228.873737) (xy 384.451117 -228.842612) (xy 384.493738 -228.818005) (xy 384.539754 -228.800553)
			(xy 384.587973 -228.790709) (xy 384.637148 -228.788728) (xy 384.686003 -228.79466) (xy 384.733274 -228.808352)
			(xy 384.777736 -228.82945) (xy 384.818239 -228.857406) (xy 384.853732 -228.891498) (xy 384.883297 -228.930842)
			(xy 384.906168 -228.974419) (xy 384.921752 -229.0211) (xy 384.929647 -229.069677) (xy 384.930142 -229.094284)
			(xy 385.259084 -229.094284) (xy 385.263044 -229.04523) (xy 385.274821 -228.997446) (xy 385.294112 -228.95217)
			(xy 385.320415 -228.910574) (xy 385.35305 -228.873737) (xy 385.391171 -228.842612) (xy 385.433792 -228.818005)
			(xy 385.479808 -228.800553) (xy 385.528027 -228.790709) (xy 385.577202 -228.788728) (xy 385.626057 -228.79466)
			(xy 385.673328 -228.808352) (xy 385.71779 -228.82945) (xy 385.758293 -228.857406) (xy 385.793786 -228.891498)
			(xy 385.823351 -228.930842) (xy 385.846222 -228.974419) (xy 385.861806 -229.0211) (xy 385.869701 -229.069677)
			(xy 385.870196 -229.094284) (xy 386.199138 -229.094284) (xy 386.203098 -229.04523) (xy 386.214875 -228.997446)
			(xy 386.234166 -228.95217) (xy 386.260469 -228.910574) (xy 386.293104 -228.873737) (xy 386.331225 -228.842612)
			(xy 386.373846 -228.818005) (xy 386.419862 -228.800553) (xy 386.468081 -228.790709) (xy 386.517256 -228.788728)
			(xy 386.566111 -228.79466) (xy 386.613382 -228.808352) (xy 386.657844 -228.82945) (xy 386.698347 -228.857406)
			(xy 386.73384 -228.891498) (xy 386.763405 -228.930842) (xy 386.786276 -228.974419) (xy 386.80186 -229.0211)
			(xy 386.809755 -229.069677) (xy 386.81025 -229.094284) (xy 386.809755 -229.118891) (xy 386.80186 -229.167468)
			(xy 386.786276 -229.214149) (xy 386.763405 -229.257726) (xy 386.73384 -229.29707) (xy 386.698347 -229.331162)
			(xy 386.657844 -229.359118) (xy 386.613382 -229.380216) (xy 386.566111 -229.393908) (xy 386.517256 -229.39984)
			(xy 386.468081 -229.397859) (xy 386.419862 -229.388015) (xy 386.373846 -229.370563) (xy 386.331225 -229.345956)
			(xy 386.293104 -229.314831) (xy 386.260469 -229.277994) (xy 386.234166 -229.236398) (xy 386.214875 -229.191122)
			(xy 386.203098 -229.143338) (xy 386.199138 -229.094284) (xy 385.870196 -229.094284) (xy 385.869701 -229.118891)
			(xy 385.861806 -229.167468) (xy 385.846222 -229.214149) (xy 385.823351 -229.257726) (xy 385.793786 -229.29707)
			(xy 385.758293 -229.331162) (xy 385.71779 -229.359118) (xy 385.673328 -229.380216) (xy 385.626057 -229.393908)
			(xy 385.577202 -229.39984) (xy 385.528027 -229.397859) (xy 385.479808 -229.388015) (xy 385.433792 -229.370563)
			(xy 385.391171 -229.345956) (xy 385.35305 -229.314831) (xy 385.320415 -229.277994) (xy 385.294112 -229.236398)
			(xy 385.274821 -229.191122) (xy 385.263044 -229.143338) (xy 385.259084 -229.094284) (xy 384.930142 -229.094284)
			(xy 384.929647 -229.118891) (xy 384.921752 -229.167468) (xy 384.906168 -229.214149) (xy 384.883297 -229.257726)
			(xy 384.853732 -229.29707) (xy 384.818239 -229.331162) (xy 384.777736 -229.359118) (xy 384.733274 -229.380216)
			(xy 384.686003 -229.393908) (xy 384.637148 -229.39984) (xy 384.587973 -229.397859) (xy 384.539754 -229.388015)
			(xy 384.493738 -229.370563) (xy 384.451117 -229.345956) (xy 384.412996 -229.314831) (xy 384.380361 -229.277994)
			(xy 384.354058 -229.236398) (xy 384.334767 -229.191122) (xy 384.32299 -229.143338) (xy 384.31903 -229.094284)
			(xy 383.990088 -229.094284) (xy 383.989593 -229.118891) (xy 383.981698 -229.167468) (xy 383.966114 -229.214149)
			(xy 383.943243 -229.257726) (xy 383.913678 -229.29707) (xy 383.878185 -229.331162) (xy 383.837682 -229.359118)
			(xy 383.79322 -229.380216) (xy 383.745949 -229.393908) (xy 383.697094 -229.39984) (xy 383.647919 -229.397859)
			(xy 383.5997 -229.388015) (xy 383.553684 -229.370563) (xy 383.511063 -229.345956) (xy 383.472942 -229.314831)
			(xy 383.440307 -229.277994) (xy 383.414004 -229.236398) (xy 383.394713 -229.191122) (xy 383.382936 -229.143338)
			(xy 383.378976 -229.094284) (xy 383.050034 -229.094284) (xy 383.049539 -229.118891) (xy 383.041644 -229.167468)
			(xy 383.02606 -229.214149) (xy 383.003189 -229.257726) (xy 382.973624 -229.29707) (xy 382.938131 -229.331162)
			(xy 382.897628 -229.359118) (xy 382.853166 -229.380216) (xy 382.805895 -229.393908) (xy 382.75704 -229.39984)
			(xy 382.707865 -229.397859) (xy 382.659646 -229.388015) (xy 382.61363 -229.370563) (xy 382.571009 -229.345956)
			(xy 382.532888 -229.314831) (xy 382.500253 -229.277994) (xy 382.47395 -229.236398) (xy 382.454659 -229.191122)
			(xy 382.442882 -229.143338) (xy 382.438922 -229.094284) (xy 382.110234 -229.094284) (xy 382.109739 -229.118891)
			(xy 382.101844 -229.167468) (xy 382.08626 -229.214149) (xy 382.063389 -229.257726) (xy 382.033824 -229.29707)
			(xy 381.998331 -229.331162) (xy 381.957828 -229.359118) (xy 381.913366 -229.380216) (xy 381.866095 -229.393908)
			(xy 381.81724 -229.39984) (xy 381.768065 -229.397859) (xy 381.719846 -229.388015) (xy 381.67383 -229.370563)
			(xy 381.631209 -229.345956) (xy 381.593088 -229.314831) (xy 381.560453 -229.277994) (xy 381.53415 -229.236398)
			(xy 381.514859 -229.191122) (xy 381.503082 -229.143338) (xy 381.499122 -229.094284) (xy 381.180594 -229.094284)
			(xy 381.180082 -229.11973) (xy 381.171918 -229.169964) (xy 381.155802 -229.218238) (xy 381.132151 -229.263301)
			(xy 381.101578 -229.303987) (xy 381.064874 -229.339242) (xy 381.02299 -229.368152) (xy 380.977011 -229.389969)
			(xy 380.928127 -229.404129) (xy 380.877606 -229.410263) (xy 380.826754 -229.408214) (xy 380.77689 -229.398034)
			(xy 380.729304 -229.379987) (xy 380.68523 -229.354541) (xy 380.645808 -229.322354) (xy 380.61206 -229.28426)
			(xy 380.584859 -229.241246) (xy 380.564911 -229.194426) (xy 380.552732 -229.145012) (xy 380.548637 -229.094284)
			(xy 380.230126 -229.094284) (xy 380.229631 -229.118891) (xy 380.221736 -229.167468) (xy 380.206152 -229.214149)
			(xy 380.183281 -229.257726) (xy 380.153716 -229.29707) (xy 380.118223 -229.331162) (xy 380.07772 -229.359118)
			(xy 380.033258 -229.380216) (xy 379.985987 -229.393908) (xy 379.937132 -229.39984) (xy 379.887957 -229.397859)
			(xy 379.839738 -229.388015) (xy 379.793722 -229.370563) (xy 379.751101 -229.345956) (xy 379.71298 -229.314831)
			(xy 379.680345 -229.277994) (xy 379.654042 -229.236398) (xy 379.634751 -229.191122) (xy 379.622974 -229.143338)
			(xy 379.619014 -229.094284) (xy 379.300486 -229.094284) (xy 379.299974 -229.11973) (xy 379.29181 -229.169964)
			(xy 379.275694 -229.218238) (xy 379.252043 -229.263301) (xy 379.22147 -229.303987) (xy 379.184766 -229.339242)
			(xy 379.142882 -229.368152) (xy 379.096903 -229.389969) (xy 379.048019 -229.404129) (xy 378.997498 -229.410263)
			(xy 378.946646 -229.408214) (xy 378.896782 -229.398034) (xy 378.849196 -229.379987) (xy 378.805122 -229.354541)
			(xy 378.7657 -229.322354) (xy 378.731952 -229.28426) (xy 378.704751 -229.241246) (xy 378.684803 -229.194426)
			(xy 378.672624 -229.145012) (xy 378.668529 -229.094284) (xy 378.350018 -229.094284) (xy 378.349523 -229.118891)
			(xy 378.341628 -229.167468) (xy 378.326044 -229.214149) (xy 378.303173 -229.257726) (xy 378.273608 -229.29707)
			(xy 378.238115 -229.331162) (xy 378.197612 -229.359118) (xy 378.15315 -229.380216) (xy 378.105879 -229.393908)
			(xy 378.057024 -229.39984) (xy 378.007849 -229.397859) (xy 377.95963 -229.388015) (xy 377.913614 -229.370563)
			(xy 377.870993 -229.345956) (xy 377.832872 -229.314831) (xy 377.800237 -229.277994) (xy 377.773934 -229.236398)
			(xy 377.754643 -229.191122) (xy 377.742866 -229.143338) (xy 377.738906 -229.094284) (xy 377.420632 -229.094284)
			(xy 377.42012 -229.11973) (xy 377.411956 -229.169964) (xy 377.39584 -229.218238) (xy 377.372189 -229.263301)
			(xy 377.341616 -229.303987) (xy 377.304912 -229.339242) (xy 377.263028 -229.368152) (xy 377.217049 -229.389969)
			(xy 377.168165 -229.404129) (xy 377.117644 -229.410263) (xy 377.066792 -229.408214) (xy 377.016928 -229.398034)
			(xy 376.969342 -229.379987) (xy 376.925268 -229.354541) (xy 376.885846 -229.322354) (xy 376.852098 -229.28426)
			(xy 376.824897 -229.241246) (xy 376.804949 -229.194426) (xy 376.79277 -229.145012) (xy 376.788675 -229.094284)
			(xy 376.480578 -229.094284) (xy 376.480066 -229.11973) (xy 376.471902 -229.169964) (xy 376.455786 -229.218238)
			(xy 376.432135 -229.263301) (xy 376.401562 -229.303987) (xy 376.364858 -229.339242) (xy 376.322974 -229.368152)
			(xy 376.276995 -229.389969) (xy 376.228111 -229.404129) (xy 376.17759 -229.410263) (xy 376.126738 -229.408214)
			(xy 376.076874 -229.398034) (xy 376.029288 -229.379987) (xy 375.985214 -229.354541) (xy 375.945792 -229.322354)
			(xy 375.912044 -229.28426) (xy 375.884843 -229.241246) (xy 375.864895 -229.194426) (xy 375.852716 -229.145012)
			(xy 375.848621 -229.094284) (xy 374.590588 -229.094284) (xy 374.590589 -229.094297) (xy 374.586469 -229.144336)
			(xy 374.574219 -229.193026) (xy 374.554169 -229.239057) (xy 374.526859 -229.281188) (xy 374.493025 -229.318284)
			(xy 374.453579 -229.349345) (xy 374.409583 -229.373535) (xy 374.362222 -229.390203) (xy 374.33758 -229.39502)
			(xy 374.329706 -229.396544) (xy 374.307608 -229.408228) (xy 374.303878 -229.410323) (xy 374.297112 -229.415558)
			(xy 374.294146 -229.418642) (xy 374.279922 -229.434136) (xy 374.273735 -229.441394) (xy 374.266817 -229.45915)
			(xy 374.26646 -229.46868) (xy 374.26646 -229.904036) (xy 374.449098 -229.904036) (xy 374.453058 -229.854982)
			(xy 374.464835 -229.807198) (xy 374.484126 -229.761922) (xy 374.510429 -229.720326) (xy 374.543064 -229.683489)
			(xy 374.581185 -229.652364) (xy 374.623806 -229.627757) (xy 374.669822 -229.610305) (xy 374.718041 -229.600461)
			(xy 374.767216 -229.59848) (xy 374.816071 -229.604412) (xy 374.863342 -229.618104) (xy 374.907804 -229.639202)
			(xy 374.948307 -229.667158) (xy 374.9838 -229.70125) (xy 375.013365 -229.740594) (xy 375.036236 -229.784171)
			(xy 375.05182 -229.830852) (xy 375.059715 -229.879429) (xy 375.06021 -229.904036) (xy 375.378467 -229.904036)
			(xy 375.382562 -229.853308) (xy 375.394741 -229.803894) (xy 375.414689 -229.757074) (xy 375.44189 -229.71406)
			(xy 375.475638 -229.675966) (xy 375.51506 -229.643779) (xy 375.559134 -229.618333) (xy 375.60672 -229.600286)
			(xy 375.656584 -229.590106) (xy 375.707436 -229.588057) (xy 375.757957 -229.594191) (xy 375.806841 -229.608351)
			(xy 375.85282 -229.630168) (xy 375.894704 -229.659078) (xy 375.931408 -229.694333) (xy 375.961981 -229.735019)
			(xy 375.985632 -229.780082) (xy 376.001748 -229.828356) (xy 376.009912 -229.87859) (xy 376.010424 -229.904036)
			(xy 376.328952 -229.904036) (xy 376.332912 -229.854982) (xy 376.344689 -229.807198) (xy 376.36398 -229.761922)
			(xy 376.390283 -229.720326) (xy 376.422918 -229.683489) (xy 376.461039 -229.652364) (xy 376.50366 -229.627757)
			(xy 376.549676 -229.610305) (xy 376.597895 -229.600461) (xy 376.64707 -229.59848) (xy 376.695925 -229.604412)
			(xy 376.743196 -229.618104) (xy 376.787658 -229.639202) (xy 376.828161 -229.667158) (xy 376.863654 -229.70125)
			(xy 376.893219 -229.740594) (xy 376.91609 -229.784171) (xy 376.931674 -229.830852) (xy 376.939569 -229.879429)
			(xy 376.940064 -229.904036) (xy 377.258575 -229.904036) (xy 377.26267 -229.853308) (xy 377.274849 -229.803894)
			(xy 377.294797 -229.757074) (xy 377.321998 -229.71406) (xy 377.355746 -229.675966) (xy 377.395168 -229.643779)
			(xy 377.439242 -229.618333) (xy 377.486828 -229.600286) (xy 377.536692 -229.590106) (xy 377.587544 -229.588057)
			(xy 377.638065 -229.594191) (xy 377.686949 -229.608351) (xy 377.732928 -229.630168) (xy 377.774812 -229.659078)
			(xy 377.811516 -229.694333) (xy 377.842089 -229.735019) (xy 377.86574 -229.780082) (xy 377.881856 -229.828356)
			(xy 377.89002 -229.87859) (xy 377.890532 -229.904036) (xy 379.138683 -229.904036) (xy 379.142778 -229.853308)
			(xy 379.154957 -229.803894) (xy 379.174905 -229.757074) (xy 379.202106 -229.71406) (xy 379.235854 -229.675966)
			(xy 379.275276 -229.643779) (xy 379.31935 -229.618333) (xy 379.366936 -229.600286) (xy 379.4168 -229.590106)
			(xy 379.467652 -229.588057) (xy 379.518173 -229.594191) (xy 379.567057 -229.608351) (xy 379.613036 -229.630168)
			(xy 379.65492 -229.659078) (xy 379.691624 -229.694333) (xy 379.722197 -229.735019) (xy 379.745848 -229.780082)
			(xy 379.761964 -229.828356) (xy 379.770128 -229.87859) (xy 379.77064 -229.904036) (xy 380.078483 -229.904036)
			(xy 380.082578 -229.853308) (xy 380.094757 -229.803894) (xy 380.114705 -229.757074) (xy 380.141906 -229.71406)
			(xy 380.175654 -229.675966) (xy 380.215076 -229.643779) (xy 380.25915 -229.618333) (xy 380.306736 -229.600286)
			(xy 380.3566 -229.590106) (xy 380.407452 -229.588057) (xy 380.457973 -229.594191) (xy 380.506857 -229.608351)
			(xy 380.552836 -229.630168) (xy 380.59472 -229.659078) (xy 380.631424 -229.694333) (xy 380.661997 -229.735019)
			(xy 380.685648 -229.780082) (xy 380.701764 -229.828356) (xy 380.709928 -229.87859) (xy 380.71044 -229.904036)
			(xy 381.028968 -229.904036) (xy 381.032928 -229.854982) (xy 381.044705 -229.807198) (xy 381.063996 -229.761922)
			(xy 381.090299 -229.720326) (xy 381.122934 -229.683489) (xy 381.161055 -229.652364) (xy 381.203676 -229.627757)
			(xy 381.249692 -229.610305) (xy 381.297911 -229.600461) (xy 381.347086 -229.59848) (xy 381.395941 -229.604412)
			(xy 381.443212 -229.618104) (xy 381.487674 -229.639202) (xy 381.528177 -229.667158) (xy 381.56367 -229.70125)
			(xy 381.593235 -229.740594) (xy 381.616106 -229.784171) (xy 381.63169 -229.830852) (xy 381.639585 -229.879429)
			(xy 381.64008 -229.904036) (xy 381.969022 -229.904036) (xy 381.972982 -229.854982) (xy 381.984759 -229.807198)
			(xy 382.00405 -229.761922) (xy 382.030353 -229.720326) (xy 382.062988 -229.683489) (xy 382.101109 -229.652364)
			(xy 382.14373 -229.627757) (xy 382.189746 -229.610305) (xy 382.237965 -229.600461) (xy 382.28714 -229.59848)
			(xy 382.335995 -229.604412) (xy 382.383266 -229.618104) (xy 382.427728 -229.639202) (xy 382.468231 -229.667158)
			(xy 382.503724 -229.70125) (xy 382.533289 -229.740594) (xy 382.55616 -229.784171) (xy 382.571744 -229.830852)
			(xy 382.579639 -229.879429) (xy 382.580134 -229.904036) (xy 382.909076 -229.904036) (xy 382.913036 -229.854982)
			(xy 382.924813 -229.807198) (xy 382.944104 -229.761922) (xy 382.970407 -229.720326) (xy 383.003042 -229.683489)
			(xy 383.041163 -229.652364) (xy 383.083784 -229.627757) (xy 383.1298 -229.610305) (xy 383.178019 -229.600461)
			(xy 383.227194 -229.59848) (xy 383.276049 -229.604412) (xy 383.32332 -229.618104) (xy 383.367782 -229.639202)
			(xy 383.408285 -229.667158) (xy 383.443778 -229.70125) (xy 383.473343 -229.740594) (xy 383.496214 -229.784171)
			(xy 383.511798 -229.830852) (xy 383.519693 -229.879429) (xy 383.520188 -229.904036) (xy 383.84913 -229.904036)
			(xy 383.85309 -229.854982) (xy 383.864867 -229.807198) (xy 383.884158 -229.761922) (xy 383.910461 -229.720326)
			(xy 383.943096 -229.683489) (xy 383.981217 -229.652364) (xy 384.023838 -229.627757) (xy 384.069854 -229.610305)
			(xy 384.118073 -229.600461) (xy 384.167248 -229.59848) (xy 384.216103 -229.604412) (xy 384.263374 -229.618104)
			(xy 384.307836 -229.639202) (xy 384.348339 -229.667158) (xy 384.383832 -229.70125) (xy 384.413397 -229.740594)
			(xy 384.436268 -229.784171) (xy 384.451852 -229.830852) (xy 384.459747 -229.879429) (xy 384.460242 -229.904036)
			(xy 385.728984 -229.904036) (xy 385.732944 -229.854982) (xy 385.744721 -229.807198) (xy 385.764012 -229.761922)
			(xy 385.790315 -229.720326) (xy 385.82295 -229.683489) (xy 385.861071 -229.652364) (xy 385.903692 -229.627757)
			(xy 385.949708 -229.610305) (xy 385.997927 -229.600461) (xy 386.047102 -229.59848) (xy 386.095957 -229.604412)
			(xy 386.143228 -229.618104) (xy 386.18769 -229.639202) (xy 386.228193 -229.667158) (xy 386.263686 -229.70125)
			(xy 386.293251 -229.740594) (xy 386.316122 -229.784171) (xy 386.331706 -229.830852) (xy 386.339601 -229.879429)
			(xy 386.340096 -229.904036) (xy 386.669038 -229.904036) (xy 386.672998 -229.854982) (xy 386.684775 -229.807198)
			(xy 386.704066 -229.761922) (xy 386.730369 -229.720326) (xy 386.763004 -229.683489) (xy 386.801125 -229.652364)
			(xy 386.843746 -229.627757) (xy 386.889762 -229.610305) (xy 386.937981 -229.600461) (xy 386.987156 -229.59848)
			(xy 387.036011 -229.604412) (xy 387.083282 -229.618104) (xy 387.127744 -229.639202) (xy 387.168247 -229.667158)
			(xy 387.20374 -229.70125) (xy 387.233305 -229.740594) (xy 387.256176 -229.784171) (xy 387.27176 -229.830852)
			(xy 387.279655 -229.879429) (xy 387.28015 -229.904036) (xy 387.279655 -229.928643) (xy 387.27176 -229.97722)
			(xy 387.256176 -230.023901) (xy 387.233305 -230.067478) (xy 387.20374 -230.106822) (xy 387.168247 -230.140914)
			(xy 387.127744 -230.16887) (xy 387.083282 -230.189968) (xy 387.036011 -230.20366) (xy 386.987156 -230.209592)
			(xy 386.937981 -230.207611) (xy 386.889762 -230.197767) (xy 386.843746 -230.180315) (xy 386.801125 -230.155708)
			(xy 386.763004 -230.124583) (xy 386.730369 -230.087746) (xy 386.704066 -230.04615) (xy 386.684775 -230.000874)
			(xy 386.672998 -229.95309) (xy 386.669038 -229.904036) (xy 386.340096 -229.904036) (xy 386.339601 -229.928643)
			(xy 386.331706 -229.97722) (xy 386.316122 -230.023901) (xy 386.293251 -230.067478) (xy 386.263686 -230.106822)
			(xy 386.228193 -230.140914) (xy 386.18769 -230.16887) (xy 386.143228 -230.189968) (xy 386.095957 -230.20366)
			(xy 386.047102 -230.209592) (xy 385.997927 -230.207611) (xy 385.949708 -230.197767) (xy 385.903692 -230.180315)
			(xy 385.861071 -230.155708) (xy 385.82295 -230.124583) (xy 385.790315 -230.087746) (xy 385.764012 -230.04615)
			(xy 385.744721 -230.000874) (xy 385.732944 -229.95309) (xy 385.728984 -229.904036) (xy 384.460242 -229.904036)
			(xy 384.459747 -229.928643) (xy 384.451852 -229.97722) (xy 384.436268 -230.023901) (xy 384.413397 -230.067478)
			(xy 384.383832 -230.106822) (xy 384.348339 -230.140914) (xy 384.307836 -230.16887) (xy 384.263374 -230.189968)
			(xy 384.216103 -230.20366) (xy 384.167248 -230.209592) (xy 384.118073 -230.207611) (xy 384.069854 -230.197767)
			(xy 384.023838 -230.180315) (xy 383.981217 -230.155708) (xy 383.943096 -230.124583) (xy 383.910461 -230.087746)
			(xy 383.884158 -230.04615) (xy 383.864867 -230.000874) (xy 383.85309 -229.95309) (xy 383.84913 -229.904036)
			(xy 383.520188 -229.904036) (xy 383.519693 -229.928643) (xy 383.511798 -229.97722) (xy 383.496214 -230.023901)
			(xy 383.473343 -230.067478) (xy 383.443778 -230.106822) (xy 383.408285 -230.140914) (xy 383.367782 -230.16887)
			(xy 383.32332 -230.189968) (xy 383.276049 -230.20366) (xy 383.227194 -230.209592) (xy 383.178019 -230.207611)
			(xy 383.1298 -230.197767) (xy 383.083784 -230.180315) (xy 383.041163 -230.155708) (xy 383.003042 -230.124583)
			(xy 382.970407 -230.087746) (xy 382.944104 -230.04615) (xy 382.924813 -230.000874) (xy 382.913036 -229.95309)
			(xy 382.909076 -229.904036) (xy 382.580134 -229.904036) (xy 382.579639 -229.928643) (xy 382.571744 -229.97722)
			(xy 382.55616 -230.023901) (xy 382.533289 -230.067478) (xy 382.503724 -230.106822) (xy 382.468231 -230.140914)
			(xy 382.427728 -230.16887) (xy 382.383266 -230.189968) (xy 382.335995 -230.20366) (xy 382.28714 -230.209592)
			(xy 382.237965 -230.207611) (xy 382.189746 -230.197767) (xy 382.14373 -230.180315) (xy 382.101109 -230.155708)
			(xy 382.062988 -230.124583) (xy 382.030353 -230.087746) (xy 382.00405 -230.04615) (xy 381.984759 -230.000874)
			(xy 381.972982 -229.95309) (xy 381.969022 -229.904036) (xy 381.64008 -229.904036) (xy 381.639585 -229.928643)
			(xy 381.63169 -229.97722) (xy 381.616106 -230.023901) (xy 381.593235 -230.067478) (xy 381.56367 -230.106822)
			(xy 381.528177 -230.140914) (xy 381.487674 -230.16887) (xy 381.443212 -230.189968) (xy 381.395941 -230.20366)
			(xy 381.347086 -230.209592) (xy 381.297911 -230.207611) (xy 381.249692 -230.197767) (xy 381.203676 -230.180315)
			(xy 381.161055 -230.155708) (xy 381.122934 -230.124583) (xy 381.090299 -230.087746) (xy 381.063996 -230.04615)
			(xy 381.044705 -230.000874) (xy 381.032928 -229.95309) (xy 381.028968 -229.904036) (xy 380.71044 -229.904036)
			(xy 380.709928 -229.929482) (xy 380.701764 -229.979716) (xy 380.685648 -230.02799) (xy 380.661997 -230.073053)
			(xy 380.631424 -230.113739) (xy 380.59472 -230.148994) (xy 380.552836 -230.177904) (xy 380.506857 -230.199721)
			(xy 380.457973 -230.213881) (xy 380.407452 -230.220015) (xy 380.3566 -230.217966) (xy 380.306736 -230.207786)
			(xy 380.25915 -230.189739) (xy 380.215076 -230.164293) (xy 380.175654 -230.132106) (xy 380.141906 -230.094012)
			(xy 380.114705 -230.050998) (xy 380.094757 -230.004178) (xy 380.082578 -229.954764) (xy 380.078483 -229.904036)
			(xy 379.77064 -229.904036) (xy 379.770128 -229.929482) (xy 379.761964 -229.979716) (xy 379.745848 -230.02799)
			(xy 379.722197 -230.073053) (xy 379.691624 -230.113739) (xy 379.65492 -230.148994) (xy 379.613036 -230.177904)
			(xy 379.567057 -230.199721) (xy 379.518173 -230.213881) (xy 379.467652 -230.220015) (xy 379.4168 -230.217966)
			(xy 379.366936 -230.207786) (xy 379.31935 -230.189739) (xy 379.275276 -230.164293) (xy 379.235854 -230.132106)
			(xy 379.202106 -230.094012) (xy 379.174905 -230.050998) (xy 379.154957 -230.004178) (xy 379.142778 -229.954764)
			(xy 379.138683 -229.904036) (xy 377.890532 -229.904036) (xy 377.89002 -229.929482) (xy 377.881856 -229.979716)
			(xy 377.86574 -230.02799) (xy 377.842089 -230.073053) (xy 377.811516 -230.113739) (xy 377.774812 -230.148994)
			(xy 377.732928 -230.177904) (xy 377.686949 -230.199721) (xy 377.638065 -230.213881) (xy 377.587544 -230.220015)
			(xy 377.536692 -230.217966) (xy 377.486828 -230.207786) (xy 377.439242 -230.189739) (xy 377.395168 -230.164293)
			(xy 377.355746 -230.132106) (xy 377.321998 -230.094012) (xy 377.294797 -230.050998) (xy 377.274849 -230.004178)
			(xy 377.26267 -229.954764) (xy 377.258575 -229.904036) (xy 376.940064 -229.904036) (xy 376.939569 -229.928643)
			(xy 376.931674 -229.97722) (xy 376.91609 -230.023901) (xy 376.893219 -230.067478) (xy 376.863654 -230.106822)
			(xy 376.828161 -230.140914) (xy 376.787658 -230.16887) (xy 376.743196 -230.189968) (xy 376.695925 -230.20366)
			(xy 376.64707 -230.209592) (xy 376.597895 -230.207611) (xy 376.549676 -230.197767) (xy 376.50366 -230.180315)
			(xy 376.461039 -230.155708) (xy 376.422918 -230.124583) (xy 376.390283 -230.087746) (xy 376.36398 -230.04615)
			(xy 376.344689 -230.000874) (xy 376.332912 -229.95309) (xy 376.328952 -229.904036) (xy 376.010424 -229.904036)
			(xy 376.009912 -229.929482) (xy 376.001748 -229.979716) (xy 375.985632 -230.02799) (xy 375.961981 -230.073053)
			(xy 375.931408 -230.113739) (xy 375.894704 -230.148994) (xy 375.85282 -230.177904) (xy 375.806841 -230.199721)
			(xy 375.757957 -230.213881) (xy 375.707436 -230.220015) (xy 375.656584 -230.217966) (xy 375.60672 -230.207786)
			(xy 375.559134 -230.189739) (xy 375.51506 -230.164293) (xy 375.475638 -230.132106) (xy 375.44189 -230.094012)
			(xy 375.414689 -230.050998) (xy 375.394741 -230.004178) (xy 375.382562 -229.954764) (xy 375.378467 -229.904036)
			(xy 375.06021 -229.904036) (xy 375.059715 -229.928643) (xy 375.05182 -229.97722) (xy 375.036236 -230.023901)
			(xy 375.013365 -230.067478) (xy 374.9838 -230.106822) (xy 374.948307 -230.140914) (xy 374.907804 -230.16887)
			(xy 374.863342 -230.189968) (xy 374.816071 -230.20366) (xy 374.767216 -230.209592) (xy 374.718041 -230.207611)
			(xy 374.669822 -230.197767) (xy 374.623806 -230.180315) (xy 374.581185 -230.155708) (xy 374.543064 -230.124583)
			(xy 374.510429 -230.087746) (xy 374.484126 -230.04615) (xy 374.464835 -230.000874) (xy 374.453058 -229.95309)
			(xy 374.449098 -229.904036) (xy 374.26646 -229.904036) (xy 374.26646 -230.3399) (xy 374.26686 -230.34942)
			(xy 374.273782 -230.367157) (xy 374.279922 -230.374444) (xy 374.294146 -230.389938) (xy 374.2971 -230.393035)
			(xy 374.303865 -230.398276) (xy 374.307608 -230.400352) (xy 374.329706 -230.412036) (xy 374.33758 -230.41356)
			(xy 374.362216 -230.418408) (xy 374.409575 -230.435074) (xy 374.453569 -230.459263) (xy 374.493015 -230.490323)
			(xy 374.526848 -230.527417) (xy 374.554157 -230.569546) (xy 374.574207 -230.615574) (xy 374.586457 -230.664263)
			(xy 374.590577 -230.714296) (xy 374.918998 -230.714296) (xy 374.922958 -230.665242) (xy 374.934735 -230.617458)
			(xy 374.954026 -230.572182) (xy 374.980329 -230.530586) (xy 375.012964 -230.493749) (xy 375.051085 -230.462624)
			(xy 375.093706 -230.438017) (xy 375.139722 -230.420565) (xy 375.187941 -230.410721) (xy 375.237116 -230.40874)
			(xy 375.285971 -230.414672) (xy 375.333242 -230.428364) (xy 375.377704 -230.449462) (xy 375.418207 -230.477418)
			(xy 375.4537 -230.51151) (xy 375.483265 -230.550854) (xy 375.506136 -230.594431) (xy 375.52172 -230.641112)
			(xy 375.529615 -230.689689) (xy 375.53011 -230.714296) (xy 375.848621 -230.714296) (xy 375.852716 -230.663568)
			(xy 375.864895 -230.614154) (xy 375.884843 -230.567334) (xy 375.912044 -230.52432) (xy 375.945792 -230.486226)
			(xy 375.985214 -230.454039) (xy 376.029288 -230.428593) (xy 376.076874 -230.410546) (xy 376.126738 -230.400366)
			(xy 376.17759 -230.398317) (xy 376.228111 -230.404451) (xy 376.276995 -230.418611) (xy 376.322974 -230.440428)
			(xy 376.364858 -230.469338) (xy 376.401562 -230.504593) (xy 376.432135 -230.545279) (xy 376.455786 -230.590342)
			(xy 376.471902 -230.638616) (xy 376.480066 -230.68885) (xy 376.480578 -230.714296) (xy 376.788675 -230.714296)
			(xy 376.79277 -230.663568) (xy 376.804949 -230.614154) (xy 376.824897 -230.567334) (xy 376.852098 -230.52432)
			(xy 376.885846 -230.486226) (xy 376.925268 -230.454039) (xy 376.969342 -230.428593) (xy 377.016928 -230.410546)
			(xy 377.066792 -230.400366) (xy 377.117644 -230.398317) (xy 377.168165 -230.404451) (xy 377.217049 -230.418611)
			(xy 377.263028 -230.440428) (xy 377.304912 -230.469338) (xy 377.341616 -230.504593) (xy 377.372189 -230.545279)
			(xy 377.39584 -230.590342) (xy 377.411956 -230.638616) (xy 377.42012 -230.68885) (xy 377.420632 -230.714296)
			(xy 377.738906 -230.714296) (xy 377.742866 -230.665242) (xy 377.754643 -230.617458) (xy 377.773934 -230.572182)
			(xy 377.800237 -230.530586) (xy 377.832872 -230.493749) (xy 377.870993 -230.462624) (xy 377.913614 -230.438017)
			(xy 377.95963 -230.420565) (xy 378.007849 -230.410721) (xy 378.057024 -230.40874) (xy 378.105879 -230.414672)
			(xy 378.15315 -230.428364) (xy 378.197612 -230.449462) (xy 378.238115 -230.477418) (xy 378.273608 -230.51151)
			(xy 378.303173 -230.550854) (xy 378.326044 -230.594431) (xy 378.341628 -230.641112) (xy 378.349523 -230.689689)
			(xy 378.350018 -230.714296) (xy 378.668529 -230.714296) (xy 378.672624 -230.663568) (xy 378.684803 -230.614154)
			(xy 378.704751 -230.567334) (xy 378.731952 -230.52432) (xy 378.7657 -230.486226) (xy 378.805122 -230.454039)
			(xy 378.849196 -230.428593) (xy 378.896782 -230.410546) (xy 378.946646 -230.400366) (xy 378.997498 -230.398317)
			(xy 379.048019 -230.404451) (xy 379.096903 -230.418611) (xy 379.142882 -230.440428) (xy 379.184766 -230.469338)
			(xy 379.22147 -230.504593) (xy 379.252043 -230.545279) (xy 379.275694 -230.590342) (xy 379.29181 -230.638616)
			(xy 379.299974 -230.68885) (xy 379.300486 -230.714296) (xy 379.619014 -230.714296) (xy 379.622974 -230.665242)
			(xy 379.634751 -230.617458) (xy 379.654042 -230.572182) (xy 379.680345 -230.530586) (xy 379.71298 -230.493749)
			(xy 379.751101 -230.462624) (xy 379.793722 -230.438017) (xy 379.839738 -230.420565) (xy 379.887957 -230.410721)
			(xy 379.937132 -230.40874) (xy 379.985987 -230.414672) (xy 380.033258 -230.428364) (xy 380.07772 -230.449462)
			(xy 380.118223 -230.477418) (xy 380.153716 -230.51151) (xy 380.183281 -230.550854) (xy 380.206152 -230.594431)
			(xy 380.221736 -230.641112) (xy 380.229631 -230.689689) (xy 380.230126 -230.714296) (xy 380.548637 -230.714296)
			(xy 380.552732 -230.663568) (xy 380.564911 -230.614154) (xy 380.584859 -230.567334) (xy 380.61206 -230.52432)
			(xy 380.645808 -230.486226) (xy 380.68523 -230.454039) (xy 380.729304 -230.428593) (xy 380.77689 -230.410546)
			(xy 380.826754 -230.400366) (xy 380.877606 -230.398317) (xy 380.928127 -230.404451) (xy 380.977011 -230.418611)
			(xy 381.02299 -230.440428) (xy 381.064874 -230.469338) (xy 381.101578 -230.504593) (xy 381.132151 -230.545279)
			(xy 381.155802 -230.590342) (xy 381.171918 -230.638616) (xy 381.180082 -230.68885) (xy 381.180589 -230.714042)
			(xy 381.499122 -230.714042) (xy 381.503082 -230.664988) (xy 381.514859 -230.617204) (xy 381.53415 -230.571928)
			(xy 381.560453 -230.530332) (xy 381.593088 -230.493495) (xy 381.631209 -230.46237) (xy 381.67383 -230.437763)
			(xy 381.719846 -230.420311) (xy 381.768065 -230.410467) (xy 381.81724 -230.408486) (xy 381.866095 -230.414418)
			(xy 381.913366 -230.42811) (xy 381.957828 -230.449208) (xy 381.998331 -230.477164) (xy 382.033824 -230.511256)
			(xy 382.063389 -230.5506) (xy 382.08626 -230.594177) (xy 382.101844 -230.640858) (xy 382.109739 -230.689435)
			(xy 382.110234 -230.714042) (xy 382.110229 -230.714296) (xy 382.438922 -230.714296) (xy 382.442882 -230.665242)
			(xy 382.454659 -230.617458) (xy 382.47395 -230.572182) (xy 382.500253 -230.530586) (xy 382.532888 -230.493749)
			(xy 382.571009 -230.462624) (xy 382.61363 -230.438017) (xy 382.659646 -230.420565) (xy 382.707865 -230.410721)
			(xy 382.75704 -230.40874) (xy 382.805895 -230.414672) (xy 382.853166 -230.428364) (xy 382.897628 -230.449462)
			(xy 382.938131 -230.477418) (xy 382.973624 -230.51151) (xy 383.003189 -230.550854) (xy 383.02606 -230.594431)
			(xy 383.041644 -230.641112) (xy 383.049539 -230.689689) (xy 383.050034 -230.714296) (xy 383.378976 -230.714296)
			(xy 383.382936 -230.665242) (xy 383.394713 -230.617458) (xy 383.414004 -230.572182) (xy 383.440307 -230.530586)
			(xy 383.472942 -230.493749) (xy 383.511063 -230.462624) (xy 383.553684 -230.438017) (xy 383.5997 -230.420565)
			(xy 383.647919 -230.410721) (xy 383.697094 -230.40874) (xy 383.745949 -230.414672) (xy 383.79322 -230.428364)
			(xy 383.837682 -230.449462) (xy 383.878185 -230.477418) (xy 383.913678 -230.51151) (xy 383.943243 -230.550854)
			(xy 383.966114 -230.594431) (xy 383.981698 -230.641112) (xy 383.989593 -230.689689) (xy 383.990088 -230.714296)
			(xy 384.31903 -230.714296) (xy 384.32299 -230.665242) (xy 384.334767 -230.617458) (xy 384.354058 -230.572182)
			(xy 384.380361 -230.530586) (xy 384.412996 -230.493749) (xy 384.451117 -230.462624) (xy 384.493738 -230.438017)
			(xy 384.539754 -230.420565) (xy 384.587973 -230.410721) (xy 384.637148 -230.40874) (xy 384.686003 -230.414672)
			(xy 384.733274 -230.428364) (xy 384.777736 -230.449462) (xy 384.818239 -230.477418) (xy 384.853732 -230.51151)
			(xy 384.883297 -230.550854) (xy 384.906168 -230.594431) (xy 384.921752 -230.641112) (xy 384.929647 -230.689689)
			(xy 384.930142 -230.714296) (xy 385.259084 -230.714296) (xy 385.263044 -230.665242) (xy 385.274821 -230.617458)
			(xy 385.294112 -230.572182) (xy 385.320415 -230.530586) (xy 385.35305 -230.493749) (xy 385.391171 -230.462624)
			(xy 385.433792 -230.438017) (xy 385.479808 -230.420565) (xy 385.528027 -230.410721) (xy 385.577202 -230.40874)
			(xy 385.626057 -230.414672) (xy 385.673328 -230.428364) (xy 385.71779 -230.449462) (xy 385.758293 -230.477418)
			(xy 385.793786 -230.51151) (xy 385.823351 -230.550854) (xy 385.846222 -230.594431) (xy 385.861806 -230.641112)
			(xy 385.869701 -230.689689) (xy 385.870191 -230.714042) (xy 386.199138 -230.714042) (xy 386.203098 -230.664988)
			(xy 386.214875 -230.617204) (xy 386.234166 -230.571928) (xy 386.260469 -230.530332) (xy 386.293104 -230.493495)
			(xy 386.331225 -230.46237) (xy 386.373846 -230.437763) (xy 386.419862 -230.420311) (xy 386.468081 -230.410467)
			(xy 386.517256 -230.408486) (xy 386.566111 -230.414418) (xy 386.613382 -230.42811) (xy 386.657844 -230.449208)
			(xy 386.698347 -230.477164) (xy 386.73384 -230.511256) (xy 386.763405 -230.5506) (xy 386.786276 -230.594177)
			(xy 386.80186 -230.640858) (xy 386.809755 -230.689435) (xy 386.81025 -230.714042) (xy 386.809755 -230.738649)
			(xy 386.80186 -230.787226) (xy 386.786276 -230.833907) (xy 386.763405 -230.877484) (xy 386.73384 -230.916828)
			(xy 386.698347 -230.95092) (xy 386.657844 -230.978876) (xy 386.613382 -230.999974) (xy 386.566111 -231.013666)
			(xy 386.517256 -231.019598) (xy 386.468081 -231.017617) (xy 386.419862 -231.007773) (xy 386.373846 -230.990321)
			(xy 386.331225 -230.965714) (xy 386.293104 -230.934589) (xy 386.260469 -230.897752) (xy 386.234166 -230.856156)
			(xy 386.214875 -230.81088) (xy 386.203098 -230.763096) (xy 386.199138 -230.714042) (xy 385.870191 -230.714042)
			(xy 385.870196 -230.714296) (xy 385.869701 -230.738903) (xy 385.861806 -230.78748) (xy 385.846222 -230.834161)
			(xy 385.823351 -230.877738) (xy 385.793786 -230.917082) (xy 385.758293 -230.951174) (xy 385.71779 -230.97913)
			(xy 385.673328 -231.000228) (xy 385.626057 -231.01392) (xy 385.577202 -231.019852) (xy 385.528027 -231.017871)
			(xy 385.479808 -231.008027) (xy 385.433792 -230.990575) (xy 385.391171 -230.965968) (xy 385.35305 -230.934843)
			(xy 385.320415 -230.898006) (xy 385.294112 -230.85641) (xy 385.274821 -230.811134) (xy 385.263044 -230.76335)
			(xy 385.259084 -230.714296) (xy 384.930142 -230.714296) (xy 384.929647 -230.738903) (xy 384.921752 -230.78748)
			(xy 384.906168 -230.834161) (xy 384.883297 -230.877738) (xy 384.853732 -230.917082) (xy 384.818239 -230.951174)
			(xy 384.777736 -230.97913) (xy 384.733274 -231.000228) (xy 384.686003 -231.01392) (xy 384.637148 -231.019852)
			(xy 384.587973 -231.017871) (xy 384.539754 -231.008027) (xy 384.493738 -230.990575) (xy 384.451117 -230.965968)
			(xy 384.412996 -230.934843) (xy 384.380361 -230.898006) (xy 384.354058 -230.85641) (xy 384.334767 -230.811134)
			(xy 384.32299 -230.76335) (xy 384.31903 -230.714296) (xy 383.990088 -230.714296) (xy 383.989593 -230.738903)
			(xy 383.981698 -230.78748) (xy 383.966114 -230.834161) (xy 383.943243 -230.877738) (xy 383.913678 -230.917082)
			(xy 383.878185 -230.951174) (xy 383.837682 -230.97913) (xy 383.79322 -231.000228) (xy 383.745949 -231.01392)
			(xy 383.697094 -231.019852) (xy 383.647919 -231.017871) (xy 383.5997 -231.008027) (xy 383.553684 -230.990575)
			(xy 383.511063 -230.965968) (xy 383.472942 -230.934843) (xy 383.440307 -230.898006) (xy 383.414004 -230.85641)
			(xy 383.394713 -230.811134) (xy 383.382936 -230.76335) (xy 383.378976 -230.714296) (xy 383.050034 -230.714296)
			(xy 383.049539 -230.738903) (xy 383.041644 -230.78748) (xy 383.02606 -230.834161) (xy 383.003189 -230.877738)
			(xy 382.973624 -230.917082) (xy 382.938131 -230.951174) (xy 382.897628 -230.97913) (xy 382.853166 -231.000228)
			(xy 382.805895 -231.01392) (xy 382.75704 -231.019852) (xy 382.707865 -231.017871) (xy 382.659646 -231.008027)
			(xy 382.61363 -230.990575) (xy 382.571009 -230.965968) (xy 382.532888 -230.934843) (xy 382.500253 -230.898006)
			(xy 382.47395 -230.85641) (xy 382.454659 -230.811134) (xy 382.442882 -230.76335) (xy 382.438922 -230.714296)
			(xy 382.110229 -230.714296) (xy 382.109739 -230.738649) (xy 382.101844 -230.787226) (xy 382.08626 -230.833907)
			(xy 382.063389 -230.877484) (xy 382.033824 -230.916828) (xy 381.998331 -230.95092) (xy 381.957828 -230.978876)
			(xy 381.913366 -230.999974) (xy 381.866095 -231.013666) (xy 381.81724 -231.019598) (xy 381.768065 -231.017617)
			(xy 381.719846 -231.007773) (xy 381.67383 -230.990321) (xy 381.631209 -230.965714) (xy 381.593088 -230.934589)
			(xy 381.560453 -230.897752) (xy 381.53415 -230.856156) (xy 381.514859 -230.81088) (xy 381.503082 -230.763096)
			(xy 381.499122 -230.714042) (xy 381.180589 -230.714042) (xy 381.180594 -230.714296) (xy 381.180082 -230.739742)
			(xy 381.171918 -230.789976) (xy 381.155802 -230.83825) (xy 381.132151 -230.883313) (xy 381.101578 -230.923999)
			(xy 381.064874 -230.959254) (xy 381.02299 -230.988164) (xy 380.977011 -231.009981) (xy 380.928127 -231.024141)
			(xy 380.877606 -231.030275) (xy 380.826754 -231.028226) (xy 380.77689 -231.018046) (xy 380.729304 -230.999999)
			(xy 380.68523 -230.974553) (xy 380.645808 -230.942366) (xy 380.61206 -230.904272) (xy 380.584859 -230.861258)
			(xy 380.564911 -230.814438) (xy 380.552732 -230.765024) (xy 380.548637 -230.714296) (xy 380.230126 -230.714296)
			(xy 380.229631 -230.738903) (xy 380.221736 -230.78748) (xy 380.206152 -230.834161) (xy 380.183281 -230.877738)
			(xy 380.153716 -230.917082) (xy 380.118223 -230.951174) (xy 380.07772 -230.97913) (xy 380.033258 -231.000228)
			(xy 379.985987 -231.01392) (xy 379.937132 -231.019852) (xy 379.887957 -231.017871) (xy 379.839738 -231.008027)
			(xy 379.793722 -230.990575) (xy 379.751101 -230.965968) (xy 379.71298 -230.934843) (xy 379.680345 -230.898006)
			(xy 379.654042 -230.85641) (xy 379.634751 -230.811134) (xy 379.622974 -230.76335) (xy 379.619014 -230.714296)
			(xy 379.300486 -230.714296) (xy 379.299974 -230.739742) (xy 379.29181 -230.789976) (xy 379.275694 -230.83825)
			(xy 379.252043 -230.883313) (xy 379.22147 -230.923999) (xy 379.184766 -230.959254) (xy 379.142882 -230.988164)
			(xy 379.096903 -231.009981) (xy 379.048019 -231.024141) (xy 378.997498 -231.030275) (xy 378.946646 -231.028226)
			(xy 378.896782 -231.018046) (xy 378.849196 -230.999999) (xy 378.805122 -230.974553) (xy 378.7657 -230.942366)
			(xy 378.731952 -230.904272) (xy 378.704751 -230.861258) (xy 378.684803 -230.814438) (xy 378.672624 -230.765024)
			(xy 378.668529 -230.714296) (xy 378.350018 -230.714296) (xy 378.349523 -230.738903) (xy 378.341628 -230.78748)
			(xy 378.326044 -230.834161) (xy 378.303173 -230.877738) (xy 378.273608 -230.917082) (xy 378.238115 -230.951174)
			(xy 378.197612 -230.97913) (xy 378.15315 -231.000228) (xy 378.105879 -231.01392) (xy 378.057024 -231.019852)
			(xy 378.007849 -231.017871) (xy 377.95963 -231.008027) (xy 377.913614 -230.990575) (xy 377.870993 -230.965968)
			(xy 377.832872 -230.934843) (xy 377.800237 -230.898006) (xy 377.773934 -230.85641) (xy 377.754643 -230.811134)
			(xy 377.742866 -230.76335) (xy 377.738906 -230.714296) (xy 377.420632 -230.714296) (xy 377.42012 -230.739742)
			(xy 377.411956 -230.789976) (xy 377.39584 -230.83825) (xy 377.372189 -230.883313) (xy 377.341616 -230.923999)
			(xy 377.304912 -230.959254) (xy 377.263028 -230.988164) (xy 377.217049 -231.009981) (xy 377.168165 -231.024141)
			(xy 377.117644 -231.030275) (xy 377.066792 -231.028226) (xy 377.016928 -231.018046) (xy 376.969342 -230.999999)
			(xy 376.925268 -230.974553) (xy 376.885846 -230.942366) (xy 376.852098 -230.904272) (xy 376.824897 -230.861258)
			(xy 376.804949 -230.814438) (xy 376.79277 -230.765024) (xy 376.788675 -230.714296) (xy 376.480578 -230.714296)
			(xy 376.480066 -230.739742) (xy 376.471902 -230.789976) (xy 376.455786 -230.83825) (xy 376.432135 -230.883313)
			(xy 376.401562 -230.923999) (xy 376.364858 -230.959254) (xy 376.322974 -230.988164) (xy 376.276995 -231.009981)
			(xy 376.228111 -231.024141) (xy 376.17759 -231.030275) (xy 376.126738 -231.028226) (xy 376.076874 -231.018046)
			(xy 376.029288 -230.999999) (xy 375.985214 -230.974553) (xy 375.945792 -230.942366) (xy 375.912044 -230.904272)
			(xy 375.884843 -230.861258) (xy 375.864895 -230.814438) (xy 375.852716 -230.765024) (xy 375.848621 -230.714296)
			(xy 375.53011 -230.714296) (xy 375.529615 -230.738903) (xy 375.52172 -230.78748) (xy 375.506136 -230.834161)
			(xy 375.483265 -230.877738) (xy 375.4537 -230.917082) (xy 375.418207 -230.951174) (xy 375.377704 -230.97913)
			(xy 375.333242 -231.000228) (xy 375.285971 -231.01392) (xy 375.237116 -231.019852) (xy 375.187941 -231.017871)
			(xy 375.139722 -231.008027) (xy 375.093706 -230.990575) (xy 375.051085 -230.965968) (xy 375.012964 -230.934843)
			(xy 374.980329 -230.898006) (xy 374.954026 -230.85641) (xy 374.934735 -230.811134) (xy 374.922958 -230.76335)
			(xy 374.918998 -230.714296) (xy 374.590577 -230.714296) (xy 374.590577 -230.714299) (xy 374.586457 -230.764336)
			(xy 374.574207 -230.813024) (xy 374.554157 -230.859053) (xy 374.526848 -230.901182) (xy 374.493016 -230.938276)
			(xy 374.453571 -230.969336) (xy 374.409576 -230.993525) (xy 374.362217 -231.010192) (xy 374.33758 -231.015032)
			(xy 374.329706 -231.016556) (xy 374.307608 -231.02824) (xy 374.303878 -231.030336) (xy 374.297113 -231.035572)
			(xy 374.294146 -231.038654) (xy 374.279922 -231.054148) (xy 374.273737 -231.061406) (xy 374.266823 -231.079162)
			(xy 374.26646 -231.088692) (xy 374.26646 -231.524048) (xy 374.449098 -231.524048) (xy 374.453058 -231.474994)
			(xy 374.464835 -231.42721) (xy 374.484126 -231.381934) (xy 374.510429 -231.340338) (xy 374.543064 -231.303501)
			(xy 374.581185 -231.272376) (xy 374.623806 -231.247769) (xy 374.669822 -231.230317) (xy 374.718041 -231.220473)
			(xy 374.767216 -231.218492) (xy 374.816071 -231.224424) (xy 374.863342 -231.238116) (xy 374.907804 -231.259214)
			(xy 374.948307 -231.28717) (xy 374.9838 -231.321262) (xy 375.013365 -231.360606) (xy 375.036236 -231.404183)
			(xy 375.05182 -231.450864) (xy 375.059715 -231.499441) (xy 375.06021 -231.524048) (xy 375.378467 -231.524048)
			(xy 375.382562 -231.47332) (xy 375.394741 -231.423906) (xy 375.414689 -231.377086) (xy 375.44189 -231.334072)
			(xy 375.475638 -231.295978) (xy 375.51506 -231.263791) (xy 375.559134 -231.238345) (xy 375.60672 -231.220298)
			(xy 375.656584 -231.210118) (xy 375.707436 -231.208069) (xy 375.757957 -231.214203) (xy 375.806841 -231.228363)
			(xy 375.85282 -231.25018) (xy 375.894704 -231.27909) (xy 375.931408 -231.314345) (xy 375.961981 -231.355031)
			(xy 375.985632 -231.400094) (xy 376.001748 -231.448368) (xy 376.009912 -231.498602) (xy 376.010424 -231.524048)
			(xy 376.328952 -231.524048) (xy 376.332912 -231.474994) (xy 376.344689 -231.42721) (xy 376.36398 -231.381934)
			(xy 376.390283 -231.340338) (xy 376.422918 -231.303501) (xy 376.461039 -231.272376) (xy 376.50366 -231.247769)
			(xy 376.549676 -231.230317) (xy 376.597895 -231.220473) (xy 376.64707 -231.218492) (xy 376.695925 -231.224424)
			(xy 376.743196 -231.238116) (xy 376.787658 -231.259214) (xy 376.828161 -231.28717) (xy 376.863654 -231.321262)
			(xy 376.893219 -231.360606) (xy 376.91609 -231.404183) (xy 376.931674 -231.450864) (xy 376.939569 -231.499441)
			(xy 376.940064 -231.524048) (xy 377.258575 -231.524048) (xy 377.26267 -231.47332) (xy 377.274849 -231.423906)
			(xy 377.294797 -231.377086) (xy 377.321998 -231.334072) (xy 377.355746 -231.295978) (xy 377.395168 -231.263791)
			(xy 377.439242 -231.238345) (xy 377.486828 -231.220298) (xy 377.536692 -231.210118) (xy 377.587544 -231.208069)
			(xy 377.638065 -231.214203) (xy 377.686949 -231.228363) (xy 377.732928 -231.25018) (xy 377.774812 -231.27909)
			(xy 377.811516 -231.314345) (xy 377.842089 -231.355031) (xy 377.86574 -231.400094) (xy 377.881856 -231.448368)
			(xy 377.89002 -231.498602) (xy 377.890532 -231.524048) (xy 378.20906 -231.524048) (xy 378.21302 -231.474994)
			(xy 378.224797 -231.42721) (xy 378.244088 -231.381934) (xy 378.270391 -231.340338) (xy 378.303026 -231.303501)
			(xy 378.341147 -231.272376) (xy 378.383768 -231.247769) (xy 378.429784 -231.230317) (xy 378.478003 -231.220473)
			(xy 378.527178 -231.218492) (xy 378.576033 -231.224424) (xy 378.623304 -231.238116) (xy 378.667766 -231.259214)
			(xy 378.708269 -231.28717) (xy 378.743762 -231.321262) (xy 378.773327 -231.360606) (xy 378.796198 -231.404183)
			(xy 378.811782 -231.450864) (xy 378.819677 -231.499441) (xy 378.820172 -231.524048) (xy 379.138683 -231.524048)
			(xy 379.142778 -231.47332) (xy 379.154957 -231.423906) (xy 379.174905 -231.377086) (xy 379.202106 -231.334072)
			(xy 379.235854 -231.295978) (xy 379.275276 -231.263791) (xy 379.31935 -231.238345) (xy 379.366936 -231.220298)
			(xy 379.4168 -231.210118) (xy 379.467652 -231.208069) (xy 379.518173 -231.214203) (xy 379.567057 -231.228363)
			(xy 379.613036 -231.25018) (xy 379.65492 -231.27909) (xy 379.691624 -231.314345) (xy 379.722197 -231.355031)
			(xy 379.745848 -231.400094) (xy 379.761964 -231.448368) (xy 379.770128 -231.498602) (xy 379.77064 -231.524048)
			(xy 380.078483 -231.524048) (xy 380.082578 -231.47332) (xy 380.094757 -231.423906) (xy 380.114705 -231.377086)
			(xy 380.141906 -231.334072) (xy 380.175654 -231.295978) (xy 380.215076 -231.263791) (xy 380.25915 -231.238345)
			(xy 380.306736 -231.220298) (xy 380.3566 -231.210118) (xy 380.407452 -231.208069) (xy 380.457973 -231.214203)
			(xy 380.506857 -231.228363) (xy 380.552836 -231.25018) (xy 380.59472 -231.27909) (xy 380.631424 -231.314345)
			(xy 380.661997 -231.355031) (xy 380.685648 -231.400094) (xy 380.701764 -231.448368) (xy 380.709928 -231.498602)
			(xy 380.71044 -231.524048) (xy 381.028968 -231.524048) (xy 381.032928 -231.474994) (xy 381.044705 -231.42721)
			(xy 381.063996 -231.381934) (xy 381.090299 -231.340338) (xy 381.122934 -231.303501) (xy 381.161055 -231.272376)
			(xy 381.203676 -231.247769) (xy 381.249692 -231.230317) (xy 381.297911 -231.220473) (xy 381.347086 -231.218492)
			(xy 381.395941 -231.224424) (xy 381.443212 -231.238116) (xy 381.487674 -231.259214) (xy 381.528177 -231.28717)
			(xy 381.56367 -231.321262) (xy 381.593235 -231.360606) (xy 381.616106 -231.404183) (xy 381.63169 -231.450864)
			(xy 381.639585 -231.499441) (xy 381.64008 -231.524048) (xy 381.969022 -231.524048) (xy 381.972982 -231.474994)
			(xy 381.984759 -231.42721) (xy 382.00405 -231.381934) (xy 382.030353 -231.340338) (xy 382.062988 -231.303501)
			(xy 382.101109 -231.272376) (xy 382.14373 -231.247769) (xy 382.189746 -231.230317) (xy 382.237965 -231.220473)
			(xy 382.28714 -231.218492) (xy 382.335995 -231.224424) (xy 382.383266 -231.238116) (xy 382.427728 -231.259214)
			(xy 382.468231 -231.28717) (xy 382.503724 -231.321262) (xy 382.533289 -231.360606) (xy 382.55616 -231.404183)
			(xy 382.571744 -231.450864) (xy 382.579639 -231.499441) (xy 382.580134 -231.524048) (xy 382.909076 -231.524048)
			(xy 382.913036 -231.474994) (xy 382.924813 -231.42721) (xy 382.944104 -231.381934) (xy 382.970407 -231.340338)
			(xy 383.003042 -231.303501) (xy 383.041163 -231.272376) (xy 383.083784 -231.247769) (xy 383.1298 -231.230317)
			(xy 383.178019 -231.220473) (xy 383.227194 -231.218492) (xy 383.276049 -231.224424) (xy 383.32332 -231.238116)
			(xy 383.367782 -231.259214) (xy 383.408285 -231.28717) (xy 383.443778 -231.321262) (xy 383.473343 -231.360606)
			(xy 383.496214 -231.404183) (xy 383.511798 -231.450864) (xy 383.519693 -231.499441) (xy 383.520188 -231.524048)
			(xy 383.84913 -231.524048) (xy 383.85309 -231.474994) (xy 383.864867 -231.42721) (xy 383.884158 -231.381934)
			(xy 383.910461 -231.340338) (xy 383.943096 -231.303501) (xy 383.981217 -231.272376) (xy 384.023838 -231.247769)
			(xy 384.069854 -231.230317) (xy 384.118073 -231.220473) (xy 384.167248 -231.218492) (xy 384.216103 -231.224424)
			(xy 384.263374 -231.238116) (xy 384.307836 -231.259214) (xy 384.348339 -231.28717) (xy 384.383832 -231.321262)
			(xy 384.413397 -231.360606) (xy 384.436268 -231.404183) (xy 384.451852 -231.450864) (xy 384.459747 -231.499441)
			(xy 384.460242 -231.524048) (xy 384.78893 -231.524048) (xy 384.79289 -231.474994) (xy 384.804667 -231.42721)
			(xy 384.823958 -231.381934) (xy 384.850261 -231.340338) (xy 384.882896 -231.303501) (xy 384.921017 -231.272376)
			(xy 384.963638 -231.247769) (xy 385.009654 -231.230317) (xy 385.057873 -231.220473) (xy 385.107048 -231.218492)
			(xy 385.155903 -231.224424) (xy 385.203174 -231.238116) (xy 385.247636 -231.259214) (xy 385.288139 -231.28717)
			(xy 385.323632 -231.321262) (xy 385.353197 -231.360606) (xy 385.376068 -231.404183) (xy 385.391652 -231.450864)
			(xy 385.399547 -231.499441) (xy 385.400042 -231.524048) (xy 385.728984 -231.524048) (xy 385.732944 -231.474994)
			(xy 385.744721 -231.42721) (xy 385.764012 -231.381934) (xy 385.790315 -231.340338) (xy 385.82295 -231.303501)
			(xy 385.861071 -231.272376) (xy 385.903692 -231.247769) (xy 385.949708 -231.230317) (xy 385.997927 -231.220473)
			(xy 386.047102 -231.218492) (xy 386.095957 -231.224424) (xy 386.143228 -231.238116) (xy 386.18769 -231.259214)
			(xy 386.228193 -231.28717) (xy 386.263686 -231.321262) (xy 386.293251 -231.360606) (xy 386.316122 -231.404183)
			(xy 386.331706 -231.450864) (xy 386.339601 -231.499441) (xy 386.340096 -231.524048) (xy 386.669038 -231.524048)
			(xy 386.672998 -231.474994) (xy 386.684775 -231.42721) (xy 386.704066 -231.381934) (xy 386.730369 -231.340338)
			(xy 386.763004 -231.303501) (xy 386.801125 -231.272376) (xy 386.843746 -231.247769) (xy 386.889762 -231.230317)
			(xy 386.937981 -231.220473) (xy 386.987156 -231.218492) (xy 387.036011 -231.224424) (xy 387.083282 -231.238116)
			(xy 387.127744 -231.259214) (xy 387.168247 -231.28717) (xy 387.20374 -231.321262) (xy 387.233305 -231.360606)
			(xy 387.256176 -231.404183) (xy 387.27176 -231.450864) (xy 387.279655 -231.499441) (xy 387.28015 -231.524048)
			(xy 387.279655 -231.548655) (xy 387.27176 -231.597232) (xy 387.256176 -231.643913) (xy 387.233305 -231.68749)
			(xy 387.20374 -231.726834) (xy 387.168247 -231.760926) (xy 387.127744 -231.788882) (xy 387.083282 -231.80998)
			(xy 387.036011 -231.823672) (xy 386.987156 -231.829604) (xy 386.937981 -231.827623) (xy 386.889762 -231.817779)
			(xy 386.843746 -231.800327) (xy 386.801125 -231.77572) (xy 386.763004 -231.744595) (xy 386.730369 -231.707758)
			(xy 386.704066 -231.666162) (xy 386.684775 -231.620886) (xy 386.672998 -231.573102) (xy 386.669038 -231.524048)
			(xy 386.340096 -231.524048) (xy 386.339601 -231.548655) (xy 386.331706 -231.597232) (xy 386.316122 -231.643913)
			(xy 386.293251 -231.68749) (xy 386.263686 -231.726834) (xy 386.228193 -231.760926) (xy 386.18769 -231.788882)
			(xy 386.143228 -231.80998) (xy 386.095957 -231.823672) (xy 386.047102 -231.829604) (xy 385.997927 -231.827623)
			(xy 385.949708 -231.817779) (xy 385.903692 -231.800327) (xy 385.861071 -231.77572) (xy 385.82295 -231.744595)
			(xy 385.790315 -231.707758) (xy 385.764012 -231.666162) (xy 385.744721 -231.620886) (xy 385.732944 -231.573102)
			(xy 385.728984 -231.524048) (xy 385.400042 -231.524048) (xy 385.399547 -231.548655) (xy 385.391652 -231.597232)
			(xy 385.376068 -231.643913) (xy 385.353197 -231.68749) (xy 385.323632 -231.726834) (xy 385.288139 -231.760926)
			(xy 385.247636 -231.788882) (xy 385.203174 -231.80998) (xy 385.155903 -231.823672) (xy 385.107048 -231.829604)
			(xy 385.057873 -231.827623) (xy 385.009654 -231.817779) (xy 384.963638 -231.800327) (xy 384.921017 -231.77572)
			(xy 384.882896 -231.744595) (xy 384.850261 -231.707758) (xy 384.823958 -231.666162) (xy 384.804667 -231.620886)
			(xy 384.79289 -231.573102) (xy 384.78893 -231.524048) (xy 384.460242 -231.524048) (xy 384.459747 -231.548655)
			(xy 384.451852 -231.597232) (xy 384.436268 -231.643913) (xy 384.413397 -231.68749) (xy 384.383832 -231.726834)
			(xy 384.348339 -231.760926) (xy 384.307836 -231.788882) (xy 384.263374 -231.80998) (xy 384.216103 -231.823672)
			(xy 384.167248 -231.829604) (xy 384.118073 -231.827623) (xy 384.069854 -231.817779) (xy 384.023838 -231.800327)
			(xy 383.981217 -231.77572) (xy 383.943096 -231.744595) (xy 383.910461 -231.707758) (xy 383.884158 -231.666162)
			(xy 383.864867 -231.620886) (xy 383.85309 -231.573102) (xy 383.84913 -231.524048) (xy 383.520188 -231.524048)
			(xy 383.519693 -231.548655) (xy 383.511798 -231.597232) (xy 383.496214 -231.643913) (xy 383.473343 -231.68749)
			(xy 383.443778 -231.726834) (xy 383.408285 -231.760926) (xy 383.367782 -231.788882) (xy 383.32332 -231.80998)
			(xy 383.276049 -231.823672) (xy 383.227194 -231.829604) (xy 383.178019 -231.827623) (xy 383.1298 -231.817779)
			(xy 383.083784 -231.800327) (xy 383.041163 -231.77572) (xy 383.003042 -231.744595) (xy 382.970407 -231.707758)
			(xy 382.944104 -231.666162) (xy 382.924813 -231.620886) (xy 382.913036 -231.573102) (xy 382.909076 -231.524048)
			(xy 382.580134 -231.524048) (xy 382.579639 -231.548655) (xy 382.571744 -231.597232) (xy 382.55616 -231.643913)
			(xy 382.533289 -231.68749) (xy 382.503724 -231.726834) (xy 382.468231 -231.760926) (xy 382.427728 -231.788882)
			(xy 382.383266 -231.80998) (xy 382.335995 -231.823672) (xy 382.28714 -231.829604) (xy 382.237965 -231.827623)
			(xy 382.189746 -231.817779) (xy 382.14373 -231.800327) (xy 382.101109 -231.77572) (xy 382.062988 -231.744595)
			(xy 382.030353 -231.707758) (xy 382.00405 -231.666162) (xy 381.984759 -231.620886) (xy 381.972982 -231.573102)
			(xy 381.969022 -231.524048) (xy 381.64008 -231.524048) (xy 381.639585 -231.548655) (xy 381.63169 -231.597232)
			(xy 381.616106 -231.643913) (xy 381.593235 -231.68749) (xy 381.56367 -231.726834) (xy 381.528177 -231.760926)
			(xy 381.487674 -231.788882) (xy 381.443212 -231.80998) (xy 381.395941 -231.823672) (xy 381.347086 -231.829604)
			(xy 381.297911 -231.827623) (xy 381.249692 -231.817779) (xy 381.203676 -231.800327) (xy 381.161055 -231.77572)
			(xy 381.122934 -231.744595) (xy 381.090299 -231.707758) (xy 381.063996 -231.666162) (xy 381.044705 -231.620886)
			(xy 381.032928 -231.573102) (xy 381.028968 -231.524048) (xy 380.71044 -231.524048) (xy 380.709928 -231.549494)
			(xy 380.701764 -231.599728) (xy 380.685648 -231.648002) (xy 380.661997 -231.693065) (xy 380.631424 -231.733751)
			(xy 380.59472 -231.769006) (xy 380.552836 -231.797916) (xy 380.506857 -231.819733) (xy 380.457973 -231.833893)
			(xy 380.407452 -231.840027) (xy 380.3566 -231.837978) (xy 380.306736 -231.827798) (xy 380.25915 -231.809751)
			(xy 380.215076 -231.784305) (xy 380.175654 -231.752118) (xy 380.141906 -231.714024) (xy 380.114705 -231.67101)
			(xy 380.094757 -231.62419) (xy 380.082578 -231.574776) (xy 380.078483 -231.524048) (xy 379.77064 -231.524048)
			(xy 379.770128 -231.549494) (xy 379.761964 -231.599728) (xy 379.745848 -231.648002) (xy 379.722197 -231.693065)
			(xy 379.691624 -231.733751) (xy 379.65492 -231.769006) (xy 379.613036 -231.797916) (xy 379.567057 -231.819733)
			(xy 379.518173 -231.833893) (xy 379.467652 -231.840027) (xy 379.4168 -231.837978) (xy 379.366936 -231.827798)
			(xy 379.31935 -231.809751) (xy 379.275276 -231.784305) (xy 379.235854 -231.752118) (xy 379.202106 -231.714024)
			(xy 379.174905 -231.67101) (xy 379.154957 -231.62419) (xy 379.142778 -231.574776) (xy 379.138683 -231.524048)
			(xy 378.820172 -231.524048) (xy 378.819677 -231.548655) (xy 378.811782 -231.597232) (xy 378.796198 -231.643913)
			(xy 378.773327 -231.68749) (xy 378.743762 -231.726834) (xy 378.708269 -231.760926) (xy 378.667766 -231.788882)
			(xy 378.623304 -231.80998) (xy 378.576033 -231.823672) (xy 378.527178 -231.829604) (xy 378.478003 -231.827623)
			(xy 378.429784 -231.817779) (xy 378.383768 -231.800327) (xy 378.341147 -231.77572) (xy 378.303026 -231.744595)
			(xy 378.270391 -231.707758) (xy 378.244088 -231.666162) (xy 378.224797 -231.620886) (xy 378.21302 -231.573102)
			(xy 378.20906 -231.524048) (xy 377.890532 -231.524048) (xy 377.89002 -231.549494) (xy 377.881856 -231.599728)
			(xy 377.86574 -231.648002) (xy 377.842089 -231.693065) (xy 377.811516 -231.733751) (xy 377.774812 -231.769006)
			(xy 377.732928 -231.797916) (xy 377.686949 -231.819733) (xy 377.638065 -231.833893) (xy 377.587544 -231.840027)
			(xy 377.536692 -231.837978) (xy 377.486828 -231.827798) (xy 377.439242 -231.809751) (xy 377.395168 -231.784305)
			(xy 377.355746 -231.752118) (xy 377.321998 -231.714024) (xy 377.294797 -231.67101) (xy 377.274849 -231.62419)
			(xy 377.26267 -231.574776) (xy 377.258575 -231.524048) (xy 376.940064 -231.524048) (xy 376.939569 -231.548655)
			(xy 376.931674 -231.597232) (xy 376.91609 -231.643913) (xy 376.893219 -231.68749) (xy 376.863654 -231.726834)
			(xy 376.828161 -231.760926) (xy 376.787658 -231.788882) (xy 376.743196 -231.80998) (xy 376.695925 -231.823672)
			(xy 376.64707 -231.829604) (xy 376.597895 -231.827623) (xy 376.549676 -231.817779) (xy 376.50366 -231.800327)
			(xy 376.461039 -231.77572) (xy 376.422918 -231.744595) (xy 376.390283 -231.707758) (xy 376.36398 -231.666162)
			(xy 376.344689 -231.620886) (xy 376.332912 -231.573102) (xy 376.328952 -231.524048) (xy 376.010424 -231.524048)
			(xy 376.009912 -231.549494) (xy 376.001748 -231.599728) (xy 375.985632 -231.648002) (xy 375.961981 -231.693065)
			(xy 375.931408 -231.733751) (xy 375.894704 -231.769006) (xy 375.85282 -231.797916) (xy 375.806841 -231.819733)
			(xy 375.757957 -231.833893) (xy 375.707436 -231.840027) (xy 375.656584 -231.837978) (xy 375.60672 -231.827798)
			(xy 375.559134 -231.809751) (xy 375.51506 -231.784305) (xy 375.475638 -231.752118) (xy 375.44189 -231.714024)
			(xy 375.414689 -231.67101) (xy 375.394741 -231.62419) (xy 375.382562 -231.574776) (xy 375.378467 -231.524048)
			(xy 375.06021 -231.524048) (xy 375.059715 -231.548655) (xy 375.05182 -231.597232) (xy 375.036236 -231.643913)
			(xy 375.013365 -231.68749) (xy 374.9838 -231.726834) (xy 374.948307 -231.760926) (xy 374.907804 -231.788882)
			(xy 374.863342 -231.80998) (xy 374.816071 -231.823672) (xy 374.767216 -231.829604) (xy 374.718041 -231.827623)
			(xy 374.669822 -231.817779) (xy 374.623806 -231.800327) (xy 374.581185 -231.77572) (xy 374.543064 -231.744595)
			(xy 374.510429 -231.707758) (xy 374.484126 -231.666162) (xy 374.464835 -231.620886) (xy 374.453058 -231.573102)
			(xy 374.449098 -231.524048) (xy 374.26646 -231.524048) (xy 374.26646 -231.959658) (xy 374.266853 -231.969181)
			(xy 374.273764 -231.986929) (xy 374.279922 -231.994202) (xy 374.294146 -232.009696) (xy 374.297098 -232.012795)
			(xy 374.303862 -232.01804) (xy 374.307608 -232.02011) (xy 374.329706 -232.031794) (xy 374.33758 -232.033318)
			(xy 374.362219 -232.038166) (xy 374.409585 -232.054833) (xy 374.453586 -232.079024) (xy 374.493037 -232.110087)
			(xy 374.526876 -232.147186) (xy 374.55419 -232.18932) (xy 374.574243 -232.235354) (xy 374.586496 -232.284049)
			(xy 374.590615 -232.334054) (xy 375.848621 -232.334054) (xy 375.852716 -232.283326) (xy 375.864895 -232.233912)
			(xy 375.884843 -232.187092) (xy 375.912044 -232.144078) (xy 375.945792 -232.105984) (xy 375.985214 -232.073797)
			(xy 376.029288 -232.048351) (xy 376.076874 -232.030304) (xy 376.126738 -232.020124) (xy 376.17759 -232.018075)
			(xy 376.228111 -232.024209) (xy 376.276995 -232.038369) (xy 376.322974 -232.060186) (xy 376.364858 -232.089096)
			(xy 376.401562 -232.124351) (xy 376.432135 -232.165037) (xy 376.455786 -232.2101) (xy 376.471902 -232.258374)
			(xy 376.480066 -232.308608) (xy 376.480578 -232.334054) (xy 376.788675 -232.334054) (xy 376.79277 -232.283326)
			(xy 376.804949 -232.233912) (xy 376.824897 -232.187092) (xy 376.852098 -232.144078) (xy 376.885846 -232.105984)
			(xy 376.925268 -232.073797) (xy 376.969342 -232.048351) (xy 377.016928 -232.030304) (xy 377.066792 -232.020124)
			(xy 377.117644 -232.018075) (xy 377.168165 -232.024209) (xy 377.217049 -232.038369) (xy 377.263028 -232.060186)
			(xy 377.304912 -232.089096) (xy 377.341616 -232.124351) (xy 377.372189 -232.165037) (xy 377.39584 -232.2101)
			(xy 377.411956 -232.258374) (xy 377.42012 -232.308608) (xy 377.420632 -232.334054) (xy 378.668529 -232.334054)
			(xy 378.672624 -232.283326) (xy 378.684803 -232.233912) (xy 378.704751 -232.187092) (xy 378.731952 -232.144078)
			(xy 378.7657 -232.105984) (xy 378.805122 -232.073797) (xy 378.849196 -232.048351) (xy 378.896782 -232.030304)
			(xy 378.946646 -232.020124) (xy 378.997498 -232.018075) (xy 379.048019 -232.024209) (xy 379.096903 -232.038369)
			(xy 379.142882 -232.060186) (xy 379.184766 -232.089096) (xy 379.22147 -232.124351) (xy 379.252043 -232.165037)
			(xy 379.275694 -232.2101) (xy 379.29181 -232.258374) (xy 379.299974 -232.308608) (xy 379.300486 -232.334054)
			(xy 379.619014 -232.334054) (xy 379.622974 -232.285) (xy 379.634751 -232.237216) (xy 379.654042 -232.19194)
			(xy 379.680345 -232.150344) (xy 379.71298 -232.113507) (xy 379.751101 -232.082382) (xy 379.793722 -232.057775)
			(xy 379.839738 -232.040323) (xy 379.887957 -232.030479) (xy 379.937132 -232.028498) (xy 379.985987 -232.03443)
			(xy 380.033258 -232.048122) (xy 380.07772 -232.06922) (xy 380.118223 -232.097176) (xy 380.153716 -232.131268)
			(xy 380.183281 -232.170612) (xy 380.206152 -232.214189) (xy 380.221736 -232.26087) (xy 380.229631 -232.309447)
			(xy 380.230126 -232.334054) (xy 380.548637 -232.334054) (xy 380.552732 -232.283326) (xy 380.564911 -232.233912)
			(xy 380.584859 -232.187092) (xy 380.61206 -232.144078) (xy 380.645808 -232.105984) (xy 380.68523 -232.073797)
			(xy 380.729304 -232.048351) (xy 380.77689 -232.030304) (xy 380.826754 -232.020124) (xy 380.877606 -232.018075)
			(xy 380.928127 -232.024209) (xy 380.977011 -232.038369) (xy 381.02299 -232.060186) (xy 381.064874 -232.089096)
			(xy 381.101578 -232.124351) (xy 381.132151 -232.165037) (xy 381.155802 -232.2101) (xy 381.171918 -232.258374)
			(xy 381.180082 -232.308608) (xy 381.180594 -232.334054) (xy 381.499122 -232.334054) (xy 381.503082 -232.285)
			(xy 381.514859 -232.237216) (xy 381.53415 -232.19194) (xy 381.560453 -232.150344) (xy 381.593088 -232.113507)
			(xy 381.631209 -232.082382) (xy 381.67383 -232.057775) (xy 381.719846 -232.040323) (xy 381.768065 -232.030479)
			(xy 381.81724 -232.028498) (xy 381.866095 -232.03443) (xy 381.913366 -232.048122) (xy 381.957828 -232.06922)
			(xy 381.998331 -232.097176) (xy 382.033824 -232.131268) (xy 382.063389 -232.170612) (xy 382.08626 -232.214189)
			(xy 382.101844 -232.26087) (xy 382.109739 -232.309447) (xy 382.110234 -232.334054) (xy 382.438922 -232.334054)
			(xy 382.442882 -232.285) (xy 382.454659 -232.237216) (xy 382.47395 -232.19194) (xy 382.500253 -232.150344)
			(xy 382.532888 -232.113507) (xy 382.571009 -232.082382) (xy 382.61363 -232.057775) (xy 382.659646 -232.040323)
			(xy 382.707865 -232.030479) (xy 382.75704 -232.028498) (xy 382.805895 -232.03443) (xy 382.853166 -232.048122)
			(xy 382.897628 -232.06922) (xy 382.938131 -232.097176) (xy 382.973624 -232.131268) (xy 383.003189 -232.170612)
			(xy 383.02606 -232.214189) (xy 383.041644 -232.26087) (xy 383.049539 -232.309447) (xy 383.050034 -232.334054)
			(xy 383.378976 -232.334054) (xy 383.382936 -232.285) (xy 383.394713 -232.237216) (xy 383.414004 -232.19194)
			(xy 383.440307 -232.150344) (xy 383.472942 -232.113507) (xy 383.511063 -232.082382) (xy 383.553684 -232.057775)
			(xy 383.5997 -232.040323) (xy 383.647919 -232.030479) (xy 383.697094 -232.028498) (xy 383.745949 -232.03443)
			(xy 383.79322 -232.048122) (xy 383.837682 -232.06922) (xy 383.878185 -232.097176) (xy 383.913678 -232.131268)
			(xy 383.943243 -232.170612) (xy 383.966114 -232.214189) (xy 383.981698 -232.26087) (xy 383.989593 -232.309447)
			(xy 383.990088 -232.334054) (xy 385.259084 -232.334054) (xy 385.263044 -232.285) (xy 385.274821 -232.237216)
			(xy 385.294112 -232.19194) (xy 385.320415 -232.150344) (xy 385.35305 -232.113507) (xy 385.391171 -232.082382)
			(xy 385.433792 -232.057775) (xy 385.479808 -232.040323) (xy 385.528027 -232.030479) (xy 385.577202 -232.028498)
			(xy 385.626057 -232.03443) (xy 385.673328 -232.048122) (xy 385.71779 -232.06922) (xy 385.758293 -232.097176)
			(xy 385.793786 -232.131268) (xy 385.823351 -232.170612) (xy 385.846222 -232.214189) (xy 385.861806 -232.26087)
			(xy 385.869701 -232.309447) (xy 385.870196 -232.334054) (xy 386.199138 -232.334054) (xy 386.203098 -232.285)
			(xy 386.214875 -232.237216) (xy 386.234166 -232.19194) (xy 386.260469 -232.150344) (xy 386.293104 -232.113507)
			(xy 386.331225 -232.082382) (xy 386.373846 -232.057775) (xy 386.419862 -232.040323) (xy 386.468081 -232.030479)
			(xy 386.517256 -232.028498) (xy 386.566111 -232.03443) (xy 386.613382 -232.048122) (xy 386.657844 -232.06922)
			(xy 386.698347 -232.097176) (xy 386.73384 -232.131268) (xy 386.763405 -232.170612) (xy 386.786276 -232.214189)
			(xy 386.80186 -232.26087) (xy 386.809755 -232.309447) (xy 386.81025 -232.334054) (xy 386.809755 -232.358661)
			(xy 386.80186 -232.407238) (xy 386.786276 -232.453919) (xy 386.763405 -232.497496) (xy 386.73384 -232.53684)
			(xy 386.698347 -232.570932) (xy 386.657844 -232.598888) (xy 386.613382 -232.619986) (xy 386.566111 -232.633678)
			(xy 386.517256 -232.63961) (xy 386.468081 -232.637629) (xy 386.419862 -232.627785) (xy 386.373846 -232.610333)
			(xy 386.331225 -232.585726) (xy 386.293104 -232.554601) (xy 386.260469 -232.517764) (xy 386.234166 -232.476168)
			(xy 386.214875 -232.430892) (xy 386.203098 -232.383108) (xy 386.199138 -232.334054) (xy 385.870196 -232.334054)
			(xy 385.869701 -232.358661) (xy 385.861806 -232.407238) (xy 385.846222 -232.453919) (xy 385.823351 -232.497496)
			(xy 385.793786 -232.53684) (xy 385.758293 -232.570932) (xy 385.71779 -232.598888) (xy 385.673328 -232.619986)
			(xy 385.626057 -232.633678) (xy 385.577202 -232.63961) (xy 385.528027 -232.637629) (xy 385.479808 -232.627785)
			(xy 385.433792 -232.610333) (xy 385.391171 -232.585726) (xy 385.35305 -232.554601) (xy 385.320415 -232.517764)
			(xy 385.294112 -232.476168) (xy 385.274821 -232.430892) (xy 385.263044 -232.383108) (xy 385.259084 -232.334054)
			(xy 383.990088 -232.334054) (xy 383.989593 -232.358661) (xy 383.981698 -232.407238) (xy 383.966114 -232.453919)
			(xy 383.943243 -232.497496) (xy 383.913678 -232.53684) (xy 383.878185 -232.570932) (xy 383.837682 -232.598888)
			(xy 383.79322 -232.619986) (xy 383.745949 -232.633678) (xy 383.697094 -232.63961) (xy 383.647919 -232.637629)
			(xy 383.5997 -232.627785) (xy 383.553684 -232.610333) (xy 383.511063 -232.585726) (xy 383.472942 -232.554601)
			(xy 383.440307 -232.517764) (xy 383.414004 -232.476168) (xy 383.394713 -232.430892) (xy 383.382936 -232.383108)
			(xy 383.378976 -232.334054) (xy 383.050034 -232.334054) (xy 383.049539 -232.358661) (xy 383.041644 -232.407238)
			(xy 383.02606 -232.453919) (xy 383.003189 -232.497496) (xy 382.973624 -232.53684) (xy 382.938131 -232.570932)
			(xy 382.897628 -232.598888) (xy 382.853166 -232.619986) (xy 382.805895 -232.633678) (xy 382.75704 -232.63961)
			(xy 382.707865 -232.637629) (xy 382.659646 -232.627785) (xy 382.61363 -232.610333) (xy 382.571009 -232.585726)
			(xy 382.532888 -232.554601) (xy 382.500253 -232.517764) (xy 382.47395 -232.476168) (xy 382.454659 -232.430892)
			(xy 382.442882 -232.383108) (xy 382.438922 -232.334054) (xy 382.110234 -232.334054) (xy 382.109739 -232.358661)
			(xy 382.101844 -232.407238) (xy 382.08626 -232.453919) (xy 382.063389 -232.497496) (xy 382.033824 -232.53684)
			(xy 381.998331 -232.570932) (xy 381.957828 -232.598888) (xy 381.913366 -232.619986) (xy 381.866095 -232.633678)
			(xy 381.81724 -232.63961) (xy 381.768065 -232.637629) (xy 381.719846 -232.627785) (xy 381.67383 -232.610333)
			(xy 381.631209 -232.585726) (xy 381.593088 -232.554601) (xy 381.560453 -232.517764) (xy 381.53415 -232.476168)
			(xy 381.514859 -232.430892) (xy 381.503082 -232.383108) (xy 381.499122 -232.334054) (xy 381.180594 -232.334054)
			(xy 381.180082 -232.3595) (xy 381.171918 -232.409734) (xy 381.155802 -232.458008) (xy 381.132151 -232.503071)
			(xy 381.101578 -232.543757) (xy 381.064874 -232.579012) (xy 381.02299 -232.607922) (xy 380.977011 -232.629739)
			(xy 380.928127 -232.643899) (xy 380.877606 -232.650033) (xy 380.826754 -232.647984) (xy 380.77689 -232.637804)
			(xy 380.729304 -232.619757) (xy 380.68523 -232.594311) (xy 380.645808 -232.562124) (xy 380.61206 -232.52403)
			(xy 380.584859 -232.481016) (xy 380.564911 -232.434196) (xy 380.552732 -232.384782) (xy 380.548637 -232.334054)
			(xy 380.230126 -232.334054) (xy 380.229631 -232.358661) (xy 380.221736 -232.407238) (xy 380.206152 -232.453919)
			(xy 380.183281 -232.497496) (xy 380.153716 -232.53684) (xy 380.118223 -232.570932) (xy 380.07772 -232.598888)
			(xy 380.033258 -232.619986) (xy 379.985987 -232.633678) (xy 379.937132 -232.63961) (xy 379.887957 -232.637629)
			(xy 379.839738 -232.627785) (xy 379.793722 -232.610333) (xy 379.751101 -232.585726) (xy 379.71298 -232.554601)
			(xy 379.680345 -232.517764) (xy 379.654042 -232.476168) (xy 379.634751 -232.430892) (xy 379.622974 -232.383108)
			(xy 379.619014 -232.334054) (xy 379.300486 -232.334054) (xy 379.299974 -232.3595) (xy 379.29181 -232.409734)
			(xy 379.275694 -232.458008) (xy 379.252043 -232.503071) (xy 379.22147 -232.543757) (xy 379.184766 -232.579012)
			(xy 379.142882 -232.607922) (xy 379.096903 -232.629739) (xy 379.048019 -232.643899) (xy 378.997498 -232.650033)
			(xy 378.946646 -232.647984) (xy 378.896782 -232.637804) (xy 378.849196 -232.619757) (xy 378.805122 -232.594311)
			(xy 378.7657 -232.562124) (xy 378.731952 -232.52403) (xy 378.704751 -232.481016) (xy 378.684803 -232.434196)
			(xy 378.672624 -232.384782) (xy 378.668529 -232.334054) (xy 377.420632 -232.334054) (xy 377.42012 -232.3595)
			(xy 377.411956 -232.409734) (xy 377.39584 -232.458008) (xy 377.372189 -232.503071) (xy 377.341616 -232.543757)
			(xy 377.304912 -232.579012) (xy 377.263028 -232.607922) (xy 377.217049 -232.629739) (xy 377.168165 -232.643899)
			(xy 377.117644 -232.650033) (xy 377.066792 -232.647984) (xy 377.016928 -232.637804) (xy 376.969342 -232.619757)
			(xy 376.925268 -232.594311) (xy 376.885846 -232.562124) (xy 376.852098 -232.52403) (xy 376.824897 -232.481016)
			(xy 376.804949 -232.434196) (xy 376.79277 -232.384782) (xy 376.788675 -232.334054) (xy 376.480578 -232.334054)
			(xy 376.480066 -232.3595) (xy 376.471902 -232.409734) (xy 376.455786 -232.458008) (xy 376.432135 -232.503071)
			(xy 376.401562 -232.543757) (xy 376.364858 -232.579012) (xy 376.322974 -232.607922) (xy 376.276995 -232.629739)
			(xy 376.228111 -232.643899) (xy 376.17759 -232.650033) (xy 376.126738 -232.647984) (xy 376.076874 -232.637804)
			(xy 376.029288 -232.619757) (xy 375.985214 -232.594311) (xy 375.945792 -232.562124) (xy 375.912044 -232.52403)
			(xy 375.884843 -232.481016) (xy 375.864895 -232.434196) (xy 375.852716 -232.384782) (xy 375.848621 -232.334054)
			(xy 374.590615 -232.334054) (xy 374.590618 -232.334092) (xy 374.586499 -232.384135) (xy 374.574249 -232.432831)
			(xy 374.554197 -232.478866) (xy 374.526886 -232.521002) (xy 374.493049 -232.558102) (xy 374.453599 -232.589167)
			(xy 374.409599 -232.61336) (xy 374.362235 -232.63003) (xy 374.33758 -232.63479) (xy 374.329706 -232.636314)
			(xy 374.307608 -232.647998) (xy 374.30388 -232.650096) (xy 374.297119 -232.655336) (xy 374.294146 -232.658412)
			(xy 374.279922 -232.673906) (xy 374.273731 -232.681162) (xy 374.266801 -232.698918) (xy 374.26646 -232.70845)
			(xy 374.26646 -233.14406) (xy 374.449098 -233.14406) (xy 374.453058 -233.095006) (xy 374.464835 -233.047222)
			(xy 374.484126 -233.001946) (xy 374.510429 -232.96035) (xy 374.543064 -232.923513) (xy 374.581185 -232.892388)
			(xy 374.623806 -232.867781) (xy 374.669822 -232.850329) (xy 374.718041 -232.840485) (xy 374.767216 -232.838504)
			(xy 374.816071 -232.844436) (xy 374.863342 -232.858128) (xy 374.907804 -232.879226) (xy 374.948307 -232.907182)
			(xy 374.9838 -232.941274) (xy 375.013365 -232.980618) (xy 375.036236 -233.024195) (xy 375.05182 -233.070876)
			(xy 375.059715 -233.119453) (xy 375.06021 -233.14406) (xy 375.378467 -233.14406) (xy 375.382562 -233.093332)
			(xy 375.394741 -233.043918) (xy 375.414689 -232.997098) (xy 375.44189 -232.954084) (xy 375.475638 -232.91599)
			(xy 375.51506 -232.883803) (xy 375.559134 -232.858357) (xy 375.60672 -232.84031) (xy 375.656584 -232.83013)
			(xy 375.707436 -232.828081) (xy 375.757957 -232.834215) (xy 375.806841 -232.848375) (xy 375.85282 -232.870192)
			(xy 375.894704 -232.899102) (xy 375.931408 -232.934357) (xy 375.961981 -232.975043) (xy 375.985632 -233.020106)
			(xy 376.001748 -233.06838) (xy 376.009912 -233.118614) (xy 376.010424 -233.14406) (xy 376.328952 -233.14406)
			(xy 376.332912 -233.095006) (xy 376.344689 -233.047222) (xy 376.36398 -233.001946) (xy 376.390283 -232.96035)
			(xy 376.422918 -232.923513) (xy 376.461039 -232.892388) (xy 376.50366 -232.867781) (xy 376.549676 -232.850329)
			(xy 376.597895 -232.840485) (xy 376.64707 -232.838504) (xy 376.695925 -232.844436) (xy 376.743196 -232.858128)
			(xy 376.787658 -232.879226) (xy 376.828161 -232.907182) (xy 376.863654 -232.941274) (xy 376.893219 -232.980618)
			(xy 376.91609 -233.024195) (xy 376.931674 -233.070876) (xy 376.939569 -233.119453) (xy 376.940064 -233.14406)
			(xy 377.258575 -233.14406) (xy 377.26267 -233.093332) (xy 377.274849 -233.043918) (xy 377.294797 -232.997098)
			(xy 377.321998 -232.954084) (xy 377.355746 -232.91599) (xy 377.395168 -232.883803) (xy 377.439242 -232.858357)
			(xy 377.486828 -232.84031) (xy 377.536692 -232.83013) (xy 377.587544 -232.828081) (xy 377.638065 -232.834215)
			(xy 377.686949 -232.848375) (xy 377.732928 -232.870192) (xy 377.774812 -232.899102) (xy 377.811516 -232.934357)
			(xy 377.842089 -232.975043) (xy 377.86574 -233.020106) (xy 377.881856 -233.06838) (xy 377.89002 -233.118614)
			(xy 377.890532 -233.14406) (xy 378.20906 -233.14406) (xy 378.21302 -233.095006) (xy 378.224797 -233.047222)
			(xy 378.244088 -233.001946) (xy 378.270391 -232.96035) (xy 378.303026 -232.923513) (xy 378.341147 -232.892388)
			(xy 378.383768 -232.867781) (xy 378.429784 -232.850329) (xy 378.478003 -232.840485) (xy 378.527178 -232.838504)
			(xy 378.576033 -232.844436) (xy 378.623304 -232.858128) (xy 378.667766 -232.879226) (xy 378.708269 -232.907182)
			(xy 378.743762 -232.941274) (xy 378.773327 -232.980618) (xy 378.796198 -233.024195) (xy 378.811782 -233.070876)
			(xy 378.819677 -233.119453) (xy 378.820172 -233.14406) (xy 379.138683 -233.14406) (xy 379.142778 -233.093332)
			(xy 379.154957 -233.043918) (xy 379.174905 -232.997098) (xy 379.202106 -232.954084) (xy 379.235854 -232.91599)
			(xy 379.275276 -232.883803) (xy 379.31935 -232.858357) (xy 379.366936 -232.84031) (xy 379.4168 -232.83013)
			(xy 379.467652 -232.828081) (xy 379.518173 -232.834215) (xy 379.567057 -232.848375) (xy 379.613036 -232.870192)
			(xy 379.65492 -232.899102) (xy 379.691624 -232.934357) (xy 379.722197 -232.975043) (xy 379.745848 -233.020106)
			(xy 379.761964 -233.06838) (xy 379.770128 -233.118614) (xy 379.77064 -233.14406) (xy 380.078483 -233.14406)
			(xy 380.082578 -233.093332) (xy 380.094757 -233.043918) (xy 380.114705 -232.997098) (xy 380.141906 -232.954084)
			(xy 380.175654 -232.91599) (xy 380.215076 -232.883803) (xy 380.25915 -232.858357) (xy 380.306736 -232.84031)
			(xy 380.3566 -232.83013) (xy 380.407452 -232.828081) (xy 380.457973 -232.834215) (xy 380.506857 -232.848375)
			(xy 380.552836 -232.870192) (xy 380.59472 -232.899102) (xy 380.631424 -232.934357) (xy 380.661997 -232.975043)
			(xy 380.685648 -233.020106) (xy 380.701764 -233.06838) (xy 380.709928 -233.118614) (xy 380.71044 -233.14406)
			(xy 381.028968 -233.14406) (xy 381.032928 -233.095006) (xy 381.044705 -233.047222) (xy 381.063996 -233.001946)
			(xy 381.090299 -232.96035) (xy 381.122934 -232.923513) (xy 381.161055 -232.892388) (xy 381.203676 -232.867781)
			(xy 381.249692 -232.850329) (xy 381.297911 -232.840485) (xy 381.347086 -232.838504) (xy 381.395941 -232.844436)
			(xy 381.443212 -232.858128) (xy 381.487674 -232.879226) (xy 381.528177 -232.907182) (xy 381.56367 -232.941274)
			(xy 381.593235 -232.980618) (xy 381.616106 -233.024195) (xy 381.63169 -233.070876) (xy 381.639585 -233.119453)
			(xy 381.64008 -233.14406) (xy 381.969022 -233.14406) (xy 381.972982 -233.095006) (xy 381.984759 -233.047222)
			(xy 382.00405 -233.001946) (xy 382.030353 -232.96035) (xy 382.062988 -232.923513) (xy 382.101109 -232.892388)
			(xy 382.14373 -232.867781) (xy 382.189746 -232.850329) (xy 382.237965 -232.840485) (xy 382.28714 -232.838504)
			(xy 382.335995 -232.844436) (xy 382.383266 -232.858128) (xy 382.427728 -232.879226) (xy 382.468231 -232.907182)
			(xy 382.503724 -232.941274) (xy 382.533289 -232.980618) (xy 382.55616 -233.024195) (xy 382.571744 -233.070876)
			(xy 382.579639 -233.119453) (xy 382.580134 -233.14406) (xy 382.909076 -233.14406) (xy 382.913036 -233.095006)
			(xy 382.924813 -233.047222) (xy 382.944104 -233.001946) (xy 382.970407 -232.96035) (xy 383.003042 -232.923513)
			(xy 383.041163 -232.892388) (xy 383.083784 -232.867781) (xy 383.1298 -232.850329) (xy 383.178019 -232.840485)
			(xy 383.227194 -232.838504) (xy 383.276049 -232.844436) (xy 383.32332 -232.858128) (xy 383.367782 -232.879226)
			(xy 383.408285 -232.907182) (xy 383.443778 -232.941274) (xy 383.473343 -232.980618) (xy 383.496214 -233.024195)
			(xy 383.511798 -233.070876) (xy 383.519693 -233.119453) (xy 383.520188 -233.14406) (xy 383.84913 -233.14406)
			(xy 383.85309 -233.095006) (xy 383.864867 -233.047222) (xy 383.884158 -233.001946) (xy 383.910461 -232.96035)
			(xy 383.943096 -232.923513) (xy 383.981217 -232.892388) (xy 384.023838 -232.867781) (xy 384.069854 -232.850329)
			(xy 384.118073 -232.840485) (xy 384.167248 -232.838504) (xy 384.216103 -232.844436) (xy 384.263374 -232.858128)
			(xy 384.307836 -232.879226) (xy 384.348339 -232.907182) (xy 384.383832 -232.941274) (xy 384.413397 -232.980618)
			(xy 384.436268 -233.024195) (xy 384.451852 -233.070876) (xy 384.459747 -233.119453) (xy 384.460242 -233.14406)
			(xy 384.78893 -233.14406) (xy 384.79289 -233.095006) (xy 384.804667 -233.047222) (xy 384.823958 -233.001946)
			(xy 384.850261 -232.96035) (xy 384.882896 -232.923513) (xy 384.921017 -232.892388) (xy 384.963638 -232.867781)
			(xy 385.009654 -232.850329) (xy 385.057873 -232.840485) (xy 385.107048 -232.838504) (xy 385.155903 -232.844436)
			(xy 385.203174 -232.858128) (xy 385.247636 -232.879226) (xy 385.288139 -232.907182) (xy 385.323632 -232.941274)
			(xy 385.353197 -232.980618) (xy 385.376068 -233.024195) (xy 385.391652 -233.070876) (xy 385.399547 -233.119453)
			(xy 385.400042 -233.14406) (xy 385.728984 -233.14406) (xy 385.732944 -233.095006) (xy 385.744721 -233.047222)
			(xy 385.764012 -233.001946) (xy 385.790315 -232.96035) (xy 385.82295 -232.923513) (xy 385.861071 -232.892388)
			(xy 385.903692 -232.867781) (xy 385.949708 -232.850329) (xy 385.997927 -232.840485) (xy 386.047102 -232.838504)
			(xy 386.095957 -232.844436) (xy 386.143228 -232.858128) (xy 386.18769 -232.879226) (xy 386.228193 -232.907182)
			(xy 386.263686 -232.941274) (xy 386.293251 -232.980618) (xy 386.316122 -233.024195) (xy 386.331706 -233.070876)
			(xy 386.339601 -233.119453) (xy 386.340096 -233.14406) (xy 386.669038 -233.14406) (xy 386.672998 -233.095006)
			(xy 386.684775 -233.047222) (xy 386.704066 -233.001946) (xy 386.730369 -232.96035) (xy 386.763004 -232.923513)
			(xy 386.801125 -232.892388) (xy 386.843746 -232.867781) (xy 386.889762 -232.850329) (xy 386.937981 -232.840485)
			(xy 386.987156 -232.838504) (xy 387.036011 -232.844436) (xy 387.083282 -232.858128) (xy 387.127744 -232.879226)
			(xy 387.168247 -232.907182) (xy 387.20374 -232.941274) (xy 387.233305 -232.980618) (xy 387.256176 -233.024195)
			(xy 387.27176 -233.070876) (xy 387.279655 -233.119453) (xy 387.28015 -233.14406) (xy 387.279655 -233.168667)
			(xy 387.27176 -233.217244) (xy 387.256176 -233.263925) (xy 387.233305 -233.307502) (xy 387.20374 -233.346846)
			(xy 387.168247 -233.380938) (xy 387.127744 -233.408894) (xy 387.083282 -233.429992) (xy 387.036011 -233.443684)
			(xy 386.987156 -233.449616) (xy 386.937981 -233.447635) (xy 386.889762 -233.437791) (xy 386.843746 -233.420339)
			(xy 386.801125 -233.395732) (xy 386.763004 -233.364607) (xy 386.730369 -233.32777) (xy 386.704066 -233.286174)
			(xy 386.684775 -233.240898) (xy 386.672998 -233.193114) (xy 386.669038 -233.14406) (xy 386.340096 -233.14406)
			(xy 386.339601 -233.168667) (xy 386.331706 -233.217244) (xy 386.316122 -233.263925) (xy 386.293251 -233.307502)
			(xy 386.263686 -233.346846) (xy 386.228193 -233.380938) (xy 386.18769 -233.408894) (xy 386.143228 -233.429992)
			(xy 386.095957 -233.443684) (xy 386.047102 -233.449616) (xy 385.997927 -233.447635) (xy 385.949708 -233.437791)
			(xy 385.903692 -233.420339) (xy 385.861071 -233.395732) (xy 385.82295 -233.364607) (xy 385.790315 -233.32777)
			(xy 385.764012 -233.286174) (xy 385.744721 -233.240898) (xy 385.732944 -233.193114) (xy 385.728984 -233.14406)
			(xy 385.400042 -233.14406) (xy 385.399547 -233.168667) (xy 385.391652 -233.217244) (xy 385.376068 -233.263925)
			(xy 385.353197 -233.307502) (xy 385.323632 -233.346846) (xy 385.288139 -233.380938) (xy 385.247636 -233.408894)
			(xy 385.203174 -233.429992) (xy 385.155903 -233.443684) (xy 385.107048 -233.449616) (xy 385.057873 -233.447635)
			(xy 385.009654 -233.437791) (xy 384.963638 -233.420339) (xy 384.921017 -233.395732) (xy 384.882896 -233.364607)
			(xy 384.850261 -233.32777) (xy 384.823958 -233.286174) (xy 384.804667 -233.240898) (xy 384.79289 -233.193114)
			(xy 384.78893 -233.14406) (xy 384.460242 -233.14406) (xy 384.459747 -233.168667) (xy 384.451852 -233.217244)
			(xy 384.436268 -233.263925) (xy 384.413397 -233.307502) (xy 384.383832 -233.346846) (xy 384.348339 -233.380938)
			(xy 384.307836 -233.408894) (xy 384.263374 -233.429992) (xy 384.216103 -233.443684) (xy 384.167248 -233.449616)
			(xy 384.118073 -233.447635) (xy 384.069854 -233.437791) (xy 384.023838 -233.420339) (xy 383.981217 -233.395732)
			(xy 383.943096 -233.364607) (xy 383.910461 -233.32777) (xy 383.884158 -233.286174) (xy 383.864867 -233.240898)
			(xy 383.85309 -233.193114) (xy 383.84913 -233.14406) (xy 383.520188 -233.14406) (xy 383.519693 -233.168667)
			(xy 383.511798 -233.217244) (xy 383.496214 -233.263925) (xy 383.473343 -233.307502) (xy 383.443778 -233.346846)
			(xy 383.408285 -233.380938) (xy 383.367782 -233.408894) (xy 383.32332 -233.429992) (xy 383.276049 -233.443684)
			(xy 383.227194 -233.449616) (xy 383.178019 -233.447635) (xy 383.1298 -233.437791) (xy 383.083784 -233.420339)
			(xy 383.041163 -233.395732) (xy 383.003042 -233.364607) (xy 382.970407 -233.32777) (xy 382.944104 -233.286174)
			(xy 382.924813 -233.240898) (xy 382.913036 -233.193114) (xy 382.909076 -233.14406) (xy 382.580134 -233.14406)
			(xy 382.579639 -233.168667) (xy 382.571744 -233.217244) (xy 382.55616 -233.263925) (xy 382.533289 -233.307502)
			(xy 382.503724 -233.346846) (xy 382.468231 -233.380938) (xy 382.427728 -233.408894) (xy 382.383266 -233.429992)
			(xy 382.335995 -233.443684) (xy 382.28714 -233.449616) (xy 382.237965 -233.447635) (xy 382.189746 -233.437791)
			(xy 382.14373 -233.420339) (xy 382.101109 -233.395732) (xy 382.062988 -233.364607) (xy 382.030353 -233.32777)
			(xy 382.00405 -233.286174) (xy 381.984759 -233.240898) (xy 381.972982 -233.193114) (xy 381.969022 -233.14406)
			(xy 381.64008 -233.14406) (xy 381.639585 -233.168667) (xy 381.63169 -233.217244) (xy 381.616106 -233.263925)
			(xy 381.593235 -233.307502) (xy 381.56367 -233.346846) (xy 381.528177 -233.380938) (xy 381.487674 -233.408894)
			(xy 381.443212 -233.429992) (xy 381.395941 -233.443684) (xy 381.347086 -233.449616) (xy 381.297911 -233.447635)
			(xy 381.249692 -233.437791) (xy 381.203676 -233.420339) (xy 381.161055 -233.395732) (xy 381.122934 -233.364607)
			(xy 381.090299 -233.32777) (xy 381.063996 -233.286174) (xy 381.044705 -233.240898) (xy 381.032928 -233.193114)
			(xy 381.028968 -233.14406) (xy 380.71044 -233.14406) (xy 380.709928 -233.169506) (xy 380.701764 -233.21974)
			(xy 380.685648 -233.268014) (xy 380.661997 -233.313077) (xy 380.631424 -233.353763) (xy 380.59472 -233.389018)
			(xy 380.552836 -233.417928) (xy 380.506857 -233.439745) (xy 380.457973 -233.453905) (xy 380.407452 -233.460039)
			(xy 380.3566 -233.45799) (xy 380.306736 -233.44781) (xy 380.25915 -233.429763) (xy 380.215076 -233.404317)
			(xy 380.175654 -233.37213) (xy 380.141906 -233.334036) (xy 380.114705 -233.291022) (xy 380.094757 -233.244202)
			(xy 380.082578 -233.194788) (xy 380.078483 -233.14406) (xy 379.77064 -233.14406) (xy 379.770128 -233.169506)
			(xy 379.761964 -233.21974) (xy 379.745848 -233.268014) (xy 379.722197 -233.313077) (xy 379.691624 -233.353763)
			(xy 379.65492 -233.389018) (xy 379.613036 -233.417928) (xy 379.567057 -233.439745) (xy 379.518173 -233.453905)
			(xy 379.467652 -233.460039) (xy 379.4168 -233.45799) (xy 379.366936 -233.44781) (xy 379.31935 -233.429763)
			(xy 379.275276 -233.404317) (xy 379.235854 -233.37213) (xy 379.202106 -233.334036) (xy 379.174905 -233.291022)
			(xy 379.154957 -233.244202) (xy 379.142778 -233.194788) (xy 379.138683 -233.14406) (xy 378.820172 -233.14406)
			(xy 378.819677 -233.168667) (xy 378.811782 -233.217244) (xy 378.796198 -233.263925) (xy 378.773327 -233.307502)
			(xy 378.743762 -233.346846) (xy 378.708269 -233.380938) (xy 378.667766 -233.408894) (xy 378.623304 -233.429992)
			(xy 378.576033 -233.443684) (xy 378.527178 -233.449616) (xy 378.478003 -233.447635) (xy 378.429784 -233.437791)
			(xy 378.383768 -233.420339) (xy 378.341147 -233.395732) (xy 378.303026 -233.364607) (xy 378.270391 -233.32777)
			(xy 378.244088 -233.286174) (xy 378.224797 -233.240898) (xy 378.21302 -233.193114) (xy 378.20906 -233.14406)
			(xy 377.890532 -233.14406) (xy 377.89002 -233.169506) (xy 377.881856 -233.21974) (xy 377.86574 -233.268014)
			(xy 377.842089 -233.313077) (xy 377.811516 -233.353763) (xy 377.774812 -233.389018) (xy 377.732928 -233.417928)
			(xy 377.686949 -233.439745) (xy 377.638065 -233.453905) (xy 377.587544 -233.460039) (xy 377.536692 -233.45799)
			(xy 377.486828 -233.44781) (xy 377.439242 -233.429763) (xy 377.395168 -233.404317) (xy 377.355746 -233.37213)
			(xy 377.321998 -233.334036) (xy 377.294797 -233.291022) (xy 377.274849 -233.244202) (xy 377.26267 -233.194788)
			(xy 377.258575 -233.14406) (xy 376.940064 -233.14406) (xy 376.939569 -233.168667) (xy 376.931674 -233.217244)
			(xy 376.91609 -233.263925) (xy 376.893219 -233.307502) (xy 376.863654 -233.346846) (xy 376.828161 -233.380938)
			(xy 376.787658 -233.408894) (xy 376.743196 -233.429992) (xy 376.695925 -233.443684) (xy 376.64707 -233.449616)
			(xy 376.597895 -233.447635) (xy 376.549676 -233.437791) (xy 376.50366 -233.420339) (xy 376.461039 -233.395732)
			(xy 376.422918 -233.364607) (xy 376.390283 -233.32777) (xy 376.36398 -233.286174) (xy 376.344689 -233.240898)
			(xy 376.332912 -233.193114) (xy 376.328952 -233.14406) (xy 376.010424 -233.14406) (xy 376.009912 -233.169506)
			(xy 376.001748 -233.21974) (xy 375.985632 -233.268014) (xy 375.961981 -233.313077) (xy 375.931408 -233.353763)
			(xy 375.894704 -233.389018) (xy 375.85282 -233.417928) (xy 375.806841 -233.439745) (xy 375.757957 -233.453905)
			(xy 375.707436 -233.460039) (xy 375.656584 -233.45799) (xy 375.60672 -233.44781) (xy 375.559134 -233.429763)
			(xy 375.51506 -233.404317) (xy 375.475638 -233.37213) (xy 375.44189 -233.334036) (xy 375.414689 -233.291022)
			(xy 375.394741 -233.244202) (xy 375.382562 -233.194788) (xy 375.378467 -233.14406) (xy 375.06021 -233.14406)
			(xy 375.059715 -233.168667) (xy 375.05182 -233.217244) (xy 375.036236 -233.263925) (xy 375.013365 -233.307502)
			(xy 374.9838 -233.346846) (xy 374.948307 -233.380938) (xy 374.907804 -233.408894) (xy 374.863342 -233.429992)
			(xy 374.816071 -233.443684) (xy 374.767216 -233.449616) (xy 374.718041 -233.447635) (xy 374.669822 -233.437791)
			(xy 374.623806 -233.420339) (xy 374.581185 -233.395732) (xy 374.543064 -233.364607) (xy 374.510429 -233.32777)
			(xy 374.484126 -233.286174) (xy 374.464835 -233.240898) (xy 374.453058 -233.193114) (xy 374.449098 -233.14406)
			(xy 374.26646 -233.14406) (xy 374.26646 -233.57967) (xy 374.266855 -233.589192) (xy 374.273769 -233.606937)
			(xy 374.279922 -233.614214) (xy 374.294146 -233.629708) (xy 374.297099 -233.632807) (xy 374.303863 -233.63805)
			(xy 374.307608 -233.640122) (xy 374.329706 -233.651806) (xy 374.33758 -233.65333) (xy 374.362218 -233.658178)
			(xy 374.409582 -233.674845) (xy 374.453581 -233.699035) (xy 374.493031 -233.730097) (xy 374.526868 -233.767194)
			(xy 374.55418 -233.809327) (xy 374.574233 -233.85536) (xy 374.586485 -233.904053) (xy 374.590605 -233.954066)
			(xy 374.918998 -233.954066) (xy 374.922958 -233.905012) (xy 374.934735 -233.857228) (xy 374.954026 -233.811952)
			(xy 374.980329 -233.770356) (xy 375.012964 -233.733519) (xy 375.051085 -233.702394) (xy 375.093706 -233.677787)
			(xy 375.139722 -233.660335) (xy 375.187941 -233.650491) (xy 375.237116 -233.64851) (xy 375.285971 -233.654442)
			(xy 375.333242 -233.668134) (xy 375.377704 -233.689232) (xy 375.418207 -233.717188) (xy 375.4537 -233.75128)
			(xy 375.483265 -233.790624) (xy 375.506136 -233.834201) (xy 375.52172 -233.880882) (xy 375.529615 -233.929459)
			(xy 375.53011 -233.954066) (xy 375.848621 -233.954066) (xy 375.852716 -233.903338) (xy 375.864895 -233.853924)
			(xy 375.884843 -233.807104) (xy 375.912044 -233.76409) (xy 375.945792 -233.725996) (xy 375.985214 -233.693809)
			(xy 376.029288 -233.668363) (xy 376.076874 -233.650316) (xy 376.126738 -233.640136) (xy 376.17759 -233.638087)
			(xy 376.228111 -233.644221) (xy 376.276995 -233.658381) (xy 376.322974 -233.680198) (xy 376.364858 -233.709108)
			(xy 376.401562 -233.744363) (xy 376.432135 -233.785049) (xy 376.455786 -233.830112) (xy 376.471902 -233.878386)
			(xy 376.480066 -233.92862) (xy 376.480578 -233.954066) (xy 376.788675 -233.954066) (xy 376.79277 -233.903338)
			(xy 376.804949 -233.853924) (xy 376.824897 -233.807104) (xy 376.852098 -233.76409) (xy 376.885846 -233.725996)
			(xy 376.925268 -233.693809) (xy 376.969342 -233.668363) (xy 377.016928 -233.650316) (xy 377.066792 -233.640136)
			(xy 377.117644 -233.638087) (xy 377.168165 -233.644221) (xy 377.217049 -233.658381) (xy 377.263028 -233.680198)
			(xy 377.304912 -233.709108) (xy 377.341616 -233.744363) (xy 377.372189 -233.785049) (xy 377.39584 -233.830112)
			(xy 377.411956 -233.878386) (xy 377.42012 -233.92862) (xy 377.420632 -233.954066) (xy 377.738906 -233.954066)
			(xy 377.742866 -233.905012) (xy 377.754643 -233.857228) (xy 377.773934 -233.811952) (xy 377.800237 -233.770356)
			(xy 377.832872 -233.733519) (xy 377.870993 -233.702394) (xy 377.913614 -233.677787) (xy 377.95963 -233.660335)
			(xy 378.007849 -233.650491) (xy 378.057024 -233.64851) (xy 378.105879 -233.654442) (xy 378.15315 -233.668134)
			(xy 378.197612 -233.689232) (xy 378.238115 -233.717188) (xy 378.273608 -233.75128) (xy 378.303173 -233.790624)
			(xy 378.326044 -233.834201) (xy 378.341628 -233.880882) (xy 378.349523 -233.929459) (xy 378.350018 -233.954066)
			(xy 378.668529 -233.954066) (xy 378.672624 -233.903338) (xy 378.684803 -233.853924) (xy 378.704751 -233.807104)
			(xy 378.731952 -233.76409) (xy 378.7657 -233.725996) (xy 378.805122 -233.693809) (xy 378.849196 -233.668363)
			(xy 378.896782 -233.650316) (xy 378.946646 -233.640136) (xy 378.997498 -233.638087) (xy 379.048019 -233.644221)
			(xy 379.096903 -233.658381) (xy 379.142882 -233.680198) (xy 379.184766 -233.709108) (xy 379.22147 -233.744363)
			(xy 379.252043 -233.785049) (xy 379.275694 -233.830112) (xy 379.29181 -233.878386) (xy 379.299974 -233.92862)
			(xy 379.300486 -233.954066) (xy 379.619014 -233.954066) (xy 379.622974 -233.905012) (xy 379.634751 -233.857228)
			(xy 379.654042 -233.811952) (xy 379.680345 -233.770356) (xy 379.71298 -233.733519) (xy 379.751101 -233.702394)
			(xy 379.793722 -233.677787) (xy 379.839738 -233.660335) (xy 379.887957 -233.650491) (xy 379.937132 -233.64851)
			(xy 379.985987 -233.654442) (xy 380.033258 -233.668134) (xy 380.07772 -233.689232) (xy 380.118223 -233.717188)
			(xy 380.153716 -233.75128) (xy 380.183281 -233.790624) (xy 380.206152 -233.834201) (xy 380.221736 -233.880882)
			(xy 380.229631 -233.929459) (xy 380.230126 -233.954066) (xy 380.548637 -233.954066) (xy 380.552732 -233.903338)
			(xy 380.564911 -233.853924) (xy 380.584859 -233.807104) (xy 380.61206 -233.76409) (xy 380.645808 -233.725996)
			(xy 380.68523 -233.693809) (xy 380.729304 -233.668363) (xy 380.77689 -233.650316) (xy 380.826754 -233.640136)
			(xy 380.877606 -233.638087) (xy 380.928127 -233.644221) (xy 380.977011 -233.658381) (xy 381.02299 -233.680198)
			(xy 381.064874 -233.709108) (xy 381.101578 -233.744363) (xy 381.132151 -233.785049) (xy 381.155802 -233.830112)
			(xy 381.171918 -233.878386) (xy 381.180082 -233.92862) (xy 381.180594 -233.954066) (xy 381.499122 -233.954066)
			(xy 381.503082 -233.905012) (xy 381.514859 -233.857228) (xy 381.53415 -233.811952) (xy 381.560453 -233.770356)
			(xy 381.593088 -233.733519) (xy 381.631209 -233.702394) (xy 381.67383 -233.677787) (xy 381.719846 -233.660335)
			(xy 381.768065 -233.650491) (xy 381.81724 -233.64851) (xy 381.866095 -233.654442) (xy 381.913366 -233.668134)
			(xy 381.957828 -233.689232) (xy 381.998331 -233.717188) (xy 382.033824 -233.75128) (xy 382.063389 -233.790624)
			(xy 382.08626 -233.834201) (xy 382.101844 -233.880882) (xy 382.109739 -233.929459) (xy 382.110234 -233.954066)
			(xy 382.438922 -233.954066) (xy 382.442882 -233.905012) (xy 382.454659 -233.857228) (xy 382.47395 -233.811952)
			(xy 382.500253 -233.770356) (xy 382.532888 -233.733519) (xy 382.571009 -233.702394) (xy 382.61363 -233.677787)
			(xy 382.659646 -233.660335) (xy 382.707865 -233.650491) (xy 382.75704 -233.64851) (xy 382.805895 -233.654442)
			(xy 382.853166 -233.668134) (xy 382.897628 -233.689232) (xy 382.938131 -233.717188) (xy 382.973624 -233.75128)
			(xy 383.003189 -233.790624) (xy 383.02606 -233.834201) (xy 383.041644 -233.880882) (xy 383.049539 -233.929459)
			(xy 383.050034 -233.954066) (xy 383.378976 -233.954066) (xy 383.382936 -233.905012) (xy 383.394713 -233.857228)
			(xy 383.414004 -233.811952) (xy 383.440307 -233.770356) (xy 383.472942 -233.733519) (xy 383.511063 -233.702394)
			(xy 383.553684 -233.677787) (xy 383.5997 -233.660335) (xy 383.647919 -233.650491) (xy 383.697094 -233.64851)
			(xy 383.745949 -233.654442) (xy 383.79322 -233.668134) (xy 383.837682 -233.689232) (xy 383.878185 -233.717188)
			(xy 383.913678 -233.75128) (xy 383.943243 -233.790624) (xy 383.966114 -233.834201) (xy 383.981698 -233.880882)
			(xy 383.989593 -233.929459) (xy 383.990088 -233.954066) (xy 384.31903 -233.954066) (xy 384.32299 -233.905012)
			(xy 384.334767 -233.857228) (xy 384.354058 -233.811952) (xy 384.380361 -233.770356) (xy 384.412996 -233.733519)
			(xy 384.451117 -233.702394) (xy 384.493738 -233.677787) (xy 384.539754 -233.660335) (xy 384.587973 -233.650491)
			(xy 384.637148 -233.64851) (xy 384.686003 -233.654442) (xy 384.733274 -233.668134) (xy 384.777736 -233.689232)
			(xy 384.818239 -233.717188) (xy 384.853732 -233.75128) (xy 384.883297 -233.790624) (xy 384.906168 -233.834201)
			(xy 384.921752 -233.880882) (xy 384.929647 -233.929459) (xy 384.930142 -233.954066) (xy 385.259084 -233.954066)
			(xy 385.263044 -233.905012) (xy 385.274821 -233.857228) (xy 385.294112 -233.811952) (xy 385.320415 -233.770356)
			(xy 385.35305 -233.733519) (xy 385.391171 -233.702394) (xy 385.433792 -233.677787) (xy 385.479808 -233.660335)
			(xy 385.528027 -233.650491) (xy 385.577202 -233.64851) (xy 385.626057 -233.654442) (xy 385.673328 -233.668134)
			(xy 385.71779 -233.689232) (xy 385.758293 -233.717188) (xy 385.793786 -233.75128) (xy 385.823351 -233.790624)
			(xy 385.846222 -233.834201) (xy 385.861806 -233.880882) (xy 385.869701 -233.929459) (xy 385.870196 -233.954066)
			(xy 386.199138 -233.954066) (xy 386.203098 -233.905012) (xy 386.214875 -233.857228) (xy 386.234166 -233.811952)
			(xy 386.260469 -233.770356) (xy 386.293104 -233.733519) (xy 386.331225 -233.702394) (xy 386.373846 -233.677787)
			(xy 386.419862 -233.660335) (xy 386.468081 -233.650491) (xy 386.517256 -233.64851) (xy 386.566111 -233.654442)
			(xy 386.613382 -233.668134) (xy 386.657844 -233.689232) (xy 386.698347 -233.717188) (xy 386.73384 -233.75128)
			(xy 386.763405 -233.790624) (xy 386.786276 -233.834201) (xy 386.80186 -233.880882) (xy 386.809755 -233.929459)
			(xy 386.81025 -233.954066) (xy 386.809755 -233.978673) (xy 386.80186 -234.02725) (xy 386.786276 -234.073931)
			(xy 386.763405 -234.117508) (xy 386.73384 -234.156852) (xy 386.698347 -234.190944) (xy 386.657844 -234.2189)
			(xy 386.613382 -234.239998) (xy 386.566111 -234.25369) (xy 386.517256 -234.259622) (xy 386.468081 -234.257641)
			(xy 386.419862 -234.247797) (xy 386.373846 -234.230345) (xy 386.331225 -234.205738) (xy 386.293104 -234.174613)
			(xy 386.260469 -234.137776) (xy 386.234166 -234.09618) (xy 386.214875 -234.050904) (xy 386.203098 -234.00312)
			(xy 386.199138 -233.954066) (xy 385.870196 -233.954066) (xy 385.869701 -233.978673) (xy 385.861806 -234.02725)
			(xy 385.846222 -234.073931) (xy 385.823351 -234.117508) (xy 385.793786 -234.156852) (xy 385.758293 -234.190944)
			(xy 385.71779 -234.2189) (xy 385.673328 -234.239998) (xy 385.626057 -234.25369) (xy 385.577202 -234.259622)
			(xy 385.528027 -234.257641) (xy 385.479808 -234.247797) (xy 385.433792 -234.230345) (xy 385.391171 -234.205738)
			(xy 385.35305 -234.174613) (xy 385.320415 -234.137776) (xy 385.294112 -234.09618) (xy 385.274821 -234.050904)
			(xy 385.263044 -234.00312) (xy 385.259084 -233.954066) (xy 384.930142 -233.954066) (xy 384.929647 -233.978673)
			(xy 384.921752 -234.02725) (xy 384.906168 -234.073931) (xy 384.883297 -234.117508) (xy 384.853732 -234.156852)
			(xy 384.818239 -234.190944) (xy 384.777736 -234.2189) (xy 384.733274 -234.239998) (xy 384.686003 -234.25369)
			(xy 384.637148 -234.259622) (xy 384.587973 -234.257641) (xy 384.539754 -234.247797) (xy 384.493738 -234.230345)
			(xy 384.451117 -234.205738) (xy 384.412996 -234.174613) (xy 384.380361 -234.137776) (xy 384.354058 -234.09618)
			(xy 384.334767 -234.050904) (xy 384.32299 -234.00312) (xy 384.31903 -233.954066) (xy 383.990088 -233.954066)
			(xy 383.989593 -233.978673) (xy 383.981698 -234.02725) (xy 383.966114 -234.073931) (xy 383.943243 -234.117508)
			(xy 383.913678 -234.156852) (xy 383.878185 -234.190944) (xy 383.837682 -234.2189) (xy 383.79322 -234.239998)
			(xy 383.745949 -234.25369) (xy 383.697094 -234.259622) (xy 383.647919 -234.257641) (xy 383.5997 -234.247797)
			(xy 383.553684 -234.230345) (xy 383.511063 -234.205738) (xy 383.472942 -234.174613) (xy 383.440307 -234.137776)
			(xy 383.414004 -234.09618) (xy 383.394713 -234.050904) (xy 383.382936 -234.00312) (xy 383.378976 -233.954066)
			(xy 383.050034 -233.954066) (xy 383.049539 -233.978673) (xy 383.041644 -234.02725) (xy 383.02606 -234.073931)
			(xy 383.003189 -234.117508) (xy 382.973624 -234.156852) (xy 382.938131 -234.190944) (xy 382.897628 -234.2189)
			(xy 382.853166 -234.239998) (xy 382.805895 -234.25369) (xy 382.75704 -234.259622) (xy 382.707865 -234.257641)
			(xy 382.659646 -234.247797) (xy 382.61363 -234.230345) (xy 382.571009 -234.205738) (xy 382.532888 -234.174613)
			(xy 382.500253 -234.137776) (xy 382.47395 -234.09618) (xy 382.454659 -234.050904) (xy 382.442882 -234.00312)
			(xy 382.438922 -233.954066) (xy 382.110234 -233.954066) (xy 382.109739 -233.978673) (xy 382.101844 -234.02725)
			(xy 382.08626 -234.073931) (xy 382.063389 -234.117508) (xy 382.033824 -234.156852) (xy 381.998331 -234.190944)
			(xy 381.957828 -234.2189) (xy 381.913366 -234.239998) (xy 381.866095 -234.25369) (xy 381.81724 -234.259622)
			(xy 381.768065 -234.257641) (xy 381.719846 -234.247797) (xy 381.67383 -234.230345) (xy 381.631209 -234.205738)
			(xy 381.593088 -234.174613) (xy 381.560453 -234.137776) (xy 381.53415 -234.09618) (xy 381.514859 -234.050904)
			(xy 381.503082 -234.00312) (xy 381.499122 -233.954066) (xy 381.180594 -233.954066) (xy 381.180082 -233.979512)
			(xy 381.171918 -234.029746) (xy 381.155802 -234.07802) (xy 381.132151 -234.123083) (xy 381.101578 -234.163769)
			(xy 381.064874 -234.199024) (xy 381.02299 -234.227934) (xy 380.977011 -234.249751) (xy 380.928127 -234.263911)
			(xy 380.877606 -234.270045) (xy 380.826754 -234.267996) (xy 380.77689 -234.257816) (xy 380.729304 -234.239769)
			(xy 380.68523 -234.214323) (xy 380.645808 -234.182136) (xy 380.61206 -234.144042) (xy 380.584859 -234.101028)
			(xy 380.564911 -234.054208) (xy 380.552732 -234.004794) (xy 380.548637 -233.954066) (xy 380.230126 -233.954066)
			(xy 380.229631 -233.978673) (xy 380.221736 -234.02725) (xy 380.206152 -234.073931) (xy 380.183281 -234.117508)
			(xy 380.153716 -234.156852) (xy 380.118223 -234.190944) (xy 380.07772 -234.2189) (xy 380.033258 -234.239998)
			(xy 379.985987 -234.25369) (xy 379.937132 -234.259622) (xy 379.887957 -234.257641) (xy 379.839738 -234.247797)
			(xy 379.793722 -234.230345) (xy 379.751101 -234.205738) (xy 379.71298 -234.174613) (xy 379.680345 -234.137776)
			(xy 379.654042 -234.09618) (xy 379.634751 -234.050904) (xy 379.622974 -234.00312) (xy 379.619014 -233.954066)
			(xy 379.300486 -233.954066) (xy 379.299974 -233.979512) (xy 379.29181 -234.029746) (xy 379.275694 -234.07802)
			(xy 379.252043 -234.123083) (xy 379.22147 -234.163769) (xy 379.184766 -234.199024) (xy 379.142882 -234.227934)
			(xy 379.096903 -234.249751) (xy 379.048019 -234.263911) (xy 378.997498 -234.270045) (xy 378.946646 -234.267996)
			(xy 378.896782 -234.257816) (xy 378.849196 -234.239769) (xy 378.805122 -234.214323) (xy 378.7657 -234.182136)
			(xy 378.731952 -234.144042) (xy 378.704751 -234.101028) (xy 378.684803 -234.054208) (xy 378.672624 -234.004794)
			(xy 378.668529 -233.954066) (xy 378.350018 -233.954066) (xy 378.349523 -233.978673) (xy 378.341628 -234.02725)
			(xy 378.326044 -234.073931) (xy 378.303173 -234.117508) (xy 378.273608 -234.156852) (xy 378.238115 -234.190944)
			(xy 378.197612 -234.2189) (xy 378.15315 -234.239998) (xy 378.105879 -234.25369) (xy 378.057024 -234.259622)
			(xy 378.007849 -234.257641) (xy 377.95963 -234.247797) (xy 377.913614 -234.230345) (xy 377.870993 -234.205738)
			(xy 377.832872 -234.174613) (xy 377.800237 -234.137776) (xy 377.773934 -234.09618) (xy 377.754643 -234.050904)
			(xy 377.742866 -234.00312) (xy 377.738906 -233.954066) (xy 377.420632 -233.954066) (xy 377.42012 -233.979512)
			(xy 377.411956 -234.029746) (xy 377.39584 -234.07802) (xy 377.372189 -234.123083) (xy 377.341616 -234.163769)
			(xy 377.304912 -234.199024) (xy 377.263028 -234.227934) (xy 377.217049 -234.249751) (xy 377.168165 -234.263911)
			(xy 377.117644 -234.270045) (xy 377.066792 -234.267996) (xy 377.016928 -234.257816) (xy 376.969342 -234.239769)
			(xy 376.925268 -234.214323) (xy 376.885846 -234.182136) (xy 376.852098 -234.144042) (xy 376.824897 -234.101028)
			(xy 376.804949 -234.054208) (xy 376.79277 -234.004794) (xy 376.788675 -233.954066) (xy 376.480578 -233.954066)
			(xy 376.480066 -233.979512) (xy 376.471902 -234.029746) (xy 376.455786 -234.07802) (xy 376.432135 -234.123083)
			(xy 376.401562 -234.163769) (xy 376.364858 -234.199024) (xy 376.322974 -234.227934) (xy 376.276995 -234.249751)
			(xy 376.228111 -234.263911) (xy 376.17759 -234.270045) (xy 376.126738 -234.267996) (xy 376.076874 -234.257816)
			(xy 376.029288 -234.239769) (xy 375.985214 -234.214323) (xy 375.945792 -234.182136) (xy 375.912044 -234.144042)
			(xy 375.884843 -234.101028) (xy 375.864895 -234.054208) (xy 375.852716 -234.004794) (xy 375.848621 -233.954066)
			(xy 375.53011 -233.954066) (xy 375.529615 -233.978673) (xy 375.52172 -234.02725) (xy 375.506136 -234.073931)
			(xy 375.483265 -234.117508) (xy 375.4537 -234.156852) (xy 375.418207 -234.190944) (xy 375.377704 -234.2189)
			(xy 375.333242 -234.239998) (xy 375.285971 -234.25369) (xy 375.237116 -234.259622) (xy 375.187941 -234.257641)
			(xy 375.139722 -234.247797) (xy 375.093706 -234.230345) (xy 375.051085 -234.205738) (xy 375.012964 -234.174613)
			(xy 374.980329 -234.137776) (xy 374.954026 -234.09618) (xy 374.934735 -234.050904) (xy 374.922958 -234.00312)
			(xy 374.918998 -233.954066) (xy 374.590605 -233.954066) (xy 374.590607 -233.954094) (xy 374.586487 -234.004136)
			(xy 374.574237 -234.052829) (xy 374.554186 -234.098863) (xy 374.526875 -234.140996) (xy 374.49304 -234.178094)
			(xy 374.453591 -234.209158) (xy 374.409593 -234.23335) (xy 374.36223 -234.250019) (xy 374.33758 -234.254802)
			(xy 374.329706 -234.256326) (xy 374.307608 -234.26801) (xy 374.30388 -234.270108) (xy 374.29712 -234.275349)
			(xy 374.294146 -234.278424) (xy 374.279922 -234.293918) (xy 374.273733 -234.301175) (xy 374.266808 -234.318931)
			(xy 374.26646 -234.328462) (xy 374.26646 -234.764072) (xy 374.449098 -234.764072) (xy 374.453058 -234.715018)
			(xy 374.464835 -234.667234) (xy 374.484126 -234.621958) (xy 374.510429 -234.580362) (xy 374.543064 -234.543525)
			(xy 374.581185 -234.5124) (xy 374.623806 -234.487793) (xy 374.669822 -234.470341) (xy 374.718041 -234.460497)
			(xy 374.767216 -234.458516) (xy 374.816071 -234.464448) (xy 374.863342 -234.47814) (xy 374.907804 -234.499238)
			(xy 374.948307 -234.527194) (xy 374.9838 -234.561286) (xy 375.013365 -234.60063) (xy 375.036236 -234.644207)
			(xy 375.05182 -234.690888) (xy 375.059715 -234.739465) (xy 375.06021 -234.764072) (xy 375.378467 -234.764072)
			(xy 375.382562 -234.713344) (xy 375.394741 -234.66393) (xy 375.414689 -234.61711) (xy 375.44189 -234.574096)
			(xy 375.475638 -234.536002) (xy 375.51506 -234.503815) (xy 375.559134 -234.478369) (xy 375.60672 -234.460322)
			(xy 375.656584 -234.450142) (xy 375.707436 -234.448093) (xy 375.757957 -234.454227) (xy 375.806841 -234.468387)
			(xy 375.85282 -234.490204) (xy 375.894704 -234.519114) (xy 375.931408 -234.554369) (xy 375.961981 -234.595055)
			(xy 375.985632 -234.640118) (xy 376.001748 -234.688392) (xy 376.009912 -234.738626) (xy 376.010424 -234.764072)
			(xy 376.328952 -234.764072) (xy 376.332912 -234.715018) (xy 376.344689 -234.667234) (xy 376.36398 -234.621958)
			(xy 376.390283 -234.580362) (xy 376.422918 -234.543525) (xy 376.461039 -234.5124) (xy 376.50366 -234.487793)
			(xy 376.549676 -234.470341) (xy 376.597895 -234.460497) (xy 376.64707 -234.458516) (xy 376.695925 -234.464448)
			(xy 376.743196 -234.47814) (xy 376.787658 -234.499238) (xy 376.828161 -234.527194) (xy 376.863654 -234.561286)
			(xy 376.893219 -234.60063) (xy 376.91609 -234.644207) (xy 376.931674 -234.690888) (xy 376.939569 -234.739465)
			(xy 376.940064 -234.764072) (xy 377.258575 -234.764072) (xy 377.26267 -234.713344) (xy 377.274849 -234.66393)
			(xy 377.294797 -234.61711) (xy 377.321998 -234.574096) (xy 377.355746 -234.536002) (xy 377.395168 -234.503815)
			(xy 377.439242 -234.478369) (xy 377.486828 -234.460322) (xy 377.536692 -234.450142) (xy 377.587544 -234.448093)
			(xy 377.638065 -234.454227) (xy 377.686949 -234.468387) (xy 377.732928 -234.490204) (xy 377.774812 -234.519114)
			(xy 377.811516 -234.554369) (xy 377.842089 -234.595055) (xy 377.86574 -234.640118) (xy 377.881856 -234.688392)
			(xy 377.89002 -234.738626) (xy 377.890532 -234.764072) (xy 379.138683 -234.764072) (xy 379.142778 -234.713344)
			(xy 379.154957 -234.66393) (xy 379.174905 -234.61711) (xy 379.202106 -234.574096) (xy 379.235854 -234.536002)
			(xy 379.275276 -234.503815) (xy 379.31935 -234.478369) (xy 379.366936 -234.460322) (xy 379.4168 -234.450142)
			(xy 379.467652 -234.448093) (xy 379.518173 -234.454227) (xy 379.567057 -234.468387) (xy 379.613036 -234.490204)
			(xy 379.65492 -234.519114) (xy 379.691624 -234.554369) (xy 379.722197 -234.595055) (xy 379.745848 -234.640118)
			(xy 379.761964 -234.688392) (xy 379.770128 -234.738626) (xy 379.77064 -234.764072) (xy 380.078483 -234.764072)
			(xy 380.082578 -234.713344) (xy 380.094757 -234.66393) (xy 380.114705 -234.61711) (xy 380.141906 -234.574096)
			(xy 380.175654 -234.536002) (xy 380.215076 -234.503815) (xy 380.25915 -234.478369) (xy 380.306736 -234.460322)
			(xy 380.3566 -234.450142) (xy 380.407452 -234.448093) (xy 380.457973 -234.454227) (xy 380.506857 -234.468387)
			(xy 380.552836 -234.490204) (xy 380.59472 -234.519114) (xy 380.631424 -234.554369) (xy 380.661997 -234.595055)
			(xy 380.685648 -234.640118) (xy 380.701764 -234.688392) (xy 380.709928 -234.738626) (xy 380.71044 -234.764072)
			(xy 381.028968 -234.764072) (xy 381.032928 -234.715018) (xy 381.044705 -234.667234) (xy 381.063996 -234.621958)
			(xy 381.090299 -234.580362) (xy 381.122934 -234.543525) (xy 381.161055 -234.5124) (xy 381.203676 -234.487793)
			(xy 381.249692 -234.470341) (xy 381.297911 -234.460497) (xy 381.347086 -234.458516) (xy 381.395941 -234.464448)
			(xy 381.443212 -234.47814) (xy 381.487674 -234.499238) (xy 381.528177 -234.527194) (xy 381.56367 -234.561286)
			(xy 381.593235 -234.60063) (xy 381.616106 -234.644207) (xy 381.63169 -234.690888) (xy 381.639585 -234.739465)
			(xy 381.64008 -234.764072) (xy 381.969022 -234.764072) (xy 381.972982 -234.715018) (xy 381.984759 -234.667234)
			(xy 382.00405 -234.621958) (xy 382.030353 -234.580362) (xy 382.062988 -234.543525) (xy 382.101109 -234.5124)
			(xy 382.14373 -234.487793) (xy 382.189746 -234.470341) (xy 382.237965 -234.460497) (xy 382.28714 -234.458516)
			(xy 382.335995 -234.464448) (xy 382.383266 -234.47814) (xy 382.427728 -234.499238) (xy 382.468231 -234.527194)
			(xy 382.503724 -234.561286) (xy 382.533289 -234.60063) (xy 382.55616 -234.644207) (xy 382.571744 -234.690888)
			(xy 382.579639 -234.739465) (xy 382.580134 -234.764072) (xy 382.909076 -234.764072) (xy 382.913036 -234.715018)
			(xy 382.924813 -234.667234) (xy 382.944104 -234.621958) (xy 382.970407 -234.580362) (xy 383.003042 -234.543525)
			(xy 383.041163 -234.5124) (xy 383.083784 -234.487793) (xy 383.1298 -234.470341) (xy 383.178019 -234.460497)
			(xy 383.227194 -234.458516) (xy 383.276049 -234.464448) (xy 383.32332 -234.47814) (xy 383.367782 -234.499238)
			(xy 383.408285 -234.527194) (xy 383.443778 -234.561286) (xy 383.473343 -234.60063) (xy 383.496214 -234.644207)
			(xy 383.511798 -234.690888) (xy 383.519693 -234.739465) (xy 383.520188 -234.764072) (xy 383.84913 -234.764072)
			(xy 383.85309 -234.715018) (xy 383.864867 -234.667234) (xy 383.884158 -234.621958) (xy 383.910461 -234.580362)
			(xy 383.943096 -234.543525) (xy 383.981217 -234.5124) (xy 384.023838 -234.487793) (xy 384.069854 -234.470341)
			(xy 384.118073 -234.460497) (xy 384.167248 -234.458516) (xy 384.216103 -234.464448) (xy 384.263374 -234.47814)
			(xy 384.307836 -234.499238) (xy 384.348339 -234.527194) (xy 384.383832 -234.561286) (xy 384.413397 -234.60063)
			(xy 384.436268 -234.644207) (xy 384.451852 -234.690888) (xy 384.459747 -234.739465) (xy 384.460242 -234.764072)
			(xy 385.728984 -234.764072) (xy 385.732944 -234.715018) (xy 385.744721 -234.667234) (xy 385.764012 -234.621958)
			(xy 385.790315 -234.580362) (xy 385.82295 -234.543525) (xy 385.861071 -234.5124) (xy 385.903692 -234.487793)
			(xy 385.949708 -234.470341) (xy 385.997927 -234.460497) (xy 386.047102 -234.458516) (xy 386.095957 -234.464448)
			(xy 386.143228 -234.47814) (xy 386.18769 -234.499238) (xy 386.228193 -234.527194) (xy 386.263686 -234.561286)
			(xy 386.293251 -234.60063) (xy 386.316122 -234.644207) (xy 386.331706 -234.690888) (xy 386.339601 -234.739465)
			(xy 386.340096 -234.764072) (xy 386.669038 -234.764072) (xy 386.672998 -234.715018) (xy 386.684775 -234.667234)
			(xy 386.704066 -234.621958) (xy 386.730369 -234.580362) (xy 386.763004 -234.543525) (xy 386.801125 -234.5124)
			(xy 386.843746 -234.487793) (xy 386.889762 -234.470341) (xy 386.937981 -234.460497) (xy 386.987156 -234.458516)
			(xy 387.036011 -234.464448) (xy 387.083282 -234.47814) (xy 387.127744 -234.499238) (xy 387.168247 -234.527194)
			(xy 387.20374 -234.561286) (xy 387.233305 -234.60063) (xy 387.256176 -234.644207) (xy 387.27176 -234.690888)
			(xy 387.279655 -234.739465) (xy 387.28015 -234.764072) (xy 387.279655 -234.788679) (xy 387.27176 -234.837256)
			(xy 387.256176 -234.883937) (xy 387.233305 -234.927514) (xy 387.20374 -234.966858) (xy 387.168247 -235.00095)
			(xy 387.127744 -235.028906) (xy 387.083282 -235.050004) (xy 387.036011 -235.063696) (xy 386.987156 -235.069628)
			(xy 386.937981 -235.067647) (xy 386.889762 -235.057803) (xy 386.843746 -235.040351) (xy 386.801125 -235.015744)
			(xy 386.763004 -234.984619) (xy 386.730369 -234.947782) (xy 386.704066 -234.906186) (xy 386.684775 -234.86091)
			(xy 386.672998 -234.813126) (xy 386.669038 -234.764072) (xy 386.340096 -234.764072) (xy 386.339601 -234.788679)
			(xy 386.331706 -234.837256) (xy 386.316122 -234.883937) (xy 386.293251 -234.927514) (xy 386.263686 -234.966858)
			(xy 386.228193 -235.00095) (xy 386.18769 -235.028906) (xy 386.143228 -235.050004) (xy 386.095957 -235.063696)
			(xy 386.047102 -235.069628) (xy 385.997927 -235.067647) (xy 385.949708 -235.057803) (xy 385.903692 -235.040351)
			(xy 385.861071 -235.015744) (xy 385.82295 -234.984619) (xy 385.790315 -234.947782) (xy 385.764012 -234.906186)
			(xy 385.744721 -234.86091) (xy 385.732944 -234.813126) (xy 385.728984 -234.764072) (xy 384.460242 -234.764072)
			(xy 384.459747 -234.788679) (xy 384.451852 -234.837256) (xy 384.436268 -234.883937) (xy 384.413397 -234.927514)
			(xy 384.383832 -234.966858) (xy 384.348339 -235.00095) (xy 384.307836 -235.028906) (xy 384.263374 -235.050004)
			(xy 384.216103 -235.063696) (xy 384.167248 -235.069628) (xy 384.118073 -235.067647) (xy 384.069854 -235.057803)
			(xy 384.023838 -235.040351) (xy 383.981217 -235.015744) (xy 383.943096 -234.984619) (xy 383.910461 -234.947782)
			(xy 383.884158 -234.906186) (xy 383.864867 -234.86091) (xy 383.85309 -234.813126) (xy 383.84913 -234.764072)
			(xy 383.520188 -234.764072) (xy 383.519693 -234.788679) (xy 383.511798 -234.837256) (xy 383.496214 -234.883937)
			(xy 383.473343 -234.927514) (xy 383.443778 -234.966858) (xy 383.408285 -235.00095) (xy 383.367782 -235.028906)
			(xy 383.32332 -235.050004) (xy 383.276049 -235.063696) (xy 383.227194 -235.069628) (xy 383.178019 -235.067647)
			(xy 383.1298 -235.057803) (xy 383.083784 -235.040351) (xy 383.041163 -235.015744) (xy 383.003042 -234.984619)
			(xy 382.970407 -234.947782) (xy 382.944104 -234.906186) (xy 382.924813 -234.86091) (xy 382.913036 -234.813126)
			(xy 382.909076 -234.764072) (xy 382.580134 -234.764072) (xy 382.579639 -234.788679) (xy 382.571744 -234.837256)
			(xy 382.55616 -234.883937) (xy 382.533289 -234.927514) (xy 382.503724 -234.966858) (xy 382.468231 -235.00095)
			(xy 382.427728 -235.028906) (xy 382.383266 -235.050004) (xy 382.335995 -235.063696) (xy 382.28714 -235.069628)
			(xy 382.237965 -235.067647) (xy 382.189746 -235.057803) (xy 382.14373 -235.040351) (xy 382.101109 -235.015744)
			(xy 382.062988 -234.984619) (xy 382.030353 -234.947782) (xy 382.00405 -234.906186) (xy 381.984759 -234.86091)
			(xy 381.972982 -234.813126) (xy 381.969022 -234.764072) (xy 381.64008 -234.764072) (xy 381.639585 -234.788679)
			(xy 381.63169 -234.837256) (xy 381.616106 -234.883937) (xy 381.593235 -234.927514) (xy 381.56367 -234.966858)
			(xy 381.528177 -235.00095) (xy 381.487674 -235.028906) (xy 381.443212 -235.050004) (xy 381.395941 -235.063696)
			(xy 381.347086 -235.069628) (xy 381.297911 -235.067647) (xy 381.249692 -235.057803) (xy 381.203676 -235.040351)
			(xy 381.161055 -235.015744) (xy 381.122934 -234.984619) (xy 381.090299 -234.947782) (xy 381.063996 -234.906186)
			(xy 381.044705 -234.86091) (xy 381.032928 -234.813126) (xy 381.028968 -234.764072) (xy 380.71044 -234.764072)
			(xy 380.709928 -234.789518) (xy 380.701764 -234.839752) (xy 380.685648 -234.888026) (xy 380.661997 -234.933089)
			(xy 380.631424 -234.973775) (xy 380.59472 -235.00903) (xy 380.552836 -235.03794) (xy 380.506857 -235.059757)
			(xy 380.457973 -235.073917) (xy 380.407452 -235.080051) (xy 380.3566 -235.078002) (xy 380.306736 -235.067822)
			(xy 380.25915 -235.049775) (xy 380.215076 -235.024329) (xy 380.175654 -234.992142) (xy 380.141906 -234.954048)
			(xy 380.114705 -234.911034) (xy 380.094757 -234.864214) (xy 380.082578 -234.8148) (xy 380.078483 -234.764072)
			(xy 379.77064 -234.764072) (xy 379.770128 -234.789518) (xy 379.761964 -234.839752) (xy 379.745848 -234.888026)
			(xy 379.722197 -234.933089) (xy 379.691624 -234.973775) (xy 379.65492 -235.00903) (xy 379.613036 -235.03794)
			(xy 379.567057 -235.059757) (xy 379.518173 -235.073917) (xy 379.467652 -235.080051) (xy 379.4168 -235.078002)
			(xy 379.366936 -235.067822) (xy 379.31935 -235.049775) (xy 379.275276 -235.024329) (xy 379.235854 -234.992142)
			(xy 379.202106 -234.954048) (xy 379.174905 -234.911034) (xy 379.154957 -234.864214) (xy 379.142778 -234.8148)
			(xy 379.138683 -234.764072) (xy 377.890532 -234.764072) (xy 377.89002 -234.789518) (xy 377.881856 -234.839752)
			(xy 377.86574 -234.888026) (xy 377.842089 -234.933089) (xy 377.811516 -234.973775) (xy 377.774812 -235.00903)
			(xy 377.732928 -235.03794) (xy 377.686949 -235.059757) (xy 377.638065 -235.073917) (xy 377.587544 -235.080051)
			(xy 377.536692 -235.078002) (xy 377.486828 -235.067822) (xy 377.439242 -235.049775) (xy 377.395168 -235.024329)
			(xy 377.355746 -234.992142) (xy 377.321998 -234.954048) (xy 377.294797 -234.911034) (xy 377.274849 -234.864214)
			(xy 377.26267 -234.8148) (xy 377.258575 -234.764072) (xy 376.940064 -234.764072) (xy 376.939569 -234.788679)
			(xy 376.931674 -234.837256) (xy 376.91609 -234.883937) (xy 376.893219 -234.927514) (xy 376.863654 -234.966858)
			(xy 376.828161 -235.00095) (xy 376.787658 -235.028906) (xy 376.743196 -235.050004) (xy 376.695925 -235.063696)
			(xy 376.64707 -235.069628) (xy 376.597895 -235.067647) (xy 376.549676 -235.057803) (xy 376.50366 -235.040351)
			(xy 376.461039 -235.015744) (xy 376.422918 -234.984619) (xy 376.390283 -234.947782) (xy 376.36398 -234.906186)
			(xy 376.344689 -234.86091) (xy 376.332912 -234.813126) (xy 376.328952 -234.764072) (xy 376.010424 -234.764072)
			(xy 376.009912 -234.789518) (xy 376.001748 -234.839752) (xy 375.985632 -234.888026) (xy 375.961981 -234.933089)
			(xy 375.931408 -234.973775) (xy 375.894704 -235.00903) (xy 375.85282 -235.03794) (xy 375.806841 -235.059757)
			(xy 375.757957 -235.073917) (xy 375.707436 -235.080051) (xy 375.656584 -235.078002) (xy 375.60672 -235.067822)
			(xy 375.559134 -235.049775) (xy 375.51506 -235.024329) (xy 375.475638 -234.992142) (xy 375.44189 -234.954048)
			(xy 375.414689 -234.911034) (xy 375.394741 -234.864214) (xy 375.382562 -234.8148) (xy 375.378467 -234.764072)
			(xy 375.06021 -234.764072) (xy 375.059715 -234.788679) (xy 375.05182 -234.837256) (xy 375.036236 -234.883937)
			(xy 375.013365 -234.927514) (xy 374.9838 -234.966858) (xy 374.948307 -235.00095) (xy 374.907804 -235.028906)
			(xy 374.863342 -235.050004) (xy 374.816071 -235.063696) (xy 374.767216 -235.069628) (xy 374.718041 -235.067647)
			(xy 374.669822 -235.057803) (xy 374.623806 -235.040351) (xy 374.581185 -235.015744) (xy 374.543064 -234.984619)
			(xy 374.510429 -234.947782) (xy 374.484126 -234.906186) (xy 374.464835 -234.86091) (xy 374.453058 -234.813126)
			(xy 374.449098 -234.764072) (xy 374.26646 -234.764072) (xy 374.26646 -235.199682) (xy 374.266857 -235.209203)
			(xy 374.273774 -235.226945) (xy 374.279922 -235.234226) (xy 374.294146 -235.24972) (xy 374.297099 -235.252818)
			(xy 374.303864 -235.258061) (xy 374.307608 -235.260134) (xy 374.329706 -235.271818) (xy 374.33758 -235.273342)
			(xy 374.360854 -235.277883) (xy 374.405728 -235.293205) (xy 374.447693 -235.315281) (xy 374.485739 -235.343581)
			(xy 374.518952 -235.377424) (xy 374.546532 -235.415995) (xy 374.567816 -235.458367) (xy 374.582293 -235.50352)
			(xy 374.589613 -235.550369) (xy 374.590056 -235.574078) (xy 375.848621 -235.574078) (xy 375.852716 -235.52335)
			(xy 375.864895 -235.473936) (xy 375.884843 -235.427116) (xy 375.912044 -235.384102) (xy 375.945792 -235.346008)
			(xy 375.985214 -235.313821) (xy 376.029288 -235.288375) (xy 376.076874 -235.270328) (xy 376.126738 -235.260148)
			(xy 376.17759 -235.258099) (xy 376.228111 -235.264233) (xy 376.276995 -235.278393) (xy 376.322974 -235.30021)
			(xy 376.364858 -235.32912) (xy 376.401562 -235.364375) (xy 376.432135 -235.405061) (xy 376.455786 -235.450124)
			(xy 376.471902 -235.498398) (xy 376.480066 -235.548632) (xy 376.480578 -235.574078) (xy 376.788675 -235.574078)
			(xy 376.79277 -235.52335) (xy 376.804949 -235.473936) (xy 376.824897 -235.427116) (xy 376.852098 -235.384102)
			(xy 376.885846 -235.346008) (xy 376.925268 -235.313821) (xy 376.969342 -235.288375) (xy 377.016928 -235.270328)
			(xy 377.066792 -235.260148) (xy 377.117644 -235.258099) (xy 377.168165 -235.264233) (xy 377.217049 -235.278393)
			(xy 377.263028 -235.30021) (xy 377.304912 -235.32912) (xy 377.341616 -235.364375) (xy 377.372189 -235.405061)
			(xy 377.39584 -235.450124) (xy 377.411956 -235.498398) (xy 377.42012 -235.548632) (xy 377.420632 -235.574078)
			(xy 377.738906 -235.574078) (xy 377.742866 -235.525024) (xy 377.754643 -235.47724) (xy 377.773934 -235.431964)
			(xy 377.800237 -235.390368) (xy 377.832872 -235.353531) (xy 377.870993 -235.322406) (xy 377.913614 -235.297799)
			(xy 377.95963 -235.280347) (xy 378.007849 -235.270503) (xy 378.057024 -235.268522) (xy 378.105879 -235.274454)
			(xy 378.15315 -235.288146) (xy 378.197612 -235.309244) (xy 378.238115 -235.3372) (xy 378.273608 -235.371292)
			(xy 378.303173 -235.410636) (xy 378.326044 -235.454213) (xy 378.341628 -235.500894) (xy 378.349523 -235.549471)
			(xy 378.350018 -235.574078) (xy 378.668529 -235.574078) (xy 378.672624 -235.52335) (xy 378.684803 -235.473936)
			(xy 378.704751 -235.427116) (xy 378.731952 -235.384102) (xy 378.7657 -235.346008) (xy 378.805122 -235.313821)
			(xy 378.849196 -235.288375) (xy 378.896782 -235.270328) (xy 378.946646 -235.260148) (xy 378.997498 -235.258099)
			(xy 379.048019 -235.264233) (xy 379.096903 -235.278393) (xy 379.142882 -235.30021) (xy 379.184766 -235.32912)
			(xy 379.22147 -235.364375) (xy 379.252043 -235.405061) (xy 379.275694 -235.450124) (xy 379.29181 -235.498398)
			(xy 379.299974 -235.548632) (xy 379.300486 -235.574078) (xy 379.619014 -235.574078) (xy 379.622974 -235.525024)
			(xy 379.634751 -235.47724) (xy 379.654042 -235.431964) (xy 379.680345 -235.390368) (xy 379.71298 -235.353531)
			(xy 379.751101 -235.322406) (xy 379.793722 -235.297799) (xy 379.839738 -235.280347) (xy 379.887957 -235.270503)
			(xy 379.937132 -235.268522) (xy 379.985987 -235.274454) (xy 380.033258 -235.288146) (xy 380.07772 -235.309244)
			(xy 380.118223 -235.3372) (xy 380.153716 -235.371292) (xy 380.183281 -235.410636) (xy 380.206152 -235.454213)
			(xy 380.221736 -235.500894) (xy 380.229631 -235.549471) (xy 380.230126 -235.574078) (xy 380.548637 -235.574078)
			(xy 380.552732 -235.52335) (xy 380.564911 -235.473936) (xy 380.584859 -235.427116) (xy 380.61206 -235.384102)
			(xy 380.645808 -235.346008) (xy 380.68523 -235.313821) (xy 380.729304 -235.288375) (xy 380.77689 -235.270328)
			(xy 380.826754 -235.260148) (xy 380.877606 -235.258099) (xy 380.928127 -235.264233) (xy 380.977011 -235.278393)
			(xy 381.02299 -235.30021) (xy 381.064874 -235.32912) (xy 381.101578 -235.364375) (xy 381.132151 -235.405061)
			(xy 381.155802 -235.450124) (xy 381.171918 -235.498398) (xy 381.180082 -235.548632) (xy 381.180594 -235.574078)
			(xy 381.499122 -235.574078) (xy 381.503082 -235.525024) (xy 381.514859 -235.47724) (xy 381.53415 -235.431964)
			(xy 381.560453 -235.390368) (xy 381.593088 -235.353531) (xy 381.631209 -235.322406) (xy 381.67383 -235.297799)
			(xy 381.719846 -235.280347) (xy 381.768065 -235.270503) (xy 381.81724 -235.268522) (xy 381.866095 -235.274454)
			(xy 381.913366 -235.288146) (xy 381.957828 -235.309244) (xy 381.998331 -235.3372) (xy 382.033824 -235.371292)
			(xy 382.063389 -235.410636) (xy 382.08626 -235.454213) (xy 382.101844 -235.500894) (xy 382.109739 -235.549471)
			(xy 382.110234 -235.574078) (xy 382.438922 -235.574078) (xy 382.442882 -235.525024) (xy 382.454659 -235.47724)
			(xy 382.47395 -235.431964) (xy 382.500253 -235.390368) (xy 382.532888 -235.353531) (xy 382.571009 -235.322406)
			(xy 382.61363 -235.297799) (xy 382.659646 -235.280347) (xy 382.707865 -235.270503) (xy 382.75704 -235.268522)
			(xy 382.805895 -235.274454) (xy 382.853166 -235.288146) (xy 382.897628 -235.309244) (xy 382.938131 -235.3372)
			(xy 382.973624 -235.371292) (xy 383.003189 -235.410636) (xy 383.02606 -235.454213) (xy 383.041644 -235.500894)
			(xy 383.049539 -235.549471) (xy 383.050034 -235.574078) (xy 383.378976 -235.574078) (xy 383.382936 -235.525024)
			(xy 383.394713 -235.47724) (xy 383.414004 -235.431964) (xy 383.440307 -235.390368) (xy 383.472942 -235.353531)
			(xy 383.511063 -235.322406) (xy 383.553684 -235.297799) (xy 383.5997 -235.280347) (xy 383.647919 -235.270503)
			(xy 383.697094 -235.268522) (xy 383.745949 -235.274454) (xy 383.79322 -235.288146) (xy 383.837682 -235.309244)
			(xy 383.878185 -235.3372) (xy 383.913678 -235.371292) (xy 383.943243 -235.410636) (xy 383.966114 -235.454213)
			(xy 383.981698 -235.500894) (xy 383.989593 -235.549471) (xy 383.990088 -235.574078) (xy 384.31903 -235.574078)
			(xy 384.32299 -235.525024) (xy 384.334767 -235.47724) (xy 384.354058 -235.431964) (xy 384.380361 -235.390368)
			(xy 384.412996 -235.353531) (xy 384.451117 -235.322406) (xy 384.493738 -235.297799) (xy 384.539754 -235.280347)
			(xy 384.587973 -235.270503) (xy 384.637148 -235.268522) (xy 384.686003 -235.274454) (xy 384.733274 -235.288146)
			(xy 384.777736 -235.309244) (xy 384.818239 -235.3372) (xy 384.853732 -235.371292) (xy 384.883297 -235.410636)
			(xy 384.906168 -235.454213) (xy 384.921752 -235.500894) (xy 384.929647 -235.549471) (xy 384.930142 -235.574078)
			(xy 385.259084 -235.574078) (xy 385.263044 -235.525024) (xy 385.274821 -235.47724) (xy 385.294112 -235.431964)
			(xy 385.320415 -235.390368) (xy 385.35305 -235.353531) (xy 385.391171 -235.322406) (xy 385.433792 -235.297799)
			(xy 385.479808 -235.280347) (xy 385.528027 -235.270503) (xy 385.577202 -235.268522) (xy 385.626057 -235.274454)
			(xy 385.673328 -235.288146) (xy 385.71779 -235.309244) (xy 385.758293 -235.3372) (xy 385.793786 -235.371292)
			(xy 385.823351 -235.410636) (xy 385.846222 -235.454213) (xy 385.861806 -235.500894) (xy 385.869701 -235.549471)
			(xy 385.870196 -235.574078) (xy 386.199138 -235.574078) (xy 386.203098 -235.525024) (xy 386.214875 -235.47724)
			(xy 386.234166 -235.431964) (xy 386.260469 -235.390368) (xy 386.293104 -235.353531) (xy 386.331225 -235.322406)
			(xy 386.373846 -235.297799) (xy 386.419862 -235.280347) (xy 386.468081 -235.270503) (xy 386.517256 -235.268522)
			(xy 386.566111 -235.274454) (xy 386.613382 -235.288146) (xy 386.657844 -235.309244) (xy 386.698347 -235.3372)
			(xy 386.73384 -235.371292) (xy 386.763405 -235.410636) (xy 386.786276 -235.454213) (xy 386.80186 -235.500894)
			(xy 386.809755 -235.549471) (xy 386.81025 -235.574078) (xy 386.809755 -235.598685) (xy 386.80186 -235.647262)
			(xy 386.786276 -235.693943) (xy 386.763405 -235.73752) (xy 386.73384 -235.776864) (xy 386.698347 -235.810956)
			(xy 386.657844 -235.838912) (xy 386.613382 -235.86001) (xy 386.566111 -235.873702) (xy 386.517256 -235.879634)
			(xy 386.468081 -235.877653) (xy 386.419862 -235.867809) (xy 386.373846 -235.850357) (xy 386.331225 -235.82575)
			(xy 386.293104 -235.794625) (xy 386.260469 -235.757788) (xy 386.234166 -235.716192) (xy 386.214875 -235.670916)
			(xy 386.203098 -235.623132) (xy 386.199138 -235.574078) (xy 385.870196 -235.574078) (xy 385.869701 -235.598685)
			(xy 385.861806 -235.647262) (xy 385.846222 -235.693943) (xy 385.823351 -235.73752) (xy 385.793786 -235.776864)
			(xy 385.758293 -235.810956) (xy 385.71779 -235.838912) (xy 385.673328 -235.86001) (xy 385.626057 -235.873702)
			(xy 385.577202 -235.879634) (xy 385.528027 -235.877653) (xy 385.479808 -235.867809) (xy 385.433792 -235.850357)
			(xy 385.391171 -235.82575) (xy 385.35305 -235.794625) (xy 385.320415 -235.757788) (xy 385.294112 -235.716192)
			(xy 385.274821 -235.670916) (xy 385.263044 -235.623132) (xy 385.259084 -235.574078) (xy 384.930142 -235.574078)
			(xy 384.929647 -235.598685) (xy 384.921752 -235.647262) (xy 384.906168 -235.693943) (xy 384.883297 -235.73752)
			(xy 384.853732 -235.776864) (xy 384.818239 -235.810956) (xy 384.777736 -235.838912) (xy 384.733274 -235.86001)
			(xy 384.686003 -235.873702) (xy 384.637148 -235.879634) (xy 384.587973 -235.877653) (xy 384.539754 -235.867809)
			(xy 384.493738 -235.850357) (xy 384.451117 -235.82575) (xy 384.412996 -235.794625) (xy 384.380361 -235.757788)
			(xy 384.354058 -235.716192) (xy 384.334767 -235.670916) (xy 384.32299 -235.623132) (xy 384.31903 -235.574078)
			(xy 383.990088 -235.574078) (xy 383.989593 -235.598685) (xy 383.981698 -235.647262) (xy 383.966114 -235.693943)
			(xy 383.943243 -235.73752) (xy 383.913678 -235.776864) (xy 383.878185 -235.810956) (xy 383.837682 -235.838912)
			(xy 383.79322 -235.86001) (xy 383.745949 -235.873702) (xy 383.697094 -235.879634) (xy 383.647919 -235.877653)
			(xy 383.5997 -235.867809) (xy 383.553684 -235.850357) (xy 383.511063 -235.82575) (xy 383.472942 -235.794625)
			(xy 383.440307 -235.757788) (xy 383.414004 -235.716192) (xy 383.394713 -235.670916) (xy 383.382936 -235.623132)
			(xy 383.378976 -235.574078) (xy 383.050034 -235.574078) (xy 383.049539 -235.598685) (xy 383.041644 -235.647262)
			(xy 383.02606 -235.693943) (xy 383.003189 -235.73752) (xy 382.973624 -235.776864) (xy 382.938131 -235.810956)
			(xy 382.897628 -235.838912) (xy 382.853166 -235.86001) (xy 382.805895 -235.873702) (xy 382.75704 -235.879634)
			(xy 382.707865 -235.877653) (xy 382.659646 -235.867809) (xy 382.61363 -235.850357) (xy 382.571009 -235.82575)
			(xy 382.532888 -235.794625) (xy 382.500253 -235.757788) (xy 382.47395 -235.716192) (xy 382.454659 -235.670916)
			(xy 382.442882 -235.623132) (xy 382.438922 -235.574078) (xy 382.110234 -235.574078) (xy 382.109739 -235.598685)
			(xy 382.101844 -235.647262) (xy 382.08626 -235.693943) (xy 382.063389 -235.73752) (xy 382.033824 -235.776864)
			(xy 381.998331 -235.810956) (xy 381.957828 -235.838912) (xy 381.913366 -235.86001) (xy 381.866095 -235.873702)
			(xy 381.81724 -235.879634) (xy 381.768065 -235.877653) (xy 381.719846 -235.867809) (xy 381.67383 -235.850357)
			(xy 381.631209 -235.82575) (xy 381.593088 -235.794625) (xy 381.560453 -235.757788) (xy 381.53415 -235.716192)
			(xy 381.514859 -235.670916) (xy 381.503082 -235.623132) (xy 381.499122 -235.574078) (xy 381.180594 -235.574078)
			(xy 381.180082 -235.599524) (xy 381.171918 -235.649758) (xy 381.155802 -235.698032) (xy 381.132151 -235.743095)
			(xy 381.101578 -235.783781) (xy 381.064874 -235.819036) (xy 381.02299 -235.847946) (xy 380.977011 -235.869763)
			(xy 380.928127 -235.883923) (xy 380.877606 -235.890057) (xy 380.826754 -235.888008) (xy 380.77689 -235.877828)
			(xy 380.729304 -235.859781) (xy 380.68523 -235.834335) (xy 380.645808 -235.802148) (xy 380.61206 -235.764054)
			(xy 380.584859 -235.72104) (xy 380.564911 -235.67422) (xy 380.552732 -235.624806) (xy 380.548637 -235.574078)
			(xy 380.230126 -235.574078) (xy 380.229631 -235.598685) (xy 380.221736 -235.647262) (xy 380.206152 -235.693943)
			(xy 380.183281 -235.73752) (xy 380.153716 -235.776864) (xy 380.118223 -235.810956) (xy 380.07772 -235.838912)
			(xy 380.033258 -235.86001) (xy 379.985987 -235.873702) (xy 379.937132 -235.879634) (xy 379.887957 -235.877653)
			(xy 379.839738 -235.867809) (xy 379.793722 -235.850357) (xy 379.751101 -235.82575) (xy 379.71298 -235.794625)
			(xy 379.680345 -235.757788) (xy 379.654042 -235.716192) (xy 379.634751 -235.670916) (xy 379.622974 -235.623132)
			(xy 379.619014 -235.574078) (xy 379.300486 -235.574078) (xy 379.299974 -235.599524) (xy 379.29181 -235.649758)
			(xy 379.275694 -235.698032) (xy 379.252043 -235.743095) (xy 379.22147 -235.783781) (xy 379.184766 -235.819036)
			(xy 379.142882 -235.847946) (xy 379.096903 -235.869763) (xy 379.048019 -235.883923) (xy 378.997498 -235.890057)
			(xy 378.946646 -235.888008) (xy 378.896782 -235.877828) (xy 378.849196 -235.859781) (xy 378.805122 -235.834335)
			(xy 378.7657 -235.802148) (xy 378.731952 -235.764054) (xy 378.704751 -235.72104) (xy 378.684803 -235.67422)
			(xy 378.672624 -235.624806) (xy 378.668529 -235.574078) (xy 378.350018 -235.574078) (xy 378.349523 -235.598685)
			(xy 378.341628 -235.647262) (xy 378.326044 -235.693943) (xy 378.303173 -235.73752) (xy 378.273608 -235.776864)
			(xy 378.238115 -235.810956) (xy 378.197612 -235.838912) (xy 378.15315 -235.86001) (xy 378.105879 -235.873702)
			(xy 378.057024 -235.879634) (xy 378.007849 -235.877653) (xy 377.95963 -235.867809) (xy 377.913614 -235.850357)
			(xy 377.870993 -235.82575) (xy 377.832872 -235.794625) (xy 377.800237 -235.757788) (xy 377.773934 -235.716192)
			(xy 377.754643 -235.670916) (xy 377.742866 -235.623132) (xy 377.738906 -235.574078) (xy 377.420632 -235.574078)
			(xy 377.42012 -235.599524) (xy 377.411956 -235.649758) (xy 377.39584 -235.698032) (xy 377.372189 -235.743095)
			(xy 377.341616 -235.783781) (xy 377.304912 -235.819036) (xy 377.263028 -235.847946) (xy 377.217049 -235.869763)
			(xy 377.168165 -235.883923) (xy 377.117644 -235.890057) (xy 377.066792 -235.888008) (xy 377.016928 -235.877828)
			(xy 376.969342 -235.859781) (xy 376.925268 -235.834335) (xy 376.885846 -235.802148) (xy 376.852098 -235.764054)
			(xy 376.824897 -235.72104) (xy 376.804949 -235.67422) (xy 376.79277 -235.624806) (xy 376.788675 -235.574078)
			(xy 376.480578 -235.574078) (xy 376.480066 -235.599524) (xy 376.471902 -235.649758) (xy 376.455786 -235.698032)
			(xy 376.432135 -235.743095) (xy 376.401562 -235.783781) (xy 376.364858 -235.819036) (xy 376.322974 -235.847946)
			(xy 376.276995 -235.869763) (xy 376.228111 -235.883923) (xy 376.17759 -235.890057) (xy 376.126738 -235.888008)
			(xy 376.076874 -235.877828) (xy 376.029288 -235.859781) (xy 375.985214 -235.834335) (xy 375.945792 -235.802148)
			(xy 375.912044 -235.764054) (xy 375.884843 -235.72104) (xy 375.864895 -235.67422) (xy 375.852716 -235.624806)
			(xy 375.848621 -235.574078) (xy 374.590056 -235.574078) (xy 374.590056 -235.580428) (xy 374.589081 -235.604506)
			(xy 374.580489 -235.651922) (xy 374.564562 -235.697402) (xy 374.541697 -235.739819) (xy 374.512458 -235.778123)
			(xy 374.495314 -235.795058) (xy 374.48811 -235.802448) (xy 374.479825 -235.821328) (xy 374.479312 -235.831634)
			(xy 374.47855 -235.904278) (xy 374.478896 -235.914479) (xy 374.486615 -235.933354) (xy 374.493536 -235.940854)
			(xy 374.638062 -236.08538) (xy 374.66397 -236.092238) (xy 374.677178 -236.088936) (xy 374.696264 -236.084222)
			(xy 374.735246 -236.07912) (xy 374.754902 -236.078776) (xy 374.778894 -236.079247) (xy 374.826286 -236.086753)
			(xy 374.871921 -236.10158) (xy 374.914674 -236.123364) (xy 374.953494 -236.151567) (xy 374.987424 -236.185495)
			(xy 375.015629 -236.224314) (xy 375.037414 -236.267066) (xy 375.052244 -236.3127) (xy 375.059752 -236.360092)
			(xy 375.06021 -236.384084) (xy 375.378467 -236.384084) (xy 375.382562 -236.333356) (xy 375.394741 -236.283942)
			(xy 375.414689 -236.237122) (xy 375.44189 -236.194108) (xy 375.475638 -236.156014) (xy 375.51506 -236.123827)
			(xy 375.559134 -236.098381) (xy 375.60672 -236.080334) (xy 375.656584 -236.070154) (xy 375.707436 -236.068105)
			(xy 375.757957 -236.074239) (xy 375.806841 -236.088399) (xy 375.85282 -236.110216) (xy 375.894704 -236.139126)
			(xy 375.931408 -236.174381) (xy 375.961981 -236.215067) (xy 375.985632 -236.26013) (xy 376.001748 -236.308404)
			(xy 376.009912 -236.358638) (xy 376.010424 -236.384084) (xy 376.328952 -236.384084) (xy 376.332912 -236.33503)
			(xy 376.344689 -236.287246) (xy 376.36398 -236.24197) (xy 376.390283 -236.200374) (xy 376.422918 -236.163537)
			(xy 376.461039 -236.132412) (xy 376.50366 -236.107805) (xy 376.549676 -236.090353) (xy 376.597895 -236.080509)
			(xy 376.64707 -236.078528) (xy 376.695925 -236.08446) (xy 376.743196 -236.098152) (xy 376.787658 -236.11925)
			(xy 376.828161 -236.147206) (xy 376.863654 -236.181298) (xy 376.893219 -236.220642) (xy 376.91609 -236.264219)
			(xy 376.931674 -236.3109) (xy 376.939569 -236.359477) (xy 376.940064 -236.384084) (xy 377.258575 -236.384084)
			(xy 377.26267 -236.333356) (xy 377.274849 -236.283942) (xy 377.294797 -236.237122) (xy 377.321998 -236.194108)
			(xy 377.355746 -236.156014) (xy 377.395168 -236.123827) (xy 377.439242 -236.098381) (xy 377.486828 -236.080334)
			(xy 377.536692 -236.070154) (xy 377.587544 -236.068105) (xy 377.638065 -236.074239) (xy 377.686949 -236.088399)
			(xy 377.732928 -236.110216) (xy 377.774812 -236.139126) (xy 377.811516 -236.174381) (xy 377.842089 -236.215067)
			(xy 377.86574 -236.26013) (xy 377.881856 -236.308404) (xy 377.89002 -236.358638) (xy 377.890532 -236.384084)
			(xy 378.20906 -236.384084) (xy 378.21302 -236.33503) (xy 378.224797 -236.287246) (xy 378.244088 -236.24197)
			(xy 378.270391 -236.200374) (xy 378.303026 -236.163537) (xy 378.341147 -236.132412) (xy 378.383768 -236.107805)
			(xy 378.429784 -236.090353) (xy 378.478003 -236.080509) (xy 378.527178 -236.078528) (xy 378.576033 -236.08446)
			(xy 378.623304 -236.098152) (xy 378.667766 -236.11925) (xy 378.708269 -236.147206) (xy 378.743762 -236.181298)
			(xy 378.773327 -236.220642) (xy 378.796198 -236.264219) (xy 378.811782 -236.3109) (xy 378.819677 -236.359477)
			(xy 378.820172 -236.384084) (xy 379.138683 -236.384084) (xy 379.142778 -236.333356) (xy 379.154957 -236.283942)
			(xy 379.174905 -236.237122) (xy 379.202106 -236.194108) (xy 379.235854 -236.156014) (xy 379.275276 -236.123827)
			(xy 379.31935 -236.098381) (xy 379.366936 -236.080334) (xy 379.4168 -236.070154) (xy 379.467652 -236.068105)
			(xy 379.518173 -236.074239) (xy 379.567057 -236.088399) (xy 379.613036 -236.110216) (xy 379.65492 -236.139126)
			(xy 379.691624 -236.174381) (xy 379.722197 -236.215067) (xy 379.745848 -236.26013) (xy 379.761964 -236.308404)
			(xy 379.770128 -236.358638) (xy 379.77064 -236.384084) (xy 380.078483 -236.384084) (xy 380.082578 -236.333356)
			(xy 380.094757 -236.283942) (xy 380.114705 -236.237122) (xy 380.141906 -236.194108) (xy 380.175654 -236.156014)
			(xy 380.215076 -236.123827) (xy 380.25915 -236.098381) (xy 380.306736 -236.080334) (xy 380.3566 -236.070154)
			(xy 380.407452 -236.068105) (xy 380.457973 -236.074239) (xy 380.506857 -236.088399) (xy 380.552836 -236.110216)
			(xy 380.59472 -236.139126) (xy 380.631424 -236.174381) (xy 380.661997 -236.215067) (xy 380.685648 -236.26013)
			(xy 380.701764 -236.308404) (xy 380.709928 -236.358638) (xy 380.71044 -236.384084) (xy 381.028968 -236.384084)
			(xy 381.032928 -236.33503) (xy 381.044705 -236.287246) (xy 381.063996 -236.24197) (xy 381.090299 -236.200374)
			(xy 381.122934 -236.163537) (xy 381.161055 -236.132412) (xy 381.203676 -236.107805) (xy 381.249692 -236.090353)
			(xy 381.297911 -236.080509) (xy 381.347086 -236.078528) (xy 381.395941 -236.08446) (xy 381.443212 -236.098152)
			(xy 381.487674 -236.11925) (xy 381.528177 -236.147206) (xy 381.56367 -236.181298) (xy 381.593235 -236.220642)
			(xy 381.616106 -236.264219) (xy 381.63169 -236.3109) (xy 381.639585 -236.359477) (xy 381.64008 -236.384084)
			(xy 381.969022 -236.384084) (xy 381.972982 -236.33503) (xy 381.984759 -236.287246) (xy 382.00405 -236.24197)
			(xy 382.030353 -236.200374) (xy 382.062988 -236.163537) (xy 382.101109 -236.132412) (xy 382.14373 -236.107805)
			(xy 382.189746 -236.090353) (xy 382.237965 -236.080509) (xy 382.28714 -236.078528) (xy 382.335995 -236.08446)
			(xy 382.383266 -236.098152) (xy 382.427728 -236.11925) (xy 382.468231 -236.147206) (xy 382.503724 -236.181298)
			(xy 382.533289 -236.220642) (xy 382.55616 -236.264219) (xy 382.571744 -236.3109) (xy 382.579639 -236.359477)
			(xy 382.580134 -236.384084) (xy 382.909076 -236.384084) (xy 382.913036 -236.33503) (xy 382.924813 -236.287246)
			(xy 382.944104 -236.24197) (xy 382.970407 -236.200374) (xy 383.003042 -236.163537) (xy 383.041163 -236.132412)
			(xy 383.083784 -236.107805) (xy 383.1298 -236.090353) (xy 383.178019 -236.080509) (xy 383.227194 -236.078528)
			(xy 383.276049 -236.08446) (xy 383.32332 -236.098152) (xy 383.367782 -236.11925) (xy 383.408285 -236.147206)
			(xy 383.443778 -236.181298) (xy 383.473343 -236.220642) (xy 383.496214 -236.264219) (xy 383.511798 -236.3109)
			(xy 383.519693 -236.359477) (xy 383.520188 -236.384084) (xy 383.84913 -236.384084) (xy 383.85309 -236.33503)
			(xy 383.864867 -236.287246) (xy 383.884158 -236.24197) (xy 383.910461 -236.200374) (xy 383.943096 -236.163537)
			(xy 383.981217 -236.132412) (xy 384.023838 -236.107805) (xy 384.069854 -236.090353) (xy 384.118073 -236.080509)
			(xy 384.167248 -236.078528) (xy 384.216103 -236.08446) (xy 384.263374 -236.098152) (xy 384.307836 -236.11925)
			(xy 384.348339 -236.147206) (xy 384.383832 -236.181298) (xy 384.413397 -236.220642) (xy 384.436268 -236.264219)
			(xy 384.451852 -236.3109) (xy 384.459747 -236.359477) (xy 384.460242 -236.384084) (xy 384.78893 -236.384084)
			(xy 384.79289 -236.33503) (xy 384.804667 -236.287246) (xy 384.823958 -236.24197) (xy 384.850261 -236.200374)
			(xy 384.882896 -236.163537) (xy 384.921017 -236.132412) (xy 384.963638 -236.107805) (xy 385.009654 -236.090353)
			(xy 385.057873 -236.080509) (xy 385.107048 -236.078528) (xy 385.155903 -236.08446) (xy 385.203174 -236.098152)
			(xy 385.247636 -236.11925) (xy 385.288139 -236.147206) (xy 385.323632 -236.181298) (xy 385.353197 -236.220642)
			(xy 385.376068 -236.264219) (xy 385.391652 -236.3109) (xy 385.399547 -236.359477) (xy 385.400042 -236.384084)
			(xy 385.728984 -236.384084) (xy 385.732944 -236.33503) (xy 385.744721 -236.287246) (xy 385.764012 -236.24197)
			(xy 385.790315 -236.200374) (xy 385.82295 -236.163537) (xy 385.861071 -236.132412) (xy 385.903692 -236.107805)
			(xy 385.949708 -236.090353) (xy 385.997927 -236.080509) (xy 386.047102 -236.078528) (xy 386.095957 -236.08446)
			(xy 386.143228 -236.098152) (xy 386.18769 -236.11925) (xy 386.228193 -236.147206) (xy 386.263686 -236.181298)
			(xy 386.293251 -236.220642) (xy 386.316122 -236.264219) (xy 386.331706 -236.3109) (xy 386.339601 -236.359477)
			(xy 386.340096 -236.384084) (xy 386.669038 -236.384084) (xy 386.672998 -236.33503) (xy 386.684775 -236.287246)
			(xy 386.704066 -236.24197) (xy 386.730369 -236.200374) (xy 386.763004 -236.163537) (xy 386.801125 -236.132412)
			(xy 386.843746 -236.107805) (xy 386.889762 -236.090353) (xy 386.937981 -236.080509) (xy 386.987156 -236.078528)
			(xy 387.036011 -236.08446) (xy 387.083282 -236.098152) (xy 387.127744 -236.11925) (xy 387.168247 -236.147206)
			(xy 387.20374 -236.181298) (xy 387.233305 -236.220642) (xy 387.256176 -236.264219) (xy 387.27176 -236.3109)
			(xy 387.279655 -236.359477) (xy 387.28015 -236.384084) (xy 387.279655 -236.408691) (xy 387.27176 -236.457268)
			(xy 387.256176 -236.503949) (xy 387.233305 -236.547526) (xy 387.20374 -236.58687) (xy 387.168247 -236.620962)
			(xy 387.127744 -236.648918) (xy 387.083282 -236.670016) (xy 387.036011 -236.683708) (xy 386.987156 -236.68964)
			(xy 386.937981 -236.687659) (xy 386.889762 -236.677815) (xy 386.843746 -236.660363) (xy 386.801125 -236.635756)
			(xy 386.763004 -236.604631) (xy 386.730369 -236.567794) (xy 386.704066 -236.526198) (xy 386.684775 -236.480922)
			(xy 386.672998 -236.433138) (xy 386.669038 -236.384084) (xy 386.340096 -236.384084) (xy 386.339601 -236.408691)
			(xy 386.331706 -236.457268) (xy 386.316122 -236.503949) (xy 386.293251 -236.547526) (xy 386.263686 -236.58687)
			(xy 386.228193 -236.620962) (xy 386.18769 -236.648918) (xy 386.143228 -236.670016) (xy 386.095957 -236.683708)
			(xy 386.047102 -236.68964) (xy 385.997927 -236.687659) (xy 385.949708 -236.677815) (xy 385.903692 -236.660363)
			(xy 385.861071 -236.635756) (xy 385.82295 -236.604631) (xy 385.790315 -236.567794) (xy 385.764012 -236.526198)
			(xy 385.744721 -236.480922) (xy 385.732944 -236.433138) (xy 385.728984 -236.384084) (xy 385.400042 -236.384084)
			(xy 385.399547 -236.408691) (xy 385.391652 -236.457268) (xy 385.376068 -236.503949) (xy 385.353197 -236.547526)
			(xy 385.323632 -236.58687) (xy 385.288139 -236.620962) (xy 385.247636 -236.648918) (xy 385.203174 -236.670016)
			(xy 385.155903 -236.683708) (xy 385.107048 -236.68964) (xy 385.057873 -236.687659) (xy 385.009654 -236.677815)
			(xy 384.963638 -236.660363) (xy 384.921017 -236.635756) (xy 384.882896 -236.604631) (xy 384.850261 -236.567794)
			(xy 384.823958 -236.526198) (xy 384.804667 -236.480922) (xy 384.79289 -236.433138) (xy 384.78893 -236.384084)
			(xy 384.460242 -236.384084) (xy 384.459747 -236.408691) (xy 384.451852 -236.457268) (xy 384.436268 -236.503949)
			(xy 384.413397 -236.547526) (xy 384.383832 -236.58687) (xy 384.348339 -236.620962) (xy 384.307836 -236.648918)
			(xy 384.263374 -236.670016) (xy 384.216103 -236.683708) (xy 384.167248 -236.68964) (xy 384.118073 -236.687659)
			(xy 384.069854 -236.677815) (xy 384.023838 -236.660363) (xy 383.981217 -236.635756) (xy 383.943096 -236.604631)
			(xy 383.910461 -236.567794) (xy 383.884158 -236.526198) (xy 383.864867 -236.480922) (xy 383.85309 -236.433138)
			(xy 383.84913 -236.384084) (xy 383.520188 -236.384084) (xy 383.519693 -236.408691) (xy 383.511798 -236.457268)
			(xy 383.496214 -236.503949) (xy 383.473343 -236.547526) (xy 383.443778 -236.58687) (xy 383.408285 -236.620962)
			(xy 383.367782 -236.648918) (xy 383.32332 -236.670016) (xy 383.276049 -236.683708) (xy 383.227194 -236.68964)
			(xy 383.178019 -236.687659) (xy 383.1298 -236.677815) (xy 383.083784 -236.660363) (xy 383.041163 -236.635756)
			(xy 383.003042 -236.604631) (xy 382.970407 -236.567794) (xy 382.944104 -236.526198) (xy 382.924813 -236.480922)
			(xy 382.913036 -236.433138) (xy 382.909076 -236.384084) (xy 382.580134 -236.384084) (xy 382.579639 -236.408691)
			(xy 382.571744 -236.457268) (xy 382.55616 -236.503949) (xy 382.533289 -236.547526) (xy 382.503724 -236.58687)
			(xy 382.468231 -236.620962) (xy 382.427728 -236.648918) (xy 382.383266 -236.670016) (xy 382.335995 -236.683708)
			(xy 382.28714 -236.68964) (xy 382.237965 -236.687659) (xy 382.189746 -236.677815) (xy 382.14373 -236.660363)
			(xy 382.101109 -236.635756) (xy 382.062988 -236.604631) (xy 382.030353 -236.567794) (xy 382.00405 -236.526198)
			(xy 381.984759 -236.480922) (xy 381.972982 -236.433138) (xy 381.969022 -236.384084) (xy 381.64008 -236.384084)
			(xy 381.639585 -236.408691) (xy 381.63169 -236.457268) (xy 381.616106 -236.503949) (xy 381.593235 -236.547526)
			(xy 381.56367 -236.58687) (xy 381.528177 -236.620962) (xy 381.487674 -236.648918) (xy 381.443212 -236.670016)
			(xy 381.395941 -236.683708) (xy 381.347086 -236.68964) (xy 381.297911 -236.687659) (xy 381.249692 -236.677815)
			(xy 381.203676 -236.660363) (xy 381.161055 -236.635756) (xy 381.122934 -236.604631) (xy 381.090299 -236.567794)
			(xy 381.063996 -236.526198) (xy 381.044705 -236.480922) (xy 381.032928 -236.433138) (xy 381.028968 -236.384084)
			(xy 380.71044 -236.384084) (xy 380.709928 -236.40953) (xy 380.701764 -236.459764) (xy 380.685648 -236.508038)
			(xy 380.661997 -236.553101) (xy 380.631424 -236.593787) (xy 380.59472 -236.629042) (xy 380.552836 -236.657952)
			(xy 380.506857 -236.679769) (xy 380.457973 -236.693929) (xy 380.407452 -236.700063) (xy 380.3566 -236.698014)
			(xy 380.306736 -236.687834) (xy 380.25915 -236.669787) (xy 380.215076 -236.644341) (xy 380.175654 -236.612154)
			(xy 380.141906 -236.57406) (xy 380.114705 -236.531046) (xy 380.094757 -236.484226) (xy 380.082578 -236.434812)
			(xy 380.078483 -236.384084) (xy 379.77064 -236.384084) (xy 379.770128 -236.40953) (xy 379.761964 -236.459764)
			(xy 379.745848 -236.508038) (xy 379.722197 -236.553101) (xy 379.691624 -236.593787) (xy 379.65492 -236.629042)
			(xy 379.613036 -236.657952) (xy 379.567057 -236.679769) (xy 379.518173 -236.693929) (xy 379.467652 -236.700063)
			(xy 379.4168 -236.698014) (xy 379.366936 -236.687834) (xy 379.31935 -236.669787) (xy 379.275276 -236.644341)
			(xy 379.235854 -236.612154) (xy 379.202106 -236.57406) (xy 379.174905 -236.531046) (xy 379.154957 -236.484226)
			(xy 379.142778 -236.434812) (xy 379.138683 -236.384084) (xy 378.820172 -236.384084) (xy 378.819677 -236.408691)
			(xy 378.811782 -236.457268) (xy 378.796198 -236.503949) (xy 378.773327 -236.547526) (xy 378.743762 -236.58687)
			(xy 378.708269 -236.620962) (xy 378.667766 -236.648918) (xy 378.623304 -236.670016) (xy 378.576033 -236.683708)
			(xy 378.527178 -236.68964) (xy 378.478003 -236.687659) (xy 378.429784 -236.677815) (xy 378.383768 -236.660363)
			(xy 378.341147 -236.635756) (xy 378.303026 -236.604631) (xy 378.270391 -236.567794) (xy 378.244088 -236.526198)
			(xy 378.224797 -236.480922) (xy 378.21302 -236.433138) (xy 378.20906 -236.384084) (xy 377.890532 -236.384084)
			(xy 377.89002 -236.40953) (xy 377.881856 -236.459764) (xy 377.86574 -236.508038) (xy 377.842089 -236.553101)
			(xy 377.811516 -236.593787) (xy 377.774812 -236.629042) (xy 377.732928 -236.657952) (xy 377.686949 -236.679769)
			(xy 377.638065 -236.693929) (xy 377.587544 -236.700063) (xy 377.536692 -236.698014) (xy 377.486828 -236.687834)
			(xy 377.439242 -236.669787) (xy 377.395168 -236.644341) (xy 377.355746 -236.612154) (xy 377.321998 -236.57406)
			(xy 377.294797 -236.531046) (xy 377.274849 -236.484226) (xy 377.26267 -236.434812) (xy 377.258575 -236.384084)
			(xy 376.940064 -236.384084) (xy 376.939569 -236.408691) (xy 376.931674 -236.457268) (xy 376.91609 -236.503949)
			(xy 376.893219 -236.547526) (xy 376.863654 -236.58687) (xy 376.828161 -236.620962) (xy 376.787658 -236.648918)
			(xy 376.743196 -236.670016) (xy 376.695925 -236.683708) (xy 376.64707 -236.68964) (xy 376.597895 -236.687659)
			(xy 376.549676 -236.677815) (xy 376.50366 -236.660363) (xy 376.461039 -236.635756) (xy 376.422918 -236.604631)
			(xy 376.390283 -236.567794) (xy 376.36398 -236.526198) (xy 376.344689 -236.480922) (xy 376.332912 -236.433138)
			(xy 376.328952 -236.384084) (xy 376.010424 -236.384084) (xy 376.009912 -236.40953) (xy 376.001748 -236.459764)
			(xy 375.985632 -236.508038) (xy 375.961981 -236.553101) (xy 375.931408 -236.593787) (xy 375.894704 -236.629042)
			(xy 375.85282 -236.657952) (xy 375.806841 -236.679769) (xy 375.757957 -236.693929) (xy 375.707436 -236.700063)
			(xy 375.656584 -236.698014) (xy 375.60672 -236.687834) (xy 375.559134 -236.669787) (xy 375.51506 -236.644341)
			(xy 375.475638 -236.612154) (xy 375.44189 -236.57406) (xy 375.414689 -236.531046) (xy 375.394741 -236.484226)
			(xy 375.382562 -236.434812) (xy 375.378467 -236.384084) (xy 375.06021 -236.384084) (xy 375.059893 -236.403743)
			(xy 375.054802 -236.44273) (xy 375.05005 -236.461808) (xy 375.046748 -236.475016) (xy 375.053606 -236.500924)
			(xy 375.699782 -237.1471) (xy 375.706198 -237.152994) (xy 375.721942 -237.160424) (xy 375.739268 -237.162121)
			(xy 375.747788 -237.160308) (xy 375.83872 -237.137702) (xy 375.858024 -237.11916) (xy 375.861834 -237.105952)
			(xy 375.869405 -237.081678) (xy 375.891214 -237.035749) (xy 375.920107 -236.993913) (xy 375.955337 -236.957252)
			(xy 375.995991 -236.926718) (xy 376.041016 -236.903099) (xy 376.089247 -236.887008) (xy 376.139434 -236.878862)
			(xy 376.164856 -236.878368) (xy 376.189671 -236.878826) (xy 376.23869 -236.886584) (xy 376.285891 -236.901915)
			(xy 376.330113 -236.924441) (xy 376.370267 -236.953609) (xy 376.405362 -236.9887) (xy 376.434536 -237.028849)
			(xy 376.457069 -237.073068) (xy 376.472406 -237.120268) (xy 376.48017 -237.169285) (xy 376.48017 -237.19409)
			(xy 376.788675 -237.19409) (xy 376.79277 -237.143362) (xy 376.804949 -237.093948) (xy 376.824897 -237.047128)
			(xy 376.852098 -237.004114) (xy 376.885846 -236.96602) (xy 376.925268 -236.933833) (xy 376.969342 -236.908387)
			(xy 377.016928 -236.89034) (xy 377.066792 -236.88016) (xy 377.117644 -236.878111) (xy 377.168165 -236.884245)
			(xy 377.217049 -236.898405) (xy 377.263028 -236.920222) (xy 377.304912 -236.949132) (xy 377.341616 -236.984387)
			(xy 377.372189 -237.025073) (xy 377.39584 -237.070136) (xy 377.411956 -237.11841) (xy 377.42012 -237.168644)
			(xy 377.420632 -237.19409) (xy 378.668529 -237.19409) (xy 378.672624 -237.143362) (xy 378.684803 -237.093948)
			(xy 378.704751 -237.047128) (xy 378.731952 -237.004114) (xy 378.7657 -236.96602) (xy 378.805122 -236.933833)
			(xy 378.849196 -236.908387) (xy 378.896782 -236.89034) (xy 378.946646 -236.88016) (xy 378.997498 -236.878111)
			(xy 379.048019 -236.884245) (xy 379.096903 -236.898405) (xy 379.142882 -236.920222) (xy 379.184766 -236.949132)
			(xy 379.22147 -236.984387) (xy 379.252043 -237.025073) (xy 379.275694 -237.070136) (xy 379.29181 -237.11841)
			(xy 379.299974 -237.168644) (xy 379.300486 -237.19409) (xy 379.619014 -237.19409) (xy 379.622974 -237.145036)
			(xy 379.634751 -237.097252) (xy 379.654042 -237.051976) (xy 379.680345 -237.01038) (xy 379.71298 -236.973543)
			(xy 379.751101 -236.942418) (xy 379.793722 -236.917811) (xy 379.839738 -236.900359) (xy 379.887957 -236.890515)
			(xy 379.937132 -236.888534) (xy 379.985987 -236.894466) (xy 380.033258 -236.908158) (xy 380.07772 -236.929256)
			(xy 380.118223 -236.957212) (xy 380.153716 -236.991304) (xy 380.183281 -237.030648) (xy 380.206152 -237.074225)
			(xy 380.221736 -237.120906) (xy 380.229631 -237.169483) (xy 380.230126 -237.19409) (xy 380.548637 -237.19409)
			(xy 380.552732 -237.143362) (xy 380.564911 -237.093948) (xy 380.584859 -237.047128) (xy 380.61206 -237.004114)
			(xy 380.645808 -236.96602) (xy 380.68523 -236.933833) (xy 380.729304 -236.908387) (xy 380.77689 -236.89034)
			(xy 380.826754 -236.88016) (xy 380.877606 -236.878111) (xy 380.928127 -236.884245) (xy 380.977011 -236.898405)
			(xy 381.02299 -236.920222) (xy 381.064874 -236.949132) (xy 381.101578 -236.984387) (xy 381.132151 -237.025073)
			(xy 381.155802 -237.070136) (xy 381.171918 -237.11841) (xy 381.180082 -237.168644) (xy 381.180594 -237.19409)
			(xy 381.499122 -237.19409) (xy 381.503082 -237.145036) (xy 381.514859 -237.097252) (xy 381.53415 -237.051976)
			(xy 381.560453 -237.01038) (xy 381.593088 -236.973543) (xy 381.631209 -236.942418) (xy 381.67383 -236.917811)
			(xy 381.719846 -236.900359) (xy 381.768065 -236.890515) (xy 381.81724 -236.888534) (xy 381.866095 -236.894466)
			(xy 381.913366 -236.908158) (xy 381.957828 -236.929256) (xy 381.998331 -236.957212) (xy 382.033824 -236.991304)
			(xy 382.063389 -237.030648) (xy 382.08626 -237.074225) (xy 382.101844 -237.120906) (xy 382.109739 -237.169483)
			(xy 382.110234 -237.19409) (xy 382.438922 -237.19409) (xy 382.442882 -237.145036) (xy 382.454659 -237.097252)
			(xy 382.47395 -237.051976) (xy 382.500253 -237.01038) (xy 382.532888 -236.973543) (xy 382.571009 -236.942418)
			(xy 382.61363 -236.917811) (xy 382.659646 -236.900359) (xy 382.707865 -236.890515) (xy 382.75704 -236.888534)
			(xy 382.805895 -236.894466) (xy 382.853166 -236.908158) (xy 382.897628 -236.929256) (xy 382.938131 -236.957212)
			(xy 382.973624 -236.991304) (xy 383.003189 -237.030648) (xy 383.02606 -237.074225) (xy 383.041644 -237.120906)
			(xy 383.049539 -237.169483) (xy 383.050034 -237.19409) (xy 383.378976 -237.19409) (xy 383.382936 -237.145036)
			(xy 383.394713 -237.097252) (xy 383.414004 -237.051976) (xy 383.440307 -237.01038) (xy 383.472942 -236.973543)
			(xy 383.511063 -236.942418) (xy 383.553684 -236.917811) (xy 383.5997 -236.900359) (xy 383.647919 -236.890515)
			(xy 383.697094 -236.888534) (xy 383.745949 -236.894466) (xy 383.79322 -236.908158) (xy 383.837682 -236.929256)
			(xy 383.878185 -236.957212) (xy 383.913678 -236.991304) (xy 383.943243 -237.030648) (xy 383.966114 -237.074225)
			(xy 383.981698 -237.120906) (xy 383.989593 -237.169483) (xy 383.990088 -237.19409) (xy 385.259084 -237.19409)
			(xy 385.263044 -237.145036) (xy 385.274821 -237.097252) (xy 385.294112 -237.051976) (xy 385.320415 -237.01038)
			(xy 385.35305 -236.973543) (xy 385.391171 -236.942418) (xy 385.433792 -236.917811) (xy 385.479808 -236.900359)
			(xy 385.528027 -236.890515) (xy 385.577202 -236.888534) (xy 385.626057 -236.894466) (xy 385.673328 -236.908158)
			(xy 385.71779 -236.929256) (xy 385.758293 -236.957212) (xy 385.793786 -236.991304) (xy 385.823351 -237.030648)
			(xy 385.846222 -237.074225) (xy 385.861806 -237.120906) (xy 385.869701 -237.169483) (xy 385.870196 -237.19409)
			(xy 386.199138 -237.19409) (xy 386.203098 -237.145036) (xy 386.214875 -237.097252) (xy 386.234166 -237.051976)
			(xy 386.260469 -237.01038) (xy 386.293104 -236.973543) (xy 386.331225 -236.942418) (xy 386.373846 -236.917811)
			(xy 386.419862 -236.900359) (xy 386.468081 -236.890515) (xy 386.517256 -236.888534) (xy 386.566111 -236.894466)
			(xy 386.613382 -236.908158) (xy 386.657844 -236.929256) (xy 386.698347 -236.957212) (xy 386.73384 -236.991304)
			(xy 386.763405 -237.030648) (xy 386.786276 -237.074225) (xy 386.80186 -237.120906) (xy 386.809755 -237.169483)
			(xy 386.81025 -237.19409) (xy 386.809755 -237.218697) (xy 386.80186 -237.267274) (xy 386.786276 -237.313955)
			(xy 386.763405 -237.357532) (xy 386.73384 -237.396876) (xy 386.698347 -237.430968) (xy 386.657844 -237.458924)
			(xy 386.613382 -237.480022) (xy 386.566111 -237.493714) (xy 386.517256 -237.499646) (xy 386.468081 -237.497665)
			(xy 386.419862 -237.487821) (xy 386.373846 -237.470369) (xy 386.331225 -237.445762) (xy 386.293104 -237.414637)
			(xy 386.260469 -237.3778) (xy 386.234166 -237.336204) (xy 386.214875 -237.290928) (xy 386.203098 -237.243144)
			(xy 386.199138 -237.19409) (xy 385.870196 -237.19409) (xy 385.869701 -237.218697) (xy 385.861806 -237.267274)
			(xy 385.846222 -237.313955) (xy 385.823351 -237.357532) (xy 385.793786 -237.396876) (xy 385.758293 -237.430968)
			(xy 385.71779 -237.458924) (xy 385.673328 -237.480022) (xy 385.626057 -237.493714) (xy 385.577202 -237.499646)
			(xy 385.528027 -237.497665) (xy 385.479808 -237.487821) (xy 385.433792 -237.470369) (xy 385.391171 -237.445762)
			(xy 385.35305 -237.414637) (xy 385.320415 -237.3778) (xy 385.294112 -237.336204) (xy 385.274821 -237.290928)
			(xy 385.263044 -237.243144) (xy 385.259084 -237.19409) (xy 383.990088 -237.19409) (xy 383.989593 -237.218697)
			(xy 383.981698 -237.267274) (xy 383.966114 -237.313955) (xy 383.943243 -237.357532) (xy 383.913678 -237.396876)
			(xy 383.878185 -237.430968) (xy 383.837682 -237.458924) (xy 383.79322 -237.480022) (xy 383.745949 -237.493714)
			(xy 383.697094 -237.499646) (xy 383.647919 -237.497665) (xy 383.5997 -237.487821) (xy 383.553684 -237.470369)
			(xy 383.511063 -237.445762) (xy 383.472942 -237.414637) (xy 383.440307 -237.3778) (xy 383.414004 -237.336204)
			(xy 383.394713 -237.290928) (xy 383.382936 -237.243144) (xy 383.378976 -237.19409) (xy 383.050034 -237.19409)
			(xy 383.049539 -237.218697) (xy 383.041644 -237.267274) (xy 383.02606 -237.313955) (xy 383.003189 -237.357532)
			(xy 382.973624 -237.396876) (xy 382.938131 -237.430968) (xy 382.897628 -237.458924) (xy 382.853166 -237.480022)
			(xy 382.805895 -237.493714) (xy 382.75704 -237.499646) (xy 382.707865 -237.497665) (xy 382.659646 -237.487821)
			(xy 382.61363 -237.470369) (xy 382.571009 -237.445762) (xy 382.532888 -237.414637) (xy 382.500253 -237.3778)
			(xy 382.47395 -237.336204) (xy 382.454659 -237.290928) (xy 382.442882 -237.243144) (xy 382.438922 -237.19409)
			(xy 382.110234 -237.19409) (xy 382.109739 -237.218697) (xy 382.101844 -237.267274) (xy 382.08626 -237.313955)
			(xy 382.063389 -237.357532) (xy 382.033824 -237.396876) (xy 381.998331 -237.430968) (xy 381.957828 -237.458924)
			(xy 381.913366 -237.480022) (xy 381.866095 -237.493714) (xy 381.81724 -237.499646) (xy 381.768065 -237.497665)
			(xy 381.719846 -237.487821) (xy 381.67383 -237.470369) (xy 381.631209 -237.445762) (xy 381.593088 -237.414637)
			(xy 381.560453 -237.3778) (xy 381.53415 -237.336204) (xy 381.514859 -237.290928) (xy 381.503082 -237.243144)
			(xy 381.499122 -237.19409) (xy 381.180594 -237.19409) (xy 381.180082 -237.219536) (xy 381.171918 -237.26977)
			(xy 381.155802 -237.318044) (xy 381.132151 -237.363107) (xy 381.101578 -237.403793) (xy 381.064874 -237.439048)
			(xy 381.02299 -237.467958) (xy 380.977011 -237.489775) (xy 380.928127 -237.503935) (xy 380.877606 -237.510069)
			(xy 380.826754 -237.50802) (xy 380.77689 -237.49784) (xy 380.729304 -237.479793) (xy 380.68523 -237.454347)
			(xy 380.645808 -237.42216) (xy 380.61206 -237.384066) (xy 380.584859 -237.341052) (xy 380.564911 -237.294232)
			(xy 380.552732 -237.244818) (xy 380.548637 -237.19409) (xy 380.230126 -237.19409) (xy 380.229631 -237.218697)
			(xy 380.221736 -237.267274) (xy 380.206152 -237.313955) (xy 380.183281 -237.357532) (xy 380.153716 -237.396876)
			(xy 380.118223 -237.430968) (xy 380.07772 -237.458924) (xy 380.033258 -237.480022) (xy 379.985987 -237.493714)
			(xy 379.937132 -237.499646) (xy 379.887957 -237.497665) (xy 379.839738 -237.487821) (xy 379.793722 -237.470369)
			(xy 379.751101 -237.445762) (xy 379.71298 -237.414637) (xy 379.680345 -237.3778) (xy 379.654042 -237.336204)
			(xy 379.634751 -237.290928) (xy 379.622974 -237.243144) (xy 379.619014 -237.19409) (xy 379.300486 -237.19409)
			(xy 379.299974 -237.219536) (xy 379.29181 -237.26977) (xy 379.275694 -237.318044) (xy 379.252043 -237.363107)
			(xy 379.22147 -237.403793) (xy 379.184766 -237.439048) (xy 379.142882 -237.467958) (xy 379.096903 -237.489775)
			(xy 379.048019 -237.503935) (xy 378.997498 -237.510069) (xy 378.946646 -237.50802) (xy 378.896782 -237.49784)
			(xy 378.849196 -237.479793) (xy 378.805122 -237.454347) (xy 378.7657 -237.42216) (xy 378.731952 -237.384066)
			(xy 378.704751 -237.341052) (xy 378.684803 -237.294232) (xy 378.672624 -237.244818) (xy 378.668529 -237.19409)
			(xy 377.420632 -237.19409) (xy 377.42012 -237.219536) (xy 377.411956 -237.26977) (xy 377.39584 -237.318044)
			(xy 377.372189 -237.363107) (xy 377.341616 -237.403793) (xy 377.304912 -237.439048) (xy 377.263028 -237.467958)
			(xy 377.217049 -237.489775) (xy 377.168165 -237.503935) (xy 377.117644 -237.510069) (xy 377.066792 -237.50802)
			(xy 377.016928 -237.49784) (xy 376.969342 -237.479793) (xy 376.925268 -237.454347) (xy 376.885846 -237.42216)
			(xy 376.852098 -237.384066) (xy 376.824897 -237.341052) (xy 376.804949 -237.294232) (xy 376.79277 -237.244818)
			(xy 376.788675 -237.19409) (xy 376.48017 -237.19409) (xy 376.48017 -237.218915) (xy 376.472406 -237.267932)
			(xy 376.457069 -237.315132) (xy 376.434536 -237.359351) (xy 376.405362 -237.3995) (xy 376.370267 -237.434591)
			(xy 376.330113 -237.463759) (xy 376.285891 -237.486285) (xy 376.23869 -237.501616) (xy 376.189671 -237.509374)
			(xy 376.164856 -237.509812) (xy 376.137982 -237.509256) (xy 376.085016 -237.500118) (xy 376.034366 -237.48213)
			(xy 376.010678 -237.469426) (xy 376.00001 -237.463584) (xy 375.975626 -237.462568) (xy 375.904252 -237.495842)
			(xy 375.89373 -237.50138) (xy 375.87889 -237.51992) (xy 375.875804 -237.531402) (xy 375.867743 -237.56803)
			(xy 375.848685 -237.640575) (xy 375.837704 -237.676436) (xy 375.83483 -237.687381) (xy 375.837854 -237.709777)
			(xy 375.85023 -237.728685) (xy 375.859548 -237.73511) (xy 375.882177 -237.749604) (xy 375.92259 -237.785022)
			(xy 375.956426 -237.826767) (xy 375.982709 -237.873636) (xy 376.000682 -237.924277) (xy 376.009827 -237.977229)
			(xy 376.010424 -238.004096) (xy 376.328952 -238.004096) (xy 376.332912 -237.955042) (xy 376.344689 -237.907258)
			(xy 376.36398 -237.861982) (xy 376.390283 -237.820386) (xy 376.422918 -237.783549) (xy 376.461039 -237.752424)
			(xy 376.50366 -237.727817) (xy 376.549676 -237.710365) (xy 376.597895 -237.700521) (xy 376.64707 -237.69854)
			(xy 376.695925 -237.704472) (xy 376.743196 -237.718164) (xy 376.787658 -237.739262) (xy 376.828161 -237.767218)
			(xy 376.863654 -237.80131) (xy 376.893219 -237.840654) (xy 376.91609 -237.884231) (xy 376.931674 -237.930912)
			(xy 376.939569 -237.979489) (xy 376.940064 -238.004096) (xy 377.258575 -238.004096) (xy 377.26267 -237.953368)
			(xy 377.274849 -237.903954) (xy 377.294797 -237.857134) (xy 377.321998 -237.81412) (xy 377.355746 -237.776026)
			(xy 377.395168 -237.743839) (xy 377.439242 -237.718393) (xy 377.486828 -237.700346) (xy 377.536692 -237.690166)
			(xy 377.587544 -237.688117) (xy 377.638065 -237.694251) (xy 377.686949 -237.708411) (xy 377.732928 -237.730228)
			(xy 377.774812 -237.759138) (xy 377.811516 -237.794393) (xy 377.842089 -237.835079) (xy 377.86574 -237.880142)
			(xy 377.881856 -237.928416) (xy 377.89002 -237.97865) (xy 377.890532 -238.004096) (xy 378.20906 -238.004096)
			(xy 378.21302 -237.955042) (xy 378.224797 -237.907258) (xy 378.244088 -237.861982) (xy 378.270391 -237.820386)
			(xy 378.303026 -237.783549) (xy 378.341147 -237.752424) (xy 378.383768 -237.727817) (xy 378.429784 -237.710365)
			(xy 378.478003 -237.700521) (xy 378.527178 -237.69854) (xy 378.576033 -237.704472) (xy 378.623304 -237.718164)
			(xy 378.667766 -237.739262) (xy 378.708269 -237.767218) (xy 378.743762 -237.80131) (xy 378.773327 -237.840654)
			(xy 378.796198 -237.884231) (xy 378.811782 -237.930912) (xy 378.819677 -237.979489) (xy 378.820172 -238.004096)
			(xy 379.138683 -238.004096) (xy 379.142778 -237.953368) (xy 379.154957 -237.903954) (xy 379.174905 -237.857134)
			(xy 379.202106 -237.81412) (xy 379.235854 -237.776026) (xy 379.275276 -237.743839) (xy 379.31935 -237.718393)
			(xy 379.366936 -237.700346) (xy 379.4168 -237.690166) (xy 379.467652 -237.688117) (xy 379.518173 -237.694251)
			(xy 379.567057 -237.708411) (xy 379.613036 -237.730228) (xy 379.65492 -237.759138) (xy 379.691624 -237.794393)
			(xy 379.722197 -237.835079) (xy 379.745848 -237.880142) (xy 379.761964 -237.928416) (xy 379.770128 -237.97865)
			(xy 379.77064 -238.004096) (xy 380.078483 -238.004096) (xy 380.082578 -237.953368) (xy 380.094757 -237.903954)
			(xy 380.114705 -237.857134) (xy 380.141906 -237.81412) (xy 380.175654 -237.776026) (xy 380.215076 -237.743839)
			(xy 380.25915 -237.718393) (xy 380.306736 -237.700346) (xy 380.3566 -237.690166) (xy 380.407452 -237.688117)
			(xy 380.457973 -237.694251) (xy 380.506857 -237.708411) (xy 380.552836 -237.730228) (xy 380.59472 -237.759138)
			(xy 380.631424 -237.794393) (xy 380.661997 -237.835079) (xy 380.685648 -237.880142) (xy 380.701764 -237.928416)
			(xy 380.709928 -237.97865) (xy 380.71044 -238.004096) (xy 381.028968 -238.004096) (xy 381.032928 -237.955042)
			(xy 381.044705 -237.907258) (xy 381.063996 -237.861982) (xy 381.090299 -237.820386) (xy 381.122934 -237.783549)
			(xy 381.161055 -237.752424) (xy 381.203676 -237.727817) (xy 381.249692 -237.710365) (xy 381.297911 -237.700521)
			(xy 381.347086 -237.69854) (xy 381.395941 -237.704472) (xy 381.443212 -237.718164) (xy 381.487674 -237.739262)
			(xy 381.528177 -237.767218) (xy 381.56367 -237.80131) (xy 381.593235 -237.840654) (xy 381.616106 -237.884231)
			(xy 381.63169 -237.930912) (xy 381.639585 -237.979489) (xy 381.64008 -238.004096) (xy 381.969022 -238.004096)
			(xy 381.972982 -237.955042) (xy 381.984759 -237.907258) (xy 382.00405 -237.861982) (xy 382.030353 -237.820386)
			(xy 382.062988 -237.783549) (xy 382.101109 -237.752424) (xy 382.14373 -237.727817) (xy 382.189746 -237.710365)
			(xy 382.237965 -237.700521) (xy 382.28714 -237.69854) (xy 382.335995 -237.704472) (xy 382.383266 -237.718164)
			(xy 382.427728 -237.739262) (xy 382.468231 -237.767218) (xy 382.503724 -237.80131) (xy 382.533289 -237.840654)
			(xy 382.55616 -237.884231) (xy 382.571744 -237.930912) (xy 382.579639 -237.979489) (xy 382.580134 -238.004096)
			(xy 382.909076 -238.004096) (xy 382.913036 -237.955042) (xy 382.924813 -237.907258) (xy 382.944104 -237.861982)
			(xy 382.970407 -237.820386) (xy 383.003042 -237.783549) (xy 383.041163 -237.752424) (xy 383.083784 -237.727817)
			(xy 383.1298 -237.710365) (xy 383.178019 -237.700521) (xy 383.227194 -237.69854) (xy 383.276049 -237.704472)
			(xy 383.32332 -237.718164) (xy 383.367782 -237.739262) (xy 383.408285 -237.767218) (xy 383.443778 -237.80131)
			(xy 383.473343 -237.840654) (xy 383.496214 -237.884231) (xy 383.511798 -237.930912) (xy 383.519693 -237.979489)
			(xy 383.520188 -238.004096) (xy 383.84913 -238.004096) (xy 383.85309 -237.955042) (xy 383.864867 -237.907258)
			(xy 383.884158 -237.861982) (xy 383.910461 -237.820386) (xy 383.943096 -237.783549) (xy 383.981217 -237.752424)
			(xy 384.023838 -237.727817) (xy 384.069854 -237.710365) (xy 384.118073 -237.700521) (xy 384.167248 -237.69854)
			(xy 384.216103 -237.704472) (xy 384.263374 -237.718164) (xy 384.307836 -237.739262) (xy 384.348339 -237.767218)
			(xy 384.383832 -237.80131) (xy 384.413397 -237.840654) (xy 384.436268 -237.884231) (xy 384.451852 -237.930912)
			(xy 384.459747 -237.979489) (xy 384.460242 -238.004096) (xy 384.78893 -238.004096) (xy 384.79289 -237.955042)
			(xy 384.804667 -237.907258) (xy 384.823958 -237.861982) (xy 384.850261 -237.820386) (xy 384.882896 -237.783549)
			(xy 384.921017 -237.752424) (xy 384.963638 -237.727817) (xy 385.009654 -237.710365) (xy 385.057873 -237.700521)
			(xy 385.107048 -237.69854) (xy 385.155903 -237.704472) (xy 385.203174 -237.718164) (xy 385.247636 -237.739262)
			(xy 385.288139 -237.767218) (xy 385.323632 -237.80131) (xy 385.353197 -237.840654) (xy 385.376068 -237.884231)
			(xy 385.391652 -237.930912) (xy 385.399547 -237.979489) (xy 385.400042 -238.004096) (xy 385.728984 -238.004096)
			(xy 385.732944 -237.955042) (xy 385.744721 -237.907258) (xy 385.764012 -237.861982) (xy 385.790315 -237.820386)
			(xy 385.82295 -237.783549) (xy 385.861071 -237.752424) (xy 385.903692 -237.727817) (xy 385.949708 -237.710365)
			(xy 385.997927 -237.700521) (xy 386.047102 -237.69854) (xy 386.095957 -237.704472) (xy 386.143228 -237.718164)
			(xy 386.18769 -237.739262) (xy 386.228193 -237.767218) (xy 386.263686 -237.80131) (xy 386.293251 -237.840654)
			(xy 386.316122 -237.884231) (xy 386.331706 -237.930912) (xy 386.339601 -237.979489) (xy 386.340096 -238.004096)
			(xy 386.669038 -238.004096) (xy 386.672998 -237.955042) (xy 386.684775 -237.907258) (xy 386.704066 -237.861982)
			(xy 386.730369 -237.820386) (xy 386.763004 -237.783549) (xy 386.801125 -237.752424) (xy 386.843746 -237.727817)
			(xy 386.889762 -237.710365) (xy 386.937981 -237.700521) (xy 386.987156 -237.69854) (xy 387.036011 -237.704472)
			(xy 387.083282 -237.718164) (xy 387.127744 -237.739262) (xy 387.168247 -237.767218) (xy 387.20374 -237.80131)
			(xy 387.233305 -237.840654) (xy 387.256176 -237.884231) (xy 387.27176 -237.930912) (xy 387.279655 -237.979489)
			(xy 387.28015 -238.004096) (xy 387.279655 -238.028703) (xy 387.27176 -238.07728) (xy 387.256176 -238.123961)
			(xy 387.233305 -238.167538) (xy 387.20374 -238.206882) (xy 387.168247 -238.240974) (xy 387.127744 -238.26893)
			(xy 387.083282 -238.290028) (xy 387.036011 -238.30372) (xy 386.987156 -238.309652) (xy 386.937981 -238.307671)
			(xy 386.889762 -238.297827) (xy 386.843746 -238.280375) (xy 386.801125 -238.255768) (xy 386.763004 -238.224643)
			(xy 386.730369 -238.187806) (xy 386.704066 -238.14621) (xy 386.684775 -238.100934) (xy 386.672998 -238.05315)
			(xy 386.669038 -238.004096) (xy 386.340096 -238.004096) (xy 386.339601 -238.028703) (xy 386.331706 -238.07728)
			(xy 386.316122 -238.123961) (xy 386.293251 -238.167538) (xy 386.263686 -238.206882) (xy 386.228193 -238.240974)
			(xy 386.18769 -238.26893) (xy 386.143228 -238.290028) (xy 386.095957 -238.30372) (xy 386.047102 -238.309652)
			(xy 385.997927 -238.307671) (xy 385.949708 -238.297827) (xy 385.903692 -238.280375) (xy 385.861071 -238.255768)
			(xy 385.82295 -238.224643) (xy 385.790315 -238.187806) (xy 385.764012 -238.14621) (xy 385.744721 -238.100934)
			(xy 385.732944 -238.05315) (xy 385.728984 -238.004096) (xy 385.400042 -238.004096) (xy 385.399547 -238.028703)
			(xy 385.391652 -238.07728) (xy 385.376068 -238.123961) (xy 385.353197 -238.167538) (xy 385.323632 -238.206882)
			(xy 385.288139 -238.240974) (xy 385.247636 -238.26893) (xy 385.203174 -238.290028) (xy 385.155903 -238.30372)
			(xy 385.107048 -238.309652) (xy 385.057873 -238.307671) (xy 385.009654 -238.297827) (xy 384.963638 -238.280375)
			(xy 384.921017 -238.255768) (xy 384.882896 -238.224643) (xy 384.850261 -238.187806) (xy 384.823958 -238.14621)
			(xy 384.804667 -238.100934) (xy 384.79289 -238.05315) (xy 384.78893 -238.004096) (xy 384.460242 -238.004096)
			(xy 384.459747 -238.028703) (xy 384.451852 -238.07728) (xy 384.436268 -238.123961) (xy 384.413397 -238.167538)
			(xy 384.383832 -238.206882) (xy 384.348339 -238.240974) (xy 384.307836 -238.26893) (xy 384.263374 -238.290028)
			(xy 384.216103 -238.30372) (xy 384.167248 -238.309652) (xy 384.118073 -238.307671) (xy 384.069854 -238.297827)
			(xy 384.023838 -238.280375) (xy 383.981217 -238.255768) (xy 383.943096 -238.224643) (xy 383.910461 -238.187806)
			(xy 383.884158 -238.14621) (xy 383.864867 -238.100934) (xy 383.85309 -238.05315) (xy 383.84913 -238.004096)
			(xy 383.520188 -238.004096) (xy 383.519693 -238.028703) (xy 383.511798 -238.07728) (xy 383.496214 -238.123961)
			(xy 383.473343 -238.167538) (xy 383.443778 -238.206882) (xy 383.408285 -238.240974) (xy 383.367782 -238.26893)
			(xy 383.32332 -238.290028) (xy 383.276049 -238.30372) (xy 383.227194 -238.309652) (xy 383.178019 -238.307671)
			(xy 383.1298 -238.297827) (xy 383.083784 -238.280375) (xy 383.041163 -238.255768) (xy 383.003042 -238.224643)
			(xy 382.970407 -238.187806) (xy 382.944104 -238.14621) (xy 382.924813 -238.100934) (xy 382.913036 -238.05315)
			(xy 382.909076 -238.004096) (xy 382.580134 -238.004096) (xy 382.579639 -238.028703) (xy 382.571744 -238.07728)
			(xy 382.55616 -238.123961) (xy 382.533289 -238.167538) (xy 382.503724 -238.206882) (xy 382.468231 -238.240974)
			(xy 382.427728 -238.26893) (xy 382.383266 -238.290028) (xy 382.335995 -238.30372) (xy 382.28714 -238.309652)
			(xy 382.237965 -238.307671) (xy 382.189746 -238.297827) (xy 382.14373 -238.280375) (xy 382.101109 -238.255768)
			(xy 382.062988 -238.224643) (xy 382.030353 -238.187806) (xy 382.00405 -238.14621) (xy 381.984759 -238.100934)
			(xy 381.972982 -238.05315) (xy 381.969022 -238.004096) (xy 381.64008 -238.004096) (xy 381.639585 -238.028703)
			(xy 381.63169 -238.07728) (xy 381.616106 -238.123961) (xy 381.593235 -238.167538) (xy 381.56367 -238.206882)
			(xy 381.528177 -238.240974) (xy 381.487674 -238.26893) (xy 381.443212 -238.290028) (xy 381.395941 -238.30372)
			(xy 381.347086 -238.309652) (xy 381.297911 -238.307671) (xy 381.249692 -238.297827) (xy 381.203676 -238.280375)
			(xy 381.161055 -238.255768) (xy 381.122934 -238.224643) (xy 381.090299 -238.187806) (xy 381.063996 -238.14621)
			(xy 381.044705 -238.100934) (xy 381.032928 -238.05315) (xy 381.028968 -238.004096) (xy 380.71044 -238.004096)
			(xy 380.709928 -238.029542) (xy 380.701764 -238.079776) (xy 380.685648 -238.12805) (xy 380.661997 -238.173113)
			(xy 380.631424 -238.213799) (xy 380.59472 -238.249054) (xy 380.552836 -238.277964) (xy 380.506857 -238.299781)
			(xy 380.457973 -238.313941) (xy 380.407452 -238.320075) (xy 380.3566 -238.318026) (xy 380.306736 -238.307846)
			(xy 380.25915 -238.289799) (xy 380.215076 -238.264353) (xy 380.175654 -238.232166) (xy 380.141906 -238.194072)
			(xy 380.114705 -238.151058) (xy 380.094757 -238.104238) (xy 380.082578 -238.054824) (xy 380.078483 -238.004096)
			(xy 379.77064 -238.004096) (xy 379.770128 -238.029542) (xy 379.761964 -238.079776) (xy 379.745848 -238.12805)
			(xy 379.722197 -238.173113) (xy 379.691624 -238.213799) (xy 379.65492 -238.249054) (xy 379.613036 -238.277964)
			(xy 379.567057 -238.299781) (xy 379.518173 -238.313941) (xy 379.467652 -238.320075) (xy 379.4168 -238.318026)
			(xy 379.366936 -238.307846) (xy 379.31935 -238.289799) (xy 379.275276 -238.264353) (xy 379.235854 -238.232166)
			(xy 379.202106 -238.194072) (xy 379.174905 -238.151058) (xy 379.154957 -238.104238) (xy 379.142778 -238.054824)
			(xy 379.138683 -238.004096) (xy 378.820172 -238.004096) (xy 378.819677 -238.028703) (xy 378.811782 -238.07728)
			(xy 378.796198 -238.123961) (xy 378.773327 -238.167538) (xy 378.743762 -238.206882) (xy 378.708269 -238.240974)
			(xy 378.667766 -238.26893) (xy 378.623304 -238.290028) (xy 378.576033 -238.30372) (xy 378.527178 -238.309652)
			(xy 378.478003 -238.307671) (xy 378.429784 -238.297827) (xy 378.383768 -238.280375) (xy 378.341147 -238.255768)
			(xy 378.303026 -238.224643) (xy 378.270391 -238.187806) (xy 378.244088 -238.14621) (xy 378.224797 -238.100934)
			(xy 378.21302 -238.05315) (xy 378.20906 -238.004096) (xy 377.890532 -238.004096) (xy 377.89002 -238.029542)
			(xy 377.881856 -238.079776) (xy 377.86574 -238.12805) (xy 377.842089 -238.173113) (xy 377.811516 -238.213799)
			(xy 377.774812 -238.249054) (xy 377.732928 -238.277964) (xy 377.686949 -238.299781) (xy 377.638065 -238.313941)
			(xy 377.587544 -238.320075) (xy 377.536692 -238.318026) (xy 377.486828 -238.307846) (xy 377.439242 -238.289799)
			(xy 377.395168 -238.264353) (xy 377.355746 -238.232166) (xy 377.321998 -238.194072) (xy 377.294797 -238.151058)
			(xy 377.274849 -238.104238) (xy 377.26267 -238.054824) (xy 377.258575 -238.004096) (xy 376.940064 -238.004096)
			(xy 376.939569 -238.028703) (xy 376.931674 -238.07728) (xy 376.91609 -238.123961) (xy 376.893219 -238.167538)
			(xy 376.863654 -238.206882) (xy 376.828161 -238.240974) (xy 376.787658 -238.26893) (xy 376.743196 -238.290028)
			(xy 376.695925 -238.30372) (xy 376.64707 -238.309652) (xy 376.597895 -238.307671) (xy 376.549676 -238.297827)
			(xy 376.50366 -238.280375) (xy 376.461039 -238.255768) (xy 376.422918 -238.224643) (xy 376.390283 -238.187806)
			(xy 376.36398 -238.14621) (xy 376.344689 -238.100934) (xy 376.332912 -238.05315) (xy 376.328952 -238.004096)
			(xy 376.010424 -238.004096) (xy 376.009884 -238.030957) (xy 376.000788 -238.083902) (xy 375.982859 -238.134543)
			(xy 375.956615 -238.181417) (xy 375.922813 -238.22317) (xy 375.882429 -238.258598) (xy 375.859802 -238.273082)
			(xy 375.850484 -238.279441) (xy 375.838087 -238.298254) (xy 375.834942 -238.320563) (xy 375.837704 -238.331502)
			(xy 375.84869 -238.367425) (xy 375.867748 -238.440098) (xy 375.875804 -238.47679) (xy 375.878902 -238.488267)
			(xy 375.893737 -238.506804) (xy 375.904252 -238.51235) (xy 375.976134 -238.545624) (xy 376.00001 -238.544608)
			(xy 376.010932 -238.538512) (xy 376.034623 -238.525938) (xy 376.085189 -238.508071) (xy 376.138042 -238.498979)
			(xy 376.164856 -238.49838) (xy 376.18967 -238.498838) (xy 376.238687 -238.506595) (xy 376.285887 -238.521926)
			(xy 376.330107 -238.544452) (xy 376.370259 -238.573618) (xy 376.405353 -238.608708) (xy 376.434525 -238.648855)
			(xy 376.457057 -238.693072) (xy 376.472394 -238.74027) (xy 376.480158 -238.789286) (xy 376.480158 -238.814102)
			(xy 376.788675 -238.814102) (xy 376.79277 -238.763374) (xy 376.804949 -238.71396) (xy 376.824897 -238.66714)
			(xy 376.852098 -238.624126) (xy 376.885846 -238.586032) (xy 376.925268 -238.553845) (xy 376.969342 -238.528399)
			(xy 377.016928 -238.510352) (xy 377.066792 -238.500172) (xy 377.117644 -238.498123) (xy 377.168165 -238.504257)
			(xy 377.217049 -238.518417) (xy 377.263028 -238.540234) (xy 377.304912 -238.569144) (xy 377.341616 -238.604399)
			(xy 377.372189 -238.645085) (xy 377.39584 -238.690148) (xy 377.411956 -238.738422) (xy 377.42012 -238.788656)
			(xy 377.420632 -238.814102) (xy 377.738906 -238.814102) (xy 377.742866 -238.765048) (xy 377.754643 -238.717264)
			(xy 377.773934 -238.671988) (xy 377.800237 -238.630392) (xy 377.832872 -238.593555) (xy 377.870993 -238.56243)
			(xy 377.913614 -238.537823) (xy 377.95963 -238.520371) (xy 378.007849 -238.510527) (xy 378.057024 -238.508546)
			(xy 378.105879 -238.514478) (xy 378.15315 -238.52817) (xy 378.197612 -238.549268) (xy 378.238115 -238.577224)
			(xy 378.273608 -238.611316) (xy 378.303173 -238.65066) (xy 378.326044 -238.694237) (xy 378.341628 -238.740918)
			(xy 378.349523 -238.789495) (xy 378.350018 -238.814102) (xy 378.668529 -238.814102) (xy 378.672624 -238.763374)
			(xy 378.684803 -238.71396) (xy 378.704751 -238.66714) (xy 378.731952 -238.624126) (xy 378.7657 -238.586032)
			(xy 378.805122 -238.553845) (xy 378.849196 -238.528399) (xy 378.896782 -238.510352) (xy 378.946646 -238.500172)
			(xy 378.997498 -238.498123) (xy 379.048019 -238.504257) (xy 379.096903 -238.518417) (xy 379.142882 -238.540234)
			(xy 379.184766 -238.569144) (xy 379.22147 -238.604399) (xy 379.252043 -238.645085) (xy 379.275694 -238.690148)
			(xy 379.29181 -238.738422) (xy 379.299974 -238.788656) (xy 379.300486 -238.814102) (xy 379.619014 -238.814102)
			(xy 379.622974 -238.765048) (xy 379.634751 -238.717264) (xy 379.654042 -238.671988) (xy 379.680345 -238.630392)
			(xy 379.71298 -238.593555) (xy 379.751101 -238.56243) (xy 379.793722 -238.537823) (xy 379.839738 -238.520371)
			(xy 379.887957 -238.510527) (xy 379.937132 -238.508546) (xy 379.985987 -238.514478) (xy 380.033258 -238.52817)
			(xy 380.07772 -238.549268) (xy 380.118223 -238.577224) (xy 380.153716 -238.611316) (xy 380.183281 -238.65066)
			(xy 380.206152 -238.694237) (xy 380.221736 -238.740918) (xy 380.229631 -238.789495) (xy 380.230126 -238.814102)
			(xy 380.548637 -238.814102) (xy 380.552732 -238.763374) (xy 380.564911 -238.71396) (xy 380.584859 -238.66714)
			(xy 380.61206 -238.624126) (xy 380.645808 -238.586032) (xy 380.68523 -238.553845) (xy 380.729304 -238.528399)
			(xy 380.77689 -238.510352) (xy 380.826754 -238.500172) (xy 380.877606 -238.498123) (xy 380.928127 -238.504257)
			(xy 380.977011 -238.518417) (xy 381.02299 -238.540234) (xy 381.064874 -238.569144) (xy 381.101578 -238.604399)
			(xy 381.132151 -238.645085) (xy 381.155802 -238.690148) (xy 381.171918 -238.738422) (xy 381.180082 -238.788656)
			(xy 381.180594 -238.814102) (xy 381.499122 -238.814102) (xy 381.503082 -238.765048) (xy 381.514859 -238.717264)
			(xy 381.53415 -238.671988) (xy 381.560453 -238.630392) (xy 381.593088 -238.593555) (xy 381.631209 -238.56243)
			(xy 381.67383 -238.537823) (xy 381.719846 -238.520371) (xy 381.768065 -238.510527) (xy 381.81724 -238.508546)
			(xy 381.866095 -238.514478) (xy 381.913366 -238.52817) (xy 381.957828 -238.549268) (xy 381.998331 -238.577224)
			(xy 382.033824 -238.611316) (xy 382.063389 -238.65066) (xy 382.08626 -238.694237) (xy 382.101844 -238.740918)
			(xy 382.109739 -238.789495) (xy 382.110234 -238.814102) (xy 382.438922 -238.814102) (xy 382.442882 -238.765048)
			(xy 382.454659 -238.717264) (xy 382.47395 -238.671988) (xy 382.500253 -238.630392) (xy 382.532888 -238.593555)
			(xy 382.571009 -238.56243) (xy 382.61363 -238.537823) (xy 382.659646 -238.520371) (xy 382.707865 -238.510527)
			(xy 382.75704 -238.508546) (xy 382.805895 -238.514478) (xy 382.853166 -238.52817) (xy 382.897628 -238.549268)
			(xy 382.938131 -238.577224) (xy 382.973624 -238.611316) (xy 383.003189 -238.65066) (xy 383.02606 -238.694237)
			(xy 383.041644 -238.740918) (xy 383.049539 -238.789495) (xy 383.050034 -238.814102) (xy 383.378976 -238.814102)
			(xy 383.382936 -238.765048) (xy 383.394713 -238.717264) (xy 383.414004 -238.671988) (xy 383.440307 -238.630392)
			(xy 383.472942 -238.593555) (xy 383.511063 -238.56243) (xy 383.553684 -238.537823) (xy 383.5997 -238.520371)
			(xy 383.647919 -238.510527) (xy 383.697094 -238.508546) (xy 383.745949 -238.514478) (xy 383.79322 -238.52817)
			(xy 383.837682 -238.549268) (xy 383.878185 -238.577224) (xy 383.913678 -238.611316) (xy 383.943243 -238.65066)
			(xy 383.966114 -238.694237) (xy 383.981698 -238.740918) (xy 383.989593 -238.789495) (xy 383.990088 -238.814102)
			(xy 384.31903 -238.814102) (xy 384.32299 -238.765048) (xy 384.334767 -238.717264) (xy 384.354058 -238.671988)
			(xy 384.380361 -238.630392) (xy 384.412996 -238.593555) (xy 384.451117 -238.56243) (xy 384.493738 -238.537823)
			(xy 384.539754 -238.520371) (xy 384.587973 -238.510527) (xy 384.637148 -238.508546) (xy 384.686003 -238.514478)
			(xy 384.733274 -238.52817) (xy 384.777736 -238.549268) (xy 384.818239 -238.577224) (xy 384.853732 -238.611316)
			(xy 384.883297 -238.65066) (xy 384.906168 -238.694237) (xy 384.921752 -238.740918) (xy 384.929647 -238.789495)
			(xy 384.930142 -238.814102) (xy 385.259084 -238.814102) (xy 385.263044 -238.765048) (xy 385.274821 -238.717264)
			(xy 385.294112 -238.671988) (xy 385.320415 -238.630392) (xy 385.35305 -238.593555) (xy 385.391171 -238.56243)
			(xy 385.433792 -238.537823) (xy 385.479808 -238.520371) (xy 385.528027 -238.510527) (xy 385.577202 -238.508546)
			(xy 385.626057 -238.514478) (xy 385.673328 -238.52817) (xy 385.71779 -238.549268) (xy 385.758293 -238.577224)
			(xy 385.793786 -238.611316) (xy 385.823351 -238.65066) (xy 385.846222 -238.694237) (xy 385.861806 -238.740918)
			(xy 385.869701 -238.789495) (xy 385.870196 -238.814102) (xy 386.199138 -238.814102) (xy 386.203098 -238.765048)
			(xy 386.214875 -238.717264) (xy 386.234166 -238.671988) (xy 386.260469 -238.630392) (xy 386.293104 -238.593555)
			(xy 386.331225 -238.56243) (xy 386.373846 -238.537823) (xy 386.419862 -238.520371) (xy 386.468081 -238.510527)
			(xy 386.517256 -238.508546) (xy 386.566111 -238.514478) (xy 386.613382 -238.52817) (xy 386.657844 -238.549268)
			(xy 386.698347 -238.577224) (xy 386.73384 -238.611316) (xy 386.763405 -238.65066) (xy 386.786276 -238.694237)
			(xy 386.80186 -238.740918) (xy 386.809755 -238.789495) (xy 386.81025 -238.814102) (xy 386.809755 -238.838709)
			(xy 386.80186 -238.887286) (xy 386.786276 -238.933967) (xy 386.763405 -238.977544) (xy 386.73384 -239.016888)
			(xy 386.698347 -239.05098) (xy 386.657844 -239.078936) (xy 386.613382 -239.100034) (xy 386.566111 -239.113726)
			(xy 386.517256 -239.119658) (xy 386.468081 -239.117677) (xy 386.419862 -239.107833) (xy 386.373846 -239.090381)
			(xy 386.331225 -239.065774) (xy 386.293104 -239.034649) (xy 386.260469 -238.997812) (xy 386.234166 -238.956216)
			(xy 386.214875 -238.91094) (xy 386.203098 -238.863156) (xy 386.199138 -238.814102) (xy 385.870196 -238.814102)
			(xy 385.869701 -238.838709) (xy 385.861806 -238.887286) (xy 385.846222 -238.933967) (xy 385.823351 -238.977544)
			(xy 385.793786 -239.016888) (xy 385.758293 -239.05098) (xy 385.71779 -239.078936) (xy 385.673328 -239.100034)
			(xy 385.626057 -239.113726) (xy 385.577202 -239.119658) (xy 385.528027 -239.117677) (xy 385.479808 -239.107833)
			(xy 385.433792 -239.090381) (xy 385.391171 -239.065774) (xy 385.35305 -239.034649) (xy 385.320415 -238.997812)
			(xy 385.294112 -238.956216) (xy 385.274821 -238.91094) (xy 385.263044 -238.863156) (xy 385.259084 -238.814102)
			(xy 384.930142 -238.814102) (xy 384.929647 -238.838709) (xy 384.921752 -238.887286) (xy 384.906168 -238.933967)
			(xy 384.883297 -238.977544) (xy 384.853732 -239.016888) (xy 384.818239 -239.05098) (xy 384.777736 -239.078936)
			(xy 384.733274 -239.100034) (xy 384.686003 -239.113726) (xy 384.637148 -239.119658) (xy 384.587973 -239.117677)
			(xy 384.539754 -239.107833) (xy 384.493738 -239.090381) (xy 384.451117 -239.065774) (xy 384.412996 -239.034649)
			(xy 384.380361 -238.997812) (xy 384.354058 -238.956216) (xy 384.334767 -238.91094) (xy 384.32299 -238.863156)
			(xy 384.31903 -238.814102) (xy 383.990088 -238.814102) (xy 383.989593 -238.838709) (xy 383.981698 -238.887286)
			(xy 383.966114 -238.933967) (xy 383.943243 -238.977544) (xy 383.913678 -239.016888) (xy 383.878185 -239.05098)
			(xy 383.837682 -239.078936) (xy 383.79322 -239.100034) (xy 383.745949 -239.113726) (xy 383.697094 -239.119658)
			(xy 383.647919 -239.117677) (xy 383.5997 -239.107833) (xy 383.553684 -239.090381) (xy 383.511063 -239.065774)
			(xy 383.472942 -239.034649) (xy 383.440307 -238.997812) (xy 383.414004 -238.956216) (xy 383.394713 -238.91094)
			(xy 383.382936 -238.863156) (xy 383.378976 -238.814102) (xy 383.050034 -238.814102) (xy 383.049539 -238.838709)
			(xy 383.041644 -238.887286) (xy 383.02606 -238.933967) (xy 383.003189 -238.977544) (xy 382.973624 -239.016888)
			(xy 382.938131 -239.05098) (xy 382.897628 -239.078936) (xy 382.853166 -239.100034) (xy 382.805895 -239.113726)
			(xy 382.75704 -239.119658) (xy 382.707865 -239.117677) (xy 382.659646 -239.107833) (xy 382.61363 -239.090381)
			(xy 382.571009 -239.065774) (xy 382.532888 -239.034649) (xy 382.500253 -238.997812) (xy 382.47395 -238.956216)
			(xy 382.454659 -238.91094) (xy 382.442882 -238.863156) (xy 382.438922 -238.814102) (xy 382.110234 -238.814102)
			(xy 382.109739 -238.838709) (xy 382.101844 -238.887286) (xy 382.08626 -238.933967) (xy 382.063389 -238.977544)
			(xy 382.033824 -239.016888) (xy 381.998331 -239.05098) (xy 381.957828 -239.078936) (xy 381.913366 -239.100034)
			(xy 381.866095 -239.113726) (xy 381.81724 -239.119658) (xy 381.768065 -239.117677) (xy 381.719846 -239.107833)
			(xy 381.67383 -239.090381) (xy 381.631209 -239.065774) (xy 381.593088 -239.034649) (xy 381.560453 -238.997812)
			(xy 381.53415 -238.956216) (xy 381.514859 -238.91094) (xy 381.503082 -238.863156) (xy 381.499122 -238.814102)
			(xy 381.180594 -238.814102) (xy 381.180082 -238.839548) (xy 381.171918 -238.889782) (xy 381.155802 -238.938056)
			(xy 381.132151 -238.983119) (xy 381.101578 -239.023805) (xy 381.064874 -239.05906) (xy 381.02299 -239.08797)
			(xy 380.977011 -239.109787) (xy 380.928127 -239.123947) (xy 380.877606 -239.130081) (xy 380.826754 -239.128032)
			(xy 380.77689 -239.117852) (xy 380.729304 -239.099805) (xy 380.68523 -239.074359) (xy 380.645808 -239.042172)
			(xy 380.61206 -239.004078) (xy 380.584859 -238.961064) (xy 380.564911 -238.914244) (xy 380.552732 -238.86483)
			(xy 380.548637 -238.814102) (xy 380.230126 -238.814102) (xy 380.229631 -238.838709) (xy 380.221736 -238.887286)
			(xy 380.206152 -238.933967) (xy 380.183281 -238.977544) (xy 380.153716 -239.016888) (xy 380.118223 -239.05098)
			(xy 380.07772 -239.078936) (xy 380.033258 -239.100034) (xy 379.985987 -239.113726) (xy 379.937132 -239.119658)
			(xy 379.887957 -239.117677) (xy 379.839738 -239.107833) (xy 379.793722 -239.090381) (xy 379.751101 -239.065774)
			(xy 379.71298 -239.034649) (xy 379.680345 -238.997812) (xy 379.654042 -238.956216) (xy 379.634751 -238.91094)
			(xy 379.622974 -238.863156) (xy 379.619014 -238.814102) (xy 379.300486 -238.814102) (xy 379.299974 -238.839548)
			(xy 379.29181 -238.889782) (xy 379.275694 -238.938056) (xy 379.252043 -238.983119) (xy 379.22147 -239.023805)
			(xy 379.184766 -239.05906) (xy 379.142882 -239.08797) (xy 379.096903 -239.109787) (xy 379.048019 -239.123947)
			(xy 378.997498 -239.130081) (xy 378.946646 -239.128032) (xy 378.896782 -239.117852) (xy 378.849196 -239.099805)
			(xy 378.805122 -239.074359) (xy 378.7657 -239.042172) (xy 378.731952 -239.004078) (xy 378.704751 -238.961064)
			(xy 378.684803 -238.914244) (xy 378.672624 -238.86483) (xy 378.668529 -238.814102) (xy 378.350018 -238.814102)
			(xy 378.349523 -238.838709) (xy 378.341628 -238.887286) (xy 378.326044 -238.933967) (xy 378.303173 -238.977544)
			(xy 378.273608 -239.016888) (xy 378.238115 -239.05098) (xy 378.197612 -239.078936) (xy 378.15315 -239.100034)
			(xy 378.105879 -239.113726) (xy 378.057024 -239.119658) (xy 378.007849 -239.117677) (xy 377.95963 -239.107833)
			(xy 377.913614 -239.090381) (xy 377.870993 -239.065774) (xy 377.832872 -239.034649) (xy 377.800237 -238.997812)
			(xy 377.773934 -238.956216) (xy 377.754643 -238.91094) (xy 377.742866 -238.863156) (xy 377.738906 -238.814102)
			(xy 377.420632 -238.814102) (xy 377.42012 -238.839548) (xy 377.411956 -238.889782) (xy 377.39584 -238.938056)
			(xy 377.372189 -238.983119) (xy 377.341616 -239.023805) (xy 377.304912 -239.05906) (xy 377.263028 -239.08797)
			(xy 377.217049 -239.109787) (xy 377.168165 -239.123947) (xy 377.117644 -239.130081) (xy 377.066792 -239.128032)
			(xy 377.016928 -239.117852) (xy 376.969342 -239.099805) (xy 376.925268 -239.074359) (xy 376.885846 -239.042172)
			(xy 376.852098 -239.004078) (xy 376.824897 -238.961064) (xy 376.804949 -238.914244) (xy 376.79277 -238.86483)
			(xy 376.788675 -238.814102) (xy 376.480158 -238.814102) (xy 376.480158 -238.838914) (xy 376.472394 -238.88793)
			(xy 376.457057 -238.935128) (xy 376.434525 -238.979345) (xy 376.405353 -239.019492) (xy 376.370259 -239.054582)
			(xy 376.330107 -239.083748) (xy 376.285887 -239.106274) (xy 376.238687 -239.121605) (xy 376.18967 -239.129362)
			(xy 376.164856 -239.129824) (xy 376.137982 -239.129268) (xy 376.085015 -239.12013) (xy 376.034366 -239.102143)
			(xy 376.010678 -239.089438) (xy 376.00001 -239.083596) (xy 375.975626 -239.08258) (xy 375.904252 -239.115854)
			(xy 375.893732 -239.121393) (xy 375.878896 -239.139934) (xy 375.875804 -239.151414) (xy 375.867743 -239.188042)
			(xy 375.848684 -239.260587) (xy 375.837704 -239.296448) (xy 375.834809 -239.3074) (xy 375.837805 -239.329825)
			(xy 375.850173 -239.348769) (xy 375.859548 -239.355122) (xy 375.882177 -239.369617) (xy 375.922588 -239.405034)
			(xy 375.956422 -239.44678) (xy 375.982704 -239.493649) (xy 376.000675 -239.54429) (xy 376.009818 -239.597241)
			(xy 376.010424 -239.624108) (xy 376.328952 -239.624108) (xy 376.332912 -239.575054) (xy 376.344689 -239.52727)
			(xy 376.36398 -239.481994) (xy 376.390283 -239.440398) (xy 376.422918 -239.403561) (xy 376.461039 -239.372436)
			(xy 376.50366 -239.347829) (xy 376.549676 -239.330377) (xy 376.597895 -239.320533) (xy 376.64707 -239.318552)
			(xy 376.695925 -239.324484) (xy 376.743196 -239.338176) (xy 376.787658 -239.359274) (xy 376.828161 -239.38723)
			(xy 376.863654 -239.421322) (xy 376.893219 -239.460666) (xy 376.91609 -239.504243) (xy 376.931674 -239.550924)
			(xy 376.939569 -239.599501) (xy 376.940064 -239.624108) (xy 377.258575 -239.624108) (xy 377.26267 -239.57338)
			(xy 377.274849 -239.523966) (xy 377.294797 -239.477146) (xy 377.321998 -239.434132) (xy 377.355746 -239.396038)
			(xy 377.395168 -239.363851) (xy 377.439242 -239.338405) (xy 377.486828 -239.320358) (xy 377.536692 -239.310178)
			(xy 377.587544 -239.308129) (xy 377.638065 -239.314263) (xy 377.686949 -239.328423) (xy 377.732928 -239.35024)
			(xy 377.774812 -239.37915) (xy 377.811516 -239.414405) (xy 377.842089 -239.455091) (xy 377.86574 -239.500154)
			(xy 377.881856 -239.548428) (xy 377.89002 -239.598662) (xy 377.890532 -239.624108) (xy 379.138683 -239.624108)
			(xy 379.142778 -239.57338) (xy 379.154957 -239.523966) (xy 379.174905 -239.477146) (xy 379.202106 -239.434132)
			(xy 379.235854 -239.396038) (xy 379.275276 -239.363851) (xy 379.31935 -239.338405) (xy 379.366936 -239.320358)
			(xy 379.4168 -239.310178) (xy 379.467652 -239.308129) (xy 379.518173 -239.314263) (xy 379.567057 -239.328423)
			(xy 379.613036 -239.35024) (xy 379.65492 -239.37915) (xy 379.691624 -239.414405) (xy 379.722197 -239.455091)
			(xy 379.745848 -239.500154) (xy 379.761964 -239.548428) (xy 379.770128 -239.598662) (xy 379.77064 -239.624108)
			(xy 380.078483 -239.624108) (xy 380.082578 -239.57338) (xy 380.094757 -239.523966) (xy 380.114705 -239.477146)
			(xy 380.141906 -239.434132) (xy 380.175654 -239.396038) (xy 380.215076 -239.363851) (xy 380.25915 -239.338405)
			(xy 380.306736 -239.320358) (xy 380.3566 -239.310178) (xy 380.407452 -239.308129) (xy 380.457973 -239.314263)
			(xy 380.506857 -239.328423) (xy 380.552836 -239.35024) (xy 380.59472 -239.37915) (xy 380.631424 -239.414405)
			(xy 380.661997 -239.455091) (xy 380.685648 -239.500154) (xy 380.701764 -239.548428) (xy 380.709928 -239.598662)
			(xy 380.71044 -239.624108) (xy 381.028968 -239.624108) (xy 381.032928 -239.575054) (xy 381.044705 -239.52727)
			(xy 381.063996 -239.481994) (xy 381.090299 -239.440398) (xy 381.122934 -239.403561) (xy 381.161055 -239.372436)
			(xy 381.203676 -239.347829) (xy 381.249692 -239.330377) (xy 381.297911 -239.320533) (xy 381.347086 -239.318552)
			(xy 381.395941 -239.324484) (xy 381.443212 -239.338176) (xy 381.487674 -239.359274) (xy 381.528177 -239.38723)
			(xy 381.56367 -239.421322) (xy 381.593235 -239.460666) (xy 381.616106 -239.504243) (xy 381.63169 -239.550924)
			(xy 381.639585 -239.599501) (xy 381.64008 -239.624108) (xy 381.969022 -239.624108) (xy 381.972982 -239.575054)
			(xy 381.984759 -239.52727) (xy 382.00405 -239.481994) (xy 382.030353 -239.440398) (xy 382.062988 -239.403561)
			(xy 382.101109 -239.372436) (xy 382.14373 -239.347829) (xy 382.189746 -239.330377) (xy 382.237965 -239.320533)
			(xy 382.28714 -239.318552) (xy 382.335995 -239.324484) (xy 382.383266 -239.338176) (xy 382.427728 -239.359274)
			(xy 382.468231 -239.38723) (xy 382.503724 -239.421322) (xy 382.533289 -239.460666) (xy 382.55616 -239.504243)
			(xy 382.571744 -239.550924) (xy 382.579639 -239.599501) (xy 382.580134 -239.624108) (xy 382.909076 -239.624108)
			(xy 382.913036 -239.575054) (xy 382.924813 -239.52727) (xy 382.944104 -239.481994) (xy 382.970407 -239.440398)
			(xy 383.003042 -239.403561) (xy 383.041163 -239.372436) (xy 383.083784 -239.347829) (xy 383.1298 -239.330377)
			(xy 383.178019 -239.320533) (xy 383.227194 -239.318552) (xy 383.276049 -239.324484) (xy 383.32332 -239.338176)
			(xy 383.367782 -239.359274) (xy 383.408285 -239.38723) (xy 383.443778 -239.421322) (xy 383.473343 -239.460666)
			(xy 383.496214 -239.504243) (xy 383.511798 -239.550924) (xy 383.519693 -239.599501) (xy 383.520188 -239.624108)
			(xy 383.84913 -239.624108) (xy 383.85309 -239.575054) (xy 383.864867 -239.52727) (xy 383.884158 -239.481994)
			(xy 383.910461 -239.440398) (xy 383.943096 -239.403561) (xy 383.981217 -239.372436) (xy 384.023838 -239.347829)
			(xy 384.069854 -239.330377) (xy 384.118073 -239.320533) (xy 384.167248 -239.318552) (xy 384.216103 -239.324484)
			(xy 384.263374 -239.338176) (xy 384.307836 -239.359274) (xy 384.348339 -239.38723) (xy 384.383832 -239.421322)
			(xy 384.413397 -239.460666) (xy 384.436268 -239.504243) (xy 384.451852 -239.550924) (xy 384.459747 -239.599501)
			(xy 384.460242 -239.624108) (xy 385.728984 -239.624108) (xy 385.732944 -239.575054) (xy 385.744721 -239.52727)
			(xy 385.764012 -239.481994) (xy 385.790315 -239.440398) (xy 385.82295 -239.403561) (xy 385.861071 -239.372436)
			(xy 385.903692 -239.347829) (xy 385.949708 -239.330377) (xy 385.997927 -239.320533) (xy 386.047102 -239.318552)
			(xy 386.095957 -239.324484) (xy 386.143228 -239.338176) (xy 386.18769 -239.359274) (xy 386.228193 -239.38723)
			(xy 386.263686 -239.421322) (xy 386.293251 -239.460666) (xy 386.316122 -239.504243) (xy 386.331706 -239.550924)
			(xy 386.339601 -239.599501) (xy 386.340096 -239.624108) (xy 386.669038 -239.624108) (xy 386.672998 -239.575054)
			(xy 386.684775 -239.52727) (xy 386.704066 -239.481994) (xy 386.730369 -239.440398) (xy 386.763004 -239.403561)
			(xy 386.801125 -239.372436) (xy 386.843746 -239.347829) (xy 386.889762 -239.330377) (xy 386.937981 -239.320533)
			(xy 386.987156 -239.318552) (xy 387.036011 -239.324484) (xy 387.083282 -239.338176) (xy 387.127744 -239.359274)
			(xy 387.168247 -239.38723) (xy 387.20374 -239.421322) (xy 387.233305 -239.460666) (xy 387.256176 -239.504243)
			(xy 387.27176 -239.550924) (xy 387.279655 -239.599501) (xy 387.28015 -239.624108) (xy 387.279655 -239.648715)
			(xy 387.27176 -239.697292) (xy 387.256176 -239.743973) (xy 387.233305 -239.78755) (xy 387.20374 -239.826894)
			(xy 387.168247 -239.860986) (xy 387.127744 -239.888942) (xy 387.083282 -239.91004) (xy 387.036011 -239.923732)
			(xy 386.987156 -239.929664) (xy 386.937981 -239.927683) (xy 386.889762 -239.917839) (xy 386.843746 -239.900387)
			(xy 386.801125 -239.87578) (xy 386.763004 -239.844655) (xy 386.730369 -239.807818) (xy 386.704066 -239.766222)
			(xy 386.684775 -239.720946) (xy 386.672998 -239.673162) (xy 386.669038 -239.624108) (xy 386.340096 -239.624108)
			(xy 386.339601 -239.648715) (xy 386.331706 -239.697292) (xy 386.316122 -239.743973) (xy 386.293251 -239.78755)
			(xy 386.263686 -239.826894) (xy 386.228193 -239.860986) (xy 386.18769 -239.888942) (xy 386.143228 -239.91004)
			(xy 386.095957 -239.923732) (xy 386.047102 -239.929664) (xy 385.997927 -239.927683) (xy 385.949708 -239.917839)
			(xy 385.903692 -239.900387) (xy 385.861071 -239.87578) (xy 385.82295 -239.844655) (xy 385.790315 -239.807818)
			(xy 385.764012 -239.766222) (xy 385.744721 -239.720946) (xy 385.732944 -239.673162) (xy 385.728984 -239.624108)
			(xy 384.460242 -239.624108) (xy 384.459747 -239.648715) (xy 384.451852 -239.697292) (xy 384.436268 -239.743973)
			(xy 384.413397 -239.78755) (xy 384.383832 -239.826894) (xy 384.348339 -239.860986) (xy 384.307836 -239.888942)
			(xy 384.263374 -239.91004) (xy 384.216103 -239.923732) (xy 384.167248 -239.929664) (xy 384.118073 -239.927683)
			(xy 384.069854 -239.917839) (xy 384.023838 -239.900387) (xy 383.981217 -239.87578) (xy 383.943096 -239.844655)
			(xy 383.910461 -239.807818) (xy 383.884158 -239.766222) (xy 383.864867 -239.720946) (xy 383.85309 -239.673162)
			(xy 383.84913 -239.624108) (xy 383.520188 -239.624108) (xy 383.519693 -239.648715) (xy 383.511798 -239.697292)
			(xy 383.496214 -239.743973) (xy 383.473343 -239.78755) (xy 383.443778 -239.826894) (xy 383.408285 -239.860986)
			(xy 383.367782 -239.888942) (xy 383.32332 -239.91004) (xy 383.276049 -239.923732) (xy 383.227194 -239.929664)
			(xy 383.178019 -239.927683) (xy 383.1298 -239.917839) (xy 383.083784 -239.900387) (xy 383.041163 -239.87578)
			(xy 383.003042 -239.844655) (xy 382.970407 -239.807818) (xy 382.944104 -239.766222) (xy 382.924813 -239.720946)
			(xy 382.913036 -239.673162) (xy 382.909076 -239.624108) (xy 382.580134 -239.624108) (xy 382.579639 -239.648715)
			(xy 382.571744 -239.697292) (xy 382.55616 -239.743973) (xy 382.533289 -239.78755) (xy 382.503724 -239.826894)
			(xy 382.468231 -239.860986) (xy 382.427728 -239.888942) (xy 382.383266 -239.91004) (xy 382.335995 -239.923732)
			(xy 382.28714 -239.929664) (xy 382.237965 -239.927683) (xy 382.189746 -239.917839) (xy 382.14373 -239.900387)
			(xy 382.101109 -239.87578) (xy 382.062988 -239.844655) (xy 382.030353 -239.807818) (xy 382.00405 -239.766222)
			(xy 381.984759 -239.720946) (xy 381.972982 -239.673162) (xy 381.969022 -239.624108) (xy 381.64008 -239.624108)
			(xy 381.639585 -239.648715) (xy 381.63169 -239.697292) (xy 381.616106 -239.743973) (xy 381.593235 -239.78755)
			(xy 381.56367 -239.826894) (xy 381.528177 -239.860986) (xy 381.487674 -239.888942) (xy 381.443212 -239.91004)
			(xy 381.395941 -239.923732) (xy 381.347086 -239.929664) (xy 381.297911 -239.927683) (xy 381.249692 -239.917839)
			(xy 381.203676 -239.900387) (xy 381.161055 -239.87578) (xy 381.122934 -239.844655) (xy 381.090299 -239.807818)
			(xy 381.063996 -239.766222) (xy 381.044705 -239.720946) (xy 381.032928 -239.673162) (xy 381.028968 -239.624108)
			(xy 380.71044 -239.624108) (xy 380.709928 -239.649554) (xy 380.701764 -239.699788) (xy 380.685648 -239.748062)
			(xy 380.661997 -239.793125) (xy 380.631424 -239.833811) (xy 380.59472 -239.869066) (xy 380.552836 -239.897976)
			(xy 380.506857 -239.919793) (xy 380.457973 -239.933953) (xy 380.407452 -239.940087) (xy 380.3566 -239.938038)
			(xy 380.306736 -239.927858) (xy 380.25915 -239.909811) (xy 380.215076 -239.884365) (xy 380.175654 -239.852178)
			(xy 380.141906 -239.814084) (xy 380.114705 -239.77107) (xy 380.094757 -239.72425) (xy 380.082578 -239.674836)
			(xy 380.078483 -239.624108) (xy 379.77064 -239.624108) (xy 379.770128 -239.649554) (xy 379.761964 -239.699788)
			(xy 379.745848 -239.748062) (xy 379.722197 -239.793125) (xy 379.691624 -239.833811) (xy 379.65492 -239.869066)
			(xy 379.613036 -239.897976) (xy 379.567057 -239.919793) (xy 379.518173 -239.933953) (xy 379.467652 -239.940087)
			(xy 379.4168 -239.938038) (xy 379.366936 -239.927858) (xy 379.31935 -239.909811) (xy 379.275276 -239.884365)
			(xy 379.235854 -239.852178) (xy 379.202106 -239.814084) (xy 379.174905 -239.77107) (xy 379.154957 -239.72425)
			(xy 379.142778 -239.674836) (xy 379.138683 -239.624108) (xy 377.890532 -239.624108) (xy 377.89002 -239.649554)
			(xy 377.881856 -239.699788) (xy 377.86574 -239.748062) (xy 377.842089 -239.793125) (xy 377.811516 -239.833811)
			(xy 377.774812 -239.869066) (xy 377.732928 -239.897976) (xy 377.686949 -239.919793) (xy 377.638065 -239.933953)
			(xy 377.587544 -239.940087) (xy 377.536692 -239.938038) (xy 377.486828 -239.927858) (xy 377.439242 -239.909811)
			(xy 377.395168 -239.884365) (xy 377.355746 -239.852178) (xy 377.321998 -239.814084) (xy 377.294797 -239.77107)
			(xy 377.274849 -239.72425) (xy 377.26267 -239.674836) (xy 377.258575 -239.624108) (xy 376.940064 -239.624108)
			(xy 376.939569 -239.648715) (xy 376.931674 -239.697292) (xy 376.91609 -239.743973) (xy 376.893219 -239.78755)
			(xy 376.863654 -239.826894) (xy 376.828161 -239.860986) (xy 376.787658 -239.888942) (xy 376.743196 -239.91004)
			(xy 376.695925 -239.923732) (xy 376.64707 -239.929664) (xy 376.597895 -239.927683) (xy 376.549676 -239.917839)
			(xy 376.50366 -239.900387) (xy 376.461039 -239.87578) (xy 376.422918 -239.844655) (xy 376.390283 -239.807818)
			(xy 376.36398 -239.766222) (xy 376.344689 -239.720946) (xy 376.332912 -239.673162) (xy 376.328952 -239.624108)
			(xy 376.010424 -239.624108) (xy 376.009961 -239.648911) (xy 376.002196 -239.697904) (xy 375.986857 -239.745078)
			(xy 375.964323 -239.78927) (xy 375.93515 -239.82939) (xy 375.900057 -239.864449) (xy 375.859909 -239.893583)
			(xy 375.815695 -239.916074) (xy 375.768506 -239.931367) (xy 375.719505 -239.939085) (xy 375.694702 -239.939576)
			(xy 375.668767 -239.93909) (xy 375.617584 -239.930679) (xy 375.56847 -239.914001) (xy 375.54535 -239.902238)
			(xy 375.535176 -239.897416) (xy 375.512722 -239.896224) (xy 375.491922 -239.904767) (xy 375.483882 -239.912652)
			(xy 375.46661 -239.931427) (xy 375.431044 -239.968011) (xy 375.412762 -239.985804) (xy 375.407936 -239.99063)
			(xy 375.393458 -240.015014) (xy 375.39168 -240.022126) (xy 375.374916 -240.084356) (xy 375.371868 -240.094516)
			(xy 375.374408 -240.114582) (xy 375.388124 -240.138966) (xy 375.391184 -240.14407) (xy 375.399269 -240.1528)
			(xy 375.404126 -240.156238) (xy 375.404634 -240.156492) (xy 375.404888 -240.156746) (xy 375.427605 -240.17214)
			(xy 375.468064 -240.20921) (xy 375.501849 -240.25245) (xy 375.528033 -240.300673) (xy 375.545897 -240.352557)
			(xy 375.554953 -240.406677) (xy 375.55551 -240.434114) (xy 375.848621 -240.434114) (xy 375.852716 -240.383386)
			(xy 375.864895 -240.333972) (xy 375.884843 -240.287152) (xy 375.912044 -240.244138) (xy 375.945792 -240.206044)
			(xy 375.985214 -240.173857) (xy 376.029288 -240.148411) (xy 376.076874 -240.130364) (xy 376.126738 -240.120184)
			(xy 376.17759 -240.118135) (xy 376.228111 -240.124269) (xy 376.276995 -240.138429) (xy 376.322974 -240.160246)
			(xy 376.364858 -240.189156) (xy 376.401562 -240.224411) (xy 376.432135 -240.265097) (xy 376.455786 -240.31016)
			(xy 376.471902 -240.358434) (xy 376.480066 -240.408668) (xy 376.480578 -240.434114) (xy 376.788675 -240.434114)
			(xy 376.79277 -240.383386) (xy 376.804949 -240.333972) (xy 376.824897 -240.287152) (xy 376.852098 -240.244138)
			(xy 376.885846 -240.206044) (xy 376.925268 -240.173857) (xy 376.969342 -240.148411) (xy 377.016928 -240.130364)
			(xy 377.066792 -240.120184) (xy 377.117644 -240.118135) (xy 377.168165 -240.124269) (xy 377.217049 -240.138429)
			(xy 377.263028 -240.160246) (xy 377.304912 -240.189156) (xy 377.341616 -240.224411) (xy 377.372189 -240.265097)
			(xy 377.39584 -240.31016) (xy 377.411956 -240.358434) (xy 377.42012 -240.408668) (xy 377.420632 -240.434114)
			(xy 377.738906 -240.434114) (xy 377.742866 -240.38506) (xy 377.754643 -240.337276) (xy 377.773934 -240.292)
			(xy 377.800237 -240.250404) (xy 377.832872 -240.213567) (xy 377.870993 -240.182442) (xy 377.913614 -240.157835)
			(xy 377.95963 -240.140383) (xy 378.007849 -240.130539) (xy 378.057024 -240.128558) (xy 378.105879 -240.13449)
			(xy 378.15315 -240.148182) (xy 378.197612 -240.16928) (xy 378.238115 -240.197236) (xy 378.273608 -240.231328)
			(xy 378.303173 -240.270672) (xy 378.326044 -240.314249) (xy 378.341628 -240.36093) (xy 378.349523 -240.409507)
			(xy 378.350018 -240.434114) (xy 378.668529 -240.434114) (xy 378.672624 -240.383386) (xy 378.684803 -240.333972)
			(xy 378.704751 -240.287152) (xy 378.731952 -240.244138) (xy 378.7657 -240.206044) (xy 378.805122 -240.173857)
			(xy 378.849196 -240.148411) (xy 378.896782 -240.130364) (xy 378.946646 -240.120184) (xy 378.997498 -240.118135)
			(xy 379.048019 -240.124269) (xy 379.096903 -240.138429) (xy 379.142882 -240.160246) (xy 379.184766 -240.189156)
			(xy 379.22147 -240.224411) (xy 379.252043 -240.265097) (xy 379.275694 -240.31016) (xy 379.29181 -240.358434)
			(xy 379.299974 -240.408668) (xy 379.300486 -240.434114) (xy 379.619014 -240.434114) (xy 379.622974 -240.38506)
			(xy 379.634751 -240.337276) (xy 379.654042 -240.292) (xy 379.680345 -240.250404) (xy 379.71298 -240.213567)
			(xy 379.751101 -240.182442) (xy 379.793722 -240.157835) (xy 379.839738 -240.140383) (xy 379.887957 -240.130539)
			(xy 379.937132 -240.128558) (xy 379.985987 -240.13449) (xy 380.033258 -240.148182) (xy 380.07772 -240.16928)
			(xy 380.118223 -240.197236) (xy 380.153716 -240.231328) (xy 380.183281 -240.270672) (xy 380.206152 -240.314249)
			(xy 380.221736 -240.36093) (xy 380.229631 -240.409507) (xy 380.230126 -240.434114) (xy 380.548637 -240.434114)
			(xy 380.552732 -240.383386) (xy 380.564911 -240.333972) (xy 380.584859 -240.287152) (xy 380.61206 -240.244138)
			(xy 380.645808 -240.206044) (xy 380.68523 -240.173857) (xy 380.729304 -240.148411) (xy 380.77689 -240.130364)
			(xy 380.826754 -240.120184) (xy 380.877606 -240.118135) (xy 380.928127 -240.124269) (xy 380.977011 -240.138429)
			(xy 381.02299 -240.160246) (xy 381.064874 -240.189156) (xy 381.101578 -240.224411) (xy 381.132151 -240.265097)
			(xy 381.155802 -240.31016) (xy 381.171918 -240.358434) (xy 381.180082 -240.408668) (xy 381.180594 -240.434114)
			(xy 381.499122 -240.434114) (xy 381.503082 -240.38506) (xy 381.514859 -240.337276) (xy 381.53415 -240.292)
			(xy 381.560453 -240.250404) (xy 381.593088 -240.213567) (xy 381.631209 -240.182442) (xy 381.67383 -240.157835)
			(xy 381.719846 -240.140383) (xy 381.768065 -240.130539) (xy 381.81724 -240.128558) (xy 381.866095 -240.13449)
			(xy 381.913366 -240.148182) (xy 381.957828 -240.16928) (xy 381.998331 -240.197236) (xy 382.033824 -240.231328)
			(xy 382.063389 -240.270672) (xy 382.08626 -240.314249) (xy 382.101844 -240.36093) (xy 382.109739 -240.409507)
			(xy 382.110234 -240.434114) (xy 382.438922 -240.434114) (xy 382.442882 -240.38506) (xy 382.454659 -240.337276)
			(xy 382.47395 -240.292) (xy 382.500253 -240.250404) (xy 382.532888 -240.213567) (xy 382.571009 -240.182442)
			(xy 382.61363 -240.157835) (xy 382.659646 -240.140383) (xy 382.707865 -240.130539) (xy 382.75704 -240.128558)
			(xy 382.805895 -240.13449) (xy 382.853166 -240.148182) (xy 382.897628 -240.16928) (xy 382.938131 -240.197236)
			(xy 382.973624 -240.231328) (xy 383.003189 -240.270672) (xy 383.02606 -240.314249) (xy 383.041644 -240.36093)
			(xy 383.049539 -240.409507) (xy 383.050034 -240.434114) (xy 383.378976 -240.434114) (xy 383.382936 -240.38506)
			(xy 383.394713 -240.337276) (xy 383.414004 -240.292) (xy 383.440307 -240.250404) (xy 383.472942 -240.213567)
			(xy 383.511063 -240.182442) (xy 383.553684 -240.157835) (xy 383.5997 -240.140383) (xy 383.647919 -240.130539)
			(xy 383.697094 -240.128558) (xy 383.745949 -240.13449) (xy 383.79322 -240.148182) (xy 383.837682 -240.16928)
			(xy 383.878185 -240.197236) (xy 383.913678 -240.231328) (xy 383.943243 -240.270672) (xy 383.966114 -240.314249)
			(xy 383.981698 -240.36093) (xy 383.989593 -240.409507) (xy 383.990088 -240.434114) (xy 384.31903 -240.434114)
			(xy 384.32299 -240.38506) (xy 384.334767 -240.337276) (xy 384.354058 -240.292) (xy 384.380361 -240.250404)
			(xy 384.412996 -240.213567) (xy 384.451117 -240.182442) (xy 384.493738 -240.157835) (xy 384.539754 -240.140383)
			(xy 384.587973 -240.130539) (xy 384.637148 -240.128558) (xy 384.686003 -240.13449) (xy 384.733274 -240.148182)
			(xy 384.777736 -240.16928) (xy 384.818239 -240.197236) (xy 384.853732 -240.231328) (xy 384.883297 -240.270672)
			(xy 384.906168 -240.314249) (xy 384.921752 -240.36093) (xy 384.929647 -240.409507) (xy 384.930142 -240.434114)
			(xy 385.259084 -240.434114) (xy 385.263044 -240.38506) (xy 385.274821 -240.337276) (xy 385.294112 -240.292)
			(xy 385.320415 -240.250404) (xy 385.35305 -240.213567) (xy 385.391171 -240.182442) (xy 385.433792 -240.157835)
			(xy 385.479808 -240.140383) (xy 385.528027 -240.130539) (xy 385.577202 -240.128558) (xy 385.626057 -240.13449)
			(xy 385.673328 -240.148182) (xy 385.71779 -240.16928) (xy 385.758293 -240.197236) (xy 385.793786 -240.231328)
			(xy 385.823351 -240.270672) (xy 385.846222 -240.314249) (xy 385.861806 -240.36093) (xy 385.869701 -240.409507)
			(xy 385.870196 -240.434114) (xy 386.199138 -240.434114) (xy 386.203098 -240.38506) (xy 386.214875 -240.337276)
			(xy 386.234166 -240.292) (xy 386.260469 -240.250404) (xy 386.293104 -240.213567) (xy 386.331225 -240.182442)
			(xy 386.373846 -240.157835) (xy 386.419862 -240.140383) (xy 386.468081 -240.130539) (xy 386.517256 -240.128558)
			(xy 386.566111 -240.13449) (xy 386.613382 -240.148182) (xy 386.657844 -240.16928) (xy 386.698347 -240.197236)
			(xy 386.73384 -240.231328) (xy 386.763405 -240.270672) (xy 386.786276 -240.314249) (xy 386.80186 -240.36093)
			(xy 386.809755 -240.409507) (xy 386.81025 -240.434114) (xy 386.809755 -240.458721) (xy 386.80186 -240.507298)
			(xy 386.786276 -240.553979) (xy 386.763405 -240.597556) (xy 386.73384 -240.6369) (xy 386.698347 -240.670992)
			(xy 386.657844 -240.698948) (xy 386.613382 -240.720046) (xy 386.566111 -240.733738) (xy 386.517256 -240.73967)
			(xy 386.468081 -240.737689) (xy 386.419862 -240.727845) (xy 386.373846 -240.710393) (xy 386.331225 -240.685786)
			(xy 386.293104 -240.654661) (xy 386.260469 -240.617824) (xy 386.234166 -240.576228) (xy 386.214875 -240.530952)
			(xy 386.203098 -240.483168) (xy 386.199138 -240.434114) (xy 385.870196 -240.434114) (xy 385.869701 -240.458721)
			(xy 385.861806 -240.507298) (xy 385.846222 -240.553979) (xy 385.823351 -240.597556) (xy 385.793786 -240.6369)
			(xy 385.758293 -240.670992) (xy 385.71779 -240.698948) (xy 385.673328 -240.720046) (xy 385.626057 -240.733738)
			(xy 385.577202 -240.73967) (xy 385.528027 -240.737689) (xy 385.479808 -240.727845) (xy 385.433792 -240.710393)
			(xy 385.391171 -240.685786) (xy 385.35305 -240.654661) (xy 385.320415 -240.617824) (xy 385.294112 -240.576228)
			(xy 385.274821 -240.530952) (xy 385.263044 -240.483168) (xy 385.259084 -240.434114) (xy 384.930142 -240.434114)
			(xy 384.929647 -240.458721) (xy 384.921752 -240.507298) (xy 384.906168 -240.553979) (xy 384.883297 -240.597556)
			(xy 384.853732 -240.6369) (xy 384.818239 -240.670992) (xy 384.777736 -240.698948) (xy 384.733274 -240.720046)
			(xy 384.686003 -240.733738) (xy 384.637148 -240.73967) (xy 384.587973 -240.737689) (xy 384.539754 -240.727845)
			(xy 384.493738 -240.710393) (xy 384.451117 -240.685786) (xy 384.412996 -240.654661) (xy 384.380361 -240.617824)
			(xy 384.354058 -240.576228) (xy 384.334767 -240.530952) (xy 384.32299 -240.483168) (xy 384.31903 -240.434114)
			(xy 383.990088 -240.434114) (xy 383.989593 -240.458721) (xy 383.981698 -240.507298) (xy 383.966114 -240.553979)
			(xy 383.943243 -240.597556) (xy 383.913678 -240.6369) (xy 383.878185 -240.670992) (xy 383.837682 -240.698948)
			(xy 383.79322 -240.720046) (xy 383.745949 -240.733738) (xy 383.697094 -240.73967) (xy 383.647919 -240.737689)
			(xy 383.5997 -240.727845) (xy 383.553684 -240.710393) (xy 383.511063 -240.685786) (xy 383.472942 -240.654661)
			(xy 383.440307 -240.617824) (xy 383.414004 -240.576228) (xy 383.394713 -240.530952) (xy 383.382936 -240.483168)
			(xy 383.378976 -240.434114) (xy 383.050034 -240.434114) (xy 383.049539 -240.458721) (xy 383.041644 -240.507298)
			(xy 383.02606 -240.553979) (xy 383.003189 -240.597556) (xy 382.973624 -240.6369) (xy 382.938131 -240.670992)
			(xy 382.897628 -240.698948) (xy 382.853166 -240.720046) (xy 382.805895 -240.733738) (xy 382.75704 -240.73967)
			(xy 382.707865 -240.737689) (xy 382.659646 -240.727845) (xy 382.61363 -240.710393) (xy 382.571009 -240.685786)
			(xy 382.532888 -240.654661) (xy 382.500253 -240.617824) (xy 382.47395 -240.576228) (xy 382.454659 -240.530952)
			(xy 382.442882 -240.483168) (xy 382.438922 -240.434114) (xy 382.110234 -240.434114) (xy 382.109739 -240.458721)
			(xy 382.101844 -240.507298) (xy 382.08626 -240.553979) (xy 382.063389 -240.597556) (xy 382.033824 -240.6369)
			(xy 381.998331 -240.670992) (xy 381.957828 -240.698948) (xy 381.913366 -240.720046) (xy 381.866095 -240.733738)
			(xy 381.81724 -240.73967) (xy 381.768065 -240.737689) (xy 381.719846 -240.727845) (xy 381.67383 -240.710393)
			(xy 381.631209 -240.685786) (xy 381.593088 -240.654661) (xy 381.560453 -240.617824) (xy 381.53415 -240.576228)
			(xy 381.514859 -240.530952) (xy 381.503082 -240.483168) (xy 381.499122 -240.434114) (xy 381.180594 -240.434114)
			(xy 381.180082 -240.45956) (xy 381.171918 -240.509794) (xy 381.155802 -240.558068) (xy 381.132151 -240.603131)
			(xy 381.101578 -240.643817) (xy 381.064874 -240.679072) (xy 381.02299 -240.707982) (xy 380.977011 -240.729799)
			(xy 380.928127 -240.743959) (xy 380.877606 -240.750093) (xy 380.826754 -240.748044) (xy 380.77689 -240.737864)
			(xy 380.729304 -240.719817) (xy 380.68523 -240.694371) (xy 380.645808 -240.662184) (xy 380.61206 -240.62409)
			(xy 380.584859 -240.581076) (xy 380.564911 -240.534256) (xy 380.552732 -240.484842) (xy 380.548637 -240.434114)
			(xy 380.230126 -240.434114) (xy 380.229631 -240.458721) (xy 380.221736 -240.507298) (xy 380.206152 -240.553979)
			(xy 380.183281 -240.597556) (xy 380.153716 -240.6369) (xy 380.118223 -240.670992) (xy 380.07772 -240.698948)
			(xy 380.033258 -240.720046) (xy 379.985987 -240.733738) (xy 379.937132 -240.73967) (xy 379.887957 -240.737689)
			(xy 379.839738 -240.727845) (xy 379.793722 -240.710393) (xy 379.751101 -240.685786) (xy 379.71298 -240.654661)
			(xy 379.680345 -240.617824) (xy 379.654042 -240.576228) (xy 379.634751 -240.530952) (xy 379.622974 -240.483168)
			(xy 379.619014 -240.434114) (xy 379.300486 -240.434114) (xy 379.299974 -240.45956) (xy 379.29181 -240.509794)
			(xy 379.275694 -240.558068) (xy 379.252043 -240.603131) (xy 379.22147 -240.643817) (xy 379.184766 -240.679072)
			(xy 379.142882 -240.707982) (xy 379.096903 -240.729799) (xy 379.048019 -240.743959) (xy 378.997498 -240.750093)
			(xy 378.946646 -240.748044) (xy 378.896782 -240.737864) (xy 378.849196 -240.719817) (xy 378.805122 -240.694371)
			(xy 378.7657 -240.662184) (xy 378.731952 -240.62409) (xy 378.704751 -240.581076) (xy 378.684803 -240.534256)
			(xy 378.672624 -240.484842) (xy 378.668529 -240.434114) (xy 378.350018 -240.434114) (xy 378.349523 -240.458721)
			(xy 378.341628 -240.507298) (xy 378.326044 -240.553979) (xy 378.303173 -240.597556) (xy 378.273608 -240.6369)
			(xy 378.238115 -240.670992) (xy 378.197612 -240.698948) (xy 378.15315 -240.720046) (xy 378.105879 -240.733738)
			(xy 378.057024 -240.73967) (xy 378.007849 -240.737689) (xy 377.95963 -240.727845) (xy 377.913614 -240.710393)
			(xy 377.870993 -240.685786) (xy 377.832872 -240.654661) (xy 377.800237 -240.617824) (xy 377.773934 -240.576228)
			(xy 377.754643 -240.530952) (xy 377.742866 -240.483168) (xy 377.738906 -240.434114) (xy 377.420632 -240.434114)
			(xy 377.42012 -240.45956) (xy 377.411956 -240.509794) (xy 377.39584 -240.558068) (xy 377.372189 -240.603131)
			(xy 377.341616 -240.643817) (xy 377.304912 -240.679072) (xy 377.263028 -240.707982) (xy 377.217049 -240.729799)
			(xy 377.168165 -240.743959) (xy 377.117644 -240.750093) (xy 377.066792 -240.748044) (xy 377.016928 -240.737864)
			(xy 376.969342 -240.719817) (xy 376.925268 -240.694371) (xy 376.885846 -240.662184) (xy 376.852098 -240.62409)
			(xy 376.824897 -240.581076) (xy 376.804949 -240.534256) (xy 376.79277 -240.484842) (xy 376.788675 -240.434114)
			(xy 376.480578 -240.434114) (xy 376.480066 -240.45956) (xy 376.471902 -240.509794) (xy 376.455786 -240.558068)
			(xy 376.432135 -240.603131) (xy 376.401562 -240.643817) (xy 376.364858 -240.679072) (xy 376.322974 -240.707982)
			(xy 376.276995 -240.729799) (xy 376.228111 -240.743959) (xy 376.17759 -240.750093) (xy 376.126738 -240.748044)
			(xy 376.076874 -240.737864) (xy 376.029288 -240.719817) (xy 375.985214 -240.694371) (xy 375.945792 -240.662184)
			(xy 375.912044 -240.62409) (xy 375.884843 -240.581076) (xy 375.864895 -240.534256) (xy 375.852716 -240.484842)
			(xy 375.848621 -240.434114) (xy 375.55551 -240.434114) (xy 375.554999 -240.460101) (xy 375.546867 -240.511433)
			(xy 375.530805 -240.560862) (xy 375.507208 -240.60717) (xy 375.476658 -240.649216) (xy 375.439907 -240.685966)
			(xy 375.39786 -240.716515) (xy 375.351551 -240.74011) (xy 375.302122 -240.75617) (xy 375.250789 -240.7643)
			(xy 375.224802 -240.764822) (xy 375.198005 -240.764275) (xy 375.145117 -240.75559) (xy 375.094316 -240.73851)
			(xy 375.07037 -240.726468) (xy 375.065036 -240.723674) (xy 375.057416 -240.721896) (xy 375.04927 -240.720174)
			(xy 375.032679 -240.721459) (xy 375.024904 -240.724436) (xy 375.004584 -240.733326) (xy 374.997218 -240.740946)
			(xy 374.942862 -240.79581) (xy 374.937782 -240.800636) (xy 374.923304 -240.825274) (xy 374.921526 -240.832386)
			(xy 374.915955 -240.854121) (xy 374.903761 -240.897307) (xy 374.897142 -240.918746) (xy 374.896634 -240.920524)
			(xy 374.896126 -240.922556) (xy 374.894493 -240.931689) (xy 374.897113 -240.950042) (xy 374.901206 -240.95837)
			(xy 374.912382 -240.97869) (xy 374.920256 -240.987326) (xy 374.925336 -240.990882) (xy 374.946621 -241.005837)
			(xy 374.984235 -241.041767) (xy 375.01522 -241.083548) (xy 375.038683 -241.129973) (xy 375.053944 -241.179701)
			(xy 375.060563 -241.231295) (xy 375.060017 -241.24412) (xy 375.378467 -241.24412) (xy 375.382562 -241.193392)
			(xy 375.394741 -241.143978) (xy 375.414689 -241.097158) (xy 375.44189 -241.054144) (xy 375.475638 -241.01605)
			(xy 375.51506 -240.983863) (xy 375.559134 -240.958417) (xy 375.60672 -240.94037) (xy 375.656584 -240.93019)
			(xy 375.707436 -240.928141) (xy 375.757957 -240.934275) (xy 375.806841 -240.948435) (xy 375.85282 -240.970252)
			(xy 375.894704 -240.999162) (xy 375.931408 -241.034417) (xy 375.961981 -241.075103) (xy 375.985632 -241.120166)
			(xy 376.001748 -241.16844) (xy 376.009912 -241.218674) (xy 376.010424 -241.24412) (xy 376.328952 -241.24412)
			(xy 376.332912 -241.195066) (xy 376.344689 -241.147282) (xy 376.36398 -241.102006) (xy 376.390283 -241.06041)
			(xy 376.422918 -241.023573) (xy 376.461039 -240.992448) (xy 376.50366 -240.967841) (xy 376.549676 -240.950389)
			(xy 376.597895 -240.940545) (xy 376.64707 -240.938564) (xy 376.695925 -240.944496) (xy 376.743196 -240.958188)
			(xy 376.787658 -240.979286) (xy 376.828161 -241.007242) (xy 376.863654 -241.041334) (xy 376.893219 -241.080678)
			(xy 376.91609 -241.124255) (xy 376.931674 -241.170936) (xy 376.939569 -241.219513) (xy 376.940064 -241.24412)
			(xy 377.258575 -241.24412) (xy 377.26267 -241.193392) (xy 377.274849 -241.143978) (xy 377.294797 -241.097158)
			(xy 377.321998 -241.054144) (xy 377.355746 -241.01605) (xy 377.395168 -240.983863) (xy 377.439242 -240.958417)
			(xy 377.486828 -240.94037) (xy 377.536692 -240.93019) (xy 377.587544 -240.928141) (xy 377.638065 -240.934275)
			(xy 377.686949 -240.948435) (xy 377.732928 -240.970252) (xy 377.774812 -240.999162) (xy 377.811516 -241.034417)
			(xy 377.842089 -241.075103) (xy 377.86574 -241.120166) (xy 377.881856 -241.16844) (xy 377.89002 -241.218674)
			(xy 377.890532 -241.24412) (xy 378.20906 -241.24412) (xy 378.21302 -241.195066) (xy 378.224797 -241.147282)
			(xy 378.244088 -241.102006) (xy 378.270391 -241.06041) (xy 378.303026 -241.023573) (xy 378.341147 -240.992448)
			(xy 378.383768 -240.967841) (xy 378.429784 -240.950389) (xy 378.478003 -240.940545) (xy 378.527178 -240.938564)
			(xy 378.576033 -240.944496) (xy 378.623304 -240.958188) (xy 378.667766 -240.979286) (xy 378.708269 -241.007242)
			(xy 378.743762 -241.041334) (xy 378.773327 -241.080678) (xy 378.796198 -241.124255) (xy 378.811782 -241.170936)
			(xy 378.819677 -241.219513) (xy 378.820172 -241.24412) (xy 379.138683 -241.24412) (xy 379.142778 -241.193392)
			(xy 379.154957 -241.143978) (xy 379.174905 -241.097158) (xy 379.202106 -241.054144) (xy 379.235854 -241.01605)
			(xy 379.275276 -240.983863) (xy 379.31935 -240.958417) (xy 379.366936 -240.94037) (xy 379.4168 -240.93019)
			(xy 379.467652 -240.928141) (xy 379.518173 -240.934275) (xy 379.567057 -240.948435) (xy 379.613036 -240.970252)
			(xy 379.65492 -240.999162) (xy 379.691624 -241.034417) (xy 379.722197 -241.075103) (xy 379.745848 -241.120166)
			(xy 379.761964 -241.16844) (xy 379.770128 -241.218674) (xy 379.77064 -241.24412) (xy 380.078483 -241.24412)
			(xy 380.082578 -241.193392) (xy 380.094757 -241.143978) (xy 380.114705 -241.097158) (xy 380.141906 -241.054144)
			(xy 380.175654 -241.01605) (xy 380.215076 -240.983863) (xy 380.25915 -240.958417) (xy 380.306736 -240.94037)
			(xy 380.3566 -240.93019) (xy 380.407452 -240.928141) (xy 380.457973 -240.934275) (xy 380.506857 -240.948435)
			(xy 380.552836 -240.970252) (xy 380.59472 -240.999162) (xy 380.631424 -241.034417) (xy 380.661997 -241.075103)
			(xy 380.685648 -241.120166) (xy 380.701764 -241.16844) (xy 380.709928 -241.218674) (xy 380.71044 -241.24412)
			(xy 381.028968 -241.24412) (xy 381.032928 -241.195066) (xy 381.044705 -241.147282) (xy 381.063996 -241.102006)
			(xy 381.090299 -241.06041) (xy 381.122934 -241.023573) (xy 381.161055 -240.992448) (xy 381.203676 -240.967841)
			(xy 381.249692 -240.950389) (xy 381.297911 -240.940545) (xy 381.347086 -240.938564) (xy 381.395941 -240.944496)
			(xy 381.443212 -240.958188) (xy 381.487674 -240.979286) (xy 381.528177 -241.007242) (xy 381.56367 -241.041334)
			(xy 381.593235 -241.080678) (xy 381.616106 -241.124255) (xy 381.63169 -241.170936) (xy 381.639585 -241.219513)
			(xy 381.64008 -241.24412) (xy 381.969022 -241.24412) (xy 381.972982 -241.195066) (xy 381.984759 -241.147282)
			(xy 382.00405 -241.102006) (xy 382.030353 -241.06041) (xy 382.062988 -241.023573) (xy 382.101109 -240.992448)
			(xy 382.14373 -240.967841) (xy 382.189746 -240.950389) (xy 382.237965 -240.940545) (xy 382.28714 -240.938564)
			(xy 382.335995 -240.944496) (xy 382.383266 -240.958188) (xy 382.427728 -240.979286) (xy 382.468231 -241.007242)
			(xy 382.503724 -241.041334) (xy 382.533289 -241.080678) (xy 382.55616 -241.124255) (xy 382.571744 -241.170936)
			(xy 382.579639 -241.219513) (xy 382.580134 -241.24412) (xy 382.909076 -241.24412) (xy 382.913036 -241.195066)
			(xy 382.924813 -241.147282) (xy 382.944104 -241.102006) (xy 382.970407 -241.06041) (xy 383.003042 -241.023573)
			(xy 383.041163 -240.992448) (xy 383.083784 -240.967841) (xy 383.1298 -240.950389) (xy 383.178019 -240.940545)
			(xy 383.227194 -240.938564) (xy 383.276049 -240.944496) (xy 383.32332 -240.958188) (xy 383.367782 -240.979286)
			(xy 383.408285 -241.007242) (xy 383.443778 -241.041334) (xy 383.473343 -241.080678) (xy 383.496214 -241.124255)
			(xy 383.511798 -241.170936) (xy 383.519693 -241.219513) (xy 383.520188 -241.24412) (xy 383.84913 -241.24412)
			(xy 383.85309 -241.195066) (xy 383.864867 -241.147282) (xy 383.884158 -241.102006) (xy 383.910461 -241.06041)
			(xy 383.943096 -241.023573) (xy 383.981217 -240.992448) (xy 384.023838 -240.967841) (xy 384.069854 -240.950389)
			(xy 384.118073 -240.940545) (xy 384.167248 -240.938564) (xy 384.216103 -240.944496) (xy 384.263374 -240.958188)
			(xy 384.307836 -240.979286) (xy 384.348339 -241.007242) (xy 384.383832 -241.041334) (xy 384.413397 -241.080678)
			(xy 384.436268 -241.124255) (xy 384.451852 -241.170936) (xy 384.459747 -241.219513) (xy 384.460242 -241.24412)
			(xy 384.78893 -241.24412) (xy 384.79289 -241.195066) (xy 384.804667 -241.147282) (xy 384.823958 -241.102006)
			(xy 384.850261 -241.06041) (xy 384.882896 -241.023573) (xy 384.921017 -240.992448) (xy 384.963638 -240.967841)
			(xy 385.009654 -240.950389) (xy 385.057873 -240.940545) (xy 385.107048 -240.938564) (xy 385.155903 -240.944496)
			(xy 385.203174 -240.958188) (xy 385.247636 -240.979286) (xy 385.288139 -241.007242) (xy 385.323632 -241.041334)
			(xy 385.353197 -241.080678) (xy 385.376068 -241.124255) (xy 385.391652 -241.170936) (xy 385.399547 -241.219513)
			(xy 385.400042 -241.24412) (xy 385.728984 -241.24412) (xy 385.732944 -241.195066) (xy 385.744721 -241.147282)
			(xy 385.764012 -241.102006) (xy 385.790315 -241.06041) (xy 385.82295 -241.023573) (xy 385.861071 -240.992448)
			(xy 385.903692 -240.967841) (xy 385.949708 -240.950389) (xy 385.997927 -240.940545) (xy 386.047102 -240.938564)
			(xy 386.095957 -240.944496) (xy 386.143228 -240.958188) (xy 386.18769 -240.979286) (xy 386.228193 -241.007242)
			(xy 386.263686 -241.041334) (xy 386.293251 -241.080678) (xy 386.316122 -241.124255) (xy 386.331706 -241.170936)
			(xy 386.339601 -241.219513) (xy 386.340096 -241.24412) (xy 386.669038 -241.24412) (xy 386.672998 -241.195066)
			(xy 386.684775 -241.147282) (xy 386.704066 -241.102006) (xy 386.730369 -241.06041) (xy 386.763004 -241.023573)
			(xy 386.801125 -240.992448) (xy 386.843746 -240.967841) (xy 386.889762 -240.950389) (xy 386.937981 -240.940545)
			(xy 386.987156 -240.938564) (xy 387.036011 -240.944496) (xy 387.083282 -240.958188) (xy 387.127744 -240.979286)
			(xy 387.168247 -241.007242) (xy 387.20374 -241.041334) (xy 387.233305 -241.080678) (xy 387.256176 -241.124255)
			(xy 387.27176 -241.170936) (xy 387.279655 -241.219513) (xy 387.28015 -241.24412) (xy 387.279655 -241.268727)
			(xy 387.27176 -241.317304) (xy 387.256176 -241.363985) (xy 387.233305 -241.407562) (xy 387.20374 -241.446906)
			(xy 387.168247 -241.480998) (xy 387.127744 -241.508954) (xy 387.083282 -241.530052) (xy 387.036011 -241.543744)
			(xy 386.987156 -241.549676) (xy 386.937981 -241.547695) (xy 386.889762 -241.537851) (xy 386.843746 -241.520399)
			(xy 386.801125 -241.495792) (xy 386.763004 -241.464667) (xy 386.730369 -241.42783) (xy 386.704066 -241.386234)
			(xy 386.684775 -241.340958) (xy 386.672998 -241.293174) (xy 386.669038 -241.24412) (xy 386.340096 -241.24412)
			(xy 386.339601 -241.268727) (xy 386.331706 -241.317304) (xy 386.316122 -241.363985) (xy 386.293251 -241.407562)
			(xy 386.263686 -241.446906) (xy 386.228193 -241.480998) (xy 386.18769 -241.508954) (xy 386.143228 -241.530052)
			(xy 386.095957 -241.543744) (xy 386.047102 -241.549676) (xy 385.997927 -241.547695) (xy 385.949708 -241.537851)
			(xy 385.903692 -241.520399) (xy 385.861071 -241.495792) (xy 385.82295 -241.464667) (xy 385.790315 -241.42783)
			(xy 385.764012 -241.386234) (xy 385.744721 -241.340958) (xy 385.732944 -241.293174) (xy 385.728984 -241.24412)
			(xy 385.400042 -241.24412) (xy 385.399547 -241.268727) (xy 385.391652 -241.317304) (xy 385.376068 -241.363985)
			(xy 385.353197 -241.407562) (xy 385.323632 -241.446906) (xy 385.288139 -241.480998) (xy 385.247636 -241.508954)
			(xy 385.203174 -241.530052) (xy 385.155903 -241.543744) (xy 385.107048 -241.549676) (xy 385.057873 -241.547695)
			(xy 385.009654 -241.537851) (xy 384.963638 -241.520399) (xy 384.921017 -241.495792) (xy 384.882896 -241.464667)
			(xy 384.850261 -241.42783) (xy 384.823958 -241.386234) (xy 384.804667 -241.340958) (xy 384.79289 -241.293174)
			(xy 384.78893 -241.24412) (xy 384.460242 -241.24412) (xy 384.459747 -241.268727) (xy 384.451852 -241.317304)
			(xy 384.436268 -241.363985) (xy 384.413397 -241.407562) (xy 384.383832 -241.446906) (xy 384.348339 -241.480998)
			(xy 384.307836 -241.508954) (xy 384.263374 -241.530052) (xy 384.216103 -241.543744) (xy 384.167248 -241.549676)
			(xy 384.118073 -241.547695) (xy 384.069854 -241.537851) (xy 384.023838 -241.520399) (xy 383.981217 -241.495792)
			(xy 383.943096 -241.464667) (xy 383.910461 -241.42783) (xy 383.884158 -241.386234) (xy 383.864867 -241.340958)
			(xy 383.85309 -241.293174) (xy 383.84913 -241.24412) (xy 383.520188 -241.24412) (xy 383.519693 -241.268727)
			(xy 383.511798 -241.317304) (xy 383.496214 -241.363985) (xy 383.473343 -241.407562) (xy 383.443778 -241.446906)
			(xy 383.408285 -241.480998) (xy 383.367782 -241.508954) (xy 383.32332 -241.530052) (xy 383.276049 -241.543744)
			(xy 383.227194 -241.549676) (xy 383.178019 -241.547695) (xy 383.1298 -241.537851) (xy 383.083784 -241.520399)
			(xy 383.041163 -241.495792) (xy 383.003042 -241.464667) (xy 382.970407 -241.42783) (xy 382.944104 -241.386234)
			(xy 382.924813 -241.340958) (xy 382.913036 -241.293174) (xy 382.909076 -241.24412) (xy 382.580134 -241.24412)
			(xy 382.579639 -241.268727) (xy 382.571744 -241.317304) (xy 382.55616 -241.363985) (xy 382.533289 -241.407562)
			(xy 382.503724 -241.446906) (xy 382.468231 -241.480998) (xy 382.427728 -241.508954) (xy 382.383266 -241.530052)
			(xy 382.335995 -241.543744) (xy 382.28714 -241.549676) (xy 382.237965 -241.547695) (xy 382.189746 -241.537851)
			(xy 382.14373 -241.520399) (xy 382.101109 -241.495792) (xy 382.062988 -241.464667) (xy 382.030353 -241.42783)
			(xy 382.00405 -241.386234) (xy 381.984759 -241.340958) (xy 381.972982 -241.293174) (xy 381.969022 -241.24412)
			(xy 381.64008 -241.24412) (xy 381.639585 -241.268727) (xy 381.63169 -241.317304) (xy 381.616106 -241.363985)
			(xy 381.593235 -241.407562) (xy 381.56367 -241.446906) (xy 381.528177 -241.480998) (xy 381.487674 -241.508954)
			(xy 381.443212 -241.530052) (xy 381.395941 -241.543744) (xy 381.347086 -241.549676) (xy 381.297911 -241.547695)
			(xy 381.249692 -241.537851) (xy 381.203676 -241.520399) (xy 381.161055 -241.495792) (xy 381.122934 -241.464667)
			(xy 381.090299 -241.42783) (xy 381.063996 -241.386234) (xy 381.044705 -241.340958) (xy 381.032928 -241.293174)
			(xy 381.028968 -241.24412) (xy 380.71044 -241.24412) (xy 380.709928 -241.269566) (xy 380.701764 -241.3198)
			(xy 380.685648 -241.368074) (xy 380.661997 -241.413137) (xy 380.631424 -241.453823) (xy 380.59472 -241.489078)
			(xy 380.552836 -241.517988) (xy 380.506857 -241.539805) (xy 380.457973 -241.553965) (xy 380.407452 -241.560099)
			(xy 380.3566 -241.55805) (xy 380.306736 -241.54787) (xy 380.25915 -241.529823) (xy 380.215076 -241.504377)
			(xy 380.175654 -241.47219) (xy 380.141906 -241.434096) (xy 380.114705 -241.391082) (xy 380.094757 -241.344262)
			(xy 380.082578 -241.294848) (xy 380.078483 -241.24412) (xy 379.77064 -241.24412) (xy 379.770128 -241.269566)
			(xy 379.761964 -241.3198) (xy 379.745848 -241.368074) (xy 379.722197 -241.413137) (xy 379.691624 -241.453823)
			(xy 379.65492 -241.489078) (xy 379.613036 -241.517988) (xy 379.567057 -241.539805) (xy 379.518173 -241.553965)
			(xy 379.467652 -241.560099) (xy 379.4168 -241.55805) (xy 379.366936 -241.54787) (xy 379.31935 -241.529823)
			(xy 379.275276 -241.504377) (xy 379.235854 -241.47219) (xy 379.202106 -241.434096) (xy 379.174905 -241.391082)
			(xy 379.154957 -241.344262) (xy 379.142778 -241.294848) (xy 379.138683 -241.24412) (xy 378.820172 -241.24412)
			(xy 378.819677 -241.268727) (xy 378.811782 -241.317304) (xy 378.796198 -241.363985) (xy 378.773327 -241.407562)
			(xy 378.743762 -241.446906) (xy 378.708269 -241.480998) (xy 378.667766 -241.508954) (xy 378.623304 -241.530052)
			(xy 378.576033 -241.543744) (xy 378.527178 -241.549676) (xy 378.478003 -241.547695) (xy 378.429784 -241.537851)
			(xy 378.383768 -241.520399) (xy 378.341147 -241.495792) (xy 378.303026 -241.464667) (xy 378.270391 -241.42783)
			(xy 378.244088 -241.386234) (xy 378.224797 -241.340958) (xy 378.21302 -241.293174) (xy 378.20906 -241.24412)
			(xy 377.890532 -241.24412) (xy 377.89002 -241.269566) (xy 377.881856 -241.3198) (xy 377.86574 -241.368074)
			(xy 377.842089 -241.413137) (xy 377.811516 -241.453823) (xy 377.774812 -241.489078) (xy 377.732928 -241.517988)
			(xy 377.686949 -241.539805) (xy 377.638065 -241.553965) (xy 377.587544 -241.560099) (xy 377.536692 -241.55805)
			(xy 377.486828 -241.54787) (xy 377.439242 -241.529823) (xy 377.395168 -241.504377) (xy 377.355746 -241.47219)
			(xy 377.321998 -241.434096) (xy 377.294797 -241.391082) (xy 377.274849 -241.344262) (xy 377.26267 -241.294848)
			(xy 377.258575 -241.24412) (xy 376.940064 -241.24412) (xy 376.939569 -241.268727) (xy 376.931674 -241.317304)
			(xy 376.91609 -241.363985) (xy 376.893219 -241.407562) (xy 376.863654 -241.446906) (xy 376.828161 -241.480998)
			(xy 376.787658 -241.508954) (xy 376.743196 -241.530052) (xy 376.695925 -241.543744) (xy 376.64707 -241.549676)
			(xy 376.597895 -241.547695) (xy 376.549676 -241.537851) (xy 376.50366 -241.520399) (xy 376.461039 -241.495792)
			(xy 376.422918 -241.464667) (xy 376.390283 -241.42783) (xy 376.36398 -241.386234) (xy 376.344689 -241.340958)
			(xy 376.332912 -241.293174) (xy 376.328952 -241.24412) (xy 376.010424 -241.24412) (xy 376.009912 -241.269566)
			(xy 376.001748 -241.3198) (xy 375.985632 -241.368074) (xy 375.961981 -241.413137) (xy 375.931408 -241.453823)
			(xy 375.894704 -241.489078) (xy 375.85282 -241.517988) (xy 375.806841 -241.539805) (xy 375.757957 -241.553965)
			(xy 375.707436 -241.560099) (xy 375.656584 -241.55805) (xy 375.60672 -241.54787) (xy 375.559134 -241.529823)
			(xy 375.51506 -241.504377) (xy 375.475638 -241.47219) (xy 375.44189 -241.434096) (xy 375.414689 -241.391082)
			(xy 375.394741 -241.344262) (xy 375.382562 -241.294848) (xy 375.378467 -241.24412) (xy 375.060017 -241.24412)
			(xy 375.058349 -241.283264) (xy 375.047365 -241.334108) (xy 375.038112 -241.35842) (xy 375.028522 -241.380905)
			(xy 375.003239 -241.42274) (xy 374.971604 -241.460004) (xy 374.934429 -241.491742) (xy 374.892665 -241.517141)
			(xy 374.870218 -241.526822) (xy 374.860312 -241.530886) (xy 374.830086 -241.562382) (xy 374.82653 -241.573558)
			(xy 374.812639 -241.614801) (xy 374.77902 -241.695081) (xy 374.738962 -241.772349) (xy 374.692733 -241.846091)
			(xy 374.640641 -241.915816) (xy 374.612154 -241.948716) (xy 374.606058 -241.955574) (xy 374.599454 -241.9731)
			(xy 374.599454 -242.054126) (xy 374.918998 -242.054126) (xy 374.922958 -242.005072) (xy 374.934735 -241.957288)
			(xy 374.954026 -241.912012) (xy 374.980329 -241.870416) (xy 375.012964 -241.833579) (xy 375.051085 -241.802454)
			(xy 375.093706 -241.777847) (xy 375.139722 -241.760395) (xy 375.187941 -241.750551) (xy 375.237116 -241.74857)
			(xy 375.285971 -241.754502) (xy 375.333242 -241.768194) (xy 375.377704 -241.789292) (xy 375.418207 -241.817248)
			(xy 375.4537 -241.85134) (xy 375.483265 -241.890684) (xy 375.506136 -241.934261) (xy 375.52172 -241.980942)
			(xy 375.529615 -242.029519) (xy 375.53011 -242.054126) (xy 375.848621 -242.054126) (xy 375.852716 -242.003398)
			(xy 375.864895 -241.953984) (xy 375.884843 -241.907164) (xy 375.912044 -241.86415) (xy 375.945792 -241.826056)
			(xy 375.985214 -241.793869) (xy 376.029288 -241.768423) (xy 376.076874 -241.750376) (xy 376.126738 -241.740196)
			(xy 376.17759 -241.738147) (xy 376.228111 -241.744281) (xy 376.276995 -241.758441) (xy 376.322974 -241.780258)
			(xy 376.364858 -241.809168) (xy 376.401562 -241.844423) (xy 376.432135 -241.885109) (xy 376.455786 -241.930172)
			(xy 376.471902 -241.978446) (xy 376.480066 -242.02868) (xy 376.480578 -242.054126) (xy 376.788675 -242.054126)
			(xy 376.79277 -242.003398) (xy 376.804949 -241.953984) (xy 376.824897 -241.907164) (xy 376.852098 -241.86415)
			(xy 376.885846 -241.826056) (xy 376.925268 -241.793869) (xy 376.969342 -241.768423) (xy 377.016928 -241.750376)
			(xy 377.066792 -241.740196) (xy 377.117644 -241.738147) (xy 377.168165 -241.744281) (xy 377.217049 -241.758441)
			(xy 377.263028 -241.780258) (xy 377.304912 -241.809168) (xy 377.341616 -241.844423) (xy 377.372189 -241.885109)
			(xy 377.39584 -241.930172) (xy 377.411956 -241.978446) (xy 377.42012 -242.02868) (xy 377.420632 -242.054126)
			(xy 378.668529 -242.054126) (xy 378.672624 -242.003398) (xy 378.684803 -241.953984) (xy 378.704751 -241.907164)
			(xy 378.731952 -241.86415) (xy 378.7657 -241.826056) (xy 378.805122 -241.793869) (xy 378.849196 -241.768423)
			(xy 378.896782 -241.750376) (xy 378.946646 -241.740196) (xy 378.997498 -241.738147) (xy 379.048019 -241.744281)
			(xy 379.096903 -241.758441) (xy 379.142882 -241.780258) (xy 379.184766 -241.809168) (xy 379.22147 -241.844423)
			(xy 379.252043 -241.885109) (xy 379.275694 -241.930172) (xy 379.29181 -241.978446) (xy 379.299974 -242.02868)
			(xy 379.300486 -242.054126) (xy 379.619014 -242.054126) (xy 379.622974 -242.005072) (xy 379.634751 -241.957288)
			(xy 379.654042 -241.912012) (xy 379.680345 -241.870416) (xy 379.71298 -241.833579) (xy 379.751101 -241.802454)
			(xy 379.793722 -241.777847) (xy 379.839738 -241.760395) (xy 379.887957 -241.750551) (xy 379.937132 -241.74857)
			(xy 379.985987 -241.754502) (xy 380.033258 -241.768194) (xy 380.07772 -241.789292) (xy 380.118223 -241.817248)
			(xy 380.153716 -241.85134) (xy 380.183281 -241.890684) (xy 380.206152 -241.934261) (xy 380.221736 -241.980942)
			(xy 380.229631 -242.029519) (xy 380.230126 -242.054126) (xy 380.548637 -242.054126) (xy 380.552732 -242.003398)
			(xy 380.564911 -241.953984) (xy 380.584859 -241.907164) (xy 380.61206 -241.86415) (xy 380.645808 -241.826056)
			(xy 380.68523 -241.793869) (xy 380.729304 -241.768423) (xy 380.77689 -241.750376) (xy 380.826754 -241.740196)
			(xy 380.877606 -241.738147) (xy 380.928127 -241.744281) (xy 380.977011 -241.758441) (xy 381.02299 -241.780258)
			(xy 381.064874 -241.809168) (xy 381.101578 -241.844423) (xy 381.132151 -241.885109) (xy 381.155802 -241.930172)
			(xy 381.171918 -241.978446) (xy 381.180082 -242.02868) (xy 381.180594 -242.054126) (xy 381.499122 -242.054126)
			(xy 381.503082 -242.005072) (xy 381.514859 -241.957288) (xy 381.53415 -241.912012) (xy 381.560453 -241.870416)
			(xy 381.593088 -241.833579) (xy 381.631209 -241.802454) (xy 381.67383 -241.777847) (xy 381.719846 -241.760395)
			(xy 381.768065 -241.750551) (xy 381.81724 -241.74857) (xy 381.866095 -241.754502) (xy 381.913366 -241.768194)
			(xy 381.957828 -241.789292) (xy 381.998331 -241.817248) (xy 382.033824 -241.85134) (xy 382.063389 -241.890684)
			(xy 382.08626 -241.934261) (xy 382.101844 -241.980942) (xy 382.109739 -242.029519) (xy 382.110234 -242.054126)
			(xy 382.438922 -242.054126) (xy 382.442882 -242.005072) (xy 382.454659 -241.957288) (xy 382.47395 -241.912012)
			(xy 382.500253 -241.870416) (xy 382.532888 -241.833579) (xy 382.571009 -241.802454) (xy 382.61363 -241.777847)
			(xy 382.659646 -241.760395) (xy 382.707865 -241.750551) (xy 382.75704 -241.74857) (xy 382.805895 -241.754502)
			(xy 382.853166 -241.768194) (xy 382.897628 -241.789292) (xy 382.938131 -241.817248) (xy 382.973624 -241.85134)
			(xy 383.003189 -241.890684) (xy 383.02606 -241.934261) (xy 383.041644 -241.980942) (xy 383.049539 -242.029519)
			(xy 383.050034 -242.054126) (xy 383.378976 -242.054126) (xy 383.382936 -242.005072) (xy 383.394713 -241.957288)
			(xy 383.414004 -241.912012) (xy 383.440307 -241.870416) (xy 383.472942 -241.833579) (xy 383.511063 -241.802454)
			(xy 383.553684 -241.777847) (xy 383.5997 -241.760395) (xy 383.647919 -241.750551) (xy 383.697094 -241.74857)
			(xy 383.745949 -241.754502) (xy 383.79322 -241.768194) (xy 383.837682 -241.789292) (xy 383.878185 -241.817248)
			(xy 383.913678 -241.85134) (xy 383.943243 -241.890684) (xy 383.966114 -241.934261) (xy 383.981698 -241.980942)
			(xy 383.989593 -242.029519) (xy 383.990088 -242.054126) (xy 385.259084 -242.054126) (xy 385.263044 -242.005072)
			(xy 385.274821 -241.957288) (xy 385.294112 -241.912012) (xy 385.320415 -241.870416) (xy 385.35305 -241.833579)
			(xy 385.391171 -241.802454) (xy 385.433792 -241.777847) (xy 385.479808 -241.760395) (xy 385.528027 -241.750551)
			(xy 385.577202 -241.74857) (xy 385.626057 -241.754502) (xy 385.673328 -241.768194) (xy 385.71779 -241.789292)
			(xy 385.758293 -241.817248) (xy 385.793786 -241.85134) (xy 385.823351 -241.890684) (xy 385.846222 -241.934261)
			(xy 385.861806 -241.980942) (xy 385.869701 -242.029519) (xy 385.870196 -242.054126) (xy 386.199138 -242.054126)
			(xy 386.203098 -242.005072) (xy 386.214875 -241.957288) (xy 386.234166 -241.912012) (xy 386.260469 -241.870416)
			(xy 386.293104 -241.833579) (xy 386.331225 -241.802454) (xy 386.373846 -241.777847) (xy 386.419862 -241.760395)
			(xy 386.468081 -241.750551) (xy 386.517256 -241.74857) (xy 386.566111 -241.754502) (xy 386.613382 -241.768194)
			(xy 386.657844 -241.789292) (xy 386.698347 -241.817248) (xy 386.73384 -241.85134) (xy 386.763405 -241.890684)
			(xy 386.786276 -241.934261) (xy 386.80186 -241.980942) (xy 386.809755 -242.029519) (xy 386.81025 -242.054126)
			(xy 386.809755 -242.078733) (xy 386.80186 -242.12731) (xy 386.786276 -242.173991) (xy 386.763405 -242.217568)
			(xy 386.73384 -242.256912) (xy 386.698347 -242.291004) (xy 386.657844 -242.31896) (xy 386.613382 -242.340058)
			(xy 386.566111 -242.35375) (xy 386.517256 -242.359682) (xy 386.468081 -242.357701) (xy 386.419862 -242.347857)
			(xy 386.373846 -242.330405) (xy 386.331225 -242.305798) (xy 386.293104 -242.274673) (xy 386.260469 -242.237836)
			(xy 386.234166 -242.19624) (xy 386.214875 -242.150964) (xy 386.203098 -242.10318) (xy 386.199138 -242.054126)
			(xy 385.870196 -242.054126) (xy 385.869701 -242.078733) (xy 385.861806 -242.12731) (xy 385.846222 -242.173991)
			(xy 385.823351 -242.217568) (xy 385.793786 -242.256912) (xy 385.758293 -242.291004) (xy 385.71779 -242.31896)
			(xy 385.673328 -242.340058) (xy 385.626057 -242.35375) (xy 385.577202 -242.359682) (xy 385.528027 -242.357701)
			(xy 385.479808 -242.347857) (xy 385.433792 -242.330405) (xy 385.391171 -242.305798) (xy 385.35305 -242.274673)
			(xy 385.320415 -242.237836) (xy 385.294112 -242.19624) (xy 385.274821 -242.150964) (xy 385.263044 -242.10318)
			(xy 385.259084 -242.054126) (xy 383.990088 -242.054126) (xy 383.989593 -242.078733) (xy 383.981698 -242.12731)
			(xy 383.966114 -242.173991) (xy 383.943243 -242.217568) (xy 383.913678 -242.256912) (xy 383.878185 -242.291004)
			(xy 383.837682 -242.31896) (xy 383.79322 -242.340058) (xy 383.745949 -242.35375) (xy 383.697094 -242.359682)
			(xy 383.647919 -242.357701) (xy 383.5997 -242.347857) (xy 383.553684 -242.330405) (xy 383.511063 -242.305798)
			(xy 383.472942 -242.274673) (xy 383.440307 -242.237836) (xy 383.414004 -242.19624) (xy 383.394713 -242.150964)
			(xy 383.382936 -242.10318) (xy 383.378976 -242.054126) (xy 383.050034 -242.054126) (xy 383.049539 -242.078733)
			(xy 383.041644 -242.12731) (xy 383.02606 -242.173991) (xy 383.003189 -242.217568) (xy 382.973624 -242.256912)
			(xy 382.938131 -242.291004) (xy 382.897628 -242.31896) (xy 382.853166 -242.340058) (xy 382.805895 -242.35375)
			(xy 382.75704 -242.359682) (xy 382.707865 -242.357701) (xy 382.659646 -242.347857) (xy 382.61363 -242.330405)
			(xy 382.571009 -242.305798) (xy 382.532888 -242.274673) (xy 382.500253 -242.237836) (xy 382.47395 -242.19624)
			(xy 382.454659 -242.150964) (xy 382.442882 -242.10318) (xy 382.438922 -242.054126) (xy 382.110234 -242.054126)
			(xy 382.109739 -242.078733) (xy 382.101844 -242.12731) (xy 382.08626 -242.173991) (xy 382.063389 -242.217568)
			(xy 382.033824 -242.256912) (xy 381.998331 -242.291004) (xy 381.957828 -242.31896) (xy 381.913366 -242.340058)
			(xy 381.866095 -242.35375) (xy 381.81724 -242.359682) (xy 381.768065 -242.357701) (xy 381.719846 -242.347857)
			(xy 381.67383 -242.330405) (xy 381.631209 -242.305798) (xy 381.593088 -242.274673) (xy 381.560453 -242.237836)
			(xy 381.53415 -242.19624) (xy 381.514859 -242.150964) (xy 381.503082 -242.10318) (xy 381.499122 -242.054126)
			(xy 381.180594 -242.054126) (xy 381.180082 -242.079572) (xy 381.171918 -242.129806) (xy 381.155802 -242.17808)
			(xy 381.132151 -242.223143) (xy 381.101578 -242.263829) (xy 381.064874 -242.299084) (xy 381.02299 -242.327994)
			(xy 380.977011 -242.349811) (xy 380.928127 -242.363971) (xy 380.877606 -242.370105) (xy 380.826754 -242.368056)
			(xy 380.77689 -242.357876) (xy 380.729304 -242.339829) (xy 380.68523 -242.314383) (xy 380.645808 -242.282196)
			(xy 380.61206 -242.244102) (xy 380.584859 -242.201088) (xy 380.564911 -242.154268) (xy 380.552732 -242.104854)
			(xy 380.548637 -242.054126) (xy 380.230126 -242.054126) (xy 380.229631 -242.078733) (xy 380.221736 -242.12731)
			(xy 380.206152 -242.173991) (xy 380.183281 -242.217568) (xy 380.153716 -242.256912) (xy 380.118223 -242.291004)
			(xy 380.07772 -242.31896) (xy 380.033258 -242.340058) (xy 379.985987 -242.35375) (xy 379.937132 -242.359682)
			(xy 379.887957 -242.357701) (xy 379.839738 -242.347857) (xy 379.793722 -242.330405) (xy 379.751101 -242.305798)
			(xy 379.71298 -242.274673) (xy 379.680345 -242.237836) (xy 379.654042 -242.19624) (xy 379.634751 -242.150964)
			(xy 379.622974 -242.10318) (xy 379.619014 -242.054126) (xy 379.300486 -242.054126) (xy 379.299974 -242.079572)
			(xy 379.29181 -242.129806) (xy 379.275694 -242.17808) (xy 379.252043 -242.223143) (xy 379.22147 -242.263829)
			(xy 379.184766 -242.299084) (xy 379.142882 -242.327994) (xy 379.096903 -242.349811) (xy 379.048019 -242.363971)
			(xy 378.997498 -242.370105) (xy 378.946646 -242.368056) (xy 378.896782 -242.357876) (xy 378.849196 -242.339829)
			(xy 378.805122 -242.314383) (xy 378.7657 -242.282196) (xy 378.731952 -242.244102) (xy 378.704751 -242.201088)
			(xy 378.684803 -242.154268) (xy 378.672624 -242.104854) (xy 378.668529 -242.054126) (xy 377.420632 -242.054126)
			(xy 377.42012 -242.079572) (xy 377.411956 -242.129806) (xy 377.39584 -242.17808) (xy 377.372189 -242.223143)
			(xy 377.341616 -242.263829) (xy 377.304912 -242.299084) (xy 377.263028 -242.327994) (xy 377.217049 -242.349811)
			(xy 377.168165 -242.363971) (xy 377.117644 -242.370105) (xy 377.066792 -242.368056) (xy 377.016928 -242.357876)
			(xy 376.969342 -242.339829) (xy 376.925268 -242.314383) (xy 376.885846 -242.282196) (xy 376.852098 -242.244102)
			(xy 376.824897 -242.201088) (xy 376.804949 -242.154268) (xy 376.79277 -242.104854) (xy 376.788675 -242.054126)
			(xy 376.480578 -242.054126) (xy 376.480066 -242.079572) (xy 376.471902 -242.129806) (xy 376.455786 -242.17808)
			(xy 376.432135 -242.223143) (xy 376.401562 -242.263829) (xy 376.364858 -242.299084) (xy 376.322974 -242.327994)
			(xy 376.276995 -242.349811) (xy 376.228111 -242.363971) (xy 376.17759 -242.370105) (xy 376.126738 -242.368056)
			(xy 376.076874 -242.357876) (xy 376.029288 -242.339829) (xy 375.985214 -242.314383) (xy 375.945792 -242.282196)
			(xy 375.912044 -242.244102) (xy 375.884843 -242.201088) (xy 375.864895 -242.154268) (xy 375.852716 -242.104854)
			(xy 375.848621 -242.054126) (xy 375.53011 -242.054126) (xy 375.529615 -242.078733) (xy 375.52172 -242.12731)
			(xy 375.506136 -242.173991) (xy 375.483265 -242.217568) (xy 375.4537 -242.256912) (xy 375.418207 -242.291004)
			(xy 375.377704 -242.31896) (xy 375.333242 -242.340058) (xy 375.285971 -242.35375) (xy 375.237116 -242.359682)
			(xy 375.187941 -242.357701) (xy 375.139722 -242.347857) (xy 375.093706 -242.330405) (xy 375.051085 -242.305798)
			(xy 375.012964 -242.274673) (xy 374.980329 -242.237836) (xy 374.954026 -242.19624) (xy 374.934735 -242.150964)
			(xy 374.922958 -242.10318) (xy 374.918998 -242.054126) (xy 374.599454 -242.054126) (xy 374.599454 -242.135152)
			(xy 374.606058 -242.152678) (xy 374.612154 -242.159536) (xy 374.640649 -242.192431) (xy 374.692766 -242.26214)
			(xy 374.739005 -242.335879) (xy 374.779057 -242.413153) (xy 374.812653 -242.493445) (xy 374.82653 -242.534694)
			(xy 374.830086 -242.54587) (xy 374.860312 -242.577366) (xy 374.870218 -242.58143) (xy 374.892362 -242.590955)
			(xy 374.933577 -242.61595) (xy 374.970352 -242.647111) (xy 375.001774 -242.683664) (xy 375.027061 -242.724701)
			(xy 375.045586 -242.769201) (xy 375.056887 -242.81606) (xy 375.060684 -242.864112) (xy 375.060682 -242.864132)
			(xy 375.378467 -242.864132) (xy 375.382562 -242.813404) (xy 375.394741 -242.76399) (xy 375.414689 -242.71717)
			(xy 375.44189 -242.674156) (xy 375.475638 -242.636062) (xy 375.51506 -242.603875) (xy 375.559134 -242.578429)
			(xy 375.60672 -242.560382) (xy 375.656584 -242.550202) (xy 375.707436 -242.548153) (xy 375.757957 -242.554287)
			(xy 375.806841 -242.568447) (xy 375.85282 -242.590264) (xy 375.894704 -242.619174) (xy 375.931408 -242.654429)
			(xy 375.961981 -242.695115) (xy 375.985632 -242.740178) (xy 376.001748 -242.788452) (xy 376.009912 -242.838686)
			(xy 376.010424 -242.864132) (xy 376.328952 -242.864132) (xy 376.332912 -242.815078) (xy 376.344689 -242.767294)
			(xy 376.36398 -242.722018) (xy 376.390283 -242.680422) (xy 376.422918 -242.643585) (xy 376.461039 -242.61246)
			(xy 376.50366 -242.587853) (xy 376.549676 -242.570401) (xy 376.597895 -242.560557) (xy 376.64707 -242.558576)
			(xy 376.695925 -242.564508) (xy 376.743196 -242.5782) (xy 376.787658 -242.599298) (xy 376.828161 -242.627254)
			(xy 376.863654 -242.661346) (xy 376.893219 -242.70069) (xy 376.91609 -242.744267) (xy 376.931674 -242.790948)
			(xy 376.939569 -242.839525) (xy 376.940064 -242.864132) (xy 377.258575 -242.864132) (xy 377.26267 -242.813404)
			(xy 377.274849 -242.76399) (xy 377.294797 -242.71717) (xy 377.321998 -242.674156) (xy 377.355746 -242.636062)
			(xy 377.395168 -242.603875) (xy 377.439242 -242.578429) (xy 377.486828 -242.560382) (xy 377.536692 -242.550202)
			(xy 377.587544 -242.548153) (xy 377.638065 -242.554287) (xy 377.686949 -242.568447) (xy 377.732928 -242.590264)
			(xy 377.774812 -242.619174) (xy 377.811516 -242.654429) (xy 377.842089 -242.695115) (xy 377.86574 -242.740178)
			(xy 377.881856 -242.788452) (xy 377.89002 -242.838686) (xy 377.890532 -242.864132) (xy 378.20906 -242.864132)
			(xy 378.21302 -242.815078) (xy 378.224797 -242.767294) (xy 378.244088 -242.722018) (xy 378.270391 -242.680422)
			(xy 378.303026 -242.643585) (xy 378.341147 -242.61246) (xy 378.383768 -242.587853) (xy 378.429784 -242.570401)
			(xy 378.478003 -242.560557) (xy 378.527178 -242.558576) (xy 378.576033 -242.564508) (xy 378.623304 -242.5782)
			(xy 378.667766 -242.599298) (xy 378.708269 -242.627254) (xy 378.743762 -242.661346) (xy 378.773327 -242.70069)
			(xy 378.796198 -242.744267) (xy 378.811782 -242.790948) (xy 378.819677 -242.839525) (xy 378.820172 -242.864132)
			(xy 379.138683 -242.864132) (xy 379.142778 -242.813404) (xy 379.154957 -242.76399) (xy 379.174905 -242.71717)
			(xy 379.202106 -242.674156) (xy 379.235854 -242.636062) (xy 379.275276 -242.603875) (xy 379.31935 -242.578429)
			(xy 379.366936 -242.560382) (xy 379.4168 -242.550202) (xy 379.467652 -242.548153) (xy 379.518173 -242.554287)
			(xy 379.567057 -242.568447) (xy 379.613036 -242.590264) (xy 379.65492 -242.619174) (xy 379.691624 -242.654429)
			(xy 379.722197 -242.695115) (xy 379.745848 -242.740178) (xy 379.761964 -242.788452) (xy 379.770128 -242.838686)
			(xy 379.77064 -242.864132) (xy 380.078483 -242.864132) (xy 380.082578 -242.813404) (xy 380.094757 -242.76399)
			(xy 380.114705 -242.71717) (xy 380.141906 -242.674156) (xy 380.175654 -242.636062) (xy 380.215076 -242.603875)
			(xy 380.25915 -242.578429) (xy 380.306736 -242.560382) (xy 380.3566 -242.550202) (xy 380.407452 -242.548153)
			(xy 380.457973 -242.554287) (xy 380.506857 -242.568447) (xy 380.552836 -242.590264) (xy 380.59472 -242.619174)
			(xy 380.631424 -242.654429) (xy 380.661997 -242.695115) (xy 380.685648 -242.740178) (xy 380.701764 -242.788452)
			(xy 380.709928 -242.838686) (xy 380.71044 -242.864132) (xy 381.028968 -242.864132) (xy 381.032928 -242.815078)
			(xy 381.044705 -242.767294) (xy 381.063996 -242.722018) (xy 381.090299 -242.680422) (xy 381.122934 -242.643585)
			(xy 381.161055 -242.61246) (xy 381.203676 -242.587853) (xy 381.249692 -242.570401) (xy 381.297911 -242.560557)
			(xy 381.347086 -242.558576) (xy 381.395941 -242.564508) (xy 381.443212 -242.5782) (xy 381.487674 -242.599298)
			(xy 381.528177 -242.627254) (xy 381.56367 -242.661346) (xy 381.593235 -242.70069) (xy 381.616106 -242.744267)
			(xy 381.63169 -242.790948) (xy 381.639585 -242.839525) (xy 381.64008 -242.864132) (xy 381.969022 -242.864132)
			(xy 381.972982 -242.815078) (xy 381.984759 -242.767294) (xy 382.00405 -242.722018) (xy 382.030353 -242.680422)
			(xy 382.062988 -242.643585) (xy 382.101109 -242.61246) (xy 382.14373 -242.587853) (xy 382.189746 -242.570401)
			(xy 382.237965 -242.560557) (xy 382.28714 -242.558576) (xy 382.335995 -242.564508) (xy 382.383266 -242.5782)
			(xy 382.427728 -242.599298) (xy 382.468231 -242.627254) (xy 382.503724 -242.661346) (xy 382.533289 -242.70069)
			(xy 382.55616 -242.744267) (xy 382.571744 -242.790948) (xy 382.579639 -242.839525) (xy 382.580134 -242.864132)
			(xy 382.909076 -242.864132) (xy 382.913036 -242.815078) (xy 382.924813 -242.767294) (xy 382.944104 -242.722018)
			(xy 382.970407 -242.680422) (xy 383.003042 -242.643585) (xy 383.041163 -242.61246) (xy 383.083784 -242.587853)
			(xy 383.1298 -242.570401) (xy 383.178019 -242.560557) (xy 383.227194 -242.558576) (xy 383.276049 -242.564508)
			(xy 383.32332 -242.5782) (xy 383.367782 -242.599298) (xy 383.408285 -242.627254) (xy 383.443778 -242.661346)
			(xy 383.473343 -242.70069) (xy 383.496214 -242.744267) (xy 383.511798 -242.790948) (xy 383.519693 -242.839525)
			(xy 383.520188 -242.864132) (xy 383.84913 -242.864132) (xy 383.85309 -242.815078) (xy 383.864867 -242.767294)
			(xy 383.884158 -242.722018) (xy 383.910461 -242.680422) (xy 383.943096 -242.643585) (xy 383.981217 -242.61246)
			(xy 384.023838 -242.587853) (xy 384.069854 -242.570401) (xy 384.118073 -242.560557) (xy 384.167248 -242.558576)
			(xy 384.216103 -242.564508) (xy 384.263374 -242.5782) (xy 384.307836 -242.599298) (xy 384.348339 -242.627254)
			(xy 384.383832 -242.661346) (xy 384.413397 -242.70069) (xy 384.436268 -242.744267) (xy 384.451852 -242.790948)
			(xy 384.459747 -242.839525) (xy 384.460242 -242.864132) (xy 384.78893 -242.864132) (xy 384.79289 -242.815078)
			(xy 384.804667 -242.767294) (xy 384.823958 -242.722018) (xy 384.850261 -242.680422) (xy 384.882896 -242.643585)
			(xy 384.921017 -242.61246) (xy 384.963638 -242.587853) (xy 385.009654 -242.570401) (xy 385.057873 -242.560557)
			(xy 385.107048 -242.558576) (xy 385.155903 -242.564508) (xy 385.203174 -242.5782) (xy 385.247636 -242.599298)
			(xy 385.288139 -242.627254) (xy 385.323632 -242.661346) (xy 385.353197 -242.70069) (xy 385.376068 -242.744267)
			(xy 385.391652 -242.790948) (xy 385.399547 -242.839525) (xy 385.400042 -242.864132) (xy 385.728984 -242.864132)
			(xy 385.732944 -242.815078) (xy 385.744721 -242.767294) (xy 385.764012 -242.722018) (xy 385.790315 -242.680422)
			(xy 385.82295 -242.643585) (xy 385.861071 -242.61246) (xy 385.903692 -242.587853) (xy 385.949708 -242.570401)
			(xy 385.997927 -242.560557) (xy 386.047102 -242.558576) (xy 386.095957 -242.564508) (xy 386.143228 -242.5782)
			(xy 386.18769 -242.599298) (xy 386.228193 -242.627254) (xy 386.263686 -242.661346) (xy 386.293251 -242.70069)
			(xy 386.316122 -242.744267) (xy 386.331706 -242.790948) (xy 386.339601 -242.839525) (xy 386.340096 -242.864132)
			(xy 386.669038 -242.864132) (xy 386.672998 -242.815078) (xy 386.684775 -242.767294) (xy 386.704066 -242.722018)
			(xy 386.730369 -242.680422) (xy 386.763004 -242.643585) (xy 386.801125 -242.61246) (xy 386.843746 -242.587853)
			(xy 386.889762 -242.570401) (xy 386.937981 -242.560557) (xy 386.987156 -242.558576) (xy 387.036011 -242.564508)
			(xy 387.083282 -242.5782) (xy 387.127744 -242.599298) (xy 387.168247 -242.627254) (xy 387.20374 -242.661346)
			(xy 387.233305 -242.70069) (xy 387.256176 -242.744267) (xy 387.27176 -242.790948) (xy 387.279655 -242.839525)
			(xy 387.28015 -242.864132) (xy 387.279655 -242.888739) (xy 387.27176 -242.937316) (xy 387.256176 -242.983997)
			(xy 387.233305 -243.027574) (xy 387.20374 -243.066918) (xy 387.168247 -243.10101) (xy 387.127744 -243.128966)
			(xy 387.083282 -243.150064) (xy 387.036011 -243.163756) (xy 386.987156 -243.169688) (xy 386.937981 -243.167707)
			(xy 386.889762 -243.157863) (xy 386.843746 -243.140411) (xy 386.801125 -243.115804) (xy 386.763004 -243.084679)
			(xy 386.730369 -243.047842) (xy 386.704066 -243.006246) (xy 386.684775 -242.96097) (xy 386.672998 -242.913186)
			(xy 386.669038 -242.864132) (xy 386.340096 -242.864132) (xy 386.339601 -242.888739) (xy 386.331706 -242.937316)
			(xy 386.316122 -242.983997) (xy 386.293251 -243.027574) (xy 386.263686 -243.066918) (xy 386.228193 -243.10101)
			(xy 386.18769 -243.128966) (xy 386.143228 -243.150064) (xy 386.095957 -243.163756) (xy 386.047102 -243.169688)
			(xy 385.997927 -243.167707) (xy 385.949708 -243.157863) (xy 385.903692 -243.140411) (xy 385.861071 -243.115804)
			(xy 385.82295 -243.084679) (xy 385.790315 -243.047842) (xy 385.764012 -243.006246) (xy 385.744721 -242.96097)
			(xy 385.732944 -242.913186) (xy 385.728984 -242.864132) (xy 385.400042 -242.864132) (xy 385.399547 -242.888739)
			(xy 385.391652 -242.937316) (xy 385.376068 -242.983997) (xy 385.353197 -243.027574) (xy 385.323632 -243.066918)
			(xy 385.288139 -243.10101) (xy 385.247636 -243.128966) (xy 385.203174 -243.150064) (xy 385.155903 -243.163756)
			(xy 385.107048 -243.169688) (xy 385.057873 -243.167707) (xy 385.009654 -243.157863) (xy 384.963638 -243.140411)
			(xy 384.921017 -243.115804) (xy 384.882896 -243.084679) (xy 384.850261 -243.047842) (xy 384.823958 -243.006246)
			(xy 384.804667 -242.96097) (xy 384.79289 -242.913186) (xy 384.78893 -242.864132) (xy 384.460242 -242.864132)
			(xy 384.459747 -242.888739) (xy 384.451852 -242.937316) (xy 384.436268 -242.983997) (xy 384.413397 -243.027574)
			(xy 384.383832 -243.066918) (xy 384.348339 -243.10101) (xy 384.307836 -243.128966) (xy 384.263374 -243.150064)
			(xy 384.216103 -243.163756) (xy 384.167248 -243.169688) (xy 384.118073 -243.167707) (xy 384.069854 -243.157863)
			(xy 384.023838 -243.140411) (xy 383.981217 -243.115804) (xy 383.943096 -243.084679) (xy 383.910461 -243.047842)
			(xy 383.884158 -243.006246) (xy 383.864867 -242.96097) (xy 383.85309 -242.913186) (xy 383.84913 -242.864132)
			(xy 383.520188 -242.864132) (xy 383.519693 -242.888739) (xy 383.511798 -242.937316) (xy 383.496214 -242.983997)
			(xy 383.473343 -243.027574) (xy 383.443778 -243.066918) (xy 383.408285 -243.10101) (xy 383.367782 -243.128966)
			(xy 383.32332 -243.150064) (xy 383.276049 -243.163756) (xy 383.227194 -243.169688) (xy 383.178019 -243.167707)
			(xy 383.1298 -243.157863) (xy 383.083784 -243.140411) (xy 383.041163 -243.115804) (xy 383.003042 -243.084679)
			(xy 382.970407 -243.047842) (xy 382.944104 -243.006246) (xy 382.924813 -242.96097) (xy 382.913036 -242.913186)
			(xy 382.909076 -242.864132) (xy 382.580134 -242.864132) (xy 382.579639 -242.888739) (xy 382.571744 -242.937316)
			(xy 382.55616 -242.983997) (xy 382.533289 -243.027574) (xy 382.503724 -243.066918) (xy 382.468231 -243.10101)
			(xy 382.427728 -243.128966) (xy 382.383266 -243.150064) (xy 382.335995 -243.163756) (xy 382.28714 -243.169688)
			(xy 382.237965 -243.167707) (xy 382.189746 -243.157863) (xy 382.14373 -243.140411) (xy 382.101109 -243.115804)
			(xy 382.062988 -243.084679) (xy 382.030353 -243.047842) (xy 382.00405 -243.006246) (xy 381.984759 -242.96097)
			(xy 381.972982 -242.913186) (xy 381.969022 -242.864132) (xy 381.64008 -242.864132) (xy 381.639585 -242.888739)
			(xy 381.63169 -242.937316) (xy 381.616106 -242.983997) (xy 381.593235 -243.027574) (xy 381.56367 -243.066918)
			(xy 381.528177 -243.10101) (xy 381.487674 -243.128966) (xy 381.443212 -243.150064) (xy 381.395941 -243.163756)
			(xy 381.347086 -243.169688) (xy 381.297911 -243.167707) (xy 381.249692 -243.157863) (xy 381.203676 -243.140411)
			(xy 381.161055 -243.115804) (xy 381.122934 -243.084679) (xy 381.090299 -243.047842) (xy 381.063996 -243.006246)
			(xy 381.044705 -242.96097) (xy 381.032928 -242.913186) (xy 381.028968 -242.864132) (xy 380.71044 -242.864132)
			(xy 380.709928 -242.889578) (xy 380.701764 -242.939812) (xy 380.685648 -242.988086) (xy 380.661997 -243.033149)
			(xy 380.631424 -243.073835) (xy 380.59472 -243.10909) (xy 380.552836 -243.138) (xy 380.506857 -243.159817)
			(xy 380.457973 -243.173977) (xy 380.407452 -243.180111) (xy 380.3566 -243.178062) (xy 380.306736 -243.167882)
			(xy 380.25915 -243.149835) (xy 380.215076 -243.124389) (xy 380.175654 -243.092202) (xy 380.141906 -243.054108)
			(xy 380.114705 -243.011094) (xy 380.094757 -242.964274) (xy 380.082578 -242.91486) (xy 380.078483 -242.864132)
			(xy 379.77064 -242.864132) (xy 379.770128 -242.889578) (xy 379.761964 -242.939812) (xy 379.745848 -242.988086)
			(xy 379.722197 -243.033149) (xy 379.691624 -243.073835) (xy 379.65492 -243.10909) (xy 379.613036 -243.138)
			(xy 379.567057 -243.159817) (xy 379.518173 -243.173977) (xy 379.467652 -243.180111) (xy 379.4168 -243.178062)
			(xy 379.366936 -243.167882) (xy 379.31935 -243.149835) (xy 379.275276 -243.124389) (xy 379.235854 -243.092202)
			(xy 379.202106 -243.054108) (xy 379.174905 -243.011094) (xy 379.154957 -242.964274) (xy 379.142778 -242.91486)
			(xy 379.138683 -242.864132) (xy 378.820172 -242.864132) (xy 378.819677 -242.888739) (xy 378.811782 -242.937316)
			(xy 378.796198 -242.983997) (xy 378.773327 -243.027574) (xy 378.743762 -243.066918) (xy 378.708269 -243.10101)
			(xy 378.667766 -243.128966) (xy 378.623304 -243.150064) (xy 378.576033 -243.163756) (xy 378.527178 -243.169688)
			(xy 378.478003 -243.167707) (xy 378.429784 -243.157863) (xy 378.383768 -243.140411) (xy 378.341147 -243.115804)
			(xy 378.303026 -243.084679) (xy 378.270391 -243.047842) (xy 378.244088 -243.006246) (xy 378.224797 -242.96097)
			(xy 378.21302 -242.913186) (xy 378.20906 -242.864132) (xy 377.890532 -242.864132) (xy 377.89002 -242.889578)
			(xy 377.881856 -242.939812) (xy 377.86574 -242.988086) (xy 377.842089 -243.033149) (xy 377.811516 -243.073835)
			(xy 377.774812 -243.10909) (xy 377.732928 -243.138) (xy 377.686949 -243.159817) (xy 377.638065 -243.173977)
			(xy 377.587544 -243.180111) (xy 377.536692 -243.178062) (xy 377.486828 -243.167882) (xy 377.439242 -243.149835)
			(xy 377.395168 -243.124389) (xy 377.355746 -243.092202) (xy 377.321998 -243.054108) (xy 377.294797 -243.011094)
			(xy 377.274849 -242.964274) (xy 377.26267 -242.91486) (xy 377.258575 -242.864132) (xy 376.940064 -242.864132)
			(xy 376.939569 -242.888739) (xy 376.931674 -242.937316) (xy 376.91609 -242.983997) (xy 376.893219 -243.027574)
			(xy 376.863654 -243.066918) (xy 376.828161 -243.10101) (xy 376.787658 -243.128966) (xy 376.743196 -243.150064)
			(xy 376.695925 -243.163756) (xy 376.64707 -243.169688) (xy 376.597895 -243.167707) (xy 376.549676 -243.157863)
			(xy 376.50366 -243.140411) (xy 376.461039 -243.115804) (xy 376.422918 -243.084679) (xy 376.390283 -243.047842)
			(xy 376.36398 -243.006246) (xy 376.344689 -242.96097) (xy 376.332912 -242.913186) (xy 376.328952 -242.864132)
			(xy 376.010424 -242.864132) (xy 376.009912 -242.889578) (xy 376.001748 -242.939812) (xy 375.985632 -242.988086)
			(xy 375.961981 -243.033149) (xy 375.931408 -243.073835) (xy 375.894704 -243.10909) (xy 375.85282 -243.138)
			(xy 375.806841 -243.159817) (xy 375.757957 -243.173977) (xy 375.707436 -243.180111) (xy 375.656584 -243.178062)
			(xy 375.60672 -243.167882) (xy 375.559134 -243.149835) (xy 375.51506 -243.124389) (xy 375.475638 -243.092202)
			(xy 375.44189 -243.054108) (xy 375.414689 -243.011094) (xy 375.394741 -242.964274) (xy 375.382562 -242.91486)
			(xy 375.378467 -242.864132) (xy 375.060682 -242.864132) (xy 375.056883 -242.912164) (xy 375.045578 -242.959022)
			(xy 375.02705 -243.003521) (xy 375.00176 -243.044556) (xy 374.970335 -243.081106) (xy 374.933557 -243.112264)
			(xy 374.89234 -243.137256) (xy 374.870218 -243.146834) (xy 374.860312 -243.150898) (xy 374.830086 -243.182394)
			(xy 374.82653 -243.19357) (xy 374.812639 -243.234813) (xy 374.779019 -243.315092) (xy 374.73896 -243.39236)
			(xy 374.69273 -243.466101) (xy 374.640638 -243.535825) (xy 374.612154 -243.568728) (xy 374.606058 -243.575586)
			(xy 374.599454 -243.593112) (xy 374.599454 -243.674138) (xy 375.848621 -243.674138) (xy 375.852716 -243.62341)
			(xy 375.864895 -243.573996) (xy 375.884843 -243.527176) (xy 375.912044 -243.484162) (xy 375.945792 -243.446068)
			(xy 375.985214 -243.413881) (xy 376.029288 -243.388435) (xy 376.076874 -243.370388) (xy 376.126738 -243.360208)
			(xy 376.17759 -243.358159) (xy 376.228111 -243.364293) (xy 376.276995 -243.378453) (xy 376.322974 -243.40027)
			(xy 376.364858 -243.42918) (xy 376.401562 -243.464435) (xy 376.432135 -243.505121) (xy 376.455786 -243.550184)
			(xy 376.471902 -243.598458) (xy 376.480066 -243.648692) (xy 376.480578 -243.674138) (xy 376.788675 -243.674138)
			(xy 376.79277 -243.62341) (xy 376.804949 -243.573996) (xy 376.824897 -243.527176) (xy 376.852098 -243.484162)
			(xy 376.885846 -243.446068) (xy 376.925268 -243.413881) (xy 376.969342 -243.388435) (xy 377.016928 -243.370388)
			(xy 377.066792 -243.360208) (xy 377.117644 -243.358159) (xy 377.168165 -243.364293) (xy 377.217049 -243.378453)
			(xy 377.263028 -243.40027) (xy 377.304912 -243.42918) (xy 377.341616 -243.464435) (xy 377.372189 -243.505121)
			(xy 377.39584 -243.550184) (xy 377.411956 -243.598458) (xy 377.42012 -243.648692) (xy 377.420632 -243.674138)
			(xy 377.738906 -243.674138) (xy 377.742866 -243.625084) (xy 377.754643 -243.5773) (xy 377.773934 -243.532024)
			(xy 377.800237 -243.490428) (xy 377.832872 -243.453591) (xy 377.870993 -243.422466) (xy 377.913614 -243.397859)
			(xy 377.95963 -243.380407) (xy 378.007849 -243.370563) (xy 378.057024 -243.368582) (xy 378.105879 -243.374514)
			(xy 378.15315 -243.388206) (xy 378.197612 -243.409304) (xy 378.238115 -243.43726) (xy 378.273608 -243.471352)
			(xy 378.303173 -243.510696) (xy 378.326044 -243.554273) (xy 378.341628 -243.600954) (xy 378.349523 -243.649531)
			(xy 378.350018 -243.674138) (xy 378.668529 -243.674138) (xy 378.672624 -243.62341) (xy 378.684803 -243.573996)
			(xy 378.704751 -243.527176) (xy 378.731952 -243.484162) (xy 378.7657 -243.446068) (xy 378.805122 -243.413881)
			(xy 378.849196 -243.388435) (xy 378.896782 -243.370388) (xy 378.946646 -243.360208) (xy 378.997498 -243.358159)
			(xy 379.048019 -243.364293) (xy 379.096903 -243.378453) (xy 379.142882 -243.40027) (xy 379.184766 -243.42918)
			(xy 379.22147 -243.464435) (xy 379.252043 -243.505121) (xy 379.275694 -243.550184) (xy 379.29181 -243.598458)
			(xy 379.299974 -243.648692) (xy 379.300486 -243.674138) (xy 379.619014 -243.674138) (xy 379.622974 -243.625084)
			(xy 379.634751 -243.5773) (xy 379.654042 -243.532024) (xy 379.680345 -243.490428) (xy 379.71298 -243.453591)
			(xy 379.751101 -243.422466) (xy 379.793722 -243.397859) (xy 379.839738 -243.380407) (xy 379.887957 -243.370563)
			(xy 379.937132 -243.368582) (xy 379.985987 -243.374514) (xy 380.033258 -243.388206) (xy 380.07772 -243.409304)
			(xy 380.118223 -243.43726) (xy 380.153716 -243.471352) (xy 380.183281 -243.510696) (xy 380.206152 -243.554273)
			(xy 380.221736 -243.600954) (xy 380.229631 -243.649531) (xy 380.230126 -243.674138) (xy 380.548637 -243.674138)
			(xy 380.552732 -243.62341) (xy 380.564911 -243.573996) (xy 380.584859 -243.527176) (xy 380.61206 -243.484162)
			(xy 380.645808 -243.446068) (xy 380.68523 -243.413881) (xy 380.729304 -243.388435) (xy 380.77689 -243.370388)
			(xy 380.826754 -243.360208) (xy 380.877606 -243.358159) (xy 380.928127 -243.364293) (xy 380.977011 -243.378453)
			(xy 381.02299 -243.40027) (xy 381.064874 -243.42918) (xy 381.101578 -243.464435) (xy 381.132151 -243.505121)
			(xy 381.155802 -243.550184) (xy 381.171918 -243.598458) (xy 381.180082 -243.648692) (xy 381.180594 -243.674138)
			(xy 381.499122 -243.674138) (xy 381.503082 -243.625084) (xy 381.514859 -243.5773) (xy 381.53415 -243.532024)
			(xy 381.560453 -243.490428) (xy 381.593088 -243.453591) (xy 381.631209 -243.422466) (xy 381.67383 -243.397859)
			(xy 381.719846 -243.380407) (xy 381.768065 -243.370563) (xy 381.81724 -243.368582) (xy 381.866095 -243.374514)
			(xy 381.913366 -243.388206) (xy 381.957828 -243.409304) (xy 381.998331 -243.43726) (xy 382.033824 -243.471352)
			(xy 382.063389 -243.510696) (xy 382.08626 -243.554273) (xy 382.101844 -243.600954) (xy 382.109739 -243.649531)
			(xy 382.110234 -243.674138) (xy 382.438922 -243.674138) (xy 382.442882 -243.625084) (xy 382.454659 -243.5773)
			(xy 382.47395 -243.532024) (xy 382.500253 -243.490428) (xy 382.532888 -243.453591) (xy 382.571009 -243.422466)
			(xy 382.61363 -243.397859) (xy 382.659646 -243.380407) (xy 382.707865 -243.370563) (xy 382.75704 -243.368582)
			(xy 382.805895 -243.374514) (xy 382.853166 -243.388206) (xy 382.897628 -243.409304) (xy 382.938131 -243.43726)
			(xy 382.973624 -243.471352) (xy 383.003189 -243.510696) (xy 383.02606 -243.554273) (xy 383.041644 -243.600954)
			(xy 383.049539 -243.649531) (xy 383.050034 -243.674138) (xy 383.378976 -243.674138) (xy 383.382936 -243.625084)
			(xy 383.394713 -243.5773) (xy 383.414004 -243.532024) (xy 383.440307 -243.490428) (xy 383.472942 -243.453591)
			(xy 383.511063 -243.422466) (xy 383.553684 -243.397859) (xy 383.5997 -243.380407) (xy 383.647919 -243.370563)
			(xy 383.697094 -243.368582) (xy 383.745949 -243.374514) (xy 383.79322 -243.388206) (xy 383.837682 -243.409304)
			(xy 383.878185 -243.43726) (xy 383.913678 -243.471352) (xy 383.943243 -243.510696) (xy 383.966114 -243.554273)
			(xy 383.981698 -243.600954) (xy 383.989593 -243.649531) (xy 383.990088 -243.674138) (xy 384.31903 -243.674138)
			(xy 384.32299 -243.625084) (xy 384.334767 -243.5773) (xy 384.354058 -243.532024) (xy 384.380361 -243.490428)
			(xy 384.412996 -243.453591) (xy 384.451117 -243.422466) (xy 384.493738 -243.397859) (xy 384.539754 -243.380407)
			(xy 384.587973 -243.370563) (xy 384.637148 -243.368582) (xy 384.686003 -243.374514) (xy 384.733274 -243.388206)
			(xy 384.777736 -243.409304) (xy 384.818239 -243.43726) (xy 384.853732 -243.471352) (xy 384.883297 -243.510696)
			(xy 384.906168 -243.554273) (xy 384.921752 -243.600954) (xy 384.929647 -243.649531) (xy 384.930142 -243.674138)
			(xy 385.259084 -243.674138) (xy 385.263044 -243.625084) (xy 385.274821 -243.5773) (xy 385.294112 -243.532024)
			(xy 385.320415 -243.490428) (xy 385.35305 -243.453591) (xy 385.391171 -243.422466) (xy 385.433792 -243.397859)
			(xy 385.479808 -243.380407) (xy 385.528027 -243.370563) (xy 385.577202 -243.368582) (xy 385.626057 -243.374514)
			(xy 385.673328 -243.388206) (xy 385.71779 -243.409304) (xy 385.758293 -243.43726) (xy 385.793786 -243.471352)
			(xy 385.823351 -243.510696) (xy 385.846222 -243.554273) (xy 385.861806 -243.600954) (xy 385.869701 -243.649531)
			(xy 385.870196 -243.674138) (xy 386.199138 -243.674138) (xy 386.203098 -243.625084) (xy 386.214875 -243.5773)
			(xy 386.234166 -243.532024) (xy 386.260469 -243.490428) (xy 386.293104 -243.453591) (xy 386.331225 -243.422466)
			(xy 386.373846 -243.397859) (xy 386.419862 -243.380407) (xy 386.468081 -243.370563) (xy 386.517256 -243.368582)
			(xy 386.566111 -243.374514) (xy 386.613382 -243.388206) (xy 386.657844 -243.409304) (xy 386.698347 -243.43726)
			(xy 386.73384 -243.471352) (xy 386.763405 -243.510696) (xy 386.786276 -243.554273) (xy 386.80186 -243.600954)
			(xy 386.809755 -243.649531) (xy 386.81025 -243.674138) (xy 386.809755 -243.698745) (xy 386.80186 -243.747322)
			(xy 386.786276 -243.794003) (xy 386.763405 -243.83758) (xy 386.73384 -243.876924) (xy 386.698347 -243.911016)
			(xy 386.657844 -243.938972) (xy 386.613382 -243.96007) (xy 386.566111 -243.973762) (xy 386.517256 -243.979694)
			(xy 386.468081 -243.977713) (xy 386.419862 -243.967869) (xy 386.373846 -243.950417) (xy 386.331225 -243.92581)
			(xy 386.293104 -243.894685) (xy 386.260469 -243.857848) (xy 386.234166 -243.816252) (xy 386.214875 -243.770976)
			(xy 386.203098 -243.723192) (xy 386.199138 -243.674138) (xy 385.870196 -243.674138) (xy 385.869701 -243.698745)
			(xy 385.861806 -243.747322) (xy 385.846222 -243.794003) (xy 385.823351 -243.83758) (xy 385.793786 -243.876924)
			(xy 385.758293 -243.911016) (xy 385.71779 -243.938972) (xy 385.673328 -243.96007) (xy 385.626057 -243.973762)
			(xy 385.577202 -243.979694) (xy 385.528027 -243.977713) (xy 385.479808 -243.967869) (xy 385.433792 -243.950417)
			(xy 385.391171 -243.92581) (xy 385.35305 -243.894685) (xy 385.320415 -243.857848) (xy 385.294112 -243.816252)
			(xy 385.274821 -243.770976) (xy 385.263044 -243.723192) (xy 385.259084 -243.674138) (xy 384.930142 -243.674138)
			(xy 384.929647 -243.698745) (xy 384.921752 -243.747322) (xy 384.906168 -243.794003) (xy 384.883297 -243.83758)
			(xy 384.853732 -243.876924) (xy 384.818239 -243.911016) (xy 384.777736 -243.938972) (xy 384.733274 -243.96007)
			(xy 384.686003 -243.973762) (xy 384.637148 -243.979694) (xy 384.587973 -243.977713) (xy 384.539754 -243.967869)
			(xy 384.493738 -243.950417) (xy 384.451117 -243.92581) (xy 384.412996 -243.894685) (xy 384.380361 -243.857848)
			(xy 384.354058 -243.816252) (xy 384.334767 -243.770976) (xy 384.32299 -243.723192) (xy 384.31903 -243.674138)
			(xy 383.990088 -243.674138) (xy 383.989593 -243.698745) (xy 383.981698 -243.747322) (xy 383.966114 -243.794003)
			(xy 383.943243 -243.83758) (xy 383.913678 -243.876924) (xy 383.878185 -243.911016) (xy 383.837682 -243.938972)
			(xy 383.79322 -243.96007) (xy 383.745949 -243.973762) (xy 383.697094 -243.979694) (xy 383.647919 -243.977713)
			(xy 383.5997 -243.967869) (xy 383.553684 -243.950417) (xy 383.511063 -243.92581) (xy 383.472942 -243.894685)
			(xy 383.440307 -243.857848) (xy 383.414004 -243.816252) (xy 383.394713 -243.770976) (xy 383.382936 -243.723192)
			(xy 383.378976 -243.674138) (xy 383.050034 -243.674138) (xy 383.049539 -243.698745) (xy 383.041644 -243.747322)
			(xy 383.02606 -243.794003) (xy 383.003189 -243.83758) (xy 382.973624 -243.876924) (xy 382.938131 -243.911016)
			(xy 382.897628 -243.938972) (xy 382.853166 -243.96007) (xy 382.805895 -243.973762) (xy 382.75704 -243.979694)
			(xy 382.707865 -243.977713) (xy 382.659646 -243.967869) (xy 382.61363 -243.950417) (xy 382.571009 -243.92581)
			(xy 382.532888 -243.894685) (xy 382.500253 -243.857848) (xy 382.47395 -243.816252) (xy 382.454659 -243.770976)
			(xy 382.442882 -243.723192) (xy 382.438922 -243.674138) (xy 382.110234 -243.674138) (xy 382.109739 -243.698745)
			(xy 382.101844 -243.747322) (xy 382.08626 -243.794003) (xy 382.063389 -243.83758) (xy 382.033824 -243.876924)
			(xy 381.998331 -243.911016) (xy 381.957828 -243.938972) (xy 381.913366 -243.96007) (xy 381.866095 -243.973762)
			(xy 381.81724 -243.979694) (xy 381.768065 -243.977713) (xy 381.719846 -243.967869) (xy 381.67383 -243.950417)
			(xy 381.631209 -243.92581) (xy 381.593088 -243.894685) (xy 381.560453 -243.857848) (xy 381.53415 -243.816252)
			(xy 381.514859 -243.770976) (xy 381.503082 -243.723192) (xy 381.499122 -243.674138) (xy 381.180594 -243.674138)
			(xy 381.180082 -243.699584) (xy 381.171918 -243.749818) (xy 381.155802 -243.798092) (xy 381.132151 -243.843155)
			(xy 381.101578 -243.883841) (xy 381.064874 -243.919096) (xy 381.02299 -243.948006) (xy 380.977011 -243.969823)
			(xy 380.928127 -243.983983) (xy 380.877606 -243.990117) (xy 380.826754 -243.988068) (xy 380.77689 -243.977888)
			(xy 380.729304 -243.959841) (xy 380.68523 -243.934395) (xy 380.645808 -243.902208) (xy 380.61206 -243.864114)
			(xy 380.584859 -243.8211) (xy 380.564911 -243.77428) (xy 380.552732 -243.724866) (xy 380.548637 -243.674138)
			(xy 380.230126 -243.674138) (xy 380.229631 -243.698745) (xy 380.221736 -243.747322) (xy 380.206152 -243.794003)
			(xy 380.183281 -243.83758) (xy 380.153716 -243.876924) (xy 380.118223 -243.911016) (xy 380.07772 -243.938972)
			(xy 380.033258 -243.96007) (xy 379.985987 -243.973762) (xy 379.937132 -243.979694) (xy 379.887957 -243.977713)
			(xy 379.839738 -243.967869) (xy 379.793722 -243.950417) (xy 379.751101 -243.92581) (xy 379.71298 -243.894685)
			(xy 379.680345 -243.857848) (xy 379.654042 -243.816252) (xy 379.634751 -243.770976) (xy 379.622974 -243.723192)
			(xy 379.619014 -243.674138) (xy 379.300486 -243.674138) (xy 379.299974 -243.699584) (xy 379.29181 -243.749818)
			(xy 379.275694 -243.798092) (xy 379.252043 -243.843155) (xy 379.22147 -243.883841) (xy 379.184766 -243.919096)
			(xy 379.142882 -243.948006) (xy 379.096903 -243.969823) (xy 379.048019 -243.983983) (xy 378.997498 -243.990117)
			(xy 378.946646 -243.988068) (xy 378.896782 -243.977888) (xy 378.849196 -243.959841) (xy 378.805122 -243.934395)
			(xy 378.7657 -243.902208) (xy 378.731952 -243.864114) (xy 378.704751 -243.8211) (xy 378.684803 -243.77428)
			(xy 378.672624 -243.724866) (xy 378.668529 -243.674138) (xy 378.350018 -243.674138) (xy 378.349523 -243.698745)
			(xy 378.341628 -243.747322) (xy 378.326044 -243.794003) (xy 378.303173 -243.83758) (xy 378.273608 -243.876924)
			(xy 378.238115 -243.911016) (xy 378.197612 -243.938972) (xy 378.15315 -243.96007) (xy 378.105879 -243.973762)
			(xy 378.057024 -243.979694) (xy 378.007849 -243.977713) (xy 377.95963 -243.967869) (xy 377.913614 -243.950417)
			(xy 377.870993 -243.92581) (xy 377.832872 -243.894685) (xy 377.800237 -243.857848) (xy 377.773934 -243.816252)
			(xy 377.754643 -243.770976) (xy 377.742866 -243.723192) (xy 377.738906 -243.674138) (xy 377.420632 -243.674138)
			(xy 377.42012 -243.699584) (xy 377.411956 -243.749818) (xy 377.39584 -243.798092) (xy 377.372189 -243.843155)
			(xy 377.341616 -243.883841) (xy 377.304912 -243.919096) (xy 377.263028 -243.948006) (xy 377.217049 -243.969823)
			(xy 377.168165 -243.983983) (xy 377.117644 -243.990117) (xy 377.066792 -243.988068) (xy 377.016928 -243.977888)
			(xy 376.969342 -243.959841) (xy 376.925268 -243.934395) (xy 376.885846 -243.902208) (xy 376.852098 -243.864114)
			(xy 376.824897 -243.8211) (xy 376.804949 -243.77428) (xy 376.79277 -243.724866) (xy 376.788675 -243.674138)
			(xy 376.480578 -243.674138) (xy 376.480066 -243.699584) (xy 376.471902 -243.749818) (xy 376.455786 -243.798092)
			(xy 376.432135 -243.843155) (xy 376.401562 -243.883841) (xy 376.364858 -243.919096) (xy 376.322974 -243.948006)
			(xy 376.276995 -243.969823) (xy 376.228111 -243.983983) (xy 376.17759 -243.990117) (xy 376.126738 -243.988068)
			(xy 376.076874 -243.977888) (xy 376.029288 -243.959841) (xy 375.985214 -243.934395) (xy 375.945792 -243.902208)
			(xy 375.912044 -243.864114) (xy 375.884843 -243.8211) (xy 375.864895 -243.77428) (xy 375.852716 -243.724866)
			(xy 375.848621 -243.674138) (xy 374.599454 -243.674138) (xy 374.599454 -243.733828) (xy 374.599915 -243.743705)
			(xy 374.607355 -243.762005) (xy 374.613932 -243.769388) (xy 374.614186 -243.769642) (xy 374.864122 -244.019578)
			(xy 374.870839 -244.026815) (xy 374.878444 -244.045019) (xy 374.878854 -244.054884) (xy 374.878854 -244.173756)
			(xy 374.879206 -244.182739) (xy 374.885423 -244.199595) (xy 374.8971 -244.213248) (xy 374.904762 -244.217952)
			(xy 374.926179 -244.230596) (xy 374.964964 -244.261725) (xy 374.998196 -244.298723) (xy 375.024999 -244.340615)
			(xy 375.044665 -244.386293) (xy 375.056674 -244.434554) (xy 375.06071 -244.484122) (xy 375.060708 -244.484144)
			(xy 375.378467 -244.484144) (xy 375.382562 -244.433416) (xy 375.394741 -244.384002) (xy 375.414689 -244.337182)
			(xy 375.44189 -244.294168) (xy 375.475638 -244.256074) (xy 375.51506 -244.223887) (xy 375.559134 -244.198441)
			(xy 375.60672 -244.180394) (xy 375.656584 -244.170214) (xy 375.707436 -244.168165) (xy 375.757957 -244.174299)
			(xy 375.806841 -244.188459) (xy 375.85282 -244.210276) (xy 375.894704 -244.239186) (xy 375.931408 -244.274441)
			(xy 375.961981 -244.315127) (xy 375.985632 -244.36019) (xy 376.001748 -244.408464) (xy 376.009912 -244.458698)
			(xy 376.010424 -244.484144) (xy 376.328952 -244.484144) (xy 376.332912 -244.43509) (xy 376.344689 -244.387306)
			(xy 376.36398 -244.34203) (xy 376.390283 -244.300434) (xy 376.422918 -244.263597) (xy 376.461039 -244.232472)
			(xy 376.50366 -244.207865) (xy 376.549676 -244.190413) (xy 376.597895 -244.180569) (xy 376.64707 -244.178588)
			(xy 376.695925 -244.18452) (xy 376.743196 -244.198212) (xy 376.787658 -244.21931) (xy 376.828161 -244.247266)
			(xy 376.863654 -244.281358) (xy 376.893219 -244.320702) (xy 376.91609 -244.364279) (xy 376.931674 -244.41096)
			(xy 376.939569 -244.459537) (xy 376.940064 -244.484144) (xy 377.258575 -244.484144) (xy 377.26267 -244.433416)
			(xy 377.274849 -244.384002) (xy 377.294797 -244.337182) (xy 377.321998 -244.294168) (xy 377.355746 -244.256074)
			(xy 377.395168 -244.223887) (xy 377.439242 -244.198441) (xy 377.486828 -244.180394) (xy 377.536692 -244.170214)
			(xy 377.587544 -244.168165) (xy 377.638065 -244.174299) (xy 377.686949 -244.188459) (xy 377.732928 -244.210276)
			(xy 377.774812 -244.239186) (xy 377.811516 -244.274441) (xy 377.842089 -244.315127) (xy 377.86574 -244.36019)
			(xy 377.881856 -244.408464) (xy 377.89002 -244.458698) (xy 377.890532 -244.484144) (xy 379.138683 -244.484144)
			(xy 379.142778 -244.433416) (xy 379.154957 -244.384002) (xy 379.174905 -244.337182) (xy 379.202106 -244.294168)
			(xy 379.235854 -244.256074) (xy 379.275276 -244.223887) (xy 379.31935 -244.198441) (xy 379.366936 -244.180394)
			(xy 379.4168 -244.170214) (xy 379.467652 -244.168165) (xy 379.518173 -244.174299) (xy 379.567057 -244.188459)
			(xy 379.613036 -244.210276) (xy 379.65492 -244.239186) (xy 379.691624 -244.274441) (xy 379.722197 -244.315127)
			(xy 379.745848 -244.36019) (xy 379.761964 -244.408464) (xy 379.770128 -244.458698) (xy 379.77064 -244.484144)
			(xy 380.078483 -244.484144) (xy 380.082578 -244.433416) (xy 380.094757 -244.384002) (xy 380.114705 -244.337182)
			(xy 380.141906 -244.294168) (xy 380.175654 -244.256074) (xy 380.215076 -244.223887) (xy 380.25915 -244.198441)
			(xy 380.306736 -244.180394) (xy 380.3566 -244.170214) (xy 380.407452 -244.168165) (xy 380.457973 -244.174299)
			(xy 380.506857 -244.188459) (xy 380.552836 -244.210276) (xy 380.59472 -244.239186) (xy 380.631424 -244.274441)
			(xy 380.661997 -244.315127) (xy 380.685648 -244.36019) (xy 380.701764 -244.408464) (xy 380.709928 -244.458698)
			(xy 380.71044 -244.484144) (xy 381.028968 -244.484144) (xy 381.032928 -244.43509) (xy 381.044705 -244.387306)
			(xy 381.063996 -244.34203) (xy 381.090299 -244.300434) (xy 381.122934 -244.263597) (xy 381.161055 -244.232472)
			(xy 381.203676 -244.207865) (xy 381.249692 -244.190413) (xy 381.297911 -244.180569) (xy 381.347086 -244.178588)
			(xy 381.395941 -244.18452) (xy 381.443212 -244.198212) (xy 381.487674 -244.21931) (xy 381.528177 -244.247266)
			(xy 381.56367 -244.281358) (xy 381.593235 -244.320702) (xy 381.616106 -244.364279) (xy 381.63169 -244.41096)
			(xy 381.639585 -244.459537) (xy 381.64008 -244.484144) (xy 381.969022 -244.484144) (xy 381.972982 -244.43509)
			(xy 381.984759 -244.387306) (xy 382.00405 -244.34203) (xy 382.030353 -244.300434) (xy 382.062988 -244.263597)
			(xy 382.101109 -244.232472) (xy 382.14373 -244.207865) (xy 382.189746 -244.190413) (xy 382.237965 -244.180569)
			(xy 382.28714 -244.178588) (xy 382.335995 -244.18452) (xy 382.383266 -244.198212) (xy 382.427728 -244.21931)
			(xy 382.468231 -244.247266) (xy 382.503724 -244.281358) (xy 382.533289 -244.320702) (xy 382.55616 -244.364279)
			(xy 382.571744 -244.41096) (xy 382.579639 -244.459537) (xy 382.580134 -244.484144) (xy 382.909076 -244.484144)
			(xy 382.913036 -244.43509) (xy 382.924813 -244.387306) (xy 382.944104 -244.34203) (xy 382.970407 -244.300434)
			(xy 383.003042 -244.263597) (xy 383.041163 -244.232472) (xy 383.083784 -244.207865) (xy 383.1298 -244.190413)
			(xy 383.178019 -244.180569) (xy 383.227194 -244.178588) (xy 383.276049 -244.18452) (xy 383.32332 -244.198212)
			(xy 383.367782 -244.21931) (xy 383.408285 -244.247266) (xy 383.443778 -244.281358) (xy 383.473343 -244.320702)
			(xy 383.496214 -244.364279) (xy 383.511798 -244.41096) (xy 383.519693 -244.459537) (xy 383.520188 -244.484144)
			(xy 383.84913 -244.484144) (xy 383.85309 -244.43509) (xy 383.864867 -244.387306) (xy 383.884158 -244.34203)
			(xy 383.910461 -244.300434) (xy 383.943096 -244.263597) (xy 383.981217 -244.232472) (xy 384.023838 -244.207865)
			(xy 384.069854 -244.190413) (xy 384.118073 -244.180569) (xy 384.167248 -244.178588) (xy 384.216103 -244.18452)
			(xy 384.263374 -244.198212) (xy 384.307836 -244.21931) (xy 384.348339 -244.247266) (xy 384.383832 -244.281358)
			(xy 384.413397 -244.320702) (xy 384.436268 -244.364279) (xy 384.451852 -244.41096) (xy 384.459747 -244.459537)
			(xy 384.460242 -244.484144) (xy 385.728984 -244.484144) (xy 385.732944 -244.43509) (xy 385.744721 -244.387306)
			(xy 385.764012 -244.34203) (xy 385.790315 -244.300434) (xy 385.82295 -244.263597) (xy 385.861071 -244.232472)
			(xy 385.903692 -244.207865) (xy 385.949708 -244.190413) (xy 385.997927 -244.180569) (xy 386.047102 -244.178588)
			(xy 386.095957 -244.18452) (xy 386.143228 -244.198212) (xy 386.18769 -244.21931) (xy 386.228193 -244.247266)
			(xy 386.263686 -244.281358) (xy 386.293251 -244.320702) (xy 386.316122 -244.364279) (xy 386.331706 -244.41096)
			(xy 386.339601 -244.459537) (xy 386.340096 -244.484144) (xy 386.669038 -244.484144) (xy 386.672998 -244.43509)
			(xy 386.684775 -244.387306) (xy 386.704066 -244.34203) (xy 386.730369 -244.300434) (xy 386.763004 -244.263597)
			(xy 386.801125 -244.232472) (xy 386.843746 -244.207865) (xy 386.889762 -244.190413) (xy 386.937981 -244.180569)
			(xy 386.987156 -244.178588) (xy 387.036011 -244.18452) (xy 387.083282 -244.198212) (xy 387.127744 -244.21931)
			(xy 387.168247 -244.247266) (xy 387.20374 -244.281358) (xy 387.233305 -244.320702) (xy 387.256176 -244.364279)
			(xy 387.27176 -244.41096) (xy 387.279655 -244.459537) (xy 387.28015 -244.484144) (xy 387.279655 -244.508751)
			(xy 387.27176 -244.557328) (xy 387.256176 -244.604009) (xy 387.233305 -244.647586) (xy 387.20374 -244.68693)
			(xy 387.168247 -244.721022) (xy 387.127744 -244.748978) (xy 387.083282 -244.770076) (xy 387.036011 -244.783768)
			(xy 386.987156 -244.7897) (xy 386.937981 -244.787719) (xy 386.889762 -244.777875) (xy 386.843746 -244.760423)
			(xy 386.801125 -244.735816) (xy 386.763004 -244.704691) (xy 386.730369 -244.667854) (xy 386.704066 -244.626258)
			(xy 386.684775 -244.580982) (xy 386.672998 -244.533198) (xy 386.669038 -244.484144) (xy 386.340096 -244.484144)
			(xy 386.339601 -244.508751) (xy 386.331706 -244.557328) (xy 386.316122 -244.604009) (xy 386.293251 -244.647586)
			(xy 386.263686 -244.68693) (xy 386.228193 -244.721022) (xy 386.18769 -244.748978) (xy 386.143228 -244.770076)
			(xy 386.095957 -244.783768) (xy 386.047102 -244.7897) (xy 385.997927 -244.787719) (xy 385.949708 -244.777875)
			(xy 385.903692 -244.760423) (xy 385.861071 -244.735816) (xy 385.82295 -244.704691) (xy 385.790315 -244.667854)
			(xy 385.764012 -244.626258) (xy 385.744721 -244.580982) (xy 385.732944 -244.533198) (xy 385.728984 -244.484144)
			(xy 384.460242 -244.484144) (xy 384.459747 -244.508751) (xy 384.451852 -244.557328) (xy 384.436268 -244.604009)
			(xy 384.413397 -244.647586) (xy 384.383832 -244.68693) (xy 384.348339 -244.721022) (xy 384.307836 -244.748978)
			(xy 384.263374 -244.770076) (xy 384.216103 -244.783768) (xy 384.167248 -244.7897) (xy 384.118073 -244.787719)
			(xy 384.069854 -244.777875) (xy 384.023838 -244.760423) (xy 383.981217 -244.735816) (xy 383.943096 -244.704691)
			(xy 383.910461 -244.667854) (xy 383.884158 -244.626258) (xy 383.864867 -244.580982) (xy 383.85309 -244.533198)
			(xy 383.84913 -244.484144) (xy 383.520188 -244.484144) (xy 383.519693 -244.508751) (xy 383.511798 -244.557328)
			(xy 383.496214 -244.604009) (xy 383.473343 -244.647586) (xy 383.443778 -244.68693) (xy 383.408285 -244.721022)
			(xy 383.367782 -244.748978) (xy 383.32332 -244.770076) (xy 383.276049 -244.783768) (xy 383.227194 -244.7897)
			(xy 383.178019 -244.787719) (xy 383.1298 -244.777875) (xy 383.083784 -244.760423) (xy 383.041163 -244.735816)
			(xy 383.003042 -244.704691) (xy 382.970407 -244.667854) (xy 382.944104 -244.626258) (xy 382.924813 -244.580982)
			(xy 382.913036 -244.533198) (xy 382.909076 -244.484144) (xy 382.580134 -244.484144) (xy 382.579639 -244.508751)
			(xy 382.571744 -244.557328) (xy 382.55616 -244.604009) (xy 382.533289 -244.647586) (xy 382.503724 -244.68693)
			(xy 382.468231 -244.721022) (xy 382.427728 -244.748978) (xy 382.383266 -244.770076) (xy 382.335995 -244.783768)
			(xy 382.28714 -244.7897) (xy 382.237965 -244.787719) (xy 382.189746 -244.777875) (xy 382.14373 -244.760423)
			(xy 382.101109 -244.735816) (xy 382.062988 -244.704691) (xy 382.030353 -244.667854) (xy 382.00405 -244.626258)
			(xy 381.984759 -244.580982) (xy 381.972982 -244.533198) (xy 381.969022 -244.484144) (xy 381.64008 -244.484144)
			(xy 381.639585 -244.508751) (xy 381.63169 -244.557328) (xy 381.616106 -244.604009) (xy 381.593235 -244.647586)
			(xy 381.56367 -244.68693) (xy 381.528177 -244.721022) (xy 381.487674 -244.748978) (xy 381.443212 -244.770076)
			(xy 381.395941 -244.783768) (xy 381.347086 -244.7897) (xy 381.297911 -244.787719) (xy 381.249692 -244.777875)
			(xy 381.203676 -244.760423) (xy 381.161055 -244.735816) (xy 381.122934 -244.704691) (xy 381.090299 -244.667854)
			(xy 381.063996 -244.626258) (xy 381.044705 -244.580982) (xy 381.032928 -244.533198) (xy 381.028968 -244.484144)
			(xy 380.71044 -244.484144) (xy 380.709928 -244.50959) (xy 380.701764 -244.559824) (xy 380.685648 -244.608098)
			(xy 380.661997 -244.653161) (xy 380.631424 -244.693847) (xy 380.59472 -244.729102) (xy 380.552836 -244.758012)
			(xy 380.506857 -244.779829) (xy 380.457973 -244.793989) (xy 380.407452 -244.800123) (xy 380.3566 -244.798074)
			(xy 380.306736 -244.787894) (xy 380.25915 -244.769847) (xy 380.215076 -244.744401) (xy 380.175654 -244.712214)
			(xy 380.141906 -244.67412) (xy 380.114705 -244.631106) (xy 380.094757 -244.584286) (xy 380.082578 -244.534872)
			(xy 380.078483 -244.484144) (xy 379.77064 -244.484144) (xy 379.770128 -244.50959) (xy 379.761964 -244.559824)
			(xy 379.745848 -244.608098) (xy 379.722197 -244.653161) (xy 379.691624 -244.693847) (xy 379.65492 -244.729102)
			(xy 379.613036 -244.758012) (xy 379.567057 -244.779829) (xy 379.518173 -244.793989) (xy 379.467652 -244.800123)
			(xy 379.4168 -244.798074) (xy 379.366936 -244.787894) (xy 379.31935 -244.769847) (xy 379.275276 -244.744401)
			(xy 379.235854 -244.712214) (xy 379.202106 -244.67412) (xy 379.174905 -244.631106) (xy 379.154957 -244.584286)
			(xy 379.142778 -244.534872) (xy 379.138683 -244.484144) (xy 377.890532 -244.484144) (xy 377.89002 -244.50959)
			(xy 377.881856 -244.559824) (xy 377.86574 -244.608098) (xy 377.842089 -244.653161) (xy 377.811516 -244.693847)
			(xy 377.774812 -244.729102) (xy 377.732928 -244.758012) (xy 377.686949 -244.779829) (xy 377.638065 -244.793989)
			(xy 377.587544 -244.800123) (xy 377.536692 -244.798074) (xy 377.486828 -244.787894) (xy 377.439242 -244.769847)
			(xy 377.395168 -244.744401) (xy 377.355746 -244.712214) (xy 377.321998 -244.67412) (xy 377.294797 -244.631106)
			(xy 377.274849 -244.584286) (xy 377.26267 -244.534872) (xy 377.258575 -244.484144) (xy 376.940064 -244.484144)
			(xy 376.939569 -244.508751) (xy 376.931674 -244.557328) (xy 376.91609 -244.604009) (xy 376.893219 -244.647586)
			(xy 376.863654 -244.68693) (xy 376.828161 -244.721022) (xy 376.787658 -244.748978) (xy 376.743196 -244.770076)
			(xy 376.695925 -244.783768) (xy 376.64707 -244.7897) (xy 376.597895 -244.787719) (xy 376.549676 -244.777875)
			(xy 376.50366 -244.760423) (xy 376.461039 -244.735816) (xy 376.422918 -244.704691) (xy 376.390283 -244.667854)
			(xy 376.36398 -244.626258) (xy 376.344689 -244.580982) (xy 376.332912 -244.533198) (xy 376.328952 -244.484144)
			(xy 376.010424 -244.484144) (xy 376.009912 -244.50959) (xy 376.001748 -244.559824) (xy 375.985632 -244.608098)
			(xy 375.961981 -244.653161) (xy 375.931408 -244.693847) (xy 375.894704 -244.729102) (xy 375.85282 -244.758012)
			(xy 375.806841 -244.779829) (xy 375.757957 -244.793989) (xy 375.707436 -244.800123) (xy 375.656584 -244.798074)
			(xy 375.60672 -244.787894) (xy 375.559134 -244.769847) (xy 375.51506 -244.744401) (xy 375.475638 -244.712214)
			(xy 375.44189 -244.67412) (xy 375.414689 -244.631106) (xy 375.394741 -244.584286) (xy 375.382562 -244.534872)
			(xy 375.378467 -244.484144) (xy 375.060708 -244.484144) (xy 375.056667 -244.533689) (xy 375.044651 -244.581948)
			(xy 375.024979 -244.627623) (xy 374.99817 -244.669511) (xy 374.964932 -244.706505) (xy 374.926143 -244.737628)
			(xy 374.904762 -244.750336) (xy 374.897127 -244.755061) (xy 374.885505 -244.768731) (xy 374.879286 -244.785562)
			(xy 374.878854 -244.794532) (xy 374.878854 -244.971316) (xy 374.879235 -244.980743) (xy 374.886059 -244.998319)
			(xy 374.898779 -245.012238) (xy 374.907048 -245.016782) (xy 374.98655 -245.056152) (xy 374.992991 -245.059102)
			(xy 375.006913 -245.061693) (xy 375.013982 -245.061232) (xy 375.020969 -245.060373) (xy 375.034116 -245.055352)
			(xy 375.03989 -245.051326) (xy 375.059943 -245.036639) (xy 375.103822 -245.013294) (xy 375.150907 -244.997379)
			(xy 375.199951 -244.989314) (xy 375.224802 -244.988842) (xy 375.248795 -244.989313) (xy 375.296189 -244.996819)
			(xy 375.341826 -245.011646) (xy 375.384582 -245.033429) (xy 375.423404 -245.061631) (xy 375.457338 -245.095559)
			(xy 375.485546 -245.134377) (xy 375.507336 -245.17713) (xy 375.52217 -245.222764) (xy 375.529683 -245.270158)
			(xy 375.53011 -245.29415) (xy 375.848621 -245.29415) (xy 375.852716 -245.243422) (xy 375.864895 -245.194008)
			(xy 375.884843 -245.147188) (xy 375.912044 -245.104174) (xy 375.945792 -245.06608) (xy 375.985214 -245.033893)
			(xy 376.029288 -245.008447) (xy 376.076874 -244.9904) (xy 376.126738 -244.98022) (xy 376.17759 -244.978171)
			(xy 376.228111 -244.984305) (xy 376.276995 -244.998465) (xy 376.322974 -245.020282) (xy 376.364858 -245.049192)
			(xy 376.401562 -245.084447) (xy 376.432135 -245.125133) (xy 376.455786 -245.170196) (xy 376.471902 -245.21847)
			(xy 376.480066 -245.268704) (xy 376.480578 -245.29415) (xy 376.788675 -245.29415) (xy 376.79277 -245.243422)
			(xy 376.804949 -245.194008) (xy 376.824897 -245.147188) (xy 376.852098 -245.104174) (xy 376.885846 -245.06608)
			(xy 376.925268 -245.033893) (xy 376.969342 -245.008447) (xy 377.016928 -244.9904) (xy 377.066792 -244.98022)
			(xy 377.117644 -244.978171) (xy 377.168165 -244.984305) (xy 377.217049 -244.998465) (xy 377.263028 -245.020282)
			(xy 377.304912 -245.049192) (xy 377.341616 -245.084447) (xy 377.372189 -245.125133) (xy 377.39584 -245.170196)
			(xy 377.411956 -245.21847) (xy 377.42012 -245.268704) (xy 377.420632 -245.29415) (xy 377.738906 -245.29415)
			(xy 377.742866 -245.245096) (xy 377.754643 -245.197312) (xy 377.773934 -245.152036) (xy 377.800237 -245.11044)
			(xy 377.832872 -245.073603) (xy 377.870993 -245.042478) (xy 377.913614 -245.017871) (xy 377.95963 -245.000419)
			(xy 378.007849 -244.990575) (xy 378.057024 -244.988594) (xy 378.105879 -244.994526) (xy 378.15315 -245.008218)
			(xy 378.197612 -245.029316) (xy 378.238115 -245.057272) (xy 378.273608 -245.091364) (xy 378.303173 -245.130708)
			(xy 378.326044 -245.174285) (xy 378.341628 -245.220966) (xy 378.349523 -245.269543) (xy 378.350018 -245.29415)
			(xy 378.668529 -245.29415) (xy 378.672624 -245.243422) (xy 378.684803 -245.194008) (xy 378.704751 -245.147188)
			(xy 378.731952 -245.104174) (xy 378.7657 -245.06608) (xy 378.805122 -245.033893) (xy 378.849196 -245.008447)
			(xy 378.896782 -244.9904) (xy 378.946646 -244.98022) (xy 378.997498 -244.978171) (xy 379.048019 -244.984305)
			(xy 379.096903 -244.998465) (xy 379.142882 -245.020282) (xy 379.184766 -245.049192) (xy 379.22147 -245.084447)
			(xy 379.252043 -245.125133) (xy 379.275694 -245.170196) (xy 379.29181 -245.21847) (xy 379.299974 -245.268704)
			(xy 379.300486 -245.29415) (xy 379.619014 -245.29415) (xy 379.622974 -245.245096) (xy 379.634751 -245.197312)
			(xy 379.654042 -245.152036) (xy 379.680345 -245.11044) (xy 379.71298 -245.073603) (xy 379.751101 -245.042478)
			(xy 379.793722 -245.017871) (xy 379.839738 -245.000419) (xy 379.887957 -244.990575) (xy 379.937132 -244.988594)
			(xy 379.985987 -244.994526) (xy 380.033258 -245.008218) (xy 380.07772 -245.029316) (xy 380.118223 -245.057272)
			(xy 380.153716 -245.091364) (xy 380.183281 -245.130708) (xy 380.206152 -245.174285) (xy 380.221736 -245.220966)
			(xy 380.229631 -245.269543) (xy 380.230126 -245.29415) (xy 380.548637 -245.29415) (xy 380.552732 -245.243422)
			(xy 380.564911 -245.194008) (xy 380.584859 -245.147188) (xy 380.61206 -245.104174) (xy 380.645808 -245.06608)
			(xy 380.68523 -245.033893) (xy 380.729304 -245.008447) (xy 380.77689 -244.9904) (xy 380.826754 -244.98022)
			(xy 380.877606 -244.978171) (xy 380.928127 -244.984305) (xy 380.977011 -244.998465) (xy 381.02299 -245.020282)
			(xy 381.064874 -245.049192) (xy 381.101578 -245.084447) (xy 381.132151 -245.125133) (xy 381.155802 -245.170196)
			(xy 381.171918 -245.21847) (xy 381.180082 -245.268704) (xy 381.180594 -245.29415) (xy 381.499122 -245.29415)
			(xy 381.503082 -245.245096) (xy 381.514859 -245.197312) (xy 381.53415 -245.152036) (xy 381.560453 -245.11044)
			(xy 381.593088 -245.073603) (xy 381.631209 -245.042478) (xy 381.67383 -245.017871) (xy 381.719846 -245.000419)
			(xy 381.768065 -244.990575) (xy 381.81724 -244.988594) (xy 381.866095 -244.994526) (xy 381.913366 -245.008218)
			(xy 381.957828 -245.029316) (xy 381.998331 -245.057272) (xy 382.033824 -245.091364) (xy 382.063389 -245.130708)
			(xy 382.08626 -245.174285) (xy 382.101844 -245.220966) (xy 382.109739 -245.269543) (xy 382.110234 -245.29415)
			(xy 382.438922 -245.29415) (xy 382.442882 -245.245096) (xy 382.454659 -245.197312) (xy 382.47395 -245.152036)
			(xy 382.500253 -245.11044) (xy 382.532888 -245.073603) (xy 382.571009 -245.042478) (xy 382.61363 -245.017871)
			(xy 382.659646 -245.000419) (xy 382.707865 -244.990575) (xy 382.75704 -244.988594) (xy 382.805895 -244.994526)
			(xy 382.853166 -245.008218) (xy 382.897628 -245.029316) (xy 382.938131 -245.057272) (xy 382.973624 -245.091364)
			(xy 383.003189 -245.130708) (xy 383.02606 -245.174285) (xy 383.041644 -245.220966) (xy 383.049539 -245.269543)
			(xy 383.050034 -245.29415) (xy 383.378976 -245.29415) (xy 383.382936 -245.245096) (xy 383.394713 -245.197312)
			(xy 383.414004 -245.152036) (xy 383.440307 -245.11044) (xy 383.472942 -245.073603) (xy 383.511063 -245.042478)
			(xy 383.553684 -245.017871) (xy 383.5997 -245.000419) (xy 383.647919 -244.990575) (xy 383.697094 -244.988594)
			(xy 383.745949 -244.994526) (xy 383.79322 -245.008218) (xy 383.837682 -245.029316) (xy 383.878185 -245.057272)
			(xy 383.913678 -245.091364) (xy 383.943243 -245.130708) (xy 383.966114 -245.174285) (xy 383.981698 -245.220966)
			(xy 383.989593 -245.269543) (xy 383.990088 -245.29415) (xy 384.31903 -245.29415) (xy 384.32299 -245.245096)
			(xy 384.334767 -245.197312) (xy 384.354058 -245.152036) (xy 384.380361 -245.11044) (xy 384.412996 -245.073603)
			(xy 384.451117 -245.042478) (xy 384.493738 -245.017871) (xy 384.539754 -245.000419) (xy 384.587973 -244.990575)
			(xy 384.637148 -244.988594) (xy 384.686003 -244.994526) (xy 384.733274 -245.008218) (xy 384.777736 -245.029316)
			(xy 384.818239 -245.057272) (xy 384.853732 -245.091364) (xy 384.883297 -245.130708) (xy 384.906168 -245.174285)
			(xy 384.921752 -245.220966) (xy 384.929647 -245.269543) (xy 384.930142 -245.29415) (xy 385.259084 -245.29415)
			(xy 385.263044 -245.245096) (xy 385.274821 -245.197312) (xy 385.294112 -245.152036) (xy 385.320415 -245.11044)
			(xy 385.35305 -245.073603) (xy 385.391171 -245.042478) (xy 385.433792 -245.017871) (xy 385.479808 -245.000419)
			(xy 385.528027 -244.990575) (xy 385.577202 -244.988594) (xy 385.626057 -244.994526) (xy 385.673328 -245.008218)
			(xy 385.71779 -245.029316) (xy 385.758293 -245.057272) (xy 385.793786 -245.091364) (xy 385.823351 -245.130708)
			(xy 385.846222 -245.174285) (xy 385.861806 -245.220966) (xy 385.869701 -245.269543) (xy 385.870196 -245.29415)
			(xy 386.199138 -245.29415) (xy 386.203098 -245.245096) (xy 386.214875 -245.197312) (xy 386.234166 -245.152036)
			(xy 386.260469 -245.11044) (xy 386.293104 -245.073603) (xy 386.331225 -245.042478) (xy 386.373846 -245.017871)
			(xy 386.419862 -245.000419) (xy 386.468081 -244.990575) (xy 386.517256 -244.988594) (xy 386.566111 -244.994526)
			(xy 386.613382 -245.008218) (xy 386.657844 -245.029316) (xy 386.698347 -245.057272) (xy 386.73384 -245.091364)
			(xy 386.763405 -245.130708) (xy 386.786276 -245.174285) (xy 386.80186 -245.220966) (xy 386.809755 -245.269543)
			(xy 386.81025 -245.29415) (xy 386.809755 -245.318757) (xy 386.80186 -245.367334) (xy 386.786276 -245.414015)
			(xy 386.763405 -245.457592) (xy 386.73384 -245.496936) (xy 386.698347 -245.531028) (xy 386.657844 -245.558984)
			(xy 386.613382 -245.580082) (xy 386.566111 -245.593774) (xy 386.517256 -245.599706) (xy 386.468081 -245.597725)
			(xy 386.419862 -245.587881) (xy 386.373846 -245.570429) (xy 386.331225 -245.545822) (xy 386.293104 -245.514697)
			(xy 386.260469 -245.47786) (xy 386.234166 -245.436264) (xy 386.214875 -245.390988) (xy 386.203098 -245.343204)
			(xy 386.199138 -245.29415) (xy 385.870196 -245.29415) (xy 385.869701 -245.318757) (xy 385.861806 -245.367334)
			(xy 385.846222 -245.414015) (xy 385.823351 -245.457592) (xy 385.793786 -245.496936) (xy 385.758293 -245.531028)
			(xy 385.71779 -245.558984) (xy 385.673328 -245.580082) (xy 385.626057 -245.593774) (xy 385.577202 -245.599706)
			(xy 385.528027 -245.597725) (xy 385.479808 -245.587881) (xy 385.433792 -245.570429) (xy 385.391171 -245.545822)
			(xy 385.35305 -245.514697) (xy 385.320415 -245.47786) (xy 385.294112 -245.436264) (xy 385.274821 -245.390988)
			(xy 385.263044 -245.343204) (xy 385.259084 -245.29415) (xy 384.930142 -245.29415) (xy 384.929647 -245.318757)
			(xy 384.921752 -245.367334) (xy 384.906168 -245.414015) (xy 384.883297 -245.457592) (xy 384.853732 -245.496936)
			(xy 384.818239 -245.531028) (xy 384.777736 -245.558984) (xy 384.733274 -245.580082) (xy 384.686003 -245.593774)
			(xy 384.637148 -245.599706) (xy 384.587973 -245.597725) (xy 384.539754 -245.587881) (xy 384.493738 -245.570429)
			(xy 384.451117 -245.545822) (xy 384.412996 -245.514697) (xy 384.380361 -245.47786) (xy 384.354058 -245.436264)
			(xy 384.334767 -245.390988) (xy 384.32299 -245.343204) (xy 384.31903 -245.29415) (xy 383.990088 -245.29415)
			(xy 383.989593 -245.318757) (xy 383.981698 -245.367334) (xy 383.966114 -245.414015) (xy 383.943243 -245.457592)
			(xy 383.913678 -245.496936) (xy 383.878185 -245.531028) (xy 383.837682 -245.558984) (xy 383.79322 -245.580082)
			(xy 383.745949 -245.593774) (xy 383.697094 -245.599706) (xy 383.647919 -245.597725) (xy 383.5997 -245.587881)
			(xy 383.553684 -245.570429) (xy 383.511063 -245.545822) (xy 383.472942 -245.514697) (xy 383.440307 -245.47786)
			(xy 383.414004 -245.436264) (xy 383.394713 -245.390988) (xy 383.382936 -245.343204) (xy 383.378976 -245.29415)
			(xy 383.050034 -245.29415) (xy 383.049539 -245.318757) (xy 383.041644 -245.367334) (xy 383.02606 -245.414015)
			(xy 383.003189 -245.457592) (xy 382.973624 -245.496936) (xy 382.938131 -245.531028) (xy 382.897628 -245.558984)
			(xy 382.853166 -245.580082) (xy 382.805895 -245.593774) (xy 382.75704 -245.599706) (xy 382.707865 -245.597725)
			(xy 382.659646 -245.587881) (xy 382.61363 -245.570429) (xy 382.571009 -245.545822) (xy 382.532888 -245.514697)
			(xy 382.500253 -245.47786) (xy 382.47395 -245.436264) (xy 382.454659 -245.390988) (xy 382.442882 -245.343204)
			(xy 382.438922 -245.29415) (xy 382.110234 -245.29415) (xy 382.109739 -245.318757) (xy 382.101844 -245.367334)
			(xy 382.08626 -245.414015) (xy 382.063389 -245.457592) (xy 382.033824 -245.496936) (xy 381.998331 -245.531028)
			(xy 381.957828 -245.558984) (xy 381.913366 -245.580082) (xy 381.866095 -245.593774) (xy 381.81724 -245.599706)
			(xy 381.768065 -245.597725) (xy 381.719846 -245.587881) (xy 381.67383 -245.570429) (xy 381.631209 -245.545822)
			(xy 381.593088 -245.514697) (xy 381.560453 -245.47786) (xy 381.53415 -245.436264) (xy 381.514859 -245.390988)
			(xy 381.503082 -245.343204) (xy 381.499122 -245.29415) (xy 381.180594 -245.29415) (xy 381.180082 -245.319596)
			(xy 381.171918 -245.36983) (xy 381.155802 -245.418104) (xy 381.132151 -245.463167) (xy 381.101578 -245.503853)
			(xy 381.064874 -245.539108) (xy 381.02299 -245.568018) (xy 380.977011 -245.589835) (xy 380.928127 -245.603995)
			(xy 380.877606 -245.610129) (xy 380.826754 -245.60808) (xy 380.77689 -245.5979) (xy 380.729304 -245.579853)
			(xy 380.68523 -245.554407) (xy 380.645808 -245.52222) (xy 380.61206 -245.484126) (xy 380.584859 -245.441112)
			(xy 380.564911 -245.394292) (xy 380.552732 -245.344878) (xy 380.548637 -245.29415) (xy 380.230126 -245.29415)
			(xy 380.229631 -245.318757) (xy 380.221736 -245.367334) (xy 380.206152 -245.414015) (xy 380.183281 -245.457592)
			(xy 380.153716 -245.496936) (xy 380.118223 -245.531028) (xy 380.07772 -245.558984) (xy 380.033258 -245.580082)
			(xy 379.985987 -245.593774) (xy 379.937132 -245.599706) (xy 379.887957 -245.597725) (xy 379.839738 -245.587881)
			(xy 379.793722 -245.570429) (xy 379.751101 -245.545822) (xy 379.71298 -245.514697) (xy 379.680345 -245.47786)
			(xy 379.654042 -245.436264) (xy 379.634751 -245.390988) (xy 379.622974 -245.343204) (xy 379.619014 -245.29415)
			(xy 379.300486 -245.29415) (xy 379.299974 -245.319596) (xy 379.29181 -245.36983) (xy 379.275694 -245.418104)
			(xy 379.252043 -245.463167) (xy 379.22147 -245.503853) (xy 379.184766 -245.539108) (xy 379.142882 -245.568018)
			(xy 379.096903 -245.589835) (xy 379.048019 -245.603995) (xy 378.997498 -245.610129) (xy 378.946646 -245.60808)
			(xy 378.896782 -245.5979) (xy 378.849196 -245.579853) (xy 378.805122 -245.554407) (xy 378.7657 -245.52222)
			(xy 378.731952 -245.484126) (xy 378.704751 -245.441112) (xy 378.684803 -245.394292) (xy 378.672624 -245.344878)
			(xy 378.668529 -245.29415) (xy 378.350018 -245.29415) (xy 378.349523 -245.318757) (xy 378.341628 -245.367334)
			(xy 378.326044 -245.414015) (xy 378.303173 -245.457592) (xy 378.273608 -245.496936) (xy 378.238115 -245.531028)
			(xy 378.197612 -245.558984) (xy 378.15315 -245.580082) (xy 378.105879 -245.593774) (xy 378.057024 -245.599706)
			(xy 378.007849 -245.597725) (xy 377.95963 -245.587881) (xy 377.913614 -245.570429) (xy 377.870993 -245.545822)
			(xy 377.832872 -245.514697) (xy 377.800237 -245.47786) (xy 377.773934 -245.436264) (xy 377.754643 -245.390988)
			(xy 377.742866 -245.343204) (xy 377.738906 -245.29415) (xy 377.420632 -245.29415) (xy 377.42012 -245.319596)
			(xy 377.411956 -245.36983) (xy 377.39584 -245.418104) (xy 377.372189 -245.463167) (xy 377.341616 -245.503853)
			(xy 377.304912 -245.539108) (xy 377.263028 -245.568018) (xy 377.217049 -245.589835) (xy 377.168165 -245.603995)
			(xy 377.117644 -245.610129) (xy 377.066792 -245.60808) (xy 377.016928 -245.5979) (xy 376.969342 -245.579853)
			(xy 376.925268 -245.554407) (xy 376.885846 -245.52222) (xy 376.852098 -245.484126) (xy 376.824897 -245.441112)
			(xy 376.804949 -245.394292) (xy 376.79277 -245.344878) (xy 376.788675 -245.29415) (xy 376.480578 -245.29415)
			(xy 376.480066 -245.319596) (xy 376.471902 -245.36983) (xy 376.455786 -245.418104) (xy 376.432135 -245.463167)
			(xy 376.401562 -245.503853) (xy 376.364858 -245.539108) (xy 376.322974 -245.568018) (xy 376.276995 -245.589835)
			(xy 376.228111 -245.603995) (xy 376.17759 -245.610129) (xy 376.126738 -245.60808) (xy 376.076874 -245.5979)
			(xy 376.029288 -245.579853) (xy 375.985214 -245.554407) (xy 375.945792 -245.52222) (xy 375.912044 -245.484126)
			(xy 375.884843 -245.441112) (xy 375.864895 -245.394292) (xy 375.852716 -245.344878) (xy 375.848621 -245.29415)
			(xy 375.53011 -245.29415) (xy 375.529971 -245.306913) (xy 375.527807 -245.332347) (xy 375.525792 -245.34495)
			(xy 375.526046 -245.34495) (xy 375.521605 -245.368567) (xy 375.506288 -245.414114) (xy 375.484029 -245.456701)
			(xy 375.455377 -245.495279) (xy 375.421039 -245.528895) (xy 375.381862 -245.556722) (xy 375.338812 -245.578072)
			(xy 375.29295 -245.592419) (xy 375.269252 -245.59641) (xy 375.255028 -245.598188) (xy 375.224802 -245.599712)
			(xy 375.199922 -245.599223) (xy 375.15082 -245.591162) (xy 375.103672 -245.575253) (xy 375.059724 -245.551915)
			(xy 375.039636 -245.537228) (xy 375.028206 -245.528592) (xy 374.99925 -245.525798) (xy 374.907048 -245.571518)
			(xy 374.898814 -245.576102) (xy 374.886129 -245.590015) (xy 374.879324 -245.60757) (xy 374.878854 -245.616984)
			(xy 374.878854 -245.793768) (xy 374.879208 -245.80275) (xy 374.885427 -245.819603) (xy 374.897106 -245.833252)
			(xy 374.904762 -245.837964) (xy 374.926186 -245.850608) (xy 374.964985 -245.881739) (xy 374.998231 -245.918742)
			(xy 375.025047 -245.96064) (xy 375.044724 -246.006328) (xy 375.056743 -246.054598) (xy 375.060786 -246.104156)
			(xy 375.378467 -246.104156) (xy 375.382562 -246.053428) (xy 375.394741 -246.004014) (xy 375.414689 -245.957194)
			(xy 375.44189 -245.91418) (xy 375.475638 -245.876086) (xy 375.51506 -245.843899) (xy 375.559134 -245.818453)
			(xy 375.60672 -245.800406) (xy 375.656584 -245.790226) (xy 375.707436 -245.788177) (xy 375.757957 -245.794311)
			(xy 375.806841 -245.808471) (xy 375.85282 -245.830288) (xy 375.894704 -245.859198) (xy 375.931408 -245.894453)
			(xy 375.961981 -245.935139) (xy 375.985632 -245.980202) (xy 376.001748 -246.028476) (xy 376.009912 -246.07871)
			(xy 376.010424 -246.104156) (xy 376.328952 -246.104156) (xy 376.332912 -246.055102) (xy 376.344689 -246.007318)
			(xy 376.36398 -245.962042) (xy 376.390283 -245.920446) (xy 376.422918 -245.883609) (xy 376.461039 -245.852484)
			(xy 376.50366 -245.827877) (xy 376.549676 -245.810425) (xy 376.597895 -245.800581) (xy 376.64707 -245.7986)
			(xy 376.695925 -245.804532) (xy 376.743196 -245.818224) (xy 376.787658 -245.839322) (xy 376.828161 -245.867278)
			(xy 376.863654 -245.90137) (xy 376.893219 -245.940714) (xy 376.91609 -245.984291) (xy 376.931674 -246.030972)
			(xy 376.939569 -246.079549) (xy 376.940064 -246.104156) (xy 377.258575 -246.104156) (xy 377.26267 -246.053428)
			(xy 377.274849 -246.004014) (xy 377.294797 -245.957194) (xy 377.321998 -245.91418) (xy 377.355746 -245.876086)
			(xy 377.395168 -245.843899) (xy 377.439242 -245.818453) (xy 377.486828 -245.800406) (xy 377.536692 -245.790226)
			(xy 377.587544 -245.788177) (xy 377.638065 -245.794311) (xy 377.686949 -245.808471) (xy 377.732928 -245.830288)
			(xy 377.774812 -245.859198) (xy 377.811516 -245.894453) (xy 377.842089 -245.935139) (xy 377.86574 -245.980202)
			(xy 377.881856 -246.028476) (xy 377.89002 -246.07871) (xy 377.890532 -246.104156) (xy 378.20906 -246.104156)
			(xy 378.21302 -246.055102) (xy 378.224797 -246.007318) (xy 378.244088 -245.962042) (xy 378.270391 -245.920446)
			(xy 378.303026 -245.883609) (xy 378.341147 -245.852484) (xy 378.383768 -245.827877) (xy 378.429784 -245.810425)
			(xy 378.478003 -245.800581) (xy 378.527178 -245.7986) (xy 378.576033 -245.804532) (xy 378.623304 -245.818224)
			(xy 378.667766 -245.839322) (xy 378.708269 -245.867278) (xy 378.743762 -245.90137) (xy 378.773327 -245.940714)
			(xy 378.796198 -245.984291) (xy 378.811782 -246.030972) (xy 378.819677 -246.079549) (xy 378.820172 -246.104156)
			(xy 379.138683 -246.104156) (xy 379.142778 -246.053428) (xy 379.154957 -246.004014) (xy 379.174905 -245.957194)
			(xy 379.202106 -245.91418) (xy 379.235854 -245.876086) (xy 379.275276 -245.843899) (xy 379.31935 -245.818453)
			(xy 379.366936 -245.800406) (xy 379.4168 -245.790226) (xy 379.467652 -245.788177) (xy 379.518173 -245.794311)
			(xy 379.567057 -245.808471) (xy 379.613036 -245.830288) (xy 379.65492 -245.859198) (xy 379.691624 -245.894453)
			(xy 379.722197 -245.935139) (xy 379.745848 -245.980202) (xy 379.761964 -246.028476) (xy 379.770128 -246.07871)
			(xy 379.77064 -246.104156) (xy 380.078483 -246.104156) (xy 380.082578 -246.053428) (xy 380.094757 -246.004014)
			(xy 380.114705 -245.957194) (xy 380.141906 -245.91418) (xy 380.175654 -245.876086) (xy 380.215076 -245.843899)
			(xy 380.25915 -245.818453) (xy 380.306736 -245.800406) (xy 380.3566 -245.790226) (xy 380.407452 -245.788177)
			(xy 380.457973 -245.794311) (xy 380.506857 -245.808471) (xy 380.552836 -245.830288) (xy 380.59472 -245.859198)
			(xy 380.631424 -245.894453) (xy 380.661997 -245.935139) (xy 380.685648 -245.980202) (xy 380.701764 -246.028476)
			(xy 380.709928 -246.07871) (xy 380.71044 -246.104156) (xy 381.028968 -246.104156) (xy 381.032928 -246.055102)
			(xy 381.044705 -246.007318) (xy 381.063996 -245.962042) (xy 381.090299 -245.920446) (xy 381.122934 -245.883609)
			(xy 381.161055 -245.852484) (xy 381.203676 -245.827877) (xy 381.249692 -245.810425) (xy 381.297911 -245.800581)
			(xy 381.347086 -245.7986) (xy 381.395941 -245.804532) (xy 381.443212 -245.818224) (xy 381.487674 -245.839322)
			(xy 381.528177 -245.867278) (xy 381.56367 -245.90137) (xy 381.593235 -245.940714) (xy 381.616106 -245.984291)
			(xy 381.63169 -246.030972) (xy 381.639585 -246.079549) (xy 381.64008 -246.104156) (xy 381.969022 -246.104156)
			(xy 381.972982 -246.055102) (xy 381.984759 -246.007318) (xy 382.00405 -245.962042) (xy 382.030353 -245.920446)
			(xy 382.062988 -245.883609) (xy 382.101109 -245.852484) (xy 382.14373 -245.827877) (xy 382.189746 -245.810425)
			(xy 382.237965 -245.800581) (xy 382.28714 -245.7986) (xy 382.335995 -245.804532) (xy 382.383266 -245.818224)
			(xy 382.427728 -245.839322) (xy 382.468231 -245.867278) (xy 382.503724 -245.90137) (xy 382.533289 -245.940714)
			(xy 382.55616 -245.984291) (xy 382.571744 -246.030972) (xy 382.579639 -246.079549) (xy 382.580134 -246.104156)
			(xy 382.909076 -246.104156) (xy 382.913036 -246.055102) (xy 382.924813 -246.007318) (xy 382.944104 -245.962042)
			(xy 382.970407 -245.920446) (xy 383.003042 -245.883609) (xy 383.041163 -245.852484) (xy 383.083784 -245.827877)
			(xy 383.1298 -245.810425) (xy 383.178019 -245.800581) (xy 383.227194 -245.7986) (xy 383.276049 -245.804532)
			(xy 383.32332 -245.818224) (xy 383.367782 -245.839322) (xy 383.408285 -245.867278) (xy 383.443778 -245.90137)
			(xy 383.473343 -245.940714) (xy 383.496214 -245.984291) (xy 383.511798 -246.030972) (xy 383.519693 -246.079549)
			(xy 383.520188 -246.104156) (xy 383.84913 -246.104156) (xy 383.85309 -246.055102) (xy 383.864867 -246.007318)
			(xy 383.884158 -245.962042) (xy 383.910461 -245.920446) (xy 383.943096 -245.883609) (xy 383.981217 -245.852484)
			(xy 384.023838 -245.827877) (xy 384.069854 -245.810425) (xy 384.118073 -245.800581) (xy 384.167248 -245.7986)
			(xy 384.216103 -245.804532) (xy 384.263374 -245.818224) (xy 384.307836 -245.839322) (xy 384.348339 -245.867278)
			(xy 384.383832 -245.90137) (xy 384.413397 -245.940714) (xy 384.436268 -245.984291) (xy 384.451852 -246.030972)
			(xy 384.459747 -246.079549) (xy 384.460242 -246.104156) (xy 384.78893 -246.104156) (xy 384.79289 -246.055102)
			(xy 384.804667 -246.007318) (xy 384.823958 -245.962042) (xy 384.850261 -245.920446) (xy 384.882896 -245.883609)
			(xy 384.921017 -245.852484) (xy 384.963638 -245.827877) (xy 385.009654 -245.810425) (xy 385.057873 -245.800581)
			(xy 385.107048 -245.7986) (xy 385.155903 -245.804532) (xy 385.203174 -245.818224) (xy 385.247636 -245.839322)
			(xy 385.288139 -245.867278) (xy 385.323632 -245.90137) (xy 385.353197 -245.940714) (xy 385.376068 -245.984291)
			(xy 385.391652 -246.030972) (xy 385.399547 -246.079549) (xy 385.400042 -246.104156) (xy 385.728984 -246.104156)
			(xy 385.732944 -246.055102) (xy 385.744721 -246.007318) (xy 385.764012 -245.962042) (xy 385.790315 -245.920446)
			(xy 385.82295 -245.883609) (xy 385.861071 -245.852484) (xy 385.903692 -245.827877) (xy 385.949708 -245.810425)
			(xy 385.997927 -245.800581) (xy 386.047102 -245.7986) (xy 386.095957 -245.804532) (xy 386.143228 -245.818224)
			(xy 386.18769 -245.839322) (xy 386.228193 -245.867278) (xy 386.263686 -245.90137) (xy 386.293251 -245.940714)
			(xy 386.316122 -245.984291) (xy 386.331706 -246.030972) (xy 386.339601 -246.079549) (xy 386.340096 -246.104156)
			(xy 386.669038 -246.104156) (xy 386.672998 -246.055102) (xy 386.684775 -246.007318) (xy 386.704066 -245.962042)
			(xy 386.730369 -245.920446) (xy 386.763004 -245.883609) (xy 386.801125 -245.852484) (xy 386.843746 -245.827877)
			(xy 386.889762 -245.810425) (xy 386.937981 -245.800581) (xy 386.987156 -245.7986) (xy 387.036011 -245.804532)
			(xy 387.083282 -245.818224) (xy 387.127744 -245.839322) (xy 387.168247 -245.867278) (xy 387.20374 -245.90137)
			(xy 387.233305 -245.940714) (xy 387.256176 -245.984291) (xy 387.27176 -246.030972) (xy 387.279655 -246.079549)
			(xy 387.28015 -246.104156) (xy 387.279655 -246.128763) (xy 387.27176 -246.17734) (xy 387.256176 -246.224021)
			(xy 387.233305 -246.267598) (xy 387.20374 -246.306942) (xy 387.168247 -246.341034) (xy 387.127744 -246.36899)
			(xy 387.083282 -246.390088) (xy 387.036011 -246.40378) (xy 386.987156 -246.409712) (xy 386.937981 -246.407731)
			(xy 386.889762 -246.397887) (xy 386.843746 -246.380435) (xy 386.801125 -246.355828) (xy 386.763004 -246.324703)
			(xy 386.730369 -246.287866) (xy 386.704066 -246.24627) (xy 386.684775 -246.200994) (xy 386.672998 -246.15321)
			(xy 386.669038 -246.104156) (xy 386.340096 -246.104156) (xy 386.339601 -246.128763) (xy 386.331706 -246.17734)
			(xy 386.316122 -246.224021) (xy 386.293251 -246.267598) (xy 386.263686 -246.306942) (xy 386.228193 -246.341034)
			(xy 386.18769 -246.36899) (xy 386.143228 -246.390088) (xy 386.095957 -246.40378) (xy 386.047102 -246.409712)
			(xy 385.997927 -246.407731) (xy 385.949708 -246.397887) (xy 385.903692 -246.380435) (xy 385.861071 -246.355828)
			(xy 385.82295 -246.324703) (xy 385.790315 -246.287866) (xy 385.764012 -246.24627) (xy 385.744721 -246.200994)
			(xy 385.732944 -246.15321) (xy 385.728984 -246.104156) (xy 385.400042 -246.104156) (xy 385.399547 -246.128763)
			(xy 385.391652 -246.17734) (xy 385.376068 -246.224021) (xy 385.353197 -246.267598) (xy 385.323632 -246.306942)
			(xy 385.288139 -246.341034) (xy 385.247636 -246.36899) (xy 385.203174 -246.390088) (xy 385.155903 -246.40378)
			(xy 385.107048 -246.409712) (xy 385.057873 -246.407731) (xy 385.009654 -246.397887) (xy 384.963638 -246.380435)
			(xy 384.921017 -246.355828) (xy 384.882896 -246.324703) (xy 384.850261 -246.287866) (xy 384.823958 -246.24627)
			(xy 384.804667 -246.200994) (xy 384.79289 -246.15321) (xy 384.78893 -246.104156) (xy 384.460242 -246.104156)
			(xy 384.459747 -246.128763) (xy 384.451852 -246.17734) (xy 384.436268 -246.224021) (xy 384.413397 -246.267598)
			(xy 384.383832 -246.306942) (xy 384.348339 -246.341034) (xy 384.307836 -246.36899) (xy 384.263374 -246.390088)
			(xy 384.216103 -246.40378) (xy 384.167248 -246.409712) (xy 384.118073 -246.407731) (xy 384.069854 -246.397887)
			(xy 384.023838 -246.380435) (xy 383.981217 -246.355828) (xy 383.943096 -246.324703) (xy 383.910461 -246.287866)
			(xy 383.884158 -246.24627) (xy 383.864867 -246.200994) (xy 383.85309 -246.15321) (xy 383.84913 -246.104156)
			(xy 383.520188 -246.104156) (xy 383.519693 -246.128763) (xy 383.511798 -246.17734) (xy 383.496214 -246.224021)
			(xy 383.473343 -246.267598) (xy 383.443778 -246.306942) (xy 383.408285 -246.341034) (xy 383.367782 -246.36899)
			(xy 383.32332 -246.390088) (xy 383.276049 -246.40378) (xy 383.227194 -246.409712) (xy 383.178019 -246.407731)
			(xy 383.1298 -246.397887) (xy 383.083784 -246.380435) (xy 383.041163 -246.355828) (xy 383.003042 -246.324703)
			(xy 382.970407 -246.287866) (xy 382.944104 -246.24627) (xy 382.924813 -246.200994) (xy 382.913036 -246.15321)
			(xy 382.909076 -246.104156) (xy 382.580134 -246.104156) (xy 382.579639 -246.128763) (xy 382.571744 -246.17734)
			(xy 382.55616 -246.224021) (xy 382.533289 -246.267598) (xy 382.503724 -246.306942) (xy 382.468231 -246.341034)
			(xy 382.427728 -246.36899) (xy 382.383266 -246.390088) (xy 382.335995 -246.40378) (xy 382.28714 -246.409712)
			(xy 382.237965 -246.407731) (xy 382.189746 -246.397887) (xy 382.14373 -246.380435) (xy 382.101109 -246.355828)
			(xy 382.062988 -246.324703) (xy 382.030353 -246.287866) (xy 382.00405 -246.24627) (xy 381.984759 -246.200994)
			(xy 381.972982 -246.15321) (xy 381.969022 -246.104156) (xy 381.64008 -246.104156) (xy 381.639585 -246.128763)
			(xy 381.63169 -246.17734) (xy 381.616106 -246.224021) (xy 381.593235 -246.267598) (xy 381.56367 -246.306942)
			(xy 381.528177 -246.341034) (xy 381.487674 -246.36899) (xy 381.443212 -246.390088) (xy 381.395941 -246.40378)
			(xy 381.347086 -246.409712) (xy 381.297911 -246.407731) (xy 381.249692 -246.397887) (xy 381.203676 -246.380435)
			(xy 381.161055 -246.355828) (xy 381.122934 -246.324703) (xy 381.090299 -246.287866) (xy 381.063996 -246.24627)
			(xy 381.044705 -246.200994) (xy 381.032928 -246.15321) (xy 381.028968 -246.104156) (xy 380.71044 -246.104156)
			(xy 380.709928 -246.129602) (xy 380.701764 -246.179836) (xy 380.685648 -246.22811) (xy 380.661997 -246.273173)
			(xy 380.631424 -246.313859) (xy 380.59472 -246.349114) (xy 380.552836 -246.378024) (xy 380.506857 -246.399841)
			(xy 380.457973 -246.414001) (xy 380.407452 -246.420135) (xy 380.3566 -246.418086) (xy 380.306736 -246.407906)
			(xy 380.25915 -246.389859) (xy 380.215076 -246.364413) (xy 380.175654 -246.332226) (xy 380.141906 -246.294132)
			(xy 380.114705 -246.251118) (xy 380.094757 -246.204298) (xy 380.082578 -246.154884) (xy 380.078483 -246.104156)
			(xy 379.77064 -246.104156) (xy 379.770128 -246.129602) (xy 379.761964 -246.179836) (xy 379.745848 -246.22811)
			(xy 379.722197 -246.273173) (xy 379.691624 -246.313859) (xy 379.65492 -246.349114) (xy 379.613036 -246.378024)
			(xy 379.567057 -246.399841) (xy 379.518173 -246.414001) (xy 379.467652 -246.420135) (xy 379.4168 -246.418086)
			(xy 379.366936 -246.407906) (xy 379.31935 -246.389859) (xy 379.275276 -246.364413) (xy 379.235854 -246.332226)
			(xy 379.202106 -246.294132) (xy 379.174905 -246.251118) (xy 379.154957 -246.204298) (xy 379.142778 -246.154884)
			(xy 379.138683 -246.104156) (xy 378.820172 -246.104156) (xy 378.819677 -246.128763) (xy 378.811782 -246.17734)
			(xy 378.796198 -246.224021) (xy 378.773327 -246.267598) (xy 378.743762 -246.306942) (xy 378.708269 -246.341034)
			(xy 378.667766 -246.36899) (xy 378.623304 -246.390088) (xy 378.576033 -246.40378) (xy 378.527178 -246.409712)
			(xy 378.478003 -246.407731) (xy 378.429784 -246.397887) (xy 378.383768 -246.380435) (xy 378.341147 -246.355828)
			(xy 378.303026 -246.324703) (xy 378.270391 -246.287866) (xy 378.244088 -246.24627) (xy 378.224797 -246.200994)
			(xy 378.21302 -246.15321) (xy 378.20906 -246.104156) (xy 377.890532 -246.104156) (xy 377.89002 -246.129602)
			(xy 377.881856 -246.179836) (xy 377.86574 -246.22811) (xy 377.842089 -246.273173) (xy 377.811516 -246.313859)
			(xy 377.774812 -246.349114) (xy 377.732928 -246.378024) (xy 377.686949 -246.399841) (xy 377.638065 -246.414001)
			(xy 377.587544 -246.420135) (xy 377.536692 -246.418086) (xy 377.486828 -246.407906) (xy 377.439242 -246.389859)
			(xy 377.395168 -246.364413) (xy 377.355746 -246.332226) (xy 377.321998 -246.294132) (xy 377.294797 -246.251118)
			(xy 377.274849 -246.204298) (xy 377.26267 -246.154884) (xy 377.258575 -246.104156) (xy 376.940064 -246.104156)
			(xy 376.939569 -246.128763) (xy 376.931674 -246.17734) (xy 376.91609 -246.224021) (xy 376.893219 -246.267598)
			(xy 376.863654 -246.306942) (xy 376.828161 -246.341034) (xy 376.787658 -246.36899) (xy 376.743196 -246.390088)
			(xy 376.695925 -246.40378) (xy 376.64707 -246.409712) (xy 376.597895 -246.407731) (xy 376.549676 -246.397887)
			(xy 376.50366 -246.380435) (xy 376.461039 -246.355828) (xy 376.422918 -246.324703) (xy 376.390283 -246.287866)
			(xy 376.36398 -246.24627) (xy 376.344689 -246.200994) (xy 376.332912 -246.15321) (xy 376.328952 -246.104156)
			(xy 376.010424 -246.104156) (xy 376.009912 -246.129602) (xy 376.001748 -246.179836) (xy 375.985632 -246.22811)
			(xy 375.961981 -246.273173) (xy 375.931408 -246.313859) (xy 375.894704 -246.349114) (xy 375.85282 -246.378024)
			(xy 375.806841 -246.399841) (xy 375.757957 -246.414001) (xy 375.707436 -246.420135) (xy 375.656584 -246.418086)
			(xy 375.60672 -246.407906) (xy 375.559134 -246.389859) (xy 375.51506 -246.364413) (xy 375.475638 -246.332226)
			(xy 375.44189 -246.294132) (xy 375.414689 -246.251118) (xy 375.394741 -246.204298) (xy 375.382562 -246.154884)
			(xy 375.378467 -246.104156) (xy 375.060786 -246.104156) (xy 375.060788 -246.104178) (xy 375.05675 -246.153759)
			(xy 375.044738 -246.202031) (xy 375.025067 -246.247721) (xy 374.998258 -246.289623) (xy 374.965017 -246.326631)
			(xy 374.926222 -246.357768) (xy 374.904762 -246.370348) (xy 374.897118 -246.375068) (xy 374.885472 -246.388735)
			(xy 374.879224 -246.405568) (xy 374.878854 -246.414544) (xy 374.878854 -246.914162) (xy 375.848621 -246.914162)
			(xy 375.852716 -246.863434) (xy 375.864895 -246.81402) (xy 375.884843 -246.7672) (xy 375.912044 -246.724186)
			(xy 375.945792 -246.686092) (xy 375.985214 -246.653905) (xy 376.029288 -246.628459) (xy 376.076874 -246.610412)
			(xy 376.126738 -246.600232) (xy 376.17759 -246.598183) (xy 376.228111 -246.604317) (xy 376.276995 -246.618477)
			(xy 376.322974 -246.640294) (xy 376.364858 -246.669204) (xy 376.401562 -246.704459) (xy 376.432135 -246.745145)
			(xy 376.455786 -246.790208) (xy 376.471902 -246.838482) (xy 376.480066 -246.888716) (xy 376.480578 -246.914162)
			(xy 376.788675 -246.914162) (xy 376.79277 -246.863434) (xy 376.804949 -246.81402) (xy 376.824897 -246.7672)
			(xy 376.852098 -246.724186) (xy 376.885846 -246.686092) (xy 376.925268 -246.653905) (xy 376.969342 -246.628459)
			(xy 377.016928 -246.610412) (xy 377.066792 -246.600232) (xy 377.117644 -246.598183) (xy 377.168165 -246.604317)
			(xy 377.217049 -246.618477) (xy 377.263028 -246.640294) (xy 377.304912 -246.669204) (xy 377.341616 -246.704459)
			(xy 377.372189 -246.745145) (xy 377.39584 -246.790208) (xy 377.411956 -246.838482) (xy 377.42012 -246.888716)
			(xy 377.420632 -246.914162) (xy 378.668529 -246.914162) (xy 378.672624 -246.863434) (xy 378.684803 -246.81402)
			(xy 378.704751 -246.7672) (xy 378.731952 -246.724186) (xy 378.7657 -246.686092) (xy 378.805122 -246.653905)
			(xy 378.849196 -246.628459) (xy 378.896782 -246.610412) (xy 378.946646 -246.600232) (xy 378.997498 -246.598183)
			(xy 379.048019 -246.604317) (xy 379.096903 -246.618477) (xy 379.142882 -246.640294) (xy 379.184766 -246.669204)
			(xy 379.22147 -246.704459) (xy 379.252043 -246.745145) (xy 379.275694 -246.790208) (xy 379.29181 -246.838482)
			(xy 379.299974 -246.888716) (xy 379.300486 -246.914162) (xy 379.619014 -246.914162) (xy 379.622974 -246.865108)
			(xy 379.634751 -246.817324) (xy 379.654042 -246.772048) (xy 379.680345 -246.730452) (xy 379.71298 -246.693615)
			(xy 379.751101 -246.66249) (xy 379.793722 -246.637883) (xy 379.839738 -246.620431) (xy 379.887957 -246.610587)
			(xy 379.937132 -246.608606) (xy 379.985987 -246.614538) (xy 380.033258 -246.62823) (xy 380.07772 -246.649328)
			(xy 380.118223 -246.677284) (xy 380.153716 -246.711376) (xy 380.183281 -246.75072) (xy 380.206152 -246.794297)
			(xy 380.221736 -246.840978) (xy 380.229631 -246.889555) (xy 380.230126 -246.914162) (xy 380.548637 -246.914162)
			(xy 380.552732 -246.863434) (xy 380.564911 -246.81402) (xy 380.584859 -246.7672) (xy 380.61206 -246.724186)
			(xy 380.645808 -246.686092) (xy 380.68523 -246.653905) (xy 380.729304 -246.628459) (xy 380.77689 -246.610412)
			(xy 380.826754 -246.600232) (xy 380.877606 -246.598183) (xy 380.928127 -246.604317) (xy 380.977011 -246.618477)
			(xy 381.02299 -246.640294) (xy 381.064874 -246.669204) (xy 381.101578 -246.704459) (xy 381.132151 -246.745145)
			(xy 381.155802 -246.790208) (xy 381.171918 -246.838482) (xy 381.180082 -246.888716) (xy 381.180594 -246.914162)
			(xy 381.499122 -246.914162) (xy 381.503082 -246.865108) (xy 381.514859 -246.817324) (xy 381.53415 -246.772048)
			(xy 381.560453 -246.730452) (xy 381.593088 -246.693615) (xy 381.631209 -246.66249) (xy 381.67383 -246.637883)
			(xy 381.719846 -246.620431) (xy 381.768065 -246.610587) (xy 381.81724 -246.608606) (xy 381.866095 -246.614538)
			(xy 381.913366 -246.62823) (xy 381.957828 -246.649328) (xy 381.998331 -246.677284) (xy 382.033824 -246.711376)
			(xy 382.063389 -246.75072) (xy 382.08626 -246.794297) (xy 382.101844 -246.840978) (xy 382.109739 -246.889555)
			(xy 382.110234 -246.914162) (xy 382.438922 -246.914162) (xy 382.442882 -246.865108) (xy 382.454659 -246.817324)
			(xy 382.47395 -246.772048) (xy 382.500253 -246.730452) (xy 382.532888 -246.693615) (xy 382.571009 -246.66249)
			(xy 382.61363 -246.637883) (xy 382.659646 -246.620431) (xy 382.707865 -246.610587) (xy 382.75704 -246.608606)
			(xy 382.805895 -246.614538) (xy 382.853166 -246.62823) (xy 382.897628 -246.649328) (xy 382.938131 -246.677284)
			(xy 382.973624 -246.711376) (xy 383.003189 -246.75072) (xy 383.02606 -246.794297) (xy 383.041644 -246.840978)
			(xy 383.049539 -246.889555) (xy 383.050034 -246.914162) (xy 383.378976 -246.914162) (xy 383.382936 -246.865108)
			(xy 383.394713 -246.817324) (xy 383.414004 -246.772048) (xy 383.440307 -246.730452) (xy 383.472942 -246.693615)
			(xy 383.511063 -246.66249) (xy 383.553684 -246.637883) (xy 383.5997 -246.620431) (xy 383.647919 -246.610587)
			(xy 383.697094 -246.608606) (xy 383.745949 -246.614538) (xy 383.79322 -246.62823) (xy 383.837682 -246.649328)
			(xy 383.878185 -246.677284) (xy 383.913678 -246.711376) (xy 383.943243 -246.75072) (xy 383.966114 -246.794297)
			(xy 383.981698 -246.840978) (xy 383.989593 -246.889555) (xy 383.990088 -246.914162) (xy 385.259084 -246.914162)
			(xy 385.263044 -246.865108) (xy 385.274821 -246.817324) (xy 385.294112 -246.772048) (xy 385.320415 -246.730452)
			(xy 385.35305 -246.693615) (xy 385.391171 -246.66249) (xy 385.433792 -246.637883) (xy 385.479808 -246.620431)
			(xy 385.528027 -246.610587) (xy 385.577202 -246.608606) (xy 385.626057 -246.614538) (xy 385.673328 -246.62823)
			(xy 385.71779 -246.649328) (xy 385.758293 -246.677284) (xy 385.793786 -246.711376) (xy 385.823351 -246.75072)
			(xy 385.846222 -246.794297) (xy 385.861806 -246.840978) (xy 385.869701 -246.889555) (xy 385.870196 -246.914162)
			(xy 386.199138 -246.914162) (xy 386.203098 -246.865108) (xy 386.214875 -246.817324) (xy 386.234166 -246.772048)
			(xy 386.260469 -246.730452) (xy 386.293104 -246.693615) (xy 386.331225 -246.66249) (xy 386.373846 -246.637883)
			(xy 386.419862 -246.620431) (xy 386.468081 -246.610587) (xy 386.517256 -246.608606) (xy 386.566111 -246.614538)
			(xy 386.613382 -246.62823) (xy 386.657844 -246.649328) (xy 386.698347 -246.677284) (xy 386.73384 -246.711376)
			(xy 386.763405 -246.75072) (xy 386.786276 -246.794297) (xy 386.80186 -246.840978) (xy 386.809755 -246.889555)
			(xy 386.81025 -246.914162) (xy 386.809755 -246.938769) (xy 386.80186 -246.987346) (xy 386.786276 -247.034027)
			(xy 386.763405 -247.077604) (xy 386.73384 -247.116948) (xy 386.698347 -247.15104) (xy 386.657844 -247.178996)
			(xy 386.613382 -247.200094) (xy 386.566111 -247.213786) (xy 386.517256 -247.219718) (xy 386.468081 -247.217737)
			(xy 386.419862 -247.207893) (xy 386.373846 -247.190441) (xy 386.331225 -247.165834) (xy 386.293104 -247.134709)
			(xy 386.260469 -247.097872) (xy 386.234166 -247.056276) (xy 386.214875 -247.011) (xy 386.203098 -246.963216)
			(xy 386.199138 -246.914162) (xy 385.870196 -246.914162) (xy 385.869701 -246.938769) (xy 385.861806 -246.987346)
			(xy 385.846222 -247.034027) (xy 385.823351 -247.077604) (xy 385.793786 -247.116948) (xy 385.758293 -247.15104)
			(xy 385.71779 -247.178996) (xy 385.673328 -247.200094) (xy 385.626057 -247.213786) (xy 385.577202 -247.219718)
			(xy 385.528027 -247.217737) (xy 385.479808 -247.207893) (xy 385.433792 -247.190441) (xy 385.391171 -247.165834)
			(xy 385.35305 -247.134709) (xy 385.320415 -247.097872) (xy 385.294112 -247.056276) (xy 385.274821 -247.011)
			(xy 385.263044 -246.963216) (xy 385.259084 -246.914162) (xy 383.990088 -246.914162) (xy 383.989593 -246.938769)
			(xy 383.981698 -246.987346) (xy 383.966114 -247.034027) (xy 383.943243 -247.077604) (xy 383.913678 -247.116948)
			(xy 383.878185 -247.15104) (xy 383.837682 -247.178996) (xy 383.79322 -247.200094) (xy 383.745949 -247.213786)
			(xy 383.697094 -247.219718) (xy 383.647919 -247.217737) (xy 383.5997 -247.207893) (xy 383.553684 -247.190441)
			(xy 383.511063 -247.165834) (xy 383.472942 -247.134709) (xy 383.440307 -247.097872) (xy 383.414004 -247.056276)
			(xy 383.394713 -247.011) (xy 383.382936 -246.963216) (xy 383.378976 -246.914162) (xy 383.050034 -246.914162)
			(xy 383.049539 -246.938769) (xy 383.041644 -246.987346) (xy 383.02606 -247.034027) (xy 383.003189 -247.077604)
			(xy 382.973624 -247.116948) (xy 382.938131 -247.15104) (xy 382.897628 -247.178996) (xy 382.853166 -247.200094)
			(xy 382.805895 -247.213786) (xy 382.75704 -247.219718) (xy 382.707865 -247.217737) (xy 382.659646 -247.207893)
			(xy 382.61363 -247.190441) (xy 382.571009 -247.165834) (xy 382.532888 -247.134709) (xy 382.500253 -247.097872)
			(xy 382.47395 -247.056276) (xy 382.454659 -247.011) (xy 382.442882 -246.963216) (xy 382.438922 -246.914162)
			(xy 382.110234 -246.914162) (xy 382.109739 -246.938769) (xy 382.101844 -246.987346) (xy 382.08626 -247.034027)
			(xy 382.063389 -247.077604) (xy 382.033824 -247.116948) (xy 381.998331 -247.15104) (xy 381.957828 -247.178996)
			(xy 381.913366 -247.200094) (xy 381.866095 -247.213786) (xy 381.81724 -247.219718) (xy 381.768065 -247.217737)
			(xy 381.719846 -247.207893) (xy 381.67383 -247.190441) (xy 381.631209 -247.165834) (xy 381.593088 -247.134709)
			(xy 381.560453 -247.097872) (xy 381.53415 -247.056276) (xy 381.514859 -247.011) (xy 381.503082 -246.963216)
			(xy 381.499122 -246.914162) (xy 381.180594 -246.914162) (xy 381.180082 -246.939608) (xy 381.171918 -246.989842)
			(xy 381.155802 -247.038116) (xy 381.132151 -247.083179) (xy 381.101578 -247.123865) (xy 381.064874 -247.15912)
			(xy 381.02299 -247.18803) (xy 380.977011 -247.209847) (xy 380.928127 -247.224007) (xy 380.877606 -247.230141)
			(xy 380.826754 -247.228092) (xy 380.77689 -247.217912) (xy 380.729304 -247.199865) (xy 380.68523 -247.174419)
			(xy 380.645808 -247.142232) (xy 380.61206 -247.104138) (xy 380.584859 -247.061124) (xy 380.564911 -247.014304)
			(xy 380.552732 -246.96489) (xy 380.548637 -246.914162) (xy 380.230126 -246.914162) (xy 380.229631 -246.938769)
			(xy 380.221736 -246.987346) (xy 380.206152 -247.034027) (xy 380.183281 -247.077604) (xy 380.153716 -247.116948)
			(xy 380.118223 -247.15104) (xy 380.07772 -247.178996) (xy 380.033258 -247.200094) (xy 379.985987 -247.213786)
			(xy 379.937132 -247.219718) (xy 379.887957 -247.217737) (xy 379.839738 -247.207893) (xy 379.793722 -247.190441)
			(xy 379.751101 -247.165834) (xy 379.71298 -247.134709) (xy 379.680345 -247.097872) (xy 379.654042 -247.056276)
			(xy 379.634751 -247.011) (xy 379.622974 -246.963216) (xy 379.619014 -246.914162) (xy 379.300486 -246.914162)
			(xy 379.299974 -246.939608) (xy 379.29181 -246.989842) (xy 379.275694 -247.038116) (xy 379.252043 -247.083179)
			(xy 379.22147 -247.123865) (xy 379.184766 -247.15912) (xy 379.142882 -247.18803) (xy 379.096903 -247.209847)
			(xy 379.048019 -247.224007) (xy 378.997498 -247.230141) (xy 378.946646 -247.228092) (xy 378.896782 -247.217912)
			(xy 378.849196 -247.199865) (xy 378.805122 -247.174419) (xy 378.7657 -247.142232) (xy 378.731952 -247.104138)
			(xy 378.704751 -247.061124) (xy 378.684803 -247.014304) (xy 378.672624 -246.96489) (xy 378.668529 -246.914162)
			(xy 377.420632 -246.914162) (xy 377.42012 -246.939608) (xy 377.411956 -246.989842) (xy 377.39584 -247.038116)
			(xy 377.372189 -247.083179) (xy 377.341616 -247.123865) (xy 377.304912 -247.15912) (xy 377.263028 -247.18803)
			(xy 377.217049 -247.209847) (xy 377.168165 -247.224007) (xy 377.117644 -247.230141) (xy 377.066792 -247.228092)
			(xy 377.016928 -247.217912) (xy 376.969342 -247.199865) (xy 376.925268 -247.174419) (xy 376.885846 -247.142232)
			(xy 376.852098 -247.104138) (xy 376.824897 -247.061124) (xy 376.804949 -247.014304) (xy 376.79277 -246.96489)
			(xy 376.788675 -246.914162) (xy 376.480578 -246.914162) (xy 376.480066 -246.939608) (xy 376.471902 -246.989842)
			(xy 376.455786 -247.038116) (xy 376.432135 -247.083179) (xy 376.401562 -247.123865) (xy 376.364858 -247.15912)
			(xy 376.322974 -247.18803) (xy 376.276995 -247.209847) (xy 376.228111 -247.224007) (xy 376.17759 -247.230141)
			(xy 376.126738 -247.228092) (xy 376.076874 -247.217912) (xy 376.029288 -247.199865) (xy 375.985214 -247.174419)
			(xy 375.945792 -247.142232) (xy 375.912044 -247.104138) (xy 375.884843 -247.061124) (xy 375.864895 -247.014304)
			(xy 375.852716 -246.96489) (xy 375.848621 -246.914162) (xy 374.878854 -246.914162) (xy 374.878854 -247.41378)
			(xy 374.879193 -247.42277) (xy 374.885394 -247.439646) (xy 374.897066 -247.45332) (xy 374.904762 -247.457976)
			(xy 374.926185 -247.47062) (xy 374.964982 -247.501751) (xy 374.998227 -247.538753) (xy 375.02504 -247.58065)
			(xy 375.044716 -247.626337) (xy 375.056734 -247.674606) (xy 375.060776 -247.724168) (xy 375.378467 -247.724168)
			(xy 375.382562 -247.67344) (xy 375.394741 -247.624026) (xy 375.414689 -247.577206) (xy 375.44189 -247.534192)
			(xy 375.475638 -247.496098) (xy 375.51506 -247.463911) (xy 375.559134 -247.438465) (xy 375.60672 -247.420418)
			(xy 375.656584 -247.410238) (xy 375.707436 -247.408189) (xy 375.757957 -247.414323) (xy 375.806841 -247.428483)
			(xy 375.85282 -247.4503) (xy 375.894704 -247.47921) (xy 375.931408 -247.514465) (xy 375.961981 -247.555151)
			(xy 375.985632 -247.600214) (xy 376.001748 -247.648488) (xy 376.009912 -247.698722) (xy 376.010424 -247.724168)
			(xy 376.328952 -247.724168) (xy 376.332912 -247.675114) (xy 376.344689 -247.62733) (xy 376.36398 -247.582054)
			(xy 376.390283 -247.540458) (xy 376.422918 -247.503621) (xy 376.461039 -247.472496) (xy 376.50366 -247.447889)
			(xy 376.549676 -247.430437) (xy 376.597895 -247.420593) (xy 376.64707 -247.418612) (xy 376.695925 -247.424544)
			(xy 376.743196 -247.438236) (xy 376.787658 -247.459334) (xy 376.828161 -247.48729) (xy 376.863654 -247.521382)
			(xy 376.893219 -247.560726) (xy 376.91609 -247.604303) (xy 376.931674 -247.650984) (xy 376.939569 -247.699561)
			(xy 376.940064 -247.724168) (xy 377.258575 -247.724168) (xy 377.26267 -247.67344) (xy 377.274849 -247.624026)
			(xy 377.294797 -247.577206) (xy 377.321998 -247.534192) (xy 377.355746 -247.496098) (xy 377.395168 -247.463911)
			(xy 377.439242 -247.438465) (xy 377.486828 -247.420418) (xy 377.536692 -247.410238) (xy 377.587544 -247.408189)
			(xy 377.638065 -247.414323) (xy 377.686949 -247.428483) (xy 377.732928 -247.4503) (xy 377.774812 -247.47921)
			(xy 377.811516 -247.514465) (xy 377.842089 -247.555151) (xy 377.86574 -247.600214) (xy 377.881856 -247.648488)
			(xy 377.89002 -247.698722) (xy 377.890532 -247.724168) (xy 378.20906 -247.724168) (xy 378.21302 -247.675114)
			(xy 378.224797 -247.62733) (xy 378.244088 -247.582054) (xy 378.270391 -247.540458) (xy 378.303026 -247.503621)
			(xy 378.341147 -247.472496) (xy 378.383768 -247.447889) (xy 378.429784 -247.430437) (xy 378.478003 -247.420593)
			(xy 378.527178 -247.418612) (xy 378.576033 -247.424544) (xy 378.623304 -247.438236) (xy 378.667766 -247.459334)
			(xy 378.708269 -247.48729) (xy 378.743762 -247.521382) (xy 378.773327 -247.560726) (xy 378.796198 -247.604303)
			(xy 378.811782 -247.650984) (xy 378.819677 -247.699561) (xy 378.820172 -247.724168) (xy 379.138683 -247.724168)
			(xy 379.142778 -247.67344) (xy 379.154957 -247.624026) (xy 379.174905 -247.577206) (xy 379.202106 -247.534192)
			(xy 379.235854 -247.496098) (xy 379.275276 -247.463911) (xy 379.31935 -247.438465) (xy 379.366936 -247.420418)
			(xy 379.4168 -247.410238) (xy 379.467652 -247.408189) (xy 379.518173 -247.414323) (xy 379.567057 -247.428483)
			(xy 379.613036 -247.4503) (xy 379.65492 -247.47921) (xy 379.691624 -247.514465) (xy 379.722197 -247.555151)
			(xy 379.745848 -247.600214) (xy 379.761964 -247.648488) (xy 379.770128 -247.698722) (xy 379.77064 -247.724168)
			(xy 380.078483 -247.724168) (xy 380.082578 -247.67344) (xy 380.094757 -247.624026) (xy 380.114705 -247.577206)
			(xy 380.141906 -247.534192) (xy 380.175654 -247.496098) (xy 380.215076 -247.463911) (xy 380.25915 -247.438465)
			(xy 380.306736 -247.420418) (xy 380.3566 -247.410238) (xy 380.407452 -247.408189) (xy 380.457973 -247.414323)
			(xy 380.506857 -247.428483) (xy 380.552836 -247.4503) (xy 380.59472 -247.47921) (xy 380.631424 -247.514465)
			(xy 380.661997 -247.555151) (xy 380.685648 -247.600214) (xy 380.701764 -247.648488) (xy 380.709928 -247.698722)
			(xy 380.71044 -247.724168) (xy 381.028968 -247.724168) (xy 381.032928 -247.675114) (xy 381.044705 -247.62733)
			(xy 381.063996 -247.582054) (xy 381.090299 -247.540458) (xy 381.122934 -247.503621) (xy 381.161055 -247.472496)
			(xy 381.203676 -247.447889) (xy 381.249692 -247.430437) (xy 381.297911 -247.420593) (xy 381.347086 -247.418612)
			(xy 381.395941 -247.424544) (xy 381.443212 -247.438236) (xy 381.487674 -247.459334) (xy 381.528177 -247.48729)
			(xy 381.56367 -247.521382) (xy 381.593235 -247.560726) (xy 381.616106 -247.604303) (xy 381.63169 -247.650984)
			(xy 381.639585 -247.699561) (xy 381.64008 -247.724168) (xy 381.969022 -247.724168) (xy 381.972982 -247.675114)
			(xy 381.984759 -247.62733) (xy 382.00405 -247.582054) (xy 382.030353 -247.540458) (xy 382.062988 -247.503621)
			(xy 382.101109 -247.472496) (xy 382.14373 -247.447889) (xy 382.189746 -247.430437) (xy 382.237965 -247.420593)
			(xy 382.28714 -247.418612) (xy 382.335995 -247.424544) (xy 382.383266 -247.438236) (xy 382.427728 -247.459334)
			(xy 382.468231 -247.48729) (xy 382.503724 -247.521382) (xy 382.533289 -247.560726) (xy 382.55616 -247.604303)
			(xy 382.571744 -247.650984) (xy 382.579639 -247.699561) (xy 382.580134 -247.724168) (xy 382.909076 -247.724168)
			(xy 382.913036 -247.675114) (xy 382.924813 -247.62733) (xy 382.944104 -247.582054) (xy 382.970407 -247.540458)
			(xy 383.003042 -247.503621) (xy 383.041163 -247.472496) (xy 383.083784 -247.447889) (xy 383.1298 -247.430437)
			(xy 383.178019 -247.420593) (xy 383.227194 -247.418612) (xy 383.276049 -247.424544) (xy 383.32332 -247.438236)
			(xy 383.367782 -247.459334) (xy 383.408285 -247.48729) (xy 383.443778 -247.521382) (xy 383.473343 -247.560726)
			(xy 383.496214 -247.604303) (xy 383.511798 -247.650984) (xy 383.519693 -247.699561) (xy 383.520188 -247.724168)
			(xy 383.84913 -247.724168) (xy 383.85309 -247.675114) (xy 383.864867 -247.62733) (xy 383.884158 -247.582054)
			(xy 383.910461 -247.540458) (xy 383.943096 -247.503621) (xy 383.981217 -247.472496) (xy 384.023838 -247.447889)
			(xy 384.069854 -247.430437) (xy 384.118073 -247.420593) (xy 384.167248 -247.418612) (xy 384.216103 -247.424544)
			(xy 384.263374 -247.438236) (xy 384.307836 -247.459334) (xy 384.348339 -247.48729) (xy 384.383832 -247.521382)
			(xy 384.413397 -247.560726) (xy 384.436268 -247.604303) (xy 384.451852 -247.650984) (xy 384.459747 -247.699561)
			(xy 384.460242 -247.724168) (xy 384.78893 -247.724168) (xy 384.79289 -247.675114) (xy 384.804667 -247.62733)
			(xy 384.823958 -247.582054) (xy 384.850261 -247.540458) (xy 384.882896 -247.503621) (xy 384.921017 -247.472496)
			(xy 384.963638 -247.447889) (xy 385.009654 -247.430437) (xy 385.057873 -247.420593) (xy 385.107048 -247.418612)
			(xy 385.155903 -247.424544) (xy 385.203174 -247.438236) (xy 385.247636 -247.459334) (xy 385.288139 -247.48729)
			(xy 385.323632 -247.521382) (xy 385.353197 -247.560726) (xy 385.376068 -247.604303) (xy 385.391652 -247.650984)
			(xy 385.399547 -247.699561) (xy 385.400042 -247.724168) (xy 385.728984 -247.724168) (xy 385.732944 -247.675114)
			(xy 385.744721 -247.62733) (xy 385.764012 -247.582054) (xy 385.790315 -247.540458) (xy 385.82295 -247.503621)
			(xy 385.861071 -247.472496) (xy 385.903692 -247.447889) (xy 385.949708 -247.430437) (xy 385.997927 -247.420593)
			(xy 386.047102 -247.418612) (xy 386.095957 -247.424544) (xy 386.143228 -247.438236) (xy 386.18769 -247.459334)
			(xy 386.228193 -247.48729) (xy 386.263686 -247.521382) (xy 386.293251 -247.560726) (xy 386.316122 -247.604303)
			(xy 386.331706 -247.650984) (xy 386.339601 -247.699561) (xy 386.340096 -247.724168) (xy 386.669038 -247.724168)
			(xy 386.672998 -247.675114) (xy 386.684775 -247.62733) (xy 386.704066 -247.582054) (xy 386.730369 -247.540458)
			(xy 386.763004 -247.503621) (xy 386.801125 -247.472496) (xy 386.843746 -247.447889) (xy 386.889762 -247.430437)
			(xy 386.937981 -247.420593) (xy 386.987156 -247.418612) (xy 387.036011 -247.424544) (xy 387.083282 -247.438236)
			(xy 387.127744 -247.459334) (xy 387.168247 -247.48729) (xy 387.20374 -247.521382) (xy 387.233305 -247.560726)
			(xy 387.256176 -247.604303) (xy 387.27176 -247.650984) (xy 387.279655 -247.699561) (xy 387.28015 -247.724168)
			(xy 387.279655 -247.748775) (xy 387.27176 -247.797352) (xy 387.256176 -247.844033) (xy 387.233305 -247.88761)
			(xy 387.20374 -247.926954) (xy 387.168247 -247.961046) (xy 387.127744 -247.989002) (xy 387.083282 -248.0101)
			(xy 387.036011 -248.023792) (xy 386.987156 -248.029724) (xy 386.937981 -248.027743) (xy 386.889762 -248.017899)
			(xy 386.843746 -248.000447) (xy 386.801125 -247.97584) (xy 386.763004 -247.944715) (xy 386.730369 -247.907878)
			(xy 386.704066 -247.866282) (xy 386.684775 -247.821006) (xy 386.672998 -247.773222) (xy 386.669038 -247.724168)
			(xy 386.340096 -247.724168) (xy 386.339601 -247.748775) (xy 386.331706 -247.797352) (xy 386.316122 -247.844033)
			(xy 386.293251 -247.88761) (xy 386.263686 -247.926954) (xy 386.228193 -247.961046) (xy 386.18769 -247.989002)
			(xy 386.143228 -248.0101) (xy 386.095957 -248.023792) (xy 386.047102 -248.029724) (xy 385.997927 -248.027743)
			(xy 385.949708 -248.017899) (xy 385.903692 -248.000447) (xy 385.861071 -247.97584) (xy 385.82295 -247.944715)
			(xy 385.790315 -247.907878) (xy 385.764012 -247.866282) (xy 385.744721 -247.821006) (xy 385.732944 -247.773222)
			(xy 385.728984 -247.724168) (xy 385.400042 -247.724168) (xy 385.399547 -247.748775) (xy 385.391652 -247.797352)
			(xy 385.376068 -247.844033) (xy 385.353197 -247.88761) (xy 385.323632 -247.926954) (xy 385.288139 -247.961046)
			(xy 385.247636 -247.989002) (xy 385.203174 -248.0101) (xy 385.155903 -248.023792) (xy 385.107048 -248.029724)
			(xy 385.057873 -248.027743) (xy 385.009654 -248.017899) (xy 384.963638 -248.000447) (xy 384.921017 -247.97584)
			(xy 384.882896 -247.944715) (xy 384.850261 -247.907878) (xy 384.823958 -247.866282) (xy 384.804667 -247.821006)
			(xy 384.79289 -247.773222) (xy 384.78893 -247.724168) (xy 384.460242 -247.724168) (xy 384.459747 -247.748775)
			(xy 384.451852 -247.797352) (xy 384.436268 -247.844033) (xy 384.413397 -247.88761) (xy 384.383832 -247.926954)
			(xy 384.348339 -247.961046) (xy 384.307836 -247.989002) (xy 384.263374 -248.0101) (xy 384.216103 -248.023792)
			(xy 384.167248 -248.029724) (xy 384.118073 -248.027743) (xy 384.069854 -248.017899) (xy 384.023838 -248.000447)
			(xy 383.981217 -247.97584) (xy 383.943096 -247.944715) (xy 383.910461 -247.907878) (xy 383.884158 -247.866282)
			(xy 383.864867 -247.821006) (xy 383.85309 -247.773222) (xy 383.84913 -247.724168) (xy 383.520188 -247.724168)
			(xy 383.519693 -247.748775) (xy 383.511798 -247.797352) (xy 383.496214 -247.844033) (xy 383.473343 -247.88761)
			(xy 383.443778 -247.926954) (xy 383.408285 -247.961046) (xy 383.367782 -247.989002) (xy 383.32332 -248.0101)
			(xy 383.276049 -248.023792) (xy 383.227194 -248.029724) (xy 383.178019 -248.027743) (xy 383.1298 -248.017899)
			(xy 383.083784 -248.000447) (xy 383.041163 -247.97584) (xy 383.003042 -247.944715) (xy 382.970407 -247.907878)
			(xy 382.944104 -247.866282) (xy 382.924813 -247.821006) (xy 382.913036 -247.773222) (xy 382.909076 -247.724168)
			(xy 382.580134 -247.724168) (xy 382.579639 -247.748775) (xy 382.571744 -247.797352) (xy 382.55616 -247.844033)
			(xy 382.533289 -247.88761) (xy 382.503724 -247.926954) (xy 382.468231 -247.961046) (xy 382.427728 -247.989002)
			(xy 382.383266 -248.0101) (xy 382.335995 -248.023792) (xy 382.28714 -248.029724) (xy 382.237965 -248.027743)
			(xy 382.189746 -248.017899) (xy 382.14373 -248.000447) (xy 382.101109 -247.97584) (xy 382.062988 -247.944715)
			(xy 382.030353 -247.907878) (xy 382.00405 -247.866282) (xy 381.984759 -247.821006) (xy 381.972982 -247.773222)
			(xy 381.969022 -247.724168) (xy 381.64008 -247.724168) (xy 381.639585 -247.748775) (xy 381.63169 -247.797352)
			(xy 381.616106 -247.844033) (xy 381.593235 -247.88761) (xy 381.56367 -247.926954) (xy 381.528177 -247.961046)
			(xy 381.487674 -247.989002) (xy 381.443212 -248.0101) (xy 381.395941 -248.023792) (xy 381.347086 -248.029724)
			(xy 381.297911 -248.027743) (xy 381.249692 -248.017899) (xy 381.203676 -248.000447) (xy 381.161055 -247.97584)
			(xy 381.122934 -247.944715) (xy 381.090299 -247.907878) (xy 381.063996 -247.866282) (xy 381.044705 -247.821006)
			(xy 381.032928 -247.773222) (xy 381.028968 -247.724168) (xy 380.71044 -247.724168) (xy 380.709928 -247.749614)
			(xy 380.701764 -247.799848) (xy 380.685648 -247.848122) (xy 380.661997 -247.893185) (xy 380.631424 -247.933871)
			(xy 380.59472 -247.969126) (xy 380.552836 -247.998036) (xy 380.506857 -248.019853) (xy 380.457973 -248.034013)
			(xy 380.407452 -248.040147) (xy 380.3566 -248.038098) (xy 380.306736 -248.027918) (xy 380.25915 -248.009871)
			(xy 380.215076 -247.984425) (xy 380.175654 -247.952238) (xy 380.141906 -247.914144) (xy 380.114705 -247.87113)
			(xy 380.094757 -247.82431) (xy 380.082578 -247.774896) (xy 380.078483 -247.724168) (xy 379.77064 -247.724168)
			(xy 379.770128 -247.749614) (xy 379.761964 -247.799848) (xy 379.745848 -247.848122) (xy 379.722197 -247.893185)
			(xy 379.691624 -247.933871) (xy 379.65492 -247.969126) (xy 379.613036 -247.998036) (xy 379.567057 -248.019853)
			(xy 379.518173 -248.034013) (xy 379.467652 -248.040147) (xy 379.4168 -248.038098) (xy 379.366936 -248.027918)
			(xy 379.31935 -248.009871) (xy 379.275276 -247.984425) (xy 379.235854 -247.952238) (xy 379.202106 -247.914144)
			(xy 379.174905 -247.87113) (xy 379.154957 -247.82431) (xy 379.142778 -247.774896) (xy 379.138683 -247.724168)
			(xy 378.820172 -247.724168) (xy 378.819677 -247.748775) (xy 378.811782 -247.797352) (xy 378.796198 -247.844033)
			(xy 378.773327 -247.88761) (xy 378.743762 -247.926954) (xy 378.708269 -247.961046) (xy 378.667766 -247.989002)
			(xy 378.623304 -248.0101) (xy 378.576033 -248.023792) (xy 378.527178 -248.029724) (xy 378.478003 -248.027743)
			(xy 378.429784 -248.017899) (xy 378.383768 -248.000447) (xy 378.341147 -247.97584) (xy 378.303026 -247.944715)
			(xy 378.270391 -247.907878) (xy 378.244088 -247.866282) (xy 378.224797 -247.821006) (xy 378.21302 -247.773222)
			(xy 378.20906 -247.724168) (xy 377.890532 -247.724168) (xy 377.89002 -247.749614) (xy 377.881856 -247.799848)
			(xy 377.86574 -247.848122) (xy 377.842089 -247.893185) (xy 377.811516 -247.933871) (xy 377.774812 -247.969126)
			(xy 377.732928 -247.998036) (xy 377.686949 -248.019853) (xy 377.638065 -248.034013) (xy 377.587544 -248.040147)
			(xy 377.536692 -248.038098) (xy 377.486828 -248.027918) (xy 377.439242 -248.009871) (xy 377.395168 -247.984425)
			(xy 377.355746 -247.952238) (xy 377.321998 -247.914144) (xy 377.294797 -247.87113) (xy 377.274849 -247.82431)
			(xy 377.26267 -247.774896) (xy 377.258575 -247.724168) (xy 376.940064 -247.724168) (xy 376.939569 -247.748775)
			(xy 376.931674 -247.797352) (xy 376.91609 -247.844033) (xy 376.893219 -247.88761) (xy 376.863654 -247.926954)
			(xy 376.828161 -247.961046) (xy 376.787658 -247.989002) (xy 376.743196 -248.0101) (xy 376.695925 -248.023792)
			(xy 376.64707 -248.029724) (xy 376.597895 -248.027743) (xy 376.549676 -248.017899) (xy 376.50366 -248.000447)
			(xy 376.461039 -247.97584) (xy 376.422918 -247.944715) (xy 376.390283 -247.907878) (xy 376.36398 -247.866282)
			(xy 376.344689 -247.821006) (xy 376.332912 -247.773222) (xy 376.328952 -247.724168) (xy 376.010424 -247.724168)
			(xy 376.009912 -247.749614) (xy 376.001748 -247.799848) (xy 375.985632 -247.848122) (xy 375.961981 -247.893185)
			(xy 375.931408 -247.933871) (xy 375.894704 -247.969126) (xy 375.85282 -247.998036) (xy 375.806841 -248.019853)
			(xy 375.757957 -248.034013) (xy 375.707436 -248.040147) (xy 375.656584 -248.038098) (xy 375.60672 -248.027918)
			(xy 375.559134 -248.009871) (xy 375.51506 -247.984425) (xy 375.475638 -247.952238) (xy 375.44189 -247.914144)
			(xy 375.414689 -247.87113) (xy 375.394741 -247.82431) (xy 375.382562 -247.774896) (xy 375.378467 -247.724168)
			(xy 375.060776 -247.724168) (xy 375.060777 -247.724184) (xy 375.056739 -247.773763) (xy 375.044726 -247.822033)
			(xy 375.025055 -247.867722) (xy 374.998246 -247.909622) (xy 374.965005 -247.946628) (xy 374.926211 -247.977763)
			(xy 374.904762 -247.99036) (xy 374.897119 -247.995081) (xy 374.885476 -248.008748) (xy 374.879233 -248.025581)
			(xy 374.878854 -248.034556) (xy 374.878854 -248.21134) (xy 374.879222 -248.220775) (xy 374.88603 -248.238372)
			(xy 374.898746 -248.252313) (xy 374.907048 -248.256806) (xy 374.98655 -248.296176) (xy 374.992991 -248.299125)
			(xy 375.006913 -248.301714) (xy 375.013982 -248.301256) (xy 375.020969 -248.300398) (xy 375.034117 -248.295379)
			(xy 375.03989 -248.29135) (xy 375.059944 -248.276666) (xy 375.103824 -248.253327) (xy 375.150909 -248.237416)
			(xy 375.199952 -248.229354) (xy 375.224802 -248.228866) (xy 375.248794 -248.229337) (xy 375.296187 -248.236843)
			(xy 375.341822 -248.25167) (xy 375.384577 -248.273453) (xy 375.423397 -248.301656) (xy 375.457328 -248.335585)
			(xy 375.485534 -248.374403) (xy 375.507321 -248.417156) (xy 375.522151 -248.46279) (xy 375.529661 -248.510182)
			(xy 375.53011 -248.534174) (xy 375.848621 -248.534174) (xy 375.852716 -248.483446) (xy 375.864895 -248.434032)
			(xy 375.884843 -248.387212) (xy 375.912044 -248.344198) (xy 375.945792 -248.306104) (xy 375.985214 -248.273917)
			(xy 376.029288 -248.248471) (xy 376.076874 -248.230424) (xy 376.126738 -248.220244) (xy 376.17759 -248.218195)
			(xy 376.228111 -248.224329) (xy 376.276995 -248.238489) (xy 376.322974 -248.260306) (xy 376.364858 -248.289216)
			(xy 376.401562 -248.324471) (xy 376.432135 -248.365157) (xy 376.455786 -248.41022) (xy 376.471902 -248.458494)
			(xy 376.480066 -248.508728) (xy 376.480578 -248.534174) (xy 376.788675 -248.534174) (xy 376.79277 -248.483446)
			(xy 376.804949 -248.434032) (xy 376.824897 -248.387212) (xy 376.852098 -248.344198) (xy 376.885846 -248.306104)
			(xy 376.925268 -248.273917) (xy 376.969342 -248.248471) (xy 377.016928 -248.230424) (xy 377.066792 -248.220244)
			(xy 377.117644 -248.218195) (xy 377.168165 -248.224329) (xy 377.217049 -248.238489) (xy 377.263028 -248.260306)
			(xy 377.304912 -248.289216) (xy 377.341616 -248.324471) (xy 377.372189 -248.365157) (xy 377.39584 -248.41022)
			(xy 377.411956 -248.458494) (xy 377.42012 -248.508728) (xy 377.420632 -248.534174) (xy 377.738906 -248.534174)
			(xy 377.742866 -248.48512) (xy 377.754643 -248.437336) (xy 377.773934 -248.39206) (xy 377.800237 -248.350464)
			(xy 377.832872 -248.313627) (xy 377.870993 -248.282502) (xy 377.913614 -248.257895) (xy 377.95963 -248.240443)
			(xy 378.007849 -248.230599) (xy 378.057024 -248.228618) (xy 378.105879 -248.23455) (xy 378.15315 -248.248242)
			(xy 378.197612 -248.26934) (xy 378.238115 -248.297296) (xy 378.273608 -248.331388) (xy 378.303173 -248.370732)
			(xy 378.326044 -248.414309) (xy 378.341628 -248.46099) (xy 378.349523 -248.509567) (xy 378.350018 -248.534174)
			(xy 378.668529 -248.534174) (xy 378.672624 -248.483446) (xy 378.684803 -248.434032) (xy 378.704751 -248.387212)
			(xy 378.731952 -248.344198) (xy 378.7657 -248.306104) (xy 378.805122 -248.273917) (xy 378.849196 -248.248471)
			(xy 378.896782 -248.230424) (xy 378.946646 -248.220244) (xy 378.997498 -248.218195) (xy 379.048019 -248.224329)
			(xy 379.096903 -248.238489) (xy 379.142882 -248.260306) (xy 379.184766 -248.289216) (xy 379.22147 -248.324471)
			(xy 379.252043 -248.365157) (xy 379.275694 -248.41022) (xy 379.29181 -248.458494) (xy 379.299974 -248.508728)
			(xy 379.300486 -248.534174) (xy 379.619014 -248.534174) (xy 379.622974 -248.48512) (xy 379.634751 -248.437336)
			(xy 379.654042 -248.39206) (xy 379.680345 -248.350464) (xy 379.71298 -248.313627) (xy 379.751101 -248.282502)
			(xy 379.793722 -248.257895) (xy 379.839738 -248.240443) (xy 379.887957 -248.230599) (xy 379.937132 -248.228618)
			(xy 379.985987 -248.23455) (xy 380.033258 -248.248242) (xy 380.07772 -248.26934) (xy 380.118223 -248.297296)
			(xy 380.153716 -248.331388) (xy 380.183281 -248.370732) (xy 380.206152 -248.414309) (xy 380.221736 -248.46099)
			(xy 380.229631 -248.509567) (xy 380.230126 -248.534174) (xy 380.548637 -248.534174) (xy 380.552732 -248.483446)
			(xy 380.564911 -248.434032) (xy 380.584859 -248.387212) (xy 380.61206 -248.344198) (xy 380.645808 -248.306104)
			(xy 380.68523 -248.273917) (xy 380.729304 -248.248471) (xy 380.77689 -248.230424) (xy 380.826754 -248.220244)
			(xy 380.877606 -248.218195) (xy 380.928127 -248.224329) (xy 380.977011 -248.238489) (xy 381.02299 -248.260306)
			(xy 381.064874 -248.289216) (xy 381.101578 -248.324471) (xy 381.132151 -248.365157) (xy 381.155802 -248.41022)
			(xy 381.171918 -248.458494) (xy 381.180082 -248.508728) (xy 381.180594 -248.534174) (xy 381.499122 -248.534174)
			(xy 381.503082 -248.48512) (xy 381.514859 -248.437336) (xy 381.53415 -248.39206) (xy 381.560453 -248.350464)
			(xy 381.593088 -248.313627) (xy 381.631209 -248.282502) (xy 381.67383 -248.257895) (xy 381.719846 -248.240443)
			(xy 381.768065 -248.230599) (xy 381.81724 -248.228618) (xy 381.866095 -248.23455) (xy 381.913366 -248.248242)
			(xy 381.957828 -248.26934) (xy 381.998331 -248.297296) (xy 382.033824 -248.331388) (xy 382.063389 -248.370732)
			(xy 382.08626 -248.414309) (xy 382.101844 -248.46099) (xy 382.109739 -248.509567) (xy 382.110234 -248.534174)
			(xy 382.438922 -248.534174) (xy 382.442882 -248.48512) (xy 382.454659 -248.437336) (xy 382.47395 -248.39206)
			(xy 382.500253 -248.350464) (xy 382.532888 -248.313627) (xy 382.571009 -248.282502) (xy 382.61363 -248.257895)
			(xy 382.659646 -248.240443) (xy 382.707865 -248.230599) (xy 382.75704 -248.228618) (xy 382.805895 -248.23455)
			(xy 382.853166 -248.248242) (xy 382.897628 -248.26934) (xy 382.938131 -248.297296) (xy 382.973624 -248.331388)
			(xy 383.003189 -248.370732) (xy 383.02606 -248.414309) (xy 383.041644 -248.46099) (xy 383.049539 -248.509567)
			(xy 383.050034 -248.534174) (xy 383.378976 -248.534174) (xy 383.382936 -248.48512) (xy 383.394713 -248.437336)
			(xy 383.414004 -248.39206) (xy 383.440307 -248.350464) (xy 383.472942 -248.313627) (xy 383.511063 -248.282502)
			(xy 383.553684 -248.257895) (xy 383.5997 -248.240443) (xy 383.647919 -248.230599) (xy 383.697094 -248.228618)
			(xy 383.745949 -248.23455) (xy 383.79322 -248.248242) (xy 383.837682 -248.26934) (xy 383.878185 -248.297296)
			(xy 383.913678 -248.331388) (xy 383.943243 -248.370732) (xy 383.966114 -248.414309) (xy 383.981698 -248.46099)
			(xy 383.989593 -248.509567) (xy 383.990088 -248.534174) (xy 384.31903 -248.534174) (xy 384.32299 -248.48512)
			(xy 384.334767 -248.437336) (xy 384.354058 -248.39206) (xy 384.380361 -248.350464) (xy 384.412996 -248.313627)
			(xy 384.451117 -248.282502) (xy 384.493738 -248.257895) (xy 384.539754 -248.240443) (xy 384.587973 -248.230599)
			(xy 384.637148 -248.228618) (xy 384.686003 -248.23455) (xy 384.733274 -248.248242) (xy 384.777736 -248.26934)
			(xy 384.818239 -248.297296) (xy 384.853732 -248.331388) (xy 384.883297 -248.370732) (xy 384.906168 -248.414309)
			(xy 384.921752 -248.46099) (xy 384.929647 -248.509567) (xy 384.930142 -248.534174) (xy 385.259084 -248.534174)
			(xy 385.263044 -248.48512) (xy 385.274821 -248.437336) (xy 385.294112 -248.39206) (xy 385.320415 -248.350464)
			(xy 385.35305 -248.313627) (xy 385.391171 -248.282502) (xy 385.433792 -248.257895) (xy 385.479808 -248.240443)
			(xy 385.528027 -248.230599) (xy 385.577202 -248.228618) (xy 385.626057 -248.23455) (xy 385.673328 -248.248242)
			(xy 385.71779 -248.26934) (xy 385.758293 -248.297296) (xy 385.793786 -248.331388) (xy 385.823351 -248.370732)
			(xy 385.846222 -248.414309) (xy 385.861806 -248.46099) (xy 385.869701 -248.509567) (xy 385.870196 -248.534174)
			(xy 386.199138 -248.534174) (xy 386.203098 -248.48512) (xy 386.214875 -248.437336) (xy 386.234166 -248.39206)
			(xy 386.260469 -248.350464) (xy 386.293104 -248.313627) (xy 386.331225 -248.282502) (xy 386.373846 -248.257895)
			(xy 386.419862 -248.240443) (xy 386.468081 -248.230599) (xy 386.517256 -248.228618) (xy 386.566111 -248.23455)
			(xy 386.613382 -248.248242) (xy 386.657844 -248.26934) (xy 386.698347 -248.297296) (xy 386.73384 -248.331388)
			(xy 386.763405 -248.370732) (xy 386.786276 -248.414309) (xy 386.80186 -248.46099) (xy 386.809755 -248.509567)
			(xy 386.81025 -248.534174) (xy 386.809755 -248.558781) (xy 386.80186 -248.607358) (xy 386.786276 -248.654039)
			(xy 386.763405 -248.697616) (xy 386.73384 -248.73696) (xy 386.698347 -248.771052) (xy 386.657844 -248.799008)
			(xy 386.613382 -248.820106) (xy 386.566111 -248.833798) (xy 386.517256 -248.83973) (xy 386.468081 -248.837749)
			(xy 386.419862 -248.827905) (xy 386.373846 -248.810453) (xy 386.331225 -248.785846) (xy 386.293104 -248.754721)
			(xy 386.260469 -248.717884) (xy 386.234166 -248.676288) (xy 386.214875 -248.631012) (xy 386.203098 -248.583228)
			(xy 386.199138 -248.534174) (xy 385.870196 -248.534174) (xy 385.869701 -248.558781) (xy 385.861806 -248.607358)
			(xy 385.846222 -248.654039) (xy 385.823351 -248.697616) (xy 385.793786 -248.73696) (xy 385.758293 -248.771052)
			(xy 385.71779 -248.799008) (xy 385.673328 -248.820106) (xy 385.626057 -248.833798) (xy 385.577202 -248.83973)
			(xy 385.528027 -248.837749) (xy 385.479808 -248.827905) (xy 385.433792 -248.810453) (xy 385.391171 -248.785846)
			(xy 385.35305 -248.754721) (xy 385.320415 -248.717884) (xy 385.294112 -248.676288) (xy 385.274821 -248.631012)
			(xy 385.263044 -248.583228) (xy 385.259084 -248.534174) (xy 384.930142 -248.534174) (xy 384.929647 -248.558781)
			(xy 384.921752 -248.607358) (xy 384.906168 -248.654039) (xy 384.883297 -248.697616) (xy 384.853732 -248.73696)
			(xy 384.818239 -248.771052) (xy 384.777736 -248.799008) (xy 384.733274 -248.820106) (xy 384.686003 -248.833798)
			(xy 384.637148 -248.83973) (xy 384.587973 -248.837749) (xy 384.539754 -248.827905) (xy 384.493738 -248.810453)
			(xy 384.451117 -248.785846) (xy 384.412996 -248.754721) (xy 384.380361 -248.717884) (xy 384.354058 -248.676288)
			(xy 384.334767 -248.631012) (xy 384.32299 -248.583228) (xy 384.31903 -248.534174) (xy 383.990088 -248.534174)
			(xy 383.989593 -248.558781) (xy 383.981698 -248.607358) (xy 383.966114 -248.654039) (xy 383.943243 -248.697616)
			(xy 383.913678 -248.73696) (xy 383.878185 -248.771052) (xy 383.837682 -248.799008) (xy 383.79322 -248.820106)
			(xy 383.745949 -248.833798) (xy 383.697094 -248.83973) (xy 383.647919 -248.837749) (xy 383.5997 -248.827905)
			(xy 383.553684 -248.810453) (xy 383.511063 -248.785846) (xy 383.472942 -248.754721) (xy 383.440307 -248.717884)
			(xy 383.414004 -248.676288) (xy 383.394713 -248.631012) (xy 383.382936 -248.583228) (xy 383.378976 -248.534174)
			(xy 383.050034 -248.534174) (xy 383.049539 -248.558781) (xy 383.041644 -248.607358) (xy 383.02606 -248.654039)
			(xy 383.003189 -248.697616) (xy 382.973624 -248.73696) (xy 382.938131 -248.771052) (xy 382.897628 -248.799008)
			(xy 382.853166 -248.820106) (xy 382.805895 -248.833798) (xy 382.75704 -248.83973) (xy 382.707865 -248.837749)
			(xy 382.659646 -248.827905) (xy 382.61363 -248.810453) (xy 382.571009 -248.785846) (xy 382.532888 -248.754721)
			(xy 382.500253 -248.717884) (xy 382.47395 -248.676288) (xy 382.454659 -248.631012) (xy 382.442882 -248.583228)
			(xy 382.438922 -248.534174) (xy 382.110234 -248.534174) (xy 382.109739 -248.558781) (xy 382.101844 -248.607358)
			(xy 382.08626 -248.654039) (xy 382.063389 -248.697616) (xy 382.033824 -248.73696) (xy 381.998331 -248.771052)
			(xy 381.957828 -248.799008) (xy 381.913366 -248.820106) (xy 381.866095 -248.833798) (xy 381.81724 -248.83973)
			(xy 381.768065 -248.837749) (xy 381.719846 -248.827905) (xy 381.67383 -248.810453) (xy 381.631209 -248.785846)
			(xy 381.593088 -248.754721) (xy 381.560453 -248.717884) (xy 381.53415 -248.676288) (xy 381.514859 -248.631012)
			(xy 381.503082 -248.583228) (xy 381.499122 -248.534174) (xy 381.180594 -248.534174) (xy 381.180082 -248.55962)
			(xy 381.171918 -248.609854) (xy 381.155802 -248.658128) (xy 381.132151 -248.703191) (xy 381.101578 -248.743877)
			(xy 381.064874 -248.779132) (xy 381.02299 -248.808042) (xy 380.977011 -248.829859) (xy 380.928127 -248.844019)
			(xy 380.877606 -248.850153) (xy 380.826754 -248.848104) (xy 380.77689 -248.837924) (xy 380.729304 -248.819877)
			(xy 380.68523 -248.794431) (xy 380.645808 -248.762244) (xy 380.61206 -248.72415) (xy 380.584859 -248.681136)
			(xy 380.564911 -248.634316) (xy 380.552732 -248.584902) (xy 380.548637 -248.534174) (xy 380.230126 -248.534174)
			(xy 380.229631 -248.558781) (xy 380.221736 -248.607358) (xy 380.206152 -248.654039) (xy 380.183281 -248.697616)
			(xy 380.153716 -248.73696) (xy 380.118223 -248.771052) (xy 380.07772 -248.799008) (xy 380.033258 -248.820106)
			(xy 379.985987 -248.833798) (xy 379.937132 -248.83973) (xy 379.887957 -248.837749) (xy 379.839738 -248.827905)
			(xy 379.793722 -248.810453) (xy 379.751101 -248.785846) (xy 379.71298 -248.754721) (xy 379.680345 -248.717884)
			(xy 379.654042 -248.676288) (xy 379.634751 -248.631012) (xy 379.622974 -248.583228) (xy 379.619014 -248.534174)
			(xy 379.300486 -248.534174) (xy 379.299974 -248.55962) (xy 379.29181 -248.609854) (xy 379.275694 -248.658128)
			(xy 379.252043 -248.703191) (xy 379.22147 -248.743877) (xy 379.184766 -248.779132) (xy 379.142882 -248.808042)
			(xy 379.096903 -248.829859) (xy 379.048019 -248.844019) (xy 378.997498 -248.850153) (xy 378.946646 -248.848104)
			(xy 378.896782 -248.837924) (xy 378.849196 -248.819877) (xy 378.805122 -248.794431) (xy 378.7657 -248.762244)
			(xy 378.731952 -248.72415) (xy 378.704751 -248.681136) (xy 378.684803 -248.634316) (xy 378.672624 -248.584902)
			(xy 378.668529 -248.534174) (xy 378.350018 -248.534174) (xy 378.349523 -248.558781) (xy 378.341628 -248.607358)
			(xy 378.326044 -248.654039) (xy 378.303173 -248.697616) (xy 378.273608 -248.73696) (xy 378.238115 -248.771052)
			(xy 378.197612 -248.799008) (xy 378.15315 -248.820106) (xy 378.105879 -248.833798) (xy 378.057024 -248.83973)
			(xy 378.007849 -248.837749) (xy 377.95963 -248.827905) (xy 377.913614 -248.810453) (xy 377.870993 -248.785846)
			(xy 377.832872 -248.754721) (xy 377.800237 -248.717884) (xy 377.773934 -248.676288) (xy 377.754643 -248.631012)
			(xy 377.742866 -248.583228) (xy 377.738906 -248.534174) (xy 377.420632 -248.534174) (xy 377.42012 -248.55962)
			(xy 377.411956 -248.609854) (xy 377.39584 -248.658128) (xy 377.372189 -248.703191) (xy 377.341616 -248.743877)
			(xy 377.304912 -248.779132) (xy 377.263028 -248.808042) (xy 377.217049 -248.829859) (xy 377.168165 -248.844019)
			(xy 377.117644 -248.850153) (xy 377.066792 -248.848104) (xy 377.016928 -248.837924) (xy 376.969342 -248.819877)
			(xy 376.925268 -248.794431) (xy 376.885846 -248.762244) (xy 376.852098 -248.72415) (xy 376.824897 -248.681136)
			(xy 376.804949 -248.634316) (xy 376.79277 -248.584902) (xy 376.788675 -248.534174) (xy 376.480578 -248.534174)
			(xy 376.480066 -248.55962) (xy 376.471902 -248.609854) (xy 376.455786 -248.658128) (xy 376.432135 -248.703191)
			(xy 376.401562 -248.743877) (xy 376.364858 -248.779132) (xy 376.322974 -248.808042) (xy 376.276995 -248.829859)
			(xy 376.228111 -248.844019) (xy 376.17759 -248.850153) (xy 376.126738 -248.848104) (xy 376.076874 -248.837924)
			(xy 376.029288 -248.819877) (xy 375.985214 -248.794431) (xy 375.945792 -248.762244) (xy 375.912044 -248.72415)
			(xy 375.884843 -248.681136) (xy 375.864895 -248.634316) (xy 375.852716 -248.584902) (xy 375.848621 -248.534174)
			(xy 375.53011 -248.534174) (xy 375.52997 -248.546937) (xy 375.527804 -248.57237) (xy 375.525792 -248.584974)
			(xy 375.526046 -248.584974) (xy 375.52161 -248.608595) (xy 375.506301 -248.654151) (xy 375.484047 -248.696748)
			(xy 375.455399 -248.735335) (xy 375.421061 -248.768961) (xy 375.381883 -248.796795) (xy 375.338829 -248.818152)
			(xy 375.292962 -248.832503) (xy 375.269252 -248.836434) (xy 375.255028 -248.838212) (xy 375.224802 -248.839736)
			(xy 375.199922 -248.839247) (xy 375.150819 -248.831187) (xy 375.103671 -248.815278) (xy 375.059722 -248.791943)
			(xy 375.039636 -248.777252) (xy 375.028206 -248.768616) (xy 374.99925 -248.765822) (xy 374.907048 -248.811542)
			(xy 374.898806 -248.816122) (xy 374.8861 -248.830032) (xy 374.87927 -248.847589) (xy 374.878854 -248.857008)
			(xy 374.878854 -249.033792) (xy 374.879195 -249.042781) (xy 374.885398 -249.059653) (xy 374.897072 -249.073324)
			(xy 374.904762 -249.077988) (xy 374.926184 -249.090632) (xy 374.96498 -249.121762) (xy 374.998222 -249.158764)
			(xy 375.025034 -249.200661) (xy 375.044708 -249.246346) (xy 375.056725 -249.294613) (xy 375.060766 -249.34418)
			(xy 375.378467 -249.34418) (xy 375.382562 -249.293452) (xy 375.394741 -249.244038) (xy 375.414689 -249.197218)
			(xy 375.44189 -249.154204) (xy 375.475638 -249.11611) (xy 375.51506 -249.083923) (xy 375.559134 -249.058477)
			(xy 375.60672 -249.04043) (xy 375.656584 -249.03025) (xy 375.707436 -249.028201) (xy 375.757957 -249.034335)
			(xy 375.806841 -249.048495) (xy 375.85282 -249.070312) (xy 375.894704 -249.099222) (xy 375.931408 -249.134477)
			(xy 375.961981 -249.175163) (xy 375.985632 -249.220226) (xy 376.001748 -249.2685) (xy 376.009912 -249.318734)
			(xy 376.010424 -249.34418) (xy 376.328952 -249.34418) (xy 376.332912 -249.295126) (xy 376.344689 -249.247342)
			(xy 376.36398 -249.202066) (xy 376.390283 -249.16047) (xy 376.422918 -249.123633) (xy 376.461039 -249.092508)
			(xy 376.50366 -249.067901) (xy 376.549676 -249.050449) (xy 376.597895 -249.040605) (xy 376.64707 -249.038624)
			(xy 376.695925 -249.044556) (xy 376.743196 -249.058248) (xy 376.787658 -249.079346) (xy 376.828161 -249.107302)
			(xy 376.863654 -249.141394) (xy 376.893219 -249.180738) (xy 376.91609 -249.224315) (xy 376.931674 -249.270996)
			(xy 376.939569 -249.319573) (xy 376.940064 -249.34418) (xy 377.269006 -249.34418) (xy 377.272966 -249.295126)
			(xy 377.284743 -249.247342) (xy 377.304034 -249.202066) (xy 377.330337 -249.16047) (xy 377.362972 -249.123633)
			(xy 377.401093 -249.092508) (xy 377.443714 -249.067901) (xy 377.48973 -249.050449) (xy 377.537949 -249.040605)
			(xy 377.587124 -249.038624) (xy 377.635979 -249.044556) (xy 377.68325 -249.058248) (xy 377.727712 -249.079346)
			(xy 377.768215 -249.107302) (xy 377.803708 -249.141394) (xy 377.833273 -249.180738) (xy 377.856144 -249.224315)
			(xy 377.871728 -249.270996) (xy 377.879623 -249.319573) (xy 377.880118 -249.34418) (xy 379.138683 -249.34418)
			(xy 379.142778 -249.293452) (xy 379.154957 -249.244038) (xy 379.174905 -249.197218) (xy 379.202106 -249.154204)
			(xy 379.235854 -249.11611) (xy 379.275276 -249.083923) (xy 379.31935 -249.058477) (xy 379.366936 -249.04043)
			(xy 379.4168 -249.03025) (xy 379.467652 -249.028201) (xy 379.518173 -249.034335) (xy 379.567057 -249.048495)
			(xy 379.613036 -249.070312) (xy 379.65492 -249.099222) (xy 379.691624 -249.134477) (xy 379.722197 -249.175163)
			(xy 379.745848 -249.220226) (xy 379.761964 -249.2685) (xy 379.770128 -249.318734) (xy 379.77064 -249.34418)
			(xy 380.088914 -249.34418) (xy 380.092874 -249.295126) (xy 380.104651 -249.247342) (xy 380.123942 -249.202066)
			(xy 380.150245 -249.16047) (xy 380.18288 -249.123633) (xy 380.221001 -249.092508) (xy 380.263622 -249.067901)
			(xy 380.309638 -249.050449) (xy 380.357857 -249.040605) (xy 380.407032 -249.038624) (xy 380.455887 -249.044556)
			(xy 380.503158 -249.058248) (xy 380.54762 -249.079346) (xy 380.588123 -249.107302) (xy 380.623616 -249.141394)
			(xy 380.653181 -249.180738) (xy 380.676052 -249.224315) (xy 380.691636 -249.270996) (xy 380.699531 -249.319573)
			(xy 380.700026 -249.34418) (xy 381.028968 -249.34418) (xy 381.032928 -249.295126) (xy 381.044705 -249.247342)
			(xy 381.063996 -249.202066) (xy 381.090299 -249.16047) (xy 381.122934 -249.123633) (xy 381.161055 -249.092508)
			(xy 381.203676 -249.067901) (xy 381.249692 -249.050449) (xy 381.297911 -249.040605) (xy 381.347086 -249.038624)
			(xy 381.395941 -249.044556) (xy 381.443212 -249.058248) (xy 381.487674 -249.079346) (xy 381.528177 -249.107302)
			(xy 381.56367 -249.141394) (xy 381.593235 -249.180738) (xy 381.616106 -249.224315) (xy 381.63169 -249.270996)
			(xy 381.639585 -249.319573) (xy 381.64008 -249.34418) (xy 381.969022 -249.34418) (xy 381.972982 -249.295126)
			(xy 381.984759 -249.247342) (xy 382.00405 -249.202066) (xy 382.030353 -249.16047) (xy 382.062988 -249.123633)
			(xy 382.101109 -249.092508) (xy 382.14373 -249.067901) (xy 382.189746 -249.050449) (xy 382.237965 -249.040605)
			(xy 382.28714 -249.038624) (xy 382.335995 -249.044556) (xy 382.383266 -249.058248) (xy 382.427728 -249.079346)
			(xy 382.468231 -249.107302) (xy 382.503724 -249.141394) (xy 382.533289 -249.180738) (xy 382.55616 -249.224315)
			(xy 382.571744 -249.270996) (xy 382.579639 -249.319573) (xy 382.580134 -249.34418) (xy 382.909076 -249.34418)
			(xy 382.913036 -249.295126) (xy 382.924813 -249.247342) (xy 382.944104 -249.202066) (xy 382.970407 -249.16047)
			(xy 383.003042 -249.123633) (xy 383.041163 -249.092508) (xy 383.083784 -249.067901) (xy 383.1298 -249.050449)
			(xy 383.178019 -249.040605) (xy 383.227194 -249.038624) (xy 383.276049 -249.044556) (xy 383.32332 -249.058248)
			(xy 383.367782 -249.079346) (xy 383.408285 -249.107302) (xy 383.443778 -249.141394) (xy 383.473343 -249.180738)
			(xy 383.496214 -249.224315) (xy 383.511798 -249.270996) (xy 383.519693 -249.319573) (xy 383.520188 -249.34418)
			(xy 383.84913 -249.34418) (xy 383.85309 -249.295126) (xy 383.864867 -249.247342) (xy 383.884158 -249.202066)
			(xy 383.910461 -249.16047) (xy 383.943096 -249.123633) (xy 383.981217 -249.092508) (xy 384.023838 -249.067901)
			(xy 384.069854 -249.050449) (xy 384.118073 -249.040605) (xy 384.167248 -249.038624) (xy 384.216103 -249.044556)
			(xy 384.263374 -249.058248) (xy 384.307836 -249.079346) (xy 384.348339 -249.107302) (xy 384.383832 -249.141394)
			(xy 384.413397 -249.180738) (xy 384.436268 -249.224315) (xy 384.451852 -249.270996) (xy 384.459747 -249.319573)
			(xy 384.460242 -249.34418) (xy 385.728984 -249.34418) (xy 385.732944 -249.295126) (xy 385.744721 -249.247342)
			(xy 385.764012 -249.202066) (xy 385.790315 -249.16047) (xy 385.82295 -249.123633) (xy 385.861071 -249.092508)
			(xy 385.903692 -249.067901) (xy 385.949708 -249.050449) (xy 385.997927 -249.040605) (xy 386.047102 -249.038624)
			(xy 386.095957 -249.044556) (xy 386.143228 -249.058248) (xy 386.18769 -249.079346) (xy 386.228193 -249.107302)
			(xy 386.263686 -249.141394) (xy 386.293251 -249.180738) (xy 386.316122 -249.224315) (xy 386.331706 -249.270996)
			(xy 386.339601 -249.319573) (xy 386.340096 -249.34418) (xy 386.669038 -249.34418) (xy 386.672998 -249.295126)
			(xy 386.684775 -249.247342) (xy 386.704066 -249.202066) (xy 386.730369 -249.16047) (xy 386.763004 -249.123633)
			(xy 386.801125 -249.092508) (xy 386.843746 -249.067901) (xy 386.889762 -249.050449) (xy 386.937981 -249.040605)
			(xy 386.987156 -249.038624) (xy 387.036011 -249.044556) (xy 387.083282 -249.058248) (xy 387.127744 -249.079346)
			(xy 387.168247 -249.107302) (xy 387.20374 -249.141394) (xy 387.233305 -249.180738) (xy 387.256176 -249.224315)
			(xy 387.27176 -249.270996) (xy 387.279655 -249.319573) (xy 387.28015 -249.34418) (xy 387.279655 -249.368787)
			(xy 387.27176 -249.417364) (xy 387.256176 -249.464045) (xy 387.233305 -249.507622) (xy 387.20374 -249.546966)
			(xy 387.168247 -249.581058) (xy 387.127744 -249.609014) (xy 387.083282 -249.630112) (xy 387.036011 -249.643804)
			(xy 386.987156 -249.649736) (xy 386.937981 -249.647755) (xy 386.889762 -249.637911) (xy 386.843746 -249.620459)
			(xy 386.801125 -249.595852) (xy 386.763004 -249.564727) (xy 386.730369 -249.52789) (xy 386.704066 -249.486294)
			(xy 386.684775 -249.441018) (xy 386.672998 -249.393234) (xy 386.669038 -249.34418) (xy 386.340096 -249.34418)
			(xy 386.339601 -249.368787) (xy 386.331706 -249.417364) (xy 386.316122 -249.464045) (xy 386.293251 -249.507622)
			(xy 386.263686 -249.546966) (xy 386.228193 -249.581058) (xy 386.18769 -249.609014) (xy 386.143228 -249.630112)
			(xy 386.095957 -249.643804) (xy 386.047102 -249.649736) (xy 385.997927 -249.647755) (xy 385.949708 -249.637911)
			(xy 385.903692 -249.620459) (xy 385.861071 -249.595852) (xy 385.82295 -249.564727) (xy 385.790315 -249.52789)
			(xy 385.764012 -249.486294) (xy 385.744721 -249.441018) (xy 385.732944 -249.393234) (xy 385.728984 -249.34418)
			(xy 384.460242 -249.34418) (xy 384.459747 -249.368787) (xy 384.451852 -249.417364) (xy 384.436268 -249.464045)
			(xy 384.413397 -249.507622) (xy 384.383832 -249.546966) (xy 384.348339 -249.581058) (xy 384.307836 -249.609014)
			(xy 384.263374 -249.630112) (xy 384.216103 -249.643804) (xy 384.167248 -249.649736) (xy 384.118073 -249.647755)
			(xy 384.069854 -249.637911) (xy 384.023838 -249.620459) (xy 383.981217 -249.595852) (xy 383.943096 -249.564727)
			(xy 383.910461 -249.52789) (xy 383.884158 -249.486294) (xy 383.864867 -249.441018) (xy 383.85309 -249.393234)
			(xy 383.84913 -249.34418) (xy 383.520188 -249.34418) (xy 383.519693 -249.368787) (xy 383.511798 -249.417364)
			(xy 383.496214 -249.464045) (xy 383.473343 -249.507622) (xy 383.443778 -249.546966) (xy 383.408285 -249.581058)
			(xy 383.367782 -249.609014) (xy 383.32332 -249.630112) (xy 383.276049 -249.643804) (xy 383.227194 -249.649736)
			(xy 383.178019 -249.647755) (xy 383.1298 -249.637911) (xy 383.083784 -249.620459) (xy 383.041163 -249.595852)
			(xy 383.003042 -249.564727) (xy 382.970407 -249.52789) (xy 382.944104 -249.486294) (xy 382.924813 -249.441018)
			(xy 382.913036 -249.393234) (xy 382.909076 -249.34418) (xy 382.580134 -249.34418) (xy 382.579639 -249.368787)
			(xy 382.571744 -249.417364) (xy 382.55616 -249.464045) (xy 382.533289 -249.507622) (xy 382.503724 -249.546966)
			(xy 382.468231 -249.581058) (xy 382.427728 -249.609014) (xy 382.383266 -249.630112) (xy 382.335995 -249.643804)
			(xy 382.28714 -249.649736) (xy 382.237965 -249.647755) (xy 382.189746 -249.637911) (xy 382.14373 -249.620459)
			(xy 382.101109 -249.595852) (xy 382.062988 -249.564727) (xy 382.030353 -249.52789) (xy 382.00405 -249.486294)
			(xy 381.984759 -249.441018) (xy 381.972982 -249.393234) (xy 381.969022 -249.34418) (xy 381.64008 -249.34418)
			(xy 381.639585 -249.368787) (xy 381.63169 -249.417364) (xy 381.616106 -249.464045) (xy 381.593235 -249.507622)
			(xy 381.56367 -249.546966) (xy 381.528177 -249.581058) (xy 381.487674 -249.609014) (xy 381.443212 -249.630112)
			(xy 381.395941 -249.643804) (xy 381.347086 -249.649736) (xy 381.297911 -249.647755) (xy 381.249692 -249.637911)
			(xy 381.203676 -249.620459) (xy 381.161055 -249.595852) (xy 381.122934 -249.564727) (xy 381.090299 -249.52789)
			(xy 381.063996 -249.486294) (xy 381.044705 -249.441018) (xy 381.032928 -249.393234) (xy 381.028968 -249.34418)
			(xy 380.700026 -249.34418) (xy 380.699531 -249.368787) (xy 380.691636 -249.417364) (xy 380.676052 -249.464045)
			(xy 380.653181 -249.507622) (xy 380.623616 -249.546966) (xy 380.588123 -249.581058) (xy 380.54762 -249.609014)
			(xy 380.503158 -249.630112) (xy 380.455887 -249.643804) (xy 380.407032 -249.649736) (xy 380.357857 -249.647755)
			(xy 380.309638 -249.637911) (xy 380.263622 -249.620459) (xy 380.221001 -249.595852) (xy 380.18288 -249.564727)
			(xy 380.150245 -249.52789) (xy 380.123942 -249.486294) (xy 380.104651 -249.441018) (xy 380.092874 -249.393234)
			(xy 380.088914 -249.34418) (xy 379.77064 -249.34418) (xy 379.770128 -249.369626) (xy 379.761964 -249.41986)
			(xy 379.745848 -249.468134) (xy 379.722197 -249.513197) (xy 379.691624 -249.553883) (xy 379.65492 -249.589138)
			(xy 379.613036 -249.618048) (xy 379.567057 -249.639865) (xy 379.518173 -249.654025) (xy 379.467652 -249.660159)
			(xy 379.4168 -249.65811) (xy 379.366936 -249.64793) (xy 379.31935 -249.629883) (xy 379.275276 -249.604437)
			(xy 379.235854 -249.57225) (xy 379.202106 -249.534156) (xy 379.174905 -249.491142) (xy 379.154957 -249.444322)
			(xy 379.142778 -249.394908) (xy 379.138683 -249.34418) (xy 377.880118 -249.34418) (xy 377.879623 -249.368787)
			(xy 377.871728 -249.417364) (xy 377.856144 -249.464045) (xy 377.833273 -249.507622) (xy 377.803708 -249.546966)
			(xy 377.768215 -249.581058) (xy 377.727712 -249.609014) (xy 377.68325 -249.630112) (xy 377.635979 -249.643804)
			(xy 377.587124 -249.649736) (xy 377.537949 -249.647755) (xy 377.48973 -249.637911) (xy 377.443714 -249.620459)
			(xy 377.401093 -249.595852) (xy 377.362972 -249.564727) (xy 377.330337 -249.52789) (xy 377.304034 -249.486294)
			(xy 377.284743 -249.441018) (xy 377.272966 -249.393234) (xy 377.269006 -249.34418) (xy 376.940064 -249.34418)
			(xy 376.939569 -249.368787) (xy 376.931674 -249.417364) (xy 376.91609 -249.464045) (xy 376.893219 -249.507622)
			(xy 376.863654 -249.546966) (xy 376.828161 -249.581058) (xy 376.787658 -249.609014) (xy 376.743196 -249.630112)
			(xy 376.695925 -249.643804) (xy 376.64707 -249.649736) (xy 376.597895 -249.647755) (xy 376.549676 -249.637911)
			(xy 376.50366 -249.620459) (xy 376.461039 -249.595852) (xy 376.422918 -249.564727) (xy 376.390283 -249.52789)
			(xy 376.36398 -249.486294) (xy 376.344689 -249.441018) (xy 376.332912 -249.393234) (xy 376.328952 -249.34418)
			(xy 376.010424 -249.34418) (xy 376.009912 -249.369626) (xy 376.001748 -249.41986) (xy 375.985632 -249.468134)
			(xy 375.961981 -249.513197) (xy 375.931408 -249.553883) (xy 375.894704 -249.589138) (xy 375.85282 -249.618048)
			(xy 375.806841 -249.639865) (xy 375.757957 -249.654025) (xy 375.707436 -249.660159) (xy 375.656584 -249.65811)
			(xy 375.60672 -249.64793) (xy 375.559134 -249.629883) (xy 375.51506 -249.604437) (xy 375.475638 -249.57225)
			(xy 375.44189 -249.534156) (xy 375.414689 -249.491142) (xy 375.394741 -249.444322) (xy 375.382562 -249.394908)
			(xy 375.378467 -249.34418) (xy 375.060766 -249.34418) (xy 375.060767 -249.34419) (xy 375.056728 -249.393767)
			(xy 375.044714 -249.442036) (xy 375.025043 -249.487722) (xy 374.998234 -249.52962) (xy 374.964994 -249.566624)
			(xy 374.926201 -249.597757) (xy 374.904762 -249.610372) (xy 374.89712 -249.615094) (xy 374.885481 -249.628761)
			(xy 374.879241 -249.645594) (xy 374.878854 -249.654568) (xy 374.878854 -249.892566) (xy 374.87832 -249.902405)
			(xy 374.87074 -249.920572) (xy 374.864122 -249.927872) (xy 374.637808 -250.154186) (xy 375.848621 -250.154186)
			(xy 375.852716 -250.103458) (xy 375.864895 -250.054044) (xy 375.884843 -250.007224) (xy 375.912044 -249.96421)
			(xy 375.945792 -249.926116) (xy 375.985214 -249.893929) (xy 376.029288 -249.868483) (xy 376.076874 -249.850436)
			(xy 376.126738 -249.840256) (xy 376.17759 -249.838207) (xy 376.228111 -249.844341) (xy 376.276995 -249.858501)
			(xy 376.322974 -249.880318) (xy 376.364858 -249.909228) (xy 376.401562 -249.944483) (xy 376.432135 -249.985169)
			(xy 376.455786 -250.030232) (xy 376.471902 -250.078506) (xy 376.480066 -250.12874) (xy 376.480578 -250.154186)
			(xy 376.799106 -250.154186) (xy 376.803066 -250.105132) (xy 376.814843 -250.057348) (xy 376.834134 -250.012072)
			(xy 376.860437 -249.970476) (xy 376.893072 -249.933639) (xy 376.931193 -249.902514) (xy 376.973814 -249.877907)
			(xy 377.01983 -249.860455) (xy 377.068049 -249.850611) (xy 377.117224 -249.84863) (xy 377.166079 -249.854562)
			(xy 377.21335 -249.868254) (xy 377.257812 -249.889352) (xy 377.298315 -249.917308) (xy 377.333808 -249.9514)
			(xy 377.363373 -249.990744) (xy 377.386244 -250.034321) (xy 377.401828 -250.081002) (xy 377.409723 -250.129579)
			(xy 377.410218 -250.154186) (xy 377.738906 -250.154186) (xy 377.742866 -250.105132) (xy 377.754643 -250.057348)
			(xy 377.773934 -250.012072) (xy 377.800237 -249.970476) (xy 377.832872 -249.933639) (xy 377.870993 -249.902514)
			(xy 377.913614 -249.877907) (xy 377.95963 -249.860455) (xy 378.007849 -249.850611) (xy 378.057024 -249.84863)
			(xy 378.105879 -249.854562) (xy 378.15315 -249.868254) (xy 378.197612 -249.889352) (xy 378.238115 -249.917308)
			(xy 378.273608 -249.9514) (xy 378.303173 -249.990744) (xy 378.326044 -250.034321) (xy 378.341628 -250.081002)
			(xy 378.349523 -250.129579) (xy 378.350018 -250.154186) (xy 378.668529 -250.154186) (xy 378.672624 -250.103458)
			(xy 378.684803 -250.054044) (xy 378.704751 -250.007224) (xy 378.731952 -249.96421) (xy 378.7657 -249.926116)
			(xy 378.805122 -249.893929) (xy 378.849196 -249.868483) (xy 378.896782 -249.850436) (xy 378.946646 -249.840256)
			(xy 378.997498 -249.838207) (xy 379.048019 -249.844341) (xy 379.096903 -249.858501) (xy 379.142882 -249.880318)
			(xy 379.184766 -249.909228) (xy 379.22147 -249.944483) (xy 379.252043 -249.985169) (xy 379.275694 -250.030232)
			(xy 379.29181 -250.078506) (xy 379.299974 -250.12874) (xy 379.300486 -250.154186) (xy 379.619014 -250.154186)
			(xy 379.622974 -250.105132) (xy 379.634751 -250.057348) (xy 379.654042 -250.012072) (xy 379.680345 -249.970476)
			(xy 379.71298 -249.933639) (xy 379.751101 -249.902514) (xy 379.793722 -249.877907) (xy 379.839738 -249.860455)
			(xy 379.887957 -249.850611) (xy 379.937132 -249.84863) (xy 379.985987 -249.854562) (xy 380.033258 -249.868254)
			(xy 380.07772 -249.889352) (xy 380.118223 -249.917308) (xy 380.153716 -249.9514) (xy 380.183281 -249.990744)
			(xy 380.206152 -250.034321) (xy 380.221736 -250.081002) (xy 380.229631 -250.129579) (xy 380.230126 -250.154186)
			(xy 380.559068 -250.154186) (xy 380.563028 -250.105132) (xy 380.574805 -250.057348) (xy 380.594096 -250.012072)
			(xy 380.620399 -249.970476) (xy 380.653034 -249.933639) (xy 380.691155 -249.902514) (xy 380.733776 -249.877907)
			(xy 380.779792 -249.860455) (xy 380.828011 -249.850611) (xy 380.877186 -249.84863) (xy 380.926041 -249.854562)
			(xy 380.973312 -249.868254) (xy 381.017774 -249.889352) (xy 381.058277 -249.917308) (xy 381.09377 -249.9514)
			(xy 381.123335 -249.990744) (xy 381.146206 -250.034321) (xy 381.16179 -250.081002) (xy 381.169685 -250.129579)
			(xy 381.17018 -250.154186) (xy 381.499122 -250.154186) (xy 381.503082 -250.105132) (xy 381.514859 -250.057348)
			(xy 381.53415 -250.012072) (xy 381.560453 -249.970476) (xy 381.593088 -249.933639) (xy 381.631209 -249.902514)
			(xy 381.67383 -249.877907) (xy 381.719846 -249.860455) (xy 381.768065 -249.850611) (xy 381.81724 -249.84863)
			(xy 381.866095 -249.854562) (xy 381.913366 -249.868254) (xy 381.957828 -249.889352) (xy 381.998331 -249.917308)
			(xy 382.033824 -249.9514) (xy 382.063389 -249.990744) (xy 382.08626 -250.034321) (xy 382.101844 -250.081002)
			(xy 382.109739 -250.129579) (xy 382.110234 -250.154186) (xy 382.438922 -250.154186) (xy 382.442882 -250.105132)
			(xy 382.454659 -250.057348) (xy 382.47395 -250.012072) (xy 382.500253 -249.970476) (xy 382.532888 -249.933639)
			(xy 382.571009 -249.902514) (xy 382.61363 -249.877907) (xy 382.659646 -249.860455) (xy 382.707865 -249.850611)
			(xy 382.75704 -249.84863) (xy 382.805895 -249.854562) (xy 382.853166 -249.868254) (xy 382.897628 -249.889352)
			(xy 382.938131 -249.917308) (xy 382.973624 -249.9514) (xy 383.003189 -249.990744) (xy 383.02606 -250.034321)
			(xy 383.041644 -250.081002) (xy 383.049539 -250.129579) (xy 383.050034 -250.154186) (xy 383.378976 -250.154186)
			(xy 383.382936 -250.105132) (xy 383.394713 -250.057348) (xy 383.414004 -250.012072) (xy 383.440307 -249.970476)
			(xy 383.472942 -249.933639) (xy 383.511063 -249.902514) (xy 383.553684 -249.877907) (xy 383.5997 -249.860455)
			(xy 383.647919 -249.850611) (xy 383.697094 -249.84863) (xy 383.745949 -249.854562) (xy 383.79322 -249.868254)
			(xy 383.837682 -249.889352) (xy 383.878185 -249.917308) (xy 383.913678 -249.9514) (xy 383.943243 -249.990744)
			(xy 383.966114 -250.034321) (xy 383.981698 -250.081002) (xy 383.989593 -250.129579) (xy 383.990088 -250.154186)
			(xy 384.31903 -250.154186) (xy 384.32299 -250.105132) (xy 384.334767 -250.057348) (xy 384.354058 -250.012072)
			(xy 384.380361 -249.970476) (xy 384.412996 -249.933639) (xy 384.451117 -249.902514) (xy 384.493738 -249.877907)
			(xy 384.539754 -249.860455) (xy 384.587973 -249.850611) (xy 384.637148 -249.84863) (xy 384.686003 -249.854562)
			(xy 384.733274 -249.868254) (xy 384.777736 -249.889352) (xy 384.818239 -249.917308) (xy 384.853732 -249.9514)
			(xy 384.883297 -249.990744) (xy 384.906168 -250.034321) (xy 384.921752 -250.081002) (xy 384.929647 -250.129579)
			(xy 384.930142 -250.154186) (xy 385.259084 -250.154186) (xy 385.263044 -250.105132) (xy 385.274821 -250.057348)
			(xy 385.294112 -250.012072) (xy 385.320415 -249.970476) (xy 385.35305 -249.933639) (xy 385.391171 -249.902514)
			(xy 385.433792 -249.877907) (xy 385.479808 -249.860455) (xy 385.528027 -249.850611) (xy 385.577202 -249.84863)
			(xy 385.626057 -249.854562) (xy 385.673328 -249.868254) (xy 385.71779 -249.889352) (xy 385.758293 -249.917308)
			(xy 385.793786 -249.9514) (xy 385.823351 -249.990744) (xy 385.846222 -250.034321) (xy 385.861806 -250.081002)
			(xy 385.869701 -250.129579) (xy 385.870196 -250.154186) (xy 386.199138 -250.154186) (xy 386.203098 -250.105132)
			(xy 386.214875 -250.057348) (xy 386.234166 -250.012072) (xy 386.260469 -249.970476) (xy 386.293104 -249.933639)
			(xy 386.331225 -249.902514) (xy 386.373846 -249.877907) (xy 386.419862 -249.860455) (xy 386.468081 -249.850611)
			(xy 386.517256 -249.84863) (xy 386.566111 -249.854562) (xy 386.613382 -249.868254) (xy 386.657844 -249.889352)
			(xy 386.698347 -249.917308) (xy 386.73384 -249.9514) (xy 386.763405 -249.990744) (xy 386.786276 -250.034321)
			(xy 386.80186 -250.081002) (xy 386.809755 -250.129579) (xy 386.81025 -250.154186) (xy 386.809755 -250.178793)
			(xy 386.80186 -250.22737) (xy 386.786276 -250.274051) (xy 386.763405 -250.317628) (xy 386.73384 -250.356972)
			(xy 386.698347 -250.391064) (xy 386.657844 -250.41902) (xy 386.613382 -250.440118) (xy 386.566111 -250.45381)
			(xy 386.517256 -250.459742) (xy 386.468081 -250.457761) (xy 386.419862 -250.447917) (xy 386.373846 -250.430465)
			(xy 386.331225 -250.405858) (xy 386.293104 -250.374733) (xy 386.260469 -250.337896) (xy 386.234166 -250.2963)
			(xy 386.214875 -250.251024) (xy 386.203098 -250.20324) (xy 386.199138 -250.154186) (xy 385.870196 -250.154186)
			(xy 385.869701 -250.178793) (xy 385.861806 -250.22737) (xy 385.846222 -250.274051) (xy 385.823351 -250.317628)
			(xy 385.793786 -250.356972) (xy 385.758293 -250.391064) (xy 385.71779 -250.41902) (xy 385.673328 -250.440118)
			(xy 385.626057 -250.45381) (xy 385.577202 -250.459742) (xy 385.528027 -250.457761) (xy 385.479808 -250.447917)
			(xy 385.433792 -250.430465) (xy 385.391171 -250.405858) (xy 385.35305 -250.374733) (xy 385.320415 -250.337896)
			(xy 385.294112 -250.2963) (xy 385.274821 -250.251024) (xy 385.263044 -250.20324) (xy 385.259084 -250.154186)
			(xy 384.930142 -250.154186) (xy 384.929647 -250.178793) (xy 384.921752 -250.22737) (xy 384.906168 -250.274051)
			(xy 384.883297 -250.317628) (xy 384.853732 -250.356972) (xy 384.818239 -250.391064) (xy 384.777736 -250.41902)
			(xy 384.733274 -250.440118) (xy 384.686003 -250.45381) (xy 384.637148 -250.459742) (xy 384.587973 -250.457761)
			(xy 384.539754 -250.447917) (xy 384.493738 -250.430465) (xy 384.451117 -250.405858) (xy 384.412996 -250.374733)
			(xy 384.380361 -250.337896) (xy 384.354058 -250.2963) (xy 384.334767 -250.251024) (xy 384.32299 -250.20324)
			(xy 384.31903 -250.154186) (xy 383.990088 -250.154186) (xy 383.989593 -250.178793) (xy 383.981698 -250.22737)
			(xy 383.966114 -250.274051) (xy 383.943243 -250.317628) (xy 383.913678 -250.356972) (xy 383.878185 -250.391064)
			(xy 383.837682 -250.41902) (xy 383.79322 -250.440118) (xy 383.745949 -250.45381) (xy 383.697094 -250.459742)
			(xy 383.647919 -250.457761) (xy 383.5997 -250.447917) (xy 383.553684 -250.430465) (xy 383.511063 -250.405858)
			(xy 383.472942 -250.374733) (xy 383.440307 -250.337896) (xy 383.414004 -250.2963) (xy 383.394713 -250.251024)
			(xy 383.382936 -250.20324) (xy 383.378976 -250.154186) (xy 383.050034 -250.154186) (xy 383.049539 -250.178793)
			(xy 383.041644 -250.22737) (xy 383.02606 -250.274051) (xy 383.003189 -250.317628) (xy 382.973624 -250.356972)
			(xy 382.938131 -250.391064) (xy 382.897628 -250.41902) (xy 382.853166 -250.440118) (xy 382.805895 -250.45381)
			(xy 382.75704 -250.459742) (xy 382.707865 -250.457761) (xy 382.659646 -250.447917) (xy 382.61363 -250.430465)
			(xy 382.571009 -250.405858) (xy 382.532888 -250.374733) (xy 382.500253 -250.337896) (xy 382.47395 -250.2963)
			(xy 382.454659 -250.251024) (xy 382.442882 -250.20324) (xy 382.438922 -250.154186) (xy 382.110234 -250.154186)
			(xy 382.109739 -250.178793) (xy 382.101844 -250.22737) (xy 382.08626 -250.274051) (xy 382.063389 -250.317628)
			(xy 382.033824 -250.356972) (xy 381.998331 -250.391064) (xy 381.957828 -250.41902) (xy 381.913366 -250.440118)
			(xy 381.866095 -250.45381) (xy 381.81724 -250.459742) (xy 381.768065 -250.457761) (xy 381.719846 -250.447917)
			(xy 381.67383 -250.430465) (xy 381.631209 -250.405858) (xy 381.593088 -250.374733) (xy 381.560453 -250.337896)
			(xy 381.53415 -250.2963) (xy 381.514859 -250.251024) (xy 381.503082 -250.20324) (xy 381.499122 -250.154186)
			(xy 381.17018 -250.154186) (xy 381.169685 -250.178793) (xy 381.16179 -250.22737) (xy 381.146206 -250.274051)
			(xy 381.123335 -250.317628) (xy 381.09377 -250.356972) (xy 381.058277 -250.391064) (xy 381.017774 -250.41902)
			(xy 380.973312 -250.440118) (xy 380.926041 -250.45381) (xy 380.877186 -250.459742) (xy 380.828011 -250.457761)
			(xy 380.779792 -250.447917) (xy 380.733776 -250.430465) (xy 380.691155 -250.405858) (xy 380.653034 -250.374733)
			(xy 380.620399 -250.337896) (xy 380.594096 -250.2963) (xy 380.574805 -250.251024) (xy 380.563028 -250.20324)
			(xy 380.559068 -250.154186) (xy 380.230126 -250.154186) (xy 380.229631 -250.178793) (xy 380.221736 -250.22737)
			(xy 380.206152 -250.274051) (xy 380.183281 -250.317628) (xy 380.153716 -250.356972) (xy 380.118223 -250.391064)
			(xy 380.07772 -250.41902) (xy 380.033258 -250.440118) (xy 379.985987 -250.45381) (xy 379.937132 -250.459742)
			(xy 379.887957 -250.457761) (xy 379.839738 -250.447917) (xy 379.793722 -250.430465) (xy 379.751101 -250.405858)
			(xy 379.71298 -250.374733) (xy 379.680345 -250.337896) (xy 379.654042 -250.2963) (xy 379.634751 -250.251024)
			(xy 379.622974 -250.20324) (xy 379.619014 -250.154186) (xy 379.300486 -250.154186) (xy 379.299974 -250.179632)
			(xy 379.29181 -250.229866) (xy 379.275694 -250.27814) (xy 379.252043 -250.323203) (xy 379.22147 -250.363889)
			(xy 379.184766 -250.399144) (xy 379.142882 -250.428054) (xy 379.096903 -250.449871) (xy 379.048019 -250.464031)
			(xy 378.997498 -250.470165) (xy 378.946646 -250.468116) (xy 378.896782 -250.457936) (xy 378.849196 -250.439889)
			(xy 378.805122 -250.414443) (xy 378.7657 -250.382256) (xy 378.731952 -250.344162) (xy 378.704751 -250.301148)
			(xy 378.684803 -250.254328) (xy 378.672624 -250.204914) (xy 378.668529 -250.154186) (xy 378.350018 -250.154186)
			(xy 378.349523 -250.178793) (xy 378.341628 -250.22737) (xy 378.326044 -250.274051) (xy 378.303173 -250.317628)
			(xy 378.273608 -250.356972) (xy 378.238115 -250.391064) (xy 378.197612 -250.41902) (xy 378.15315 -250.440118)
			(xy 378.105879 -250.45381) (xy 378.057024 -250.459742) (xy 378.007849 -250.457761) (xy 377.95963 -250.447917)
			(xy 377.913614 -250.430465) (xy 377.870993 -250.405858) (xy 377.832872 -250.374733) (xy 377.800237 -250.337896)
			(xy 377.773934 -250.2963) (xy 377.754643 -250.251024) (xy 377.742866 -250.20324) (xy 377.738906 -250.154186)
			(xy 377.410218 -250.154186) (xy 377.409723 -250.178793) (xy 377.401828 -250.22737) (xy 377.386244 -250.274051)
			(xy 377.363373 -250.317628) (xy 377.333808 -250.356972) (xy 377.298315 -250.391064) (xy 377.257812 -250.41902)
			(xy 377.21335 -250.440118) (xy 377.166079 -250.45381) (xy 377.117224 -250.459742) (xy 377.068049 -250.457761)
			(xy 377.01983 -250.447917) (xy 376.973814 -250.430465) (xy 376.931193 -250.405858) (xy 376.893072 -250.374733)
			(xy 376.860437 -250.337896) (xy 376.834134 -250.2963) (xy 376.814843 -250.251024) (xy 376.803066 -250.20324)
			(xy 376.799106 -250.154186) (xy 376.480578 -250.154186) (xy 376.480066 -250.179632) (xy 376.471902 -250.229866)
			(xy 376.455786 -250.27814) (xy 376.432135 -250.323203) (xy 376.401562 -250.363889) (xy 376.364858 -250.399144)
			(xy 376.322974 -250.428054) (xy 376.276995 -250.449871) (xy 376.228111 -250.464031) (xy 376.17759 -250.470165)
			(xy 376.126738 -250.468116) (xy 376.076874 -250.457936) (xy 376.029288 -250.439889) (xy 375.985214 -250.414443)
			(xy 375.945792 -250.382256) (xy 375.912044 -250.344162) (xy 375.884843 -250.301148) (xy 375.864895 -250.254328)
			(xy 375.852716 -250.204914) (xy 375.848621 -250.154186) (xy 374.637808 -250.154186) (xy 374.591326 -250.200668)
			(xy 374.584468 -250.213114) (xy 374.582944 -250.220226) (xy 374.577119 -250.244312) (xy 374.55874 -250.290329)
			(xy 374.533174 -250.332776) (xy 374.501093 -250.37054) (xy 374.463336 -250.402631) (xy 374.420895 -250.428207)
			(xy 374.374883 -250.446597) (xy 374.350788 -250.452382) (xy 374.343676 -250.453906) (xy 374.33123 -250.460764)
			(xy 374.207786 -250.584208) (xy 374.200548 -250.590921) (xy 374.182343 -250.598515) (xy 374.17248 -250.59894)
			(xy 373.748046 -250.59894) (xy 373.738206 -250.599471) (xy 373.720035 -250.607048) (xy 373.71274 -250.613672)
			(xy 373.36222 -250.964192) (xy 374.449098 -250.964192) (xy 374.453058 -250.915138) (xy 374.464835 -250.867354)
			(xy 374.484126 -250.822078) (xy 374.510429 -250.780482) (xy 374.543064 -250.743645) (xy 374.581185 -250.71252)
			(xy 374.623806 -250.687913) (xy 374.669822 -250.670461) (xy 374.718041 -250.660617) (xy 374.767216 -250.658636)
			(xy 374.816071 -250.664568) (xy 374.863342 -250.67826) (xy 374.907804 -250.699358) (xy 374.948307 -250.727314)
			(xy 374.9838 -250.761406) (xy 375.013365 -250.80075) (xy 375.036236 -250.844327) (xy 375.05182 -250.891008)
			(xy 375.059715 -250.939585) (xy 375.06021 -250.964192) (xy 375.378467 -250.964192) (xy 375.382562 -250.913464)
			(xy 375.394741 -250.86405) (xy 375.414689 -250.81723) (xy 375.44189 -250.774216) (xy 375.475638 -250.736122)
			(xy 375.51506 -250.703935) (xy 375.559134 -250.678489) (xy 375.60672 -250.660442) (xy 375.656584 -250.650262)
			(xy 375.707436 -250.648213) (xy 375.757957 -250.654347) (xy 375.806841 -250.668507) (xy 375.85282 -250.690324)
			(xy 375.894704 -250.719234) (xy 375.931408 -250.754489) (xy 375.961981 -250.795175) (xy 375.985632 -250.840238)
			(xy 376.001748 -250.888512) (xy 376.009912 -250.938746) (xy 376.010424 -250.964192) (xy 376.328952 -250.964192)
			(xy 376.332912 -250.915138) (xy 376.344689 -250.867354) (xy 376.36398 -250.822078) (xy 376.390283 -250.780482)
			(xy 376.422918 -250.743645) (xy 376.461039 -250.71252) (xy 376.50366 -250.687913) (xy 376.549676 -250.670461)
			(xy 376.597895 -250.660617) (xy 376.64707 -250.658636) (xy 376.695925 -250.664568) (xy 376.743196 -250.67826)
			(xy 376.787658 -250.699358) (xy 376.828161 -250.727314) (xy 376.863654 -250.761406) (xy 376.893219 -250.80075)
			(xy 376.91609 -250.844327) (xy 376.931674 -250.891008) (xy 376.939569 -250.939585) (xy 376.940064 -250.964192)
			(xy 377.258575 -250.964192) (xy 377.26267 -250.913464) (xy 377.274849 -250.86405) (xy 377.294797 -250.81723)
			(xy 377.321998 -250.774216) (xy 377.355746 -250.736122) (xy 377.395168 -250.703935) (xy 377.439242 -250.678489)
			(xy 377.486828 -250.660442) (xy 377.536692 -250.650262) (xy 377.587544 -250.648213) (xy 377.638065 -250.654347)
			(xy 377.686949 -250.668507) (xy 377.732928 -250.690324) (xy 377.774812 -250.719234) (xy 377.811516 -250.754489)
			(xy 377.842089 -250.795175) (xy 377.86574 -250.840238) (xy 377.881856 -250.888512) (xy 377.89002 -250.938746)
			(xy 377.890532 -250.964192) (xy 378.20906 -250.964192) (xy 378.21302 -250.915138) (xy 378.224797 -250.867354)
			(xy 378.244088 -250.822078) (xy 378.270391 -250.780482) (xy 378.303026 -250.743645) (xy 378.341147 -250.71252)
			(xy 378.383768 -250.687913) (xy 378.429784 -250.670461) (xy 378.478003 -250.660617) (xy 378.527178 -250.658636)
			(xy 378.576033 -250.664568) (xy 378.623304 -250.67826) (xy 378.667766 -250.699358) (xy 378.708269 -250.727314)
			(xy 378.743762 -250.761406) (xy 378.773327 -250.80075) (xy 378.796198 -250.844327) (xy 378.811782 -250.891008)
			(xy 378.819677 -250.939585) (xy 378.820172 -250.964192) (xy 379.138683 -250.964192) (xy 379.142778 -250.913464)
			(xy 379.154957 -250.86405) (xy 379.174905 -250.81723) (xy 379.202106 -250.774216) (xy 379.235854 -250.736122)
			(xy 379.275276 -250.703935) (xy 379.31935 -250.678489) (xy 379.366936 -250.660442) (xy 379.4168 -250.650262)
			(xy 379.467652 -250.648213) (xy 379.518173 -250.654347) (xy 379.567057 -250.668507) (xy 379.613036 -250.690324)
			(xy 379.65492 -250.719234) (xy 379.691624 -250.754489) (xy 379.722197 -250.795175) (xy 379.745848 -250.840238)
			(xy 379.761964 -250.888512) (xy 379.770128 -250.938746) (xy 379.77064 -250.964192) (xy 380.078483 -250.964192)
			(xy 380.082578 -250.913464) (xy 380.094757 -250.86405) (xy 380.114705 -250.81723) (xy 380.141906 -250.774216)
			(xy 380.175654 -250.736122) (xy 380.215076 -250.703935) (xy 380.25915 -250.678489) (xy 380.306736 -250.660442)
			(xy 380.3566 -250.650262) (xy 380.407452 -250.648213) (xy 380.457973 -250.654347) (xy 380.506857 -250.668507)
			(xy 380.552836 -250.690324) (xy 380.59472 -250.719234) (xy 380.631424 -250.754489) (xy 380.661997 -250.795175)
			(xy 380.685648 -250.840238) (xy 380.701764 -250.888512) (xy 380.709928 -250.938746) (xy 380.71044 -250.964192)
			(xy 381.028968 -250.964192) (xy 381.032928 -250.915138) (xy 381.044705 -250.867354) (xy 381.063996 -250.822078)
			(xy 381.090299 -250.780482) (xy 381.122934 -250.743645) (xy 381.161055 -250.71252) (xy 381.203676 -250.687913)
			(xy 381.249692 -250.670461) (xy 381.297911 -250.660617) (xy 381.347086 -250.658636) (xy 381.395941 -250.664568)
			(xy 381.443212 -250.67826) (xy 381.487674 -250.699358) (xy 381.528177 -250.727314) (xy 381.56367 -250.761406)
			(xy 381.593235 -250.80075) (xy 381.616106 -250.844327) (xy 381.63169 -250.891008) (xy 381.639585 -250.939585)
			(xy 381.64008 -250.964192) (xy 381.969022 -250.964192) (xy 381.972982 -250.915138) (xy 381.984759 -250.867354)
			(xy 382.00405 -250.822078) (xy 382.030353 -250.780482) (xy 382.062988 -250.743645) (xy 382.101109 -250.71252)
			(xy 382.14373 -250.687913) (xy 382.189746 -250.670461) (xy 382.237965 -250.660617) (xy 382.28714 -250.658636)
			(xy 382.335995 -250.664568) (xy 382.383266 -250.67826) (xy 382.427728 -250.699358) (xy 382.468231 -250.727314)
			(xy 382.503724 -250.761406) (xy 382.533289 -250.80075) (xy 382.55616 -250.844327) (xy 382.571744 -250.891008)
			(xy 382.579639 -250.939585) (xy 382.580134 -250.964192) (xy 382.909076 -250.964192) (xy 382.913036 -250.915138)
			(xy 382.924813 -250.867354) (xy 382.944104 -250.822078) (xy 382.970407 -250.780482) (xy 383.003042 -250.743645)
			(xy 383.041163 -250.71252) (xy 383.083784 -250.687913) (xy 383.1298 -250.670461) (xy 383.178019 -250.660617)
			(xy 383.227194 -250.658636) (xy 383.276049 -250.664568) (xy 383.32332 -250.67826) (xy 383.367782 -250.699358)
			(xy 383.408285 -250.727314) (xy 383.443778 -250.761406) (xy 383.473343 -250.80075) (xy 383.496214 -250.844327)
			(xy 383.511798 -250.891008) (xy 383.519693 -250.939585) (xy 383.520188 -250.964192) (xy 383.84913 -250.964192)
			(xy 383.85309 -250.915138) (xy 383.864867 -250.867354) (xy 383.884158 -250.822078) (xy 383.910461 -250.780482)
			(xy 383.943096 -250.743645) (xy 383.981217 -250.71252) (xy 384.023838 -250.687913) (xy 384.069854 -250.670461)
			(xy 384.118073 -250.660617) (xy 384.167248 -250.658636) (xy 384.216103 -250.664568) (xy 384.263374 -250.67826)
			(xy 384.307836 -250.699358) (xy 384.348339 -250.727314) (xy 384.383832 -250.761406) (xy 384.413397 -250.80075)
			(xy 384.436268 -250.844327) (xy 384.451852 -250.891008) (xy 384.459747 -250.939585) (xy 384.460242 -250.964192)
			(xy 384.78893 -250.964192) (xy 384.79289 -250.915138) (xy 384.804667 -250.867354) (xy 384.823958 -250.822078)
			(xy 384.850261 -250.780482) (xy 384.882896 -250.743645) (xy 384.921017 -250.71252) (xy 384.963638 -250.687913)
			(xy 385.009654 -250.670461) (xy 385.057873 -250.660617) (xy 385.107048 -250.658636) (xy 385.155903 -250.664568)
			(xy 385.203174 -250.67826) (xy 385.247636 -250.699358) (xy 385.288139 -250.727314) (xy 385.323632 -250.761406)
			(xy 385.353197 -250.80075) (xy 385.376068 -250.844327) (xy 385.391652 -250.891008) (xy 385.399547 -250.939585)
			(xy 385.400042 -250.964192) (xy 385.728984 -250.964192) (xy 385.732944 -250.915138) (xy 385.744721 -250.867354)
			(xy 385.764012 -250.822078) (xy 385.790315 -250.780482) (xy 385.82295 -250.743645) (xy 385.861071 -250.71252)
			(xy 385.903692 -250.687913) (xy 385.949708 -250.670461) (xy 385.997927 -250.660617) (xy 386.047102 -250.658636)
			(xy 386.095957 -250.664568) (xy 386.143228 -250.67826) (xy 386.18769 -250.699358) (xy 386.228193 -250.727314)
			(xy 386.263686 -250.761406) (xy 386.293251 -250.80075) (xy 386.316122 -250.844327) (xy 386.331706 -250.891008)
			(xy 386.339601 -250.939585) (xy 386.340096 -250.964192) (xy 386.669038 -250.964192) (xy 386.672998 -250.915138)
			(xy 386.684775 -250.867354) (xy 386.704066 -250.822078) (xy 386.730369 -250.780482) (xy 386.763004 -250.743645)
			(xy 386.801125 -250.71252) (xy 386.843746 -250.687913) (xy 386.889762 -250.670461) (xy 386.937981 -250.660617)
			(xy 386.987156 -250.658636) (xy 387.036011 -250.664568) (xy 387.083282 -250.67826) (xy 387.127744 -250.699358)
			(xy 387.168247 -250.727314) (xy 387.20374 -250.761406) (xy 387.233305 -250.80075) (xy 387.256176 -250.844327)
			(xy 387.27176 -250.891008) (xy 387.279655 -250.939585) (xy 387.28015 -250.964192) (xy 387.279655 -250.988799)
			(xy 387.27176 -251.037376) (xy 387.256176 -251.084057) (xy 387.233305 -251.127634) (xy 387.20374 -251.166978)
			(xy 387.168247 -251.20107) (xy 387.127744 -251.229026) (xy 387.083282 -251.250124) (xy 387.036011 -251.263816)
			(xy 386.987156 -251.269748) (xy 386.937981 -251.267767) (xy 386.889762 -251.257923) (xy 386.843746 -251.240471)
			(xy 386.801125 -251.215864) (xy 386.763004 -251.184739) (xy 386.730369 -251.147902) (xy 386.704066 -251.106306)
			(xy 386.684775 -251.06103) (xy 386.672998 -251.013246) (xy 386.669038 -250.964192) (xy 386.340096 -250.964192)
			(xy 386.339601 -250.988799) (xy 386.331706 -251.037376) (xy 386.316122 -251.084057) (xy 386.293251 -251.127634)
			(xy 386.263686 -251.166978) (xy 386.228193 -251.20107) (xy 386.18769 -251.229026) (xy 386.143228 -251.250124)
			(xy 386.095957 -251.263816) (xy 386.047102 -251.269748) (xy 385.997927 -251.267767) (xy 385.949708 -251.257923)
			(xy 385.903692 -251.240471) (xy 385.861071 -251.215864) (xy 385.82295 -251.184739) (xy 385.790315 -251.147902)
			(xy 385.764012 -251.106306) (xy 385.744721 -251.06103) (xy 385.732944 -251.013246) (xy 385.728984 -250.964192)
			(xy 385.400042 -250.964192) (xy 385.399547 -250.988799) (xy 385.391652 -251.037376) (xy 385.376068 -251.084057)
			(xy 385.353197 -251.127634) (xy 385.323632 -251.166978) (xy 385.288139 -251.20107) (xy 385.247636 -251.229026)
			(xy 385.203174 -251.250124) (xy 385.155903 -251.263816) (xy 385.107048 -251.269748) (xy 385.057873 -251.267767)
			(xy 385.009654 -251.257923) (xy 384.963638 -251.240471) (xy 384.921017 -251.215864) (xy 384.882896 -251.184739)
			(xy 384.850261 -251.147902) (xy 384.823958 -251.106306) (xy 384.804667 -251.06103) (xy 384.79289 -251.013246)
			(xy 384.78893 -250.964192) (xy 384.460242 -250.964192) (xy 384.459747 -250.988799) (xy 384.451852 -251.037376)
			(xy 384.436268 -251.084057) (xy 384.413397 -251.127634) (xy 384.383832 -251.166978) (xy 384.348339 -251.20107)
			(xy 384.307836 -251.229026) (xy 384.263374 -251.250124) (xy 384.216103 -251.263816) (xy 384.167248 -251.269748)
			(xy 384.118073 -251.267767) (xy 384.069854 -251.257923) (xy 384.023838 -251.240471) (xy 383.981217 -251.215864)
			(xy 383.943096 -251.184739) (xy 383.910461 -251.147902) (xy 383.884158 -251.106306) (xy 383.864867 -251.06103)
			(xy 383.85309 -251.013246) (xy 383.84913 -250.964192) (xy 383.520188 -250.964192) (xy 383.519693 -250.988799)
			(xy 383.511798 -251.037376) (xy 383.496214 -251.084057) (xy 383.473343 -251.127634) (xy 383.443778 -251.166978)
			(xy 383.408285 -251.20107) (xy 383.367782 -251.229026) (xy 383.32332 -251.250124) (xy 383.276049 -251.263816)
			(xy 383.227194 -251.269748) (xy 383.178019 -251.267767) (xy 383.1298 -251.257923) (xy 383.083784 -251.240471)
			(xy 383.041163 -251.215864) (xy 383.003042 -251.184739) (xy 382.970407 -251.147902) (xy 382.944104 -251.106306)
			(xy 382.924813 -251.06103) (xy 382.913036 -251.013246) (xy 382.909076 -250.964192) (xy 382.580134 -250.964192)
			(xy 382.579639 -250.988799) (xy 382.571744 -251.037376) (xy 382.55616 -251.084057) (xy 382.533289 -251.127634)
			(xy 382.503724 -251.166978) (xy 382.468231 -251.20107) (xy 382.427728 -251.229026) (xy 382.383266 -251.250124)
			(xy 382.335995 -251.263816) (xy 382.28714 -251.269748) (xy 382.237965 -251.267767) (xy 382.189746 -251.257923)
			(xy 382.14373 -251.240471) (xy 382.101109 -251.215864) (xy 382.062988 -251.184739) (xy 382.030353 -251.147902)
			(xy 382.00405 -251.106306) (xy 381.984759 -251.06103) (xy 381.972982 -251.013246) (xy 381.969022 -250.964192)
			(xy 381.64008 -250.964192) (xy 381.639585 -250.988799) (xy 381.63169 -251.037376) (xy 381.616106 -251.084057)
			(xy 381.593235 -251.127634) (xy 381.56367 -251.166978) (xy 381.528177 -251.20107) (xy 381.487674 -251.229026)
			(xy 381.443212 -251.250124) (xy 381.395941 -251.263816) (xy 381.347086 -251.269748) (xy 381.297911 -251.267767)
			(xy 381.249692 -251.257923) (xy 381.203676 -251.240471) (xy 381.161055 -251.215864) (xy 381.122934 -251.184739)
			(xy 381.090299 -251.147902) (xy 381.063996 -251.106306) (xy 381.044705 -251.06103) (xy 381.032928 -251.013246)
			(xy 381.028968 -250.964192) (xy 380.71044 -250.964192) (xy 380.709928 -250.989638) (xy 380.701764 -251.039872)
			(xy 380.685648 -251.088146) (xy 380.661997 -251.133209) (xy 380.631424 -251.173895) (xy 380.59472 -251.20915)
			(xy 380.552836 -251.23806) (xy 380.506857 -251.259877) (xy 380.457973 -251.274037) (xy 380.407452 -251.280171)
			(xy 380.3566 -251.278122) (xy 380.306736 -251.267942) (xy 380.25915 -251.249895) (xy 380.215076 -251.224449)
			(xy 380.175654 -251.192262) (xy 380.141906 -251.154168) (xy 380.114705 -251.111154) (xy 380.094757 -251.064334)
			(xy 380.082578 -251.01492) (xy 380.078483 -250.964192) (xy 379.77064 -250.964192) (xy 379.770128 -250.989638)
			(xy 379.761964 -251.039872) (xy 379.745848 -251.088146) (xy 379.722197 -251.133209) (xy 379.691624 -251.173895)
			(xy 379.65492 -251.20915) (xy 379.613036 -251.23806) (xy 379.567057 -251.259877) (xy 379.518173 -251.274037)
			(xy 379.467652 -251.280171) (xy 379.4168 -251.278122) (xy 379.366936 -251.267942) (xy 379.31935 -251.249895)
			(xy 379.275276 -251.224449) (xy 379.235854 -251.192262) (xy 379.202106 -251.154168) (xy 379.174905 -251.111154)
			(xy 379.154957 -251.064334) (xy 379.142778 -251.01492) (xy 379.138683 -250.964192) (xy 378.820172 -250.964192)
			(xy 378.819677 -250.988799) (xy 378.811782 -251.037376) (xy 378.796198 -251.084057) (xy 378.773327 -251.127634)
			(xy 378.743762 -251.166978) (xy 378.708269 -251.20107) (xy 378.667766 -251.229026) (xy 378.623304 -251.250124)
			(xy 378.576033 -251.263816) (xy 378.527178 -251.269748) (xy 378.478003 -251.267767) (xy 378.429784 -251.257923)
			(xy 378.383768 -251.240471) (xy 378.341147 -251.215864) (xy 378.303026 -251.184739) (xy 378.270391 -251.147902)
			(xy 378.244088 -251.106306) (xy 378.224797 -251.06103) (xy 378.21302 -251.013246) (xy 378.20906 -250.964192)
			(xy 377.890532 -250.964192) (xy 377.89002 -250.989638) (xy 377.881856 -251.039872) (xy 377.86574 -251.088146)
			(xy 377.842089 -251.133209) (xy 377.811516 -251.173895) (xy 377.774812 -251.20915) (xy 377.732928 -251.23806)
			(xy 377.686949 -251.259877) (xy 377.638065 -251.274037) (xy 377.587544 -251.280171) (xy 377.536692 -251.278122)
			(xy 377.486828 -251.267942) (xy 377.439242 -251.249895) (xy 377.395168 -251.224449) (xy 377.355746 -251.192262)
			(xy 377.321998 -251.154168) (xy 377.294797 -251.111154) (xy 377.274849 -251.064334) (xy 377.26267 -251.01492)
			(xy 377.258575 -250.964192) (xy 376.940064 -250.964192) (xy 376.939569 -250.988799) (xy 376.931674 -251.037376)
			(xy 376.91609 -251.084057) (xy 376.893219 -251.127634) (xy 376.863654 -251.166978) (xy 376.828161 -251.20107)
			(xy 376.787658 -251.229026) (xy 376.743196 -251.250124) (xy 376.695925 -251.263816) (xy 376.64707 -251.269748)
			(xy 376.597895 -251.267767) (xy 376.549676 -251.257923) (xy 376.50366 -251.240471) (xy 376.461039 -251.215864)
			(xy 376.422918 -251.184739) (xy 376.390283 -251.147902) (xy 376.36398 -251.106306) (xy 376.344689 -251.06103)
			(xy 376.332912 -251.013246) (xy 376.328952 -250.964192) (xy 376.010424 -250.964192) (xy 376.009912 -250.989638)
			(xy 376.001748 -251.039872) (xy 375.985632 -251.088146) (xy 375.961981 -251.133209) (xy 375.931408 -251.173895)
			(xy 375.894704 -251.20915) (xy 375.85282 -251.23806) (xy 375.806841 -251.259877) (xy 375.757957 -251.274037)
			(xy 375.707436 -251.280171) (xy 375.656584 -251.278122) (xy 375.60672 -251.267942) (xy 375.559134 -251.249895)
			(xy 375.51506 -251.224449) (xy 375.475638 -251.192262) (xy 375.44189 -251.154168) (xy 375.414689 -251.111154)
			(xy 375.394741 -251.064334) (xy 375.382562 -251.01492) (xy 375.378467 -250.964192) (xy 375.06021 -250.964192)
			(xy 375.059715 -250.988799) (xy 375.05182 -251.037376) (xy 375.036236 -251.084057) (xy 375.013365 -251.127634)
			(xy 374.9838 -251.166978) (xy 374.948307 -251.20107) (xy 374.907804 -251.229026) (xy 374.863342 -251.250124)
			(xy 374.816071 -251.263816) (xy 374.767216 -251.269748) (xy 374.718041 -251.267767) (xy 374.669822 -251.257923)
			(xy 374.623806 -251.240471) (xy 374.581185 -251.215864) (xy 374.543064 -251.184739) (xy 374.510429 -251.147902)
			(xy 374.484126 -251.106306) (xy 374.464835 -251.06103) (xy 374.453058 -251.013246) (xy 374.449098 -250.964192)
			(xy 373.36222 -250.964192) (xy 372.816374 -251.510038) (xy 372.809202 -251.516618) (xy 372.791293 -251.524187)
			(xy 372.781576 -251.52477) (xy 372.781322 -251.52477) (xy 372.769199 -251.525695) (xy 372.747839 -251.537231)
			(xy 372.740428 -251.546868) (xy 372.694708 -251.61367) (xy 372.689347 -251.622245) (xy 372.685267 -251.642035)
			(xy 372.686834 -251.652024) (xy 372.688612 -251.660914) (xy 372.69039 -251.665994) (xy 372.690644 -251.666502)
			(xy 372.699834 -251.692666) (xy 372.709677 -251.747234) (xy 372.710188 -251.774198) (xy 373.978944 -251.774198)
			(xy 373.982904 -251.725144) (xy 373.994681 -251.67736) (xy 374.013972 -251.632084) (xy 374.040275 -251.590488)
			(xy 374.07291 -251.553651) (xy 374.111031 -251.522526) (xy 374.153652 -251.497919) (xy 374.199668 -251.480467)
			(xy 374.247887 -251.470623) (xy 374.297062 -251.468642) (xy 374.345917 -251.474574) (xy 374.393188 -251.488266)
			(xy 374.43765 -251.509364) (xy 374.478153 -251.53732) (xy 374.513646 -251.571412) (xy 374.543211 -251.610756)
			(xy 374.566082 -251.654333) (xy 374.581666 -251.701014) (xy 374.589561 -251.749591) (xy 374.590056 -251.774198)
			(xy 375.848621 -251.774198) (xy 375.852716 -251.72347) (xy 375.864895 -251.674056) (xy 375.884843 -251.627236)
			(xy 375.912044 -251.584222) (xy 375.945792 -251.546128) (xy 375.985214 -251.513941) (xy 376.029288 -251.488495)
			(xy 376.076874 -251.470448) (xy 376.126738 -251.460268) (xy 376.17759 -251.458219) (xy 376.228111 -251.464353)
			(xy 376.276995 -251.478513) (xy 376.322974 -251.50033) (xy 376.364858 -251.52924) (xy 376.401562 -251.564495)
			(xy 376.432135 -251.605181) (xy 376.455786 -251.650244) (xy 376.471902 -251.698518) (xy 376.480066 -251.748752)
			(xy 376.480578 -251.774198) (xy 376.799106 -251.774198) (xy 376.803066 -251.725144) (xy 376.814843 -251.67736)
			(xy 376.834134 -251.632084) (xy 376.860437 -251.590488) (xy 376.893072 -251.553651) (xy 376.931193 -251.522526)
			(xy 376.973814 -251.497919) (xy 377.01983 -251.480467) (xy 377.068049 -251.470623) (xy 377.117224 -251.468642)
			(xy 377.166079 -251.474574) (xy 377.21335 -251.488266) (xy 377.257812 -251.509364) (xy 377.298315 -251.53732)
			(xy 377.333808 -251.571412) (xy 377.363373 -251.610756) (xy 377.386244 -251.654333) (xy 377.401828 -251.701014)
			(xy 377.409723 -251.749591) (xy 377.410218 -251.774198) (xy 378.668529 -251.774198) (xy 378.672624 -251.72347)
			(xy 378.684803 -251.674056) (xy 378.704751 -251.627236) (xy 378.731952 -251.584222) (xy 378.7657 -251.546128)
			(xy 378.805122 -251.513941) (xy 378.849196 -251.488495) (xy 378.896782 -251.470448) (xy 378.946646 -251.460268)
			(xy 378.997498 -251.458219) (xy 379.048019 -251.464353) (xy 379.096903 -251.478513) (xy 379.142882 -251.50033)
			(xy 379.184766 -251.52924) (xy 379.22147 -251.564495) (xy 379.252043 -251.605181) (xy 379.275694 -251.650244)
			(xy 379.29181 -251.698518) (xy 379.299974 -251.748752) (xy 379.300486 -251.774198) (xy 379.619014 -251.774198)
			(xy 379.622974 -251.725144) (xy 379.634751 -251.67736) (xy 379.654042 -251.632084) (xy 379.680345 -251.590488)
			(xy 379.71298 -251.553651) (xy 379.751101 -251.522526) (xy 379.793722 -251.497919) (xy 379.839738 -251.480467)
			(xy 379.887957 -251.470623) (xy 379.937132 -251.468642) (xy 379.985987 -251.474574) (xy 380.033258 -251.488266)
			(xy 380.07772 -251.509364) (xy 380.118223 -251.53732) (xy 380.153716 -251.571412) (xy 380.183281 -251.610756)
			(xy 380.206152 -251.654333) (xy 380.221736 -251.701014) (xy 380.229631 -251.749591) (xy 380.230126 -251.774198)
			(xy 380.559068 -251.774198) (xy 380.563028 -251.725144) (xy 380.574805 -251.67736) (xy 380.594096 -251.632084)
			(xy 380.620399 -251.590488) (xy 380.653034 -251.553651) (xy 380.691155 -251.522526) (xy 380.733776 -251.497919)
			(xy 380.779792 -251.480467) (xy 380.828011 -251.470623) (xy 380.877186 -251.468642) (xy 380.926041 -251.474574)
			(xy 380.973312 -251.488266) (xy 381.017774 -251.509364) (xy 381.058277 -251.53732) (xy 381.09377 -251.571412)
			(xy 381.123335 -251.610756) (xy 381.146206 -251.654333) (xy 381.16179 -251.701014) (xy 381.169685 -251.749591)
			(xy 381.17018 -251.774198) (xy 381.499122 -251.774198) (xy 381.503082 -251.725144) (xy 381.514859 -251.67736)
			(xy 381.53415 -251.632084) (xy 381.560453 -251.590488) (xy 381.593088 -251.553651) (xy 381.631209 -251.522526)
			(xy 381.67383 -251.497919) (xy 381.719846 -251.480467) (xy 381.768065 -251.470623) (xy 381.81724 -251.468642)
			(xy 381.866095 -251.474574) (xy 381.913366 -251.488266) (xy 381.957828 -251.509364) (xy 381.998331 -251.53732)
			(xy 382.033824 -251.571412) (xy 382.063389 -251.610756) (xy 382.08626 -251.654333) (xy 382.101844 -251.701014)
			(xy 382.109739 -251.749591) (xy 382.110234 -251.774198) (xy 382.438922 -251.774198) (xy 382.442882 -251.725144)
			(xy 382.454659 -251.67736) (xy 382.47395 -251.632084) (xy 382.500253 -251.590488) (xy 382.532888 -251.553651)
			(xy 382.571009 -251.522526) (xy 382.61363 -251.497919) (xy 382.659646 -251.480467) (xy 382.707865 -251.470623)
			(xy 382.75704 -251.468642) (xy 382.805895 -251.474574) (xy 382.853166 -251.488266) (xy 382.897628 -251.509364)
			(xy 382.938131 -251.53732) (xy 382.973624 -251.571412) (xy 383.003189 -251.610756) (xy 383.02606 -251.654333)
			(xy 383.041644 -251.701014) (xy 383.049539 -251.749591) (xy 383.050034 -251.774198) (xy 383.378976 -251.774198)
			(xy 383.382936 -251.725144) (xy 383.394713 -251.67736) (xy 383.414004 -251.632084) (xy 383.440307 -251.590488)
			(xy 383.472942 -251.553651) (xy 383.511063 -251.522526) (xy 383.553684 -251.497919) (xy 383.5997 -251.480467)
			(xy 383.647919 -251.470623) (xy 383.697094 -251.468642) (xy 383.745949 -251.474574) (xy 383.79322 -251.488266)
			(xy 383.837682 -251.509364) (xy 383.878185 -251.53732) (xy 383.913678 -251.571412) (xy 383.943243 -251.610756)
			(xy 383.966114 -251.654333) (xy 383.981698 -251.701014) (xy 383.989593 -251.749591) (xy 383.990088 -251.774198)
			(xy 385.259084 -251.774198) (xy 385.263044 -251.725144) (xy 385.274821 -251.67736) (xy 385.294112 -251.632084)
			(xy 385.320415 -251.590488) (xy 385.35305 -251.553651) (xy 385.391171 -251.522526) (xy 385.433792 -251.497919)
			(xy 385.479808 -251.480467) (xy 385.528027 -251.470623) (xy 385.577202 -251.468642) (xy 385.626057 -251.474574)
			(xy 385.673328 -251.488266) (xy 385.71779 -251.509364) (xy 385.758293 -251.53732) (xy 385.793786 -251.571412)
			(xy 385.823351 -251.610756) (xy 385.846222 -251.654333) (xy 385.861806 -251.701014) (xy 385.869701 -251.749591)
			(xy 385.870196 -251.774198) (xy 386.199138 -251.774198) (xy 386.203098 -251.725144) (xy 386.214875 -251.67736)
			(xy 386.234166 -251.632084) (xy 386.260469 -251.590488) (xy 386.293104 -251.553651) (xy 386.331225 -251.522526)
			(xy 386.373846 -251.497919) (xy 386.419862 -251.480467) (xy 386.468081 -251.470623) (xy 386.517256 -251.468642)
			(xy 386.566111 -251.474574) (xy 386.613382 -251.488266) (xy 386.657844 -251.509364) (xy 386.698347 -251.53732)
			(xy 386.73384 -251.571412) (xy 386.763405 -251.610756) (xy 386.786276 -251.654333) (xy 386.80186 -251.701014)
			(xy 386.809755 -251.749591) (xy 386.81025 -251.774198) (xy 387.138938 -251.774198) (xy 387.142898 -251.725144)
			(xy 387.154675 -251.67736) (xy 387.173966 -251.632084) (xy 387.200269 -251.590488) (xy 387.232904 -251.553651)
			(xy 387.271025 -251.522526) (xy 387.313646 -251.497919) (xy 387.359662 -251.480467) (xy 387.407881 -251.470623)
			(xy 387.457056 -251.468642) (xy 387.505911 -251.474574) (xy 387.553182 -251.488266) (xy 387.597644 -251.509364)
			(xy 387.638147 -251.53732) (xy 387.67364 -251.571412) (xy 387.703205 -251.610756) (xy 387.726076 -251.654333)
			(xy 387.74166 -251.701014) (xy 387.749555 -251.749591) (xy 387.75005 -251.774198) (xy 387.749555 -251.798805)
			(xy 387.74166 -251.847382) (xy 387.726076 -251.894063) (xy 387.703205 -251.93764) (xy 387.67364 -251.976984)
			(xy 387.638147 -252.011076) (xy 387.597644 -252.039032) (xy 387.553182 -252.06013) (xy 387.505911 -252.073822)
			(xy 387.457056 -252.079754) (xy 387.407881 -252.077773) (xy 387.359662 -252.067929) (xy 387.313646 -252.050477)
			(xy 387.271025 -252.02587) (xy 387.232904 -251.994745) (xy 387.200269 -251.957908) (xy 387.173966 -251.916312)
			(xy 387.154675 -251.871036) (xy 387.142898 -251.823252) (xy 387.138938 -251.774198) (xy 386.81025 -251.774198)
			(xy 386.809755 -251.798805) (xy 386.80186 -251.847382) (xy 386.786276 -251.894063) (xy 386.763405 -251.93764)
			(xy 386.73384 -251.976984) (xy 386.698347 -252.011076) (xy 386.657844 -252.039032) (xy 386.613382 -252.06013)
			(xy 386.566111 -252.073822) (xy 386.517256 -252.079754) (xy 386.468081 -252.077773) (xy 386.419862 -252.067929)
			(xy 386.373846 -252.050477) (xy 386.331225 -252.02587) (xy 386.293104 -251.994745) (xy 386.260469 -251.957908)
			(xy 386.234166 -251.916312) (xy 386.214875 -251.871036) (xy 386.203098 -251.823252) (xy 386.199138 -251.774198)
			(xy 385.870196 -251.774198) (xy 385.869701 -251.798805) (xy 385.861806 -251.847382) (xy 385.846222 -251.894063)
			(xy 385.823351 -251.93764) (xy 385.793786 -251.976984) (xy 385.758293 -252.011076) (xy 385.71779 -252.039032)
			(xy 385.673328 -252.06013) (xy 385.626057 -252.073822) (xy 385.577202 -252.079754) (xy 385.528027 -252.077773)
			(xy 385.479808 -252.067929) (xy 385.433792 -252.050477) (xy 385.391171 -252.02587) (xy 385.35305 -251.994745)
			(xy 385.320415 -251.957908) (xy 385.294112 -251.916312) (xy 385.274821 -251.871036) (xy 385.263044 -251.823252)
			(xy 385.259084 -251.774198) (xy 383.990088 -251.774198) (xy 383.989593 -251.798805) (xy 383.981698 -251.847382)
			(xy 383.966114 -251.894063) (xy 383.943243 -251.93764) (xy 383.913678 -251.976984) (xy 383.878185 -252.011076)
			(xy 383.837682 -252.039032) (xy 383.79322 -252.06013) (xy 383.745949 -252.073822) (xy 383.697094 -252.079754)
			(xy 383.647919 -252.077773) (xy 383.5997 -252.067929) (xy 383.553684 -252.050477) (xy 383.511063 -252.02587)
			(xy 383.472942 -251.994745) (xy 383.440307 -251.957908) (xy 383.414004 -251.916312) (xy 383.394713 -251.871036)
			(xy 383.382936 -251.823252) (xy 383.378976 -251.774198) (xy 383.050034 -251.774198) (xy 383.049539 -251.798805)
			(xy 383.041644 -251.847382) (xy 383.02606 -251.894063) (xy 383.003189 -251.93764) (xy 382.973624 -251.976984)
			(xy 382.938131 -252.011076) (xy 382.897628 -252.039032) (xy 382.853166 -252.06013) (xy 382.805895 -252.073822)
			(xy 382.75704 -252.079754) (xy 382.707865 -252.077773) (xy 382.659646 -252.067929) (xy 382.61363 -252.050477)
			(xy 382.571009 -252.02587) (xy 382.532888 -251.994745) (xy 382.500253 -251.957908) (xy 382.47395 -251.916312)
			(xy 382.454659 -251.871036) (xy 382.442882 -251.823252) (xy 382.438922 -251.774198) (xy 382.110234 -251.774198)
			(xy 382.109739 -251.798805) (xy 382.101844 -251.847382) (xy 382.08626 -251.894063) (xy 382.063389 -251.93764)
			(xy 382.033824 -251.976984) (xy 381.998331 -252.011076) (xy 381.957828 -252.039032) (xy 381.913366 -252.06013)
			(xy 381.866095 -252.073822) (xy 381.81724 -252.079754) (xy 381.768065 -252.077773) (xy 381.719846 -252.067929)
			(xy 381.67383 -252.050477) (xy 381.631209 -252.02587) (xy 381.593088 -251.994745) (xy 381.560453 -251.957908)
			(xy 381.53415 -251.916312) (xy 381.514859 -251.871036) (xy 381.503082 -251.823252) (xy 381.499122 -251.774198)
			(xy 381.17018 -251.774198) (xy 381.169685 -251.798805) (xy 381.16179 -251.847382) (xy 381.146206 -251.894063)
			(xy 381.123335 -251.93764) (xy 381.09377 -251.976984) (xy 381.058277 -252.011076) (xy 381.017774 -252.039032)
			(xy 380.973312 -252.06013) (xy 380.926041 -252.073822) (xy 380.877186 -252.079754) (xy 380.828011 -252.077773)
			(xy 380.779792 -252.067929) (xy 380.733776 -252.050477) (xy 380.691155 -252.02587) (xy 380.653034 -251.994745)
			(xy 380.620399 -251.957908) (xy 380.594096 -251.916312) (xy 380.574805 -251.871036) (xy 380.563028 -251.823252)
			(xy 380.559068 -251.774198) (xy 380.230126 -251.774198) (xy 380.229631 -251.798805) (xy 380.221736 -251.847382)
			(xy 380.206152 -251.894063) (xy 380.183281 -251.93764) (xy 380.153716 -251.976984) (xy 380.118223 -252.011076)
			(xy 380.07772 -252.039032) (xy 380.033258 -252.06013) (xy 379.985987 -252.073822) (xy 379.937132 -252.079754)
			(xy 379.887957 -252.077773) (xy 379.839738 -252.067929) (xy 379.793722 -252.050477) (xy 379.751101 -252.02587)
			(xy 379.71298 -251.994745) (xy 379.680345 -251.957908) (xy 379.654042 -251.916312) (xy 379.634751 -251.871036)
			(xy 379.622974 -251.823252) (xy 379.619014 -251.774198) (xy 379.300486 -251.774198) (xy 379.299974 -251.799644)
			(xy 379.29181 -251.849878) (xy 379.275694 -251.898152) (xy 379.252043 -251.943215) (xy 379.22147 -251.983901)
			(xy 379.184766 -252.019156) (xy 379.142882 -252.048066) (xy 379.096903 -252.069883) (xy 379.048019 -252.084043)
			(xy 378.997498 -252.090177) (xy 378.946646 -252.088128) (xy 378.896782 -252.077948) (xy 378.849196 -252.059901)
			(xy 378.805122 -252.034455) (xy 378.7657 -252.002268) (xy 378.731952 -251.964174) (xy 378.704751 -251.92116)
			(xy 378.684803 -251.87434) (xy 378.672624 -251.824926) (xy 378.668529 -251.774198) (xy 377.410218 -251.774198)
			(xy 377.409723 -251.798805) (xy 377.401828 -251.847382) (xy 377.386244 -251.894063) (xy 377.363373 -251.93764)
			(xy 377.333808 -251.976984) (xy 377.298315 -252.011076) (xy 377.257812 -252.039032) (xy 377.21335 -252.06013)
			(xy 377.166079 -252.073822) (xy 377.117224 -252.079754) (xy 377.068049 -252.077773) (xy 377.01983 -252.067929)
			(xy 376.973814 -252.050477) (xy 376.931193 -252.02587) (xy 376.893072 -251.994745) (xy 376.860437 -251.957908)
			(xy 376.834134 -251.916312) (xy 376.814843 -251.871036) (xy 376.803066 -251.823252) (xy 376.799106 -251.774198)
			(xy 376.480578 -251.774198) (xy 376.480066 -251.799644) (xy 376.471902 -251.849878) (xy 376.455786 -251.898152)
			(xy 376.432135 -251.943215) (xy 376.401562 -251.983901) (xy 376.364858 -252.019156) (xy 376.322974 -252.048066)
			(xy 376.276995 -252.069883) (xy 376.228111 -252.084043) (xy 376.17759 -252.090177) (xy 376.126738 -252.088128)
			(xy 376.076874 -252.077948) (xy 376.029288 -252.059901) (xy 375.985214 -252.034455) (xy 375.945792 -252.002268)
			(xy 375.912044 -251.964174) (xy 375.884843 -251.92116) (xy 375.864895 -251.87434) (xy 375.852716 -251.824926)
			(xy 375.848621 -251.774198) (xy 374.590056 -251.774198) (xy 374.589561 -251.798805) (xy 374.581666 -251.847382)
			(xy 374.566082 -251.894063) (xy 374.543211 -251.93764) (xy 374.513646 -251.976984) (xy 374.478153 -252.011076)
			(xy 374.43765 -252.039032) (xy 374.393188 -252.06013) (xy 374.345917 -252.073822) (xy 374.297062 -252.079754)
			(xy 374.247887 -252.077773) (xy 374.199668 -252.067929) (xy 374.153652 -252.050477) (xy 374.111031 -252.02587)
			(xy 374.07291 -251.994745) (xy 374.040275 -251.957908) (xy 374.013972 -251.916312) (xy 373.994681 -251.871036)
			(xy 373.982904 -251.823252) (xy 373.978944 -251.774198) (xy 372.710188 -251.774198) (xy 372.710202 -251.77496)
			(xy 372.710202 -251.778262) (xy 372.709431 -251.802044) (xy 372.701425 -251.848947) (xy 372.686241 -251.89404)
			(xy 372.664246 -251.936231) (xy 372.635972 -251.9745) (xy 372.602104 -252.00792) (xy 372.563461 -252.035681)
			(xy 372.52098 -252.057113) (xy 372.475689 -252.071695) (xy 372.428684 -252.079075) (xy 372.404894 -252.079506)
			(xy 372.381116 -252.079052) (xy 372.334135 -252.07168) (xy 372.288864 -252.057114) (xy 372.246398 -252.035708)
			(xy 372.207764 -252.007977) (xy 372.173894 -251.974594) (xy 372.145609 -251.936364) (xy 372.123591 -251.894211)
			(xy 372.108373 -251.849156) (xy 372.100323 -251.802286) (xy 372.099586 -251.778516) (xy 372.099586 -251.774452)
			(xy 372.100221 -251.745689) (xy 372.110964 -251.689176) (xy 372.120922 -251.662184) (xy 372.121176 -251.661676)
			(xy 372.123139 -251.655987) (xy 372.124685 -251.644054) (xy 372.124224 -251.638054) (xy 372.122954 -251.6251)
			(xy 372.069868 -251.546868) (xy 372.062296 -251.536924) (xy 372.040189 -251.525322) (xy 372.027704 -251.52477)
			(xy 371.333776 -251.52477) (xy 371.323935 -251.524242) (xy 371.305765 -251.516663) (xy 371.29847 -251.510038)
			(xy 371.06225 -251.273818) (xy 371.04066 -251.266198) (xy 371.028976 -251.267468) (xy 370.994686 -251.2695)
			(xy 370.970696 -251.269028) (xy 370.923306 -251.26152) (xy 370.877675 -251.246692) (xy 370.834924 -251.224907)
			(xy 370.796108 -251.196704) (xy 370.762182 -251.162775) (xy 370.733981 -251.123957) (xy 370.7122 -251.081205)
			(xy 370.697374 -251.035572) (xy 370.68987 -250.988182) (xy 370.689378 -250.964192) (xy 370.69141 -250.929902)
			(xy 370.69268 -250.918218) (xy 370.68506 -250.896628) (xy 370.402358 -250.613926) (xy 370.395246 -250.60656)
			(xy 370.37645 -250.59894) (xy 369.460526 -250.59894) (xy 369.450688 -250.599475) (xy 369.432522 -250.607056)
			(xy 369.42522 -250.613672) (xy 369.359688 -250.679204) (xy 369.353261 -250.686246) (xy 369.345706 -250.703735)
			(xy 369.344956 -250.71324) (xy 369.344194 -250.734576) (xy 369.344142 -250.739294) (xy 369.345553 -250.748623)
			(xy 369.346988 -250.753118) (xy 369.354608 -250.774962) (xy 369.359434 -250.781312) (xy 369.37371 -250.801251)
			(xy 369.396393 -250.844727) (xy 369.411847 -250.891265) (xy 369.419675 -250.939673) (xy 369.42014 -250.964192)
			(xy 369.41967 -250.988185) (xy 369.412165 -251.035579) (xy 369.397339 -251.081216) (xy 369.375556 -251.123972)
			(xy 369.347353 -251.162795) (xy 369.313425 -251.196727) (xy 369.274606 -251.224935) (xy 369.231853 -251.246723)
			(xy 369.186218 -251.261556) (xy 369.138824 -251.269067) (xy 369.114832 -251.2695) (xy 369.103292 -251.26937)
			(xy 369.080281 -251.267587) (xy 369.068858 -251.265944) (xy 369.065048 -251.265436) (xy 369.064032 -251.265436)
			(xy 369.040406 -251.260977) (xy 368.99485 -251.245611) (xy 368.952268 -251.223292) (xy 368.932714 -251.209302)
			(xy 368.926364 -251.20473) (xy 368.904012 -251.196856) (xy 368.899694 -251.195526) (xy 368.89075 -251.194247)
			(xy 368.886232 -251.194316) (xy 368.86388 -251.194824) (xy 368.85452 -251.195486) (xy 368.837197 -251.202657)
			(xy 368.830098 -251.208794) (xy 368.82959 -251.209302) (xy 368.715544 -251.323348) (xy 368.711427 -251.327668)
			(xy 368.70514 -251.337807) (xy 368.703098 -251.343414) (xy 368.701203 -251.349913) (xy 368.700571 -251.363431)
			(xy 368.701828 -251.370084) (xy 368.717068 -251.439426) (xy 368.718618 -251.445556) (xy 368.724267 -251.456863)
			(xy 368.728244 -251.461778) (xy 368.746786 -251.483368) (xy 368.756184 -251.489972) (xy 368.761772 -251.492258)
			(xy 368.785286 -251.502602) (xy 368.828751 -251.529974) (xy 368.867023 -251.564234) (xy 368.899023 -251.604415)
			(xy 368.923847 -251.649384) (xy 368.940796 -251.697873) (xy 368.949392 -251.748515) (xy 368.949986 -251.774198)
			(xy 370.218982 -251.774198) (xy 370.222942 -251.725144) (xy 370.234719 -251.67736) (xy 370.25401 -251.632084)
			(xy 370.280313 -251.590488) (xy 370.312948 -251.553651) (xy 370.351069 -251.522526) (xy 370.39369 -251.497919)
			(xy 370.439706 -251.480467) (xy 370.487925 -251.470623) (xy 370.5371 -251.468642) (xy 370.585955 -251.474574)
			(xy 370.633226 -251.488266) (xy 370.677688 -251.509364) (xy 370.718191 -251.53732) (xy 370.753684 -251.571412)
			(xy 370.783249 -251.610756) (xy 370.80612 -251.654333) (xy 370.821704 -251.701014) (xy 370.829599 -251.749591)
			(xy 370.830094 -251.774198) (xy 370.829599 -251.798805) (xy 370.821704 -251.847382) (xy 370.80612 -251.894063)
			(xy 370.783249 -251.93764) (xy 370.753684 -251.976984) (xy 370.718191 -252.011076) (xy 370.677688 -252.039032)
			(xy 370.633226 -252.06013) (xy 370.585955 -252.073822) (xy 370.5371 -252.079754) (xy 370.487925 -252.077773)
			(xy 370.439706 -252.067929) (xy 370.39369 -252.050477) (xy 370.351069 -252.02587) (xy 370.312948 -251.994745)
			(xy 370.280313 -251.957908) (xy 370.25401 -251.916312) (xy 370.234719 -251.871036) (xy 370.222942 -251.823252)
			(xy 370.218982 -251.774198) (xy 368.949986 -251.774198) (xy 368.94954 -251.798191) (xy 368.942033 -251.845585)
			(xy 368.927205 -251.891222) (xy 368.905419 -251.933976) (xy 368.877213 -251.972797) (xy 368.843281 -252.006726)
			(xy 368.804459 -252.03493) (xy 368.761703 -252.056712) (xy 368.716066 -252.071538) (xy 368.668671 -252.079042)
			(xy 368.644678 -252.079506) (xy 368.618622 -252.078984) (xy 368.567266 -252.070149) (xy 368.518156 -252.052722)
			(xy 368.472717 -252.02721) (xy 368.43227 -251.994352) (xy 368.39799 -251.955105) (xy 368.370871 -251.910606)
			(xy 368.351702 -251.86215) (xy 368.341038 -251.811142) (xy 368.339624 -251.78512) (xy 368.33937 -251.7775)
			(xy 368.33937 -251.774198) (xy 368.339893 -251.747931) (xy 368.348842 -251.696167) (xy 368.366526 -251.646701)
			(xy 368.378994 -251.623576) (xy 368.385598 -251.611638) (xy 368.385598 -251.584968) (xy 368.33556 -251.499116)
			(xy 368.333274 -251.49556) (xy 368.326197 -251.486566) (xy 368.306281 -251.475353) (xy 368.29492 -251.47397)
			(xy 367.625376 -251.47397) (xy 367.615535 -251.473442) (xy 367.597365 -251.465863) (xy 367.59007 -251.459238)
			(xy 367.382806 -251.251974) (xy 367.354104 -251.245624) (xy 367.33988 -251.250704) (xy 367.314474 -251.259449)
			(xy 367.261586 -251.268903) (xy 367.234724 -251.2695) (xy 367.211189 -251.269073) (xy 367.164675 -251.261863)
			(xy 367.11982 -251.247595) (xy 367.077688 -251.226607) (xy 367.03928 -251.199398) (xy 367.005506 -251.166613)
			(xy 366.977168 -251.12903) (xy 366.954939 -251.08754) (xy 366.939345 -251.043129) (xy 366.930756 -250.996849)
			(xy 366.92967 -250.973336) (xy 366.929416 -250.972574) (xy 366.929416 -250.967494) (xy 366.929416 -250.964192)
			(xy 366.930003 -250.937329) (xy 366.939457 -250.88444) (xy 366.948212 -250.859036) (xy 366.953292 -250.844812)
			(xy 366.946942 -250.81611) (xy 366.744758 -250.613926) (xy 366.737646 -250.60656) (xy 366.71885 -250.59894)
			(xy 365.767366 -250.59894) (xy 365.757524 -250.599468) (xy 365.739348 -250.607039) (xy 365.73206 -250.613672)
			(xy 365.616744 -250.728988) (xy 365.615474 -250.730512) (xy 365.611833 -250.734582) (xy 365.606201 -250.743935)
			(xy 365.604298 -250.749054) (xy 365.602079 -250.75671) (xy 365.602072 -250.772642) (xy 365.604298 -250.780296)
			(xy 365.606838 -250.78817) (xy 365.612426 -250.800108) (xy 365.627364 -250.824845) (xy 365.648671 -250.878552)
			(xy 365.659528 -250.935302) (xy 365.660178 -250.964192) (xy 365.659732 -250.988185) (xy 365.652226 -251.035579)
			(xy 365.637398 -251.081216) (xy 365.615613 -251.123971) (xy 365.587407 -251.162792) (xy 365.553475 -251.196721)
			(xy 365.514652 -251.224924) (xy 365.471896 -251.246707) (xy 365.426258 -251.261532) (xy 365.378863 -251.269034)
			(xy 365.35487 -251.2695) (xy 365.333208 -251.269145) (xy 365.290315 -251.263057) (xy 365.248718 -251.25095)
			(xy 365.209257 -251.233071) (xy 365.190786 -251.221748) (xy 365.178848 -251.21616) (xy 365.170212 -251.213366)
			(xy 365.161669 -251.211208) (xy 365.144091 -251.212192) (xy 365.127883 -251.219067) (xy 365.12119 -251.224796)
			(xy 365.119666 -251.226066) (xy 365.00181 -251.343922) (xy 364.993868 -251.352827) (xy 364.986458 -251.375476)
			(xy 364.987586 -251.387356) (xy 365.001556 -251.478288) (xy 365.015526 -251.497846) (xy 365.026194 -251.503688)
			(xy 365.047034 -251.515102) (xy 365.085214 -251.543384) (xy 365.118553 -251.577236) (xy 365.146248 -251.615844)
			(xy 365.16763 -251.658274) (xy 365.182184 -251.703504) (xy 365.189557 -251.750441) (xy 365.190024 -251.774198)
			(xy 366.45902 -251.774198) (xy 366.46298 -251.725144) (xy 366.474757 -251.67736) (xy 366.494048 -251.632084)
			(xy 366.520351 -251.590488) (xy 366.552986 -251.553651) (xy 366.591107 -251.522526) (xy 366.633728 -251.497919)
			(xy 366.679744 -251.480467) (xy 366.727963 -251.470623) (xy 366.777138 -251.468642) (xy 366.825993 -251.474574)
			(xy 366.873264 -251.488266) (xy 366.917726 -251.509364) (xy 366.958229 -251.53732) (xy 366.993722 -251.571412)
			(xy 367.023287 -251.610756) (xy 367.046158 -251.654333) (xy 367.061742 -251.701014) (xy 367.069637 -251.749591)
			(xy 367.070132 -251.774198) (xy 367.069637 -251.798805) (xy 367.061742 -251.847382) (xy 367.046158 -251.894063)
			(xy 367.023287 -251.93764) (xy 366.993722 -251.976984) (xy 366.958229 -252.011076) (xy 366.917726 -252.039032)
			(xy 366.873264 -252.06013) (xy 366.825993 -252.073822) (xy 366.777138 -252.079754) (xy 366.727963 -252.077773)
			(xy 366.679744 -252.067929) (xy 366.633728 -252.050477) (xy 366.591107 -252.02587) (xy 366.552986 -251.994745)
			(xy 366.520351 -251.957908) (xy 366.494048 -251.916312) (xy 366.474757 -251.871036) (xy 366.46298 -251.823252)
			(xy 366.45902 -251.774198) (xy 365.190024 -251.774198) (xy 365.189554 -251.79819) (xy 365.182048 -251.845583)
			(xy 365.167221 -251.891218) (xy 365.145438 -251.933972) (xy 365.117235 -251.972792) (xy 365.083306 -252.006723)
			(xy 365.044487 -252.034928) (xy 365.001735 -252.056714) (xy 364.9561 -252.071544) (xy 364.908708 -252.079052)
			(xy 364.884716 -252.079506) (xy 364.858664 -252.078979) (xy 364.807316 -252.070135) (xy 364.758214 -252.052703)
			(xy 364.712785 -252.027188) (xy 364.672347 -251.99433) (xy 364.638075 -251.955084) (xy 364.610963 -251.91059)
			(xy 364.591798 -251.862138) (xy 364.581138 -251.811136) (xy 364.579662 -251.78512) (xy 364.579408 -251.7775)
			(xy 364.579408 -251.774198) (xy 364.579931 -251.747932) (xy 364.588881 -251.696168) (xy 364.606567 -251.646703)
			(xy 364.619032 -251.623576) (xy 364.625636 -251.611638) (xy 364.625636 -251.584968) (xy 364.575598 -251.499116)
			(xy 364.573312 -251.49556) (xy 364.56623 -251.486576) (xy 364.546312 -251.475387) (xy 364.534958 -251.47397)
			(xy 364.137956 -251.47397) (xy 364.128117 -251.473438) (xy 364.109952 -251.465854) (xy 364.10265 -251.459238)
			(xy 363.828076 -251.184664) (xy 363.820964 -251.177552) (xy 363.802676 -251.169678) (xy 363.723174 -251.168916)
			(xy 363.713324 -251.169331) (xy 363.695037 -251.176652) (xy 363.687614 -251.18314) (xy 363.68736 -251.183394)
			(xy 363.670159 -251.199449) (xy 363.631744 -251.226616) (xy 363.589619 -251.247575) (xy 363.544781 -251.261833)
			(xy 363.498287 -251.269052) (xy 363.474762 -251.2695) (xy 363.451036 -251.269047) (xy 363.404157 -251.261703)
			(xy 363.358978 -251.247195) (xy 363.316586 -251.225875) (xy 363.278002 -251.198254) (xy 363.244154 -251.164998)
			(xy 363.215857 -251.126908) (xy 363.193792 -251.084899) (xy 363.17849 -251.039982) (xy 363.170319 -250.99324)
			(xy 363.169454 -250.969526) (xy 363.169454 -250.964192) (xy 363.169885 -250.941493) (xy 363.176637 -250.896601)
			(xy 363.182916 -250.874784) (xy 363.183932 -250.871228) (xy 363.185202 -250.862592) (xy 363.186217 -250.85268)
			(xy 363.18151 -250.83334) (xy 363.176058 -250.825) (xy 363.129322 -250.760992) (xy 363.122293 -250.752362)
			(xy 363.102788 -250.741694) (xy 363.09173 -250.740418) (xy 363.088682 -250.740164) (xy 361.982512 -250.740164)
			(xy 361.97921 -250.740164) (xy 361.97794 -250.740418) (xy 361.966888 -250.741708) (xy 361.94739 -250.752377)
			(xy 361.940348 -250.760992) (xy 361.893612 -250.825) (xy 361.888122 -250.833326) (xy 361.883398 -250.852679)
			(xy 361.884468 -250.862592) (xy 361.885738 -250.871228) (xy 361.886754 -250.874784) (xy 361.893019 -250.896604)
			(xy 361.899772 -250.941495) (xy 361.900216 -250.964192) (xy 361.900216 -250.969526) (xy 361.899282 -250.994492)
			(xy 361.89029 -251.043634) (xy 361.873418 -251.090657) (xy 361.849118 -251.134306) (xy 361.818036 -251.173418)
			(xy 361.781002 -251.206948) (xy 361.739004 -251.234003) (xy 361.693162 -251.25386) (xy 361.644699 -251.26599)
			(xy 361.594908 -251.27007) (xy 361.545117 -251.26599) (xy 361.496654 -251.25386) (xy 361.450812 -251.234003)
			(xy 361.408814 -251.206948) (xy 361.37178 -251.173418) (xy 361.340698 -251.134306) (xy 361.316398 -251.090657)
			(xy 361.299526 -251.043634) (xy 361.290534 -250.994492) (xy 361.2896 -250.969526) (xy 361.2896 -250.964192)
			(xy 361.290031 -250.941494) (xy 361.296784 -250.896601) (xy 361.303062 -250.874784) (xy 361.304078 -250.871228)
			(xy 361.305348 -250.862592) (xy 361.306363 -250.852681) (xy 361.301652 -250.833342) (xy 361.296204 -250.825)
			(xy 361.249468 -250.760992) (xy 361.242442 -250.752355) (xy 361.222939 -250.741669) (xy 361.211876 -250.740418)
			(xy 361.208828 -250.740164) (xy 357.239316 -250.740164) (xy 357.236014 -250.740164) (xy 357.234998 -250.740418)
			(xy 357.225824 -250.741354) (xy 357.209018 -250.748907) (xy 357.202232 -250.75515) (xy 357.173784 -250.783598)
			(xy 357.16845 -250.815602) (xy 357.175562 -250.830334) (xy 357.185335 -250.851281) (xy 357.199144 -250.895391)
			(xy 357.20613 -250.941081) (xy 357.20655 -250.964192) (xy 357.20608 -250.988185) (xy 357.198575 -251.03558)
			(xy 357.183749 -251.081218) (xy 357.161967 -251.123975) (xy 357.133764 -251.162798) (xy 357.099836 -251.196732)
			(xy 357.061017 -251.22494) (xy 357.018264 -251.24673) (xy 356.972629 -251.261563) (xy 356.925235 -251.269076)
			(xy 356.901242 -251.2695) (xy 356.878134 -251.269051) (xy 356.832451 -251.26205) (xy 356.78834 -251.24826)
			(xy 356.767384 -251.238512) (xy 356.752652 -251.2314) (xy 356.720648 -251.236734) (xy 356.601776 -251.355606)
			(xy 356.594538 -251.362318) (xy 356.576332 -251.369909) (xy 356.56647 -251.370338) (xy 356.347776 -251.370338)
			(xy 356.342696 -251.375164) (xy 355.765354 -251.375164) (xy 355.753599 -251.37576) (xy 355.732549 -251.386226)
			(xy 355.724968 -251.39523) (xy 355.721213 -251.40031) (xy 359.872791 -251.40031) (xy 359.876821 -251.347812)
			(xy 359.888818 -251.296544) (xy 359.908501 -251.247709) (xy 359.935407 -251.20245) (xy 359.968907 -251.161829)
			(xy 360.008215 -251.126798) (xy 360.05241 -251.098178) (xy 360.100455 -251.076639) (xy 360.151226 -251.062687)
			(xy 360.203531 -251.056649) (xy 360.256145 -251.058666) (xy 360.307835 -251.06869) (xy 360.357388 -251.086488)
			(xy 360.403644 -251.111641) (xy 360.445518 -251.14356) (xy 360.48203 -251.181498) (xy 360.512322 -251.224564)
			(xy 360.535685 -251.271749) (xy 360.551571 -251.321948) (xy 360.559608 -251.373984) (xy 360.560112 -251.40031)
			(xy 360.559608 -251.426636) (xy 360.551571 -251.478672) (xy 360.535685 -251.528871) (xy 360.512322 -251.576056)
			(xy 360.48203 -251.619122) (xy 360.445518 -251.65706) (xy 360.403644 -251.688979) (xy 360.357388 -251.714132)
			(xy 360.307835 -251.73193) (xy 360.256145 -251.741954) (xy 360.203531 -251.743971) (xy 360.151226 -251.737933)
			(xy 360.100455 -251.723981) (xy 360.05241 -251.702442) (xy 360.008215 -251.673822) (xy 359.968907 -251.638791)
			(xy 359.935407 -251.59817) (xy 359.908501 -251.552911) (xy 359.888818 -251.504076) (xy 359.876821 -251.452808)
			(xy 359.872791 -251.40031) (xy 355.721213 -251.40031) (xy 355.72065 -251.401072) (xy 355.678994 -251.508514)
			(xy 355.686106 -251.53874) (xy 355.69779 -251.549408) (xy 355.716049 -251.566891) (xy 355.74709 -251.606786)
			(xy 355.77114 -251.651247) (xy 355.787542 -251.699061) (xy 355.795849 -251.748923) (xy 355.796342 -251.774198)
			(xy 357.065338 -251.774198) (xy 357.069298 -251.725144) (xy 357.081075 -251.67736) (xy 357.100366 -251.632084)
			(xy 357.126669 -251.590488) (xy 357.159304 -251.553651) (xy 357.197425 -251.522526) (xy 357.240046 -251.497919)
			(xy 357.286062 -251.480467) (xy 357.334281 -251.470623) (xy 357.383456 -251.468642) (xy 357.432311 -251.474574)
			(xy 357.479582 -251.488266) (xy 357.524044 -251.509364) (xy 357.564547 -251.53732) (xy 357.60004 -251.571412)
			(xy 357.629605 -251.610756) (xy 357.652476 -251.654333) (xy 357.66806 -251.701014) (xy 357.675955 -251.749591)
			(xy 357.67645 -251.774198) (xy 360.81895 -251.774198) (xy 360.82291 -251.725144) (xy 360.834687 -251.67736)
			(xy 360.853978 -251.632084) (xy 360.880281 -251.590488) (xy 360.912916 -251.553651) (xy 360.951037 -251.522526)
			(xy 360.993658 -251.497919) (xy 361.039674 -251.480467) (xy 361.087893 -251.470623) (xy 361.137068 -251.468642)
			(xy 361.185923 -251.474574) (xy 361.233194 -251.488266) (xy 361.277656 -251.509364) (xy 361.318159 -251.53732)
			(xy 361.353652 -251.571412) (xy 361.383217 -251.610756) (xy 361.406088 -251.654333) (xy 361.421672 -251.701014)
			(xy 361.429567 -251.749591) (xy 361.430062 -251.774198) (xy 362.699058 -251.774198) (xy 362.703018 -251.725144)
			(xy 362.714795 -251.67736) (xy 362.734086 -251.632084) (xy 362.760389 -251.590488) (xy 362.793024 -251.553651)
			(xy 362.831145 -251.522526) (xy 362.873766 -251.497919) (xy 362.919782 -251.480467) (xy 362.968001 -251.470623)
			(xy 363.017176 -251.468642) (xy 363.066031 -251.474574) (xy 363.113302 -251.488266) (xy 363.157764 -251.509364)
			(xy 363.198267 -251.53732) (xy 363.23376 -251.571412) (xy 363.263325 -251.610756) (xy 363.286196 -251.654333)
			(xy 363.30178 -251.701014) (xy 363.309675 -251.749591) (xy 363.31017 -251.774198) (xy 363.309675 -251.798805)
			(xy 363.30178 -251.847382) (xy 363.286196 -251.894063) (xy 363.263325 -251.93764) (xy 363.23376 -251.976984)
			(xy 363.198267 -252.011076) (xy 363.157764 -252.039032) (xy 363.113302 -252.06013) (xy 363.066031 -252.073822)
			(xy 363.017176 -252.079754) (xy 362.968001 -252.077773) (xy 362.919782 -252.067929) (xy 362.873766 -252.050477)
			(xy 362.831145 -252.02587) (xy 362.793024 -251.994745) (xy 362.760389 -251.957908) (xy 362.734086 -251.916312)
			(xy 362.714795 -251.871036) (xy 362.703018 -251.823252) (xy 362.699058 -251.774198) (xy 361.430062 -251.774198)
			(xy 361.429567 -251.798805) (xy 361.421672 -251.847382) (xy 361.406088 -251.894063) (xy 361.383217 -251.93764)
			(xy 361.353652 -251.976984) (xy 361.318159 -252.011076) (xy 361.277656 -252.039032) (xy 361.233194 -252.06013)
			(xy 361.185923 -252.073822) (xy 361.137068 -252.079754) (xy 361.087893 -252.077773) (xy 361.039674 -252.067929)
			(xy 360.993658 -252.050477) (xy 360.951037 -252.02587) (xy 360.912916 -251.994745) (xy 360.880281 -251.957908)
			(xy 360.853978 -251.916312) (xy 360.834687 -251.871036) (xy 360.82291 -251.823252) (xy 360.81895 -251.774198)
			(xy 357.67645 -251.774198) (xy 357.675955 -251.798805) (xy 357.66806 -251.847382) (xy 357.652476 -251.894063)
			(xy 357.629605 -251.93764) (xy 357.60004 -251.976984) (xy 357.564547 -252.011076) (xy 357.524044 -252.039032)
			(xy 357.479582 -252.06013) (xy 357.432311 -252.073822) (xy 357.383456 -252.079754) (xy 357.334281 -252.077773)
			(xy 357.286062 -252.067929) (xy 357.240046 -252.050477) (xy 357.197425 -252.02587) (xy 357.159304 -251.994745)
			(xy 357.126669 -251.957908) (xy 357.100366 -251.916312) (xy 357.081075 -251.871036) (xy 357.069298 -251.823252)
			(xy 357.065338 -251.774198) (xy 355.796342 -251.774198) (xy 355.79582 -251.799453) (xy 355.787507 -251.849275)
			(xy 355.771106 -251.897049) (xy 355.747065 -251.941472) (xy 355.716041 -251.981332) (xy 355.678879 -252.015542)
			(xy 355.636593 -252.043168) (xy 355.590337 -252.063458) (xy 355.541372 -252.075858) (xy 355.491034 -252.080029)
			(xy 355.440696 -252.075858) (xy 355.391731 -252.063458) (xy 355.345475 -252.043168) (xy 355.303189 -252.015542)
			(xy 355.266027 -251.981332) (xy 355.235003 -251.941472) (xy 355.210962 -251.897049) (xy 355.194561 -251.849275)
			(xy 355.186248 -251.799453) (xy 355.185726 -251.774198) (xy 355.186247 -251.748926) (xy 355.194562 -251.699071)
			(xy 355.210965 -251.651264) (xy 355.235009 -251.606806) (xy 355.266039 -251.566909) (xy 355.284278 -251.549408)
			(xy 355.295962 -251.53874) (xy 355.303074 -251.508514) (xy 355.263958 -251.407676) (xy 355.260509 -251.399729)
			(xy 355.249206 -251.386615) (xy 355.24186 -251.382022) (xy 355.230176 -251.375164) (xy 353.8855 -251.375164)
			(xy 353.87374 -251.375751) (xy 353.852674 -251.386205) (xy 353.845114 -251.39523) (xy 353.840796 -251.401072)
			(xy 353.79914 -251.508514) (xy 353.806252 -251.53874) (xy 353.817936 -251.549408) (xy 353.836192 -251.566893)
			(xy 353.86723 -251.606789) (xy 353.891276 -251.65125) (xy 353.907675 -251.699064) (xy 353.91598 -251.748924)
			(xy 353.916488 -251.774198) (xy 353.915966 -251.799453) (xy 353.907653 -251.849275) (xy 353.891252 -251.897049)
			(xy 353.867211 -251.941472) (xy 353.836187 -251.981332) (xy 353.799025 -252.015542) (xy 353.756739 -252.043168)
			(xy 353.710483 -252.063458) (xy 353.661518 -252.075858) (xy 353.61118 -252.080029) (xy 353.560842 -252.075858)
			(xy 353.511877 -252.063458) (xy 353.465621 -252.043168) (xy 353.423335 -252.015542) (xy 353.386173 -251.981332)
			(xy 353.355149 -251.941472) (xy 353.331108 -251.897049) (xy 353.314707 -251.849275) (xy 353.306394 -251.799453)
			(xy 353.305872 -251.774198) (xy 353.306393 -251.748926) (xy 353.314707 -251.69907) (xy 353.331107 -251.65126)
			(xy 353.355149 -251.606799) (xy 353.386175 -251.566898) (xy 353.404424 -251.549408) (xy 353.416108 -251.53874)
			(xy 353.42322 -251.508514) (xy 353.384104 -251.407676) (xy 353.380658 -251.399726) (xy 353.369361 -251.386603)
			(xy 353.362006 -251.382022) (xy 353.350322 -251.375164) (xy 352.005392 -251.375164) (xy 351.993633 -251.375752)
			(xy 351.97257 -251.386208) (xy 351.965006 -251.39523) (xy 351.960688 -251.401072) (xy 351.919032 -251.508514)
			(xy 351.926144 -251.53874) (xy 351.937828 -251.549408) (xy 351.956085 -251.566892) (xy 351.987123 -251.606789)
			(xy 352.01117 -251.65125) (xy 352.027569 -251.699063) (xy 352.035874 -251.748924) (xy 352.03638 -251.774198)
			(xy 352.035858 -251.799453) (xy 352.027545 -251.849275) (xy 352.011144 -251.897049) (xy 351.987103 -251.941472)
			(xy 351.956079 -251.981332) (xy 351.918917 -252.015542) (xy 351.876631 -252.043168) (xy 351.830375 -252.063458)
			(xy 351.78141 -252.075858) (xy 351.731072 -252.080029) (xy 351.680734 -252.075858) (xy 351.631769 -252.063458)
			(xy 351.585513 -252.043168) (xy 351.543227 -252.015542) (xy 351.506065 -251.981332) (xy 351.475041 -251.941472)
			(xy 351.451 -251.897049) (xy 351.434599 -251.849275) (xy 351.426286 -251.799453) (xy 351.425764 -251.774198)
			(xy 351.426285 -251.748926) (xy 351.434598 -251.699069) (xy 351.450999 -251.65126) (xy 351.47504 -251.606798)
			(xy 351.506066 -251.566897) (xy 351.524316 -251.549408) (xy 351.536 -251.53874) (xy 351.543112 -251.508514)
			(xy 351.503996 -251.407676) (xy 351.500549 -251.399726) (xy 351.489251 -251.386605) (xy 351.481898 -251.382022)
			(xy 351.470214 -251.375164) (xy 350.735392 -251.375164) (xy 350.73209 -251.375164) (xy 350.731074 -251.375418)
			(xy 350.721902 -251.376358) (xy 350.705102 -251.383917) (xy 350.698308 -251.39015) (xy 350.604074 -251.484638)
			(xy 350.597366 -251.491878) (xy 350.589784 -251.510083) (xy 350.589342 -251.519944) (xy 350.589342 -251.807218)
			(xy 350.589801 -251.817096) (xy 350.597238 -251.8354) (xy 350.60382 -251.842778) (xy 350.604074 -251.843032)
			(xy 351.177352 -252.41631) (xy 359.853741 -252.41631) (xy 359.857771 -252.363812) (xy 359.869768 -252.312544)
			(xy 359.889451 -252.263709) (xy 359.916357 -252.21845) (xy 359.949857 -252.177829) (xy 359.989165 -252.142798)
			(xy 360.03336 -252.114178) (xy 360.081405 -252.092639) (xy 360.132176 -252.078687) (xy 360.184481 -252.072649)
			(xy 360.237095 -252.074666) (xy 360.288785 -252.08469) (xy 360.338338 -252.102488) (xy 360.384594 -252.127641)
			(xy 360.426468 -252.15956) (xy 360.46298 -252.197498) (xy 360.493272 -252.240564) (xy 360.516635 -252.287749)
			(xy 360.532521 -252.337948) (xy 360.540558 -252.389984) (xy 360.541062 -252.41631) (xy 360.540558 -252.442636)
			(xy 360.532521 -252.494672) (xy 360.516635 -252.544871) (xy 360.49716 -252.584204) (xy 368.809028 -252.584204)
			(xy 368.812988 -252.53515) (xy 368.824765 -252.487366) (xy 368.844056 -252.44209) (xy 368.870359 -252.400494)
			(xy 368.902994 -252.363657) (xy 368.941115 -252.332532) (xy 368.983736 -252.307925) (xy 369.029752 -252.290473)
			(xy 369.077971 -252.280629) (xy 369.127146 -252.278648) (xy 369.176001 -252.28458) (xy 369.223272 -252.298272)
			(xy 369.267734 -252.31937) (xy 369.308237 -252.347326) (xy 369.34373 -252.381418) (xy 369.373295 -252.420762)
			(xy 369.396166 -252.464339) (xy 369.41175 -252.51102) (xy 369.419645 -252.559597) (xy 369.42014 -252.584204)
			(xy 370.688882 -252.584204) (xy 370.692842 -252.53515) (xy 370.704619 -252.487366) (xy 370.72391 -252.44209)
			(xy 370.750213 -252.400494) (xy 370.782848 -252.363657) (xy 370.820969 -252.332532) (xy 370.86359 -252.307925)
			(xy 370.909606 -252.290473) (xy 370.957825 -252.280629) (xy 371.007 -252.278648) (xy 371.055855 -252.28458)
			(xy 371.103126 -252.298272) (xy 371.147588 -252.31937) (xy 371.188091 -252.347326) (xy 371.223584 -252.381418)
			(xy 371.253149 -252.420762) (xy 371.27602 -252.464339) (xy 371.291604 -252.51102) (xy 371.299499 -252.559597)
			(xy 371.299994 -252.584204) (xy 372.56899 -252.584204) (xy 372.57295 -252.53515) (xy 372.584727 -252.487366)
			(xy 372.604018 -252.44209) (xy 372.630321 -252.400494) (xy 372.662956 -252.363657) (xy 372.701077 -252.332532)
			(xy 372.743698 -252.307925) (xy 372.789714 -252.290473) (xy 372.837933 -252.280629) (xy 372.887108 -252.278648)
			(xy 372.935963 -252.28458) (xy 372.983234 -252.298272) (xy 373.027696 -252.31937) (xy 373.068199 -252.347326)
			(xy 373.103692 -252.381418) (xy 373.133257 -252.420762) (xy 373.156128 -252.464339) (xy 373.171712 -252.51102)
			(xy 373.179607 -252.559597) (xy 373.180102 -252.584204) (xy 374.449098 -252.584204) (xy 374.453058 -252.53515)
			(xy 374.464835 -252.487366) (xy 374.484126 -252.44209) (xy 374.510429 -252.400494) (xy 374.543064 -252.363657)
			(xy 374.581185 -252.332532) (xy 374.623806 -252.307925) (xy 374.669822 -252.290473) (xy 374.718041 -252.280629)
			(xy 374.767216 -252.278648) (xy 374.816071 -252.28458) (xy 374.863342 -252.298272) (xy 374.907804 -252.31937)
			(xy 374.948307 -252.347326) (xy 374.9838 -252.381418) (xy 375.013365 -252.420762) (xy 375.036236 -252.464339)
			(xy 375.05182 -252.51102) (xy 375.059715 -252.559597) (xy 375.06021 -252.584204) (xy 375.388898 -252.584204)
			(xy 375.392858 -252.53515) (xy 375.404635 -252.487366) (xy 375.423926 -252.44209) (xy 375.450229 -252.400494)
			(xy 375.482864 -252.363657) (xy 375.520985 -252.332532) (xy 375.563606 -252.307925) (xy 375.609622 -252.290473)
			(xy 375.657841 -252.280629) (xy 375.707016 -252.278648) (xy 375.755871 -252.28458) (xy 375.803142 -252.298272)
			(xy 375.847604 -252.31937) (xy 375.888107 -252.347326) (xy 375.9236 -252.381418) (xy 375.953165 -252.420762)
			(xy 375.976036 -252.464339) (xy 375.99162 -252.51102) (xy 375.999515 -252.559597) (xy 376.00001 -252.584204)
			(xy 376.328952 -252.584204) (xy 376.332912 -252.53515) (xy 376.344689 -252.487366) (xy 376.36398 -252.44209)
			(xy 376.390283 -252.400494) (xy 376.422918 -252.363657) (xy 376.461039 -252.332532) (xy 376.50366 -252.307925)
			(xy 376.549676 -252.290473) (xy 376.597895 -252.280629) (xy 376.64707 -252.278648) (xy 376.695925 -252.28458)
			(xy 376.743196 -252.298272) (xy 376.787658 -252.31937) (xy 376.828161 -252.347326) (xy 376.863654 -252.381418)
			(xy 376.893219 -252.420762) (xy 376.91609 -252.464339) (xy 376.931674 -252.51102) (xy 376.939569 -252.559597)
			(xy 376.940064 -252.584204) (xy 377.258575 -252.584204) (xy 377.26267 -252.533476) (xy 377.274849 -252.484062)
			(xy 377.294797 -252.437242) (xy 377.321998 -252.394228) (xy 377.355746 -252.356134) (xy 377.395168 -252.323947)
			(xy 377.439242 -252.298501) (xy 377.486828 -252.280454) (xy 377.536692 -252.270274) (xy 377.587544 -252.268225)
			(xy 377.638065 -252.274359) (xy 377.686949 -252.288519) (xy 377.732928 -252.310336) (xy 377.774812 -252.339246)
			(xy 377.811516 -252.374501) (xy 377.842089 -252.415187) (xy 377.86574 -252.46025) (xy 377.881856 -252.508524)
			(xy 377.89002 -252.558758) (xy 377.890532 -252.584204) (xy 378.20906 -252.584204) (xy 378.21302 -252.53515)
			(xy 378.224797 -252.487366) (xy 378.244088 -252.44209) (xy 378.270391 -252.400494) (xy 378.303026 -252.363657)
			(xy 378.341147 -252.332532) (xy 378.383768 -252.307925) (xy 378.429784 -252.290473) (xy 378.478003 -252.280629)
			(xy 378.527178 -252.278648) (xy 378.576033 -252.28458) (xy 378.623304 -252.298272) (xy 378.667766 -252.31937)
			(xy 378.708269 -252.347326) (xy 378.743762 -252.381418) (xy 378.773327 -252.420762) (xy 378.796198 -252.464339)
			(xy 378.811782 -252.51102) (xy 378.819677 -252.559597) (xy 378.820172 -252.584204) (xy 379.149114 -252.584204)
			(xy 379.153074 -252.53515) (xy 379.164851 -252.487366) (xy 379.184142 -252.44209) (xy 379.210445 -252.400494)
			(xy 379.24308 -252.363657) (xy 379.281201 -252.332532) (xy 379.323822 -252.307925) (xy 379.369838 -252.290473)
			(xy 379.418057 -252.280629) (xy 379.467232 -252.278648) (xy 379.516087 -252.28458) (xy 379.563358 -252.298272)
			(xy 379.60782 -252.31937) (xy 379.648323 -252.347326) (xy 379.683816 -252.381418) (xy 379.713381 -252.420762)
			(xy 379.736252 -252.464339) (xy 379.751836 -252.51102) (xy 379.759731 -252.559597) (xy 379.760226 -252.584204)
			(xy 380.078483 -252.584204) (xy 380.082578 -252.533476) (xy 380.094757 -252.484062) (xy 380.114705 -252.437242)
			(xy 380.141906 -252.394228) (xy 380.175654 -252.356134) (xy 380.215076 -252.323947) (xy 380.25915 -252.298501)
			(xy 380.306736 -252.280454) (xy 380.3566 -252.270274) (xy 380.407452 -252.268225) (xy 380.457973 -252.274359)
			(xy 380.506857 -252.288519) (xy 380.552836 -252.310336) (xy 380.59472 -252.339246) (xy 380.631424 -252.374501)
			(xy 380.661997 -252.415187) (xy 380.685648 -252.46025) (xy 380.701764 -252.508524) (xy 380.709928 -252.558758)
			(xy 380.71044 -252.584204) (xy 381.028968 -252.584204) (xy 381.032928 -252.53515) (xy 381.044705 -252.487366)
			(xy 381.063996 -252.44209) (xy 381.090299 -252.400494) (xy 381.122934 -252.363657) (xy 381.161055 -252.332532)
			(xy 381.203676 -252.307925) (xy 381.249692 -252.290473) (xy 381.297911 -252.280629) (xy 381.347086 -252.278648)
			(xy 381.395941 -252.28458) (xy 381.443212 -252.298272) (xy 381.487674 -252.31937) (xy 381.528177 -252.347326)
			(xy 381.56367 -252.381418) (xy 381.593235 -252.420762) (xy 381.616106 -252.464339) (xy 381.63169 -252.51102)
			(xy 381.639585 -252.559597) (xy 381.64008 -252.584204) (xy 381.969022 -252.584204) (xy 381.972982 -252.53515)
			(xy 381.984759 -252.487366) (xy 382.00405 -252.44209) (xy 382.030353 -252.400494) (xy 382.062988 -252.363657)
			(xy 382.101109 -252.332532) (xy 382.14373 -252.307925) (xy 382.189746 -252.290473) (xy 382.237965 -252.280629)
			(xy 382.28714 -252.278648) (xy 382.335995 -252.28458) (xy 382.383266 -252.298272) (xy 382.427728 -252.31937)
			(xy 382.468231 -252.347326) (xy 382.503724 -252.381418) (xy 382.533289 -252.420762) (xy 382.55616 -252.464339)
			(xy 382.571744 -252.51102) (xy 382.579639 -252.559597) (xy 382.580134 -252.584204) (xy 382.909076 -252.584204)
			(xy 382.913036 -252.53515) (xy 382.924813 -252.487366) (xy 382.944104 -252.44209) (xy 382.970407 -252.400494)
			(xy 383.003042 -252.363657) (xy 383.041163 -252.332532) (xy 383.083784 -252.307925) (xy 383.1298 -252.290473)
			(xy 383.178019 -252.280629) (xy 383.227194 -252.278648) (xy 383.276049 -252.28458) (xy 383.32332 -252.298272)
			(xy 383.367782 -252.31937) (xy 383.408285 -252.347326) (xy 383.443778 -252.381418) (xy 383.473343 -252.420762)
			(xy 383.496214 -252.464339) (xy 383.511798 -252.51102) (xy 383.519693 -252.559597) (xy 383.520188 -252.584204)
			(xy 383.84913 -252.584204) (xy 383.85309 -252.53515) (xy 383.864867 -252.487366) (xy 383.884158 -252.44209)
			(xy 383.910461 -252.400494) (xy 383.943096 -252.363657) (xy 383.981217 -252.332532) (xy 384.023838 -252.307925)
			(xy 384.069854 -252.290473) (xy 384.118073 -252.280629) (xy 384.167248 -252.278648) (xy 384.216103 -252.28458)
			(xy 384.263374 -252.298272) (xy 384.307836 -252.31937) (xy 384.348339 -252.347326) (xy 384.383832 -252.381418)
			(xy 384.413397 -252.420762) (xy 384.436268 -252.464339) (xy 384.451852 -252.51102) (xy 384.459747 -252.559597)
			(xy 384.460242 -252.584204) (xy 384.78893 -252.584204) (xy 384.79289 -252.53515) (xy 384.804667 -252.487366)
			(xy 384.823958 -252.44209) (xy 384.850261 -252.400494) (xy 384.882896 -252.363657) (xy 384.921017 -252.332532)
			(xy 384.963638 -252.307925) (xy 385.009654 -252.290473) (xy 385.057873 -252.280629) (xy 385.107048 -252.278648)
			(xy 385.155903 -252.28458) (xy 385.203174 -252.298272) (xy 385.247636 -252.31937) (xy 385.288139 -252.347326)
			(xy 385.323632 -252.381418) (xy 385.353197 -252.420762) (xy 385.376068 -252.464339) (xy 385.391652 -252.51102)
			(xy 385.399547 -252.559597) (xy 385.400042 -252.584204) (xy 385.728984 -252.584204) (xy 385.732944 -252.53515)
			(xy 385.744721 -252.487366) (xy 385.764012 -252.44209) (xy 385.790315 -252.400494) (xy 385.82295 -252.363657)
			(xy 385.861071 -252.332532) (xy 385.903692 -252.307925) (xy 385.949708 -252.290473) (xy 385.997927 -252.280629)
			(xy 386.047102 -252.278648) (xy 386.095957 -252.28458) (xy 386.143228 -252.298272) (xy 386.18769 -252.31937)
			(xy 386.228193 -252.347326) (xy 386.263686 -252.381418) (xy 386.293251 -252.420762) (xy 386.316122 -252.464339)
			(xy 386.331706 -252.51102) (xy 386.339601 -252.559597) (xy 386.340096 -252.584204) (xy 386.669038 -252.584204)
			(xy 386.672998 -252.53515) (xy 386.684775 -252.487366) (xy 386.704066 -252.44209) (xy 386.730369 -252.400494)
			(xy 386.763004 -252.363657) (xy 386.801125 -252.332532) (xy 386.843746 -252.307925) (xy 386.889762 -252.290473)
			(xy 386.937981 -252.280629) (xy 386.987156 -252.278648) (xy 387.036011 -252.28458) (xy 387.083282 -252.298272)
			(xy 387.127744 -252.31937) (xy 387.168247 -252.347326) (xy 387.20374 -252.381418) (xy 387.233305 -252.420762)
			(xy 387.256176 -252.464339) (xy 387.27176 -252.51102) (xy 387.279655 -252.559597) (xy 387.28015 -252.584204)
			(xy 387.609092 -252.584204) (xy 387.613052 -252.53515) (xy 387.624829 -252.487366) (xy 387.64412 -252.44209)
			(xy 387.670423 -252.400494) (xy 387.703058 -252.363657) (xy 387.741179 -252.332532) (xy 387.7838 -252.307925)
			(xy 387.829816 -252.290473) (xy 387.878035 -252.280629) (xy 387.92721 -252.278648) (xy 387.976065 -252.28458)
			(xy 388.023336 -252.298272) (xy 388.067798 -252.31937) (xy 388.108301 -252.347326) (xy 388.143794 -252.381418)
			(xy 388.173359 -252.420762) (xy 388.19623 -252.464339) (xy 388.211814 -252.51102) (xy 388.219709 -252.559597)
			(xy 388.220204 -252.584204) (xy 388.219709 -252.608811) (xy 388.211814 -252.657388) (xy 388.19623 -252.704069)
			(xy 388.173359 -252.747646) (xy 388.143794 -252.78699) (xy 388.108301 -252.821082) (xy 388.067798 -252.849038)
			(xy 388.023336 -252.870136) (xy 387.976065 -252.883828) (xy 387.92721 -252.88976) (xy 387.878035 -252.887779)
			(xy 387.829816 -252.877935) (xy 387.7838 -252.860483) (xy 387.741179 -252.835876) (xy 387.703058 -252.804751)
			(xy 387.670423 -252.767914) (xy 387.64412 -252.726318) (xy 387.624829 -252.681042) (xy 387.613052 -252.633258)
			(xy 387.609092 -252.584204) (xy 387.28015 -252.584204) (xy 387.279655 -252.608811) (xy 387.27176 -252.657388)
			(xy 387.256176 -252.704069) (xy 387.233305 -252.747646) (xy 387.20374 -252.78699) (xy 387.168247 -252.821082)
			(xy 387.127744 -252.849038) (xy 387.083282 -252.870136) (xy 387.036011 -252.883828) (xy 386.987156 -252.88976)
			(xy 386.937981 -252.887779) (xy 386.889762 -252.877935) (xy 386.843746 -252.860483) (xy 386.801125 -252.835876)
			(xy 386.763004 -252.804751) (xy 386.730369 -252.767914) (xy 386.704066 -252.726318) (xy 386.684775 -252.681042)
			(xy 386.672998 -252.633258) (xy 386.669038 -252.584204) (xy 386.340096 -252.584204) (xy 386.339601 -252.608811)
			(xy 386.331706 -252.657388) (xy 386.316122 -252.704069) (xy 386.293251 -252.747646) (xy 386.263686 -252.78699)
			(xy 386.228193 -252.821082) (xy 386.18769 -252.849038) (xy 386.143228 -252.870136) (xy 386.095957 -252.883828)
			(xy 386.047102 -252.88976) (xy 385.997927 -252.887779) (xy 385.949708 -252.877935) (xy 385.903692 -252.860483)
			(xy 385.861071 -252.835876) (xy 385.82295 -252.804751) (xy 385.790315 -252.767914) (xy 385.764012 -252.726318)
			(xy 385.744721 -252.681042) (xy 385.732944 -252.633258) (xy 385.728984 -252.584204) (xy 385.400042 -252.584204)
			(xy 385.399547 -252.608811) (xy 385.391652 -252.657388) (xy 385.376068 -252.704069) (xy 385.353197 -252.747646)
			(xy 385.323632 -252.78699) (xy 385.288139 -252.821082) (xy 385.247636 -252.849038) (xy 385.203174 -252.870136)
			(xy 385.155903 -252.883828) (xy 385.107048 -252.88976) (xy 385.057873 -252.887779) (xy 385.009654 -252.877935)
			(xy 384.963638 -252.860483) (xy 384.921017 -252.835876) (xy 384.882896 -252.804751) (xy 384.850261 -252.767914)
			(xy 384.823958 -252.726318) (xy 384.804667 -252.681042) (xy 384.79289 -252.633258) (xy 384.78893 -252.584204)
			(xy 384.460242 -252.584204) (xy 384.459747 -252.608811) (xy 384.451852 -252.657388) (xy 384.436268 -252.704069)
			(xy 384.413397 -252.747646) (xy 384.383832 -252.78699) (xy 384.348339 -252.821082) (xy 384.307836 -252.849038)
			(xy 384.263374 -252.870136) (xy 384.216103 -252.883828) (xy 384.167248 -252.88976) (xy 384.118073 -252.887779)
			(xy 384.069854 -252.877935) (xy 384.023838 -252.860483) (xy 383.981217 -252.835876) (xy 383.943096 -252.804751)
			(xy 383.910461 -252.767914) (xy 383.884158 -252.726318) (xy 383.864867 -252.681042) (xy 383.85309 -252.633258)
			(xy 383.84913 -252.584204) (xy 383.520188 -252.584204) (xy 383.519693 -252.608811) (xy 383.511798 -252.657388)
			(xy 383.496214 -252.704069) (xy 383.473343 -252.747646) (xy 383.443778 -252.78699) (xy 383.408285 -252.821082)
			(xy 383.367782 -252.849038) (xy 383.32332 -252.870136) (xy 383.276049 -252.883828) (xy 383.227194 -252.88976)
			(xy 383.178019 -252.887779) (xy 383.1298 -252.877935) (xy 383.083784 -252.860483) (xy 383.041163 -252.835876)
			(xy 383.003042 -252.804751) (xy 382.970407 -252.767914) (xy 382.944104 -252.726318) (xy 382.924813 -252.681042)
			(xy 382.913036 -252.633258) (xy 382.909076 -252.584204) (xy 382.580134 -252.584204) (xy 382.579639 -252.608811)
			(xy 382.571744 -252.657388) (xy 382.55616 -252.704069) (xy 382.533289 -252.747646) (xy 382.503724 -252.78699)
			(xy 382.468231 -252.821082) (xy 382.427728 -252.849038) (xy 382.383266 -252.870136) (xy 382.335995 -252.883828)
			(xy 382.28714 -252.88976) (xy 382.237965 -252.887779) (xy 382.189746 -252.877935) (xy 382.14373 -252.860483)
			(xy 382.101109 -252.835876) (xy 382.062988 -252.804751) (xy 382.030353 -252.767914) (xy 382.00405 -252.726318)
			(xy 381.984759 -252.681042) (xy 381.972982 -252.633258) (xy 381.969022 -252.584204) (xy 381.64008 -252.584204)
			(xy 381.639585 -252.608811) (xy 381.63169 -252.657388) (xy 381.616106 -252.704069) (xy 381.593235 -252.747646)
			(xy 381.56367 -252.78699) (xy 381.528177 -252.821082) (xy 381.487674 -252.849038) (xy 381.443212 -252.870136)
			(xy 381.395941 -252.883828) (xy 381.347086 -252.88976) (xy 381.297911 -252.887779) (xy 381.249692 -252.877935)
			(xy 381.203676 -252.860483) (xy 381.161055 -252.835876) (xy 381.122934 -252.804751) (xy 381.090299 -252.767914)
			(xy 381.063996 -252.726318) (xy 381.044705 -252.681042) (xy 381.032928 -252.633258) (xy 381.028968 -252.584204)
			(xy 380.71044 -252.584204) (xy 380.709928 -252.60965) (xy 380.701764 -252.659884) (xy 380.685648 -252.708158)
			(xy 380.661997 -252.753221) (xy 380.631424 -252.793907) (xy 380.59472 -252.829162) (xy 380.552836 -252.858072)
			(xy 380.506857 -252.879889) (xy 380.457973 -252.894049) (xy 380.407452 -252.900183) (xy 380.3566 -252.898134)
			(xy 380.306736 -252.887954) (xy 380.25915 -252.869907) (xy 380.215076 -252.844461) (xy 380.175654 -252.812274)
			(xy 380.141906 -252.77418) (xy 380.114705 -252.731166) (xy 380.094757 -252.684346) (xy 380.082578 -252.634932)
			(xy 380.078483 -252.584204) (xy 379.760226 -252.584204) (xy 379.759731 -252.608811) (xy 379.751836 -252.657388)
			(xy 379.736252 -252.704069) (xy 379.713381 -252.747646) (xy 379.683816 -252.78699) (xy 379.648323 -252.821082)
			(xy 379.60782 -252.849038) (xy 379.563358 -252.870136) (xy 379.516087 -252.883828) (xy 379.467232 -252.88976)
			(xy 379.418057 -252.887779) (xy 379.369838 -252.877935) (xy 379.323822 -252.860483) (xy 379.281201 -252.835876)
			(xy 379.24308 -252.804751) (xy 379.210445 -252.767914) (xy 379.184142 -252.726318) (xy 379.164851 -252.681042)
			(xy 379.153074 -252.633258) (xy 379.149114 -252.584204) (xy 378.820172 -252.584204) (xy 378.819677 -252.608811)
			(xy 378.811782 -252.657388) (xy 378.796198 -252.704069) (xy 378.773327 -252.747646) (xy 378.743762 -252.78699)
			(xy 378.708269 -252.821082) (xy 378.667766 -252.849038) (xy 378.623304 -252.870136) (xy 378.576033 -252.883828)
			(xy 378.527178 -252.88976) (xy 378.478003 -252.887779) (xy 378.429784 -252.877935) (xy 378.383768 -252.860483)
			(xy 378.341147 -252.835876) (xy 378.303026 -252.804751) (xy 378.270391 -252.767914) (xy 378.244088 -252.726318)
			(xy 378.224797 -252.681042) (xy 378.21302 -252.633258) (xy 378.20906 -252.584204) (xy 377.890532 -252.584204)
			(xy 377.89002 -252.60965) (xy 377.881856 -252.659884) (xy 377.86574 -252.708158) (xy 377.842089 -252.753221)
			(xy 377.811516 -252.793907) (xy 377.774812 -252.829162) (xy 377.732928 -252.858072) (xy 377.686949 -252.879889)
			(xy 377.638065 -252.894049) (xy 377.587544 -252.900183) (xy 377.536692 -252.898134) (xy 377.486828 -252.887954)
			(xy 377.439242 -252.869907) (xy 377.395168 -252.844461) (xy 377.355746 -252.812274) (xy 377.321998 -252.77418)
			(xy 377.294797 -252.731166) (xy 377.274849 -252.684346) (xy 377.26267 -252.634932) (xy 377.258575 -252.584204)
			(xy 376.940064 -252.584204) (xy 376.939569 -252.608811) (xy 376.931674 -252.657388) (xy 376.91609 -252.704069)
			(xy 376.893219 -252.747646) (xy 376.863654 -252.78699) (xy 376.828161 -252.821082) (xy 376.787658 -252.849038)
			(xy 376.743196 -252.870136) (xy 376.695925 -252.883828) (xy 376.64707 -252.88976) (xy 376.597895 -252.887779)
			(xy 376.549676 -252.877935) (xy 376.50366 -252.860483) (xy 376.461039 -252.835876) (xy 376.422918 -252.804751)
			(xy 376.390283 -252.767914) (xy 376.36398 -252.726318) (xy 376.344689 -252.681042) (xy 376.332912 -252.633258)
			(xy 376.328952 -252.584204) (xy 376.00001 -252.584204) (xy 375.999515 -252.608811) (xy 375.99162 -252.657388)
			(xy 375.976036 -252.704069) (xy 375.953165 -252.747646) (xy 375.9236 -252.78699) (xy 375.888107 -252.821082)
			(xy 375.847604 -252.849038) (xy 375.803142 -252.870136) (xy 375.755871 -252.883828) (xy 375.707016 -252.88976)
			(xy 375.657841 -252.887779) (xy 375.609622 -252.877935) (xy 375.563606 -252.860483) (xy 375.520985 -252.835876)
			(xy 375.482864 -252.804751) (xy 375.450229 -252.767914) (xy 375.423926 -252.726318) (xy 375.404635 -252.681042)
			(xy 375.392858 -252.633258) (xy 375.388898 -252.584204) (xy 375.06021 -252.584204) (xy 375.059715 -252.608811)
			(xy 375.05182 -252.657388) (xy 375.036236 -252.704069) (xy 375.013365 -252.747646) (xy 374.9838 -252.78699)
			(xy 374.948307 -252.821082) (xy 374.907804 -252.849038) (xy 374.863342 -252.870136) (xy 374.816071 -252.883828)
			(xy 374.767216 -252.88976) (xy 374.718041 -252.887779) (xy 374.669822 -252.877935) (xy 374.623806 -252.860483)
			(xy 374.581185 -252.835876) (xy 374.543064 -252.804751) (xy 374.510429 -252.767914) (xy 374.484126 -252.726318)
			(xy 374.464835 -252.681042) (xy 374.453058 -252.633258) (xy 374.449098 -252.584204) (xy 373.180102 -252.584204)
			(xy 373.179607 -252.608811) (xy 373.171712 -252.657388) (xy 373.156128 -252.704069) (xy 373.133257 -252.747646)
			(xy 373.103692 -252.78699) (xy 373.068199 -252.821082) (xy 373.027696 -252.849038) (xy 372.983234 -252.870136)
			(xy 372.935963 -252.883828) (xy 372.887108 -252.88976) (xy 372.837933 -252.887779) (xy 372.789714 -252.877935)
			(xy 372.743698 -252.860483) (xy 372.701077 -252.835876) (xy 372.662956 -252.804751) (xy 372.630321 -252.767914)
			(xy 372.604018 -252.726318) (xy 372.584727 -252.681042) (xy 372.57295 -252.633258) (xy 372.56899 -252.584204)
			(xy 371.299994 -252.584204) (xy 371.299499 -252.608811) (xy 371.291604 -252.657388) (xy 371.27602 -252.704069)
			(xy 371.253149 -252.747646) (xy 371.223584 -252.78699) (xy 371.188091 -252.821082) (xy 371.147588 -252.849038)
			(xy 371.103126 -252.870136) (xy 371.055855 -252.883828) (xy 371.007 -252.88976) (xy 370.957825 -252.887779)
			(xy 370.909606 -252.877935) (xy 370.86359 -252.860483) (xy 370.820969 -252.835876) (xy 370.782848 -252.804751)
			(xy 370.750213 -252.767914) (xy 370.72391 -252.726318) (xy 370.704619 -252.681042) (xy 370.692842 -252.633258)
			(xy 370.688882 -252.584204) (xy 369.42014 -252.584204) (xy 369.419645 -252.608811) (xy 369.41175 -252.657388)
			(xy 369.396166 -252.704069) (xy 369.373295 -252.747646) (xy 369.34373 -252.78699) (xy 369.308237 -252.821082)
			(xy 369.267734 -252.849038) (xy 369.223272 -252.870136) (xy 369.176001 -252.883828) (xy 369.127146 -252.88976)
			(xy 369.077971 -252.887779) (xy 369.029752 -252.877935) (xy 368.983736 -252.860483) (xy 368.941115 -252.835876)
			(xy 368.902994 -252.804751) (xy 368.870359 -252.767914) (xy 368.844056 -252.726318) (xy 368.824765 -252.681042)
			(xy 368.812988 -252.633258) (xy 368.809028 -252.584204) (xy 360.49716 -252.584204) (xy 360.493272 -252.592056)
			(xy 360.46298 -252.635122) (xy 360.426468 -252.67306) (xy 360.384594 -252.704979) (xy 360.338338 -252.730132)
			(xy 360.288785 -252.74793) (xy 360.237095 -252.757954) (xy 360.184481 -252.759971) (xy 360.132176 -252.753933)
			(xy 360.081405 -252.739981) (xy 360.03336 -252.718442) (xy 359.989165 -252.689822) (xy 359.949857 -252.654791)
			(xy 359.916357 -252.61417) (xy 359.889451 -252.568911) (xy 359.869768 -252.520076) (xy 359.857771 -252.468808)
			(xy 359.853741 -252.41631) (xy 351.177352 -252.41631) (xy 351.899982 -253.13894) (xy 351.90684 -253.144782)
			(xy 351.908364 -253.145798) (xy 351.927036 -253.159997) (xy 351.960205 -253.193166) (xy 351.974404 -253.211838)
			(xy 351.97542 -253.213362) (xy 351.981262 -253.22022) (xy 352.15322 -253.392178) (xy 353.302074 -253.392178)
			(xy 353.306034 -253.343124) (xy 353.317811 -253.29534) (xy 353.337102 -253.250064) (xy 353.363405 -253.208468)
			(xy 353.39604 -253.171631) (xy 353.434161 -253.140506) (xy 353.476782 -253.115899) (xy 353.522798 -253.098447)
			(xy 353.571017 -253.088603) (xy 353.620192 -253.086622) (xy 353.669047 -253.092554) (xy 353.716318 -253.106246)
			(xy 353.76078 -253.127344) (xy 353.801283 -253.1553) (xy 353.836776 -253.189392) (xy 353.866341 -253.228736)
			(xy 353.889212 -253.272313) (xy 353.904796 -253.318994) (xy 353.912691 -253.367571) (xy 353.913186 -253.392178)
			(xy 355.182182 -253.392178) (xy 355.186142 -253.343124) (xy 355.197919 -253.29534) (xy 355.21721 -253.250064)
			(xy 355.243513 -253.208468) (xy 355.276148 -253.171631) (xy 355.314269 -253.140506) (xy 355.35689 -253.115899)
			(xy 355.402906 -253.098447) (xy 355.451125 -253.088603) (xy 355.5003 -253.086622) (xy 355.549155 -253.092554)
			(xy 355.596426 -253.106246) (xy 355.640888 -253.127344) (xy 355.681391 -253.1553) (xy 355.716884 -253.189392)
			(xy 355.746449 -253.228736) (xy 355.76932 -253.272313) (xy 355.784904 -253.318994) (xy 355.792799 -253.367571)
			(xy 355.793294 -253.392178) (xy 357.06229 -253.392178) (xy 357.06625 -253.343124) (xy 357.078027 -253.29534)
			(xy 357.097318 -253.250064) (xy 357.123621 -253.208468) (xy 357.156256 -253.171631) (xy 357.194377 -253.140506)
			(xy 357.236998 -253.115899) (xy 357.283014 -253.098447) (xy 357.331233 -253.088603) (xy 357.380408 -253.086622)
			(xy 357.429263 -253.092554) (xy 357.476534 -253.106246) (xy 357.520996 -253.127344) (xy 357.561499 -253.1553)
			(xy 357.596992 -253.189392) (xy 357.626557 -253.228736) (xy 357.649428 -253.272313) (xy 357.665012 -253.318994)
			(xy 357.672907 -253.367571) (xy 357.673402 -253.392178) (xy 357.672907 -253.416785) (xy 357.670384 -253.43231)
			(xy 359.853741 -253.43231) (xy 359.857771 -253.379812) (xy 359.869768 -253.328544) (xy 359.889451 -253.279709)
			(xy 359.916357 -253.23445) (xy 359.949857 -253.193829) (xy 359.989165 -253.158798) (xy 360.03336 -253.130178)
			(xy 360.081405 -253.108639) (xy 360.132176 -253.094687) (xy 360.184481 -253.088649) (xy 360.237095 -253.090666)
			(xy 360.288785 -253.10069) (xy 360.338338 -253.118488) (xy 360.384594 -253.143641) (xy 360.426468 -253.17556)
			(xy 360.46298 -253.213498) (xy 360.493272 -253.256564) (xy 360.516635 -253.303749) (xy 360.532521 -253.353948)
			(xy 360.538426 -253.392178) (xy 360.822252 -253.392178) (xy 360.826212 -253.343124) (xy 360.837989 -253.29534)
			(xy 360.85728 -253.250064) (xy 360.883583 -253.208468) (xy 360.916218 -253.171631) (xy 360.954339 -253.140506)
			(xy 360.99696 -253.115899) (xy 361.042976 -253.098447) (xy 361.091195 -253.088603) (xy 361.14037 -253.086622)
			(xy 361.189225 -253.092554) (xy 361.236496 -253.106246) (xy 361.280958 -253.127344) (xy 361.321461 -253.1553)
			(xy 361.356954 -253.189392) (xy 361.386519 -253.228736) (xy 361.40939 -253.272313) (xy 361.424974 -253.318994)
			(xy 361.432869 -253.367571) (xy 361.433364 -253.392178) (xy 362.702106 -253.392178) (xy 362.706066 -253.343124)
			(xy 362.717843 -253.29534) (xy 362.737134 -253.250064) (xy 362.763437 -253.208468) (xy 362.796072 -253.171631)
			(xy 362.834193 -253.140506) (xy 362.876814 -253.115899) (xy 362.92283 -253.098447) (xy 362.971049 -253.088603)
			(xy 363.020224 -253.086622) (xy 363.069079 -253.092554) (xy 363.11635 -253.106246) (xy 363.160812 -253.127344)
			(xy 363.201315 -253.1553) (xy 363.236808 -253.189392) (xy 363.266373 -253.228736) (xy 363.289244 -253.272313)
			(xy 363.304828 -253.318994) (xy 363.312723 -253.367571) (xy 363.313218 -253.392178) (xy 364.582214 -253.392178)
			(xy 364.586174 -253.343124) (xy 364.597951 -253.29534) (xy 364.617242 -253.250064) (xy 364.643545 -253.208468)
			(xy 364.67618 -253.171631) (xy 364.714301 -253.140506) (xy 364.756922 -253.115899) (xy 364.802938 -253.098447)
			(xy 364.851157 -253.088603) (xy 364.900332 -253.086622) (xy 364.949187 -253.092554) (xy 364.996458 -253.106246)
			(xy 365.04092 -253.127344) (xy 365.081423 -253.1553) (xy 365.116916 -253.189392) (xy 365.146481 -253.228736)
			(xy 365.169352 -253.272313) (xy 365.184936 -253.318994) (xy 365.192831 -253.367571) (xy 365.193326 -253.392178)
			(xy 366.462068 -253.392178) (xy 366.466028 -253.343124) (xy 366.477805 -253.29534) (xy 366.497096 -253.250064)
			(xy 366.523399 -253.208468) (xy 366.556034 -253.171631) (xy 366.594155 -253.140506) (xy 366.636776 -253.115899)
			(xy 366.682792 -253.098447) (xy 366.731011 -253.088603) (xy 366.780186 -253.086622) (xy 366.829041 -253.092554)
			(xy 366.876312 -253.106246) (xy 366.920774 -253.127344) (xy 366.961277 -253.1553) (xy 366.99677 -253.189392)
			(xy 367.026335 -253.228736) (xy 367.049206 -253.272313) (xy 367.06479 -253.318994) (xy 367.072685 -253.367571)
			(xy 367.07318 -253.392178) (xy 367.073139 -253.39421) (xy 370.218982 -253.39421) (xy 370.222942 -253.345156)
			(xy 370.234719 -253.297372) (xy 370.25401 -253.252096) (xy 370.280313 -253.2105) (xy 370.312948 -253.173663)
			(xy 370.351069 -253.142538) (xy 370.39369 -253.117931) (xy 370.439706 -253.100479) (xy 370.487925 -253.090635)
			(xy 370.5371 -253.088654) (xy 370.585955 -253.094586) (xy 370.633226 -253.108278) (xy 370.677688 -253.129376)
			(xy 370.718191 -253.157332) (xy 370.753684 -253.191424) (xy 370.783249 -253.230768) (xy 370.80612 -253.274345)
			(xy 370.821704 -253.321026) (xy 370.829599 -253.369603) (xy 370.830094 -253.39421) (xy 372.09909 -253.39421)
			(xy 372.10305 -253.345156) (xy 372.114827 -253.297372) (xy 372.134118 -253.252096) (xy 372.160421 -253.2105)
			(xy 372.193056 -253.173663) (xy 372.231177 -253.142538) (xy 372.273798 -253.117931) (xy 372.319814 -253.100479)
			(xy 372.368033 -253.090635) (xy 372.417208 -253.088654) (xy 372.466063 -253.094586) (xy 372.513334 -253.108278)
			(xy 372.557796 -253.129376) (xy 372.598299 -253.157332) (xy 372.633792 -253.191424) (xy 372.663357 -253.230768)
			(xy 372.686228 -253.274345) (xy 372.701812 -253.321026) (xy 372.709707 -253.369603) (xy 372.710202 -253.39421)
			(xy 373.978944 -253.39421) (xy 373.982904 -253.345156) (xy 373.994681 -253.297372) (xy 374.013972 -253.252096)
			(xy 374.040275 -253.2105) (xy 374.07291 -253.173663) (xy 374.111031 -253.142538) (xy 374.153652 -253.117931)
			(xy 374.199668 -253.100479) (xy 374.247887 -253.090635) (xy 374.297062 -253.088654) (xy 374.345917 -253.094586)
			(xy 374.393188 -253.108278) (xy 374.43765 -253.129376) (xy 374.478153 -253.157332) (xy 374.513646 -253.191424)
			(xy 374.543211 -253.230768) (xy 374.566082 -253.274345) (xy 374.581666 -253.321026) (xy 374.589561 -253.369603)
			(xy 374.590056 -253.39421) (xy 375.848621 -253.39421) (xy 375.852716 -253.343482) (xy 375.864895 -253.294068)
			(xy 375.884843 -253.247248) (xy 375.912044 -253.204234) (xy 375.945792 -253.16614) (xy 375.985214 -253.133953)
			(xy 376.029288 -253.108507) (xy 376.076874 -253.09046) (xy 376.126738 -253.08028) (xy 376.17759 -253.078231)
			(xy 376.228111 -253.084365) (xy 376.276995 -253.098525) (xy 376.322974 -253.120342) (xy 376.364858 -253.149252)
			(xy 376.401562 -253.184507) (xy 376.432135 -253.225193) (xy 376.455786 -253.270256) (xy 376.471902 -253.31853)
			(xy 376.480066 -253.368764) (xy 376.480578 -253.39421) (xy 376.788675 -253.39421) (xy 376.79277 -253.343482)
			(xy 376.804949 -253.294068) (xy 376.824897 -253.247248) (xy 376.852098 -253.204234) (xy 376.885846 -253.16614)
			(xy 376.925268 -253.133953) (xy 376.969342 -253.108507) (xy 377.016928 -253.09046) (xy 377.066792 -253.08028)
			(xy 377.117644 -253.078231) (xy 377.168165 -253.084365) (xy 377.217049 -253.098525) (xy 377.263028 -253.120342)
			(xy 377.304912 -253.149252) (xy 377.341616 -253.184507) (xy 377.372189 -253.225193) (xy 377.39584 -253.270256)
			(xy 377.411956 -253.31853) (xy 377.42012 -253.368764) (xy 377.420632 -253.39421) (xy 377.738906 -253.39421)
			(xy 377.742866 -253.345156) (xy 377.754643 -253.297372) (xy 377.773934 -253.252096) (xy 377.800237 -253.2105)
			(xy 377.832872 -253.173663) (xy 377.870993 -253.142538) (xy 377.913614 -253.117931) (xy 377.95963 -253.100479)
			(xy 378.007849 -253.090635) (xy 378.057024 -253.088654) (xy 378.105879 -253.094586) (xy 378.15315 -253.108278)
			(xy 378.197612 -253.129376) (xy 378.238115 -253.157332) (xy 378.273608 -253.191424) (xy 378.303173 -253.230768)
			(xy 378.326044 -253.274345) (xy 378.341628 -253.321026) (xy 378.349523 -253.369603) (xy 378.350018 -253.39421)
			(xy 378.668529 -253.39421) (xy 378.672624 -253.343482) (xy 378.684803 -253.294068) (xy 378.704751 -253.247248)
			(xy 378.731952 -253.204234) (xy 378.7657 -253.16614) (xy 378.805122 -253.133953) (xy 378.849196 -253.108507)
			(xy 378.896782 -253.09046) (xy 378.946646 -253.08028) (xy 378.997498 -253.078231) (xy 379.048019 -253.084365)
			(xy 379.096903 -253.098525) (xy 379.142882 -253.120342) (xy 379.184766 -253.149252) (xy 379.22147 -253.184507)
			(xy 379.252043 -253.225193) (xy 379.275694 -253.270256) (xy 379.29181 -253.31853) (xy 379.299974 -253.368764)
			(xy 379.300486 -253.39421) (xy 379.619014 -253.39421) (xy 379.622974 -253.345156) (xy 379.634751 -253.297372)
			(xy 379.654042 -253.252096) (xy 379.680345 -253.2105) (xy 379.71298 -253.173663) (xy 379.751101 -253.142538)
			(xy 379.793722 -253.117931) (xy 379.839738 -253.100479) (xy 379.887957 -253.090635) (xy 379.937132 -253.088654)
			(xy 379.985987 -253.094586) (xy 380.033258 -253.108278) (xy 380.07772 -253.129376) (xy 380.118223 -253.157332)
			(xy 380.153716 -253.191424) (xy 380.183281 -253.230768) (xy 380.206152 -253.274345) (xy 380.221736 -253.321026)
			(xy 380.229631 -253.369603) (xy 380.230126 -253.39421) (xy 380.548637 -253.39421) (xy 380.552732 -253.343482)
			(xy 380.564911 -253.294068) (xy 380.584859 -253.247248) (xy 380.61206 -253.204234) (xy 380.645808 -253.16614)
			(xy 380.68523 -253.133953) (xy 380.729304 -253.108507) (xy 380.77689 -253.09046) (xy 380.826754 -253.08028)
			(xy 380.877606 -253.078231) (xy 380.928127 -253.084365) (xy 380.977011 -253.098525) (xy 381.02299 -253.120342)
			(xy 381.064874 -253.149252) (xy 381.101578 -253.184507) (xy 381.132151 -253.225193) (xy 381.155802 -253.270256)
			(xy 381.171918 -253.31853) (xy 381.180082 -253.368764) (xy 381.180594 -253.39421) (xy 381.499122 -253.39421)
			(xy 381.503082 -253.345156) (xy 381.514859 -253.297372) (xy 381.53415 -253.252096) (xy 381.560453 -253.2105)
			(xy 381.593088 -253.173663) (xy 381.631209 -253.142538) (xy 381.67383 -253.117931) (xy 381.719846 -253.100479)
			(xy 381.768065 -253.090635) (xy 381.81724 -253.088654) (xy 381.866095 -253.094586) (xy 381.913366 -253.108278)
			(xy 381.957828 -253.129376) (xy 381.998331 -253.157332) (xy 382.033824 -253.191424) (xy 382.063389 -253.230768)
			(xy 382.08626 -253.274345) (xy 382.101844 -253.321026) (xy 382.109739 -253.369603) (xy 382.110234 -253.39421)
			(xy 382.438922 -253.39421) (xy 382.442882 -253.345156) (xy 382.454659 -253.297372) (xy 382.47395 -253.252096)
			(xy 382.500253 -253.2105) (xy 382.532888 -253.173663) (xy 382.571009 -253.142538) (xy 382.61363 -253.117931)
			(xy 382.659646 -253.100479) (xy 382.707865 -253.090635) (xy 382.75704 -253.088654) (xy 382.805895 -253.094586)
			(xy 382.853166 -253.108278) (xy 382.897628 -253.129376) (xy 382.938131 -253.157332) (xy 382.973624 -253.191424)
			(xy 383.003189 -253.230768) (xy 383.02606 -253.274345) (xy 383.041644 -253.321026) (xy 383.049539 -253.369603)
			(xy 383.050034 -253.39421) (xy 383.378976 -253.39421) (xy 383.382936 -253.345156) (xy 383.394713 -253.297372)
			(xy 383.414004 -253.252096) (xy 383.440307 -253.2105) (xy 383.472942 -253.173663) (xy 383.511063 -253.142538)
			(xy 383.553684 -253.117931) (xy 383.5997 -253.100479) (xy 383.647919 -253.090635) (xy 383.697094 -253.088654)
			(xy 383.745949 -253.094586) (xy 383.79322 -253.108278) (xy 383.837682 -253.129376) (xy 383.878185 -253.157332)
			(xy 383.913678 -253.191424) (xy 383.943243 -253.230768) (xy 383.966114 -253.274345) (xy 383.981698 -253.321026)
			(xy 383.989593 -253.369603) (xy 383.990088 -253.39421) (xy 384.31903 -253.39421) (xy 384.32299 -253.345156)
			(xy 384.334767 -253.297372) (xy 384.354058 -253.252096) (xy 384.380361 -253.2105) (xy 384.412996 -253.173663)
			(xy 384.451117 -253.142538) (xy 384.493738 -253.117931) (xy 384.539754 -253.100479) (xy 384.587973 -253.090635)
			(xy 384.637148 -253.088654) (xy 384.686003 -253.094586) (xy 384.733274 -253.108278) (xy 384.777736 -253.129376)
			(xy 384.818239 -253.157332) (xy 384.853732 -253.191424) (xy 384.883297 -253.230768) (xy 384.906168 -253.274345)
			(xy 384.921752 -253.321026) (xy 384.929647 -253.369603) (xy 384.930142 -253.39421) (xy 385.259084 -253.39421)
			(xy 385.263044 -253.345156) (xy 385.274821 -253.297372) (xy 385.294112 -253.252096) (xy 385.320415 -253.2105)
			(xy 385.35305 -253.173663) (xy 385.391171 -253.142538) (xy 385.433792 -253.117931) (xy 385.479808 -253.100479)
			(xy 385.528027 -253.090635) (xy 385.577202 -253.088654) (xy 385.626057 -253.094586) (xy 385.673328 -253.108278)
			(xy 385.71779 -253.129376) (xy 385.758293 -253.157332) (xy 385.793786 -253.191424) (xy 385.823351 -253.230768)
			(xy 385.846222 -253.274345) (xy 385.861806 -253.321026) (xy 385.869701 -253.369603) (xy 385.870196 -253.39421)
			(xy 386.199138 -253.39421) (xy 386.203098 -253.345156) (xy 386.214875 -253.297372) (xy 386.234166 -253.252096)
			(xy 386.260469 -253.2105) (xy 386.293104 -253.173663) (xy 386.331225 -253.142538) (xy 386.373846 -253.117931)
			(xy 386.419862 -253.100479) (xy 386.468081 -253.090635) (xy 386.517256 -253.088654) (xy 386.566111 -253.094586)
			(xy 386.613382 -253.108278) (xy 386.657844 -253.129376) (xy 386.698347 -253.157332) (xy 386.73384 -253.191424)
			(xy 386.763405 -253.230768) (xy 386.786276 -253.274345) (xy 386.80186 -253.321026) (xy 386.809755 -253.369603)
			(xy 386.81025 -253.39421) (xy 387.138938 -253.39421) (xy 387.142898 -253.345156) (xy 387.154675 -253.297372)
			(xy 387.173966 -253.252096) (xy 387.200269 -253.2105) (xy 387.232904 -253.173663) (xy 387.271025 -253.142538)
			(xy 387.313646 -253.117931) (xy 387.359662 -253.100479) (xy 387.407881 -253.090635) (xy 387.457056 -253.088654)
			(xy 387.505911 -253.094586) (xy 387.553182 -253.108278) (xy 387.597644 -253.129376) (xy 387.638147 -253.157332)
			(xy 387.67364 -253.191424) (xy 387.703205 -253.230768) (xy 387.726076 -253.274345) (xy 387.74166 -253.321026)
			(xy 387.749555 -253.369603) (xy 387.75005 -253.39421) (xy 387.749555 -253.418817) (xy 387.74166 -253.467394)
			(xy 387.726076 -253.514075) (xy 387.703205 -253.557652) (xy 387.67364 -253.596996) (xy 387.638147 -253.631088)
			(xy 387.597644 -253.659044) (xy 387.553182 -253.680142) (xy 387.505911 -253.693834) (xy 387.457056 -253.699766)
			(xy 387.407881 -253.697785) (xy 387.359662 -253.687941) (xy 387.313646 -253.670489) (xy 387.271025 -253.645882)
			(xy 387.232904 -253.614757) (xy 387.200269 -253.57792) (xy 387.173966 -253.536324) (xy 387.154675 -253.491048)
			(xy 387.142898 -253.443264) (xy 387.138938 -253.39421) (xy 386.81025 -253.39421) (xy 386.809755 -253.418817)
			(xy 386.80186 -253.467394) (xy 386.786276 -253.514075) (xy 386.763405 -253.557652) (xy 386.73384 -253.596996)
			(xy 386.698347 -253.631088) (xy 386.657844 -253.659044) (xy 386.613382 -253.680142) (xy 386.566111 -253.693834)
			(xy 386.517256 -253.699766) (xy 386.468081 -253.697785) (xy 386.419862 -253.687941) (xy 386.373846 -253.670489)
			(xy 386.331225 -253.645882) (xy 386.293104 -253.614757) (xy 386.260469 -253.57792) (xy 386.234166 -253.536324)
			(xy 386.214875 -253.491048) (xy 386.203098 -253.443264) (xy 386.199138 -253.39421) (xy 385.870196 -253.39421)
			(xy 385.869701 -253.418817) (xy 385.861806 -253.467394) (xy 385.846222 -253.514075) (xy 385.823351 -253.557652)
			(xy 385.793786 -253.596996) (xy 385.758293 -253.631088) (xy 385.71779 -253.659044) (xy 385.673328 -253.680142)
			(xy 385.626057 -253.693834) (xy 385.577202 -253.699766) (xy 385.528027 -253.697785) (xy 385.479808 -253.687941)
			(xy 385.433792 -253.670489) (xy 385.391171 -253.645882) (xy 385.35305 -253.614757) (xy 385.320415 -253.57792)
			(xy 385.294112 -253.536324) (xy 385.274821 -253.491048) (xy 385.263044 -253.443264) (xy 385.259084 -253.39421)
			(xy 384.930142 -253.39421) (xy 384.929647 -253.418817) (xy 384.921752 -253.467394) (xy 384.906168 -253.514075)
			(xy 384.883297 -253.557652) (xy 384.853732 -253.596996) (xy 384.818239 -253.631088) (xy 384.777736 -253.659044)
			(xy 384.733274 -253.680142) (xy 384.686003 -253.693834) (xy 384.637148 -253.699766) (xy 384.587973 -253.697785)
			(xy 384.539754 -253.687941) (xy 384.493738 -253.670489) (xy 384.451117 -253.645882) (xy 384.412996 -253.614757)
			(xy 384.380361 -253.57792) (xy 384.354058 -253.536324) (xy 384.334767 -253.491048) (xy 384.32299 -253.443264)
			(xy 384.31903 -253.39421) (xy 383.990088 -253.39421) (xy 383.989593 -253.418817) (xy 383.981698 -253.467394)
			(xy 383.966114 -253.514075) (xy 383.943243 -253.557652) (xy 383.913678 -253.596996) (xy 383.878185 -253.631088)
			(xy 383.837682 -253.659044) (xy 383.79322 -253.680142) (xy 383.745949 -253.693834) (xy 383.697094 -253.699766)
			(xy 383.647919 -253.697785) (xy 383.5997 -253.687941) (xy 383.553684 -253.670489) (xy 383.511063 -253.645882)
			(xy 383.472942 -253.614757) (xy 383.440307 -253.57792) (xy 383.414004 -253.536324) (xy 383.394713 -253.491048)
			(xy 383.382936 -253.443264) (xy 383.378976 -253.39421) (xy 383.050034 -253.39421) (xy 383.049539 -253.418817)
			(xy 383.041644 -253.467394) (xy 383.02606 -253.514075) (xy 383.003189 -253.557652) (xy 382.973624 -253.596996)
			(xy 382.938131 -253.631088) (xy 382.897628 -253.659044) (xy 382.853166 -253.680142) (xy 382.805895 -253.693834)
			(xy 382.75704 -253.699766) (xy 382.707865 -253.697785) (xy 382.659646 -253.687941) (xy 382.61363 -253.670489)
			(xy 382.571009 -253.645882) (xy 382.532888 -253.614757) (xy 382.500253 -253.57792) (xy 382.47395 -253.536324)
			(xy 382.454659 -253.491048) (xy 382.442882 -253.443264) (xy 382.438922 -253.39421) (xy 382.110234 -253.39421)
			(xy 382.109739 -253.418817) (xy 382.101844 -253.467394) (xy 382.08626 -253.514075) (xy 382.063389 -253.557652)
			(xy 382.033824 -253.596996) (xy 381.998331 -253.631088) (xy 381.957828 -253.659044) (xy 381.913366 -253.680142)
			(xy 381.866095 -253.693834) (xy 381.81724 -253.699766) (xy 381.768065 -253.697785) (xy 381.719846 -253.687941)
			(xy 381.67383 -253.670489) (xy 381.631209 -253.645882) (xy 381.593088 -253.614757) (xy 381.560453 -253.57792)
			(xy 381.53415 -253.536324) (xy 381.514859 -253.491048) (xy 381.503082 -253.443264) (xy 381.499122 -253.39421)
			(xy 381.180594 -253.39421) (xy 381.180082 -253.419656) (xy 381.171918 -253.46989) (xy 381.155802 -253.518164)
			(xy 381.132151 -253.563227) (xy 381.101578 -253.603913) (xy 381.064874 -253.639168) (xy 381.02299 -253.668078)
			(xy 380.977011 -253.689895) (xy 380.928127 -253.704055) (xy 380.877606 -253.710189) (xy 380.826754 -253.70814)
			(xy 380.77689 -253.69796) (xy 380.729304 -253.679913) (xy 380.68523 -253.654467) (xy 380.645808 -253.62228)
			(xy 380.61206 -253.584186) (xy 380.584859 -253.541172) (xy 380.564911 -253.494352) (xy 380.552732 -253.444938)
			(xy 380.548637 -253.39421) (xy 380.230126 -253.39421) (xy 380.229631 -253.418817) (xy 380.221736 -253.467394)
			(xy 380.206152 -253.514075) (xy 380.183281 -253.557652) (xy 380.153716 -253.596996) (xy 380.118223 -253.631088)
			(xy 380.07772 -253.659044) (xy 380.033258 -253.680142) (xy 379.985987 -253.693834) (xy 379.937132 -253.699766)
			(xy 379.887957 -253.697785) (xy 379.839738 -253.687941) (xy 379.793722 -253.670489) (xy 379.751101 -253.645882)
			(xy 379.71298 -253.614757) (xy 379.680345 -253.57792) (xy 379.654042 -253.536324) (xy 379.634751 -253.491048)
			(xy 379.622974 -253.443264) (xy 379.619014 -253.39421) (xy 379.300486 -253.39421) (xy 379.299974 -253.419656)
			(xy 379.29181 -253.46989) (xy 379.275694 -253.518164) (xy 379.252043 -253.563227) (xy 379.22147 -253.603913)
			(xy 379.184766 -253.639168) (xy 379.142882 -253.668078) (xy 379.096903 -253.689895) (xy 379.048019 -253.704055)
			(xy 378.997498 -253.710189) (xy 378.946646 -253.70814) (xy 378.896782 -253.69796) (xy 378.849196 -253.679913)
			(xy 378.805122 -253.654467) (xy 378.7657 -253.62228) (xy 378.731952 -253.584186) (xy 378.704751 -253.541172)
			(xy 378.684803 -253.494352) (xy 378.672624 -253.444938) (xy 378.668529 -253.39421) (xy 378.350018 -253.39421)
			(xy 378.349523 -253.418817) (xy 378.341628 -253.467394) (xy 378.326044 -253.514075) (xy 378.303173 -253.557652)
			(xy 378.273608 -253.596996) (xy 378.238115 -253.631088) (xy 378.197612 -253.659044) (xy 378.15315 -253.680142)
			(xy 378.105879 -253.693834) (xy 378.057024 -253.699766) (xy 378.007849 -253.697785) (xy 377.95963 -253.687941)
			(xy 377.913614 -253.670489) (xy 377.870993 -253.645882) (xy 377.832872 -253.614757) (xy 377.800237 -253.57792)
			(xy 377.773934 -253.536324) (xy 377.754643 -253.491048) (xy 377.742866 -253.443264) (xy 377.738906 -253.39421)
			(xy 377.420632 -253.39421) (xy 377.42012 -253.419656) (xy 377.411956 -253.46989) (xy 377.39584 -253.518164)
			(xy 377.372189 -253.563227) (xy 377.341616 -253.603913) (xy 377.304912 -253.639168) (xy 377.263028 -253.668078)
			(xy 377.217049 -253.689895) (xy 377.168165 -253.704055) (xy 377.117644 -253.710189) (xy 377.066792 -253.70814)
			(xy 377.016928 -253.69796) (xy 376.969342 -253.679913) (xy 376.925268 -253.654467) (xy 376.885846 -253.62228)
			(xy 376.852098 -253.584186) (xy 376.824897 -253.541172) (xy 376.804949 -253.494352) (xy 376.79277 -253.444938)
			(xy 376.788675 -253.39421) (xy 376.480578 -253.39421) (xy 376.480066 -253.419656) (xy 376.471902 -253.46989)
			(xy 376.455786 -253.518164) (xy 376.432135 -253.563227) (xy 376.401562 -253.603913) (xy 376.364858 -253.639168)
			(xy 376.322974 -253.668078) (xy 376.276995 -253.689895) (xy 376.228111 -253.704055) (xy 376.17759 -253.710189)
			(xy 376.126738 -253.70814) (xy 376.076874 -253.69796) (xy 376.029288 -253.679913) (xy 375.985214 -253.654467)
			(xy 375.945792 -253.62228) (xy 375.912044 -253.584186) (xy 375.884843 -253.541172) (xy 375.864895 -253.494352)
			(xy 375.852716 -253.444938) (xy 375.848621 -253.39421) (xy 374.590056 -253.39421) (xy 374.589561 -253.418817)
			(xy 374.581666 -253.467394) (xy 374.566082 -253.514075) (xy 374.543211 -253.557652) (xy 374.513646 -253.596996)
			(xy 374.478153 -253.631088) (xy 374.43765 -253.659044) (xy 374.393188 -253.680142) (xy 374.345917 -253.693834)
			(xy 374.297062 -253.699766) (xy 374.247887 -253.697785) (xy 374.199668 -253.687941) (xy 374.153652 -253.670489)
			(xy 374.111031 -253.645882) (xy 374.07291 -253.614757) (xy 374.040275 -253.57792) (xy 374.013972 -253.536324)
			(xy 373.994681 -253.491048) (xy 373.982904 -253.443264) (xy 373.978944 -253.39421) (xy 372.710202 -253.39421)
			(xy 372.709707 -253.418817) (xy 372.701812 -253.467394) (xy 372.686228 -253.514075) (xy 372.663357 -253.557652)
			(xy 372.633792 -253.596996) (xy 372.598299 -253.631088) (xy 372.557796 -253.659044) (xy 372.513334 -253.680142)
			(xy 372.466063 -253.693834) (xy 372.417208 -253.699766) (xy 372.368033 -253.697785) (xy 372.319814 -253.687941)
			(xy 372.273798 -253.670489) (xy 372.231177 -253.645882) (xy 372.193056 -253.614757) (xy 372.160421 -253.57792)
			(xy 372.134118 -253.536324) (xy 372.114827 -253.491048) (xy 372.10305 -253.443264) (xy 372.09909 -253.39421)
			(xy 370.830094 -253.39421) (xy 370.829599 -253.418817) (xy 370.821704 -253.467394) (xy 370.80612 -253.514075)
			(xy 370.783249 -253.557652) (xy 370.753684 -253.596996) (xy 370.718191 -253.631088) (xy 370.677688 -253.659044)
			(xy 370.633226 -253.680142) (xy 370.585955 -253.693834) (xy 370.5371 -253.699766) (xy 370.487925 -253.697785)
			(xy 370.439706 -253.687941) (xy 370.39369 -253.670489) (xy 370.351069 -253.645882) (xy 370.312948 -253.614757)
			(xy 370.280313 -253.57792) (xy 370.25401 -253.536324) (xy 370.234719 -253.491048) (xy 370.222942 -253.443264)
			(xy 370.218982 -253.39421) (xy 367.073139 -253.39421) (xy 367.072685 -253.416785) (xy 367.06479 -253.465362)
			(xy 367.049206 -253.512043) (xy 367.026335 -253.55562) (xy 366.99677 -253.594964) (xy 366.961277 -253.629056)
			(xy 366.920774 -253.657012) (xy 366.876312 -253.67811) (xy 366.829041 -253.691802) (xy 366.780186 -253.697734)
			(xy 366.731011 -253.695753) (xy 366.682792 -253.685909) (xy 366.636776 -253.668457) (xy 366.594155 -253.64385)
			(xy 366.556034 -253.612725) (xy 366.523399 -253.575888) (xy 366.497096 -253.534292) (xy 366.477805 -253.489016)
			(xy 366.466028 -253.441232) (xy 366.462068 -253.392178) (xy 365.193326 -253.392178) (xy 365.192831 -253.416785)
			(xy 365.184936 -253.465362) (xy 365.169352 -253.512043) (xy 365.146481 -253.55562) (xy 365.116916 -253.594964)
			(xy 365.081423 -253.629056) (xy 365.04092 -253.657012) (xy 364.996458 -253.67811) (xy 364.949187 -253.691802)
			(xy 364.900332 -253.697734) (xy 364.851157 -253.695753) (xy 364.802938 -253.685909) (xy 364.756922 -253.668457)
			(xy 364.714301 -253.64385) (xy 364.67618 -253.612725) (xy 364.643545 -253.575888) (xy 364.617242 -253.534292)
			(xy 364.597951 -253.489016) (xy 364.586174 -253.441232) (xy 364.582214 -253.392178) (xy 363.313218 -253.392178)
			(xy 363.312723 -253.416785) (xy 363.304828 -253.465362) (xy 363.289244 -253.512043) (xy 363.266373 -253.55562)
			(xy 363.236808 -253.594964) (xy 363.201315 -253.629056) (xy 363.160812 -253.657012) (xy 363.11635 -253.67811)
			(xy 363.069079 -253.691802) (xy 363.020224 -253.697734) (xy 362.971049 -253.695753) (xy 362.92283 -253.685909)
			(xy 362.876814 -253.668457) (xy 362.834193 -253.64385) (xy 362.796072 -253.612725) (xy 362.763437 -253.575888)
			(xy 362.737134 -253.534292) (xy 362.717843 -253.489016) (xy 362.706066 -253.441232) (xy 362.702106 -253.392178)
			(xy 361.433364 -253.392178) (xy 361.432869 -253.416785) (xy 361.424974 -253.465362) (xy 361.40939 -253.512043)
			(xy 361.386519 -253.55562) (xy 361.356954 -253.594964) (xy 361.321461 -253.629056) (xy 361.280958 -253.657012)
			(xy 361.236496 -253.67811) (xy 361.189225 -253.691802) (xy 361.14037 -253.697734) (xy 361.091195 -253.695753)
			(xy 361.042976 -253.685909) (xy 360.99696 -253.668457) (xy 360.954339 -253.64385) (xy 360.916218 -253.612725)
			(xy 360.883583 -253.575888) (xy 360.85728 -253.534292) (xy 360.837989 -253.489016) (xy 360.826212 -253.441232)
			(xy 360.822252 -253.392178) (xy 360.538426 -253.392178) (xy 360.540558 -253.405984) (xy 360.541062 -253.43231)
			(xy 360.540558 -253.458636) (xy 360.532521 -253.510672) (xy 360.516635 -253.560871) (xy 360.493272 -253.608056)
			(xy 360.46298 -253.651122) (xy 360.426468 -253.68906) (xy 360.384594 -253.720979) (xy 360.338338 -253.746132)
			(xy 360.288785 -253.76393) (xy 360.237095 -253.773954) (xy 360.184481 -253.775971) (xy 360.132176 -253.769933)
			(xy 360.081405 -253.755981) (xy 360.03336 -253.734442) (xy 359.989165 -253.705822) (xy 359.949857 -253.670791)
			(xy 359.916357 -253.63017) (xy 359.889451 -253.584911) (xy 359.869768 -253.536076) (xy 359.857771 -253.484808)
			(xy 359.853741 -253.43231) (xy 357.670384 -253.43231) (xy 357.665012 -253.465362) (xy 357.649428 -253.512043)
			(xy 357.626557 -253.55562) (xy 357.596992 -253.594964) (xy 357.561499 -253.629056) (xy 357.520996 -253.657012)
			(xy 357.476534 -253.67811) (xy 357.429263 -253.691802) (xy 357.380408 -253.697734) (xy 357.331233 -253.695753)
			(xy 357.283014 -253.685909) (xy 357.236998 -253.668457) (xy 357.194377 -253.64385) (xy 357.156256 -253.612725)
			(xy 357.123621 -253.575888) (xy 357.097318 -253.534292) (xy 357.078027 -253.489016) (xy 357.06625 -253.441232)
			(xy 357.06229 -253.392178) (xy 355.793294 -253.392178) (xy 355.792799 -253.416785) (xy 355.784904 -253.465362)
			(xy 355.76932 -253.512043) (xy 355.746449 -253.55562) (xy 355.716884 -253.594964) (xy 355.681391 -253.629056)
			(xy 355.640888 -253.657012) (xy 355.596426 -253.67811) (xy 355.549155 -253.691802) (xy 355.5003 -253.697734)
			(xy 355.451125 -253.695753) (xy 355.402906 -253.685909) (xy 355.35689 -253.668457) (xy 355.314269 -253.64385)
			(xy 355.276148 -253.612725) (xy 355.243513 -253.575888) (xy 355.21721 -253.534292) (xy 355.197919 -253.489016)
			(xy 355.186142 -253.441232) (xy 355.182182 -253.392178) (xy 353.913186 -253.392178) (xy 353.912691 -253.416785)
			(xy 353.904796 -253.465362) (xy 353.889212 -253.512043) (xy 353.866341 -253.55562) (xy 353.836776 -253.594964)
			(xy 353.801283 -253.629056) (xy 353.76078 -253.657012) (xy 353.716318 -253.67811) (xy 353.669047 -253.691802)
			(xy 353.620192 -253.697734) (xy 353.571017 -253.695753) (xy 353.522798 -253.685909) (xy 353.476782 -253.668457)
			(xy 353.434161 -253.64385) (xy 353.39604 -253.612725) (xy 353.363405 -253.575888) (xy 353.337102 -253.534292)
			(xy 353.317811 -253.489016) (xy 353.306034 -253.441232) (xy 353.302074 -253.392178) (xy 352.15322 -253.392178)
			(xy 353.209352 -254.44831) (xy 359.853741 -254.44831) (xy 359.857771 -254.395812) (xy 359.869768 -254.344544)
			(xy 359.889451 -254.295709) (xy 359.916357 -254.25045) (xy 359.949857 -254.209829) (xy 359.989165 -254.174798)
			(xy 360.03336 -254.146178) (xy 360.081405 -254.124639) (xy 360.132176 -254.110687) (xy 360.184481 -254.104649)
			(xy 360.237095 -254.106666) (xy 360.288785 -254.11669) (xy 360.338338 -254.134488) (xy 360.384594 -254.159641)
			(xy 360.426468 -254.19156) (xy 360.438648 -254.204216) (xy 368.809028 -254.204216) (xy 368.812988 -254.155162)
			(xy 368.824765 -254.107378) (xy 368.844056 -254.062102) (xy 368.870359 -254.020506) (xy 368.902994 -253.983669)
			(xy 368.941115 -253.952544) (xy 368.983736 -253.927937) (xy 369.029752 -253.910485) (xy 369.077971 -253.900641)
			(xy 369.127146 -253.89866) (xy 369.176001 -253.904592) (xy 369.223272 -253.918284) (xy 369.267734 -253.939382)
			(xy 369.308237 -253.967338) (xy 369.34373 -254.00143) (xy 369.373295 -254.040774) (xy 369.396166 -254.084351)
			(xy 369.41175 -254.131032) (xy 369.419645 -254.179609) (xy 369.42014 -254.204216) (xy 370.688882 -254.204216)
			(xy 370.692842 -254.155162) (xy 370.704619 -254.107378) (xy 370.72391 -254.062102) (xy 370.750213 -254.020506)
			(xy 370.782848 -253.983669) (xy 370.820969 -253.952544) (xy 370.86359 -253.927937) (xy 370.909606 -253.910485)
			(xy 370.957825 -253.900641) (xy 371.007 -253.89866) (xy 371.055855 -253.904592) (xy 371.103126 -253.918284)
			(xy 371.147588 -253.939382) (xy 371.188091 -253.967338) (xy 371.223584 -254.00143) (xy 371.253149 -254.040774)
			(xy 371.27602 -254.084351) (xy 371.291604 -254.131032) (xy 371.299499 -254.179609) (xy 371.299994 -254.204216)
			(xy 372.56899 -254.204216) (xy 372.57295 -254.155162) (xy 372.584727 -254.107378) (xy 372.604018 -254.062102)
			(xy 372.630321 -254.020506) (xy 372.662956 -253.983669) (xy 372.701077 -253.952544) (xy 372.743698 -253.927937)
			(xy 372.789714 -253.910485) (xy 372.837933 -253.900641) (xy 372.887108 -253.89866) (xy 372.935963 -253.904592)
			(xy 372.983234 -253.918284) (xy 373.027696 -253.939382) (xy 373.068199 -253.967338) (xy 373.103692 -254.00143)
			(xy 373.133257 -254.040774) (xy 373.156128 -254.084351) (xy 373.171712 -254.131032) (xy 373.179607 -254.179609)
			(xy 373.180102 -254.204216) (xy 374.449098 -254.204216) (xy 374.453058 -254.155162) (xy 374.464835 -254.107378)
			(xy 374.484126 -254.062102) (xy 374.510429 -254.020506) (xy 374.543064 -253.983669) (xy 374.581185 -253.952544)
			(xy 374.623806 -253.927937) (xy 374.669822 -253.910485) (xy 374.718041 -253.900641) (xy 374.767216 -253.89866)
			(xy 374.816071 -253.904592) (xy 374.863342 -253.918284) (xy 374.907804 -253.939382) (xy 374.948307 -253.967338)
			(xy 374.9838 -254.00143) (xy 375.013365 -254.040774) (xy 375.036236 -254.084351) (xy 375.05182 -254.131032)
			(xy 375.059715 -254.179609) (xy 375.06021 -254.204216) (xy 375.378467 -254.204216) (xy 375.382562 -254.153488)
			(xy 375.394741 -254.104074) (xy 375.414689 -254.057254) (xy 375.44189 -254.01424) (xy 375.475638 -253.976146)
			(xy 375.51506 -253.943959) (xy 375.559134 -253.918513) (xy 375.60672 -253.900466) (xy 375.656584 -253.890286)
			(xy 375.707436 -253.888237) (xy 375.757957 -253.894371) (xy 375.806841 -253.908531) (xy 375.85282 -253.930348)
			(xy 375.894704 -253.959258) (xy 375.931408 -253.994513) (xy 375.961981 -254.035199) (xy 375.985632 -254.080262)
			(xy 376.001748 -254.128536) (xy 376.009912 -254.17877) (xy 376.010424 -254.204216) (xy 376.328952 -254.204216)
			(xy 376.332912 -254.155162) (xy 376.344689 -254.107378) (xy 376.36398 -254.062102) (xy 376.390283 -254.020506)
			(xy 376.422918 -253.983669) (xy 376.461039 -253.952544) (xy 376.50366 -253.927937) (xy 376.549676 -253.910485)
			(xy 376.597895 -253.900641) (xy 376.64707 -253.89866) (xy 376.695925 -253.904592) (xy 376.743196 -253.918284)
			(xy 376.787658 -253.939382) (xy 376.828161 -253.967338) (xy 376.863654 -254.00143) (xy 376.893219 -254.040774)
			(xy 376.91609 -254.084351) (xy 376.931674 -254.131032) (xy 376.939569 -254.179609) (xy 376.940064 -254.204216)
			(xy 377.258575 -254.204216) (xy 377.26267 -254.153488) (xy 377.274849 -254.104074) (xy 377.294797 -254.057254)
			(xy 377.321998 -254.01424) (xy 377.355746 -253.976146) (xy 377.395168 -253.943959) (xy 377.439242 -253.918513)
			(xy 377.486828 -253.900466) (xy 377.536692 -253.890286) (xy 377.587544 -253.888237) (xy 377.638065 -253.894371)
			(xy 377.686949 -253.908531) (xy 377.732928 -253.930348) (xy 377.774812 -253.959258) (xy 377.811516 -253.994513)
			(xy 377.842089 -254.035199) (xy 377.86574 -254.080262) (xy 377.881856 -254.128536) (xy 377.89002 -254.17877)
			(xy 377.890532 -254.204216) (xy 379.138683 -254.204216) (xy 379.142778 -254.153488) (xy 379.154957 -254.104074)
			(xy 379.174905 -254.057254) (xy 379.202106 -254.01424) (xy 379.235854 -253.976146) (xy 379.275276 -253.943959)
			(xy 379.31935 -253.918513) (xy 379.366936 -253.900466) (xy 379.4168 -253.890286) (xy 379.467652 -253.888237)
			(xy 379.518173 -253.894371) (xy 379.567057 -253.908531) (xy 379.613036 -253.930348) (xy 379.65492 -253.959258)
			(xy 379.691624 -253.994513) (xy 379.722197 -254.035199) (xy 379.745848 -254.080262) (xy 379.761964 -254.128536)
			(xy 379.770128 -254.17877) (xy 379.77064 -254.204216) (xy 380.078483 -254.204216) (xy 380.082578 -254.153488)
			(xy 380.094757 -254.104074) (xy 380.114705 -254.057254) (xy 380.141906 -254.01424) (xy 380.175654 -253.976146)
			(xy 380.215076 -253.943959) (xy 380.25915 -253.918513) (xy 380.306736 -253.900466) (xy 380.3566 -253.890286)
			(xy 380.407452 -253.888237) (xy 380.457973 -253.894371) (xy 380.506857 -253.908531) (xy 380.552836 -253.930348)
			(xy 380.59472 -253.959258) (xy 380.631424 -253.994513) (xy 380.661997 -254.035199) (xy 380.685648 -254.080262)
			(xy 380.701764 -254.128536) (xy 380.709928 -254.17877) (xy 380.71044 -254.204216) (xy 381.028968 -254.204216)
			(xy 381.032928 -254.155162) (xy 381.044705 -254.107378) (xy 381.063996 -254.062102) (xy 381.090299 -254.020506)
			(xy 381.122934 -253.983669) (xy 381.161055 -253.952544) (xy 381.203676 -253.927937) (xy 381.249692 -253.910485)
			(xy 381.297911 -253.900641) (xy 381.347086 -253.89866) (xy 381.395941 -253.904592) (xy 381.443212 -253.918284)
			(xy 381.487674 -253.939382) (xy 381.528177 -253.967338) (xy 381.56367 -254.00143) (xy 381.593235 -254.040774)
			(xy 381.616106 -254.084351) (xy 381.63169 -254.131032) (xy 381.639585 -254.179609) (xy 381.64008 -254.204216)
			(xy 381.969022 -254.204216) (xy 381.972982 -254.155162) (xy 381.984759 -254.107378) (xy 382.00405 -254.062102)
			(xy 382.030353 -254.020506) (xy 382.062988 -253.983669) (xy 382.101109 -253.952544) (xy 382.14373 -253.927937)
			(xy 382.189746 -253.910485) (xy 382.237965 -253.900641) (xy 382.28714 -253.89866) (xy 382.335995 -253.904592)
			(xy 382.383266 -253.918284) (xy 382.427728 -253.939382) (xy 382.468231 -253.967338) (xy 382.503724 -254.00143)
			(xy 382.533289 -254.040774) (xy 382.55616 -254.084351) (xy 382.571744 -254.131032) (xy 382.579639 -254.179609)
			(xy 382.580134 -254.204216) (xy 382.909076 -254.204216) (xy 382.913036 -254.155162) (xy 382.924813 -254.107378)
			(xy 382.944104 -254.062102) (xy 382.970407 -254.020506) (xy 383.003042 -253.983669) (xy 383.041163 -253.952544)
			(xy 383.083784 -253.927937) (xy 383.1298 -253.910485) (xy 383.178019 -253.900641) (xy 383.227194 -253.89866)
			(xy 383.276049 -253.904592) (xy 383.32332 -253.918284) (xy 383.367782 -253.939382) (xy 383.408285 -253.967338)
			(xy 383.443778 -254.00143) (xy 383.473343 -254.040774) (xy 383.496214 -254.084351) (xy 383.511798 -254.131032)
			(xy 383.519693 -254.179609) (xy 383.520188 -254.204216) (xy 383.84913 -254.204216) (xy 383.85309 -254.155162)
			(xy 383.864867 -254.107378) (xy 383.884158 -254.062102) (xy 383.910461 -254.020506) (xy 383.943096 -253.983669)
			(xy 383.981217 -253.952544) (xy 384.023838 -253.927937) (xy 384.069854 -253.910485) (xy 384.118073 -253.900641)
			(xy 384.167248 -253.89866) (xy 384.216103 -253.904592) (xy 384.263374 -253.918284) (xy 384.307836 -253.939382)
			(xy 384.348339 -253.967338) (xy 384.383832 -254.00143) (xy 384.413397 -254.040774) (xy 384.436268 -254.084351)
			(xy 384.451852 -254.131032) (xy 384.459747 -254.179609) (xy 384.460242 -254.204216) (xy 385.728984 -254.204216)
			(xy 385.732944 -254.155162) (xy 385.744721 -254.107378) (xy 385.764012 -254.062102) (xy 385.790315 -254.020506)
			(xy 385.82295 -253.983669) (xy 385.861071 -253.952544) (xy 385.903692 -253.927937) (xy 385.949708 -253.910485)
			(xy 385.997927 -253.900641) (xy 386.047102 -253.89866) (xy 386.095957 -253.904592) (xy 386.143228 -253.918284)
			(xy 386.18769 -253.939382) (xy 386.228193 -253.967338) (xy 386.263686 -254.00143) (xy 386.293251 -254.040774)
			(xy 386.316122 -254.084351) (xy 386.331706 -254.131032) (xy 386.339601 -254.179609) (xy 386.340096 -254.204216)
			(xy 386.669038 -254.204216) (xy 386.672998 -254.155162) (xy 386.684775 -254.107378) (xy 386.704066 -254.062102)
			(xy 386.730369 -254.020506) (xy 386.763004 -253.983669) (xy 386.801125 -253.952544) (xy 386.843746 -253.927937)
			(xy 386.889762 -253.910485) (xy 386.937981 -253.900641) (xy 386.987156 -253.89866) (xy 387.036011 -253.904592)
			(xy 387.083282 -253.918284) (xy 387.127744 -253.939382) (xy 387.168247 -253.967338) (xy 387.20374 -254.00143)
			(xy 387.233305 -254.040774) (xy 387.256176 -254.084351) (xy 387.27176 -254.131032) (xy 387.279655 -254.179609)
			(xy 387.28015 -254.204216) (xy 387.279655 -254.228823) (xy 387.27176 -254.2774) (xy 387.256176 -254.324081)
			(xy 387.233305 -254.367658) (xy 387.20374 -254.407002) (xy 387.168247 -254.441094) (xy 387.127744 -254.46905)
			(xy 387.083282 -254.490148) (xy 387.036011 -254.50384) (xy 386.987156 -254.509772) (xy 386.937981 -254.507791)
			(xy 386.889762 -254.497947) (xy 386.843746 -254.480495) (xy 386.801125 -254.455888) (xy 386.763004 -254.424763)
			(xy 386.730369 -254.387926) (xy 386.704066 -254.34633) (xy 386.684775 -254.301054) (xy 386.672998 -254.25327)
			(xy 386.669038 -254.204216) (xy 386.340096 -254.204216) (xy 386.339601 -254.228823) (xy 386.331706 -254.2774)
			(xy 386.316122 -254.324081) (xy 386.293251 -254.367658) (xy 386.263686 -254.407002) (xy 386.228193 -254.441094)
			(xy 386.18769 -254.46905) (xy 386.143228 -254.490148) (xy 386.095957 -254.50384) (xy 386.047102 -254.509772)
			(xy 385.997927 -254.507791) (xy 385.949708 -254.497947) (xy 385.903692 -254.480495) (xy 385.861071 -254.455888)
			(xy 385.82295 -254.424763) (xy 385.790315 -254.387926) (xy 385.764012 -254.34633) (xy 385.744721 -254.301054)
			(xy 385.732944 -254.25327) (xy 385.728984 -254.204216) (xy 384.460242 -254.204216) (xy 384.459747 -254.228823)
			(xy 384.451852 -254.2774) (xy 384.436268 -254.324081) (xy 384.413397 -254.367658) (xy 384.383832 -254.407002)
			(xy 384.348339 -254.441094) (xy 384.307836 -254.46905) (xy 384.263374 -254.490148) (xy 384.216103 -254.50384)
			(xy 384.167248 -254.509772) (xy 384.118073 -254.507791) (xy 384.069854 -254.497947) (xy 384.023838 -254.480495)
			(xy 383.981217 -254.455888) (xy 383.943096 -254.424763) (xy 383.910461 -254.387926) (xy 383.884158 -254.34633)
			(xy 383.864867 -254.301054) (xy 383.85309 -254.25327) (xy 383.84913 -254.204216) (xy 383.520188 -254.204216)
			(xy 383.519693 -254.228823) (xy 383.511798 -254.2774) (xy 383.496214 -254.324081) (xy 383.473343 -254.367658)
			(xy 383.443778 -254.407002) (xy 383.408285 -254.441094) (xy 383.367782 -254.46905) (xy 383.32332 -254.490148)
			(xy 383.276049 -254.50384) (xy 383.227194 -254.509772) (xy 383.178019 -254.507791) (xy 383.1298 -254.497947)
			(xy 383.083784 -254.480495) (xy 383.041163 -254.455888) (xy 383.003042 -254.424763) (xy 382.970407 -254.387926)
			(xy 382.944104 -254.34633) (xy 382.924813 -254.301054) (xy 382.913036 -254.25327) (xy 382.909076 -254.204216)
			(xy 382.580134 -254.204216) (xy 382.579639 -254.228823) (xy 382.571744 -254.2774) (xy 382.55616 -254.324081)
			(xy 382.533289 -254.367658) (xy 382.503724 -254.407002) (xy 382.468231 -254.441094) (xy 382.427728 -254.46905)
			(xy 382.383266 -254.490148) (xy 382.335995 -254.50384) (xy 382.28714 -254.509772) (xy 382.237965 -254.507791)
			(xy 382.189746 -254.497947) (xy 382.14373 -254.480495) (xy 382.101109 -254.455888) (xy 382.062988 -254.424763)
			(xy 382.030353 -254.387926) (xy 382.00405 -254.34633) (xy 381.984759 -254.301054) (xy 381.972982 -254.25327)
			(xy 381.969022 -254.204216) (xy 381.64008 -254.204216) (xy 381.639585 -254.228823) (xy 381.63169 -254.2774)
			(xy 381.616106 -254.324081) (xy 381.593235 -254.367658) (xy 381.56367 -254.407002) (xy 381.528177 -254.441094)
			(xy 381.487674 -254.46905) (xy 381.443212 -254.490148) (xy 381.395941 -254.50384) (xy 381.347086 -254.509772)
			(xy 381.297911 -254.507791) (xy 381.249692 -254.497947) (xy 381.203676 -254.480495) (xy 381.161055 -254.455888)
			(xy 381.122934 -254.424763) (xy 381.090299 -254.387926) (xy 381.063996 -254.34633) (xy 381.044705 -254.301054)
			(xy 381.032928 -254.25327) (xy 381.028968 -254.204216) (xy 380.71044 -254.204216) (xy 380.709928 -254.229662)
			(xy 380.701764 -254.279896) (xy 380.685648 -254.32817) (xy 380.661997 -254.373233) (xy 380.631424 -254.413919)
			(xy 380.59472 -254.449174) (xy 380.552836 -254.478084) (xy 380.506857 -254.499901) (xy 380.457973 -254.514061)
			(xy 380.407452 -254.520195) (xy 380.3566 -254.518146) (xy 380.306736 -254.507966) (xy 380.25915 -254.489919)
			(xy 380.215076 -254.464473) (xy 380.175654 -254.432286) (xy 380.141906 -254.394192) (xy 380.114705 -254.351178)
			(xy 380.094757 -254.304358) (xy 380.082578 -254.254944) (xy 380.078483 -254.204216) (xy 379.77064 -254.204216)
			(xy 379.770128 -254.229662) (xy 379.761964 -254.279896) (xy 379.745848 -254.32817) (xy 379.722197 -254.373233)
			(xy 379.691624 -254.413919) (xy 379.65492 -254.449174) (xy 379.613036 -254.478084) (xy 379.567057 -254.499901)
			(xy 379.518173 -254.514061) (xy 379.467652 -254.520195) (xy 379.4168 -254.518146) (xy 379.366936 -254.507966)
			(xy 379.31935 -254.489919) (xy 379.275276 -254.464473) (xy 379.235854 -254.432286) (xy 379.202106 -254.394192)
			(xy 379.174905 -254.351178) (xy 379.154957 -254.304358) (xy 379.142778 -254.254944) (xy 379.138683 -254.204216)
			(xy 377.890532 -254.204216) (xy 377.89002 -254.229662) (xy 377.881856 -254.279896) (xy 377.86574 -254.32817)
			(xy 377.842089 -254.373233) (xy 377.811516 -254.413919) (xy 377.774812 -254.449174) (xy 377.732928 -254.478084)
			(xy 377.686949 -254.499901) (xy 377.638065 -254.514061) (xy 377.587544 -254.520195) (xy 377.536692 -254.518146)
			(xy 377.486828 -254.507966) (xy 377.439242 -254.489919) (xy 377.395168 -254.464473) (xy 377.355746 -254.432286)
			(xy 377.321998 -254.394192) (xy 377.294797 -254.351178) (xy 377.274849 -254.304358) (xy 377.26267 -254.254944)
			(xy 377.258575 -254.204216) (xy 376.940064 -254.204216) (xy 376.939569 -254.228823) (xy 376.931674 -254.2774)
			(xy 376.91609 -254.324081) (xy 376.893219 -254.367658) (xy 376.863654 -254.407002) (xy 376.828161 -254.441094)
			(xy 376.787658 -254.46905) (xy 376.743196 -254.490148) (xy 376.695925 -254.50384) (xy 376.64707 -254.509772)
			(xy 376.597895 -254.507791) (xy 376.549676 -254.497947) (xy 376.50366 -254.480495) (xy 376.461039 -254.455888)
			(xy 376.422918 -254.424763) (xy 376.390283 -254.387926) (xy 376.36398 -254.34633) (xy 376.344689 -254.301054)
			(xy 376.332912 -254.25327) (xy 376.328952 -254.204216) (xy 376.010424 -254.204216) (xy 376.009912 -254.229662)
			(xy 376.001748 -254.279896) (xy 375.985632 -254.32817) (xy 375.961981 -254.373233) (xy 375.931408 -254.413919)
			(xy 375.894704 -254.449174) (xy 375.85282 -254.478084) (xy 375.806841 -254.499901) (xy 375.757957 -254.514061)
			(xy 375.707436 -254.520195) (xy 375.656584 -254.518146) (xy 375.60672 -254.507966) (xy 375.559134 -254.489919)
			(xy 375.51506 -254.464473) (xy 375.475638 -254.432286) (xy 375.44189 -254.394192) (xy 375.414689 -254.351178)
			(xy 375.394741 -254.304358) (xy 375.382562 -254.254944) (xy 375.378467 -254.204216) (xy 375.06021 -254.204216)
			(xy 375.059715 -254.228823) (xy 375.05182 -254.2774) (xy 375.036236 -254.324081) (xy 375.013365 -254.367658)
			(xy 374.9838 -254.407002) (xy 374.948307 -254.441094) (xy 374.907804 -254.46905) (xy 374.863342 -254.490148)
			(xy 374.816071 -254.50384) (xy 374.767216 -254.509772) (xy 374.718041 -254.507791) (xy 374.669822 -254.497947)
			(xy 374.623806 -254.480495) (xy 374.581185 -254.455888) (xy 374.543064 -254.424763) (xy 374.510429 -254.387926)
			(xy 374.484126 -254.34633) (xy 374.464835 -254.301054) (xy 374.453058 -254.25327) (xy 374.449098 -254.204216)
			(xy 373.180102 -254.204216) (xy 373.179607 -254.228823) (xy 373.171712 -254.2774) (xy 373.156128 -254.324081)
			(xy 373.133257 -254.367658) (xy 373.103692 -254.407002) (xy 373.068199 -254.441094) (xy 373.027696 -254.46905)
			(xy 372.983234 -254.490148) (xy 372.935963 -254.50384) (xy 372.887108 -254.509772) (xy 372.837933 -254.507791)
			(xy 372.789714 -254.497947) (xy 372.743698 -254.480495) (xy 372.701077 -254.455888) (xy 372.662956 -254.424763)
			(xy 372.630321 -254.387926) (xy 372.604018 -254.34633) (xy 372.584727 -254.301054) (xy 372.57295 -254.25327)
			(xy 372.56899 -254.204216) (xy 371.299994 -254.204216) (xy 371.299499 -254.228823) (xy 371.291604 -254.2774)
			(xy 371.27602 -254.324081) (xy 371.253149 -254.367658) (xy 371.223584 -254.407002) (xy 371.188091 -254.441094)
			(xy 371.147588 -254.46905) (xy 371.103126 -254.490148) (xy 371.055855 -254.50384) (xy 371.007 -254.509772)
			(xy 370.957825 -254.507791) (xy 370.909606 -254.497947) (xy 370.86359 -254.480495) (xy 370.820969 -254.455888)
			(xy 370.782848 -254.424763) (xy 370.750213 -254.387926) (xy 370.72391 -254.34633) (xy 370.704619 -254.301054)
			(xy 370.692842 -254.25327) (xy 370.688882 -254.204216) (xy 369.42014 -254.204216) (xy 369.419645 -254.228823)
			(xy 369.41175 -254.2774) (xy 369.396166 -254.324081) (xy 369.373295 -254.367658) (xy 369.34373 -254.407002)
			(xy 369.308237 -254.441094) (xy 369.267734 -254.46905) (xy 369.223272 -254.490148) (xy 369.176001 -254.50384)
			(xy 369.127146 -254.509772) (xy 369.077971 -254.507791) (xy 369.029752 -254.497947) (xy 368.983736 -254.480495)
			(xy 368.941115 -254.455888) (xy 368.902994 -254.424763) (xy 368.870359 -254.387926) (xy 368.844056 -254.34633)
			(xy 368.824765 -254.301054) (xy 368.812988 -254.25327) (xy 368.809028 -254.204216) (xy 360.438648 -254.204216)
			(xy 360.46298 -254.229498) (xy 360.493272 -254.272564) (xy 360.516635 -254.319749) (xy 360.532521 -254.369948)
			(xy 360.540558 -254.421984) (xy 360.541062 -254.44831) (xy 360.540558 -254.474636) (xy 360.532521 -254.526672)
			(xy 360.516635 -254.576871) (xy 360.493272 -254.624056) (xy 360.46298 -254.667122) (xy 360.426468 -254.70506)
			(xy 360.384594 -254.736979) (xy 360.338338 -254.762132) (xy 360.288785 -254.77993) (xy 360.237095 -254.789954)
			(xy 360.184481 -254.791971) (xy 360.132176 -254.785933) (xy 360.081405 -254.771981) (xy 360.03336 -254.750442)
			(xy 359.989165 -254.721822) (xy 359.949857 -254.686791) (xy 359.916357 -254.64617) (xy 359.889451 -254.600911)
			(xy 359.869768 -254.552076) (xy 359.857771 -254.500808) (xy 359.853741 -254.44831) (xy 353.209352 -254.44831)
			(xy 353.775264 -255.014222) (xy 370.218982 -255.014222) (xy 370.222942 -254.965168) (xy 370.234719 -254.917384)
			(xy 370.25401 -254.872108) (xy 370.280313 -254.830512) (xy 370.312948 -254.793675) (xy 370.351069 -254.76255)
			(xy 370.39369 -254.737943) (xy 370.439706 -254.720491) (xy 370.487925 -254.710647) (xy 370.5371 -254.708666)
			(xy 370.585955 -254.714598) (xy 370.633226 -254.72829) (xy 370.677688 -254.749388) (xy 370.718191 -254.777344)
			(xy 370.753684 -254.811436) (xy 370.783249 -254.85078) (xy 370.80612 -254.894357) (xy 370.821704 -254.941038)
			(xy 370.829599 -254.989615) (xy 370.830094 -255.014222) (xy 372.09909 -255.014222) (xy 372.10305 -254.965168)
			(xy 372.114827 -254.917384) (xy 372.134118 -254.872108) (xy 372.160421 -254.830512) (xy 372.193056 -254.793675)
			(xy 372.231177 -254.76255) (xy 372.273798 -254.737943) (xy 372.319814 -254.720491) (xy 372.368033 -254.710647)
			(xy 372.417208 -254.708666) (xy 372.466063 -254.714598) (xy 372.513334 -254.72829) (xy 372.557796 -254.749388)
			(xy 372.598299 -254.777344) (xy 372.633792 -254.811436) (xy 372.663357 -254.85078) (xy 372.686228 -254.894357)
			(xy 372.701812 -254.941038) (xy 372.709707 -254.989615) (xy 372.710202 -255.014222) (xy 373.978944 -255.014222)
			(xy 373.982904 -254.965168) (xy 373.994681 -254.917384) (xy 374.013972 -254.872108) (xy 374.040275 -254.830512)
			(xy 374.07291 -254.793675) (xy 374.111031 -254.76255) (xy 374.153652 -254.737943) (xy 374.199668 -254.720491)
			(xy 374.247887 -254.710647) (xy 374.297062 -254.708666) (xy 374.345917 -254.714598) (xy 374.393188 -254.72829)
			(xy 374.43765 -254.749388) (xy 374.478153 -254.777344) (xy 374.513646 -254.811436) (xy 374.543211 -254.85078)
			(xy 374.566082 -254.894357) (xy 374.581666 -254.941038) (xy 374.589561 -254.989615) (xy 374.590056 -255.014222)
			(xy 375.848621 -255.014222) (xy 375.852716 -254.963494) (xy 375.864895 -254.91408) (xy 375.884843 -254.86726)
			(xy 375.912044 -254.824246) (xy 375.945792 -254.786152) (xy 375.985214 -254.753965) (xy 376.029288 -254.728519)
			(xy 376.076874 -254.710472) (xy 376.126738 -254.700292) (xy 376.17759 -254.698243) (xy 376.228111 -254.704377)
			(xy 376.276995 -254.718537) (xy 376.322974 -254.740354) (xy 376.364858 -254.769264) (xy 376.401562 -254.804519)
			(xy 376.432135 -254.845205) (xy 376.455786 -254.890268) (xy 376.471902 -254.938542) (xy 376.480066 -254.988776)
			(xy 376.480578 -255.014222) (xy 376.788675 -255.014222) (xy 376.79277 -254.963494) (xy 376.804949 -254.91408)
			(xy 376.824897 -254.86726) (xy 376.852098 -254.824246) (xy 376.885846 -254.786152) (xy 376.925268 -254.753965)
			(xy 376.969342 -254.728519) (xy 377.016928 -254.710472) (xy 377.066792 -254.700292) (xy 377.117644 -254.698243)
			(xy 377.168165 -254.704377) (xy 377.217049 -254.718537) (xy 377.263028 -254.740354) (xy 377.304912 -254.769264)
			(xy 377.341616 -254.804519) (xy 377.372189 -254.845205) (xy 377.39584 -254.890268) (xy 377.411956 -254.938542)
			(xy 377.42012 -254.988776) (xy 377.420632 -255.014222) (xy 377.738906 -255.014222) (xy 377.742866 -254.965168)
			(xy 377.754643 -254.917384) (xy 377.773934 -254.872108) (xy 377.800237 -254.830512) (xy 377.832872 -254.793675)
			(xy 377.870993 -254.76255) (xy 377.913614 -254.737943) (xy 377.95963 -254.720491) (xy 378.007849 -254.710647)
			(xy 378.057024 -254.708666) (xy 378.105879 -254.714598) (xy 378.15315 -254.72829) (xy 378.197612 -254.749388)
			(xy 378.238115 -254.777344) (xy 378.273608 -254.811436) (xy 378.303173 -254.85078) (xy 378.326044 -254.894357)
			(xy 378.341628 -254.941038) (xy 378.349523 -254.989615) (xy 378.350018 -255.014222) (xy 378.668529 -255.014222)
			(xy 378.672624 -254.963494) (xy 378.684803 -254.91408) (xy 378.704751 -254.86726) (xy 378.731952 -254.824246)
			(xy 378.7657 -254.786152) (xy 378.805122 -254.753965) (xy 378.849196 -254.728519) (xy 378.896782 -254.710472)
			(xy 378.946646 -254.700292) (xy 378.997498 -254.698243) (xy 379.048019 -254.704377) (xy 379.096903 -254.718537)
			(xy 379.142882 -254.740354) (xy 379.184766 -254.769264) (xy 379.22147 -254.804519) (xy 379.252043 -254.845205)
			(xy 379.275694 -254.890268) (xy 379.29181 -254.938542) (xy 379.299974 -254.988776) (xy 379.300486 -255.014222)
			(xy 379.619014 -255.014222) (xy 379.622974 -254.965168) (xy 379.634751 -254.917384) (xy 379.654042 -254.872108)
			(xy 379.680345 -254.830512) (xy 379.71298 -254.793675) (xy 379.751101 -254.76255) (xy 379.793722 -254.737943)
			(xy 379.839738 -254.720491) (xy 379.887957 -254.710647) (xy 379.937132 -254.708666) (xy 379.985987 -254.714598)
			(xy 380.033258 -254.72829) (xy 380.07772 -254.749388) (xy 380.118223 -254.777344) (xy 380.153716 -254.811436)
			(xy 380.183281 -254.85078) (xy 380.206152 -254.894357) (xy 380.221736 -254.941038) (xy 380.229631 -254.989615)
			(xy 380.230126 -255.014222) (xy 380.548637 -255.014222) (xy 380.552732 -254.963494) (xy 380.564911 -254.91408)
			(xy 380.584859 -254.86726) (xy 380.61206 -254.824246) (xy 380.645808 -254.786152) (xy 380.68523 -254.753965)
			(xy 380.729304 -254.728519) (xy 380.77689 -254.710472) (xy 380.826754 -254.700292) (xy 380.877606 -254.698243)
			(xy 380.928127 -254.704377) (xy 380.977011 -254.718537) (xy 381.02299 -254.740354) (xy 381.064874 -254.769264)
			(xy 381.101578 -254.804519) (xy 381.132151 -254.845205) (xy 381.155802 -254.890268) (xy 381.171918 -254.938542)
			(xy 381.180082 -254.988776) (xy 381.180594 -255.014222) (xy 381.499122 -255.014222) (xy 381.503082 -254.965168)
			(xy 381.514859 -254.917384) (xy 381.53415 -254.872108) (xy 381.560453 -254.830512) (xy 381.593088 -254.793675)
			(xy 381.631209 -254.76255) (xy 381.67383 -254.737943) (xy 381.719846 -254.720491) (xy 381.768065 -254.710647)
			(xy 381.81724 -254.708666) (xy 381.866095 -254.714598) (xy 381.913366 -254.72829) (xy 381.957828 -254.749388)
			(xy 381.998331 -254.777344) (xy 382.033824 -254.811436) (xy 382.063389 -254.85078) (xy 382.08626 -254.894357)
			(xy 382.101844 -254.941038) (xy 382.109739 -254.989615) (xy 382.110234 -255.014222) (xy 382.438922 -255.014222)
			(xy 382.442882 -254.965168) (xy 382.454659 -254.917384) (xy 382.47395 -254.872108) (xy 382.500253 -254.830512)
			(xy 382.532888 -254.793675) (xy 382.571009 -254.76255) (xy 382.61363 -254.737943) (xy 382.659646 -254.720491)
			(xy 382.707865 -254.710647) (xy 382.75704 -254.708666) (xy 382.805895 -254.714598) (xy 382.853166 -254.72829)
			(xy 382.897628 -254.749388) (xy 382.938131 -254.777344) (xy 382.973624 -254.811436) (xy 383.003189 -254.85078)
			(xy 383.02606 -254.894357) (xy 383.041644 -254.941038) (xy 383.049539 -254.989615) (xy 383.050034 -255.014222)
			(xy 383.378976 -255.014222) (xy 383.382936 -254.965168) (xy 383.394713 -254.917384) (xy 383.414004 -254.872108)
			(xy 383.440307 -254.830512) (xy 383.472942 -254.793675) (xy 383.511063 -254.76255) (xy 383.553684 -254.737943)
			(xy 383.5997 -254.720491) (xy 383.647919 -254.710647) (xy 383.697094 -254.708666) (xy 383.745949 -254.714598)
			(xy 383.79322 -254.72829) (xy 383.837682 -254.749388) (xy 383.878185 -254.777344) (xy 383.913678 -254.811436)
			(xy 383.943243 -254.85078) (xy 383.966114 -254.894357) (xy 383.981698 -254.941038) (xy 383.989593 -254.989615)
			(xy 383.990088 -255.014222) (xy 384.31903 -255.014222) (xy 384.32299 -254.965168) (xy 384.334767 -254.917384)
			(xy 384.354058 -254.872108) (xy 384.380361 -254.830512) (xy 384.412996 -254.793675) (xy 384.451117 -254.76255)
			(xy 384.493738 -254.737943) (xy 384.539754 -254.720491) (xy 384.587973 -254.710647) (xy 384.637148 -254.708666)
			(xy 384.686003 -254.714598) (xy 384.733274 -254.72829) (xy 384.777736 -254.749388) (xy 384.818239 -254.777344)
			(xy 384.853732 -254.811436) (xy 384.883297 -254.85078) (xy 384.906168 -254.894357) (xy 384.921752 -254.941038)
			(xy 384.929647 -254.989615) (xy 384.930142 -255.014222) (xy 385.259084 -255.014222) (xy 385.263044 -254.965168)
			(xy 385.274821 -254.917384) (xy 385.294112 -254.872108) (xy 385.320415 -254.830512) (xy 385.35305 -254.793675)
			(xy 385.391171 -254.76255) (xy 385.433792 -254.737943) (xy 385.479808 -254.720491) (xy 385.528027 -254.710647)
			(xy 385.577202 -254.708666) (xy 385.626057 -254.714598) (xy 385.673328 -254.72829) (xy 385.71779 -254.749388)
			(xy 385.758293 -254.777344) (xy 385.793786 -254.811436) (xy 385.823351 -254.85078) (xy 385.846222 -254.894357)
			(xy 385.861806 -254.941038) (xy 385.869701 -254.989615) (xy 385.870196 -255.014222) (xy 386.199138 -255.014222)
			(xy 386.203098 -254.965168) (xy 386.214875 -254.917384) (xy 386.234166 -254.872108) (xy 386.260469 -254.830512)
			(xy 386.293104 -254.793675) (xy 386.331225 -254.76255) (xy 386.373846 -254.737943) (xy 386.419862 -254.720491)
			(xy 386.468081 -254.710647) (xy 386.517256 -254.708666) (xy 386.566111 -254.714598) (xy 386.613382 -254.72829)
			(xy 386.657844 -254.749388) (xy 386.698347 -254.777344) (xy 386.73384 -254.811436) (xy 386.763405 -254.85078)
			(xy 386.786276 -254.894357) (xy 386.80186 -254.941038) (xy 386.809755 -254.989615) (xy 386.81025 -255.014222)
			(xy 387.138938 -255.014222) (xy 387.142898 -254.965168) (xy 387.154675 -254.917384) (xy 387.173966 -254.872108)
			(xy 387.200269 -254.830512) (xy 387.232904 -254.793675) (xy 387.271025 -254.76255) (xy 387.313646 -254.737943)
			(xy 387.359662 -254.720491) (xy 387.407881 -254.710647) (xy 387.457056 -254.708666) (xy 387.505911 -254.714598)
			(xy 387.553182 -254.72829) (xy 387.597644 -254.749388) (xy 387.638147 -254.777344) (xy 387.67364 -254.811436)
			(xy 387.703205 -254.85078) (xy 387.726076 -254.894357) (xy 387.74166 -254.941038) (xy 387.749555 -254.989615)
			(xy 387.75005 -255.014222) (xy 387.749555 -255.038829) (xy 387.74166 -255.087406) (xy 387.726076 -255.134087)
			(xy 387.703205 -255.177664) (xy 387.67364 -255.217008) (xy 387.638147 -255.2511) (xy 387.597644 -255.279056)
			(xy 387.553182 -255.300154) (xy 387.505911 -255.313846) (xy 387.457056 -255.319778) (xy 387.407881 -255.317797)
			(xy 387.359662 -255.307953) (xy 387.313646 -255.290501) (xy 387.271025 -255.265894) (xy 387.232904 -255.234769)
			(xy 387.200269 -255.197932) (xy 387.173966 -255.156336) (xy 387.154675 -255.11106) (xy 387.142898 -255.063276)
			(xy 387.138938 -255.014222) (xy 386.81025 -255.014222) (xy 386.809755 -255.038829) (xy 386.80186 -255.087406)
			(xy 386.786276 -255.134087) (xy 386.763405 -255.177664) (xy 386.73384 -255.217008) (xy 386.698347 -255.2511)
			(xy 386.657844 -255.279056) (xy 386.613382 -255.300154) (xy 386.566111 -255.313846) (xy 386.517256 -255.319778)
			(xy 386.468081 -255.317797) (xy 386.419862 -255.307953) (xy 386.373846 -255.290501) (xy 386.331225 -255.265894)
			(xy 386.293104 -255.234769) (xy 386.260469 -255.197932) (xy 386.234166 -255.156336) (xy 386.214875 -255.11106)
			(xy 386.203098 -255.063276) (xy 386.199138 -255.014222) (xy 385.870196 -255.014222) (xy 385.869701 -255.038829)
			(xy 385.861806 -255.087406) (xy 385.846222 -255.134087) (xy 385.823351 -255.177664) (xy 385.793786 -255.217008)
			(xy 385.758293 -255.2511) (xy 385.71779 -255.279056) (xy 385.673328 -255.300154) (xy 385.626057 -255.313846)
			(xy 385.577202 -255.319778) (xy 385.528027 -255.317797) (xy 385.479808 -255.307953) (xy 385.433792 -255.290501)
			(xy 385.391171 -255.265894) (xy 385.35305 -255.234769) (xy 385.320415 -255.197932) (xy 385.294112 -255.156336)
			(xy 385.274821 -255.11106) (xy 385.263044 -255.063276) (xy 385.259084 -255.014222) (xy 384.930142 -255.014222)
			(xy 384.929647 -255.038829) (xy 384.921752 -255.087406) (xy 384.906168 -255.134087) (xy 384.883297 -255.177664)
			(xy 384.853732 -255.217008) (xy 384.818239 -255.2511) (xy 384.777736 -255.279056) (xy 384.733274 -255.300154)
			(xy 384.686003 -255.313846) (xy 384.637148 -255.319778) (xy 384.587973 -255.317797) (xy 384.539754 -255.307953)
			(xy 384.493738 -255.290501) (xy 384.451117 -255.265894) (xy 384.412996 -255.234769) (xy 384.380361 -255.197932)
			(xy 384.354058 -255.156336) (xy 384.334767 -255.11106) (xy 384.32299 -255.063276) (xy 384.31903 -255.014222)
			(xy 383.990088 -255.014222) (xy 383.989593 -255.038829) (xy 383.981698 -255.087406) (xy 383.966114 -255.134087)
			(xy 383.943243 -255.177664) (xy 383.913678 -255.217008) (xy 383.878185 -255.2511) (xy 383.837682 -255.279056)
			(xy 383.79322 -255.300154) (xy 383.745949 -255.313846) (xy 383.697094 -255.319778) (xy 383.647919 -255.317797)
			(xy 383.5997 -255.307953) (xy 383.553684 -255.290501) (xy 383.511063 -255.265894) (xy 383.472942 -255.234769)
			(xy 383.440307 -255.197932) (xy 383.414004 -255.156336) (xy 383.394713 -255.11106) (xy 383.382936 -255.063276)
			(xy 383.378976 -255.014222) (xy 383.050034 -255.014222) (xy 383.049539 -255.038829) (xy 383.041644 -255.087406)
			(xy 383.02606 -255.134087) (xy 383.003189 -255.177664) (xy 382.973624 -255.217008) (xy 382.938131 -255.2511)
			(xy 382.897628 -255.279056) (xy 382.853166 -255.300154) (xy 382.805895 -255.313846) (xy 382.75704 -255.319778)
			(xy 382.707865 -255.317797) (xy 382.659646 -255.307953) (xy 382.61363 -255.290501) (xy 382.571009 -255.265894)
			(xy 382.532888 -255.234769) (xy 382.500253 -255.197932) (xy 382.47395 -255.156336) (xy 382.454659 -255.11106)
			(xy 382.442882 -255.063276) (xy 382.438922 -255.014222) (xy 382.110234 -255.014222) (xy 382.109739 -255.038829)
			(xy 382.101844 -255.087406) (xy 382.08626 -255.134087) (xy 382.063389 -255.177664) (xy 382.033824 -255.217008)
			(xy 381.998331 -255.2511) (xy 381.957828 -255.279056) (xy 381.913366 -255.300154) (xy 381.866095 -255.313846)
			(xy 381.81724 -255.319778) (xy 381.768065 -255.317797) (xy 381.719846 -255.307953) (xy 381.67383 -255.290501)
			(xy 381.631209 -255.265894) (xy 381.593088 -255.234769) (xy 381.560453 -255.197932) (xy 381.53415 -255.156336)
			(xy 381.514859 -255.11106) (xy 381.503082 -255.063276) (xy 381.499122 -255.014222) (xy 381.180594 -255.014222)
			(xy 381.180082 -255.039668) (xy 381.171918 -255.089902) (xy 381.155802 -255.138176) (xy 381.132151 -255.183239)
			(xy 381.101578 -255.223925) (xy 381.064874 -255.25918) (xy 381.02299 -255.28809) (xy 380.977011 -255.309907)
			(xy 380.928127 -255.324067) (xy 380.877606 -255.330201) (xy 380.826754 -255.328152) (xy 380.77689 -255.317972)
			(xy 380.729304 -255.299925) (xy 380.68523 -255.274479) (xy 380.645808 -255.242292) (xy 380.61206 -255.204198)
			(xy 380.584859 -255.161184) (xy 380.564911 -255.114364) (xy 380.552732 -255.06495) (xy 380.548637 -255.014222)
			(xy 380.230126 -255.014222) (xy 380.229631 -255.038829) (xy 380.221736 -255.087406) (xy 380.206152 -255.134087)
			(xy 380.183281 -255.177664) (xy 380.153716 -255.217008) (xy 380.118223 -255.2511) (xy 380.07772 -255.279056)
			(xy 380.033258 -255.300154) (xy 379.985987 -255.313846) (xy 379.937132 -255.319778) (xy 379.887957 -255.317797)
			(xy 379.839738 -255.307953) (xy 379.793722 -255.290501) (xy 379.751101 -255.265894) (xy 379.71298 -255.234769)
			(xy 379.680345 -255.197932) (xy 379.654042 -255.156336) (xy 379.634751 -255.11106) (xy 379.622974 -255.063276)
			(xy 379.619014 -255.014222) (xy 379.300486 -255.014222) (xy 379.299974 -255.039668) (xy 379.29181 -255.089902)
			(xy 379.275694 -255.138176) (xy 379.252043 -255.183239) (xy 379.22147 -255.223925) (xy 379.184766 -255.25918)
			(xy 379.142882 -255.28809) (xy 379.096903 -255.309907) (xy 379.048019 -255.324067) (xy 378.997498 -255.330201)
			(xy 378.946646 -255.328152) (xy 378.896782 -255.317972) (xy 378.849196 -255.299925) (xy 378.805122 -255.274479)
			(xy 378.7657 -255.242292) (xy 378.731952 -255.204198) (xy 378.704751 -255.161184) (xy 378.684803 -255.114364)
			(xy 378.672624 -255.06495) (xy 378.668529 -255.014222) (xy 378.350018 -255.014222) (xy 378.349523 -255.038829)
			(xy 378.341628 -255.087406) (xy 378.326044 -255.134087) (xy 378.303173 -255.177664) (xy 378.273608 -255.217008)
			(xy 378.238115 -255.2511) (xy 378.197612 -255.279056) (xy 378.15315 -255.300154) (xy 378.105879 -255.313846)
			(xy 378.057024 -255.319778) (xy 378.007849 -255.317797) (xy 377.95963 -255.307953) (xy 377.913614 -255.290501)
			(xy 377.870993 -255.265894) (xy 377.832872 -255.234769) (xy 377.800237 -255.197932) (xy 377.773934 -255.156336)
			(xy 377.754643 -255.11106) (xy 377.742866 -255.063276) (xy 377.738906 -255.014222) (xy 377.420632 -255.014222)
			(xy 377.42012 -255.039668) (xy 377.411956 -255.089902) (xy 377.39584 -255.138176) (xy 377.372189 -255.183239)
			(xy 377.341616 -255.223925) (xy 377.304912 -255.25918) (xy 377.263028 -255.28809) (xy 377.217049 -255.309907)
			(xy 377.168165 -255.324067) (xy 377.117644 -255.330201) (xy 377.066792 -255.328152) (xy 377.016928 -255.317972)
			(xy 376.969342 -255.299925) (xy 376.925268 -255.274479) (xy 376.885846 -255.242292) (xy 376.852098 -255.204198)
			(xy 376.824897 -255.161184) (xy 376.804949 -255.114364) (xy 376.79277 -255.06495) (xy 376.788675 -255.014222)
			(xy 376.480578 -255.014222) (xy 376.480066 -255.039668) (xy 376.471902 -255.089902) (xy 376.455786 -255.138176)
			(xy 376.432135 -255.183239) (xy 376.401562 -255.223925) (xy 376.364858 -255.25918) (xy 376.322974 -255.28809)
			(xy 376.276995 -255.309907) (xy 376.228111 -255.324067) (xy 376.17759 -255.330201) (xy 376.126738 -255.328152)
			(xy 376.076874 -255.317972) (xy 376.029288 -255.299925) (xy 375.985214 -255.274479) (xy 375.945792 -255.242292)
			(xy 375.912044 -255.204198) (xy 375.884843 -255.161184) (xy 375.864895 -255.114364) (xy 375.852716 -255.06495)
			(xy 375.848621 -255.014222) (xy 374.590056 -255.014222) (xy 374.589561 -255.038829) (xy 374.581666 -255.087406)
			(xy 374.566082 -255.134087) (xy 374.543211 -255.177664) (xy 374.513646 -255.217008) (xy 374.478153 -255.2511)
			(xy 374.43765 -255.279056) (xy 374.393188 -255.300154) (xy 374.345917 -255.313846) (xy 374.297062 -255.319778)
			(xy 374.247887 -255.317797) (xy 374.199668 -255.307953) (xy 374.153652 -255.290501) (xy 374.111031 -255.265894)
			(xy 374.07291 -255.234769) (xy 374.040275 -255.197932) (xy 374.013972 -255.156336) (xy 373.994681 -255.11106)
			(xy 373.982904 -255.063276) (xy 373.978944 -255.014222) (xy 372.710202 -255.014222) (xy 372.709707 -255.038829)
			(xy 372.701812 -255.087406) (xy 372.686228 -255.134087) (xy 372.663357 -255.177664) (xy 372.633792 -255.217008)
			(xy 372.598299 -255.2511) (xy 372.557796 -255.279056) (xy 372.513334 -255.300154) (xy 372.466063 -255.313846)
			(xy 372.417208 -255.319778) (xy 372.368033 -255.317797) (xy 372.319814 -255.307953) (xy 372.273798 -255.290501)
			(xy 372.231177 -255.265894) (xy 372.193056 -255.234769) (xy 372.160421 -255.197932) (xy 372.134118 -255.156336)
			(xy 372.114827 -255.11106) (xy 372.10305 -255.063276) (xy 372.09909 -255.014222) (xy 370.830094 -255.014222)
			(xy 370.829599 -255.038829) (xy 370.821704 -255.087406) (xy 370.80612 -255.134087) (xy 370.783249 -255.177664)
			(xy 370.753684 -255.217008) (xy 370.718191 -255.2511) (xy 370.677688 -255.279056) (xy 370.633226 -255.300154)
			(xy 370.585955 -255.313846) (xy 370.5371 -255.319778) (xy 370.487925 -255.317797) (xy 370.439706 -255.307953)
			(xy 370.39369 -255.290501) (xy 370.351069 -255.265894) (xy 370.312948 -255.234769) (xy 370.280313 -255.197932)
			(xy 370.25401 -255.156336) (xy 370.234719 -255.11106) (xy 370.222942 -255.063276) (xy 370.218982 -255.014222)
			(xy 353.775264 -255.014222) (xy 354.025454 -255.264412) (xy 354.032735 -255.271084) (xy 354.050902 -255.278778)
			(xy 354.06076 -255.279398) (xy 354.081588 -255.279652) (xy 354.086191 -255.279622) (xy 354.095265 -255.278088)
			(xy 354.099622 -255.276604) (xy 354.123244 -255.267968) (xy 354.129848 -255.262634) (xy 354.152947 -255.244785)
			(xy 354.203948 -255.216391) (xy 354.259014 -255.197027) (xy 354.316561 -255.187251) (xy 354.345748 -255.186688)
			(xy 354.353114 -255.186688) (xy 354.379692 -255.187792) (xy 354.432048 -255.197191) (xy 354.482328 -255.214553)
			(xy 354.529328 -255.239462) (xy 354.571923 -255.271322) (xy 354.609095 -255.309372) (xy 354.639953 -255.352699)
			(xy 354.663758 -255.400267) (xy 354.679942 -255.450938) (xy 354.688117 -255.503499) (xy 354.688648 -255.530096)
			(xy 365.036865 -255.530096) (xy 365.040895 -255.477598) (xy 365.052892 -255.42633) (xy 365.072575 -255.377495)
			(xy 365.099481 -255.332236) (xy 365.132981 -255.291615) (xy 365.172289 -255.256584) (xy 365.216484 -255.227964)
			(xy 365.264529 -255.206425) (xy 365.3153 -255.192473) (xy 365.367605 -255.186435) (xy 365.420219 -255.188452)
			(xy 365.471909 -255.198476) (xy 365.521462 -255.216274) (xy 365.567718 -255.241427) (xy 365.609592 -255.273346)
			(xy 365.646104 -255.311284) (xy 365.676396 -255.35435) (xy 365.699759 -255.401535) (xy 365.715645 -255.451734)
			(xy 365.723682 -255.50377) (xy 365.724186 -255.530096) (xy 365.723682 -255.556422) (xy 365.715645 -255.608458)
			(xy 365.699759 -255.658657) (xy 365.676396 -255.705842) (xy 365.646104 -255.748908) (xy 365.609592 -255.786846)
			(xy 365.567718 -255.818765) (xy 365.557672 -255.824228) (xy 368.809028 -255.824228) (xy 368.812988 -255.775174)
			(xy 368.824765 -255.72739) (xy 368.844056 -255.682114) (xy 368.870359 -255.640518) (xy 368.902994 -255.603681)
			(xy 368.941115 -255.572556) (xy 368.983736 -255.547949) (xy 369.029752 -255.530497) (xy 369.077971 -255.520653)
			(xy 369.127146 -255.518672) (xy 369.176001 -255.524604) (xy 369.223272 -255.538296) (xy 369.267734 -255.559394)
			(xy 369.308237 -255.58735) (xy 369.34373 -255.621442) (xy 369.373295 -255.660786) (xy 369.396166 -255.704363)
			(xy 369.41175 -255.751044) (xy 369.419645 -255.799621) (xy 369.42014 -255.824228) (xy 370.688882 -255.824228)
			(xy 370.692842 -255.775174) (xy 370.704619 -255.72739) (xy 370.72391 -255.682114) (xy 370.750213 -255.640518)
			(xy 370.782848 -255.603681) (xy 370.820969 -255.572556) (xy 370.86359 -255.547949) (xy 370.909606 -255.530497)
			(xy 370.957825 -255.520653) (xy 371.007 -255.518672) (xy 371.055855 -255.524604) (xy 371.103126 -255.538296)
			(xy 371.147588 -255.559394) (xy 371.188091 -255.58735) (xy 371.223584 -255.621442) (xy 371.253149 -255.660786)
			(xy 371.27602 -255.704363) (xy 371.291604 -255.751044) (xy 371.299499 -255.799621) (xy 371.299994 -255.824228)
			(xy 372.56899 -255.824228) (xy 372.57295 -255.775174) (xy 372.584727 -255.72739) (xy 372.604018 -255.682114)
			(xy 372.630321 -255.640518) (xy 372.662956 -255.603681) (xy 372.701077 -255.572556) (xy 372.743698 -255.547949)
			(xy 372.789714 -255.530497) (xy 372.837933 -255.520653) (xy 372.887108 -255.518672) (xy 372.935963 -255.524604)
			(xy 372.983234 -255.538296) (xy 373.027696 -255.559394) (xy 373.068199 -255.58735) (xy 373.103692 -255.621442)
			(xy 373.133257 -255.660786) (xy 373.156128 -255.704363) (xy 373.171712 -255.751044) (xy 373.179607 -255.799621)
			(xy 373.180102 -255.824228) (xy 374.449098 -255.824228) (xy 374.453058 -255.775174) (xy 374.464835 -255.72739)
			(xy 374.484126 -255.682114) (xy 374.510429 -255.640518) (xy 374.543064 -255.603681) (xy 374.581185 -255.572556)
			(xy 374.623806 -255.547949) (xy 374.669822 -255.530497) (xy 374.718041 -255.520653) (xy 374.767216 -255.518672)
			(xy 374.816071 -255.524604) (xy 374.863342 -255.538296) (xy 374.907804 -255.559394) (xy 374.948307 -255.58735)
			(xy 374.9838 -255.621442) (xy 375.013365 -255.660786) (xy 375.036236 -255.704363) (xy 375.05182 -255.751044)
			(xy 375.059715 -255.799621) (xy 375.06021 -255.824228) (xy 375.378467 -255.824228) (xy 375.382562 -255.7735)
			(xy 375.394741 -255.724086) (xy 375.414689 -255.677266) (xy 375.44189 -255.634252) (xy 375.475638 -255.596158)
			(xy 375.51506 -255.563971) (xy 375.559134 -255.538525) (xy 375.60672 -255.520478) (xy 375.656584 -255.510298)
			(xy 375.707436 -255.508249) (xy 375.757957 -255.514383) (xy 375.806841 -255.528543) (xy 375.85282 -255.55036)
			(xy 375.894704 -255.57927) (xy 375.931408 -255.614525) (xy 375.961981 -255.655211) (xy 375.985632 -255.700274)
			(xy 376.001748 -255.748548) (xy 376.009912 -255.798782) (xy 376.010424 -255.824228) (xy 376.328952 -255.824228)
			(xy 376.332912 -255.775174) (xy 376.344689 -255.72739) (xy 376.36398 -255.682114) (xy 376.390283 -255.640518)
			(xy 376.422918 -255.603681) (xy 376.461039 -255.572556) (xy 376.50366 -255.547949) (xy 376.549676 -255.530497)
			(xy 376.597895 -255.520653) (xy 376.64707 -255.518672) (xy 376.695925 -255.524604) (xy 376.743196 -255.538296)
			(xy 376.787658 -255.559394) (xy 376.828161 -255.58735) (xy 376.863654 -255.621442) (xy 376.893219 -255.660786)
			(xy 376.91609 -255.704363) (xy 376.931674 -255.751044) (xy 376.939569 -255.799621) (xy 376.940064 -255.824228)
			(xy 377.258575 -255.824228) (xy 377.26267 -255.7735) (xy 377.274849 -255.724086) (xy 377.294797 -255.677266)
			(xy 377.321998 -255.634252) (xy 377.355746 -255.596158) (xy 377.395168 -255.563971) (xy 377.439242 -255.538525)
			(xy 377.486828 -255.520478) (xy 377.536692 -255.510298) (xy 377.587544 -255.508249) (xy 377.638065 -255.514383)
			(xy 377.686949 -255.528543) (xy 377.732928 -255.55036) (xy 377.774812 -255.57927) (xy 377.811516 -255.614525)
			(xy 377.842089 -255.655211) (xy 377.86574 -255.700274) (xy 377.881856 -255.748548) (xy 377.89002 -255.798782)
			(xy 377.890532 -255.824228) (xy 378.20906 -255.824228) (xy 378.21302 -255.775174) (xy 378.224797 -255.72739)
			(xy 378.244088 -255.682114) (xy 378.270391 -255.640518) (xy 378.303026 -255.603681) (xy 378.341147 -255.572556)
			(xy 378.383768 -255.547949) (xy 378.429784 -255.530497) (xy 378.478003 -255.520653) (xy 378.527178 -255.518672)
			(xy 378.576033 -255.524604) (xy 378.623304 -255.538296) (xy 378.667766 -255.559394) (xy 378.708269 -255.58735)
			(xy 378.743762 -255.621442) (xy 378.773327 -255.660786) (xy 378.796198 -255.704363) (xy 378.811782 -255.751044)
			(xy 378.819677 -255.799621) (xy 378.820172 -255.824228) (xy 379.138683 -255.824228) (xy 379.142778 -255.7735)
			(xy 379.154957 -255.724086) (xy 379.174905 -255.677266) (xy 379.202106 -255.634252) (xy 379.235854 -255.596158)
			(xy 379.275276 -255.563971) (xy 379.31935 -255.538525) (xy 379.366936 -255.520478) (xy 379.4168 -255.510298)
			(xy 379.467652 -255.508249) (xy 379.518173 -255.514383) (xy 379.567057 -255.528543) (xy 379.613036 -255.55036)
			(xy 379.65492 -255.57927) (xy 379.691624 -255.614525) (xy 379.722197 -255.655211) (xy 379.745848 -255.700274)
			(xy 379.761964 -255.748548) (xy 379.770128 -255.798782) (xy 379.77064 -255.824228) (xy 380.078483 -255.824228)
			(xy 380.082578 -255.7735) (xy 380.094757 -255.724086) (xy 380.114705 -255.677266) (xy 380.141906 -255.634252)
			(xy 380.175654 -255.596158) (xy 380.215076 -255.563971) (xy 380.25915 -255.538525) (xy 380.306736 -255.520478)
			(xy 380.3566 -255.510298) (xy 380.407452 -255.508249) (xy 380.457973 -255.514383) (xy 380.506857 -255.528543)
			(xy 380.552836 -255.55036) (xy 380.59472 -255.57927) (xy 380.631424 -255.614525) (xy 380.661997 -255.655211)
			(xy 380.685648 -255.700274) (xy 380.701764 -255.748548) (xy 380.709928 -255.798782) (xy 380.71044 -255.824228)
			(xy 381.028968 -255.824228) (xy 381.032928 -255.775174) (xy 381.044705 -255.72739) (xy 381.063996 -255.682114)
			(xy 381.090299 -255.640518) (xy 381.122934 -255.603681) (xy 381.161055 -255.572556) (xy 381.203676 -255.547949)
			(xy 381.249692 -255.530497) (xy 381.297911 -255.520653) (xy 381.347086 -255.518672) (xy 381.395941 -255.524604)
			(xy 381.443212 -255.538296) (xy 381.487674 -255.559394) (xy 381.528177 -255.58735) (xy 381.56367 -255.621442)
			(xy 381.593235 -255.660786) (xy 381.616106 -255.704363) (xy 381.63169 -255.751044) (xy 381.639585 -255.799621)
			(xy 381.64008 -255.824228) (xy 381.969022 -255.824228) (xy 381.972982 -255.775174) (xy 381.984759 -255.72739)
			(xy 382.00405 -255.682114) (xy 382.030353 -255.640518) (xy 382.062988 -255.603681) (xy 382.101109 -255.572556)
			(xy 382.14373 -255.547949) (xy 382.189746 -255.530497) (xy 382.237965 -255.520653) (xy 382.28714 -255.518672)
			(xy 382.335995 -255.524604) (xy 382.383266 -255.538296) (xy 382.427728 -255.559394) (xy 382.468231 -255.58735)
			(xy 382.503724 -255.621442) (xy 382.533289 -255.660786) (xy 382.55616 -255.704363) (xy 382.571744 -255.751044)
			(xy 382.579639 -255.799621) (xy 382.580134 -255.824228) (xy 382.909076 -255.824228) (xy 382.913036 -255.775174)
			(xy 382.924813 -255.72739) (xy 382.944104 -255.682114) (xy 382.970407 -255.640518) (xy 383.003042 -255.603681)
			(xy 383.041163 -255.572556) (xy 383.083784 -255.547949) (xy 383.1298 -255.530497) (xy 383.178019 -255.520653)
			(xy 383.227194 -255.518672) (xy 383.276049 -255.524604) (xy 383.32332 -255.538296) (xy 383.367782 -255.559394)
			(xy 383.408285 -255.58735) (xy 383.443778 -255.621442) (xy 383.473343 -255.660786) (xy 383.496214 -255.704363)
			(xy 383.511798 -255.751044) (xy 383.519693 -255.799621) (xy 383.520188 -255.824228) (xy 383.84913 -255.824228)
			(xy 383.85309 -255.775174) (xy 383.864867 -255.72739) (xy 383.884158 -255.682114) (xy 383.910461 -255.640518)
			(xy 383.943096 -255.603681) (xy 383.981217 -255.572556) (xy 384.023838 -255.547949) (xy 384.069854 -255.530497)
			(xy 384.118073 -255.520653) (xy 384.167248 -255.518672) (xy 384.216103 -255.524604) (xy 384.263374 -255.538296)
			(xy 384.307836 -255.559394) (xy 384.348339 -255.58735) (xy 384.383832 -255.621442) (xy 384.413397 -255.660786)
			(xy 384.436268 -255.704363) (xy 384.451852 -255.751044) (xy 384.459747 -255.799621) (xy 384.460242 -255.824228)
			(xy 384.78893 -255.824228) (xy 384.79289 -255.775174) (xy 384.804667 -255.72739) (xy 384.823958 -255.682114)
			(xy 384.850261 -255.640518) (xy 384.882896 -255.603681) (xy 384.921017 -255.572556) (xy 384.963638 -255.547949)
			(xy 385.009654 -255.530497) (xy 385.057873 -255.520653) (xy 385.107048 -255.518672) (xy 385.155903 -255.524604)
			(xy 385.203174 -255.538296) (xy 385.247636 -255.559394) (xy 385.288139 -255.58735) (xy 385.323632 -255.621442)
			(xy 385.353197 -255.660786) (xy 385.376068 -255.704363) (xy 385.391652 -255.751044) (xy 385.399547 -255.799621)
			(xy 385.400042 -255.824228) (xy 385.728984 -255.824228) (xy 385.732944 -255.775174) (xy 385.744721 -255.72739)
			(xy 385.764012 -255.682114) (xy 385.790315 -255.640518) (xy 385.82295 -255.603681) (xy 385.861071 -255.572556)
			(xy 385.903692 -255.547949) (xy 385.949708 -255.530497) (xy 385.997927 -255.520653) (xy 386.047102 -255.518672)
			(xy 386.095957 -255.524604) (xy 386.143228 -255.538296) (xy 386.18769 -255.559394) (xy 386.228193 -255.58735)
			(xy 386.263686 -255.621442) (xy 386.293251 -255.660786) (xy 386.316122 -255.704363) (xy 386.331706 -255.751044)
			(xy 386.339601 -255.799621) (xy 386.340096 -255.824228) (xy 386.669038 -255.824228) (xy 386.672998 -255.775174)
			(xy 386.684775 -255.72739) (xy 386.704066 -255.682114) (xy 386.730369 -255.640518) (xy 386.763004 -255.603681)
			(xy 386.801125 -255.572556) (xy 386.843746 -255.547949) (xy 386.889762 -255.530497) (xy 386.937981 -255.520653)
			(xy 386.987156 -255.518672) (xy 387.036011 -255.524604) (xy 387.083282 -255.538296) (xy 387.127744 -255.559394)
			(xy 387.168247 -255.58735) (xy 387.20374 -255.621442) (xy 387.233305 -255.660786) (xy 387.256176 -255.704363)
			(xy 387.27176 -255.751044) (xy 387.279655 -255.799621) (xy 387.28015 -255.824228) (xy 387.279655 -255.848835)
			(xy 387.27176 -255.897412) (xy 387.256176 -255.944093) (xy 387.233305 -255.98767) (xy 387.20374 -256.027014)
			(xy 387.168247 -256.061106) (xy 387.127744 -256.089062) (xy 387.083282 -256.11016) (xy 387.036011 -256.123852)
			(xy 386.987156 -256.129784) (xy 386.937981 -256.127803) (xy 386.889762 -256.117959) (xy 386.843746 -256.100507)
			(xy 386.801125 -256.0759) (xy 386.763004 -256.044775) (xy 386.730369 -256.007938) (xy 386.704066 -255.966342)
			(xy 386.684775 -255.921066) (xy 386.672998 -255.873282) (xy 386.669038 -255.824228) (xy 386.340096 -255.824228)
			(xy 386.339601 -255.848835) (xy 386.331706 -255.897412) (xy 386.316122 -255.944093) (xy 386.293251 -255.98767)
			(xy 386.263686 -256.027014) (xy 386.228193 -256.061106) (xy 386.18769 -256.089062) (xy 386.143228 -256.11016)
			(xy 386.095957 -256.123852) (xy 386.047102 -256.129784) (xy 385.997927 -256.127803) (xy 385.949708 -256.117959)
			(xy 385.903692 -256.100507) (xy 385.861071 -256.0759) (xy 385.82295 -256.044775) (xy 385.790315 -256.007938)
			(xy 385.764012 -255.966342) (xy 385.744721 -255.921066) (xy 385.732944 -255.873282) (xy 385.728984 -255.824228)
			(xy 385.400042 -255.824228) (xy 385.399547 -255.848835) (xy 385.391652 -255.897412) (xy 385.376068 -255.944093)
			(xy 385.353197 -255.98767) (xy 385.323632 -256.027014) (xy 385.288139 -256.061106) (xy 385.247636 -256.089062)
			(xy 385.203174 -256.11016) (xy 385.155903 -256.123852) (xy 385.107048 -256.129784) (xy 385.057873 -256.127803)
			(xy 385.009654 -256.117959) (xy 384.963638 -256.100507) (xy 384.921017 -256.0759) (xy 384.882896 -256.044775)
			(xy 384.850261 -256.007938) (xy 384.823958 -255.966342) (xy 384.804667 -255.921066) (xy 384.79289 -255.873282)
			(xy 384.78893 -255.824228) (xy 384.460242 -255.824228) (xy 384.459747 -255.848835) (xy 384.451852 -255.897412)
			(xy 384.436268 -255.944093) (xy 384.413397 -255.98767) (xy 384.383832 -256.027014) (xy 384.348339 -256.061106)
			(xy 384.307836 -256.089062) (xy 384.263374 -256.11016) (xy 384.216103 -256.123852) (xy 384.167248 -256.129784)
			(xy 384.118073 -256.127803) (xy 384.069854 -256.117959) (xy 384.023838 -256.100507) (xy 383.981217 -256.0759)
			(xy 383.943096 -256.044775) (xy 383.910461 -256.007938) (xy 383.884158 -255.966342) (xy 383.864867 -255.921066)
			(xy 383.85309 -255.873282) (xy 383.84913 -255.824228) (xy 383.520188 -255.824228) (xy 383.519693 -255.848835)
			(xy 383.511798 -255.897412) (xy 383.496214 -255.944093) (xy 383.473343 -255.98767) (xy 383.443778 -256.027014)
			(xy 383.408285 -256.061106) (xy 383.367782 -256.089062) (xy 383.32332 -256.11016) (xy 383.276049 -256.123852)
			(xy 383.227194 -256.129784) (xy 383.178019 -256.127803) (xy 383.1298 -256.117959) (xy 383.083784 -256.100507)
			(xy 383.041163 -256.0759) (xy 383.003042 -256.044775) (xy 382.970407 -256.007938) (xy 382.944104 -255.966342)
			(xy 382.924813 -255.921066) (xy 382.913036 -255.873282) (xy 382.909076 -255.824228) (xy 382.580134 -255.824228)
			(xy 382.579639 -255.848835) (xy 382.571744 -255.897412) (xy 382.55616 -255.944093) (xy 382.533289 -255.98767)
			(xy 382.503724 -256.027014) (xy 382.468231 -256.061106) (xy 382.427728 -256.089062) (xy 382.383266 -256.11016)
			(xy 382.335995 -256.123852) (xy 382.28714 -256.129784) (xy 382.237965 -256.127803) (xy 382.189746 -256.117959)
			(xy 382.14373 -256.100507) (xy 382.101109 -256.0759) (xy 382.062988 -256.044775) (xy 382.030353 -256.007938)
			(xy 382.00405 -255.966342) (xy 381.984759 -255.921066) (xy 381.972982 -255.873282) (xy 381.969022 -255.824228)
			(xy 381.64008 -255.824228) (xy 381.639585 -255.848835) (xy 381.63169 -255.897412) (xy 381.616106 -255.944093)
			(xy 381.593235 -255.98767) (xy 381.56367 -256.027014) (xy 381.528177 -256.061106) (xy 381.487674 -256.089062)
			(xy 381.443212 -256.11016) (xy 381.395941 -256.123852) (xy 381.347086 -256.129784) (xy 381.297911 -256.127803)
			(xy 381.249692 -256.117959) (xy 381.203676 -256.100507) (xy 381.161055 -256.0759) (xy 381.122934 -256.044775)
			(xy 381.090299 -256.007938) (xy 381.063996 -255.966342) (xy 381.044705 -255.921066) (xy 381.032928 -255.873282)
			(xy 381.028968 -255.824228) (xy 380.71044 -255.824228) (xy 380.709928 -255.849674) (xy 380.701764 -255.899908)
			(xy 380.685648 -255.948182) (xy 380.661997 -255.993245) (xy 380.631424 -256.033931) (xy 380.59472 -256.069186)
			(xy 380.552836 -256.098096) (xy 380.506857 -256.119913) (xy 380.457973 -256.134073) (xy 380.407452 -256.140207)
			(xy 380.3566 -256.138158) (xy 380.306736 -256.127978) (xy 380.25915 -256.109931) (xy 380.215076 -256.084485)
			(xy 380.175654 -256.052298) (xy 380.141906 -256.014204) (xy 380.114705 -255.97119) (xy 380.094757 -255.92437)
			(xy 380.082578 -255.874956) (xy 380.078483 -255.824228) (xy 379.77064 -255.824228) (xy 379.770128 -255.849674)
			(xy 379.761964 -255.899908) (xy 379.745848 -255.948182) (xy 379.722197 -255.993245) (xy 379.691624 -256.033931)
			(xy 379.65492 -256.069186) (xy 379.613036 -256.098096) (xy 379.567057 -256.119913) (xy 379.518173 -256.134073)
			(xy 379.467652 -256.140207) (xy 379.4168 -256.138158) (xy 379.366936 -256.127978) (xy 379.31935 -256.109931)
			(xy 379.275276 -256.084485) (xy 379.235854 -256.052298) (xy 379.202106 -256.014204) (xy 379.174905 -255.97119)
			(xy 379.154957 -255.92437) (xy 379.142778 -255.874956) (xy 379.138683 -255.824228) (xy 378.820172 -255.824228)
			(xy 378.819677 -255.848835) (xy 378.811782 -255.897412) (xy 378.796198 -255.944093) (xy 378.773327 -255.98767)
			(xy 378.743762 -256.027014) (xy 378.708269 -256.061106) (xy 378.667766 -256.089062) (xy 378.623304 -256.11016)
			(xy 378.576033 -256.123852) (xy 378.527178 -256.129784) (xy 378.478003 -256.127803) (xy 378.429784 -256.117959)
			(xy 378.383768 -256.100507) (xy 378.341147 -256.0759) (xy 378.303026 -256.044775) (xy 378.270391 -256.007938)
			(xy 378.244088 -255.966342) (xy 378.224797 -255.921066) (xy 378.21302 -255.873282) (xy 378.20906 -255.824228)
			(xy 377.890532 -255.824228) (xy 377.89002 -255.849674) (xy 377.881856 -255.899908) (xy 377.86574 -255.948182)
			(xy 377.842089 -255.993245) (xy 377.811516 -256.033931) (xy 377.774812 -256.069186) (xy 377.732928 -256.098096)
			(xy 377.686949 -256.119913) (xy 377.638065 -256.134073) (xy 377.587544 -256.140207) (xy 377.536692 -256.138158)
			(xy 377.486828 -256.127978) (xy 377.439242 -256.109931) (xy 377.395168 -256.084485) (xy 377.355746 -256.052298)
			(xy 377.321998 -256.014204) (xy 377.294797 -255.97119) (xy 377.274849 -255.92437) (xy 377.26267 -255.874956)
			(xy 377.258575 -255.824228) (xy 376.940064 -255.824228) (xy 376.939569 -255.848835) (xy 376.931674 -255.897412)
			(xy 376.91609 -255.944093) (xy 376.893219 -255.98767) (xy 376.863654 -256.027014) (xy 376.828161 -256.061106)
			(xy 376.787658 -256.089062) (xy 376.743196 -256.11016) (xy 376.695925 -256.123852) (xy 376.64707 -256.129784)
			(xy 376.597895 -256.127803) (xy 376.549676 -256.117959) (xy 376.50366 -256.100507) (xy 376.461039 -256.0759)
			(xy 376.422918 -256.044775) (xy 376.390283 -256.007938) (xy 376.36398 -255.966342) (xy 376.344689 -255.921066)
			(xy 376.332912 -255.873282) (xy 376.328952 -255.824228) (xy 376.010424 -255.824228) (xy 376.009912 -255.849674)
			(xy 376.001748 -255.899908) (xy 375.985632 -255.948182) (xy 375.961981 -255.993245) (xy 375.931408 -256.033931)
			(xy 375.894704 -256.069186) (xy 375.85282 -256.098096) (xy 375.806841 -256.119913) (xy 375.757957 -256.134073)
			(xy 375.707436 -256.140207) (xy 375.656584 -256.138158) (xy 375.60672 -256.127978) (xy 375.559134 -256.109931)
			(xy 375.51506 -256.084485) (xy 375.475638 -256.052298) (xy 375.44189 -256.014204) (xy 375.414689 -255.97119)
			(xy 375.394741 -255.92437) (xy 375.382562 -255.874956) (xy 375.378467 -255.824228) (xy 375.06021 -255.824228)
			(xy 375.059715 -255.848835) (xy 375.05182 -255.897412) (xy 375.036236 -255.944093) (xy 375.013365 -255.98767)
			(xy 374.9838 -256.027014) (xy 374.948307 -256.061106) (xy 374.907804 -256.089062) (xy 374.863342 -256.11016)
			(xy 374.816071 -256.123852) (xy 374.767216 -256.129784) (xy 374.718041 -256.127803) (xy 374.669822 -256.117959)
			(xy 374.623806 -256.100507) (xy 374.581185 -256.0759) (xy 374.543064 -256.044775) (xy 374.510429 -256.007938)
			(xy 374.484126 -255.966342) (xy 374.464835 -255.921066) (xy 374.453058 -255.873282) (xy 374.449098 -255.824228)
			(xy 373.180102 -255.824228) (xy 373.179607 -255.848835) (xy 373.171712 -255.897412) (xy 373.156128 -255.944093)
			(xy 373.133257 -255.98767) (xy 373.103692 -256.027014) (xy 373.068199 -256.061106) (xy 373.027696 -256.089062)
			(xy 372.983234 -256.11016) (xy 372.935963 -256.123852) (xy 372.887108 -256.129784) (xy 372.837933 -256.127803)
			(xy 372.789714 -256.117959) (xy 372.743698 -256.100507) (xy 372.701077 -256.0759) (xy 372.662956 -256.044775)
			(xy 372.630321 -256.007938) (xy 372.604018 -255.966342) (xy 372.584727 -255.921066) (xy 372.57295 -255.873282)
			(xy 372.56899 -255.824228) (xy 371.299994 -255.824228) (xy 371.299499 -255.848835) (xy 371.291604 -255.897412)
			(xy 371.27602 -255.944093) (xy 371.253149 -255.98767) (xy 371.223584 -256.027014) (xy 371.188091 -256.061106)
			(xy 371.147588 -256.089062) (xy 371.103126 -256.11016) (xy 371.055855 -256.123852) (xy 371.007 -256.129784)
			(xy 370.957825 -256.127803) (xy 370.909606 -256.117959) (xy 370.86359 -256.100507) (xy 370.820969 -256.0759)
			(xy 370.782848 -256.044775) (xy 370.750213 -256.007938) (xy 370.72391 -255.966342) (xy 370.704619 -255.921066)
			(xy 370.692842 -255.873282) (xy 370.688882 -255.824228) (xy 369.42014 -255.824228) (xy 369.419645 -255.848835)
			(xy 369.41175 -255.897412) (xy 369.396166 -255.944093) (xy 369.373295 -255.98767) (xy 369.34373 -256.027014)
			(xy 369.308237 -256.061106) (xy 369.267734 -256.089062) (xy 369.223272 -256.11016) (xy 369.176001 -256.123852)
			(xy 369.127146 -256.129784) (xy 369.077971 -256.127803) (xy 369.029752 -256.117959) (xy 368.983736 -256.100507)
			(xy 368.941115 -256.0759) (xy 368.902994 -256.044775) (xy 368.870359 -256.007938) (xy 368.844056 -255.966342)
			(xy 368.824765 -255.921066) (xy 368.812988 -255.873282) (xy 368.809028 -255.824228) (xy 365.557672 -255.824228)
			(xy 365.521462 -255.843918) (xy 365.471909 -255.861716) (xy 365.420219 -255.87174) (xy 365.367605 -255.873757)
			(xy 365.3153 -255.867719) (xy 365.264529 -255.853767) (xy 365.216484 -255.832228) (xy 365.172289 -255.803608)
			(xy 365.132981 -255.768577) (xy 365.099481 -255.727956) (xy 365.072575 -255.682697) (xy 365.052892 -255.633862)
			(xy 365.040895 -255.582594) (xy 365.036865 -255.530096) (xy 354.688648 -255.530096) (xy 354.688134 -255.556892)
			(xy 354.679807 -255.609835) (xy 354.663356 -255.66084) (xy 354.63918 -255.70867) (xy 354.607866 -255.752163)
			(xy 354.570174 -255.790262) (xy 354.527021 -255.822042) (xy 354.479454 -255.846732) (xy 354.454206 -255.855724)
			(xy 354.44684 -255.858264) (xy 354.434394 -255.867154) (xy 354.413566 -255.894586) (xy 354.408823 -255.901372)
			(xy 354.403527 -255.917048) (xy 354.403152 -255.92532) (xy 354.403152 -256.084832) (xy 354.403474 -256.093112)
			(xy 354.408789 -256.108795) (xy 354.413566 -256.115566) (xy 354.434394 -256.142998) (xy 354.44684 -256.151888)
			(xy 354.454206 -256.154428) (xy 354.479452 -256.16342) (xy 354.527012 -256.188117) (xy 354.570159 -256.219902)
			(xy 354.607844 -256.258002) (xy 354.639155 -256.301494) (xy 354.66333 -256.349321) (xy 354.675596 -256.387346)
			(xy 355.244149 -256.387346) (xy 355.248179 -256.334848) (xy 355.260176 -256.28358) (xy 355.279859 -256.234745)
			(xy 355.306765 -256.189486) (xy 355.340265 -256.148865) (xy 355.379573 -256.113834) (xy 355.423768 -256.085214)
			(xy 355.471813 -256.063675) (xy 355.522584 -256.049723) (xy 355.574889 -256.043685) (xy 355.627503 -256.045702)
			(xy 355.679193 -256.055726) (xy 355.728746 -256.073524) (xy 355.775002 -256.098677) (xy 355.816876 -256.130596)
			(xy 355.853388 -256.168534) (xy 355.88368 -256.2116) (xy 355.907043 -256.258785) (xy 355.922929 -256.308984)
			(xy 355.930966 -256.36102) (xy 355.93147 -256.387346) (xy 356.194109 -256.387346) (xy 356.198139 -256.334848)
			(xy 356.210136 -256.28358) (xy 356.229819 -256.234745) (xy 356.256725 -256.189486) (xy 356.290225 -256.148865)
			(xy 356.329533 -256.113834) (xy 356.373728 -256.085214) (xy 356.421773 -256.063675) (xy 356.472544 -256.049723)
			(xy 356.524849 -256.043685) (xy 356.577463 -256.045702) (xy 356.629153 -256.055726) (xy 356.678706 -256.073524)
			(xy 356.724962 -256.098677) (xy 356.766836 -256.130596) (xy 356.803348 -256.168534) (xy 356.83364 -256.2116)
			(xy 356.857003 -256.258785) (xy 356.872889 -256.308984) (xy 356.880926 -256.36102) (xy 356.88143 -256.387346)
			(xy 357.144069 -256.387346) (xy 357.148099 -256.334848) (xy 357.160096 -256.28358) (xy 357.179779 -256.234745)
			(xy 357.206685 -256.189486) (xy 357.240185 -256.148865) (xy 357.279493 -256.113834) (xy 357.323688 -256.085214)
			(xy 357.371733 -256.063675) (xy 357.422504 -256.049723) (xy 357.474809 -256.043685) (xy 357.527423 -256.045702)
			(xy 357.579113 -256.055726) (xy 357.628666 -256.073524) (xy 357.674922 -256.098677) (xy 357.716796 -256.130596)
			(xy 357.753308 -256.168534) (xy 357.7836 -256.2116) (xy 357.806963 -256.258785) (xy 357.822849 -256.308984)
			(xy 357.830886 -256.36102) (xy 357.83139 -256.387346) (xy 358.094029 -256.387346) (xy 358.098059 -256.334848)
			(xy 358.110056 -256.28358) (xy 358.129739 -256.234745) (xy 358.156645 -256.189486) (xy 358.190145 -256.148865)
			(xy 358.229453 -256.113834) (xy 358.273648 -256.085214) (xy 358.321693 -256.063675) (xy 358.372464 -256.049723)
			(xy 358.424769 -256.043685) (xy 358.477383 -256.045702) (xy 358.529073 -256.055726) (xy 358.578626 -256.073524)
			(xy 358.624882 -256.098677) (xy 358.666756 -256.130596) (xy 358.703268 -256.168534) (xy 358.73356 -256.2116)
			(xy 358.756923 -256.258785) (xy 358.772809 -256.308984) (xy 358.780846 -256.36102) (xy 358.78135 -256.387346)
			(xy 359.043989 -256.387346) (xy 359.048019 -256.334848) (xy 359.060016 -256.28358) (xy 359.079699 -256.234745)
			(xy 359.106605 -256.189486) (xy 359.140105 -256.148865) (xy 359.179413 -256.113834) (xy 359.223608 -256.085214)
			(xy 359.271653 -256.063675) (xy 359.322424 -256.049723) (xy 359.374729 -256.043685) (xy 359.427343 -256.045702)
			(xy 359.479033 -256.055726) (xy 359.528586 -256.073524) (xy 359.574842 -256.098677) (xy 359.616716 -256.130596)
			(xy 359.653228 -256.168534) (xy 359.68352 -256.2116) (xy 359.706883 -256.258785) (xy 359.722769 -256.308984)
			(xy 359.730806 -256.36102) (xy 359.73131 -256.387346) (xy 359.993949 -256.387346) (xy 359.997979 -256.334848)
			(xy 360.009976 -256.28358) (xy 360.029659 -256.234745) (xy 360.056565 -256.189486) (xy 360.090065 -256.148865)
			(xy 360.129373 -256.113834) (xy 360.173568 -256.085214) (xy 360.221613 -256.063675) (xy 360.272384 -256.049723)
			(xy 360.324689 -256.043685) (xy 360.377303 -256.045702) (xy 360.428993 -256.055726) (xy 360.478546 -256.073524)
			(xy 360.524802 -256.098677) (xy 360.566676 -256.130596) (xy 360.603188 -256.168534) (xy 360.63348 -256.2116)
			(xy 360.656843 -256.258785) (xy 360.672729 -256.308984) (xy 360.680766 -256.36102) (xy 360.68127 -256.387346)
			(xy 360.944163 -256.387346) (xy 360.948193 -256.334848) (xy 360.96019 -256.28358) (xy 360.979873 -256.234745)
			(xy 361.006779 -256.189486) (xy 361.040279 -256.148865) (xy 361.079587 -256.113834) (xy 361.123782 -256.085214)
			(xy 361.171827 -256.063675) (xy 361.222598 -256.049723) (xy 361.274903 -256.043685) (xy 361.327517 -256.045702)
			(xy 361.379207 -256.055726) (xy 361.42876 -256.073524) (xy 361.475016 -256.098677) (xy 361.51689 -256.130596)
			(xy 361.553402 -256.168534) (xy 361.583694 -256.2116) (xy 361.607057 -256.258785) (xy 361.622943 -256.308984)
			(xy 361.63098 -256.36102) (xy 361.631484 -256.387346) (xy 361.894123 -256.387346) (xy 361.898153 -256.334848)
			(xy 361.91015 -256.28358) (xy 361.929833 -256.234745) (xy 361.956739 -256.189486) (xy 361.990239 -256.148865)
			(xy 362.029547 -256.113834) (xy 362.073742 -256.085214) (xy 362.121787 -256.063675) (xy 362.172558 -256.049723)
			(xy 362.224863 -256.043685) (xy 362.277477 -256.045702) (xy 362.329167 -256.055726) (xy 362.37872 -256.073524)
			(xy 362.424976 -256.098677) (xy 362.46685 -256.130596) (xy 362.503362 -256.168534) (xy 362.533654 -256.2116)
			(xy 362.557017 -256.258785) (xy 362.572903 -256.308984) (xy 362.58094 -256.36102) (xy 362.581444 -256.387346)
			(xy 362.844083 -256.387346) (xy 362.848113 -256.334848) (xy 362.86011 -256.28358) (xy 362.879793 -256.234745)
			(xy 362.906699 -256.189486) (xy 362.940199 -256.148865) (xy 362.979507 -256.113834) (xy 363.023702 -256.085214)
			(xy 363.071747 -256.063675) (xy 363.122518 -256.049723) (xy 363.174823 -256.043685) (xy 363.227437 -256.045702)
			(xy 363.279127 -256.055726) (xy 363.32868 -256.073524) (xy 363.374936 -256.098677) (xy 363.41681 -256.130596)
			(xy 363.453322 -256.168534) (xy 363.483614 -256.2116) (xy 363.506977 -256.258785) (xy 363.522863 -256.308984)
			(xy 363.5309 -256.36102) (xy 363.531404 -256.387346) (xy 363.794043 -256.387346) (xy 363.798073 -256.334848)
			(xy 363.81007 -256.28358) (xy 363.829753 -256.234745) (xy 363.856659 -256.189486) (xy 363.890159 -256.148865)
			(xy 363.929467 -256.113834) (xy 363.973662 -256.085214) (xy 364.021707 -256.063675) (xy 364.072478 -256.049723)
			(xy 364.124783 -256.043685) (xy 364.177397 -256.045702) (xy 364.229087 -256.055726) (xy 364.27864 -256.073524)
			(xy 364.324896 -256.098677) (xy 364.36677 -256.130596) (xy 364.403282 -256.168534) (xy 364.433574 -256.2116)
			(xy 364.456937 -256.258785) (xy 364.472823 -256.308984) (xy 364.48086 -256.36102) (xy 364.481364 -256.387346)
			(xy 364.48086 -256.413672) (xy 364.472823 -256.465708) (xy 364.468282 -256.480056) (xy 365.036865 -256.480056)
			(xy 365.040895 -256.427558) (xy 365.052892 -256.37629) (xy 365.072575 -256.327455) (xy 365.099481 -256.282196)
			(xy 365.132981 -256.241575) (xy 365.172289 -256.206544) (xy 365.216484 -256.177924) (xy 365.264529 -256.156385)
			(xy 365.3153 -256.142433) (xy 365.367605 -256.136395) (xy 365.420219 -256.138412) (xy 365.471909 -256.148436)
			(xy 365.521462 -256.166234) (xy 365.567718 -256.191387) (xy 365.609592 -256.223306) (xy 365.646104 -256.261244)
			(xy 365.676396 -256.30431) (xy 365.699759 -256.351495) (xy 365.715645 -256.401694) (xy 365.723682 -256.45373)
			(xy 365.724186 -256.480056) (xy 365.723682 -256.506382) (xy 365.715645 -256.558418) (xy 365.699759 -256.608617)
			(xy 365.687075 -256.634234) (xy 370.218982 -256.634234) (xy 370.222942 -256.58518) (xy 370.234719 -256.537396)
			(xy 370.25401 -256.49212) (xy 370.280313 -256.450524) (xy 370.312948 -256.413687) (xy 370.351069 -256.382562)
			(xy 370.39369 -256.357955) (xy 370.439706 -256.340503) (xy 370.487925 -256.330659) (xy 370.5371 -256.328678)
			(xy 370.585955 -256.33461) (xy 370.633226 -256.348302) (xy 370.677688 -256.3694) (xy 370.718191 -256.397356)
			(xy 370.753684 -256.431448) (xy 370.783249 -256.470792) (xy 370.80612 -256.514369) (xy 370.821704 -256.56105)
			(xy 370.829599 -256.609627) (xy 370.830094 -256.634234) (xy 372.09909 -256.634234) (xy 372.10305 -256.58518)
			(xy 372.114827 -256.537396) (xy 372.134118 -256.49212) (xy 372.160421 -256.450524) (xy 372.193056 -256.413687)
			(xy 372.231177 -256.382562) (xy 372.273798 -256.357955) (xy 372.319814 -256.340503) (xy 372.368033 -256.330659)
			(xy 372.417208 -256.328678) (xy 372.466063 -256.33461) (xy 372.513334 -256.348302) (xy 372.557796 -256.3694)
			(xy 372.598299 -256.397356) (xy 372.633792 -256.431448) (xy 372.663357 -256.470792) (xy 372.686228 -256.514369)
			(xy 372.701812 -256.56105) (xy 372.709707 -256.609627) (xy 372.710202 -256.634234) (xy 373.978944 -256.634234)
			(xy 373.982904 -256.58518) (xy 373.994681 -256.537396) (xy 374.013972 -256.49212) (xy 374.040275 -256.450524)
			(xy 374.07291 -256.413687) (xy 374.111031 -256.382562) (xy 374.153652 -256.357955) (xy 374.199668 -256.340503)
			(xy 374.247887 -256.330659) (xy 374.297062 -256.328678) (xy 374.345917 -256.33461) (xy 374.393188 -256.348302)
			(xy 374.43765 -256.3694) (xy 374.478153 -256.397356) (xy 374.513646 -256.431448) (xy 374.543211 -256.470792)
			(xy 374.566082 -256.514369) (xy 374.581666 -256.56105) (xy 374.589561 -256.609627) (xy 374.590056 -256.634234)
			(xy 375.859052 -256.634234) (xy 375.863012 -256.58518) (xy 375.874789 -256.537396) (xy 375.89408 -256.49212)
			(xy 375.920383 -256.450524) (xy 375.953018 -256.413687) (xy 375.991139 -256.382562) (xy 376.03376 -256.357955)
			(xy 376.079776 -256.340503) (xy 376.127995 -256.330659) (xy 376.17717 -256.328678) (xy 376.226025 -256.33461)
			(xy 376.273296 -256.348302) (xy 376.317758 -256.3694) (xy 376.358261 -256.397356) (xy 376.393754 -256.431448)
			(xy 376.423319 -256.470792) (xy 376.44619 -256.514369) (xy 376.461774 -256.56105) (xy 376.469669 -256.609627)
			(xy 376.470164 -256.634234) (xy 376.788675 -256.634234) (xy 376.79277 -256.583506) (xy 376.804949 -256.534092)
			(xy 376.824897 -256.487272) (xy 376.852098 -256.444258) (xy 376.885846 -256.406164) (xy 376.925268 -256.373977)
			(xy 376.969342 -256.348531) (xy 377.016928 -256.330484) (xy 377.066792 -256.320304) (xy 377.117644 -256.318255)
			(xy 377.168165 -256.324389) (xy 377.217049 -256.338549) (xy 377.263028 -256.360366) (xy 377.304912 -256.389276)
			(xy 377.341616 -256.424531) (xy 377.372189 -256.465217) (xy 377.39584 -256.51028) (xy 377.411956 -256.558554)
			(xy 377.42012 -256.608788) (xy 377.420632 -256.634234) (xy 378.67896 -256.634234) (xy 378.68292 -256.58518)
			(xy 378.694697 -256.537396) (xy 378.713988 -256.49212) (xy 378.740291 -256.450524) (xy 378.772926 -256.413687)
			(xy 378.811047 -256.382562) (xy 378.853668 -256.357955) (xy 378.899684 -256.340503) (xy 378.947903 -256.330659)
			(xy 378.997078 -256.328678) (xy 379.045933 -256.33461) (xy 379.093204 -256.348302) (xy 379.137666 -256.3694)
			(xy 379.178169 -256.397356) (xy 379.213662 -256.431448) (xy 379.243227 -256.470792) (xy 379.266098 -256.514369)
			(xy 379.281682 -256.56105) (xy 379.289577 -256.609627) (xy 379.290072 -256.634234) (xy 379.619014 -256.634234)
			(xy 379.622974 -256.58518) (xy 379.634751 -256.537396) (xy 379.654042 -256.49212) (xy 379.680345 -256.450524)
			(xy 379.71298 -256.413687) (xy 379.751101 -256.382562) (xy 379.793722 -256.357955) (xy 379.839738 -256.340503)
			(xy 379.887957 -256.330659) (xy 379.937132 -256.328678) (xy 379.985987 -256.33461) (xy 380.033258 -256.348302)
			(xy 380.07772 -256.3694) (xy 380.118223 -256.397356) (xy 380.153716 -256.431448) (xy 380.183281 -256.470792)
			(xy 380.206152 -256.514369) (xy 380.221736 -256.56105) (xy 380.229631 -256.609627) (xy 380.230126 -256.634234)
			(xy 380.548637 -256.634234) (xy 380.552732 -256.583506) (xy 380.564911 -256.534092) (xy 380.584859 -256.487272)
			(xy 380.61206 -256.444258) (xy 380.645808 -256.406164) (xy 380.68523 -256.373977) (xy 380.729304 -256.348531)
			(xy 380.77689 -256.330484) (xy 380.826754 -256.320304) (xy 380.877606 -256.318255) (xy 380.928127 -256.324389)
			(xy 380.977011 -256.338549) (xy 381.02299 -256.360366) (xy 381.064874 -256.389276) (xy 381.101578 -256.424531)
			(xy 381.132151 -256.465217) (xy 381.155802 -256.51028) (xy 381.171918 -256.558554) (xy 381.180082 -256.608788)
			(xy 381.180594 -256.634234) (xy 381.499122 -256.634234) (xy 381.503082 -256.58518) (xy 381.514859 -256.537396)
			(xy 381.53415 -256.49212) (xy 381.560453 -256.450524) (xy 381.593088 -256.413687) (xy 381.631209 -256.382562)
			(xy 381.67383 -256.357955) (xy 381.719846 -256.340503) (xy 381.768065 -256.330659) (xy 381.81724 -256.328678)
			(xy 381.866095 -256.33461) (xy 381.913366 -256.348302) (xy 381.957828 -256.3694) (xy 381.998331 -256.397356)
			(xy 382.033824 -256.431448) (xy 382.063389 -256.470792) (xy 382.08626 -256.514369) (xy 382.101844 -256.56105)
			(xy 382.109739 -256.609627) (xy 382.110234 -256.634234) (xy 382.438922 -256.634234) (xy 382.442882 -256.58518)
			(xy 382.454659 -256.537396) (xy 382.47395 -256.49212) (xy 382.500253 -256.450524) (xy 382.532888 -256.413687)
			(xy 382.571009 -256.382562) (xy 382.61363 -256.357955) (xy 382.659646 -256.340503) (xy 382.707865 -256.330659)
			(xy 382.75704 -256.328678) (xy 382.805895 -256.33461) (xy 382.853166 -256.348302) (xy 382.897628 -256.3694)
			(xy 382.938131 -256.397356) (xy 382.973624 -256.431448) (xy 383.003189 -256.470792) (xy 383.02606 -256.514369)
			(xy 383.041644 -256.56105) (xy 383.049539 -256.609627) (xy 383.050034 -256.634234) (xy 383.378976 -256.634234)
			(xy 383.382936 -256.58518) (xy 383.394713 -256.537396) (xy 383.414004 -256.49212) (xy 383.440307 -256.450524)
			(xy 383.472942 -256.413687) (xy 383.511063 -256.382562) (xy 383.553684 -256.357955) (xy 383.5997 -256.340503)
			(xy 383.647919 -256.330659) (xy 383.697094 -256.328678) (xy 383.745949 -256.33461) (xy 383.79322 -256.348302)
			(xy 383.837682 -256.3694) (xy 383.878185 -256.397356) (xy 383.913678 -256.431448) (xy 383.943243 -256.470792)
			(xy 383.966114 -256.514369) (xy 383.981698 -256.56105) (xy 383.989593 -256.609627) (xy 383.990088 -256.634234)
			(xy 385.259084 -256.634234) (xy 385.263044 -256.58518) (xy 385.274821 -256.537396) (xy 385.294112 -256.49212)
			(xy 385.320415 -256.450524) (xy 385.35305 -256.413687) (xy 385.391171 -256.382562) (xy 385.433792 -256.357955)
			(xy 385.479808 -256.340503) (xy 385.528027 -256.330659) (xy 385.577202 -256.328678) (xy 385.626057 -256.33461)
			(xy 385.673328 -256.348302) (xy 385.71779 -256.3694) (xy 385.758293 -256.397356) (xy 385.793786 -256.431448)
			(xy 385.823351 -256.470792) (xy 385.846222 -256.514369) (xy 385.861806 -256.56105) (xy 385.869701 -256.609627)
			(xy 385.870196 -256.634234) (xy 386.199138 -256.634234) (xy 386.203098 -256.58518) (xy 386.214875 -256.537396)
			(xy 386.234166 -256.49212) (xy 386.260469 -256.450524) (xy 386.293104 -256.413687) (xy 386.331225 -256.382562)
			(xy 386.373846 -256.357955) (xy 386.419862 -256.340503) (xy 386.468081 -256.330659) (xy 386.517256 -256.328678)
			(xy 386.566111 -256.33461) (xy 386.613382 -256.348302) (xy 386.657844 -256.3694) (xy 386.698347 -256.397356)
			(xy 386.73384 -256.431448) (xy 386.763405 -256.470792) (xy 386.786276 -256.514369) (xy 386.80186 -256.56105)
			(xy 386.809755 -256.609627) (xy 386.81025 -256.634234) (xy 387.138938 -256.634234) (xy 387.142898 -256.58518)
			(xy 387.154675 -256.537396) (xy 387.173966 -256.49212) (xy 387.200269 -256.450524) (xy 387.232904 -256.413687)
			(xy 387.271025 -256.382562) (xy 387.313646 -256.357955) (xy 387.359662 -256.340503) (xy 387.407881 -256.330659)
			(xy 387.457056 -256.328678) (xy 387.505911 -256.33461) (xy 387.553182 -256.348302) (xy 387.597644 -256.3694)
			(xy 387.638147 -256.397356) (xy 387.67364 -256.431448) (xy 387.703205 -256.470792) (xy 387.726076 -256.514369)
			(xy 387.74166 -256.56105) (xy 387.749555 -256.609627) (xy 387.75005 -256.634234) (xy 387.749555 -256.658841)
			(xy 387.74166 -256.707418) (xy 387.726076 -256.754099) (xy 387.703205 -256.797676) (xy 387.67364 -256.83702)
			(xy 387.638147 -256.871112) (xy 387.597644 -256.899068) (xy 387.553182 -256.920166) (xy 387.505911 -256.933858)
			(xy 387.457056 -256.93979) (xy 387.407881 -256.937809) (xy 387.359662 -256.927965) (xy 387.313646 -256.910513)
			(xy 387.271025 -256.885906) (xy 387.232904 -256.854781) (xy 387.200269 -256.817944) (xy 387.173966 -256.776348)
			(xy 387.154675 -256.731072) (xy 387.142898 -256.683288) (xy 387.138938 -256.634234) (xy 386.81025 -256.634234)
			(xy 386.809755 -256.658841) (xy 386.80186 -256.707418) (xy 386.786276 -256.754099) (xy 386.763405 -256.797676)
			(xy 386.73384 -256.83702) (xy 386.698347 -256.871112) (xy 386.657844 -256.899068) (xy 386.613382 -256.920166)
			(xy 386.566111 -256.933858) (xy 386.517256 -256.93979) (xy 386.468081 -256.937809) (xy 386.419862 -256.927965)
			(xy 386.373846 -256.910513) (xy 386.331225 -256.885906) (xy 386.293104 -256.854781) (xy 386.260469 -256.817944)
			(xy 386.234166 -256.776348) (xy 386.214875 -256.731072) (xy 386.203098 -256.683288) (xy 386.199138 -256.634234)
			(xy 385.870196 -256.634234) (xy 385.869701 -256.658841) (xy 385.861806 -256.707418) (xy 385.846222 -256.754099)
			(xy 385.823351 -256.797676) (xy 385.793786 -256.83702) (xy 385.758293 -256.871112) (xy 385.71779 -256.899068)
			(xy 385.673328 -256.920166) (xy 385.626057 -256.933858) (xy 385.577202 -256.93979) (xy 385.528027 -256.937809)
			(xy 385.479808 -256.927965) (xy 385.433792 -256.910513) (xy 385.391171 -256.885906) (xy 385.35305 -256.854781)
			(xy 385.320415 -256.817944) (xy 385.294112 -256.776348) (xy 385.274821 -256.731072) (xy 385.263044 -256.683288)
			(xy 385.259084 -256.634234) (xy 383.990088 -256.634234) (xy 383.989593 -256.658841) (xy 383.981698 -256.707418)
			(xy 383.966114 -256.754099) (xy 383.943243 -256.797676) (xy 383.913678 -256.83702) (xy 383.878185 -256.871112)
			(xy 383.837682 -256.899068) (xy 383.79322 -256.920166) (xy 383.745949 -256.933858) (xy 383.697094 -256.93979)
			(xy 383.647919 -256.937809) (xy 383.5997 -256.927965) (xy 383.553684 -256.910513) (xy 383.511063 -256.885906)
			(xy 383.472942 -256.854781) (xy 383.440307 -256.817944) (xy 383.414004 -256.776348) (xy 383.394713 -256.731072)
			(xy 383.382936 -256.683288) (xy 383.378976 -256.634234) (xy 383.050034 -256.634234) (xy 383.049539 -256.658841)
			(xy 383.041644 -256.707418) (xy 383.02606 -256.754099) (xy 383.003189 -256.797676) (xy 382.973624 -256.83702)
			(xy 382.938131 -256.871112) (xy 382.897628 -256.899068) (xy 382.853166 -256.920166) (xy 382.805895 -256.933858)
			(xy 382.75704 -256.93979) (xy 382.707865 -256.937809) (xy 382.659646 -256.927965) (xy 382.61363 -256.910513)
			(xy 382.571009 -256.885906) (xy 382.532888 -256.854781) (xy 382.500253 -256.817944) (xy 382.47395 -256.776348)
			(xy 382.454659 -256.731072) (xy 382.442882 -256.683288) (xy 382.438922 -256.634234) (xy 382.110234 -256.634234)
			(xy 382.109739 -256.658841) (xy 382.101844 -256.707418) (xy 382.08626 -256.754099) (xy 382.063389 -256.797676)
			(xy 382.033824 -256.83702) (xy 381.998331 -256.871112) (xy 381.957828 -256.899068) (xy 381.913366 -256.920166)
			(xy 381.866095 -256.933858) (xy 381.81724 -256.93979) (xy 381.768065 -256.937809) (xy 381.719846 -256.927965)
			(xy 381.67383 -256.910513) (xy 381.631209 -256.885906) (xy 381.593088 -256.854781) (xy 381.560453 -256.817944)
			(xy 381.53415 -256.776348) (xy 381.514859 -256.731072) (xy 381.503082 -256.683288) (xy 381.499122 -256.634234)
			(xy 381.180594 -256.634234) (xy 381.180082 -256.65968) (xy 381.171918 -256.709914) (xy 381.155802 -256.758188)
			(xy 381.132151 -256.803251) (xy 381.101578 -256.843937) (xy 381.064874 -256.879192) (xy 381.02299 -256.908102)
			(xy 380.977011 -256.929919) (xy 380.928127 -256.944079) (xy 380.877606 -256.950213) (xy 380.826754 -256.948164)
			(xy 380.77689 -256.937984) (xy 380.729304 -256.919937) (xy 380.68523 -256.894491) (xy 380.645808 -256.862304)
			(xy 380.61206 -256.82421) (xy 380.584859 -256.781196) (xy 380.564911 -256.734376) (xy 380.552732 -256.684962)
			(xy 380.548637 -256.634234) (xy 380.230126 -256.634234) (xy 380.229631 -256.658841) (xy 380.221736 -256.707418)
			(xy 380.206152 -256.754099) (xy 380.183281 -256.797676) (xy 380.153716 -256.83702) (xy 380.118223 -256.871112)
			(xy 380.07772 -256.899068) (xy 380.033258 -256.920166) (xy 379.985987 -256.933858) (xy 379.937132 -256.93979)
			(xy 379.887957 -256.937809) (xy 379.839738 -256.927965) (xy 379.793722 -256.910513) (xy 379.751101 -256.885906)
			(xy 379.71298 -256.854781) (xy 379.680345 -256.817944) (xy 379.654042 -256.776348) (xy 379.634751 -256.731072)
			(xy 379.622974 -256.683288) (xy 379.619014 -256.634234) (xy 379.290072 -256.634234) (xy 379.289577 -256.658841)
			(xy 379.281682 -256.707418) (xy 379.266098 -256.754099) (xy 379.243227 -256.797676) (xy 379.213662 -256.83702)
			(xy 379.178169 -256.871112) (xy 379.137666 -256.899068) (xy 379.093204 -256.920166) (xy 379.045933 -256.933858)
			(xy 378.997078 -256.93979) (xy 378.947903 -256.937809) (xy 378.899684 -256.927965) (xy 378.853668 -256.910513)
			(xy 378.811047 -256.885906) (xy 378.772926 -256.854781) (xy 378.740291 -256.817944) (xy 378.713988 -256.776348)
			(xy 378.694697 -256.731072) (xy 378.68292 -256.683288) (xy 378.67896 -256.634234) (xy 377.420632 -256.634234)
			(xy 377.42012 -256.65968) (xy 377.411956 -256.709914) (xy 377.39584 -256.758188) (xy 377.372189 -256.803251)
			(xy 377.341616 -256.843937) (xy 377.304912 -256.879192) (xy 377.263028 -256.908102) (xy 377.217049 -256.929919)
			(xy 377.168165 -256.944079) (xy 377.117644 -256.950213) (xy 377.066792 -256.948164) (xy 377.016928 -256.937984)
			(xy 376.969342 -256.919937) (xy 376.925268 -256.894491) (xy 376.885846 -256.862304) (xy 376.852098 -256.82421)
			(xy 376.824897 -256.781196) (xy 376.804949 -256.734376) (xy 376.79277 -256.684962) (xy 376.788675 -256.634234)
			(xy 376.470164 -256.634234) (xy 376.469669 -256.658841) (xy 376.461774 -256.707418) (xy 376.44619 -256.754099)
			(xy 376.423319 -256.797676) (xy 376.393754 -256.83702) (xy 376.358261 -256.871112) (xy 376.317758 -256.899068)
			(xy 376.273296 -256.920166) (xy 376.226025 -256.933858) (xy 376.17717 -256.93979) (xy 376.127995 -256.937809)
			(xy 376.079776 -256.927965) (xy 376.03376 -256.910513) (xy 375.991139 -256.885906) (xy 375.953018 -256.854781)
			(xy 375.920383 -256.817944) (xy 375.89408 -256.776348) (xy 375.874789 -256.731072) (xy 375.863012 -256.683288)
			(xy 375.859052 -256.634234) (xy 374.590056 -256.634234) (xy 374.589561 -256.658841) (xy 374.581666 -256.707418)
			(xy 374.566082 -256.754099) (xy 374.543211 -256.797676) (xy 374.513646 -256.83702) (xy 374.478153 -256.871112)
			(xy 374.43765 -256.899068) (xy 374.393188 -256.920166) (xy 374.345917 -256.933858) (xy 374.297062 -256.93979)
			(xy 374.247887 -256.937809) (xy 374.199668 -256.927965) (xy 374.153652 -256.910513) (xy 374.111031 -256.885906)
			(xy 374.07291 -256.854781) (xy 374.040275 -256.817944) (xy 374.013972 -256.776348) (xy 373.994681 -256.731072)
			(xy 373.982904 -256.683288) (xy 373.978944 -256.634234) (xy 372.710202 -256.634234) (xy 372.709707 -256.658841)
			(xy 372.701812 -256.707418) (xy 372.686228 -256.754099) (xy 372.663357 -256.797676) (xy 372.633792 -256.83702)
			(xy 372.598299 -256.871112) (xy 372.557796 -256.899068) (xy 372.513334 -256.920166) (xy 372.466063 -256.933858)
			(xy 372.417208 -256.93979) (xy 372.368033 -256.937809) (xy 372.319814 -256.927965) (xy 372.273798 -256.910513)
			(xy 372.231177 -256.885906) (xy 372.193056 -256.854781) (xy 372.160421 -256.817944) (xy 372.134118 -256.776348)
			(xy 372.114827 -256.731072) (xy 372.10305 -256.683288) (xy 372.09909 -256.634234) (xy 370.830094 -256.634234)
			(xy 370.829599 -256.658841) (xy 370.821704 -256.707418) (xy 370.80612 -256.754099) (xy 370.783249 -256.797676)
			(xy 370.753684 -256.83702) (xy 370.718191 -256.871112) (xy 370.677688 -256.899068) (xy 370.633226 -256.920166)
			(xy 370.585955 -256.933858) (xy 370.5371 -256.93979) (xy 370.487925 -256.937809) (xy 370.439706 -256.927965)
			(xy 370.39369 -256.910513) (xy 370.351069 -256.885906) (xy 370.312948 -256.854781) (xy 370.280313 -256.817944)
			(xy 370.25401 -256.776348) (xy 370.234719 -256.731072) (xy 370.222942 -256.683288) (xy 370.218982 -256.634234)
			(xy 365.687075 -256.634234) (xy 365.676396 -256.655802) (xy 365.646104 -256.698868) (xy 365.609592 -256.736806)
			(xy 365.567718 -256.768725) (xy 365.521462 -256.793878) (xy 365.471909 -256.811676) (xy 365.420219 -256.8217)
			(xy 365.367605 -256.823717) (xy 365.3153 -256.817679) (xy 365.264529 -256.803727) (xy 365.216484 -256.782188)
			(xy 365.172289 -256.753568) (xy 365.132981 -256.718537) (xy 365.099481 -256.677916) (xy 365.072575 -256.632657)
			(xy 365.052892 -256.583822) (xy 365.040895 -256.532554) (xy 365.036865 -256.480056) (xy 364.468282 -256.480056)
			(xy 364.456937 -256.515907) (xy 364.433574 -256.563092) (xy 364.403282 -256.606158) (xy 364.36677 -256.644096)
			(xy 364.324896 -256.676015) (xy 364.27864 -256.701168) (xy 364.229087 -256.718966) (xy 364.177397 -256.72899)
			(xy 364.124783 -256.731007) (xy 364.072478 -256.724969) (xy 364.021707 -256.711017) (xy 363.973662 -256.689478)
			(xy 363.929467 -256.660858) (xy 363.890159 -256.625827) (xy 363.856659 -256.585206) (xy 363.829753 -256.539947)
			(xy 363.81007 -256.491112) (xy 363.798073 -256.439844) (xy 363.794043 -256.387346) (xy 363.531404 -256.387346)
			(xy 363.5309 -256.413672) (xy 363.522863 -256.465708) (xy 363.506977 -256.515907) (xy 363.483614 -256.563092)
			(xy 363.453322 -256.606158) (xy 363.41681 -256.644096) (xy 363.374936 -256.676015) (xy 363.32868 -256.701168)
			(xy 363.279127 -256.718966) (xy 363.227437 -256.72899) (xy 363.174823 -256.731007) (xy 363.122518 -256.724969)
			(xy 363.071747 -256.711017) (xy 363.023702 -256.689478) (xy 362.979507 -256.660858) (xy 362.940199 -256.625827)
			(xy 362.906699 -256.585206) (xy 362.879793 -256.539947) (xy 362.86011 -256.491112) (xy 362.848113 -256.439844)
			(xy 362.844083 -256.387346) (xy 362.581444 -256.387346) (xy 362.58094 -256.413672) (xy 362.572903 -256.465708)
			(xy 362.557017 -256.515907) (xy 362.533654 -256.563092) (xy 362.503362 -256.606158) (xy 362.46685 -256.644096)
			(xy 362.424976 -256.676015) (xy 362.37872 -256.701168) (xy 362.329167 -256.718966) (xy 362.277477 -256.72899)
			(xy 362.224863 -256.731007) (xy 362.172558 -256.724969) (xy 362.121787 -256.711017) (xy 362.073742 -256.689478)
			(xy 362.029547 -256.660858) (xy 361.990239 -256.625827) (xy 361.956739 -256.585206) (xy 361.929833 -256.539947)
			(xy 361.91015 -256.491112) (xy 361.898153 -256.439844) (xy 361.894123 -256.387346) (xy 361.631484 -256.387346)
			(xy 361.63098 -256.413672) (xy 361.622943 -256.465708) (xy 361.607057 -256.515907) (xy 361.583694 -256.563092)
			(xy 361.553402 -256.606158) (xy 361.51689 -256.644096) (xy 361.475016 -256.676015) (xy 361.42876 -256.701168)
			(xy 361.379207 -256.718966) (xy 361.327517 -256.72899) (xy 361.274903 -256.731007) (xy 361.222598 -256.724969)
			(xy 361.171827 -256.711017) (xy 361.123782 -256.689478) (xy 361.079587 -256.660858) (xy 361.040279 -256.625827)
			(xy 361.006779 -256.585206) (xy 360.979873 -256.539947) (xy 360.96019 -256.491112) (xy 360.948193 -256.439844)
			(xy 360.944163 -256.387346) (xy 360.68127 -256.387346) (xy 360.680766 -256.413672) (xy 360.672729 -256.465708)
			(xy 360.656843 -256.515907) (xy 360.63348 -256.563092) (xy 360.603188 -256.606158) (xy 360.566676 -256.644096)
			(xy 360.524802 -256.676015) (xy 360.478546 -256.701168) (xy 360.428993 -256.718966) (xy 360.377303 -256.72899)
			(xy 360.324689 -256.731007) (xy 360.272384 -256.724969) (xy 360.221613 -256.711017) (xy 360.173568 -256.689478)
			(xy 360.129373 -256.660858) (xy 360.090065 -256.625827) (xy 360.056565 -256.585206) (xy 360.029659 -256.539947)
			(xy 360.009976 -256.491112) (xy 359.997979 -256.439844) (xy 359.993949 -256.387346) (xy 359.73131 -256.387346)
			(xy 359.730806 -256.413672) (xy 359.722769 -256.465708) (xy 359.706883 -256.515907) (xy 359.68352 -256.563092)
			(xy 359.653228 -256.606158) (xy 359.616716 -256.644096) (xy 359.574842 -256.676015) (xy 359.528586 -256.701168)
			(xy 359.479033 -256.718966) (xy 359.427343 -256.72899) (xy 359.374729 -256.731007) (xy 359.322424 -256.724969)
			(xy 359.271653 -256.711017) (xy 359.223608 -256.689478) (xy 359.179413 -256.660858) (xy 359.140105 -256.625827)
			(xy 359.106605 -256.585206) (xy 359.079699 -256.539947) (xy 359.060016 -256.491112) (xy 359.048019 -256.439844)
			(xy 359.043989 -256.387346) (xy 358.78135 -256.387346) (xy 358.780846 -256.413672) (xy 358.772809 -256.465708)
			(xy 358.756923 -256.515907) (xy 358.73356 -256.563092) (xy 358.703268 -256.606158) (xy 358.666756 -256.644096)
			(xy 358.624882 -256.676015) (xy 358.578626 -256.701168) (xy 358.529073 -256.718966) (xy 358.477383 -256.72899)
			(xy 358.424769 -256.731007) (xy 358.372464 -256.724969) (xy 358.321693 -256.711017) (xy 358.273648 -256.689478)
			(xy 358.229453 -256.660858) (xy 358.190145 -256.625827) (xy 358.156645 -256.585206) (xy 358.129739 -256.539947)
			(xy 358.110056 -256.491112) (xy 358.098059 -256.439844) (xy 358.094029 -256.387346) (xy 357.83139 -256.387346)
			(xy 357.830886 -256.413672) (xy 357.822849 -256.465708) (xy 357.806963 -256.515907) (xy 357.7836 -256.563092)
			(xy 357.753308 -256.606158) (xy 357.716796 -256.644096) (xy 357.674922 -256.676015) (xy 357.628666 -256.701168)
			(xy 357.579113 -256.718966) (xy 357.527423 -256.72899) (xy 357.474809 -256.731007) (xy 357.422504 -256.724969)
			(xy 357.371733 -256.711017) (xy 357.323688 -256.689478) (xy 357.279493 -256.660858) (xy 357.240185 -256.625827)
			(xy 357.206685 -256.585206) (xy 357.179779 -256.539947) (xy 357.160096 -256.491112) (xy 357.148099 -256.439844)
			(xy 357.144069 -256.387346) (xy 356.88143 -256.387346) (xy 356.880926 -256.413672) (xy 356.872889 -256.465708)
			(xy 356.857003 -256.515907) (xy 356.83364 -256.563092) (xy 356.803348 -256.606158) (xy 356.766836 -256.644096)
			(xy 356.724962 -256.676015) (xy 356.678706 -256.701168) (xy 356.629153 -256.718966) (xy 356.577463 -256.72899)
			(xy 356.524849 -256.731007) (xy 356.472544 -256.724969) (xy 356.421773 -256.711017) (xy 356.373728 -256.689478)
			(xy 356.329533 -256.660858) (xy 356.290225 -256.625827) (xy 356.256725 -256.585206) (xy 356.229819 -256.539947)
			(xy 356.210136 -256.491112) (xy 356.198139 -256.439844) (xy 356.194109 -256.387346) (xy 355.93147 -256.387346)
			(xy 355.930966 -256.413672) (xy 355.922929 -256.465708) (xy 355.907043 -256.515907) (xy 355.88368 -256.563092)
			(xy 355.853388 -256.606158) (xy 355.816876 -256.644096) (xy 355.775002 -256.676015) (xy 355.728746 -256.701168)
			(xy 355.679193 -256.718966) (xy 355.627503 -256.72899) (xy 355.574889 -256.731007) (xy 355.522584 -256.724969)
			(xy 355.471813 -256.711017) (xy 355.423768 -256.689478) (xy 355.379573 -256.660858) (xy 355.340265 -256.625827)
			(xy 355.306765 -256.585206) (xy 355.279859 -256.539947) (xy 355.260176 -256.491112) (xy 355.248179 -256.439844)
			(xy 355.244149 -256.387346) (xy 354.675596 -256.387346) (xy 354.679782 -256.400323) (xy 354.688113 -256.453261)
			(xy 354.688648 -256.480056) (xy 354.688135 -256.507224) (xy 354.679587 -256.560884) (xy 354.662695 -256.612528)
			(xy 354.637883 -256.660869) (xy 354.605768 -256.704699) (xy 354.586794 -256.72415) (xy 354.579428 -256.731516)
			(xy 354.571808 -256.74955) (xy 354.5713 -256.830322) (xy 354.571716 -256.840171) (xy 354.579045 -256.858451)
			(xy 354.585524 -256.865882) (xy 354.586032 -256.86639) (xy 354.59162 -256.871978) (xy 354.591874 -256.872232)
			(xy 354.599255 -256.878813) (xy 354.617555 -256.886259) (xy 354.627434 -256.88671) (xy 356.025958 -256.88671)
			(xy 356.035796 -256.887244) (xy 356.053959 -256.894829) (xy 356.061264 -256.901442) (xy 356.4382 -257.278378)
			(xy 356.44492 -257.285614) (xy 356.452528 -257.303819) (xy 356.452932 -257.313684) (xy 356.452932 -257.35915)
			(xy 356.452932 -257.362452) (xy 356.45418 -257.37304) (xy 356.464032 -257.391921) (xy 356.471982 -257.399028)
			(xy 356.478332 -257.403092) (xy 356.54107 -257.439668) (xy 356.546948 -257.442807) (xy 356.559811 -257.446272)
			(xy 356.56647 -257.446526) (xy 356.59568 -257.446526) (xy 356.60711 -257.443732) (xy 356.612952 -257.440684)
			(xy 356.637677 -257.428379) (xy 356.690081 -257.410953) (xy 356.744597 -257.402135) (xy 356.77221 -257.401568)
			(xy 356.799195 -257.402098) (xy 356.852501 -257.410542) (xy 356.90383 -257.42722) (xy 356.951919 -257.451722)
			(xy 356.995582 -257.483445) (xy 357.033746 -257.521607) (xy 357.06547 -257.565269) (xy 357.089974 -257.613357)
			(xy 357.106655 -257.664685) (xy 357.115101 -257.717991) (xy 357.115618 -257.744976) (xy 358.928419 -257.744976)
			(xy 358.932449 -257.692478) (xy 358.944446 -257.64121) (xy 358.964129 -257.592375) (xy 358.991035 -257.547116)
			(xy 359.024535 -257.506495) (xy 359.063843 -257.471464) (xy 359.108038 -257.442844) (xy 359.156083 -257.421305)
			(xy 359.206854 -257.407353) (xy 359.259159 -257.401315) (xy 359.311773 -257.403332) (xy 359.363463 -257.413356)
			(xy 359.413016 -257.431154) (xy 359.459272 -257.456307) (xy 359.501146 -257.488226) (xy 359.537658 -257.526164)
			(xy 359.56795 -257.56923) (xy 359.591313 -257.616415) (xy 359.607199 -257.666614) (xy 359.615236 -257.71865)
			(xy 359.61574 -257.744976) (xy 361.178351 -257.744976) (xy 361.182381 -257.692478) (xy 361.194378 -257.64121)
			(xy 361.214061 -257.592375) (xy 361.240967 -257.547116) (xy 361.274467 -257.506495) (xy 361.313775 -257.471464)
			(xy 361.35797 -257.442844) (xy 361.406015 -257.421305) (xy 361.456786 -257.407353) (xy 361.509091 -257.401315)
			(xy 361.561705 -257.403332) (xy 361.613395 -257.413356) (xy 361.662948 -257.431154) (xy 361.709204 -257.456307)
			(xy 361.751078 -257.488226) (xy 361.78759 -257.526164) (xy 361.817882 -257.56923) (xy 361.841245 -257.616415)
			(xy 361.857131 -257.666614) (xy 361.865168 -257.71865) (xy 361.865672 -257.744976) (xy 363.778295 -257.744976)
			(xy 363.782325 -257.692478) (xy 363.794322 -257.64121) (xy 363.814005 -257.592375) (xy 363.840911 -257.547116)
			(xy 363.874411 -257.506495) (xy 363.913719 -257.471464) (xy 363.957914 -257.442844) (xy 364.005959 -257.421305)
			(xy 364.05673 -257.407353) (xy 364.109035 -257.401315) (xy 364.161649 -257.403332) (xy 364.213339 -257.413356)
			(xy 364.259724 -257.430016) (xy 365.036865 -257.430016) (xy 365.040895 -257.377518) (xy 365.052892 -257.32625)
			(xy 365.072575 -257.277415) (xy 365.099481 -257.232156) (xy 365.132981 -257.191535) (xy 365.172289 -257.156504)
			(xy 365.216484 -257.127884) (xy 365.264529 -257.106345) (xy 365.3153 -257.092393) (xy 365.367605 -257.086355)
			(xy 365.420219 -257.088372) (xy 365.471909 -257.098396) (xy 365.521462 -257.116194) (xy 365.567718 -257.141347)
			(xy 365.609592 -257.173266) (xy 365.646104 -257.211204) (xy 365.676396 -257.25427) (xy 365.699759 -257.301455)
			(xy 365.715645 -257.351654) (xy 365.723682 -257.40369) (xy 365.724186 -257.430016) (xy 365.723682 -257.456342)
			(xy 365.715645 -257.508378) (xy 365.699759 -257.558577) (xy 365.676396 -257.605762) (xy 365.646104 -257.648828)
			(xy 365.609592 -257.686766) (xy 365.567718 -257.718685) (xy 365.521462 -257.743838) (xy 365.471909 -257.761636)
			(xy 365.420219 -257.77166) (xy 365.367605 -257.773677) (xy 365.3153 -257.767639) (xy 365.264529 -257.753687)
			(xy 365.216484 -257.732148) (xy 365.172289 -257.703528) (xy 365.132981 -257.668497) (xy 365.099481 -257.627876)
			(xy 365.072575 -257.582617) (xy 365.052892 -257.533782) (xy 365.040895 -257.482514) (xy 365.036865 -257.430016)
			(xy 364.259724 -257.430016) (xy 364.262892 -257.431154) (xy 364.309148 -257.456307) (xy 364.351022 -257.488226)
			(xy 364.387534 -257.526164) (xy 364.417826 -257.56923) (xy 364.441189 -257.616415) (xy 364.457075 -257.666614)
			(xy 364.465112 -257.71865) (xy 364.465616 -257.744976) (xy 364.465112 -257.771302) (xy 364.457075 -257.823338)
			(xy 364.441189 -257.873537) (xy 364.417826 -257.920722) (xy 364.4112 -257.930142) (xy 368.805717 -257.930142)
			(xy 368.809747 -257.877644) (xy 368.821744 -257.826376) (xy 368.841427 -257.777541) (xy 368.868333 -257.732282)
			(xy 368.901833 -257.691661) (xy 368.941141 -257.65663) (xy 368.985336 -257.62801) (xy 369.033381 -257.606471)
			(xy 369.084152 -257.592519) (xy 369.136457 -257.586481) (xy 369.189071 -257.588498) (xy 369.240761 -257.598522)
			(xy 369.290314 -257.61632) (xy 369.33657 -257.641473) (xy 369.378444 -257.673392) (xy 369.414956 -257.71133)
			(xy 369.445248 -257.754396) (xy 369.468611 -257.801581) (xy 369.484497 -257.85178) (xy 369.492534 -257.903816)
			(xy 369.493038 -257.930142) (xy 370.731291 -257.930142) (xy 370.735321 -257.877644) (xy 370.747318 -257.826376)
			(xy 370.767001 -257.777541) (xy 370.793907 -257.732282) (xy 370.827407 -257.691661) (xy 370.866715 -257.65663)
			(xy 370.91091 -257.62801) (xy 370.958955 -257.606471) (xy 371.009726 -257.592519) (xy 371.062031 -257.586481)
			(xy 371.114645 -257.588498) (xy 371.166335 -257.598522) (xy 371.215888 -257.61632) (xy 371.262144 -257.641473)
			(xy 371.304018 -257.673392) (xy 371.34053 -257.71133) (xy 371.370822 -257.754396) (xy 371.394185 -257.801581)
			(xy 371.410071 -257.85178) (xy 371.418108 -257.903816) (xy 371.418612 -257.930142) (xy 372.509291 -257.930142)
			(xy 372.513321 -257.877644) (xy 372.525318 -257.826376) (xy 372.545001 -257.777541) (xy 372.571907 -257.732282)
			(xy 372.605407 -257.691661) (xy 372.644715 -257.65663) (xy 372.68891 -257.62801) (xy 372.736955 -257.606471)
			(xy 372.787726 -257.592519) (xy 372.840031 -257.586481) (xy 372.892645 -257.588498) (xy 372.944335 -257.598522)
			(xy 372.993888 -257.61632) (xy 373.040144 -257.641473) (xy 373.082018 -257.673392) (xy 373.11853 -257.71133)
			(xy 373.148822 -257.754396) (xy 373.172185 -257.801581) (xy 373.188071 -257.85178) (xy 373.196108 -257.903816)
			(xy 373.196612 -257.930142) (xy 373.196108 -257.956468) (xy 373.188071 -258.008504) (xy 373.172185 -258.058703)
			(xy 373.148822 -258.105888) (xy 373.11853 -258.148954) (xy 373.082018 -258.186892) (xy 373.040144 -258.218811)
			(xy 372.993888 -258.243964) (xy 372.944335 -258.261762) (xy 372.892645 -258.271786) (xy 372.840031 -258.273803)
			(xy 372.787726 -258.267765) (xy 372.736955 -258.253813) (xy 372.68891 -258.232274) (xy 372.644715 -258.203654)
			(xy 372.605407 -258.168623) (xy 372.571907 -258.128002) (xy 372.545001 -258.082743) (xy 372.525318 -258.033908)
			(xy 372.513321 -257.98264) (xy 372.509291 -257.930142) (xy 371.418612 -257.930142) (xy 371.418108 -257.956468)
			(xy 371.410071 -258.008504) (xy 371.394185 -258.058703) (xy 371.370822 -258.105888) (xy 371.34053 -258.148954)
			(xy 371.304018 -258.186892) (xy 371.262144 -258.218811) (xy 371.215888 -258.243964) (xy 371.166335 -258.261762)
			(xy 371.114645 -258.271786) (xy 371.062031 -258.273803) (xy 371.009726 -258.267765) (xy 370.958955 -258.253813)
			(xy 370.91091 -258.232274) (xy 370.866715 -258.203654) (xy 370.827407 -258.168623) (xy 370.793907 -258.128002)
			(xy 370.767001 -258.082743) (xy 370.747318 -258.033908) (xy 370.735321 -257.98264) (xy 370.731291 -257.930142)
			(xy 369.493038 -257.930142) (xy 369.492534 -257.956468) (xy 369.484497 -258.008504) (xy 369.468611 -258.058703)
			(xy 369.445248 -258.105888) (xy 369.414956 -258.148954) (xy 369.378444 -258.186892) (xy 369.33657 -258.218811)
			(xy 369.290314 -258.243964) (xy 369.240761 -258.261762) (xy 369.189071 -258.271786) (xy 369.136457 -258.273803)
			(xy 369.084152 -258.267765) (xy 369.033381 -258.253813) (xy 368.985336 -258.232274) (xy 368.941141 -258.203654)
			(xy 368.901833 -258.168623) (xy 368.868333 -258.128002) (xy 368.841427 -258.082743) (xy 368.821744 -258.033908)
			(xy 368.809747 -257.98264) (xy 368.805717 -257.930142) (xy 364.4112 -257.930142) (xy 364.387534 -257.963788)
			(xy 364.351022 -258.001726) (xy 364.309148 -258.033645) (xy 364.262892 -258.058798) (xy 364.213339 -258.076596)
			(xy 364.161649 -258.08662) (xy 364.109035 -258.088637) (xy 364.05673 -258.082599) (xy 364.005959 -258.068647)
			(xy 363.957914 -258.047108) (xy 363.913719 -258.018488) (xy 363.874411 -257.983457) (xy 363.840911 -257.942836)
			(xy 363.814005 -257.897577) (xy 363.794322 -257.848742) (xy 363.782325 -257.797474) (xy 363.778295 -257.744976)
			(xy 361.865672 -257.744976) (xy 361.865168 -257.771302) (xy 361.857131 -257.823338) (xy 361.841245 -257.873537)
			(xy 361.817882 -257.920722) (xy 361.78759 -257.963788) (xy 361.751078 -258.001726) (xy 361.709204 -258.033645)
			(xy 361.662948 -258.058798) (xy 361.613395 -258.076596) (xy 361.561705 -258.08662) (xy 361.509091 -258.088637)
			(xy 361.456786 -258.082599) (xy 361.406015 -258.068647) (xy 361.35797 -258.047108) (xy 361.313775 -258.018488)
			(xy 361.274467 -257.983457) (xy 361.240967 -257.942836) (xy 361.214061 -257.897577) (xy 361.194378 -257.848742)
			(xy 361.182381 -257.797474) (xy 361.178351 -257.744976) (xy 359.61574 -257.744976) (xy 359.615236 -257.771302)
			(xy 359.607199 -257.823338) (xy 359.591313 -257.873537) (xy 359.56795 -257.920722) (xy 359.537658 -257.963788)
			(xy 359.501146 -258.001726) (xy 359.459272 -258.033645) (xy 359.413016 -258.058798) (xy 359.363463 -258.076596)
			(xy 359.311773 -258.08662) (xy 359.259159 -258.088637) (xy 359.206854 -258.082599) (xy 359.156083 -258.068647)
			(xy 359.108038 -258.047108) (xy 359.063843 -258.018488) (xy 359.024535 -257.983457) (xy 358.991035 -257.942836)
			(xy 358.964129 -257.897577) (xy 358.944446 -257.848742) (xy 358.932449 -257.797474) (xy 358.928419 -257.744976)
			(xy 357.115618 -257.744976) (xy 357.115127 -257.771493) (xy 357.10698 -257.823899) (xy 357.090875 -257.874429)
			(xy 357.067196 -257.921884) (xy 357.036505 -257.965136) (xy 356.99953 -258.003157) (xy 356.957152 -258.035044)
			(xy 356.934008 -258.047998) (xy 356.92334 -258.053586) (xy 356.90937 -258.073398) (xy 356.895908 -258.16433)
			(xy 356.894932 -258.175622) (xy 356.901657 -258.197237) (xy 356.908862 -258.205986) (xy 356.909624 -258.207002)
			(xy 356.920546 -258.217924) (xy 356.921054 -258.218432) (xy 356.928434 -258.225017) (xy 356.946733 -258.23247)
			(xy 356.956614 -258.23291) (xy 358.946958 -258.23291) (xy 358.956796 -258.233444) (xy 358.974959 -258.241029)
			(xy 358.982264 -258.247642) (xy 359.114598 -258.379976) (xy 365.036865 -258.379976) (xy 365.040895 -258.327478)
			(xy 365.052892 -258.27621) (xy 365.072575 -258.227375) (xy 365.099481 -258.182116) (xy 365.132981 -258.141495)
			(xy 365.172289 -258.106464) (xy 365.216484 -258.077844) (xy 365.264529 -258.056305) (xy 365.3153 -258.042353)
			(xy 365.367605 -258.036315) (xy 365.420219 -258.038332) (xy 365.471909 -258.048356) (xy 365.521462 -258.066154)
			(xy 365.567718 -258.091307) (xy 365.609592 -258.123226) (xy 365.646104 -258.161164) (xy 365.676396 -258.20423)
			(xy 365.699759 -258.251415) (xy 365.715645 -258.301614) (xy 365.723682 -258.35365) (xy 365.724186 -258.379976)
			(xy 365.723682 -258.406302) (xy 365.715645 -258.458338) (xy 365.699759 -258.508537) (xy 365.676396 -258.555722)
			(xy 365.646104 -258.598788) (xy 365.609592 -258.636726) (xy 365.567718 -258.668645) (xy 365.521462 -258.693798)
			(xy 365.471909 -258.711596) (xy 365.420219 -258.72162) (xy 365.367605 -258.723637) (xy 365.3153 -258.717599)
			(xy 365.264529 -258.703647) (xy 365.216484 -258.682108) (xy 365.172289 -258.653488) (xy 365.132981 -258.618457)
			(xy 365.099481 -258.577836) (xy 365.072575 -258.532577) (xy 365.052892 -258.483742) (xy 365.040895 -258.432474)
			(xy 365.036865 -258.379976) (xy 359.114598 -258.379976) (xy 359.184702 -258.45008) (xy 359.207562 -258.457446)
			(xy 359.219754 -258.455668) (xy 359.232816 -258.453775) (xy 359.259134 -258.451743) (xy 359.272332 -258.451604)
			(xy 359.275126 -258.451604) (xy 359.301826 -258.452331) (xy 359.354523 -258.461034) (xy 359.405236 -258.477791)
			(xy 359.452744 -258.502197) (xy 359.495901 -258.533664) (xy 359.533665 -258.571433) (xy 359.565126 -258.614594)
			(xy 359.589526 -258.662105) (xy 359.606277 -258.712821) (xy 359.614973 -258.765518) (xy 359.61574 -258.792218)
			(xy 359.61574 -258.793742) (xy 359.61574 -258.795012) (xy 359.615616 -258.808211) (xy 359.613582 -258.834529)
			(xy 359.611676 -258.84759) (xy 359.609898 -258.859782) (xy 359.617264 -258.882642) (xy 359.790746 -259.056124)
			(xy 359.791254 -259.056632) (xy 359.798634 -259.063217) (xy 359.816933 -259.07067) (xy 359.826814 -259.07111)
			(xy 361.114848 -259.07111) (xy 361.115864 -259.07111) (xy 361.127538 -259.070294) (xy 361.148313 -259.059578)
			(xy 361.155742 -259.050536) (xy 361.157266 -259.04825) (xy 361.202732 -258.979162) (xy 361.206052 -258.97371)
			(xy 361.21017 -258.961632) (xy 361.21086 -258.955286) (xy 361.211876 -258.94284) (xy 361.206796 -258.930648)
			(xy 361.197958 -258.90914) (xy 361.185509 -258.864336) (xy 361.179227 -258.818262) (xy 361.178856 -258.795012)
			(xy 361.178856 -258.79044) (xy 361.179724 -258.76369) (xy 361.188729 -258.710934) (xy 361.205808 -258.660214)
			(xy 361.230548 -258.612757) (xy 361.26235 -258.569713) (xy 361.300445 -258.532122) (xy 361.343909 -258.500896)
			(xy 361.391691 -258.476789) (xy 361.442634 -258.460387) (xy 361.495505 -258.452085) (xy 361.549023 -258.452085)
			(xy 361.601894 -258.460387) (xy 361.652837 -258.476789) (xy 361.700619 -258.500896) (xy 361.744083 -258.532122)
			(xy 361.782178 -258.569713) (xy 361.81398 -258.612757) (xy 361.83872 -258.660214) (xy 361.855799 -258.710934)
			(xy 361.864804 -258.76369) (xy 361.865672 -258.79044) (xy 361.865672 -258.795012) (xy 361.865285 -258.818261)
			(xy 361.859004 -258.864334) (xy 361.846561 -258.909137) (xy 361.837732 -258.930648) (xy 361.837478 -258.93141)
			(xy 361.835237 -258.937103) (xy 361.833301 -258.949179) (xy 361.833668 -258.955286) (xy 361.834684 -258.96824)
			(xy 361.887262 -259.04825) (xy 361.888786 -259.050536) (xy 361.896202 -259.059592) (xy 361.916985 -259.070303)
			(xy 361.928664 -259.07111) (xy 363.714792 -259.07111) (xy 363.715808 -259.07111) (xy 363.727477 -259.070285)
			(xy 363.748238 -259.059558) (xy 363.755686 -259.050536) (xy 363.75721 -259.04825) (xy 363.802676 -258.979162)
			(xy 363.805994 -258.973709) (xy 363.810108 -258.961631) (xy 363.810804 -258.955286) (xy 363.81182 -258.94284)
			(xy 363.80674 -258.930648) (xy 363.797903 -258.909139) (xy 363.785457 -258.864336) (xy 363.779175 -258.818262)
			(xy 363.7788 -258.795012) (xy 363.7788 -258.79044) (xy 363.779668 -258.76369) (xy 363.788673 -258.710934)
			(xy 363.805752 -258.660214) (xy 363.830492 -258.612757) (xy 363.862294 -258.569713) (xy 363.900389 -258.532122)
			(xy 363.943853 -258.500896) (xy 363.991635 -258.476789) (xy 364.042578 -258.460387) (xy 364.095449 -258.452085)
			(xy 364.148967 -258.452085) (xy 364.201838 -258.460387) (xy 364.252781 -258.476789) (xy 364.300563 -258.500896)
			(xy 364.344027 -258.532122) (xy 364.382122 -258.569713) (xy 364.413924 -258.612757) (xy 364.438664 -258.660214)
			(xy 364.455743 -258.710934) (xy 364.464748 -258.76369) (xy 364.465616 -258.79044) (xy 364.465616 -258.795012)
			(xy 364.465229 -258.818261) (xy 364.46362 -258.830064) (xy 368.805717 -258.830064) (xy 368.809747 -258.777566)
			(xy 368.821744 -258.726298) (xy 368.841427 -258.677463) (xy 368.868333 -258.632204) (xy 368.901833 -258.591583)
			(xy 368.941141 -258.556552) (xy 368.985336 -258.527932) (xy 369.033381 -258.506393) (xy 369.084152 -258.492441)
			(xy 369.136457 -258.486403) (xy 369.189071 -258.48842) (xy 369.240761 -258.498444) (xy 369.290314 -258.516242)
			(xy 369.33657 -258.541395) (xy 369.378444 -258.573314) (xy 369.414956 -258.611252) (xy 369.445248 -258.654318)
			(xy 369.468611 -258.701503) (xy 369.484497 -258.751702) (xy 369.492534 -258.803738) (xy 369.493038 -258.830064)
			(xy 370.731291 -258.830064) (xy 370.735321 -258.777566) (xy 370.747318 -258.726298) (xy 370.767001 -258.677463)
			(xy 370.793907 -258.632204) (xy 370.827407 -258.591583) (xy 370.866715 -258.556552) (xy 370.91091 -258.527932)
			(xy 370.958955 -258.506393) (xy 371.009726 -258.492441) (xy 371.062031 -258.486403) (xy 371.114645 -258.48842)
			(xy 371.166335 -258.498444) (xy 371.215888 -258.516242) (xy 371.262144 -258.541395) (xy 371.304018 -258.573314)
			(xy 371.34053 -258.611252) (xy 371.370822 -258.654318) (xy 371.394185 -258.701503) (xy 371.410071 -258.751702)
			(xy 371.418108 -258.803738) (xy 371.418612 -258.830064) (xy 372.509291 -258.830064) (xy 372.513321 -258.777566)
			(xy 372.525318 -258.726298) (xy 372.545001 -258.677463) (xy 372.571907 -258.632204) (xy 372.605407 -258.591583)
			(xy 372.644715 -258.556552) (xy 372.68891 -258.527932) (xy 372.736955 -258.506393) (xy 372.787726 -258.492441)
			(xy 372.840031 -258.486403) (xy 372.892645 -258.48842) (xy 372.944335 -258.498444) (xy 372.993888 -258.516242)
			(xy 373.040144 -258.541395) (xy 373.082018 -258.573314) (xy 373.11853 -258.611252) (xy 373.148822 -258.654318)
			(xy 373.172185 -258.701503) (xy 373.188071 -258.751702) (xy 373.196108 -258.803738) (xy 373.196612 -258.830064)
			(xy 373.196108 -258.85639) (xy 373.188071 -258.908426) (xy 373.172185 -258.958625) (xy 373.148822 -259.00581)
			(xy 373.11853 -259.048876) (xy 373.082018 -259.086814) (xy 373.040144 -259.118733) (xy 372.993888 -259.143886)
			(xy 372.944335 -259.161684) (xy 372.892645 -259.171708) (xy 372.840031 -259.173725) (xy 372.787726 -259.167687)
			(xy 372.736955 -259.153735) (xy 372.68891 -259.132196) (xy 372.644715 -259.103576) (xy 372.605407 -259.068545)
			(xy 372.571907 -259.027924) (xy 372.545001 -258.982665) (xy 372.525318 -258.93383) (xy 372.513321 -258.882562)
			(xy 372.509291 -258.830064) (xy 371.418612 -258.830064) (xy 371.418108 -258.85639) (xy 371.410071 -258.908426)
			(xy 371.394185 -258.958625) (xy 371.370822 -259.00581) (xy 371.34053 -259.048876) (xy 371.304018 -259.086814)
			(xy 371.262144 -259.118733) (xy 371.215888 -259.143886) (xy 371.166335 -259.161684) (xy 371.114645 -259.171708)
			(xy 371.062031 -259.173725) (xy 371.009726 -259.167687) (xy 370.958955 -259.153735) (xy 370.91091 -259.132196)
			(xy 370.866715 -259.103576) (xy 370.827407 -259.068545) (xy 370.793907 -259.027924) (xy 370.767001 -258.982665)
			(xy 370.747318 -258.93383) (xy 370.735321 -258.882562) (xy 370.731291 -258.830064) (xy 369.493038 -258.830064)
			(xy 369.492534 -258.85639) (xy 369.484497 -258.908426) (xy 369.468611 -258.958625) (xy 369.445248 -259.00581)
			(xy 369.414956 -259.048876) (xy 369.378444 -259.086814) (xy 369.33657 -259.118733) (xy 369.290314 -259.143886)
			(xy 369.240761 -259.161684) (xy 369.189071 -259.171708) (xy 369.136457 -259.173725) (xy 369.084152 -259.167687)
			(xy 369.033381 -259.153735) (xy 368.985336 -259.132196) (xy 368.941141 -259.103576) (xy 368.901833 -259.068545)
			(xy 368.868333 -259.027924) (xy 368.841427 -258.982665) (xy 368.821744 -258.93383) (xy 368.809747 -258.882562)
			(xy 368.805717 -258.830064) (xy 364.46362 -258.830064) (xy 364.458949 -258.864334) (xy 364.446507 -258.909137)
			(xy 364.437676 -258.930648) (xy 364.437422 -258.93141) (xy 364.435183 -258.937103) (xy 364.43325 -258.949179)
			(xy 364.433612 -258.955286) (xy 364.434628 -258.96824) (xy 364.487206 -259.04825) (xy 364.48873 -259.050536)
			(xy 364.496142 -259.059602) (xy 364.516925 -259.070335) (xy 364.528608 -259.07111) (xy 365.129318 -259.07111)
			(xy 365.133527 -259.071028) (xy 365.141826 -259.069621) (xy 365.145828 -259.068316) (xy 365.167672 -259.060696)
			(xy 365.174022 -259.05587) (xy 365.19651 -259.039608) (xy 365.245631 -259.01379) (xy 365.29826 -258.996196)
			(xy 365.353032 -258.987281) (xy 365.380778 -258.986782) (xy 365.408526 -258.987291) (xy 365.463304 -258.996175)
			(xy 365.515937 -259.013765) (xy 365.565051 -259.0396) (xy 365.587534 -259.05587) (xy 365.593884 -259.060696)
			(xy 365.615728 -259.068316) (xy 365.619735 -259.069604) (xy 365.628031 -259.071016) (xy 365.632238 -259.07111)
			(xy 365.703358 -259.07111) (xy 365.713196 -259.071644) (xy 365.731359 -259.079229) (xy 365.738664 -259.085842)
			(xy 365.9124 -259.259578) (xy 365.91912 -259.266814) (xy 365.926728 -259.285019) (xy 365.927132 -259.294884)
			(xy 365.927132 -259.729986) (xy 368.805717 -259.729986) (xy 368.809747 -259.677488) (xy 368.821744 -259.62622)
			(xy 368.841427 -259.577385) (xy 368.868333 -259.532126) (xy 368.901833 -259.491505) (xy 368.941141 -259.456474)
			(xy 368.985336 -259.427854) (xy 369.033381 -259.406315) (xy 369.084152 -259.392363) (xy 369.136457 -259.386325)
			(xy 369.189071 -259.388342) (xy 369.240761 -259.398366) (xy 369.290314 -259.416164) (xy 369.33657 -259.441317)
			(xy 369.378444 -259.473236) (xy 369.414956 -259.511174) (xy 369.445248 -259.55424) (xy 369.468611 -259.601425)
			(xy 369.484497 -259.651624) (xy 369.492534 -259.70366) (xy 369.493038 -259.729986) (xy 370.731291 -259.729986)
			(xy 370.735321 -259.677488) (xy 370.747318 -259.62622) (xy 370.767001 -259.577385) (xy 370.793907 -259.532126)
			(xy 370.827407 -259.491505) (xy 370.866715 -259.456474) (xy 370.91091 -259.427854) (xy 370.958955 -259.406315)
			(xy 371.009726 -259.392363) (xy 371.062031 -259.386325) (xy 371.114645 -259.388342) (xy 371.166335 -259.398366)
			(xy 371.215888 -259.416164) (xy 371.262144 -259.441317) (xy 371.304018 -259.473236) (xy 371.34053 -259.511174)
			(xy 371.370822 -259.55424) (xy 371.394185 -259.601425) (xy 371.410071 -259.651624) (xy 371.418108 -259.70366)
			(xy 371.418612 -259.729986) (xy 372.509291 -259.729986) (xy 372.513321 -259.677488) (xy 372.525318 -259.62622)
			(xy 372.545001 -259.577385) (xy 372.571907 -259.532126) (xy 372.605407 -259.491505) (xy 372.644715 -259.456474)
			(xy 372.68891 -259.427854) (xy 372.736955 -259.406315) (xy 372.787726 -259.392363) (xy 372.840031 -259.386325)
			(xy 372.892645 -259.388342) (xy 372.944335 -259.398366) (xy 372.993888 -259.416164) (xy 373.040144 -259.441317)
			(xy 373.082018 -259.473236) (xy 373.11853 -259.511174) (xy 373.148822 -259.55424) (xy 373.172185 -259.601425)
			(xy 373.188071 -259.651624) (xy 373.196108 -259.70366) (xy 373.196612 -259.729986) (xy 373.196108 -259.756312)
			(xy 373.188071 -259.808348) (xy 373.172185 -259.858547) (xy 373.148822 -259.905732) (xy 373.11853 -259.948798)
			(xy 373.082018 -259.986736) (xy 373.040144 -260.018655) (xy 372.993888 -260.043808) (xy 372.944335 -260.061606)
			(xy 372.892645 -260.07163) (xy 372.840031 -260.073647) (xy 372.787726 -260.067609) (xy 372.736955 -260.053657)
			(xy 372.68891 -260.032118) (xy 372.644715 -260.003498) (xy 372.605407 -259.968467) (xy 372.571907 -259.927846)
			(xy 372.545001 -259.882587) (xy 372.525318 -259.833752) (xy 372.513321 -259.782484) (xy 372.509291 -259.729986)
			(xy 371.418612 -259.729986) (xy 371.418108 -259.756312) (xy 371.410071 -259.808348) (xy 371.394185 -259.858547)
			(xy 371.370822 -259.905732) (xy 371.34053 -259.948798) (xy 371.304018 -259.986736) (xy 371.262144 -260.018655)
			(xy 371.215888 -260.043808) (xy 371.166335 -260.061606) (xy 371.114645 -260.07163) (xy 371.062031 -260.073647)
			(xy 371.009726 -260.067609) (xy 370.958955 -260.053657) (xy 370.91091 -260.032118) (xy 370.866715 -260.003498)
			(xy 370.827407 -259.968467) (xy 370.793907 -259.927846) (xy 370.767001 -259.882587) (xy 370.747318 -259.833752)
			(xy 370.735321 -259.782484) (xy 370.731291 -259.729986) (xy 369.493038 -259.729986) (xy 369.492534 -259.756312)
			(xy 369.484497 -259.808348) (xy 369.468611 -259.858547) (xy 369.445248 -259.905732) (xy 369.414956 -259.948798)
			(xy 369.378444 -259.986736) (xy 369.33657 -260.018655) (xy 369.290314 -260.043808) (xy 369.240761 -260.061606)
			(xy 369.189071 -260.07163) (xy 369.136457 -260.073647) (xy 369.084152 -260.067609) (xy 369.033381 -260.053657)
			(xy 368.985336 -260.032118) (xy 368.941141 -260.003498) (xy 368.901833 -259.968467) (xy 368.868333 -259.927846)
			(xy 368.841427 -259.882587) (xy 368.821744 -259.833752) (xy 368.809747 -259.782484) (xy 368.805717 -259.729986)
			(xy 365.927132 -259.729986) (xy 365.927132 -261.12597) (xy 369.578902 -261.12597) (xy 369.582862 -261.076916)
			(xy 369.594639 -261.029132) (xy 369.61393 -260.983856) (xy 369.640233 -260.94226) (xy 369.672868 -260.905423)
			(xy 369.710989 -260.874298) (xy 369.75361 -260.849691) (xy 369.799626 -260.832239) (xy 369.847845 -260.822395)
			(xy 369.89702 -260.820414) (xy 369.945875 -260.826346) (xy 369.993146 -260.840038) (xy 370.037608 -260.861136)
			(xy 370.078111 -260.889092) (xy 370.113604 -260.923184) (xy 370.143169 -260.962528) (xy 370.16604 -261.006105)
			(xy 370.181624 -261.052786) (xy 370.189519 -261.101363) (xy 370.190014 -261.12597) (xy 371.45901 -261.12597)
			(xy 371.46297 -261.076916) (xy 371.474747 -261.029132) (xy 371.494038 -260.983856) (xy 371.520341 -260.94226)
			(xy 371.552976 -260.905423) (xy 371.591097 -260.874298) (xy 371.633718 -260.849691) (xy 371.679734 -260.832239)
			(xy 371.727953 -260.822395) (xy 371.777128 -260.820414) (xy 371.825983 -260.826346) (xy 371.873254 -260.840038)
			(xy 371.917716 -260.861136) (xy 371.958219 -260.889092) (xy 371.993712 -260.923184) (xy 372.023277 -260.962528)
			(xy 372.046148 -261.006105) (xy 372.061732 -261.052786) (xy 372.069627 -261.101363) (xy 372.070122 -261.12597)
			(xy 373.339118 -261.12597) (xy 373.343078 -261.076916) (xy 373.354855 -261.029132) (xy 373.374146 -260.983856)
			(xy 373.400449 -260.94226) (xy 373.433084 -260.905423) (xy 373.471205 -260.874298) (xy 373.513826 -260.849691)
			(xy 373.559842 -260.832239) (xy 373.608061 -260.822395) (xy 373.657236 -260.820414) (xy 373.706091 -260.826346)
			(xy 373.753362 -260.840038) (xy 373.797824 -260.861136) (xy 373.838327 -260.889092) (xy 373.87382 -260.923184)
			(xy 373.903385 -260.962528) (xy 373.926256 -261.006105) (xy 373.94184 -261.052786) (xy 373.949735 -261.101363)
			(xy 373.95023 -261.12597) (xy 375.218972 -261.12597) (xy 375.222932 -261.076916) (xy 375.234709 -261.029132)
			(xy 375.254 -260.983856) (xy 375.280303 -260.94226) (xy 375.312938 -260.905423) (xy 375.351059 -260.874298)
			(xy 375.39368 -260.849691) (xy 375.439696 -260.832239) (xy 375.487915 -260.822395) (xy 375.53709 -260.820414)
			(xy 375.585945 -260.826346) (xy 375.633216 -260.840038) (xy 375.677678 -260.861136) (xy 375.718181 -260.889092)
			(xy 375.753674 -260.923184) (xy 375.783239 -260.962528) (xy 375.80611 -261.006105) (xy 375.821694 -261.052786)
			(xy 375.829589 -261.101363) (xy 375.830084 -261.12597) (xy 376.159026 -261.12597) (xy 376.162986 -261.076916)
			(xy 376.174763 -261.029132) (xy 376.194054 -260.983856) (xy 376.220357 -260.94226) (xy 376.252992 -260.905423)
			(xy 376.291113 -260.874298) (xy 376.333734 -260.849691) (xy 376.37975 -260.832239) (xy 376.427969 -260.822395)
			(xy 376.477144 -260.820414) (xy 376.525999 -260.826346) (xy 376.57327 -260.840038) (xy 376.617732 -260.861136)
			(xy 376.658235 -260.889092) (xy 376.693728 -260.923184) (xy 376.723293 -260.962528) (xy 376.746164 -261.006105)
			(xy 376.761748 -261.052786) (xy 376.769643 -261.101363) (xy 376.770138 -261.12597) (xy 377.09908 -261.12597)
			(xy 377.10304 -261.076916) (xy 377.114817 -261.029132) (xy 377.134108 -260.983856) (xy 377.160411 -260.94226)
			(xy 377.193046 -260.905423) (xy 377.231167 -260.874298) (xy 377.273788 -260.849691) (xy 377.319804 -260.832239)
			(xy 377.368023 -260.822395) (xy 377.417198 -260.820414) (xy 377.466053 -260.826346) (xy 377.513324 -260.840038)
			(xy 377.557786 -260.861136) (xy 377.598289 -260.889092) (xy 377.633782 -260.923184) (xy 377.663347 -260.962528)
			(xy 377.686218 -261.006105) (xy 377.701802 -261.052786) (xy 377.709697 -261.101363) (xy 377.710192 -261.12597)
			(xy 378.039134 -261.12597) (xy 378.043094 -261.076916) (xy 378.054871 -261.029132) (xy 378.074162 -260.983856)
			(xy 378.100465 -260.94226) (xy 378.1331 -260.905423) (xy 378.171221 -260.874298) (xy 378.213842 -260.849691)
			(xy 378.259858 -260.832239) (xy 378.308077 -260.822395) (xy 378.357252 -260.820414) (xy 378.406107 -260.826346)
			(xy 378.453378 -260.840038) (xy 378.49784 -260.861136) (xy 378.538343 -260.889092) (xy 378.573836 -260.923184)
			(xy 378.603401 -260.962528) (xy 378.626272 -261.006105) (xy 378.641856 -261.052786) (xy 378.649751 -261.101363)
			(xy 378.650246 -261.12597) (xy 378.978934 -261.12597) (xy 378.982894 -261.076916) (xy 378.994671 -261.029132)
			(xy 379.013962 -260.983856) (xy 379.040265 -260.94226) (xy 379.0729 -260.905423) (xy 379.111021 -260.874298)
			(xy 379.153642 -260.849691) (xy 379.199658 -260.832239) (xy 379.247877 -260.822395) (xy 379.297052 -260.820414)
			(xy 379.345907 -260.826346) (xy 379.393178 -260.840038) (xy 379.43764 -260.861136) (xy 379.478143 -260.889092)
			(xy 379.513636 -260.923184) (xy 379.543201 -260.962528) (xy 379.566072 -261.006105) (xy 379.581656 -261.052786)
			(xy 379.589551 -261.101363) (xy 379.590046 -261.12597) (xy 379.918988 -261.12597) (xy 379.922948 -261.076916)
			(xy 379.934725 -261.029132) (xy 379.954016 -260.983856) (xy 379.980319 -260.94226) (xy 380.012954 -260.905423)
			(xy 380.051075 -260.874298) (xy 380.093696 -260.849691) (xy 380.139712 -260.832239) (xy 380.187931 -260.822395)
			(xy 380.237106 -260.820414) (xy 380.285961 -260.826346) (xy 380.333232 -260.840038) (xy 380.377694 -260.861136)
			(xy 380.418197 -260.889092) (xy 380.45369 -260.923184) (xy 380.483255 -260.962528) (xy 380.506126 -261.006105)
			(xy 380.52171 -261.052786) (xy 380.529605 -261.101363) (xy 380.5301 -261.12597) (xy 380.859042 -261.12597)
			(xy 380.863002 -261.076916) (xy 380.874779 -261.029132) (xy 380.89407 -260.983856) (xy 380.920373 -260.94226)
			(xy 380.953008 -260.905423) (xy 380.991129 -260.874298) (xy 381.03375 -260.849691) (xy 381.079766 -260.832239)
			(xy 381.127985 -260.822395) (xy 381.17716 -260.820414) (xy 381.226015 -260.826346) (xy 381.273286 -260.840038)
			(xy 381.317748 -260.861136) (xy 381.358251 -260.889092) (xy 381.393744 -260.923184) (xy 381.423309 -260.962528)
			(xy 381.44618 -261.006105) (xy 381.461764 -261.052786) (xy 381.469659 -261.101363) (xy 381.470154 -261.12597)
			(xy 381.799096 -261.12597) (xy 381.803056 -261.076916) (xy 381.814833 -261.029132) (xy 381.834124 -260.983856)
			(xy 381.860427 -260.94226) (xy 381.893062 -260.905423) (xy 381.931183 -260.874298) (xy 381.973804 -260.849691)
			(xy 382.01982 -260.832239) (xy 382.068039 -260.822395) (xy 382.117214 -260.820414) (xy 382.166069 -260.826346)
			(xy 382.21334 -260.840038) (xy 382.257802 -260.861136) (xy 382.298305 -260.889092) (xy 382.333798 -260.923184)
			(xy 382.363363 -260.962528) (xy 382.386234 -261.006105) (xy 382.401818 -261.052786) (xy 382.409713 -261.101363)
			(xy 382.410208 -261.12597) (xy 382.738896 -261.12597) (xy 382.742856 -261.076916) (xy 382.754633 -261.029132)
			(xy 382.773924 -260.983856) (xy 382.800227 -260.94226) (xy 382.832862 -260.905423) (xy 382.870983 -260.874298)
			(xy 382.913604 -260.849691) (xy 382.95962 -260.832239) (xy 383.007839 -260.822395) (xy 383.057014 -260.820414)
			(xy 383.105869 -260.826346) (xy 383.15314 -260.840038) (xy 383.197602 -260.861136) (xy 383.238105 -260.889092)
			(xy 383.273598 -260.923184) (xy 383.303163 -260.962528) (xy 383.326034 -261.006105) (xy 383.341618 -261.052786)
			(xy 383.349513 -261.101363) (xy 383.350008 -261.12597) (xy 383.67895 -261.12597) (xy 383.68291 -261.076916)
			(xy 383.694687 -261.029132) (xy 383.713978 -260.983856) (xy 383.740281 -260.94226) (xy 383.772916 -260.905423)
			(xy 383.811037 -260.874298) (xy 383.853658 -260.849691) (xy 383.899674 -260.832239) (xy 383.947893 -260.822395)
			(xy 383.997068 -260.820414) (xy 384.045923 -260.826346) (xy 384.093194 -260.840038) (xy 384.137656 -260.861136)
			(xy 384.178159 -260.889092) (xy 384.213652 -260.923184) (xy 384.243217 -260.962528) (xy 384.266088 -261.006105)
			(xy 384.281672 -261.052786) (xy 384.289567 -261.101363) (xy 384.290062 -261.12597) (xy 384.619004 -261.12597)
			(xy 384.622964 -261.076916) (xy 384.634741 -261.029132) (xy 384.654032 -260.983856) (xy 384.680335 -260.94226)
			(xy 384.71297 -260.905423) (xy 384.751091 -260.874298) (xy 384.793712 -260.849691) (xy 384.839728 -260.832239)
			(xy 384.887947 -260.822395) (xy 384.937122 -260.820414) (xy 384.985977 -260.826346) (xy 385.033248 -260.840038)
			(xy 385.07771 -260.861136) (xy 385.118213 -260.889092) (xy 385.153706 -260.923184) (xy 385.183271 -260.962528)
			(xy 385.206142 -261.006105) (xy 385.221726 -261.052786) (xy 385.229621 -261.101363) (xy 385.230116 -261.12597)
			(xy 385.559058 -261.12597) (xy 385.563018 -261.076916) (xy 385.574795 -261.029132) (xy 385.594086 -260.983856)
			(xy 385.620389 -260.94226) (xy 385.653024 -260.905423) (xy 385.691145 -260.874298) (xy 385.733766 -260.849691)
			(xy 385.779782 -260.832239) (xy 385.828001 -260.822395) (xy 385.877176 -260.820414) (xy 385.926031 -260.826346)
			(xy 385.973302 -260.840038) (xy 386.017764 -260.861136) (xy 386.058267 -260.889092) (xy 386.09376 -260.923184)
			(xy 386.123325 -260.962528) (xy 386.146196 -261.006105) (xy 386.16178 -261.052786) (xy 386.169675 -261.101363)
			(xy 386.17017 -261.12597) (xy 386.499112 -261.12597) (xy 386.503072 -261.076916) (xy 386.514849 -261.029132)
			(xy 386.53414 -260.983856) (xy 386.560443 -260.94226) (xy 386.593078 -260.905423) (xy 386.631199 -260.874298)
			(xy 386.67382 -260.849691) (xy 386.719836 -260.832239) (xy 386.768055 -260.822395) (xy 386.81723 -260.820414)
			(xy 386.866085 -260.826346) (xy 386.913356 -260.840038) (xy 386.957818 -260.861136) (xy 386.998321 -260.889092)
			(xy 387.033814 -260.923184) (xy 387.063379 -260.962528) (xy 387.08625 -261.006105) (xy 387.101834 -261.052786)
			(xy 387.109729 -261.101363) (xy 387.110224 -261.12597) (xy 387.438912 -261.12597) (xy 387.442872 -261.076916)
			(xy 387.454649 -261.029132) (xy 387.47394 -260.983856) (xy 387.500243 -260.94226) (xy 387.532878 -260.905423)
			(xy 387.570999 -260.874298) (xy 387.61362 -260.849691) (xy 387.659636 -260.832239) (xy 387.707855 -260.822395)
			(xy 387.75703 -260.820414) (xy 387.805885 -260.826346) (xy 387.853156 -260.840038) (xy 387.897618 -260.861136)
			(xy 387.938121 -260.889092) (xy 387.973614 -260.923184) (xy 388.003179 -260.962528) (xy 388.02605 -261.006105)
			(xy 388.041634 -261.052786) (xy 388.049529 -261.101363) (xy 388.050024 -261.12597) (xy 388.049529 -261.150577)
			(xy 388.041634 -261.199154) (xy 388.02605 -261.245835) (xy 388.003179 -261.289412) (xy 387.973614 -261.328756)
			(xy 387.938121 -261.362848) (xy 387.897618 -261.390804) (xy 387.853156 -261.411902) (xy 387.805885 -261.425594)
			(xy 387.75703 -261.431526) (xy 387.707855 -261.429545) (xy 387.659636 -261.419701) (xy 387.61362 -261.402249)
			(xy 387.570999 -261.377642) (xy 387.532878 -261.346517) (xy 387.500243 -261.30968) (xy 387.47394 -261.268084)
			(xy 387.454649 -261.222808) (xy 387.442872 -261.175024) (xy 387.438912 -261.12597) (xy 387.110224 -261.12597)
			(xy 387.109729 -261.150577) (xy 387.101834 -261.199154) (xy 387.08625 -261.245835) (xy 387.063379 -261.289412)
			(xy 387.033814 -261.328756) (xy 386.998321 -261.362848) (xy 386.957818 -261.390804) (xy 386.913356 -261.411902)
			(xy 386.866085 -261.425594) (xy 386.81723 -261.431526) (xy 386.768055 -261.429545) (xy 386.719836 -261.419701)
			(xy 386.67382 -261.402249) (xy 386.631199 -261.377642) (xy 386.593078 -261.346517) (xy 386.560443 -261.30968)
			(xy 386.53414 -261.268084) (xy 386.514849 -261.222808) (xy 386.503072 -261.175024) (xy 386.499112 -261.12597)
			(xy 386.17017 -261.12597) (xy 386.169675 -261.150577) (xy 386.16178 -261.199154) (xy 386.146196 -261.245835)
			(xy 386.123325 -261.289412) (xy 386.09376 -261.328756) (xy 386.058267 -261.362848) (xy 386.017764 -261.390804)
			(xy 385.973302 -261.411902) (xy 385.926031 -261.425594) (xy 385.877176 -261.431526) (xy 385.828001 -261.429545)
			(xy 385.779782 -261.419701) (xy 385.733766 -261.402249) (xy 385.691145 -261.377642) (xy 385.653024 -261.346517)
			(xy 385.620389 -261.30968) (xy 385.594086 -261.268084) (xy 385.574795 -261.222808) (xy 385.563018 -261.175024)
			(xy 385.559058 -261.12597) (xy 385.230116 -261.12597) (xy 385.229621 -261.150577) (xy 385.221726 -261.199154)
			(xy 385.206142 -261.245835) (xy 385.183271 -261.289412) (xy 385.153706 -261.328756) (xy 385.118213 -261.362848)
			(xy 385.07771 -261.390804) (xy 385.033248 -261.411902) (xy 384.985977 -261.425594) (xy 384.937122 -261.431526)
			(xy 384.887947 -261.429545) (xy 384.839728 -261.419701) (xy 384.793712 -261.402249) (xy 384.751091 -261.377642)
			(xy 384.71297 -261.346517) (xy 384.680335 -261.30968) (xy 384.654032 -261.268084) (xy 384.634741 -261.222808)
			(xy 384.622964 -261.175024) (xy 384.619004 -261.12597) (xy 384.290062 -261.12597) (xy 384.289567 -261.150577)
			(xy 384.281672 -261.199154) (xy 384.266088 -261.245835) (xy 384.243217 -261.289412) (xy 384.213652 -261.328756)
			(xy 384.178159 -261.362848) (xy 384.137656 -261.390804) (xy 384.093194 -261.411902) (xy 384.045923 -261.425594)
			(xy 383.997068 -261.431526) (xy 383.947893 -261.429545) (xy 383.899674 -261.419701) (xy 383.853658 -261.402249)
			(xy 383.811037 -261.377642) (xy 383.772916 -261.346517) (xy 383.740281 -261.30968) (xy 383.713978 -261.268084)
			(xy 383.694687 -261.222808) (xy 383.68291 -261.175024) (xy 383.67895 -261.12597) (xy 383.350008 -261.12597)
			(xy 383.349513 -261.150577) (xy 383.341618 -261.199154) (xy 383.326034 -261.245835) (xy 383.303163 -261.289412)
			(xy 383.273598 -261.328756) (xy 383.238105 -261.362848) (xy 383.197602 -261.390804) (xy 383.15314 -261.411902)
			(xy 383.105869 -261.425594) (xy 383.057014 -261.431526) (xy 383.007839 -261.429545) (xy 382.95962 -261.419701)
			(xy 382.913604 -261.402249) (xy 382.870983 -261.377642) (xy 382.832862 -261.346517) (xy 382.800227 -261.30968)
			(xy 382.773924 -261.268084) (xy 382.754633 -261.222808) (xy 382.742856 -261.175024) (xy 382.738896 -261.12597)
			(xy 382.410208 -261.12597) (xy 382.409713 -261.150577) (xy 382.401818 -261.199154) (xy 382.386234 -261.245835)
			(xy 382.363363 -261.289412) (xy 382.333798 -261.328756) (xy 382.298305 -261.362848) (xy 382.257802 -261.390804)
			(xy 382.21334 -261.411902) (xy 382.166069 -261.425594) (xy 382.117214 -261.431526) (xy 382.068039 -261.429545)
			(xy 382.01982 -261.419701) (xy 381.973804 -261.402249) (xy 381.931183 -261.377642) (xy 381.893062 -261.346517)
			(xy 381.860427 -261.30968) (xy 381.834124 -261.268084) (xy 381.814833 -261.222808) (xy 381.803056 -261.175024)
			(xy 381.799096 -261.12597) (xy 381.470154 -261.12597) (xy 381.469659 -261.150577) (xy 381.461764 -261.199154)
			(xy 381.44618 -261.245835) (xy 381.423309 -261.289412) (xy 381.393744 -261.328756) (xy 381.358251 -261.362848)
			(xy 381.317748 -261.390804) (xy 381.273286 -261.411902) (xy 381.226015 -261.425594) (xy 381.17716 -261.431526)
			(xy 381.127985 -261.429545) (xy 381.079766 -261.419701) (xy 381.03375 -261.402249) (xy 380.991129 -261.377642)
			(xy 380.953008 -261.346517) (xy 380.920373 -261.30968) (xy 380.89407 -261.268084) (xy 380.874779 -261.222808)
			(xy 380.863002 -261.175024) (xy 380.859042 -261.12597) (xy 380.5301 -261.12597) (xy 380.529605 -261.150577)
			(xy 380.52171 -261.199154) (xy 380.506126 -261.245835) (xy 380.483255 -261.289412) (xy 380.45369 -261.328756)
			(xy 380.418197 -261.362848) (xy 380.377694 -261.390804) (xy 380.333232 -261.411902) (xy 380.285961 -261.425594)
			(xy 380.237106 -261.431526) (xy 380.187931 -261.429545) (xy 380.139712 -261.419701) (xy 380.093696 -261.402249)
			(xy 380.051075 -261.377642) (xy 380.012954 -261.346517) (xy 379.980319 -261.30968) (xy 379.954016 -261.268084)
			(xy 379.934725 -261.222808) (xy 379.922948 -261.175024) (xy 379.918988 -261.12597) (xy 379.590046 -261.12597)
			(xy 379.589551 -261.150577) (xy 379.581656 -261.199154) (xy 379.566072 -261.245835) (xy 379.543201 -261.289412)
			(xy 379.513636 -261.328756) (xy 379.478143 -261.362848) (xy 379.43764 -261.390804) (xy 379.393178 -261.411902)
			(xy 379.345907 -261.425594) (xy 379.297052 -261.431526) (xy 379.247877 -261.429545) (xy 379.199658 -261.419701)
			(xy 379.153642 -261.402249) (xy 379.111021 -261.377642) (xy 379.0729 -261.346517) (xy 379.040265 -261.30968)
			(xy 379.013962 -261.268084) (xy 378.994671 -261.222808) (xy 378.982894 -261.175024) (xy 378.978934 -261.12597)
			(xy 378.650246 -261.12597) (xy 378.649751 -261.150577) (xy 378.641856 -261.199154) (xy 378.626272 -261.245835)
			(xy 378.603401 -261.289412) (xy 378.573836 -261.328756) (xy 378.538343 -261.362848) (xy 378.49784 -261.390804)
			(xy 378.453378 -261.411902) (xy 378.406107 -261.425594) (xy 378.357252 -261.431526) (xy 378.308077 -261.429545)
			(xy 378.259858 -261.419701) (xy 378.213842 -261.402249) (xy 378.171221 -261.377642) (xy 378.1331 -261.346517)
			(xy 378.100465 -261.30968) (xy 378.074162 -261.268084) (xy 378.054871 -261.222808) (xy 378.043094 -261.175024)
			(xy 378.039134 -261.12597) (xy 377.710192 -261.12597) (xy 377.709697 -261.150577) (xy 377.701802 -261.199154)
			(xy 377.686218 -261.245835) (xy 377.663347 -261.289412) (xy 377.633782 -261.328756) (xy 377.598289 -261.362848)
			(xy 377.557786 -261.390804) (xy 377.513324 -261.411902) (xy 377.466053 -261.425594) (xy 377.417198 -261.431526)
			(xy 377.368023 -261.429545) (xy 377.319804 -261.419701) (xy 377.273788 -261.402249) (xy 377.231167 -261.377642)
			(xy 377.193046 -261.346517) (xy 377.160411 -261.30968) (xy 377.134108 -261.268084) (xy 377.114817 -261.222808)
			(xy 377.10304 -261.175024) (xy 377.09908 -261.12597) (xy 376.770138 -261.12597) (xy 376.769643 -261.150577)
			(xy 376.761748 -261.199154) (xy 376.746164 -261.245835) (xy 376.723293 -261.289412) (xy 376.693728 -261.328756)
			(xy 376.658235 -261.362848) (xy 376.617732 -261.390804) (xy 376.57327 -261.411902) (xy 376.525999 -261.425594)
			(xy 376.477144 -261.431526) (xy 376.427969 -261.429545) (xy 376.37975 -261.419701) (xy 376.333734 -261.402249)
			(xy 376.291113 -261.377642) (xy 376.252992 -261.346517) (xy 376.220357 -261.30968) (xy 376.194054 -261.268084)
			(xy 376.174763 -261.222808) (xy 376.162986 -261.175024) (xy 376.159026 -261.12597) (xy 375.830084 -261.12597)
			(xy 375.829589 -261.150577) (xy 375.821694 -261.199154) (xy 375.80611 -261.245835) (xy 375.783239 -261.289412)
			(xy 375.753674 -261.328756) (xy 375.718181 -261.362848) (xy 375.677678 -261.390804) (xy 375.633216 -261.411902)
			(xy 375.585945 -261.425594) (xy 375.53709 -261.431526) (xy 375.487915 -261.429545) (xy 375.439696 -261.419701)
			(xy 375.39368 -261.402249) (xy 375.351059 -261.377642) (xy 375.312938 -261.346517) (xy 375.280303 -261.30968)
			(xy 375.254 -261.268084) (xy 375.234709 -261.222808) (xy 375.222932 -261.175024) (xy 375.218972 -261.12597)
			(xy 373.95023 -261.12597) (xy 373.949735 -261.150577) (xy 373.94184 -261.199154) (xy 373.926256 -261.245835)
			(xy 373.903385 -261.289412) (xy 373.87382 -261.328756) (xy 373.838327 -261.362848) (xy 373.797824 -261.390804)
			(xy 373.753362 -261.411902) (xy 373.706091 -261.425594) (xy 373.657236 -261.431526) (xy 373.608061 -261.429545)
			(xy 373.559842 -261.419701) (xy 373.513826 -261.402249) (xy 373.471205 -261.377642) (xy 373.433084 -261.346517)
			(xy 373.400449 -261.30968) (xy 373.374146 -261.268084) (xy 373.354855 -261.222808) (xy 373.343078 -261.175024)
			(xy 373.339118 -261.12597) (xy 372.070122 -261.12597) (xy 372.069627 -261.150577) (xy 372.061732 -261.199154)
			(xy 372.046148 -261.245835) (xy 372.023277 -261.289412) (xy 371.993712 -261.328756) (xy 371.958219 -261.362848)
			(xy 371.917716 -261.390804) (xy 371.873254 -261.411902) (xy 371.825983 -261.425594) (xy 371.777128 -261.431526)
			(xy 371.727953 -261.429545) (xy 371.679734 -261.419701) (xy 371.633718 -261.402249) (xy 371.591097 -261.377642)
			(xy 371.552976 -261.346517) (xy 371.520341 -261.30968) (xy 371.494038 -261.268084) (xy 371.474747 -261.222808)
			(xy 371.46297 -261.175024) (xy 371.45901 -261.12597) (xy 370.190014 -261.12597) (xy 370.189519 -261.150577)
			(xy 370.181624 -261.199154) (xy 370.16604 -261.245835) (xy 370.143169 -261.289412) (xy 370.113604 -261.328756)
			(xy 370.078111 -261.362848) (xy 370.037608 -261.390804) (xy 369.993146 -261.411902) (xy 369.945875 -261.425594)
			(xy 369.89702 -261.431526) (xy 369.847845 -261.429545) (xy 369.799626 -261.419701) (xy 369.75361 -261.402249)
			(xy 369.710989 -261.377642) (xy 369.672868 -261.346517) (xy 369.640233 -261.30968) (xy 369.61393 -261.268084)
			(xy 369.594639 -261.222808) (xy 369.582862 -261.175024) (xy 369.578902 -261.12597) (xy 365.927132 -261.12597)
			(xy 365.927132 -261.285228) (xy 365.927594 -261.295104) (xy 365.935044 -261.313397) (xy 365.94161 -261.320788)
			(xy 365.941864 -261.321042) (xy 366.166146 -261.545324) (xy 366.166654 -261.545832) (xy 366.174034 -261.552417)
			(xy 366.192333 -261.55987) (xy 366.202214 -261.56031) (xy 367.031778 -261.56031) (xy 367.041615 -261.560848)
			(xy 367.059773 -261.568438) (xy 367.067084 -261.575042) (xy 367.672366 -262.180324) (xy 367.672874 -262.180832)
			(xy 367.680255 -262.187413) (xy 367.698555 -262.194859) (xy 367.708434 -262.19531) (xy 369.98148 -262.19531)
			(xy 369.994127 -262.194641) (xy 370.016398 -262.182653) (xy 370.023898 -262.17245) (xy 370.069618 -262.103616)
			(xy 370.075999 -262.092686) (xy 370.078253 -262.067508) (xy 370.073936 -262.05561) (xy 370.062586 -262.027012)
			(xy 370.050303 -261.966735) (xy 370.049552 -261.935976) (xy 370.049552 -261.931404) (xy 370.050428 -261.906396)
			(xy 370.059325 -261.857158) (xy 370.076129 -261.810028) (xy 370.100393 -261.766269) (xy 370.131467 -261.727052)
			(xy 370.168519 -261.693426) (xy 370.210558 -261.66629) (xy 370.256458 -261.646372) (xy 370.304992 -261.634203)
			(xy 370.35486 -261.630111) (xy 370.404728 -261.634203) (xy 370.453262 -261.646372) (xy 370.499162 -261.66629)
			(xy 370.541201 -261.693426) (xy 370.578253 -261.727052) (xy 370.609327 -261.766269) (xy 370.633591 -261.810028)
			(xy 370.650395 -261.857158) (xy 370.659292 -261.906396) (xy 370.660168 -261.931404) (xy 370.660168 -261.934452)
			(xy 370.660168 -261.935976) (xy 371.92891 -261.935976) (xy 371.93287 -261.886922) (xy 371.944647 -261.839138)
			(xy 371.963938 -261.793862) (xy 371.990241 -261.752266) (xy 372.022876 -261.715429) (xy 372.060997 -261.684304)
			(xy 372.103618 -261.659697) (xy 372.149634 -261.642245) (xy 372.197853 -261.632401) (xy 372.247028 -261.63042)
			(xy 372.295883 -261.636352) (xy 372.343154 -261.650044) (xy 372.387616 -261.671142) (xy 372.428119 -261.699098)
			(xy 372.463612 -261.73319) (xy 372.493177 -261.772534) (xy 372.516048 -261.816111) (xy 372.531632 -261.862792)
			(xy 372.539527 -261.911369) (xy 372.540022 -261.935976) (xy 373.809018 -261.935976) (xy 373.812978 -261.886922)
			(xy 373.824755 -261.839138) (xy 373.844046 -261.793862) (xy 373.870349 -261.752266) (xy 373.902984 -261.715429)
			(xy 373.941105 -261.684304) (xy 373.983726 -261.659697) (xy 374.029742 -261.642245) (xy 374.077961 -261.632401)
			(xy 374.127136 -261.63042) (xy 374.175991 -261.636352) (xy 374.223262 -261.650044) (xy 374.267724 -261.671142)
			(xy 374.308227 -261.699098) (xy 374.34372 -261.73319) (xy 374.373285 -261.772534) (xy 374.396156 -261.816111)
			(xy 374.41174 -261.862792) (xy 374.419635 -261.911369) (xy 374.42013 -261.935976) (xy 375.678695 -261.935976)
			(xy 375.68279 -261.885248) (xy 375.694969 -261.835834) (xy 375.714917 -261.789014) (xy 375.742118 -261.746)
			(xy 375.775866 -261.707906) (xy 375.815288 -261.675719) (xy 375.859362 -261.650273) (xy 375.906948 -261.632226)
			(xy 375.956812 -261.622046) (xy 376.007664 -261.619997) (xy 376.058185 -261.626131) (xy 376.107069 -261.640291)
			(xy 376.153048 -261.662108) (xy 376.194932 -261.691018) (xy 376.231636 -261.726273) (xy 376.262209 -261.766959)
			(xy 376.28586 -261.812022) (xy 376.301976 -261.860296) (xy 376.31014 -261.91053) (xy 376.310652 -261.935976)
			(xy 376.628926 -261.935976) (xy 376.632886 -261.886922) (xy 376.644663 -261.839138) (xy 376.663954 -261.793862)
			(xy 376.690257 -261.752266) (xy 376.722892 -261.715429) (xy 376.761013 -261.684304) (xy 376.803634 -261.659697)
			(xy 376.84965 -261.642245) (xy 376.897869 -261.632401) (xy 376.947044 -261.63042) (xy 376.995899 -261.636352)
			(xy 377.04317 -261.650044) (xy 377.087632 -261.671142) (xy 377.128135 -261.699098) (xy 377.163628 -261.73319)
			(xy 377.193193 -261.772534) (xy 377.216064 -261.816111) (xy 377.231648 -261.862792) (xy 377.239543 -261.911369)
			(xy 377.240038 -261.935976) (xy 377.56898 -261.935976) (xy 377.57294 -261.886922) (xy 377.584717 -261.839138)
			(xy 377.604008 -261.793862) (xy 377.630311 -261.752266) (xy 377.662946 -261.715429) (xy 377.701067 -261.684304)
			(xy 377.743688 -261.659697) (xy 377.789704 -261.642245) (xy 377.837923 -261.632401) (xy 377.887098 -261.63042)
			(xy 377.935953 -261.636352) (xy 377.983224 -261.650044) (xy 378.027686 -261.671142) (xy 378.068189 -261.699098)
			(xy 378.103682 -261.73319) (xy 378.133247 -261.772534) (xy 378.156118 -261.816111) (xy 378.171702 -261.862792)
			(xy 378.179597 -261.911369) (xy 378.180092 -261.935976) (xy 378.509034 -261.935976) (xy 378.512994 -261.886922)
			(xy 378.524771 -261.839138) (xy 378.544062 -261.793862) (xy 378.570365 -261.752266) (xy 378.603 -261.715429)
			(xy 378.641121 -261.684304) (xy 378.683742 -261.659697) (xy 378.729758 -261.642245) (xy 378.777977 -261.632401)
			(xy 378.827152 -261.63042) (xy 378.876007 -261.636352) (xy 378.923278 -261.650044) (xy 378.96774 -261.671142)
			(xy 379.008243 -261.699098) (xy 379.043736 -261.73319) (xy 379.073301 -261.772534) (xy 379.096172 -261.816111)
			(xy 379.111756 -261.862792) (xy 379.119651 -261.911369) (xy 379.120146 -261.935976) (xy 379.438657 -261.935976)
			(xy 379.442752 -261.885248) (xy 379.454931 -261.835834) (xy 379.474879 -261.789014) (xy 379.50208 -261.746)
			(xy 379.535828 -261.707906) (xy 379.57525 -261.675719) (xy 379.619324 -261.650273) (xy 379.66691 -261.632226)
			(xy 379.716774 -261.622046) (xy 379.767626 -261.619997) (xy 379.818147 -261.626131) (xy 379.867031 -261.640291)
			(xy 379.91301 -261.662108) (xy 379.954894 -261.691018) (xy 379.991598 -261.726273) (xy 380.022171 -261.766959)
			(xy 380.045822 -261.812022) (xy 380.061938 -261.860296) (xy 380.070102 -261.91053) (xy 380.070614 -261.935976)
			(xy 380.388888 -261.935976) (xy 380.392848 -261.886922) (xy 380.404625 -261.839138) (xy 380.423916 -261.793862)
			(xy 380.450219 -261.752266) (xy 380.482854 -261.715429) (xy 380.520975 -261.684304) (xy 380.563596 -261.659697)
			(xy 380.609612 -261.642245) (xy 380.657831 -261.632401) (xy 380.707006 -261.63042) (xy 380.755861 -261.636352)
			(xy 380.803132 -261.650044) (xy 380.847594 -261.671142) (xy 380.888097 -261.699098) (xy 380.92359 -261.73319)
			(xy 380.953155 -261.772534) (xy 380.976026 -261.816111) (xy 380.99161 -261.862792) (xy 380.999505 -261.911369)
			(xy 381 -261.935976) (xy 381.328942 -261.935976) (xy 381.332902 -261.886922) (xy 381.344679 -261.839138)
			(xy 381.36397 -261.793862) (xy 381.390273 -261.752266) (xy 381.422908 -261.715429) (xy 381.461029 -261.684304)
			(xy 381.50365 -261.659697) (xy 381.549666 -261.642245) (xy 381.597885 -261.632401) (xy 381.64706 -261.63042)
			(xy 381.695915 -261.636352) (xy 381.743186 -261.650044) (xy 381.787648 -261.671142) (xy 381.828151 -261.699098)
			(xy 381.863644 -261.73319) (xy 381.893209 -261.772534) (xy 381.91608 -261.816111) (xy 381.931664 -261.862792)
			(xy 381.939559 -261.911369) (xy 381.940054 -261.935976) (xy 382.268996 -261.935976) (xy 382.272956 -261.886922)
			(xy 382.284733 -261.839138) (xy 382.304024 -261.793862) (xy 382.330327 -261.752266) (xy 382.362962 -261.715429)
			(xy 382.401083 -261.684304) (xy 382.443704 -261.659697) (xy 382.48972 -261.642245) (xy 382.537939 -261.632401)
			(xy 382.587114 -261.63042) (xy 382.635969 -261.636352) (xy 382.68324 -261.650044) (xy 382.727702 -261.671142)
			(xy 382.768205 -261.699098) (xy 382.803698 -261.73319) (xy 382.833263 -261.772534) (xy 382.856134 -261.816111)
			(xy 382.871718 -261.862792) (xy 382.879613 -261.911369) (xy 382.880108 -261.935976) (xy 383.20905 -261.935976)
			(xy 383.21301 -261.886922) (xy 383.224787 -261.839138) (xy 383.244078 -261.793862) (xy 383.270381 -261.752266)
			(xy 383.303016 -261.715429) (xy 383.341137 -261.684304) (xy 383.383758 -261.659697) (xy 383.429774 -261.642245)
			(xy 383.477993 -261.632401) (xy 383.527168 -261.63042) (xy 383.576023 -261.636352) (xy 383.623294 -261.650044)
			(xy 383.667756 -261.671142) (xy 383.708259 -261.699098) (xy 383.743752 -261.73319) (xy 383.773317 -261.772534)
			(xy 383.796188 -261.816111) (xy 383.811772 -261.862792) (xy 383.819667 -261.911369) (xy 383.820162 -261.935976)
			(xy 384.149104 -261.935976) (xy 384.153064 -261.886922) (xy 384.164841 -261.839138) (xy 384.184132 -261.793862)
			(xy 384.210435 -261.752266) (xy 384.24307 -261.715429) (xy 384.281191 -261.684304) (xy 384.323812 -261.659697)
			(xy 384.369828 -261.642245) (xy 384.418047 -261.632401) (xy 384.467222 -261.63042) (xy 384.516077 -261.636352)
			(xy 384.563348 -261.650044) (xy 384.60781 -261.671142) (xy 384.648313 -261.699098) (xy 384.683806 -261.73319)
			(xy 384.713371 -261.772534) (xy 384.736242 -261.816111) (xy 384.751826 -261.862792) (xy 384.759721 -261.911369)
			(xy 384.760216 -261.935976) (xy 385.088904 -261.935976) (xy 385.092864 -261.886922) (xy 385.104641 -261.839138)
			(xy 385.123932 -261.793862) (xy 385.150235 -261.752266) (xy 385.18287 -261.715429) (xy 385.220991 -261.684304)
			(xy 385.263612 -261.659697) (xy 385.309628 -261.642245) (xy 385.357847 -261.632401) (xy 385.407022 -261.63042)
			(xy 385.455877 -261.636352) (xy 385.503148 -261.650044) (xy 385.54761 -261.671142) (xy 385.588113 -261.699098)
			(xy 385.623606 -261.73319) (xy 385.653171 -261.772534) (xy 385.676042 -261.816111) (xy 385.691626 -261.862792)
			(xy 385.699521 -261.911369) (xy 385.700016 -261.935976) (xy 386.028958 -261.935976) (xy 386.032918 -261.886922)
			(xy 386.044695 -261.839138) (xy 386.063986 -261.793862) (xy 386.090289 -261.752266) (xy 386.122924 -261.715429)
			(xy 386.161045 -261.684304) (xy 386.203666 -261.659697) (xy 386.249682 -261.642245) (xy 386.297901 -261.632401)
			(xy 386.347076 -261.63042) (xy 386.395931 -261.636352) (xy 386.443202 -261.650044) (xy 386.487664 -261.671142)
			(xy 386.528167 -261.699098) (xy 386.56366 -261.73319) (xy 386.593225 -261.772534) (xy 386.616096 -261.816111)
			(xy 386.63168 -261.862792) (xy 386.639575 -261.911369) (xy 386.64007 -261.935976) (xy 386.969012 -261.935976)
			(xy 386.972972 -261.886922) (xy 386.984749 -261.839138) (xy 387.00404 -261.793862) (xy 387.030343 -261.752266)
			(xy 387.062978 -261.715429) (xy 387.101099 -261.684304) (xy 387.14372 -261.659697) (xy 387.189736 -261.642245)
			(xy 387.237955 -261.632401) (xy 387.28713 -261.63042) (xy 387.335985 -261.636352) (xy 387.383256 -261.650044)
			(xy 387.427718 -261.671142) (xy 387.468221 -261.699098) (xy 387.503714 -261.73319) (xy 387.533279 -261.772534)
			(xy 387.55615 -261.816111) (xy 387.571734 -261.862792) (xy 387.579629 -261.911369) (xy 387.580124 -261.935976)
			(xy 387.579629 -261.960583) (xy 387.571734 -262.00916) (xy 387.55615 -262.055841) (xy 387.533279 -262.099418)
			(xy 387.503714 -262.138762) (xy 387.468221 -262.172854) (xy 387.427718 -262.20081) (xy 387.383256 -262.221908)
			(xy 387.335985 -262.2356) (xy 387.28713 -262.241532) (xy 387.237955 -262.239551) (xy 387.189736 -262.229707)
			(xy 387.14372 -262.212255) (xy 387.101099 -262.187648) (xy 387.062978 -262.156523) (xy 387.030343 -262.119686)
			(xy 387.00404 -262.07809) (xy 386.984749 -262.032814) (xy 386.972972 -261.98503) (xy 386.969012 -261.935976)
			(xy 386.64007 -261.935976) (xy 386.639575 -261.960583) (xy 386.63168 -262.00916) (xy 386.616096 -262.055841)
			(xy 386.593225 -262.099418) (xy 386.56366 -262.138762) (xy 386.528167 -262.172854) (xy 386.487664 -262.20081)
			(xy 386.443202 -262.221908) (xy 386.395931 -262.2356) (xy 386.347076 -262.241532) (xy 386.297901 -262.239551)
			(xy 386.249682 -262.229707) (xy 386.203666 -262.212255) (xy 386.161045 -262.187648) (xy 386.122924 -262.156523)
			(xy 386.090289 -262.119686) (xy 386.063986 -262.07809) (xy 386.044695 -262.032814) (xy 386.032918 -261.98503)
			(xy 386.028958 -261.935976) (xy 385.700016 -261.935976) (xy 385.699521 -261.960583) (xy 385.691626 -262.00916)
			(xy 385.676042 -262.055841) (xy 385.653171 -262.099418) (xy 385.623606 -262.138762) (xy 385.588113 -262.172854)
			(xy 385.54761 -262.20081) (xy 385.503148 -262.221908) (xy 385.455877 -262.2356) (xy 385.407022 -262.241532)
			(xy 385.357847 -262.239551) (xy 385.309628 -262.229707) (xy 385.263612 -262.212255) (xy 385.220991 -262.187648)
			(xy 385.18287 -262.156523) (xy 385.150235 -262.119686) (xy 385.123932 -262.07809) (xy 385.104641 -262.032814)
			(xy 385.092864 -261.98503) (xy 385.088904 -261.935976) (xy 384.760216 -261.935976) (xy 384.759721 -261.960583)
			(xy 384.751826 -262.00916) (xy 384.736242 -262.055841) (xy 384.713371 -262.099418) (xy 384.683806 -262.138762)
			(xy 384.648313 -262.172854) (xy 384.60781 -262.20081) (xy 384.563348 -262.221908) (xy 384.516077 -262.2356)
			(xy 384.467222 -262.241532) (xy 384.418047 -262.239551) (xy 384.369828 -262.229707) (xy 384.323812 -262.212255)
			(xy 384.281191 -262.187648) (xy 384.24307 -262.156523) (xy 384.210435 -262.119686) (xy 384.184132 -262.07809)
			(xy 384.164841 -262.032814) (xy 384.153064 -261.98503) (xy 384.149104 -261.935976) (xy 383.820162 -261.935976)
			(xy 383.819667 -261.960583) (xy 383.811772 -262.00916) (xy 383.796188 -262.055841) (xy 383.773317 -262.099418)
			(xy 383.743752 -262.138762) (xy 383.708259 -262.172854) (xy 383.667756 -262.20081) (xy 383.623294 -262.221908)
			(xy 383.576023 -262.2356) (xy 383.527168 -262.241532) (xy 383.477993 -262.239551) (xy 383.429774 -262.229707)
			(xy 383.383758 -262.212255) (xy 383.341137 -262.187648) (xy 383.303016 -262.156523) (xy 383.270381 -262.119686)
			(xy 383.244078 -262.07809) (xy 383.224787 -262.032814) (xy 383.21301 -261.98503) (xy 383.20905 -261.935976)
			(xy 382.880108 -261.935976) (xy 382.879613 -261.960583) (xy 382.871718 -262.00916) (xy 382.856134 -262.055841)
			(xy 382.833263 -262.099418) (xy 382.803698 -262.138762) (xy 382.768205 -262.172854) (xy 382.727702 -262.20081)
			(xy 382.68324 -262.221908) (xy 382.635969 -262.2356) (xy 382.587114 -262.241532) (xy 382.537939 -262.239551)
			(xy 382.48972 -262.229707) (xy 382.443704 -262.212255) (xy 382.401083 -262.187648) (xy 382.362962 -262.156523)
			(xy 382.330327 -262.119686) (xy 382.304024 -262.07809) (xy 382.284733 -262.032814) (xy 382.272956 -261.98503)
			(xy 382.268996 -261.935976) (xy 381.940054 -261.935976) (xy 381.939559 -261.960583) (xy 381.931664 -262.00916)
			(xy 381.91608 -262.055841) (xy 381.893209 -262.099418) (xy 381.863644 -262.138762) (xy 381.828151 -262.172854)
			(xy 381.787648 -262.20081) (xy 381.743186 -262.221908) (xy 381.695915 -262.2356) (xy 381.64706 -262.241532)
			(xy 381.597885 -262.239551) (xy 381.549666 -262.229707) (xy 381.50365 -262.212255) (xy 381.461029 -262.187648)
			(xy 381.422908 -262.156523) (xy 381.390273 -262.119686) (xy 381.36397 -262.07809) (xy 381.344679 -262.032814)
			(xy 381.332902 -261.98503) (xy 381.328942 -261.935976) (xy 381 -261.935976) (xy 380.999505 -261.960583)
			(xy 380.99161 -262.00916) (xy 380.976026 -262.055841) (xy 380.953155 -262.099418) (xy 380.92359 -262.138762)
			(xy 380.888097 -262.172854) (xy 380.847594 -262.20081) (xy 380.803132 -262.221908) (xy 380.755861 -262.2356)
			(xy 380.707006 -262.241532) (xy 380.657831 -262.239551) (xy 380.609612 -262.229707) (xy 380.563596 -262.212255)
			(xy 380.520975 -262.187648) (xy 380.482854 -262.156523) (xy 380.450219 -262.119686) (xy 380.423916 -262.07809)
			(xy 380.404625 -262.032814) (xy 380.392848 -261.98503) (xy 380.388888 -261.935976) (xy 380.070614 -261.935976)
			(xy 380.070102 -261.961422) (xy 380.061938 -262.011656) (xy 380.045822 -262.05993) (xy 380.022171 -262.104993)
			(xy 379.991598 -262.145679) (xy 379.954894 -262.180934) (xy 379.91301 -262.209844) (xy 379.867031 -262.231661)
			(xy 379.818147 -262.245821) (xy 379.767626 -262.251955) (xy 379.716774 -262.249906) (xy 379.66691 -262.239726)
			(xy 379.619324 -262.221679) (xy 379.57525 -262.196233) (xy 379.535828 -262.164046) (xy 379.50208 -262.125952)
			(xy 379.474879 -262.082938) (xy 379.454931 -262.036118) (xy 379.442752 -261.986704) (xy 379.438657 -261.935976)
			(xy 379.120146 -261.935976) (xy 379.119651 -261.960583) (xy 379.111756 -262.00916) (xy 379.096172 -262.055841)
			(xy 379.073301 -262.099418) (xy 379.043736 -262.138762) (xy 379.008243 -262.172854) (xy 378.96774 -262.20081)
			(xy 378.923278 -262.221908) (xy 378.876007 -262.2356) (xy 378.827152 -262.241532) (xy 378.777977 -262.239551)
			(xy 378.729758 -262.229707) (xy 378.683742 -262.212255) (xy 378.641121 -262.187648) (xy 378.603 -262.156523)
			(xy 378.570365 -262.119686) (xy 378.544062 -262.07809) (xy 378.524771 -262.032814) (xy 378.512994 -261.98503)
			(xy 378.509034 -261.935976) (xy 378.180092 -261.935976) (xy 378.179597 -261.960583) (xy 378.171702 -262.00916)
			(xy 378.156118 -262.055841) (xy 378.133247 -262.099418) (xy 378.103682 -262.138762) (xy 378.068189 -262.172854)
			(xy 378.027686 -262.20081) (xy 377.983224 -262.221908) (xy 377.935953 -262.2356) (xy 377.887098 -262.241532)
			(xy 377.837923 -262.239551) (xy 377.789704 -262.229707) (xy 377.743688 -262.212255) (xy 377.701067 -262.187648)
			(xy 377.662946 -262.156523) (xy 377.630311 -262.119686) (xy 377.604008 -262.07809) (xy 377.584717 -262.032814)
			(xy 377.57294 -261.98503) (xy 377.56898 -261.935976) (xy 377.240038 -261.935976) (xy 377.239543 -261.960583)
			(xy 377.231648 -262.00916) (xy 377.216064 -262.055841) (xy 377.193193 -262.099418) (xy 377.163628 -262.138762)
			(xy 377.128135 -262.172854) (xy 377.087632 -262.20081) (xy 377.04317 -262.221908) (xy 376.995899 -262.2356)
			(xy 376.947044 -262.241532) (xy 376.897869 -262.239551) (xy 376.84965 -262.229707) (xy 376.803634 -262.212255)
			(xy 376.761013 -262.187648) (xy 376.722892 -262.156523) (xy 376.690257 -262.119686) (xy 376.663954 -262.07809)
			(xy 376.644663 -262.032814) (xy 376.632886 -261.98503) (xy 376.628926 -261.935976) (xy 376.310652 -261.935976)
			(xy 376.31014 -261.961422) (xy 376.301976 -262.011656) (xy 376.28586 -262.05993) (xy 376.262209 -262.104993)
			(xy 376.231636 -262.145679) (xy 376.194932 -262.180934) (xy 376.153048 -262.209844) (xy 376.107069 -262.231661)
			(xy 376.058185 -262.245821) (xy 376.007664 -262.251955) (xy 375.956812 -262.249906) (xy 375.906948 -262.239726)
			(xy 375.859362 -262.221679) (xy 375.815288 -262.196233) (xy 375.775866 -262.164046) (xy 375.742118 -262.125952)
			(xy 375.714917 -262.082938) (xy 375.694969 -262.036118) (xy 375.68279 -261.986704) (xy 375.678695 -261.935976)
			(xy 374.42013 -261.935976) (xy 374.419635 -261.960583) (xy 374.41174 -262.00916) (xy 374.396156 -262.055841)
			(xy 374.373285 -262.099418) (xy 374.34372 -262.138762) (xy 374.308227 -262.172854) (xy 374.267724 -262.20081)
			(xy 374.223262 -262.221908) (xy 374.175991 -262.2356) (xy 374.127136 -262.241532) (xy 374.077961 -262.239551)
			(xy 374.029742 -262.229707) (xy 373.983726 -262.212255) (xy 373.941105 -262.187648) (xy 373.902984 -262.156523)
			(xy 373.870349 -262.119686) (xy 373.844046 -262.07809) (xy 373.824755 -262.032814) (xy 373.812978 -261.98503)
			(xy 373.809018 -261.935976) (xy 372.540022 -261.935976) (xy 372.539527 -261.960583) (xy 372.531632 -262.00916)
			(xy 372.516048 -262.055841) (xy 372.493177 -262.099418) (xy 372.463612 -262.138762) (xy 372.428119 -262.172854)
			(xy 372.387616 -262.20081) (xy 372.343154 -262.221908) (xy 372.295883 -262.2356) (xy 372.247028 -262.241532)
			(xy 372.197853 -262.239551) (xy 372.149634 -262.229707) (xy 372.103618 -262.212255) (xy 372.060997 -262.187648)
			(xy 372.022876 -262.156523) (xy 371.990241 -262.119686) (xy 371.963938 -262.07809) (xy 371.944647 -262.032814)
			(xy 371.93287 -261.98503) (xy 371.92891 -261.935976) (xy 370.660168 -261.935976) (xy 370.659404 -261.966733)
			(xy 370.64712 -262.027008) (xy 370.635784 -262.05561) (xy 370.631413 -262.067498) (xy 370.633693 -262.092689)
			(xy 370.640102 -262.103616) (xy 370.685822 -262.17245) (xy 370.693335 -262.182646) (xy 370.715594 -262.194661)
			(xy 370.72824 -262.19531) (xy 371.349778 -262.19531) (xy 371.359615 -262.195848) (xy 371.377773 -262.203438)
			(xy 371.385084 -262.210042) (xy 371.618256 -262.443214) (xy 371.625171 -262.449639) (xy 371.642403 -262.457311)
			(xy 371.661244 -262.458237) (xy 371.670326 -262.45566) (xy 371.692951 -262.448765) (xy 371.739644 -262.441241)
			(xy 371.76329 -262.440674) (xy 371.76837 -262.440674) (xy 371.792001 -262.441393) (xy 371.838623 -262.449225)
			(xy 371.883481 -262.464149) (xy 371.925502 -262.485808) (xy 371.963684 -262.513685) (xy 371.997113 -262.547113)
			(xy 372.02499 -262.585294) (xy 372.04665 -262.627316) (xy 372.061574 -262.672173) (xy 372.069406 -262.718795)
			(xy 372.070122 -262.742426) (xy 372.070122 -262.746236) (xy 372.069635 -262.770201) (xy 372.062111 -262.817538)
			(xy 372.055136 -262.84047) (xy 372.052515 -262.849546) (xy 372.053442 -262.8684) (xy 372.061131 -262.885641)
			(xy 372.067582 -262.89254) (xy 372.244366 -263.069324) (xy 372.244874 -263.069832) (xy 372.252255 -263.076413)
			(xy 372.270555 -263.083859) (xy 372.280434 -263.08431) (xy 373.3165 -263.08431) (xy 373.325526 -263.083996)
			(xy 373.342479 -263.077804) (xy 373.356209 -263.06609) (xy 373.36095 -263.058402) (xy 373.361458 -263.057386)
			(xy 373.408194 -262.96493) (xy 373.405908 -262.936736) (xy 373.397526 -262.925052) (xy 373.383891 -262.905386)
			(xy 373.362256 -262.862705) (xy 373.347533 -262.817175) (xy 373.340082 -262.769908) (xy 373.339614 -262.745982)
			(xy 373.339614 -262.73887) (xy 373.340684 -262.714) (xy 373.349898 -262.665083) (xy 373.366924 -262.618308)
			(xy 373.39131 -262.574914) (xy 373.42241 -262.536049) (xy 373.459402 -262.502742) (xy 373.501306 -262.475875)
			(xy 373.547012 -262.456159) (xy 373.59531 -262.444117) (xy 373.644922 -262.440068) (xy 373.694534 -262.444117)
			(xy 373.742832 -262.456159) (xy 373.788538 -262.475875) (xy 373.830442 -262.502742) (xy 373.867434 -262.536049)
			(xy 373.898534 -262.574914) (xy 373.92292 -262.618308) (xy 373.939946 -262.665083) (xy 373.94916 -262.714)
			(xy 373.95023 -262.73887) (xy 373.95023 -262.744204) (xy 373.95023 -262.745982) (xy 373.949787 -262.76991)
			(xy 373.942355 -262.817185) (xy 373.927625 -262.862717) (xy 373.905959 -262.905387) (xy 373.892318 -262.925052)
			(xy 373.883936 -262.936736) (xy 373.88165 -262.96493) (xy 373.927878 -263.05637) (xy 373.928894 -263.058402)
			(xy 373.933641 -263.066079) (xy 373.947391 -263.077752) (xy 373.964325 -263.083963) (xy 373.973344 -263.08431)
			(xy 374.789192 -263.08431) (xy 374.809766 -263.07542) (xy 374.814393 -263.073644) (xy 374.824115 -263.071719)
			(xy 374.82907 -263.07161) (xy 374.829324 -263.07161) (xy 375.187464 -263.07161) (xy 375.196667 -263.071215)
			(xy 375.213898 -263.064739) (xy 375.227764 -263.052631) (xy 375.232422 -263.044686) (xy 375.27357 -262.967724)
			(xy 375.277527 -262.959463) (xy 375.279908 -262.941314) (xy 375.275787 -262.92348) (xy 375.27103 -262.915654)
			(xy 375.270776 -262.9154) (xy 375.258642 -262.896494) (xy 375.239458 -262.855874) (xy 375.226435 -262.812881)
			(xy 375.219853 -262.768443) (xy 375.219468 -262.745982) (xy 375.219468 -262.738616) (xy 375.220474 -262.715004)
			(xy 375.228871 -262.668497) (xy 375.244335 -262.62384) (xy 375.266498 -262.582101) (xy 375.294829 -262.544276)
			(xy 375.328652 -262.51127) (xy 375.367158 -262.483871) (xy 375.409427 -262.462736) (xy 375.454448 -262.448367)
			(xy 375.501146 -262.44111) (xy 375.524776 -262.440674) (xy 375.548412 -262.441122) (xy 375.595117 -262.448417)
			(xy 375.640141 -262.462821) (xy 375.682407 -262.483989) (xy 375.720908 -262.511417) (xy 375.754723 -262.54445)
			(xy 375.783045 -262.582297) (xy 375.805198 -262.624057) (xy 375.820652 -262.668731) (xy 375.829039 -262.715252)
			(xy 375.830084 -262.73887) (xy 375.830084 -262.745982) (xy 375.829687 -262.768443) (xy 375.823109 -262.812881)
			(xy 375.810092 -262.855875) (xy 375.790916 -262.896499) (xy 375.778776 -262.9154) (xy 375.778522 -262.915654)
			(xy 375.77377 -262.923485) (xy 375.76963 -262.941315) (xy 375.772023 -262.959463) (xy 375.775982 -262.967724)
			(xy 375.81713 -263.044686) (xy 375.821786 -263.052644) (xy 375.835619 -263.064811) (xy 375.852875 -263.071264)
			(xy 375.862088 -263.07161) (xy 376.127518 -263.07161) (xy 376.136716 -263.071207) (xy 376.153933 -263.064718)
			(xy 376.167783 -263.052607) (xy 376.172476 -263.044686) (xy 376.21464 -262.965184) (xy 376.213116 -262.93699)
			(xy 376.204988 -262.925052) (xy 376.191817 -262.905201) (xy 376.170956 -262.862371) (xy 376.156766 -262.816894)
			(xy 376.149568 -262.769801) (xy 376.149108 -262.745982) (xy 376.149595 -262.721172) (xy 376.157357 -262.672164)
			(xy 376.17269 -262.624974) (xy 376.195217 -262.580763) (xy 376.224382 -262.54062) (xy 376.259468 -262.505534)
			(xy 376.299611 -262.476369) (xy 376.343822 -262.453842) (xy 376.391012 -262.438509) (xy 376.44002 -262.430747)
			(xy 376.48964 -262.430747) (xy 376.538648 -262.438509) (xy 376.585838 -262.453842) (xy 376.630049 -262.476369)
			(xy 376.670192 -262.505534) (xy 376.705278 -262.54062) (xy 376.734443 -262.580763) (xy 376.75697 -262.624974)
			(xy 376.772303 -262.672164) (xy 376.780065 -262.721172) (xy 376.780552 -262.745982) (xy 376.780097 -262.769801)
			(xy 376.772896 -262.816893) (xy 376.7587 -262.862368) (xy 376.737832 -262.905193) (xy 376.724672 -262.925052)
			(xy 376.716544 -262.93699) (xy 376.714766 -262.965184) (xy 376.757184 -263.044686) (xy 376.761838 -263.052649)
			(xy 376.775669 -263.064829) (xy 376.792926 -263.071297) (xy 376.802142 -263.07161) (xy 377.067572 -263.07161)
			(xy 377.076775 -263.071214) (xy 377.094004 -263.064736) (xy 377.107867 -263.052627) (xy 377.11253 -263.044686)
			(xy 377.154694 -262.965184) (xy 377.15317 -262.93699) (xy 377.145042 -262.925052) (xy 377.131902 -262.90519)
			(xy 377.111106 -262.862351) (xy 377.096974 -262.816875) (xy 377.089829 -262.769793) (xy 377.089416 -262.745982)
			(xy 377.089902 -262.721192) (xy 377.097658 -262.672224) (xy 377.112979 -262.625071) (xy 377.135488 -262.580896)
			(xy 377.16463 -262.540785) (xy 377.199687 -262.505728) (xy 377.239798 -262.476586) (xy 377.283973 -262.454077)
			(xy 377.331126 -262.438756) (xy 377.380094 -262.431) (xy 377.429674 -262.431) (xy 377.478642 -262.438756)
			(xy 377.525795 -262.454077) (xy 377.56997 -262.476586) (xy 377.610081 -262.505728) (xy 377.645138 -262.540785)
			(xy 377.67428 -262.580896) (xy 377.696789 -262.625071) (xy 377.71211 -262.672224) (xy 377.719866 -262.721192)
			(xy 377.720352 -262.745982) (xy 377.719939 -262.769794) (xy 377.712817 -262.816881) (xy 377.698687 -262.86236)
			(xy 377.677871 -262.905192) (xy 377.664726 -262.925052) (xy 377.656598 -262.93699) (xy 377.65482 -262.965184)
			(xy 377.697238 -263.044686) (xy 377.701895 -263.052643) (xy 377.715728 -263.064808) (xy 377.732983 -263.071258)
			(xy 377.742196 -263.07161) (xy 378.007626 -263.07161) (xy 378.016824 -263.071205) (xy 378.034038 -263.064715)
			(xy 378.047886 -263.052604) (xy 378.052584 -263.044686) (xy 378.093732 -262.967724) (xy 378.097691 -262.959463)
			(xy 378.100074 -262.941315) (xy 378.09595 -262.92348) (xy 378.091192 -262.915654) (xy 378.090938 -262.9154)
			(xy 378.078802 -262.896495) (xy 378.059614 -262.855876) (xy 378.046588 -262.812882) (xy 378.040005 -262.768444)
			(xy 378.03963 -262.745982) (xy 378.03963 -262.738616) (xy 378.040636 -262.715003) (xy 378.049032 -262.668494)
			(xy 378.064496 -262.623834) (xy 378.086658 -262.582092) (xy 378.114989 -262.544264) (xy 378.148811 -262.511254)
			(xy 378.187317 -262.483852) (xy 378.229586 -262.462711) (xy 378.274608 -262.448338) (xy 378.321307 -262.441075)
			(xy 378.344938 -262.440674) (xy 378.368576 -262.44112) (xy 378.415285 -262.44841) (xy 378.460314 -262.46281)
			(xy 378.502586 -262.483976) (xy 378.541092 -262.511404) (xy 378.574912 -262.544436) (xy 378.603238 -262.582286)
			(xy 378.625394 -262.624047) (xy 378.64085 -262.668725) (xy 378.649238 -262.71525) (xy 378.650246 -262.73887)
			(xy 378.650246 -262.745982) (xy 378.64985 -262.768443) (xy 378.643272 -262.812882) (xy 378.630257 -262.855877)
			(xy 378.611085 -262.896503) (xy 378.598938 -262.9154) (xy 378.598684 -262.915654) (xy 378.593935 -262.923486)
			(xy 378.589799 -262.941315) (xy 378.592189 -262.959462) (xy 378.596144 -262.967724) (xy 378.637292 -263.044686)
			(xy 378.641946 -263.052648) (xy 378.655778 -263.064826) (xy 378.673034 -263.071292) (xy 378.68225 -263.07161)
			(xy 378.947426 -263.07161) (xy 378.956624 -263.071205) (xy 378.973838 -263.064715) (xy 378.987686 -263.052604)
			(xy 378.992384 -263.044686) (xy 379.034548 -262.965184) (xy 379.033024 -262.93699) (xy 379.024896 -262.925052)
			(xy 379.011724 -262.905201) (xy 378.990864 -262.862371) (xy 378.976673 -262.816894) (xy 378.969475 -262.769801)
			(xy 378.969016 -262.745982) (xy 378.969503 -262.721172) (xy 378.977265 -262.672164) (xy 378.992598 -262.624974)
			(xy 379.015125 -262.580763) (xy 379.04429 -262.54062) (xy 379.079376 -262.505534) (xy 379.119519 -262.476369)
			(xy 379.16373 -262.453842) (xy 379.21092 -262.438509) (xy 379.259928 -262.430747) (xy 379.309548 -262.430747)
			(xy 379.358556 -262.438509) (xy 379.405746 -262.453842) (xy 379.449957 -262.476369) (xy 379.4901 -262.505534)
			(xy 379.525186 -262.54062) (xy 379.554351 -262.580763) (xy 379.576878 -262.624974) (xy 379.592211 -262.672164)
			(xy 379.599973 -262.721172) (xy 379.60046 -262.745982) (xy 379.918988 -262.745982) (xy 379.922948 -262.696928)
			(xy 379.934725 -262.649144) (xy 379.954016 -262.603868) (xy 379.980319 -262.562272) (xy 380.012954 -262.525435)
			(xy 380.051075 -262.49431) (xy 380.093696 -262.469703) (xy 380.139712 -262.452251) (xy 380.187931 -262.442407)
			(xy 380.237106 -262.440426) (xy 380.285961 -262.446358) (xy 380.333232 -262.46005) (xy 380.377694 -262.481148)
			(xy 380.418197 -262.509104) (xy 380.45369 -262.543196) (xy 380.483255 -262.58254) (xy 380.506126 -262.626117)
			(xy 380.52171 -262.672798) (xy 380.529605 -262.721375) (xy 380.5301 -262.745982) (xy 380.848611 -262.745982)
			(xy 380.852706 -262.695254) (xy 380.864885 -262.64584) (xy 380.884833 -262.59902) (xy 380.912034 -262.556006)
			(xy 380.945782 -262.517912) (xy 380.985204 -262.485725) (xy 381.029278 -262.460279) (xy 381.076864 -262.442232)
			(xy 381.126728 -262.432052) (xy 381.17758 -262.430003) (xy 381.228101 -262.436137) (xy 381.276985 -262.450297)
			(xy 381.322964 -262.472114) (xy 381.364848 -262.501024) (xy 381.401552 -262.536279) (xy 381.432125 -262.576965)
			(xy 381.455776 -262.622028) (xy 381.471892 -262.670302) (xy 381.480056 -262.720536) (xy 381.480568 -262.745982)
			(xy 381.799096 -262.745982) (xy 381.803056 -262.696928) (xy 381.814833 -262.649144) (xy 381.834124 -262.603868)
			(xy 381.860427 -262.562272) (xy 381.893062 -262.525435) (xy 381.931183 -262.49431) (xy 381.973804 -262.469703)
			(xy 382.01982 -262.452251) (xy 382.068039 -262.442407) (xy 382.117214 -262.440426) (xy 382.166069 -262.446358)
			(xy 382.21334 -262.46005) (xy 382.257802 -262.481148) (xy 382.298305 -262.509104) (xy 382.333798 -262.543196)
			(xy 382.363363 -262.58254) (xy 382.386234 -262.626117) (xy 382.401818 -262.672798) (xy 382.409713 -262.721375)
			(xy 382.410208 -262.745982) (xy 382.738896 -262.745982) (xy 382.742856 -262.696928) (xy 382.754633 -262.649144)
			(xy 382.773924 -262.603868) (xy 382.800227 -262.562272) (xy 382.832862 -262.525435) (xy 382.870983 -262.49431)
			(xy 382.913604 -262.469703) (xy 382.95962 -262.452251) (xy 383.007839 -262.442407) (xy 383.057014 -262.440426)
			(xy 383.105869 -262.446358) (xy 383.15314 -262.46005) (xy 383.197602 -262.481148) (xy 383.238105 -262.509104)
			(xy 383.273598 -262.543196) (xy 383.303163 -262.58254) (xy 383.326034 -262.626117) (xy 383.341618 -262.672798)
			(xy 383.349513 -262.721375) (xy 383.350008 -262.745982) (xy 383.67895 -262.745982) (xy 383.68291 -262.696928)
			(xy 383.694687 -262.649144) (xy 383.713978 -262.603868) (xy 383.740281 -262.562272) (xy 383.772916 -262.525435)
			(xy 383.811037 -262.49431) (xy 383.853658 -262.469703) (xy 383.899674 -262.452251) (xy 383.947893 -262.442407)
			(xy 383.997068 -262.440426) (xy 384.045923 -262.446358) (xy 384.093194 -262.46005) (xy 384.137656 -262.481148)
			(xy 384.178159 -262.509104) (xy 384.213652 -262.543196) (xy 384.243217 -262.58254) (xy 384.266088 -262.626117)
			(xy 384.281672 -262.672798) (xy 384.289567 -262.721375) (xy 384.290062 -262.745982) (xy 384.619004 -262.745982)
			(xy 384.622964 -262.696928) (xy 384.634741 -262.649144) (xy 384.654032 -262.603868) (xy 384.680335 -262.562272)
			(xy 384.71297 -262.525435) (xy 384.751091 -262.49431) (xy 384.793712 -262.469703) (xy 384.839728 -262.452251)
			(xy 384.887947 -262.442407) (xy 384.937122 -262.440426) (xy 384.985977 -262.446358) (xy 385.033248 -262.46005)
			(xy 385.07771 -262.481148) (xy 385.118213 -262.509104) (xy 385.153706 -262.543196) (xy 385.183271 -262.58254)
			(xy 385.206142 -262.626117) (xy 385.221726 -262.672798) (xy 385.229621 -262.721375) (xy 385.230116 -262.745982)
			(xy 385.559058 -262.745982) (xy 385.563018 -262.696928) (xy 385.574795 -262.649144) (xy 385.594086 -262.603868)
			(xy 385.620389 -262.562272) (xy 385.653024 -262.525435) (xy 385.691145 -262.49431) (xy 385.733766 -262.469703)
			(xy 385.779782 -262.452251) (xy 385.828001 -262.442407) (xy 385.877176 -262.440426) (xy 385.926031 -262.446358)
			(xy 385.973302 -262.46005) (xy 386.017764 -262.481148) (xy 386.058267 -262.509104) (xy 386.09376 -262.543196)
			(xy 386.123325 -262.58254) (xy 386.146196 -262.626117) (xy 386.16178 -262.672798) (xy 386.169675 -262.721375)
			(xy 386.17017 -262.745982) (xy 386.499112 -262.745982) (xy 386.503072 -262.696928) (xy 386.514849 -262.649144)
			(xy 386.53414 -262.603868) (xy 386.560443 -262.562272) (xy 386.593078 -262.525435) (xy 386.631199 -262.49431)
			(xy 386.67382 -262.469703) (xy 386.719836 -262.452251) (xy 386.768055 -262.442407) (xy 386.81723 -262.440426)
			(xy 386.866085 -262.446358) (xy 386.913356 -262.46005) (xy 386.957818 -262.481148) (xy 386.998321 -262.509104)
			(xy 387.033814 -262.543196) (xy 387.063379 -262.58254) (xy 387.08625 -262.626117) (xy 387.101834 -262.672798)
			(xy 387.109729 -262.721375) (xy 387.110224 -262.745982) (xy 387.438912 -262.745982) (xy 387.442872 -262.696928)
			(xy 387.454649 -262.649144) (xy 387.47394 -262.603868) (xy 387.500243 -262.562272) (xy 387.532878 -262.525435)
			(xy 387.570999 -262.49431) (xy 387.61362 -262.469703) (xy 387.659636 -262.452251) (xy 387.707855 -262.442407)
			(xy 387.75703 -262.440426) (xy 387.805885 -262.446358) (xy 387.853156 -262.46005) (xy 387.897618 -262.481148)
			(xy 387.938121 -262.509104) (xy 387.973614 -262.543196) (xy 388.003179 -262.58254) (xy 388.02605 -262.626117)
			(xy 388.041634 -262.672798) (xy 388.049529 -262.721375) (xy 388.050024 -262.745982) (xy 388.049529 -262.770589)
			(xy 388.041634 -262.819166) (xy 388.02605 -262.865847) (xy 388.003179 -262.909424) (xy 387.973614 -262.948768)
			(xy 387.938121 -262.98286) (xy 387.897618 -263.010816) (xy 387.853156 -263.031914) (xy 387.805885 -263.045606)
			(xy 387.75703 -263.051538) (xy 387.707855 -263.049557) (xy 387.659636 -263.039713) (xy 387.61362 -263.022261)
			(xy 387.570999 -262.997654) (xy 387.532878 -262.966529) (xy 387.500243 -262.929692) (xy 387.47394 -262.888096)
			(xy 387.454649 -262.84282) (xy 387.442872 -262.795036) (xy 387.438912 -262.745982) (xy 387.110224 -262.745982)
			(xy 387.109729 -262.770589) (xy 387.101834 -262.819166) (xy 387.08625 -262.865847) (xy 387.063379 -262.909424)
			(xy 387.033814 -262.948768) (xy 386.998321 -262.98286) (xy 386.957818 -263.010816) (xy 386.913356 -263.031914)
			(xy 386.866085 -263.045606) (xy 386.81723 -263.051538) (xy 386.768055 -263.049557) (xy 386.719836 -263.039713)
			(xy 386.67382 -263.022261) (xy 386.631199 -262.997654) (xy 386.593078 -262.966529) (xy 386.560443 -262.929692)
			(xy 386.53414 -262.888096) (xy 386.514849 -262.84282) (xy 386.503072 -262.795036) (xy 386.499112 -262.745982)
			(xy 386.17017 -262.745982) (xy 386.169675 -262.770589) (xy 386.16178 -262.819166) (xy 386.146196 -262.865847)
			(xy 386.123325 -262.909424) (xy 386.09376 -262.948768) (xy 386.058267 -262.98286) (xy 386.017764 -263.010816)
			(xy 385.973302 -263.031914) (xy 385.926031 -263.045606) (xy 385.877176 -263.051538) (xy 385.828001 -263.049557)
			(xy 385.779782 -263.039713) (xy 385.733766 -263.022261) (xy 385.691145 -262.997654) (xy 385.653024 -262.966529)
			(xy 385.620389 -262.929692) (xy 385.594086 -262.888096) (xy 385.574795 -262.84282) (xy 385.563018 -262.795036)
			(xy 385.559058 -262.745982) (xy 385.230116 -262.745982) (xy 385.229621 -262.770589) (xy 385.221726 -262.819166)
			(xy 385.206142 -262.865847) (xy 385.183271 -262.909424) (xy 385.153706 -262.948768) (xy 385.118213 -262.98286)
			(xy 385.07771 -263.010816) (xy 385.033248 -263.031914) (xy 384.985977 -263.045606) (xy 384.937122 -263.051538)
			(xy 384.887947 -263.049557) (xy 384.839728 -263.039713) (xy 384.793712 -263.022261) (xy 384.751091 -262.997654)
			(xy 384.71297 -262.966529) (xy 384.680335 -262.929692) (xy 384.654032 -262.888096) (xy 384.634741 -262.84282)
			(xy 384.622964 -262.795036) (xy 384.619004 -262.745982) (xy 384.290062 -262.745982) (xy 384.289567 -262.770589)
			(xy 384.281672 -262.819166) (xy 384.266088 -262.865847) (xy 384.243217 -262.909424) (xy 384.213652 -262.948768)
			(xy 384.178159 -262.98286) (xy 384.137656 -263.010816) (xy 384.093194 -263.031914) (xy 384.045923 -263.045606)
			(xy 383.997068 -263.051538) (xy 383.947893 -263.049557) (xy 383.899674 -263.039713) (xy 383.853658 -263.022261)
			(xy 383.811037 -262.997654) (xy 383.772916 -262.966529) (xy 383.740281 -262.929692) (xy 383.713978 -262.888096)
			(xy 383.694687 -262.84282) (xy 383.68291 -262.795036) (xy 383.67895 -262.745982) (xy 383.350008 -262.745982)
			(xy 383.349513 -262.770589) (xy 383.341618 -262.819166) (xy 383.326034 -262.865847) (xy 383.303163 -262.909424)
			(xy 383.273598 -262.948768) (xy 383.238105 -262.98286) (xy 383.197602 -263.010816) (xy 383.15314 -263.031914)
			(xy 383.105869 -263.045606) (xy 383.057014 -263.051538) (xy 383.007839 -263.049557) (xy 382.95962 -263.039713)
			(xy 382.913604 -263.022261) (xy 382.870983 -262.997654) (xy 382.832862 -262.966529) (xy 382.800227 -262.929692)
			(xy 382.773924 -262.888096) (xy 382.754633 -262.84282) (xy 382.742856 -262.795036) (xy 382.738896 -262.745982)
			(xy 382.410208 -262.745982) (xy 382.409713 -262.770589) (xy 382.401818 -262.819166) (xy 382.386234 -262.865847)
			(xy 382.363363 -262.909424) (xy 382.333798 -262.948768) (xy 382.298305 -262.98286) (xy 382.257802 -263.010816)
			(xy 382.21334 -263.031914) (xy 382.166069 -263.045606) (xy 382.117214 -263.051538) (xy 382.068039 -263.049557)
			(xy 382.01982 -263.039713) (xy 381.973804 -263.022261) (xy 381.931183 -262.997654) (xy 381.893062 -262.966529)
			(xy 381.860427 -262.929692) (xy 381.834124 -262.888096) (xy 381.814833 -262.84282) (xy 381.803056 -262.795036)
			(xy 381.799096 -262.745982) (xy 381.480568 -262.745982) (xy 381.480056 -262.771428) (xy 381.471892 -262.821662)
			(xy 381.455776 -262.869936) (xy 381.432125 -262.914999) (xy 381.401552 -262.955685) (xy 381.364848 -262.99094)
			(xy 381.322964 -263.01985) (xy 381.276985 -263.041667) (xy 381.228101 -263.055827) (xy 381.17758 -263.061961)
			(xy 381.126728 -263.059912) (xy 381.076864 -263.049732) (xy 381.029278 -263.031685) (xy 380.985204 -263.006239)
			(xy 380.945782 -262.974052) (xy 380.912034 -262.935958) (xy 380.884833 -262.892944) (xy 380.864885 -262.846124)
			(xy 380.852706 -262.79671) (xy 380.848611 -262.745982) (xy 380.5301 -262.745982) (xy 380.529605 -262.770589)
			(xy 380.52171 -262.819166) (xy 380.506126 -262.865847) (xy 380.483255 -262.909424) (xy 380.45369 -262.948768)
			(xy 380.418197 -262.98286) (xy 380.377694 -263.010816) (xy 380.333232 -263.031914) (xy 380.285961 -263.045606)
			(xy 380.237106 -263.051538) (xy 380.187931 -263.049557) (xy 380.139712 -263.039713) (xy 380.093696 -263.022261)
			(xy 380.051075 -262.997654) (xy 380.012954 -262.966529) (xy 379.980319 -262.929692) (xy 379.954016 -262.888096)
			(xy 379.934725 -262.84282) (xy 379.922948 -262.795036) (xy 379.918988 -262.745982) (xy 379.60046 -262.745982)
			(xy 379.600035 -262.769688) (xy 379.592945 -262.816567) (xy 379.578921 -262.861857) (xy 379.55828 -262.90454)
			(xy 379.531485 -262.943654) (xy 379.49914 -262.97832) (xy 379.480826 -262.993378) (xy 379.471936 -263.000236)
			(xy 379.46203 -263.01954) (xy 379.458982 -263.090152) (xy 379.459025 -263.10072) (xy 379.466631 -263.120411)
			(xy 379.473714 -263.128252) (xy 379.598174 -263.252712) (xy 379.603385 -263.257625) (xy 379.615888 -263.2646)
			(xy 379.622812 -263.266428) (xy 379.62713 -263.267444) (xy 379.64734 -263.258924) (xy 379.689523 -263.246921)
			(xy 379.732963 -263.240874) (xy 379.754892 -263.24052) (xy 379.779682 -263.241005) (xy 379.828653 -263.24876)
			(xy 379.875807 -263.26408) (xy 379.919985 -263.286588) (xy 379.960097 -263.31573) (xy 379.995157 -263.350787)
			(xy 380.024301 -263.390898) (xy 380.046812 -263.435074) (xy 380.062135 -263.482228) (xy 380.069893 -263.531198)
			(xy 380.07036 -263.555988) (xy 380.069815 -263.583618) (xy 380.060242 -263.638041) (xy 380.05131 -263.664192)
			(xy 380.04623 -263.678162) (xy 380.05258 -263.707118) (xy 380.225046 -263.879584) (xy 380.225554 -263.880092)
			(xy 380.232937 -263.88667) (xy 380.251236 -263.894114) (xy 380.261114 -263.89457)
		)
		(stroke
			(width 0)
			(type solid)
		)
		(fill yes)
		(layer "In6.Cu")
		(net "PVDDCR_SOC_P0")
	)
	(gr_poly
		(pts
			(xy 132.426456 -263.894824) (xy 132.435152 -263.894465) (xy 132.451541 -263.888637) (xy 132.465041 -263.877669)
			(xy 132.46989 -263.87044) (xy 132.473446 -263.863836) (xy 132.510022 -263.792462) (xy 132.513052 -263.786042)
			(xy 132.515774 -263.772116) (xy 132.515356 -263.76503) (xy 132.515102 -263.761474) (xy 132.497362 -263.73986)
			(xy 132.469018 -263.691667) (xy 132.449611 -263.639232) (xy 132.43975 -263.584197) (xy 132.439156 -263.556242)
			(xy 132.439643 -263.531432) (xy 132.447405 -263.482424) (xy 132.462738 -263.435234) (xy 132.485265 -263.391023)
			(xy 132.51443 -263.35088) (xy 132.549516 -263.315794) (xy 132.589659 -263.286629) (xy 132.63387 -263.264102)
			(xy 132.68106 -263.248769) (xy 132.730068 -263.241007) (xy 132.779688 -263.241007) (xy 132.828696 -263.248769)
			(xy 132.875886 -263.264102) (xy 132.920097 -263.286629) (xy 132.96024 -263.315794) (xy 132.995326 -263.35088)
			(xy 133.024491 -263.391023) (xy 133.047018 -263.435234) (xy 133.062351 -263.482424) (xy 133.070113 -263.531432)
			(xy 133.0706 -263.556242) (xy 133.070087 -263.582345) (xy 133.061487 -263.633838) (xy 133.044527 -263.683213)
			(xy 133.019672 -263.729123) (xy 133.004052 -263.750044) (xy 132.999756 -263.755995) (xy 132.994451 -263.769674)
			(xy 132.993638 -263.776968) (xy 132.993384 -263.779254) (xy 133.039612 -263.869932) (xy 133.044414 -263.877302)
			(xy 133.05797 -263.888491) (xy 133.074511 -263.894437) (xy 133.0833 -263.894824) (xy 133.366256 -263.894824)
			(xy 133.374952 -263.894465) (xy 133.391341 -263.888637) (xy 133.404841 -263.877669) (xy 133.40969 -263.87044)
			(xy 133.413246 -263.863836) (xy 133.452108 -263.787636) (xy 133.456781 -263.776336) (xy 133.456117 -263.75193)
			(xy 133.450838 -263.7409) (xy 133.44398 -263.73074) (xy 133.443726 -263.730232) (xy 133.430895 -263.710959)
			(xy 133.410575 -263.669356) (xy 133.396768 -263.625163) (xy 133.389788 -263.579392) (xy 133.38937 -263.556242)
			(xy 133.389892 -263.530987) (xy 133.398205 -263.481165) (xy 133.414606 -263.433391) (xy 133.438647 -263.388968)
			(xy 133.469671 -263.349108) (xy 133.506833 -263.314898) (xy 133.549119 -263.287272) (xy 133.595375 -263.266982)
			(xy 133.64434 -263.254582) (xy 133.694678 -263.250411) (xy 133.745016 -263.254582) (xy 133.793981 -263.266982)
			(xy 133.840237 -263.287272) (xy 133.882523 -263.314898) (xy 133.919685 -263.349108) (xy 133.950709 -263.388968)
			(xy 133.97475 -263.433391) (xy 133.991151 -263.481165) (xy 133.999464 -263.530987) (xy 133.999986 -263.556242)
			(xy 133.999523 -263.580212) (xy 133.992043 -263.627564) (xy 133.977259 -263.673167) (xy 133.955533 -263.715901)
			(xy 133.94182 -263.735566) (xy 133.937756 -263.741154) (xy 133.93293 -263.754108) (xy 133.932422 -263.76122)
			(xy 133.932115 -263.768237) (xy 133.934826 -263.782013) (xy 133.937756 -263.788398) (xy 133.979158 -263.869424)
			(xy 133.983939 -263.876913) (xy 133.997545 -263.88832) (xy 134.014224 -263.894405) (xy 134.0231 -263.894824)
			(xy 134.30631 -263.894824) (xy 134.31501 -263.894472) (xy 134.33141 -263.888654) (xy 134.344922 -263.87769)
			(xy 134.349744 -263.87044) (xy 134.3533 -263.863836) (xy 134.392162 -263.787636) (xy 134.396838 -263.776337)
			(xy 134.396173 -263.751929) (xy 134.390892 -263.7409) (xy 134.384034 -263.73074) (xy 134.38378 -263.730232)
			(xy 134.370947 -263.710959) (xy 134.350624 -263.669357) (xy 134.336814 -263.625164) (xy 134.329833 -263.579392)
			(xy 134.329424 -263.556242) (xy 134.329946 -263.530987) (xy 134.338259 -263.481165) (xy 134.35466 -263.433391)
			(xy 134.378701 -263.388968) (xy 134.409725 -263.349108) (xy 134.446887 -263.314898) (xy 134.489173 -263.287272)
			(xy 134.535429 -263.266982) (xy 134.584394 -263.254582) (xy 134.634732 -263.250411) (xy 134.68507 -263.254582)
			(xy 134.734035 -263.266982) (xy 134.780291 -263.287272) (xy 134.822577 -263.314898) (xy 134.859739 -263.349108)
			(xy 134.890763 -263.388968) (xy 134.914804 -263.433391) (xy 134.931205 -263.481165) (xy 134.939518 -263.530987)
			(xy 134.94004 -263.556242) (xy 134.939576 -263.580212) (xy 134.932096 -263.627563) (xy 134.91731 -263.673165)
			(xy 134.895581 -263.715897) (xy 134.881874 -263.735566) (xy 134.87781 -263.741154) (xy 134.872984 -263.754108)
			(xy 134.872476 -263.76122) (xy 134.872168 -263.768238) (xy 134.874878 -263.782015) (xy 134.87781 -263.788398)
			(xy 134.919212 -263.869424) (xy 134.923991 -263.876918) (xy 134.937594 -263.888337) (xy 134.954275 -263.894437)
			(xy 134.963154 -263.894824) (xy 135.246364 -263.894824) (xy 135.25506 -263.894464) (xy 135.271446 -263.888634)
			(xy 135.284944 -263.877665) (xy 135.289798 -263.87044) (xy 135.293354 -263.863836) (xy 135.332216 -263.787636)
			(xy 135.336889 -263.776336) (xy 135.336225 -263.75193) (xy 135.330946 -263.7409) (xy 135.324088 -263.73074)
			(xy 135.323834 -263.730232) (xy 135.311002 -263.710959) (xy 135.290683 -263.669356) (xy 135.276875 -263.625163)
			(xy 135.269895 -263.579392) (xy 135.269478 -263.556242) (xy 135.27 -263.530987) (xy 135.278313 -263.481165)
			(xy 135.294714 -263.433391) (xy 135.318755 -263.388968) (xy 135.349779 -263.349108) (xy 135.386941 -263.314898)
			(xy 135.429227 -263.287272) (xy 135.475483 -263.266982) (xy 135.524448 -263.254582) (xy 135.574786 -263.250411)
			(xy 135.625124 -263.254582) (xy 135.674089 -263.266982) (xy 135.720345 -263.287272) (xy 135.762631 -263.314898)
			(xy 135.799793 -263.349108) (xy 135.830817 -263.388968) (xy 135.854858 -263.433391) (xy 135.871259 -263.481165)
			(xy 135.879572 -263.530987) (xy 135.880094 -263.556242) (xy 135.879631 -263.580212) (xy 135.872151 -263.627565)
			(xy 135.857367 -263.673168) (xy 135.835642 -263.715902) (xy 135.821928 -263.735566) (xy 135.817864 -263.741154)
			(xy 135.813038 -263.754108) (xy 135.81253 -263.76122) (xy 135.812223 -263.768237) (xy 135.814935 -263.782013)
			(xy 135.817864 -263.788398) (xy 135.859266 -263.869424) (xy 135.864048 -263.876912) (xy 135.877653 -263.888317)
			(xy 135.894332 -263.894399) (xy 135.903208 -263.894824) (xy 136.186418 -263.894824) (xy 136.195118 -263.894471)
			(xy 136.211515 -263.888651) (xy 136.225025 -263.877686) (xy 136.229852 -263.87044) (xy 136.233408 -263.863836)
			(xy 136.27227 -263.787636) (xy 136.276945 -263.776337) (xy 136.276281 -263.751929) (xy 136.271 -263.7409)
			(xy 136.264142 -263.73074) (xy 136.263888 -263.730232) (xy 136.251058 -263.710958) (xy 136.230741 -263.669355)
			(xy 136.216936 -263.625162) (xy 136.209957 -263.579392) (xy 136.209532 -263.556242) (xy 136.210054 -263.530987)
			(xy 136.218367 -263.481165) (xy 136.234768 -263.433391) (xy 136.258809 -263.388968) (xy 136.289833 -263.349108)
			(xy 136.326995 -263.314898) (xy 136.369281 -263.287272) (xy 136.415537 -263.266982) (xy 136.464502 -263.254582)
			(xy 136.51484 -263.250411) (xy 136.565178 -263.254582) (xy 136.614143 -263.266982) (xy 136.660399 -263.287272)
			(xy 136.702685 -263.314898) (xy 136.739847 -263.349108) (xy 136.770871 -263.388968) (xy 136.794912 -263.433391)
			(xy 136.811313 -263.481165) (xy 136.819626 -263.530987) (xy 136.820148 -263.556242) (xy 136.819685 -263.580212)
			(xy 136.812204 -263.627564) (xy 136.797418 -263.673166) (xy 136.77569 -263.715898) (xy 136.761982 -263.735566)
			(xy 136.757918 -263.741154) (xy 136.753092 -263.754108) (xy 136.752584 -263.76122) (xy 136.752276 -263.768238)
			(xy 136.754986 -263.782014) (xy 136.757918 -263.788398) (xy 136.79932 -263.869424) (xy 136.804099 -263.876918)
			(xy 136.817703 -263.888334) (xy 136.834383 -263.894431) (xy 136.843262 -263.894824) (xy 138.066272 -263.894824)
			(xy 138.074967 -263.894463) (xy 138.091351 -263.888631) (xy 138.104847 -263.877662) (xy 138.109706 -263.87044)
			(xy 138.113262 -263.863836) (xy 138.152124 -263.787636) (xy 138.156796 -263.776336) (xy 138.156132 -263.75193)
			(xy 138.150854 -263.7409) (xy 138.143996 -263.73074) (xy 138.143742 -263.730232) (xy 138.13091 -263.710959)
			(xy 138.11059 -263.669356) (xy 138.096781 -263.625163) (xy 138.089802 -263.579392) (xy 138.089386 -263.556242)
			(xy 138.089908 -263.530987) (xy 138.098221 -263.481165) (xy 138.114622 -263.433391) (xy 138.138663 -263.388968)
			(xy 138.169687 -263.349108) (xy 138.206849 -263.314898) (xy 138.249135 -263.287272) (xy 138.295391 -263.266982)
			(xy 138.344356 -263.254582) (xy 138.394694 -263.250411) (xy 138.445032 -263.254582) (xy 138.493997 -263.266982)
			(xy 138.540253 -263.287272) (xy 138.582539 -263.314898) (xy 138.619701 -263.349108) (xy 138.650725 -263.388968)
			(xy 138.674766 -263.433391) (xy 138.691167 -263.481165) (xy 138.69948 -263.530987) (xy 138.700002 -263.556242)
			(xy 138.699539 -263.580212) (xy 138.69206 -263.627565) (xy 138.677276 -263.673168) (xy 138.655551 -263.715903)
			(xy 138.641836 -263.735566) (xy 138.637772 -263.741154) (xy 138.632946 -263.754108) (xy 138.632438 -263.76122)
			(xy 138.632131 -263.768237) (xy 138.634843 -263.782013) (xy 138.637772 -263.788398) (xy 138.679174 -263.869424)
			(xy 138.683956 -263.876912) (xy 138.697562 -263.888314) (xy 138.714241 -263.894394) (xy 138.723116 -263.894824)
			(xy 139.006326 -263.894824) (xy 139.015025 -263.89447) (xy 139.031421 -263.888648) (xy 139.044929 -263.877683)
			(xy 139.04976 -263.87044) (xy 139.053316 -263.863836) (xy 139.092178 -263.787636) (xy 139.096853 -263.776337)
			(xy 139.096188 -263.751929) (xy 139.090908 -263.7409) (xy 139.08405 -263.73074) (xy 139.083796 -263.730232)
			(xy 139.070966 -263.710958) (xy 139.050648 -263.669355) (xy 139.036842 -263.625162) (xy 139.029864 -263.579392)
			(xy 139.02944 -263.556242) (xy 139.029962 -263.530987) (xy 139.038275 -263.481165) (xy 139.054676 -263.433391)
			(xy 139.078717 -263.388968) (xy 139.109741 -263.349108) (xy 139.146903 -263.314898) (xy 139.189189 -263.287272)
			(xy 139.235445 -263.266982) (xy 139.28441 -263.254582) (xy 139.334748 -263.250411) (xy 139.385086 -263.254582)
			(xy 139.434051 -263.266982) (xy 139.480307 -263.287272) (xy 139.522593 -263.314898) (xy 139.559755 -263.349108)
			(xy 139.590779 -263.388968) (xy 139.61482 -263.433391) (xy 139.631221 -263.481165) (xy 139.639534 -263.530987)
			(xy 139.640056 -263.556242) (xy 139.639593 -263.580212) (xy 139.632113 -263.627564) (xy 139.617327 -263.673166)
			(xy 139.595599 -263.715899) (xy 139.58189 -263.735566) (xy 139.577826 -263.741154) (xy 139.573 -263.754108)
			(xy 139.572492 -263.76122) (xy 139.572184 -263.768238) (xy 139.574894 -263.782014) (xy 139.577826 -263.788398)
			(xy 139.619228 -263.869424) (xy 139.624008 -263.876917) (xy 139.637612 -263.888331) (xy 139.654292 -263.894426)
			(xy 139.66317 -263.894824) (xy 139.94638 -263.894824) (xy 139.955074 -263.894461) (xy 139.971457 -263.888628)
			(xy 139.98495 -263.877658) (xy 139.989814 -263.87044) (xy 139.99337 -263.863836) (xy 140.032232 -263.787636)
			(xy 140.036904 -263.776336) (xy 140.03624 -263.75193) (xy 140.030962 -263.7409) (xy 140.024104 -263.73074)
			(xy 140.02385 -263.730232) (xy 140.011018 -263.710959) (xy 139.990697 -263.669356) (xy 139.976888 -263.625163)
			(xy 139.969908 -263.579392) (xy 139.969494 -263.556242) (xy 139.969937 -263.532247) (xy 139.977439 -263.484846)
			(xy 139.992263 -263.439203) (xy 140.014047 -263.396441) (xy 140.042252 -263.357614) (xy 140.076184 -263.323678)
			(xy 140.115007 -263.295468) (xy 140.157766 -263.273679) (xy 140.203407 -263.258848) (xy 140.250807 -263.25134)
			(xy 140.274802 -263.250934) (xy 140.298569 -263.251381) (xy 140.34553 -263.258738) (xy 140.390781 -263.27329)
			(xy 140.433228 -263.294685) (xy 140.471842 -263.322404) (xy 140.50569 -263.355777) (xy 140.520166 -263.374632)
			(xy 140.523976 -263.379712) (xy 140.533628 -263.38784) (xy 140.537946 -263.389618) (xy 140.539978 -263.390634)
			(xy 140.54659 -263.393434) (xy 140.560771 -263.395637) (xy 140.567918 -263.394952) (xy 140.65377 -263.383522)
			(xy 140.660444 -263.382468) (xy 140.672932 -263.37732) (xy 140.678408 -263.373362) (xy 140.683996 -263.369044)
			(xy 140.69187 -263.358376) (xy 140.69441 -263.351772) (xy 140.705575 -263.324361) (xy 140.732881 -263.271845)
			(xy 140.765578 -263.222505) (xy 140.8033 -263.176892) (xy 140.824204 -263.155938) (xy 140.83157 -263.148572)
			(xy 140.83538 -263.139428) (xy 140.837253 -263.134689) (xy 140.839305 -263.124709) (xy 140.839444 -263.119616)
			(xy 140.839444 -263.099804) (xy 140.838957 -263.089793) (xy 140.8313 -263.071292) (xy 140.817148 -263.057127)
			(xy 140.798655 -263.049452) (xy 140.788644 -263.049004) (xy 140.785596 -263.049004) (xy 140.782548 -263.049258)
			(xy 140.773125 -263.050349) (xy 140.754188 -263.051495) (xy 140.744702 -263.051544) (xy 140.72071 -263.051074)
			(xy 140.673316 -263.043568) (xy 140.627679 -263.028741) (xy 140.584923 -263.006958) (xy 140.546102 -262.978756)
			(xy 140.512169 -262.944827) (xy 140.483962 -262.906009) (xy 140.462173 -262.863256) (xy 140.447341 -262.817621)
			(xy 140.439829 -262.770228) (xy 140.439394 -262.746236) (xy 140.43987 -262.721912) (xy 140.44759 -262.673881)
			(xy 140.462824 -262.62768) (xy 140.485186 -262.584477) (xy 140.514113 -262.545364) (xy 140.548873 -262.511329)
			(xy 140.588587 -262.483233) (xy 140.632252 -262.461786) (xy 140.678764 -262.447529) (xy 140.702792 -262.443722)
			(xy 140.715492 -262.441944) (xy 140.725652 -262.434578) (xy 140.730449 -262.430799) (xy 140.738269 -262.421423)
			(xy 140.741146 -262.416036) (xy 140.778484 -262.34009) (xy 140.782516 -262.329401) (xy 140.781838 -262.306597)
			(xy 140.777214 -262.296148) (xy 140.73124 -262.217408) (xy 140.720779 -262.198923) (xy 140.702345 -262.160655)
			(xy 140.69441 -262.140954) (xy 140.69441 -262.1407) (xy 140.691788 -262.134403) (xy 140.683676 -262.123442)
			(xy 140.678408 -262.11911) (xy 140.673074 -262.115046) (xy 140.660882 -262.109712) (xy 140.568172 -262.09752)
			(xy 140.563725 -262.097003) (xy 140.55478 -262.097392) (xy 140.550392 -262.098282) (xy 140.539978 -262.101838)
			(xy 140.533628 -262.104886) (xy 140.523976 -262.11276) (xy 140.520166 -262.11784) (xy 140.505662 -262.136669)
			(xy 140.471807 -262.170024) (xy 140.433194 -262.197732) (xy 140.390755 -262.219124) (xy 140.345515 -262.233685)
			(xy 140.298565 -262.241062) (xy 140.274802 -262.241538) (xy 140.249542 -262.241045) (xy 140.19971 -262.23273)
			(xy 140.151927 -262.216326) (xy 140.107495 -262.192282) (xy 140.067627 -262.161251) (xy 140.03341 -262.124082)
			(xy 140.005778 -262.081788) (xy 139.985484 -262.035523) (xy 139.973082 -261.986548) (xy 139.96891 -261.9362)
			(xy 139.973082 -261.885852) (xy 139.985484 -261.836877) (xy 140.005778 -261.790612) (xy 140.03341 -261.748318)
			(xy 140.067627 -261.711149) (xy 140.107495 -261.680118) (xy 140.151927 -261.656074) (xy 140.19971 -261.63967)
			(xy 140.249542 -261.631355) (xy 140.274802 -261.630922) (xy 140.298569 -261.631369) (xy 140.34553 -261.638726)
			(xy 140.390782 -261.653278) (xy 140.433229 -261.674672) (xy 140.471844 -261.70239) (xy 140.505693 -261.735763)
			(xy 140.520166 -261.75462) (xy 140.523976 -261.7597) (xy 140.533628 -261.767828) (xy 140.537946 -261.769606)
			(xy 140.539978 -261.770622) (xy 140.546589 -261.773423) (xy 140.560771 -261.775626) (xy 140.567918 -261.77494)
			(xy 140.65377 -261.76351) (xy 140.660444 -261.762455) (xy 140.672931 -261.757307) (xy 140.678408 -261.75335)
			(xy 140.683996 -261.749032) (xy 140.69187 -261.738364) (xy 140.69441 -261.73176) (xy 140.705575 -261.704349)
			(xy 140.732883 -261.651834) (xy 140.76558 -261.602495) (xy 140.803303 -261.556882) (xy 140.824204 -261.535926)
			(xy 140.83157 -261.52856) (xy 140.83538 -261.519416) (xy 140.837252 -261.514677) (xy 140.839302 -261.504697)
			(xy 140.839444 -261.499604) (xy 140.839444 -261.479792) (xy 140.838955 -261.469782) (xy 140.831296 -261.451286)
			(xy 140.817145 -261.437124) (xy 140.798653 -261.429452) (xy 140.788644 -261.428992) (xy 140.785596 -261.428992)
			(xy 140.782548 -261.429246) (xy 140.773125 -261.430336) (xy 140.754188 -261.431483) (xy 140.744702 -261.431532)
			(xy 140.72071 -261.431062) (xy 140.673317 -261.423556) (xy 140.627681 -261.408729) (xy 140.584926 -261.386946)
			(xy 140.546105 -261.358743) (xy 140.512174 -261.324815) (xy 140.483968 -261.285996) (xy 140.462181 -261.243243)
			(xy 140.44735 -261.197609) (xy 140.43984 -261.150216) (xy 140.439394 -261.126224) (xy 140.439846 -261.102444)
			(xy 140.447214 -261.05546) (xy 140.461777 -261.010185) (xy 140.483182 -260.967715) (xy 140.510912 -260.929076)
			(xy 140.544296 -260.895203) (xy 140.582527 -260.866915) (xy 140.624681 -260.844894) (xy 140.669739 -260.829675)
			(xy 140.716612 -260.821624) (xy 140.740384 -260.820916) (xy 140.750544 -260.820662) (xy 140.759434 -260.816852)
			(xy 140.763939 -260.814842) (xy 140.772128 -260.809343) (xy 140.77569 -260.80593) (xy 140.826744 -260.754368)
			(xy 140.832555 -260.747157) (xy 140.839078 -260.729839) (xy 140.839444 -260.720586) (xy 140.839444 -256.91338)
			(xy 140.83898 -256.90344) (xy 140.831429 -256.88505) (xy 140.817436 -256.870929) (xy 140.808456 -256.866644)
			(xy 140.754862 -256.845308) (xy 140.72235 -256.832354) (xy 140.716267 -256.830106) (xy 140.703408 -256.828448)
			(xy 140.69695 -256.829052) (xy 140.666978 -256.844038) (xy 140.661136 -256.84988) (xy 140.64384 -256.86662)
			(xy 140.604953 -256.894986) (xy 140.562097 -256.916897) (xy 140.516332 -256.931809) (xy 140.468794 -256.939353)
			(xy 140.444728 -256.939796) (xy 140.44168 -256.939796) (xy 140.417619 -256.939099) (xy 140.37016 -256.931063)
			(xy 140.324548 -256.915683) (xy 140.281915 -256.893338) (xy 140.243314 -256.864582) (xy 140.209701 -256.830127)
			(xy 140.18191 -256.790826) (xy 140.160627 -256.747652) (xy 140.14638 -256.701674) (xy 140.142468 -256.677922)
			(xy 140.140944 -256.667508) (xy 140.139166 -256.634742) (xy 140.139166 -256.634488) (xy 140.139661 -256.609876)
			(xy 140.147555 -256.561289) (xy 140.163136 -256.514597) (xy 140.186002 -256.471006) (xy 140.215561 -256.431645)
			(xy 140.251047 -256.397532) (xy 140.291544 -256.36955) (xy 140.336003 -256.348423) (xy 140.383275 -256.334697)
			(xy 140.407644 -256.331212) (xy 140.408406 -256.331212) (xy 140.414865 -256.33013) (xy 140.42696 -256.325121)
			(xy 140.432282 -256.321306) (xy 140.437616 -256.317242) (xy 140.445998 -256.306828) (xy 140.457682 -256.278888)
			(xy 140.476986 -256.23266) (xy 140.478835 -256.22798) (xy 140.480891 -256.218131) (xy 140.48105 -256.213102)
			(xy 140.48105 -256.180336) (xy 140.475716 -256.171192) (xy 140.465302 -256.157222) (xy 140.458444 -256.147824)
			(xy 140.449808 -256.13487) (xy 140.434254 -256.111031) (xy 140.407534 -256.060766) (xy 140.396468 -256.03454)
			(xy 140.395198 -256.030984) (xy 140.394182 -256.02819) (xy 140.385292 -256.016506) (xy 140.379061 -256.008988)
			(xy 140.362341 -255.998934) (xy 140.35278 -255.996948) (xy 140.351256 -255.996694) (xy 140.264896 -255.985518)
			(xy 140.259324 -255.985268) (xy 140.248298 -255.986927) (xy 140.243052 -255.98882) (xy 140.233654 -255.993138)
			(xy 140.224002 -256.001012) (xy 140.220192 -256.006092) (xy 140.205688 -256.02492) (xy 140.171831 -256.058272)
			(xy 140.133217 -256.085979) (xy 140.090779 -256.107371) (xy 140.045539 -256.121933) (xy 139.99859 -256.129313)
			(xy 139.974828 -256.12979) (xy 139.94957 -256.1293) (xy 139.899743 -256.120989) (xy 139.851964 -256.10459)
			(xy 139.807535 -256.08055) (xy 139.76767 -256.049525) (xy 139.733455 -256.012361) (xy 139.705824 -255.970072)
			(xy 139.685531 -255.923812) (xy 139.67313 -255.874843) (xy 139.668958 -255.8245) (xy 139.67313 -255.774157)
			(xy 139.685531 -255.725188) (xy 139.705824 -255.678928) (xy 139.733455 -255.636639) (xy 139.76767 -255.599475)
			(xy 139.807535 -255.56845) (xy 139.851964 -255.54441) (xy 139.899743 -255.528011) (xy 139.94957 -255.5197)
			(xy 139.974828 -255.519174) (xy 139.998595 -255.519622) (xy 140.045555 -255.526982) (xy 140.090805 -255.541535)
			(xy 140.133252 -255.562929) (xy 140.171867 -255.590646) (xy 140.205718 -255.624017) (xy 140.220192 -255.642872)
			(xy 140.224002 -255.647952) (xy 140.233654 -255.655826) (xy 140.241528 -255.659636) (xy 140.247173 -255.661804)
			(xy 140.259109 -255.663727) (xy 140.26515 -255.663446) (xy 140.267944 -255.663192) (xy 140.339826 -255.65354)
			(xy 140.346497 -255.652479) (xy 140.358978 -255.647322) (xy 140.364464 -255.64338) (xy 140.388594 -255.62433)
			(xy 140.396468 -255.61417) (xy 140.399008 -255.608074) (xy 140.406143 -255.591435) (xy 140.422285 -255.559024)
			(xy 140.431266 -255.543304) (xy 140.476986 -255.464818) (xy 140.48105 -255.454658) (xy 140.483288 -255.44555)
			(xy 140.481603 -255.426885) (xy 140.477748 -255.418336) (xy 140.44168 -255.34493) (xy 140.438798 -255.339438)
			(xy 140.430831 -255.329937) (xy 140.425932 -255.326134) (xy 140.415772 -255.318768) (xy 140.40739 -255.317498)
			(xy 140.402818 -255.31699) (xy 140.378769 -255.313205) (xy 140.332207 -255.299002) (xy 140.288488 -255.27759)
			(xy 140.248723 -255.24951) (xy 140.213919 -255.215474) (xy 140.184957 -255.176346) (xy 140.162574 -255.133117)
			(xy 140.147335 -255.086883) (xy 140.139628 -255.038816) (xy 140.139166 -255.014476) (xy 140.139662 -254.989865)
			(xy 140.147557 -254.941279) (xy 140.16314 -254.894588) (xy 140.186006 -254.850999) (xy 140.215565 -254.81164)
			(xy 140.251052 -254.777529) (xy 140.291548 -254.749548) (xy 140.336006 -254.728422) (xy 140.383277 -254.714696)
			(xy 140.407644 -254.7112) (xy 140.408406 -254.7112) (xy 140.415018 -254.710131) (xy 140.427378 -254.704985)
			(xy 140.43279 -254.70104) (xy 140.43787 -254.69723) (xy 140.445998 -254.686816) (xy 140.457682 -254.658876)
			(xy 140.476986 -254.612648) (xy 140.478834 -254.607968) (xy 140.480888 -254.598119) (xy 140.48105 -254.59309)
			(xy 140.48105 -254.560324) (xy 140.475716 -254.55118) (xy 140.465302 -254.53721) (xy 140.458444 -254.527812)
			(xy 140.449808 -254.514858) (xy 140.43425 -254.49102) (xy 140.407523 -254.440759) (xy 140.396468 -254.414528)
			(xy 140.395198 -254.410972) (xy 140.394182 -254.408178) (xy 140.385292 -254.396494) (xy 140.37906 -254.388977)
			(xy 140.36234 -254.378926) (xy 140.35278 -254.376936) (xy 140.351256 -254.376682) (xy 140.264896 -254.365506)
			(xy 140.259324 -254.365257) (xy 140.248299 -254.366918) (xy 140.243052 -254.368808) (xy 140.233654 -254.373126)
			(xy 140.224002 -254.381) (xy 140.220192 -254.38608) (xy 140.205688 -254.404908) (xy 140.171832 -254.438262)
			(xy 140.133218 -254.46597) (xy 140.09078 -254.487363) (xy 140.04554 -254.501925) (xy 139.998591 -254.509306)
			(xy 139.974828 -254.509778) (xy 139.949571 -254.509288) (xy 139.899746 -254.500977) (xy 139.851968 -254.484579)
			(xy 139.807542 -254.46054) (xy 139.767678 -254.429516) (xy 139.733464 -254.392354) (xy 139.705835 -254.350067)
			(xy 139.685543 -254.303808) (xy 139.673142 -254.254841) (xy 139.66897 -254.2045) (xy 139.673142 -254.154159)
			(xy 139.685543 -254.105192) (xy 139.705835 -254.058933) (xy 139.733464 -254.016646) (xy 139.767678 -253.979484)
			(xy 139.807542 -253.94846) (xy 139.851968 -253.924421) (xy 139.899746 -253.908023) (xy 139.949571 -253.899712)
			(xy 139.974828 -253.899162) (xy 139.998595 -253.89961) (xy 140.045555 -253.90697) (xy 140.090806 -253.921522)
			(xy 140.133253 -253.942916) (xy 140.17187 -253.970633) (xy 140.205721 -254.004002) (xy 140.220192 -254.02286)
			(xy 140.224002 -254.02794) (xy 140.233654 -254.035814) (xy 140.241528 -254.039624) (xy 140.247173 -254.041793)
			(xy 140.259109 -254.043715) (xy 140.26515 -254.043434) (xy 140.267944 -254.04318) (xy 140.339826 -254.033528)
			(xy 140.346497 -254.032467) (xy 140.358977 -254.027309) (xy 140.364464 -254.023368) (xy 140.388594 -254.004318)
			(xy 140.396468 -253.994158) (xy 140.399008 -253.988062) (xy 140.406143 -253.971423) (xy 140.422286 -253.939013)
			(xy 140.431266 -253.923292) (xy 140.476986 -253.844806) (xy 140.482047 -253.833979) (xy 140.482594 -253.810118)
			(xy 140.478002 -253.799086) (xy 140.44168 -253.724918) (xy 140.438797 -253.719427) (xy 140.430829 -253.709928)
			(xy 140.425932 -253.706122) (xy 140.415772 -253.698756) (xy 140.408914 -253.69774) (xy 140.384472 -253.694378)
			(xy 140.337044 -253.680789) (xy 140.292419 -253.65975) (xy 140.251759 -253.631808) (xy 140.216121 -253.597691)
			(xy 140.186435 -253.558286) (xy 140.163472 -253.51462) (xy 140.14783 -253.467829) (xy 140.139918 -253.419132)
			(xy 140.13942 -253.394464) (xy 140.139893 -253.370475) (xy 140.147404 -253.32309) (xy 140.162235 -253.277462)
			(xy 140.184021 -253.234717) (xy 140.212225 -253.195905) (xy 140.246154 -253.161984) (xy 140.284971 -253.133787)
			(xy 140.327722 -253.11201) (xy 140.373352 -253.097189) (xy 140.420739 -253.089688) (xy 140.444728 -253.089156)
			(xy 140.469437 -253.089635) (xy 140.51821 -253.097601) (xy 140.565063 -253.11332) (xy 140.608771 -253.136381)
			(xy 140.648194 -253.166181) (xy 140.682301 -253.201944) (xy 140.710201 -253.242734) (xy 140.72108 -253.264924)
			(xy 140.724636 -253.27229) (xy 140.734796 -253.283212) (xy 140.74394 -253.288546) (xy 140.752593 -253.29259)
			(xy 140.771576 -253.294571) (xy 140.789964 -253.289455) (xy 140.805196 -253.277954) (xy 140.810488 -253.270004)
			(xy 140.813028 -253.265432) (xy 140.818616 -253.25578) (xy 140.820648 -253.252224) (xy 140.828014 -253.239524)
			(xy 140.83157 -253.233682) (xy 140.83284 -253.231142) (xy 140.835891 -253.225376) (xy 140.839227 -253.21277)
			(xy 140.839444 -253.20625) (xy 140.839444 -252.917452) (xy 140.839157 -252.909666) (xy 140.8345 -252.894805)
			(xy 140.8303 -252.888242) (xy 140.825982 -252.8824) (xy 140.814552 -252.873256) (xy 140.806678 -252.870208)
			(xy 140.782401 -252.86047) (xy 140.737332 -252.833927) (xy 140.697448 -252.800089) (xy 140.663918 -252.759947)
			(xy 140.637723 -252.714675) (xy 140.619631 -252.6656) (xy 140.610171 -252.614158) (xy 140.60932 -252.588014)
			(xy 140.60932 -252.584204) (xy 140.609845 -252.558969) (xy 140.618145 -252.509187) (xy 140.634505 -252.461443)
			(xy 140.658481 -252.417032) (xy 140.689422 -252.377159) (xy 140.707618 -252.359668) (xy 140.715238 -252.352556)
			(xy 140.725144 -252.330712) (xy 140.727055 -252.326366) (xy 140.729359 -252.317158) (xy 140.729716 -252.312424)
			(xy 140.730224 -252.303788) (xy 140.727176 -252.29439) (xy 140.722858 -252.280166) (xy 140.719048 -252.26645)
			(xy 140.696696 -252.183138) (xy 140.69441 -252.174756) (xy 140.69441 -252.174248) (xy 140.694156 -252.173486)
			(xy 140.693902 -252.172978) (xy 140.680948 -252.124464) (xy 140.673074 -252.094746) (xy 140.673074 -252.094492)
			(xy 140.671819 -252.090365) (xy 140.668119 -252.082574) (xy 140.665708 -252.078998) (xy 140.665708 -252.078744)
			(xy 140.66139 -252.072394) (xy 140.657623 -252.067411) (xy 140.648113 -252.059318) (xy 140.642594 -252.056392)
			(xy 140.625576 -252.047756) (xy 140.618261 -252.044842) (xy 140.602612 -252.043171) (xy 140.594842 -252.044454)
			(xy 140.58138 -252.047756) (xy 140.576554 -252.050042) (xy 140.555942 -252.059409) (xy 140.512646 -252.072643)
			(xy 140.467872 -252.079351) (xy 140.445236 -252.07976) (xy 140.444728 -252.07976) (xy 140.420735 -252.079316)
			(xy 140.373339 -252.071812) (xy 140.3277 -252.056986) (xy 140.284944 -252.035201) (xy 140.246122 -252.006995)
			(xy 140.212192 -251.973062) (xy 140.183989 -251.934239) (xy 140.162207 -251.891481) (xy 140.147383 -251.845842)
			(xy 140.139883 -251.798445) (xy 140.13942 -251.774452) (xy 140.13989 -251.750501) (xy 140.147375 -251.703186)
			(xy 140.162153 -251.65762) (xy 140.183862 -251.614919) (xy 140.21197 -251.57613) (xy 140.245789 -251.542204)
			(xy 140.284488 -251.513972) (xy 140.32712 -251.492127) (xy 140.372639 -251.477203) (xy 140.396214 -251.472954)
			(xy 140.408914 -251.470922) (xy 140.43787 -251.448824) (xy 140.438378 -251.44857) (xy 140.443638 -251.444261)
			(xy 140.451876 -251.433449) (xy 140.454634 -251.427234) (xy 140.482066 -251.360178) (xy 140.484353 -251.35397)
			(xy 140.486032 -251.340852) (xy 140.485368 -251.33427) (xy 140.484606 -251.32792) (xy 140.479272 -251.31522)
			(xy 140.474954 -251.309886) (xy 140.457345 -251.286902) (xy 140.426452 -251.23793) (xy 140.400791 -251.186024)
			(xy 140.390372 -251.15901) (xy 140.389102 -251.155962) (xy 140.378688 -251.147834) (xy 140.37319 -251.143716)
			(xy 140.360569 -251.138311) (xy 140.353796 -251.137166) (xy 140.27531 -251.126752) (xy 140.26881 -251.126332)
			(xy 140.255952 -251.128385) (xy 140.24991 -251.130816) (xy 140.22578 -251.143008) (xy 140.217652 -251.149612)
			(xy 140.214096 -251.15393) (xy 140.199547 -251.171663) (xy 140.166031 -251.202976) (xy 140.128205 -251.228919)
			(xy 140.086922 -251.248907) (xy 140.043112 -251.262489) (xy 139.997762 -251.26936) (xy 139.974828 -251.269754)
			(xy 139.949565 -251.269263) (xy 139.899727 -251.260951) (xy 139.851938 -251.244549) (xy 139.8075 -251.220504)
			(xy 139.767626 -251.189472) (xy 139.733404 -251.152301) (xy 139.705768 -251.110003) (xy 139.685471 -251.063733)
			(xy 139.673067 -251.014753) (xy 139.668894 -250.9644) (xy 139.673067 -250.914047) (xy 139.685471 -250.865067)
			(xy 139.705768 -250.818797) (xy 139.733404 -250.776499) (xy 139.767626 -250.739328) (xy 139.8075 -250.708296)
			(xy 139.851938 -250.684251) (xy 139.899727 -250.667849) (xy 139.949565 -250.659537) (xy 139.974828 -250.659138)
			(xy 139.99775 -250.659543) (xy 140.04308 -250.666386) (xy 140.086878 -250.679927) (xy 140.12816 -250.699864)
			(xy 140.165997 -250.725748) (xy 140.19954 -250.756997) (xy 140.214096 -250.774708) (xy 140.217652 -250.77928)
			(xy 140.225526 -250.78563) (xy 140.24991 -250.798076) (xy 140.256193 -250.800599) (xy 140.269587 -250.80254)
			(xy 140.276326 -250.801886) (xy 140.288772 -250.800362) (xy 140.353796 -250.791726) (xy 140.36048 -250.790594)
			(xy 140.372963 -250.785316) (xy 140.378434 -250.781312) (xy 140.383768 -250.777248) (xy 140.391642 -250.76658)
			(xy 140.394182 -250.759976) (xy 140.402178 -250.740269) (xy 140.42074 -250.702001) (xy 140.431266 -250.683522)
			(xy 140.47597 -250.60656) (xy 140.481663 -250.595458) (xy 140.482608 -250.570552) (xy 140.477748 -250.559062)
			(xy 140.441426 -250.48464) (xy 140.438484 -250.479132) (xy 140.430393 -250.469625) (xy 140.425424 -250.465844)
			(xy 140.415772 -250.458732) (xy 140.403072 -250.456954) (xy 140.379027 -250.453165) (xy 140.332473 -250.438957)
			(xy 140.288763 -250.417541) (xy 140.249007 -250.389459) (xy 140.214212 -250.355422) (xy 140.18526 -250.316295)
			(xy 140.162886 -250.273068) (xy 140.147655 -250.226838) (xy 140.139955 -250.178777) (xy 140.13942 -250.15444)
			(xy 140.139891 -250.130489) (xy 140.147377 -250.083176) (xy 140.162156 -250.037612) (xy 140.183866 -249.994912)
			(xy 140.211975 -249.956125) (xy 140.245793 -249.9222) (xy 140.284492 -249.893969) (xy 140.327123 -249.872125)
			(xy 140.372641 -249.857203) (xy 140.396214 -249.852942) (xy 140.408914 -249.85091) (xy 140.43787 -249.828812)
			(xy 140.438378 -249.828558) (xy 140.443637 -249.824248) (xy 140.451873 -249.813435) (xy 140.454634 -249.807222)
			(xy 140.482066 -249.740166) (xy 140.484352 -249.733958) (xy 140.486027 -249.72084) (xy 140.485368 -249.714258)
			(xy 140.484606 -249.707908) (xy 140.479272 -249.695208) (xy 140.474954 -249.689874) (xy 140.457346 -249.66689)
			(xy 140.426453 -249.617917) (xy 140.400793 -249.566011) (xy 140.390372 -249.538998) (xy 140.389102 -249.53595)
			(xy 140.378688 -249.527822) (xy 140.37319 -249.523705) (xy 140.360568 -249.518301) (xy 140.353796 -249.517154)
			(xy 140.27531 -249.50674) (xy 140.26881 -249.50632) (xy 140.255952 -249.508373) (xy 140.24991 -249.510804)
			(xy 140.22578 -249.522996) (xy 140.217652 -249.5296) (xy 140.214096 -249.533918) (xy 140.199547 -249.551651)
			(xy 140.166032 -249.582966) (xy 140.128206 -249.60891) (xy 140.086923 -249.628898) (xy 140.043112 -249.642481)
			(xy 139.997762 -249.649352) (xy 139.974828 -249.649742) (xy 139.949566 -249.649251) (xy 139.89973 -249.64094)
			(xy 139.851943 -249.624538) (xy 139.807507 -249.600494) (xy 139.767634 -249.569464) (xy 139.733414 -249.532293)
			(xy 139.705778 -249.489997) (xy 139.685482 -249.443729) (xy 139.673078 -249.394751) (xy 139.668906 -249.3444)
			(xy 139.673078 -249.294049) (xy 139.685482 -249.245071) (xy 139.705778 -249.198803) (xy 139.733414 -249.156507)
			(xy 139.767634 -249.119336) (xy 139.807507 -249.088306) (xy 139.851943 -249.064262) (xy 139.89973 -249.04786)
			(xy 139.949566 -249.039549) (xy 139.974828 -249.039126) (xy 139.99775 -249.039531) (xy 140.04308 -249.046373)
			(xy 140.086879 -249.059915) (xy 140.128161 -249.079851) (xy 140.165999 -249.105734) (xy 140.199543 -249.136982)
			(xy 140.214096 -249.154696) (xy 140.217652 -249.159268) (xy 140.225526 -249.165618) (xy 140.24991 -249.178064)
			(xy 140.256193 -249.180588) (xy 140.269587 -249.182529) (xy 140.276326 -249.181874) (xy 140.288772 -249.18035)
			(xy 140.353796 -249.171714) (xy 140.36048 -249.170582) (xy 140.372962 -249.165303) (xy 140.378434 -249.1613)
			(xy 140.383768 -249.157236) (xy 140.391642 -249.146568) (xy 140.394182 -249.139964) (xy 140.402178 -249.120257)
			(xy 140.420741 -249.08199) (xy 140.431266 -249.06351) (xy 140.47597 -248.986548) (xy 140.481661 -248.975446)
			(xy 140.4826 -248.950543) (xy 140.477748 -248.93905) (xy 140.441426 -248.864628) (xy 140.438483 -248.859121)
			(xy 140.430391 -248.849616) (xy 140.425424 -248.845832) (xy 140.415772 -248.83872) (xy 140.403072 -248.836942)
			(xy 140.379024 -248.833154) (xy 140.332464 -248.818948) (xy 140.288747 -248.797533) (xy 140.248984 -248.769452)
			(xy 140.214179 -248.735417) (xy 140.185217 -248.696291) (xy 140.162831 -248.653064) (xy 140.147588 -248.606832)
			(xy 140.139875 -248.558768) (xy 140.13942 -248.534428) (xy 140.139892 -248.510478) (xy 140.14738 -248.463166)
			(xy 140.16216 -248.417603) (xy 140.18387 -248.374905) (xy 140.211979 -248.336119) (xy 140.245798 -248.302196)
			(xy 140.284496 -248.273967) (xy 140.327126 -248.252124) (xy 140.372643 -248.237202) (xy 140.396214 -248.23293)
			(xy 140.408914 -248.230898) (xy 140.43787 -248.2088) (xy 140.438378 -248.208546) (xy 140.443636 -248.204235)
			(xy 140.451869 -248.193422) (xy 140.454634 -248.18721) (xy 140.482066 -248.120154) (xy 140.48435 -248.113946)
			(xy 140.486023 -248.100828) (xy 140.485368 -248.094246) (xy 140.484606 -248.087896) (xy 140.479272 -248.075196)
			(xy 140.474954 -248.069862) (xy 140.457346 -248.046878) (xy 140.426455 -247.997905) (xy 140.400796 -247.945998)
			(xy 140.390372 -247.918986) (xy 140.389102 -247.915938) (xy 140.378688 -247.90781) (xy 140.373189 -247.903694)
			(xy 140.360568 -247.898292) (xy 140.353796 -247.897142) (xy 140.27531 -247.886728) (xy 140.26881 -247.886308)
			(xy 140.255952 -247.888361) (xy 140.24991 -247.890792) (xy 140.22578 -247.902984) (xy 140.217652 -247.909588)
			(xy 140.214096 -247.913906) (xy 140.199548 -247.93164) (xy 140.166033 -247.962955) (xy 140.128207 -247.9889)
			(xy 140.086924 -248.00889) (xy 140.043113 -248.022473) (xy 139.997762 -248.029345) (xy 139.974828 -248.02973)
			(xy 139.949567 -248.029239) (xy 139.899733 -248.020928) (xy 139.851948 -248.004527) (xy 139.807513 -247.980484)
			(xy 139.767643 -247.949455) (xy 139.733423 -247.912286) (xy 139.705789 -247.869992) (xy 139.685493 -247.823725)
			(xy 139.67309 -247.774749) (xy 139.668918 -247.7244) (xy 139.67309 -247.674051) (xy 139.685493 -247.625075)
			(xy 139.705789 -247.578808) (xy 139.733423 -247.536514) (xy 139.767643 -247.499345) (xy 139.807513 -247.468316)
			(xy 139.851948 -247.444273) (xy 139.899733 -247.427872) (xy 139.949567 -247.419561) (xy 139.974828 -247.419114)
			(xy 139.99775 -247.419519) (xy 140.043081 -247.426361) (xy 140.086879 -247.439902) (xy 140.128162 -247.459838)
			(xy 140.166001 -247.48572) (xy 140.199546 -247.516968) (xy 140.214096 -247.534684) (xy 140.217652 -247.539256)
			(xy 140.225526 -247.545606) (xy 140.24991 -247.558052) (xy 140.256193 -247.560576) (xy 140.269587 -247.562518)
			(xy 140.276326 -247.561862) (xy 140.288772 -247.560338) (xy 140.353796 -247.551702) (xy 140.36048 -247.55057)
			(xy 140.372962 -247.54529) (xy 140.378434 -247.541288) (xy 140.383768 -247.537224) (xy 140.391642 -247.526556)
			(xy 140.394182 -247.519952) (xy 140.402178 -247.500246) (xy 140.420742 -247.461979) (xy 140.431266 -247.443498)
			(xy 140.47597 -247.366536) (xy 140.481658 -247.355434) (xy 140.482592 -247.330533) (xy 140.477748 -247.319038)
			(xy 140.441426 -247.244616) (xy 140.438482 -247.23911) (xy 140.430389 -247.229606) (xy 140.425424 -247.22582)
			(xy 140.415772 -247.218708) (xy 140.403072 -247.21693) (xy 140.379025 -247.213142) (xy 140.332465 -247.198935)
			(xy 140.28875 -247.17752) (xy 140.248987 -247.149439) (xy 140.214184 -247.115404) (xy 140.185223 -247.076278)
			(xy 140.162839 -247.033051) (xy 140.147597 -246.98682) (xy 140.139886 -246.938756) (xy 140.13942 -246.914416)
			(xy 140.139893 -246.890466) (xy 140.147382 -246.843156) (xy 140.162163 -246.797595) (xy 140.183875 -246.754898)
			(xy 140.211984 -246.716114) (xy 140.245802 -246.682192) (xy 140.2845 -246.653964) (xy 140.32713 -246.632122)
			(xy 140.372646 -246.617202) (xy 140.396214 -246.612918) (xy 140.408914 -246.610886) (xy 140.43787 -246.588788)
			(xy 140.438378 -246.588534) (xy 140.443635 -246.584223) (xy 140.451866 -246.573408) (xy 140.454634 -246.567198)
			(xy 140.482066 -246.500142) (xy 140.484349 -246.493934) (xy 140.486018 -246.480817) (xy 140.485368 -246.474234)
			(xy 140.484606 -246.467884) (xy 140.479272 -246.455184) (xy 140.474954 -246.44985) (xy 140.457347 -246.426865)
			(xy 140.426457 -246.377892) (xy 140.400799 -246.325985) (xy 140.390372 -246.298974) (xy 140.389102 -246.295926)
			(xy 140.378688 -246.287798) (xy 140.373189 -246.283683) (xy 140.360567 -246.278282) (xy 140.353796 -246.27713)
			(xy 140.27531 -246.266716) (xy 140.268811 -246.266296) (xy 140.255953 -246.268352) (xy 140.24991 -246.27078)
			(xy 140.22578 -246.282972) (xy 140.217652 -246.289576) (xy 140.214096 -246.293894) (xy 140.199548 -246.311629)
			(xy 140.166034 -246.342945) (xy 140.128208 -246.368891) (xy 140.086925 -246.388882) (xy 140.043114 -246.402466)
			(xy 139.997762 -246.409337) (xy 139.974828 -246.409718) (xy 139.949568 -246.409227) (xy 139.899736 -246.400916)
			(xy 139.851952 -246.384516) (xy 139.80752 -246.360474) (xy 139.767651 -246.329446) (xy 139.733433 -246.292279)
			(xy 139.7058 -246.249986) (xy 139.685505 -246.203721) (xy 139.673102 -246.154747) (xy 139.66893 -246.1044)
			(xy 139.673102 -246.054053) (xy 139.685505 -246.005079) (xy 139.7058 -245.958814) (xy 139.733433 -245.916521)
			(xy 139.767651 -245.879354) (xy 139.80752 -245.848326) (xy 139.851952 -245.824284) (xy 139.899736 -245.807884)
			(xy 139.949568 -245.799573) (xy 139.974828 -245.799102) (xy 139.99775 -245.799507) (xy 140.043081 -245.806349)
			(xy 140.08688 -245.81989) (xy 140.128163 -245.839825) (xy 140.166003 -245.865706) (xy 140.199549 -245.896953)
			(xy 140.214096 -245.914672) (xy 140.217652 -245.919244) (xy 140.225526 -245.925594) (xy 140.24991 -245.93804)
			(xy 140.256193 -245.940565) (xy 140.269587 -245.942507) (xy 140.276326 -245.94185) (xy 140.288772 -245.940326)
			(xy 140.353796 -245.93169) (xy 140.36048 -245.930557) (xy 140.372961 -245.925276) (xy 140.378434 -245.921276)
			(xy 140.383768 -245.917212) (xy 140.391642 -245.906544) (xy 140.394182 -245.89994) (xy 140.402179 -245.880234)
			(xy 140.420743 -245.841967) (xy 140.431266 -245.823486) (xy 140.47597 -245.746524) (xy 140.481655 -245.735422)
			(xy 140.482584 -245.710524) (xy 140.477748 -245.699026) (xy 140.441426 -245.624604) (xy 140.438481 -245.619099)
			(xy 140.430387 -245.609597) (xy 140.425424 -245.605808) (xy 140.415772 -245.598696) (xy 140.403072 -245.596918)
			(xy 140.379025 -245.59313) (xy 140.332466 -245.578923) (xy 140.288752 -245.557508) (xy 140.24899 -245.529427)
			(xy 140.214188 -245.495391) (xy 140.185229 -245.456265) (xy 140.162846 -245.413038) (xy 140.147606 -245.366807)
			(xy 140.139896 -245.318743) (xy 140.13942 -245.294404) (xy 140.139894 -245.270455) (xy 140.147384 -245.223146)
			(xy 140.162167 -245.177586) (xy 140.183879 -245.134891) (xy 140.211988 -245.096109) (xy 140.245806 -245.062188)
			(xy 140.284504 -245.033962) (xy 140.327133 -245.012121) (xy 140.372648 -244.997201) (xy 140.396214 -244.992906)
			(xy 140.408914 -244.990874) (xy 140.43787 -244.968776) (xy 140.438378 -244.968522) (xy 140.443634 -244.96421)
			(xy 140.451863 -244.953394) (xy 140.454634 -244.947186) (xy 140.482066 -244.88013) (xy 140.484347 -244.873922)
			(xy 140.486014 -244.860805) (xy 140.485368 -244.854222) (xy 140.484606 -244.847872) (xy 140.479272 -244.835172)
			(xy 140.474954 -244.829838) (xy 140.457347 -244.806853) (xy 140.426458 -244.757879) (xy 140.400801 -244.705972)
			(xy 140.390372 -244.678962) (xy 140.389102 -244.675914) (xy 140.378688 -244.667786) (xy 140.373189 -244.663672)
			(xy 140.360567 -244.658272) (xy 140.353796 -244.657118) (xy 140.27531 -244.646704) (xy 140.268811 -244.646284)
			(xy 140.255953 -244.64834) (xy 140.24991 -244.650768) (xy 140.22578 -244.66296) (xy 140.217652 -244.669564)
			(xy 140.214096 -244.673882) (xy 140.199545 -244.691612) (xy 140.166027 -244.72292) (xy 140.128201 -244.748859)
			(xy 140.086918 -244.768843) (xy 140.043109 -244.782423) (xy 139.997761 -244.789292) (xy 139.974828 -244.789706)
			(xy 139.949569 -244.789216) (xy 139.899739 -244.780905) (xy 139.851957 -244.764505) (xy 139.807526 -244.740464)
			(xy 139.767659 -244.709437) (xy 139.733442 -244.672271) (xy 139.70581 -244.62998) (xy 139.685516 -244.583718)
			(xy 139.673114 -244.534745) (xy 139.668942 -244.4844) (xy 139.673114 -244.434055) (xy 139.685516 -244.385082)
			(xy 139.70581 -244.33882) (xy 139.733442 -244.296529) (xy 139.767659 -244.259363) (xy 139.807526 -244.228336)
			(xy 139.851957 -244.204295) (xy 139.899739 -244.187895) (xy 139.949569 -244.179584) (xy 139.974828 -244.17909)
			(xy 139.99775 -244.179495) (xy 140.043082 -244.186337) (xy 140.086881 -244.199877) (xy 140.128165 -244.219811)
			(xy 140.166005 -244.245693) (xy 140.199552 -244.276939) (xy 140.214096 -244.29466) (xy 140.217652 -244.299232)
			(xy 140.225526 -244.305582) (xy 140.24991 -244.318028) (xy 140.256193 -244.320553) (xy 140.269587 -244.322496)
			(xy 140.276326 -244.321838) (xy 140.288772 -244.320314) (xy 140.353796 -244.311678) (xy 140.36048 -244.310545)
			(xy 140.37296 -244.305263) (xy 140.378434 -244.301264) (xy 140.383768 -244.2972) (xy 140.391642 -244.286532)
			(xy 140.394182 -244.279928) (xy 140.402179 -244.260222) (xy 140.420744 -244.221956) (xy 140.431266 -244.203474)
			(xy 140.47597 -244.126512) (xy 140.481652 -244.11541) (xy 140.482575 -244.090515) (xy 140.477748 -244.079014)
			(xy 140.441426 -244.004592) (xy 140.43848 -243.999088) (xy 140.430384 -243.989588) (xy 140.425424 -243.985796)
			(xy 140.415772 -243.978684) (xy 140.403072 -243.976906) (xy 140.379025 -243.973118) (xy 140.332467 -243.958911)
			(xy 140.288754 -243.937495) (xy 140.248993 -243.909414) (xy 140.214193 -243.875378) (xy 140.185235 -243.836251)
			(xy 140.162853 -243.793025) (xy 140.147615 -243.746794) (xy 140.139907 -243.698731) (xy 140.13942 -243.674392)
			(xy 140.139887 -243.650439) (xy 140.147367 -243.60312) (xy 140.162141 -243.557548) (xy 140.183848 -243.514842)
			(xy 140.211955 -243.476048) (xy 140.245774 -243.442116) (xy 140.284475 -243.41388) (xy 140.327109 -243.392031)
			(xy 140.372631 -243.377105) (xy 140.396214 -243.372894) (xy 140.408914 -243.370862) (xy 140.43787 -243.348764)
			(xy 140.438378 -243.34851) (xy 140.443633 -243.344198) (xy 140.45186 -243.333381) (xy 140.454634 -243.327174)
			(xy 140.482066 -243.260118) (xy 140.484346 -243.25391) (xy 140.486009 -243.240793) (xy 140.485368 -243.23421)
			(xy 140.484606 -243.22786) (xy 140.479272 -243.21516) (xy 140.474954 -243.209826) (xy 140.457344 -243.186843)
			(xy 140.426447 -243.137872) (xy 140.400782 -243.085967) (xy 140.390372 -243.05895) (xy 140.389102 -243.055902)
			(xy 140.378688 -243.047774) (xy 140.373188 -243.043661) (xy 140.360566 -243.038262) (xy 140.353796 -243.037106)
			(xy 140.27531 -243.026692) (xy 140.26881 -243.026272) (xy 140.255953 -243.028327) (xy 140.24991 -243.030756)
			(xy 140.22578 -243.042948) (xy 140.217652 -243.049552) (xy 140.214096 -243.05387) (xy 140.199546 -243.071601)
			(xy 140.166028 -243.10291) (xy 140.128202 -243.128849) (xy 140.086919 -243.148834) (xy 140.04311 -243.162415)
			(xy 139.997761 -243.169285) (xy 139.974828 -243.169694) (xy 139.94957 -243.169204) (xy 139.899742 -243.160893)
			(xy 139.851962 -243.144494) (xy 139.807533 -243.120454) (xy 139.767667 -243.089428) (xy 139.733452 -243.052264)
			(xy 139.705821 -243.009974) (xy 139.685527 -242.963714) (xy 139.673126 -242.914744) (xy 139.668954 -242.8644)
			(xy 139.673126 -242.814056) (xy 139.685527 -242.765086) (xy 139.705821 -242.718826) (xy 139.733452 -242.676536)
			(xy 139.767667 -242.639372) (xy 139.807533 -242.608346) (xy 139.851962 -242.584306) (xy 139.899742 -242.567907)
			(xy 139.94957 -242.559596) (xy 139.974828 -242.559078) (xy 139.99775 -242.559483) (xy 140.043082 -242.566325)
			(xy 140.086882 -242.579864) (xy 140.128166 -242.599798) (xy 140.166007 -242.625679) (xy 140.199555 -242.656924)
			(xy 140.214096 -242.674648) (xy 140.217652 -242.67922) (xy 140.225526 -242.68557) (xy 140.24991 -242.698016)
			(xy 140.256193 -242.700542) (xy 140.269588 -242.702485) (xy 140.276326 -242.701826) (xy 140.288772 -242.700302)
			(xy 140.353796 -242.691666) (xy 140.360479 -242.690533) (xy 140.372959 -242.68525) (xy 140.378434 -242.681252)
			(xy 140.383768 -242.677188) (xy 140.391642 -242.66652) (xy 140.394182 -242.659916) (xy 140.40218 -242.64021)
			(xy 140.420745 -242.601944) (xy 140.431266 -242.583462) (xy 140.47597 -242.5065) (xy 140.481649 -242.495398)
			(xy 140.482567 -242.470505) (xy 140.477748 -242.459002) (xy 140.441426 -242.38458) (xy 140.438479 -242.379076)
			(xy 140.430382 -242.369578) (xy 140.425424 -242.365784) (xy 140.415772 -242.358672) (xy 140.403072 -242.356894)
			(xy 140.379026 -242.353106) (xy 140.332469 -242.338898) (xy 140.288756 -242.317483) (xy 140.248997 -242.289401)
			(xy 140.214197 -242.255365) (xy 140.185241 -242.216238) (xy 140.162861 -242.173012) (xy 140.147625 -242.126781)
			(xy 140.139918 -242.078718) (xy 140.13942 -242.05438) (xy 140.139888 -242.030427) (xy 140.147369 -241.98311)
			(xy 140.162145 -241.93754) (xy 140.183852 -241.894835) (xy 140.21196 -241.856042) (xy 140.245778 -241.822113)
			(xy 140.284479 -241.793878) (xy 140.327112 -241.77203) (xy 140.372633 -241.757105) (xy 140.396214 -241.752882)
			(xy 140.408914 -241.75085) (xy 140.43787 -241.728752) (xy 140.438378 -241.728498) (xy 140.443632 -241.724185)
			(xy 140.451856 -241.713367) (xy 140.454634 -241.707162) (xy 140.482066 -241.640106) (xy 140.484344 -241.633897)
			(xy 140.486004 -241.620781) (xy 140.485368 -241.614198) (xy 140.484606 -241.607848) (xy 140.479272 -241.595148)
			(xy 140.474954 -241.589814) (xy 140.457344 -241.566831) (xy 140.426449 -241.517859) (xy 140.400785 -241.465954)
			(xy 140.390372 -241.438938) (xy 140.389102 -241.43589) (xy 140.378688 -241.427762) (xy 140.373188 -241.42365)
			(xy 140.360566 -241.418252) (xy 140.353796 -241.417094) (xy 140.27531 -241.40668) (xy 140.26881 -241.40626)
			(xy 140.255953 -241.408314) (xy 140.24991 -241.410744) (xy 140.22578 -241.422936) (xy 140.217652 -241.42954)
			(xy 140.214096 -241.433858) (xy 140.199546 -241.451589) (xy 140.166029 -241.4829) (xy 140.128203 -241.50884)
			(xy 140.08692 -241.528826) (xy 140.04311 -241.542407) (xy 139.997761 -241.549277) (xy 139.974828 -241.549682)
			(xy 139.949571 -241.549192) (xy 139.899745 -241.540881) (xy 139.851967 -241.524483) (xy 139.807539 -241.500444)
			(xy 139.767675 -241.469419) (xy 139.733461 -241.432256) (xy 139.705831 -241.389969) (xy 139.685539 -241.34371)
			(xy 139.673138 -241.294742) (xy 139.668966 -241.2444) (xy 139.673138 -241.194058) (xy 139.685539 -241.14509)
			(xy 139.705831 -241.098831) (xy 139.733461 -241.056544) (xy 139.767675 -241.019381) (xy 139.807539 -240.988356)
			(xy 139.851967 -240.964317) (xy 139.899745 -240.947919) (xy 139.949571 -240.939608) (xy 139.974828 -240.939066)
			(xy 139.99775 -240.939471) (xy 140.043079 -240.946314) (xy 140.086876 -240.959857) (xy 140.128157 -240.979795)
			(xy 140.165992 -241.00568) (xy 140.199533 -241.036931) (xy 140.214096 -241.054636) (xy 140.217652 -241.059208)
			(xy 140.225526 -241.065558) (xy 140.24991 -241.078004) (xy 140.256193 -241.08053) (xy 140.269588 -241.082474)
			(xy 140.276326 -241.081814) (xy 140.288772 -241.08029) (xy 140.353796 -241.071654) (xy 140.360481 -241.070523)
			(xy 140.372966 -241.065248) (xy 140.378434 -241.06124) (xy 140.383768 -241.057176) (xy 140.391642 -241.046508)
			(xy 140.394182 -241.039904) (xy 140.402177 -241.020197) (xy 140.420737 -240.981928) (xy 140.431266 -240.96345)
			(xy 140.47597 -240.886488) (xy 140.481646 -240.875386) (xy 140.482559 -240.850496) (xy 140.477748 -240.83899)
			(xy 140.441426 -240.764568) (xy 140.438486 -240.759058) (xy 140.430399 -240.749547) (xy 140.425424 -240.745772)
			(xy 140.415772 -240.73866) (xy 140.403072 -240.736882) (xy 140.379026 -240.733093) (xy 140.33247 -240.718886)
			(xy 140.288758 -240.69747) (xy 140.249 -240.669388) (xy 140.214202 -240.635352) (xy 140.185247 -240.596225)
			(xy 140.162868 -240.552999) (xy 140.147634 -240.506768) (xy 140.139929 -240.458706) (xy 140.13942 -240.434368)
			(xy 140.139889 -240.410416) (xy 140.147372 -240.3631) (xy 140.162148 -240.317531) (xy 140.183856 -240.274828)
			(xy 140.211964 -240.236037) (xy 140.245783 -240.202109) (xy 140.284483 -240.173875) (xy 140.327115 -240.152028)
			(xy 140.372635 -240.137104) (xy 140.396214 -240.13287) (xy 140.408914 -240.130838) (xy 140.43787 -240.10874)
			(xy 140.438378 -240.108486) (xy 140.443639 -240.104178) (xy 140.45188 -240.093367) (xy 140.454634 -240.08715)
			(xy 140.482066 -240.020094) (xy 140.484356 -240.013887) (xy 140.486038 -240.000768) (xy 140.485368 -239.994186)
			(xy 140.484606 -239.987836) (xy 140.479272 -239.975136) (xy 140.474954 -239.969802) (xy 140.457345 -239.946819)
			(xy 140.42645 -239.897847) (xy 140.400787 -239.845941) (xy 140.390372 -239.818926) (xy 140.389102 -239.815878)
			(xy 140.378688 -239.80775) (xy 140.373187 -239.803638) (xy 140.360565 -239.798242) (xy 140.353796 -239.797082)
			(xy 140.27531 -239.786668) (xy 140.26881 -239.786248) (xy 140.255953 -239.788302) (xy 140.24991 -239.790732)
			(xy 140.22578 -239.802924) (xy 140.217652 -239.809528) (xy 140.214096 -239.813846) (xy 140.199546 -239.831578)
			(xy 140.16603 -239.86289) (xy 140.128204 -239.888831) (xy 140.086921 -239.908818) (xy 140.043111 -239.922399)
			(xy 139.997761 -239.92927) (xy 139.974828 -239.92967) (xy 139.949572 -239.92918) (xy 139.899748 -239.92087)
			(xy 139.851972 -239.904472) (xy 139.807546 -239.880434) (xy 139.767683 -239.849411) (xy 139.733471 -239.812249)
			(xy 139.705842 -239.769963) (xy 139.68555 -239.723706) (xy 139.673149 -239.67474) (xy 139.668978 -239.6244)
			(xy 139.673149 -239.57406) (xy 139.68555 -239.525094) (xy 139.705842 -239.478837) (xy 139.733471 -239.436551)
			(xy 139.767683 -239.399389) (xy 139.807546 -239.368366) (xy 139.851972 -239.344328) (xy 139.899748 -239.32793)
			(xy 139.949572 -239.31962) (xy 139.974828 -239.319054) (xy 139.99775 -239.319459) (xy 140.04308 -239.326302)
			(xy 140.086877 -239.339844) (xy 140.128158 -239.359782) (xy 140.165994 -239.385666) (xy 140.199536 -239.416916)
			(xy 140.214096 -239.434624) (xy 140.217652 -239.439196) (xy 140.225526 -239.445546) (xy 140.24991 -239.457992)
			(xy 140.256192 -239.460519) (xy 140.269588 -239.462463) (xy 140.276326 -239.461802) (xy 140.288772 -239.460278)
			(xy 140.353796 -239.451642) (xy 140.360481 -239.450511) (xy 140.372965 -239.445234) (xy 140.378434 -239.441228)
			(xy 140.383768 -239.437164) (xy 140.391642 -239.426496) (xy 140.394182 -239.419892) (xy 140.402177 -239.400185)
			(xy 140.420739 -239.361917) (xy 140.431266 -239.343438) (xy 140.47597 -239.266476) (xy 140.481668 -239.255374)
			(xy 140.482619 -239.230465) (xy 140.477748 -239.218978) (xy 140.441426 -239.144556) (xy 140.438485 -239.139047)
			(xy 140.430396 -239.129537) (xy 140.425424 -239.12576) (xy 140.415772 -239.118648) (xy 140.403072 -239.11687)
			(xy 140.379026 -239.113081) (xy 140.332471 -239.098874) (xy 140.288761 -239.077458) (xy 140.249003 -239.049376)
			(xy 140.214206 -239.01534) (xy 140.185253 -238.976212) (xy 140.162876 -238.932986) (xy 140.147643 -238.886756)
			(xy 140.13994 -238.838694) (xy 140.13942 -238.814356) (xy 140.13989 -238.790405) (xy 140.147374 -238.74309)
			(xy 140.162152 -238.697523) (xy 140.183861 -238.654821) (xy 140.211969 -238.616032) (xy 140.245787 -238.582105)
			(xy 140.284487 -238.553873) (xy 140.327119 -238.532027) (xy 140.372638 -238.517104) (xy 140.396214 -238.512858)
			(xy 140.408914 -238.510826) (xy 140.43787 -238.488728) (xy 140.438378 -238.488474) (xy 140.443638 -238.484165)
			(xy 140.451877 -238.473354) (xy 140.454634 -238.467138) (xy 140.482066 -238.400082) (xy 140.484354 -238.393874)
			(xy 140.486033 -238.380756) (xy 140.485368 -238.374174) (xy 140.484606 -238.367824) (xy 140.479272 -238.355124)
			(xy 140.474954 -238.34979) (xy 140.457345 -238.326806) (xy 140.426451 -238.277834) (xy 140.40079 -238.225928)
			(xy 140.390372 -238.198914) (xy 140.389102 -238.195866) (xy 140.378688 -238.187738) (xy 140.373187 -238.183627)
			(xy 140.360565 -238.178233) (xy 140.353796 -238.17707) (xy 140.27531 -238.166656) (xy 140.26881 -238.166236)
			(xy 140.255952 -238.16829) (xy 140.24991 -238.17072) (xy 140.22578 -238.182912) (xy 140.217652 -238.189516)
			(xy 140.214096 -238.193834) (xy 140.199547 -238.211567) (xy 140.166031 -238.242879) (xy 140.128205 -238.268822)
			(xy 140.086922 -238.288809) (xy 140.043111 -238.302392) (xy 139.997762 -238.309262) (xy 139.974828 -238.309658)
			(xy 139.949565 -238.309167) (xy 139.899726 -238.300855) (xy 139.851936 -238.284453) (xy 139.807498 -238.260407)
			(xy 139.767624 -238.229375) (xy 139.733401 -238.192203) (xy 139.705764 -238.149905) (xy 139.685467 -238.103634)
			(xy 139.673063 -238.054654) (xy 139.66889 -238.0043) (xy 139.673063 -237.953946) (xy 139.685467 -237.904966)
			(xy 139.705764 -237.858695) (xy 139.733401 -237.816397) (xy 139.767624 -237.779225) (xy 139.807498 -237.748193)
			(xy 139.851936 -237.724147) (xy 139.899726 -237.707745) (xy 139.949565 -237.699433) (xy 139.974828 -237.699042)
			(xy 139.99775 -237.699447) (xy 140.04308 -237.70629) (xy 140.086878 -237.719832) (xy 140.128159 -237.739768)
			(xy 140.165996 -237.765652) (xy 140.199539 -237.796902) (xy 140.214096 -237.814612) (xy 140.217652 -237.819184)
			(xy 140.225526 -237.825534) (xy 140.24991 -237.83798) (xy 140.256193 -237.840503) (xy 140.269587 -237.842443)
			(xy 140.276326 -237.84179) (xy 140.288772 -237.840266) (xy 140.353796 -237.83163) (xy 140.36048 -237.830498)
			(xy 140.372964 -237.825221) (xy 140.378434 -237.821216) (xy 140.383768 -237.817152) (xy 140.391642 -237.806484)
			(xy 140.394182 -237.79988) (xy 140.402178 -237.780173) (xy 140.42074 -237.741905) (xy 140.431266 -237.723426)
			(xy 140.47597 -237.646464) (xy 140.481664 -237.635362) (xy 140.482611 -237.610456) (xy 140.477748 -237.598966)
			(xy 140.441426 -237.524544) (xy 140.438484 -237.519036) (xy 140.430394 -237.509528) (xy 140.425424 -237.505748)
			(xy 140.415772 -237.498636) (xy 140.403072 -237.496858) (xy 140.379027 -237.493069) (xy 140.332472 -237.478862)
			(xy 140.288763 -237.457445) (xy 140.249006 -237.429363) (xy 140.214211 -237.395327) (xy 140.185258 -237.356199)
			(xy 140.162883 -237.312973) (xy 140.147652 -237.266743) (xy 140.139951 -237.218681) (xy 140.13942 -237.194344)
			(xy 140.139891 -237.170393) (xy 140.147376 -237.12308) (xy 140.162155 -237.077514) (xy 140.183865 -237.034814)
			(xy 140.211973 -236.996026) (xy 140.245792 -236.962101) (xy 140.284491 -236.93387) (xy 140.327122 -236.912026)
			(xy 140.37264 -236.897103) (xy 140.396214 -236.892846) (xy 140.408914 -236.890814) (xy 140.43787 -236.868716)
			(xy 140.438378 -236.868462) (xy 140.443637 -236.864153) (xy 140.451874 -236.85334) (xy 140.454634 -236.847126)
			(xy 140.482066 -236.78007) (xy 140.484352 -236.773862) (xy 140.486029 -236.760744) (xy 140.485368 -236.754162)
			(xy 140.484606 -236.747812) (xy 140.479272 -236.735112) (xy 140.474954 -236.729778) (xy 140.457346 -236.706794)
			(xy 140.426453 -236.657821) (xy 140.400792 -236.605915) (xy 140.390372 -236.578902) (xy 140.389102 -236.575854)
			(xy 140.378688 -236.567726) (xy 140.37319 -236.563609) (xy 140.360569 -236.558205) (xy 140.353796 -236.557058)
			(xy 140.27531 -236.546644) (xy 140.26881 -236.546224) (xy 140.255952 -236.548277) (xy 140.24991 -236.550708)
			(xy 140.22578 -236.5629) (xy 140.217652 -236.569504) (xy 140.214096 -236.573822) (xy 140.199547 -236.591555)
			(xy 140.166032 -236.622869) (xy 140.128206 -236.648813) (xy 140.086923 -236.668801) (xy 140.043112 -236.682384)
			(xy 139.997762 -236.689255) (xy 139.974828 -236.689646) (xy 139.949566 -236.689155) (xy 139.899729 -236.680843)
			(xy 139.851941 -236.664442) (xy 139.807504 -236.640397) (xy 139.767632 -236.609366) (xy 139.733411 -236.572196)
			(xy 139.705775 -236.529899) (xy 139.685478 -236.483631) (xy 139.673075 -236.434652) (xy 139.668902 -236.3843)
			(xy 139.673075 -236.333948) (xy 139.685478 -236.284969) (xy 139.705775 -236.238701) (xy 139.733411 -236.196404)
			(xy 139.767632 -236.159234) (xy 139.807504 -236.128203) (xy 139.851941 -236.104158) (xy 139.899729 -236.087757)
			(xy 139.949566 -236.079445) (xy 139.974828 -236.07903) (xy 139.99775 -236.079435) (xy 140.04308 -236.086278)
			(xy 140.086878 -236.099819) (xy 140.12816 -236.119755) (xy 140.165998 -236.145639) (xy 140.199542 -236.176887)
			(xy 140.214096 -236.1946) (xy 140.217652 -236.199172) (xy 140.225526 -236.205522) (xy 140.24991 -236.217968)
			(xy 140.256193 -236.220491) (xy 140.269587 -236.222432) (xy 140.276326 -236.221778) (xy 140.288772 -236.220254)
			(xy 140.353796 -236.211618) (xy 140.36048 -236.210486) (xy 140.372963 -236.205207) (xy 140.378434 -236.201204)
			(xy 140.383768 -236.19714) (xy 140.391642 -236.186472) (xy 140.394182 -236.179868) (xy 140.402178 -236.160161)
			(xy 140.420741 -236.121894) (xy 140.431266 -236.103414) (xy 140.47597 -236.026452) (xy 140.481662 -236.01535)
			(xy 140.482602 -235.990446) (xy 140.477748 -235.978954) (xy 140.441426 -235.904532) (xy 140.438483 -235.899025)
			(xy 140.430392 -235.889519) (xy 140.425424 -235.885736) (xy 140.415772 -235.878624) (xy 140.403072 -235.876846)
			(xy 140.379024 -235.873058) (xy 140.332463 -235.858852) (xy 140.288747 -235.837437) (xy 140.248982 -235.809356)
			(xy 140.214178 -235.775322) (xy 140.185215 -235.736195) (xy 140.162829 -235.692968) (xy 140.147585 -235.646737)
			(xy 140.139871 -235.598672) (xy 140.13942 -235.574332) (xy 140.139892 -235.550382) (xy 140.147379 -235.50307)
			(xy 140.162159 -235.457506) (xy 140.183869 -235.414807) (xy 140.211978 -235.376021) (xy 140.245796 -235.342097)
			(xy 140.284495 -235.313868) (xy 140.327125 -235.292024) (xy 140.372643 -235.277103) (xy 140.396214 -235.272834)
			(xy 140.408914 -235.270802) (xy 140.43787 -235.248704) (xy 140.438378 -235.24845) (xy 140.443636 -235.24414)
			(xy 140.451871 -235.233326) (xy 140.454634 -235.227114) (xy 140.482066 -235.160058) (xy 140.484351 -235.15385)
			(xy 140.486024 -235.140732) (xy 140.485368 -235.13415) (xy 140.484606 -235.1278) (xy 140.479272 -235.1151)
			(xy 140.474954 -235.109766) (xy 140.457346 -235.086782) (xy 140.426454 -235.037809) (xy 140.400795 -234.985902)
			(xy 140.390372 -234.95889) (xy 140.389102 -234.955842) (xy 140.378688 -234.947714) (xy 140.37319 -234.943598)
			(xy 140.360568 -234.938195) (xy 140.353796 -234.937046) (xy 140.27531 -234.926632) (xy 140.26881 -234.926212)
			(xy 140.255952 -234.928265) (xy 140.24991 -234.930696) (xy 140.22578 -234.942888) (xy 140.217652 -234.949492)
			(xy 140.214096 -234.95381) (xy 140.199548 -234.971544) (xy 140.166032 -235.002859) (xy 140.128207 -235.028803)
			(xy 140.086924 -235.048793) (xy 140.043113 -235.062376) (xy 139.997762 -235.069247) (xy 139.974828 -235.069634)
			(xy 139.949567 -235.069143) (xy 139.899732 -235.060832) (xy 139.851946 -235.044431) (xy 139.807511 -235.020387)
			(xy 139.76764 -234.989358) (xy 139.73342 -234.952188) (xy 139.705786 -234.909893) (xy 139.68549 -234.863627)
			(xy 139.673086 -234.81465) (xy 139.668914 -234.7643) (xy 139.673086 -234.71395) (xy 139.68549 -234.664973)
			(xy 139.705786 -234.618707) (xy 139.73342 -234.576412) (xy 139.76764 -234.539242) (xy 139.807511 -234.508213)
			(xy 139.851946 -234.484169) (xy 139.899732 -234.467768) (xy 139.949567 -234.459457) (xy 139.974828 -234.459018)
			(xy 139.99775 -234.459423) (xy 140.043081 -234.466265) (xy 140.086879 -234.479806) (xy 140.128162 -234.499742)
			(xy 140.166 -234.525625) (xy 140.199545 -234.556873) (xy 140.214096 -234.574588) (xy 140.217652 -234.57916)
			(xy 140.225526 -234.58551) (xy 140.24991 -234.597956) (xy 140.256193 -234.60048) (xy 140.269587 -234.602421)
			(xy 140.276326 -234.601766) (xy 140.288772 -234.600242) (xy 140.353796 -234.591606) (xy 140.36048 -234.590474)
			(xy 140.372962 -234.585194) (xy 140.378434 -234.581192) (xy 140.383768 -234.577128) (xy 140.391642 -234.56646)
			(xy 140.394182 -234.559856) (xy 140.402178 -234.54015) (xy 140.420742 -234.501882) (xy 140.431266 -234.483402)
			(xy 140.47597 -234.40644) (xy 140.481659 -234.395338) (xy 140.482594 -234.370437) (xy 140.477748 -234.358942)
			(xy 140.441426 -234.28452) (xy 140.438482 -234.279014) (xy 140.43039 -234.269509) (xy 140.425424 -234.265724)
			(xy 140.415772 -234.258612) (xy 140.403072 -234.256834) (xy 140.379024 -234.253046) (xy 140.332464 -234.238839)
			(xy 140.288749 -234.217424) (xy 140.248986 -234.189344) (xy 140.214182 -234.155309) (xy 140.185221 -234.116182)
			(xy 140.162836 -234.072955) (xy 140.147594 -234.026724) (xy 140.139882 -233.97866) (xy 140.13942 -233.95432)
			(xy 140.139893 -233.93037) (xy 140.147381 -233.883059) (xy 140.162162 -233.837497) (xy 140.183873 -233.794801)
			(xy 140.211982 -233.756016) (xy 140.2458 -233.722093) (xy 140.284499 -233.693865) (xy 140.327129 -233.672023)
			(xy 140.372645 -233.657102) (xy 140.396214 -233.652822) (xy 140.408914 -233.65079) (xy 140.43787 -233.628692)
			(xy 140.438378 -233.628438) (xy 140.443635 -233.624127) (xy 140.451867 -233.613313) (xy 140.454634 -233.607102)
			(xy 140.482066 -233.540046) (xy 140.484349 -233.533838) (xy 140.48602 -233.520721) (xy 140.485368 -233.514138)
			(xy 140.484606 -233.507788) (xy 140.479272 -233.495088) (xy 140.474954 -233.489754) (xy 140.457346 -233.46677)
			(xy 140.426456 -233.417796) (xy 140.400797 -233.365889) (xy 140.390372 -233.338878) (xy 140.389102 -233.33583)
			(xy 140.378688 -233.327702) (xy 140.373189 -233.323587) (xy 140.360568 -233.318185) (xy 140.353796 -233.317034)
			(xy 140.27531 -233.30662) (xy 140.26881 -233.3062) (xy 140.255952 -233.308252) (xy 140.24991 -233.310684)
			(xy 140.22578 -233.322876) (xy 140.217652 -233.32948) (xy 140.214096 -233.333798) (xy 140.199548 -233.351532)
			(xy 140.166033 -233.382849) (xy 140.128208 -233.408794) (xy 140.086924 -233.428784) (xy 140.043113 -233.442368)
			(xy 139.997762 -233.44924) (xy 139.974828 -233.449622) (xy 139.949568 -233.449131) (xy 139.899735 -233.44082)
			(xy 139.851951 -233.42442) (xy 139.807518 -233.400377) (xy 139.767648 -233.369349) (xy 139.73343 -233.332181)
			(xy 139.705796 -233.289888) (xy 139.685501 -233.243623) (xy 139.673098 -233.194648) (xy 139.668926 -233.1443)
			(xy 139.673098 -233.093952) (xy 139.685501 -233.044977) (xy 139.705796 -232.998712) (xy 139.73343 -232.956419)
			(xy 139.767648 -232.919251) (xy 139.807518 -232.888223) (xy 139.851951 -232.86418) (xy 139.899735 -232.84778)
			(xy 139.949568 -232.839469) (xy 139.974828 -232.839006) (xy 139.99775 -232.839411) (xy 140.043081 -232.846253)
			(xy 140.08688 -232.859794) (xy 140.128163 -232.879729) (xy 140.166002 -232.905611) (xy 140.199548 -232.936858)
			(xy 140.214096 -232.954576) (xy 140.217652 -232.959148) (xy 140.225526 -232.965498) (xy 140.24991 -232.977944)
			(xy 140.256193 -232.980468) (xy 140.269587 -232.98241) (xy 140.276326 -232.981754) (xy 140.288772 -232.98023)
			(xy 140.353796 -232.971594) (xy 140.36048 -232.970461) (xy 140.372961 -232.965181) (xy 140.378434 -232.96118)
			(xy 140.383768 -232.957116) (xy 140.391642 -232.946448) (xy 140.394182 -232.939844) (xy 140.402179 -232.920138)
			(xy 140.420743 -232.881871) (xy 140.431266 -232.86339) (xy 140.47597 -232.786428) (xy 140.481656 -232.775326)
			(xy 140.482586 -232.750427) (xy 140.477748 -232.73893) (xy 140.441426 -232.664508) (xy 140.438481 -232.659002)
			(xy 140.430387 -232.6495) (xy 140.425424 -232.645712) (xy 140.415772 -232.6386) (xy 140.403072 -232.636822)
			(xy 140.379025 -232.633034) (xy 140.332466 -232.618827) (xy 140.288751 -232.597412) (xy 140.248989 -232.569331)
			(xy 140.214187 -232.535296) (xy 140.185227 -232.496169) (xy 140.162843 -232.452942) (xy 140.147603 -232.406711)
			(xy 140.139893 -232.358647) (xy 140.13942 -232.334308) (xy 140.139894 -232.310359) (xy 140.147384 -232.263049)
			(xy 140.162166 -232.217489) (xy 140.183877 -232.174794) (xy 140.211987 -232.13601) (xy 140.245805 -232.10209)
			(xy 140.284503 -232.073863) (xy 140.327132 -232.052022) (xy 140.372647 -232.037101) (xy 140.396214 -232.03281)
			(xy 140.408914 -232.030778) (xy 140.43787 -232.00868) (xy 140.438378 -232.008426) (xy 140.443634 -232.004114)
			(xy 140.451864 -231.993299) (xy 140.454634 -231.98709) (xy 140.482066 -231.920034) (xy 140.484348 -231.913826)
			(xy 140.486015 -231.900709) (xy 140.485368 -231.894126) (xy 140.484606 -231.887776) (xy 140.479272 -231.875076)
			(xy 140.474954 -231.869742) (xy 140.457347 -231.846757) (xy 140.426458 -231.797783) (xy 140.4008 -231.745876)
			(xy 140.390372 -231.718866) (xy 140.389102 -231.715818) (xy 140.378688 -231.70769) (xy 140.373189 -231.703576)
			(xy 140.360567 -231.698175) (xy 140.353796 -231.697022) (xy 140.27531 -231.686608) (xy 140.268811 -231.686188)
			(xy 140.255953 -231.688244) (xy 140.24991 -231.690672) (xy 140.22578 -231.702864) (xy 140.217652 -231.709468)
			(xy 140.214096 -231.713786) (xy 140.199545 -231.731516) (xy 140.166027 -231.762824) (xy 140.128201 -231.788762)
			(xy 140.086918 -231.808746) (xy 140.043109 -231.822325) (xy 139.997761 -231.829195) (xy 139.974828 -231.82961)
			(xy 139.949569 -231.82912) (xy 139.899738 -231.820809) (xy 139.851956 -231.804409) (xy 139.807524 -231.780367)
			(xy 139.767656 -231.74934) (xy 139.733439 -231.712174) (xy 139.705807 -231.669882) (xy 139.685512 -231.623619)
			(xy 139.67311 -231.574646) (xy 139.668938 -231.5243) (xy 139.67311 -231.473954) (xy 139.685512 -231.424981)
			(xy 139.705807 -231.378718) (xy 139.733439 -231.336426) (xy 139.767656 -231.29926) (xy 139.807524 -231.268233)
			(xy 139.851956 -231.244191) (xy 139.899738 -231.227791) (xy 139.949569 -231.21948) (xy 139.974828 -231.218994)
			(xy 139.99775 -231.219399) (xy 140.043081 -231.226241) (xy 140.086881 -231.239781) (xy 140.128164 -231.259716)
			(xy 140.166004 -231.285597) (xy 140.199551 -231.316844) (xy 140.214096 -231.334564) (xy 140.217652 -231.339136)
			(xy 140.225526 -231.345486) (xy 140.24991 -231.357932) (xy 140.256193 -231.360457) (xy 140.269587 -231.362399)
			(xy 140.276326 -231.361742) (xy 140.288772 -231.360218) (xy 140.353796 -231.351582) (xy 140.36048 -231.350449)
			(xy 140.37296 -231.345168) (xy 140.378434 -231.341168) (xy 140.383768 -231.337104) (xy 140.391642 -231.326436)
			(xy 140.394182 -231.319832) (xy 140.402179 -231.300126) (xy 140.420744 -231.26186) (xy 140.431266 -231.243378)
			(xy 140.476986 -231.164638) (xy 140.481592 -231.154545) (xy 140.482516 -231.132406) (xy 140.478764 -231.121966)
			(xy 140.447014 -231.05618) (xy 140.444982 -231.05237) (xy 140.438124 -231.04348) (xy 140.430758 -231.03713)
			(xy 140.403326 -231.017318) (xy 140.391896 -231.015286) (xy 140.368622 -231.010743) (xy 140.32375 -230.99542)
			(xy 140.281786 -230.973342) (xy 140.24374 -230.945042) (xy 140.210527 -230.9112) (xy 140.182946 -230.87263)
			(xy 140.16166 -230.830259) (xy 140.147181 -230.785107) (xy 140.139857 -230.738259) (xy 140.13942 -230.71455)
			(xy 140.139534 -230.704485) (xy 140.140934 -230.684402) (xy 140.142214 -230.674418) (xy 140.142468 -230.671116)
			(xy 140.142976 -230.668068) (xy 140.143484 -230.664258) (xy 140.143484 -230.66375) (xy 140.147875 -230.640371)
			(xy 140.162943 -230.595255) (xy 140.184832 -230.553024) (xy 140.213012 -230.514703) (xy 140.246798 -230.48122)
			(xy 140.285371 -230.453388) (xy 140.327798 -230.431881) (xy 140.373049 -230.41722) (xy 140.396468 -230.413052)
			(xy 140.409168 -230.41102) (xy 140.438124 -230.388922) (xy 140.443445 -230.384703) (xy 140.451827 -230.374023)
			(xy 140.454634 -230.36784) (xy 140.462254 -230.349044) (xy 140.48232 -230.300276) (xy 140.484605 -230.294068)
			(xy 140.486281 -230.28095) (xy 140.485622 -230.274368) (xy 140.48486 -230.267764) (xy 140.479526 -230.255064)
			(xy 140.475208 -230.24973) (xy 140.450525 -230.21722) (xy 140.409852 -230.146451) (xy 140.394182 -230.10876)
			(xy 140.394182 -230.108506) (xy 140.391487 -230.102306) (xy 140.383374 -230.091498) (xy 140.37818 -230.08717)
			(xy 140.372846 -230.083106) (xy 140.360654 -230.077772) (xy 140.280898 -230.067358) (xy 140.276326 -230.06685)
			(xy 140.269587 -230.066266) (xy 140.256204 -230.068184) (xy 140.24991 -230.07066) (xy 140.22578 -230.082852)
			(xy 140.217652 -230.089456) (xy 140.214096 -230.093774) (xy 140.199545 -230.111505) (xy 140.166028 -230.142813)
			(xy 140.128202 -230.168752) (xy 140.086919 -230.188737) (xy 140.043109 -230.202317) (xy 139.997761 -230.209187)
			(xy 139.974828 -230.209598) (xy 139.94957 -230.209108) (xy 139.899741 -230.200797) (xy 139.85196 -230.184398)
			(xy 139.807531 -230.160357) (xy 139.767664 -230.129331) (xy 139.733449 -230.092166) (xy 139.705817 -230.049876)
			(xy 139.685524 -230.003615) (xy 139.673122 -229.954644) (xy 139.66895 -229.9043) (xy 139.673122 -229.853956)
			(xy 139.685524 -229.804985) (xy 139.705817 -229.758724) (xy 139.733449 -229.716434) (xy 139.767664 -229.679269)
			(xy 139.807531 -229.648243) (xy 139.85196 -229.624202) (xy 139.899741 -229.607803) (xy 139.94957 -229.599492)
			(xy 139.974828 -229.598982) (xy 139.99775 -229.599387) (xy 140.043082 -229.606229) (xy 140.086881 -229.619769)
			(xy 140.128165 -229.639703) (xy 140.166006 -229.665583) (xy 140.199554 -229.696829) (xy 140.214096 -229.714552)
			(xy 140.217652 -229.719124) (xy 140.225526 -229.725474) (xy 140.24991 -229.73792) (xy 140.256193 -229.740446)
			(xy 140.269588 -229.742388) (xy 140.276326 -229.74173) (xy 140.288772 -229.740206) (xy 140.353796 -229.73157)
			(xy 140.36048 -229.730437) (xy 140.372959 -229.725154) (xy 140.378434 -229.721156) (xy 140.383768 -229.717092)
			(xy 140.391642 -229.706424) (xy 140.394182 -229.69982) (xy 140.402179 -229.680114) (xy 140.420745 -229.641848)
			(xy 140.431266 -229.623366) (xy 140.476986 -229.544626) (xy 140.481589 -229.534533) (xy 140.482508 -229.512396)
			(xy 140.478764 -229.501954) (xy 140.447014 -229.436168) (xy 140.444982 -229.432358) (xy 140.438124 -229.423468)
			(xy 140.430758 -229.417118) (xy 140.403326 -229.397306) (xy 140.391896 -229.395274) (xy 140.368623 -229.390731)
			(xy 140.323751 -229.375407) (xy 140.281788 -229.35333) (xy 140.243743 -229.32503) (xy 140.210531 -229.291187)
			(xy 140.182952 -229.252617) (xy 140.161667 -229.210246) (xy 140.14719 -229.165094) (xy 140.139868 -229.118246)
			(xy 140.13942 -229.094538) (xy 140.139891 -229.070587) (xy 140.147378 -229.023275) (xy 140.162157 -228.97771)
			(xy 140.183867 -228.935011) (xy 140.211976 -228.896224) (xy 140.245794 -228.862299) (xy 140.284493 -228.834069)
			(xy 140.327124 -228.812225) (xy 140.372641 -228.797303) (xy 140.396214 -228.79304) (xy 140.408914 -228.791008)
			(xy 140.43787 -228.76891) (xy 140.438378 -228.768656) (xy 140.443637 -228.764346) (xy 140.451872 -228.753533)
			(xy 140.454634 -228.74732) (xy 140.482066 -228.680264) (xy 140.484351 -228.674056) (xy 140.486026 -228.660938)
			(xy 140.485368 -228.654356) (xy 140.484606 -228.648006) (xy 140.479272 -228.635306) (xy 140.474954 -228.629972)
			(xy 140.457346 -228.606988) (xy 140.426454 -228.558015) (xy 140.400794 -228.506109) (xy 140.390372 -228.479096)
			(xy 140.389102 -228.476048) (xy 140.378688 -228.46792) (xy 140.37319 -228.463803) (xy 140.360568 -228.4584)
			(xy 140.353796 -228.457252) (xy 140.27531 -228.446838) (xy 140.26881 -228.446418) (xy 140.255952 -228.448471)
			(xy 140.24991 -228.450902) (xy 140.22578 -228.463094) (xy 140.217652 -228.469698) (xy 140.214096 -228.474016)
			(xy 140.199547 -228.491749) (xy 140.166032 -228.523064) (xy 140.128206 -228.549008) (xy 140.086923 -228.568997)
			(xy 140.043112 -228.58258) (xy 139.997762 -228.589451) (xy 139.974828 -228.58984) (xy 139.949566 -228.589349)
			(xy 139.899731 -228.581038) (xy 139.851944 -228.564636) (xy 139.807508 -228.540592) (xy 139.767636 -228.509562)
			(xy 139.733415 -228.472392) (xy 139.70578 -228.430096) (xy 139.685484 -228.383829) (xy 139.67308 -228.334851)
			(xy 139.668908 -228.2845) (xy 139.67308 -228.234149) (xy 139.685484 -228.185171) (xy 139.70578 -228.138904)
			(xy 139.733415 -228.096608) (xy 139.767636 -228.059438) (xy 139.807508 -228.028408) (xy 139.851944 -228.004364)
			(xy 139.899731 -227.987962) (xy 139.949566 -227.979651) (xy 139.974828 -227.979224) (xy 139.99775 -227.979629)
			(xy 140.04308 -227.986471) (xy 140.086879 -228.000013) (xy 140.128161 -228.019949) (xy 140.165999 -228.045832)
			(xy 140.199543 -228.07708) (xy 140.214096 -228.094794) (xy 140.217652 -228.099366) (xy 140.225526 -228.105716)
			(xy 140.24991 -228.118162) (xy 140.256193 -228.120686) (xy 140.269587 -228.122627) (xy 140.276326 -228.121972)
			(xy 140.288772 -228.120448) (xy 140.353796 -228.111812) (xy 140.36048 -228.11068) (xy 140.372962 -228.105401)
			(xy 140.378434 -228.101398) (xy 140.383768 -228.097334) (xy 140.391642 -228.086666) (xy 140.394182 -228.080062)
			(xy 140.402178 -228.060355) (xy 140.420741 -228.022088) (xy 140.431266 -228.003608) (xy 140.47597 -227.926646)
			(xy 140.48166 -227.915544) (xy 140.482598 -227.890641) (xy 140.477748 -227.879148) (xy 140.441426 -227.804726)
			(xy 140.438483 -227.799219) (xy 140.430391 -227.789714) (xy 140.425424 -227.78593) (xy 140.415772 -227.778818)
			(xy 140.403072 -227.77704) (xy 140.379024 -227.773252) (xy 140.332464 -227.759046) (xy 140.288748 -227.737631)
			(xy 140.248984 -227.70955) (xy 140.21418 -227.675515) (xy 140.185218 -227.636388) (xy 140.162832 -227.593162)
			(xy 140.14759 -227.54693) (xy 140.139876 -227.498866) (xy 140.13942 -227.474526) (xy 140.139892 -227.450576)
			(xy 140.14738 -227.403265) (xy 140.16216 -227.357702) (xy 140.183871 -227.315004) (xy 140.21198 -227.276218)
			(xy 140.245798 -227.242295) (xy 140.284497 -227.214066) (xy 140.327127 -227.192224) (xy 140.372644 -227.177302)
			(xy 140.396214 -227.173028) (xy 140.408914 -227.170996) (xy 140.43787 -227.148898) (xy 140.438378 -227.148644)
			(xy 140.443636 -227.144333) (xy 140.451869 -227.133519) (xy 140.454634 -227.127308) (xy 140.482066 -227.060252)
			(xy 140.48435 -227.054044) (xy 140.486022 -227.040926) (xy 140.485368 -227.034344) (xy 140.484606 -227.027994)
			(xy 140.479272 -227.015294) (xy 140.474954 -227.00996) (xy 140.457346 -226.986976) (xy 140.426455 -226.938002)
			(xy 140.400796 -226.886096) (xy 140.390372 -226.859084) (xy 140.389102 -226.856036) (xy 140.378688 -226.847908)
			(xy 140.373189 -226.843792) (xy 140.360568 -226.83839) (xy 140.353796 -226.83724) (xy 140.27531 -226.826826)
			(xy 140.26881 -226.826406) (xy 140.255952 -226.828459) (xy 140.24991 -226.83089) (xy 140.22578 -226.843082)
			(xy 140.217652 -226.849686) (xy 140.214096 -226.854004) (xy 140.199548 -226.871738) (xy 140.166033 -226.903054)
			(xy 140.128207 -226.928999) (xy 140.086924 -226.948988) (xy 140.043113 -226.962572) (xy 139.997762 -226.969443)
			(xy 139.974828 -226.969828) (xy 139.949567 -226.969337) (xy 139.899734 -226.961026) (xy 139.851948 -226.944625)
			(xy 139.807514 -226.920582) (xy 139.767644 -226.889553) (xy 139.733425 -226.852385) (xy 139.705791 -226.810091)
			(xy 139.685495 -226.763825) (xy 139.673092 -226.714849) (xy 139.66892 -226.6645) (xy 139.673092 -226.614151)
			(xy 139.685495 -226.565175) (xy 139.705791 -226.518909) (xy 139.733425 -226.476615) (xy 139.767644 -226.439447)
			(xy 139.807514 -226.408418) (xy 139.851948 -226.384375) (xy 139.899734 -226.367974) (xy 139.949567 -226.359663)
			(xy 139.974828 -226.359212) (xy 139.99775 -226.359617) (xy 140.043081 -226.366459) (xy 140.08688 -226.38)
			(xy 140.128162 -226.399936) (xy 140.166001 -226.425818) (xy 140.199546 -226.457065) (xy 140.214096 -226.474782)
			(xy 140.217652 -226.479354) (xy 140.225526 -226.485704) (xy 140.24991 -226.49815) (xy 140.256193 -226.500674)
			(xy 140.269587 -226.502616) (xy 140.276326 -226.50196) (xy 140.288772 -226.500436) (xy 140.353796 -226.4918)
			(xy 140.36048 -226.490668) (xy 140.372961 -226.485388) (xy 140.378434 -226.481386) (xy 140.383768 -226.477322)
			(xy 140.391642 -226.466654) (xy 140.394182 -226.46005) (xy 140.402179 -226.440344) (xy 140.420742 -226.402077)
			(xy 140.431266 -226.383596) (xy 140.47597 -226.306634) (xy 140.481657 -226.295532) (xy 140.48259 -226.270632)
			(xy 140.477748 -226.259136) (xy 140.441426 -226.184714) (xy 140.438482 -226.179208) (xy 140.430388 -226.169705)
			(xy 140.425424 -226.165918) (xy 140.415772 -226.158806) (xy 140.403072 -226.157028) (xy 140.379025 -226.15324)
			(xy 140.332465 -226.139033) (xy 140.28875 -226.117618) (xy 140.248987 -226.089537) (xy 140.214185 -226.055502)
			(xy 140.185224 -226.016375) (xy 140.16284 -225.973149) (xy 140.147599 -225.926917) (xy 140.139887 -225.878853)
			(xy 140.13942 -225.854514) (xy 140.139865 -225.830521) (xy 140.14737 -225.783125) (xy 140.162198 -225.737488)
			(xy 140.183983 -225.694732) (xy 140.212189 -225.65591) (xy 140.246121 -225.62198) (xy 140.284944 -225.593776)
			(xy 140.327701 -225.571993) (xy 140.373339 -225.557167) (xy 140.420735 -225.549664) (xy 140.444728 -225.549206)
			(xy 140.46798 -225.549642) (xy 140.513947 -225.55669) (xy 140.558316 -225.570619) (xy 140.600063 -225.591107)
			(xy 140.638225 -225.617683) (xy 140.671922 -225.649732) (xy 140.686536 -225.667824) (xy 140.68679 -225.668078)
			(xy 140.690714 -225.672784) (xy 140.700343 -225.680357) (xy 140.70584 -225.683064) (xy 140.711428 -225.685858)
			(xy 140.72362 -225.68789) (xy 140.812012 -225.682302) (xy 140.824147 -225.680882) (xy 140.845122 -225.668422)
			(xy 140.852144 -225.658426) (xy 140.868654 -225.629724) (xy 140.901166 -225.57359) (xy 140.911099 -225.556874)
			(xy 140.932965 -225.524715) (xy 140.944854 -225.509328) (xy 140.944854 -225.509074) (xy 140.948892 -225.503672)
			(xy 140.954304 -225.491323) (xy 140.955522 -225.48469) (xy 140.9573 -225.471482) (xy 140.918946 -225.378518)
			(xy 140.916187 -225.372358) (xy 140.907939 -225.36168) (xy 140.90269 -225.357436) (xy 140.897356 -225.353372)
			(xy 140.885164 -225.348546) (xy 140.878052 -225.34753) (xy 140.853688 -225.34407) (xy 140.806426 -225.330376)
			(xy 140.761971 -225.309281) (xy 140.721475 -225.28133) (xy 140.685984 -225.247246) (xy 140.656419 -225.207913)
			(xy 140.633543 -225.164347) (xy 140.61795 -225.117677) (xy 140.610042 -225.069111) (xy 140.609574 -225.044508)
			(xy 140.610044 -225.020516) (xy 140.617549 -224.973122) (xy 140.632375 -224.927486) (xy 140.654158 -224.884731)
			(xy 140.682361 -224.84591) (xy 140.71629 -224.811978) (xy 140.755109 -224.783772) (xy 140.797862 -224.761985)
			(xy 140.843497 -224.747155) (xy 140.89089 -224.739646) (xy 140.914882 -224.7392) (xy 140.938648 -224.739651)
			(xy 140.985608 -224.747013) (xy 141.03086 -224.761561) (xy 141.073311 -224.782944) (xy 141.111937 -224.810647)
			(xy 141.145804 -224.843999) (xy 141.174096 -224.882195) (xy 141.196128 -224.924314) (xy 141.211368 -224.969337)
			(xy 141.219449 -225.016178) (xy 141.22019 -225.039936) (xy 141.22019 -225.045016) (xy 141.219448 -225.075368)
			(xy 141.207429 -225.134873) (xy 141.196314 -225.163126) (xy 141.193765 -225.169535) (xy 141.191839 -225.183185)
			(xy 141.192504 -225.19005) (xy 141.194282 -225.20275) (xy 141.256004 -225.281998) (xy 141.260262 -225.287185)
			(xy 141.270941 -225.295304) (xy 141.277086 -225.298) (xy 141.283232 -225.300268) (xy 141.29622 -225.301936)
			(xy 141.30274 -225.301302) (xy 141.302994 -225.301302) (xy 141.323822 -225.298762) (xy 141.32433 -225.298762)
			(xy 141.32687 -225.298508) (xy 141.341306 -225.297084) (xy 141.370277 -225.29556) (xy 141.384782 -225.29546)
			(xy 141.396733 -225.295459) (xy 141.420617 -225.296347) (xy 141.432534 -225.297238) (xy 141.432788 -225.297238)
			(xy 141.455648 -225.299778) (xy 141.467586 -225.301302) (xy 141.478508 -225.297492) (xy 141.483951 -225.295436)
			(xy 141.493825 -225.289284) (xy 141.498066 -225.2853) (xy 141.549882 -225.233484) (xy 141.556598 -225.226247)
			(xy 141.564195 -225.208042) (xy 141.564614 -225.198178) (xy 141.564614 -225.14052) (xy 141.562328 -225.133154)
			(xy 141.556289 -225.111621) (xy 141.549793 -225.067376) (xy 141.549374 -225.045016) (xy 141.549374 -225.044)
			(xy 141.549741 -225.021636) (xy 141.556238 -224.977384) (xy 141.562328 -224.955862) (xy 141.564614 -224.948496)
			(xy 141.564614 -224.632012) (xy 141.564106 -224.624646) (xy 141.562425 -224.616028) (xy 141.554109 -224.600578)
			(xy 141.54785 -224.59442) (xy 141.486636 -224.544382) (xy 141.482271 -224.54098) (xy 141.472404 -224.535975)
			(xy 141.467078 -224.534476) (xy 141.45641 -224.531682) (xy 141.449552 -224.532952) (xy 141.44498 -224.533968)
			(xy 141.430085 -224.536734) (xy 141.399931 -224.539661) (xy 141.384782 -224.53981) (xy 141.359527 -224.539287)
			(xy 141.309708 -224.530971) (xy 141.261936 -224.514568) (xy 141.217516 -224.490527) (xy 141.177658 -224.459502)
			(xy 141.14345 -224.422341) (xy 141.115825 -224.380055) (xy 141.095537 -224.3338) (xy 141.083138 -224.284837)
			(xy 141.078967 -224.2345) (xy 141.083138 -224.184163) (xy 141.095537 -224.1352) (xy 141.115825 -224.088945)
			(xy 141.14345 -224.046659) (xy 141.177658 -224.009498) (xy 141.217516 -223.978473) (xy 141.261936 -223.954432)
			(xy 141.309708 -223.938029) (xy 141.359527 -223.929713) (xy 141.384782 -223.929194) (xy 141.397545 -223.929334)
			(xy 141.422978 -223.931501) (xy 141.435582 -223.933512) (xy 141.435582 -223.933258) (xy 141.460325 -223.937946)
			(xy 141.507938 -223.954343) (xy 141.552214 -223.97833) (xy 141.591954 -224.009259) (xy 141.626078 -224.046291)
			(xy 141.653663 -224.08842) (xy 141.67396 -224.134505) (xy 141.686418 -224.183297) (xy 141.689074 -224.20834)
			(xy 141.689928 -224.215478) (xy 141.695075 -224.228893) (xy 141.699234 -224.234756) (xy 141.699488 -224.23501)
			(xy 141.704063 -224.240571) (xy 141.71567 -224.249079) (xy 141.722348 -224.251774) (xy 141.806422 -224.282508)
			(xy 141.815617 -224.285438) (xy 141.834893 -224.284918) (xy 141.852611 -224.277307) (xy 141.859762 -224.270824)
			(xy 142.084806 -224.04578) (xy 142.086584 -224.043494) (xy 142.097234 -224.030575) (xy 142.120911 -224.006902)
			(xy 142.133828 -223.99625) (xy 142.136114 -223.994472) (xy 142.156942 -223.973644) (xy 142.165578 -223.962468)
			(xy 142.168372 -223.957134) (xy 142.17015 -223.95053) (xy 142.17015 -223.950276) (xy 142.18284 -223.903459)
			(xy 142.215175 -223.812) (xy 142.255229 -223.723647) (xy 142.302706 -223.639052) (xy 142.357257 -223.558836)
			(xy 142.418481 -223.48359) (xy 142.451836 -223.448372) (xy 142.472156 -223.428052) (xy 142.475966 -223.424242)
			(xy 142.482824 -223.413828) (xy 142.485221 -223.409995) (xy 142.488796 -223.401693) (xy 142.489936 -223.397318)
			(xy 142.490952 -223.393254) (xy 142.491206 -223.391476) (xy 142.491206 -223.390206) (xy 142.494517 -223.3654)
			(xy 142.508169 -223.317257) (xy 142.529479 -223.271979) (xy 142.557878 -223.230776) (xy 142.592608 -223.194748)
			(xy 142.612364 -223.179386) (xy 142.619222 -223.174306) (xy 142.633446 -223.153478) (xy 142.635894 -223.149853)
			(xy 142.639608 -223.141935) (xy 142.640812 -223.13773) (xy 142.653288 -223.092082) (xy 142.684856 -223.002862)
			(xy 142.723774 -222.916595) (xy 142.76977 -222.833885) (xy 142.822521 -222.755311) (xy 142.881659 -222.681423)
			(xy 142.913862 -222.646748) (xy 142.920212 -222.63989) (xy 142.933928 -222.607378) (xy 142.934436 -222.598488)
			(xy 142.936086 -222.573528) (xy 142.945974 -222.524496) (xy 142.963143 -222.477515) (xy 142.987201 -222.433661)
			(xy 143.017597 -222.393937) (xy 143.035274 -222.376238) (xy 143.04264 -222.369126) (xy 143.04645 -222.360236)
			(xy 143.048429 -222.355456) (xy 143.0506 -222.345341) (xy 143.050768 -222.34017) (xy 143.051022 -222.313754)
			(xy 143.05153 -222.264478) (xy 143.0511 -222.259324) (xy 143.048414 -222.249338) (xy 143.046196 -222.244666)
			(xy 143.043656 -222.23984) (xy 143.036798 -222.231458) (xy 142.918942 -222.113602) (xy 142.91412 -222.109047)
			(xy 142.902672 -222.102357) (xy 142.896336 -222.100394) (xy 142.890494 -222.09887) (xy 142.877794 -222.098616)
			(xy 142.870682 -222.100394) (xy 142.852017 -222.10489) (xy 142.813932 -222.109731) (xy 142.794736 -222.110046)
			(xy 142.771016 -222.109601) (xy 142.724144 -222.102274) (xy 142.678969 -222.087791) (xy 142.657576 -222.077534)
			(xy 142.65148 -222.074486) (xy 142.641574 -222.0722) (xy 137.587482 -222.0722) (xy 137.581471 -222.072364)
			(xy 137.569786 -222.075181) (xy 137.564368 -222.077788) (xy 137.560894 -222.079628) (xy 137.554516 -222.084222)
			(xy 137.551668 -222.086932) (xy 137.02411 -222.61449) (xy 137.319016 -222.61449) (xy 137.322976 -222.565436)
			(xy 137.334753 -222.517652) (xy 137.354044 -222.472376) (xy 137.380347 -222.43078) (xy 137.412982 -222.393943)
			(xy 137.451103 -222.362818) (xy 137.493724 -222.338211) (xy 137.53974 -222.320759) (xy 137.587959 -222.310915)
			(xy 137.637134 -222.308934) (xy 137.685989 -222.314866) (xy 137.73326 -222.328558) (xy 137.777722 -222.349656)
			(xy 137.818225 -222.377612) (xy 137.853718 -222.411704) (xy 137.883283 -222.451048) (xy 137.906154 -222.494625)
			(xy 137.921738 -222.541306) (xy 137.929633 -222.589883) (xy 137.930128 -222.61449) (xy 138.25907 -222.61449)
			(xy 138.26303 -222.565436) (xy 138.274807 -222.517652) (xy 138.294098 -222.472376) (xy 138.320401 -222.43078)
			(xy 138.353036 -222.393943) (xy 138.391157 -222.362818) (xy 138.433778 -222.338211) (xy 138.479794 -222.320759)
			(xy 138.528013 -222.310915) (xy 138.577188 -222.308934) (xy 138.626043 -222.314866) (xy 138.673314 -222.328558)
			(xy 138.717776 -222.349656) (xy 138.758279 -222.377612) (xy 138.793772 -222.411704) (xy 138.823337 -222.451048)
			(xy 138.846208 -222.494625) (xy 138.861792 -222.541306) (xy 138.869687 -222.589883) (xy 138.870182 -222.61449)
			(xy 140.138924 -222.61449) (xy 140.142884 -222.565436) (xy 140.154661 -222.517652) (xy 140.173952 -222.472376)
			(xy 140.200255 -222.43078) (xy 140.23289 -222.393943) (xy 140.271011 -222.362818) (xy 140.313632 -222.338211)
			(xy 140.359648 -222.320759) (xy 140.407867 -222.310915) (xy 140.457042 -222.308934) (xy 140.505897 -222.314866)
			(xy 140.553168 -222.328558) (xy 140.59763 -222.349656) (xy 140.638133 -222.377612) (xy 140.673626 -222.411704)
			(xy 140.703191 -222.451048) (xy 140.726062 -222.494625) (xy 140.741646 -222.541306) (xy 140.749541 -222.589883)
			(xy 140.750036 -222.61449) (xy 141.078978 -222.61449) (xy 141.082938 -222.565436) (xy 141.094715 -222.517652)
			(xy 141.114006 -222.472376) (xy 141.140309 -222.43078) (xy 141.172944 -222.393943) (xy 141.211065 -222.362818)
			(xy 141.253686 -222.338211) (xy 141.299702 -222.320759) (xy 141.347921 -222.310915) (xy 141.397096 -222.308934)
			(xy 141.445951 -222.314866) (xy 141.493222 -222.328558) (xy 141.537684 -222.349656) (xy 141.578187 -222.377612)
			(xy 141.61368 -222.411704) (xy 141.643245 -222.451048) (xy 141.666116 -222.494625) (xy 141.6817 -222.541306)
			(xy 141.689595 -222.589883) (xy 141.69009 -222.61449) (xy 141.689595 -222.639097) (xy 141.6817 -222.687674)
			(xy 141.666116 -222.734355) (xy 141.643245 -222.777932) (xy 141.61368 -222.817276) (xy 141.578187 -222.851368)
			(xy 141.537684 -222.879324) (xy 141.493222 -222.900422) (xy 141.445951 -222.914114) (xy 141.397096 -222.920046)
			(xy 141.347921 -222.918065) (xy 141.299702 -222.908221) (xy 141.253686 -222.890769) (xy 141.211065 -222.866162)
			(xy 141.172944 -222.835037) (xy 141.140309 -222.7982) (xy 141.114006 -222.756604) (xy 141.094715 -222.711328)
			(xy 141.082938 -222.663544) (xy 141.078978 -222.61449) (xy 140.750036 -222.61449) (xy 140.749541 -222.639097)
			(xy 140.741646 -222.687674) (xy 140.726062 -222.734355) (xy 140.703191 -222.777932) (xy 140.673626 -222.817276)
			(xy 140.638133 -222.851368) (xy 140.59763 -222.879324) (xy 140.553168 -222.900422) (xy 140.505897 -222.914114)
			(xy 140.457042 -222.920046) (xy 140.407867 -222.918065) (xy 140.359648 -222.908221) (xy 140.313632 -222.890769)
			(xy 140.271011 -222.866162) (xy 140.23289 -222.835037) (xy 140.200255 -222.7982) (xy 140.173952 -222.756604)
			(xy 140.154661 -222.711328) (xy 140.142884 -222.663544) (xy 140.138924 -222.61449) (xy 138.870182 -222.61449)
			(xy 138.869687 -222.639097) (xy 138.861792 -222.687674) (xy 138.846208 -222.734355) (xy 138.823337 -222.777932)
			(xy 138.793772 -222.817276) (xy 138.758279 -222.851368) (xy 138.717776 -222.879324) (xy 138.673314 -222.900422)
			(xy 138.626043 -222.914114) (xy 138.577188 -222.920046) (xy 138.528013 -222.918065) (xy 138.479794 -222.908221)
			(xy 138.433778 -222.890769) (xy 138.391157 -222.866162) (xy 138.353036 -222.835037) (xy 138.320401 -222.7982)
			(xy 138.294098 -222.756604) (xy 138.274807 -222.711328) (xy 138.26303 -222.663544) (xy 138.25907 -222.61449)
			(xy 137.930128 -222.61449) (xy 137.929633 -222.639097) (xy 137.921738 -222.687674) (xy 137.906154 -222.734355)
			(xy 137.883283 -222.777932) (xy 137.853718 -222.817276) (xy 137.818225 -222.851368) (xy 137.777722 -222.879324)
			(xy 137.73326 -222.900422) (xy 137.685989 -222.914114) (xy 137.637134 -222.920046) (xy 137.587959 -222.918065)
			(xy 137.53974 -222.908221) (xy 137.493724 -222.890769) (xy 137.451103 -222.866162) (xy 137.412982 -222.835037)
			(xy 137.380347 -222.7982) (xy 137.354044 -222.756604) (xy 137.334753 -222.711328) (xy 137.322976 -222.663544)
			(xy 137.319016 -222.61449) (xy 137.02411 -222.61449) (xy 136.214104 -223.424496) (xy 136.848862 -223.424496)
			(xy 136.852822 -223.375442) (xy 136.864599 -223.327658) (xy 136.88389 -223.282382) (xy 136.910193 -223.240786)
			(xy 136.942828 -223.203949) (xy 136.980949 -223.172824) (xy 137.02357 -223.148217) (xy 137.069586 -223.130765)
			(xy 137.117805 -223.120921) (xy 137.16698 -223.11894) (xy 137.215835 -223.124872) (xy 137.263106 -223.138564)
			(xy 137.307568 -223.159662) (xy 137.348071 -223.187618) (xy 137.383564 -223.22171) (xy 137.413129 -223.261054)
			(xy 137.436 -223.304631) (xy 137.451584 -223.351312) (xy 137.459479 -223.399889) (xy 137.459974 -223.424496)
			(xy 137.788916 -223.424496) (xy 137.792876 -223.375442) (xy 137.804653 -223.327658) (xy 137.823944 -223.282382)
			(xy 137.850247 -223.240786) (xy 137.882882 -223.203949) (xy 137.921003 -223.172824) (xy 137.963624 -223.148217)
			(xy 138.00964 -223.130765) (xy 138.057859 -223.120921) (xy 138.107034 -223.11894) (xy 138.155889 -223.124872)
			(xy 138.20316 -223.138564) (xy 138.247622 -223.159662) (xy 138.288125 -223.187618) (xy 138.323618 -223.22171)
			(xy 138.353183 -223.261054) (xy 138.376054 -223.304631) (xy 138.391638 -223.351312) (xy 138.399533 -223.399889)
			(xy 138.400028 -223.424496) (xy 139.669024 -223.424496) (xy 139.672984 -223.375442) (xy 139.684761 -223.327658)
			(xy 139.704052 -223.282382) (xy 139.730355 -223.240786) (xy 139.76299 -223.203949) (xy 139.801111 -223.172824)
			(xy 139.843732 -223.148217) (xy 139.889748 -223.130765) (xy 139.937967 -223.120921) (xy 139.987142 -223.11894)
			(xy 140.035997 -223.124872) (xy 140.083268 -223.138564) (xy 140.12773 -223.159662) (xy 140.168233 -223.187618)
			(xy 140.203726 -223.22171) (xy 140.233291 -223.261054) (xy 140.256162 -223.304631) (xy 140.271746 -223.351312)
			(xy 140.279641 -223.399889) (xy 140.280136 -223.424496) (xy 140.609078 -223.424496) (xy 140.613038 -223.375442)
			(xy 140.624815 -223.327658) (xy 140.644106 -223.282382) (xy 140.670409 -223.240786) (xy 140.703044 -223.203949)
			(xy 140.741165 -223.172824) (xy 140.783786 -223.148217) (xy 140.829802 -223.130765) (xy 140.878021 -223.120921)
			(xy 140.927196 -223.11894) (xy 140.976051 -223.124872) (xy 141.023322 -223.138564) (xy 141.067784 -223.159662)
			(xy 141.108287 -223.187618) (xy 141.14378 -223.22171) (xy 141.173345 -223.261054) (xy 141.196216 -223.304631)
			(xy 141.2118 -223.351312) (xy 141.219695 -223.399889) (xy 141.22019 -223.424496) (xy 141.219695 -223.449103)
			(xy 141.2118 -223.49768) (xy 141.196216 -223.544361) (xy 141.173345 -223.587938) (xy 141.14378 -223.627282)
			(xy 141.108287 -223.661374) (xy 141.067784 -223.68933) (xy 141.023322 -223.710428) (xy 140.976051 -223.72412)
			(xy 140.927196 -223.730052) (xy 140.878021 -223.728071) (xy 140.829802 -223.718227) (xy 140.783786 -223.700775)
			(xy 140.741165 -223.676168) (xy 140.703044 -223.645043) (xy 140.670409 -223.608206) (xy 140.644106 -223.56661)
			(xy 140.624815 -223.521334) (xy 140.613038 -223.47355) (xy 140.609078 -223.424496) (xy 140.280136 -223.424496)
			(xy 140.279641 -223.449103) (xy 140.271746 -223.49768) (xy 140.256162 -223.544361) (xy 140.233291 -223.587938)
			(xy 140.203726 -223.627282) (xy 140.168233 -223.661374) (xy 140.12773 -223.68933) (xy 140.083268 -223.710428)
			(xy 140.035997 -223.72412) (xy 139.987142 -223.730052) (xy 139.937967 -223.728071) (xy 139.889748 -223.718227)
			(xy 139.843732 -223.700775) (xy 139.801111 -223.676168) (xy 139.76299 -223.645043) (xy 139.730355 -223.608206)
			(xy 139.704052 -223.56661) (xy 139.684761 -223.521334) (xy 139.672984 -223.47355) (xy 139.669024 -223.424496)
			(xy 138.400028 -223.424496) (xy 138.399533 -223.449103) (xy 138.391638 -223.49768) (xy 138.376054 -223.544361)
			(xy 138.353183 -223.587938) (xy 138.323618 -223.627282) (xy 138.288125 -223.661374) (xy 138.247622 -223.68933)
			(xy 138.20316 -223.710428) (xy 138.155889 -223.72412) (xy 138.107034 -223.730052) (xy 138.057859 -223.728071)
			(xy 138.00964 -223.718227) (xy 137.963624 -223.700775) (xy 137.921003 -223.676168) (xy 137.882882 -223.645043)
			(xy 137.850247 -223.608206) (xy 137.823944 -223.56661) (xy 137.804653 -223.521334) (xy 137.792876 -223.47355)
			(xy 137.788916 -223.424496) (xy 137.459974 -223.424496) (xy 137.459479 -223.449103) (xy 137.451584 -223.49768)
			(xy 137.436 -223.544361) (xy 137.413129 -223.587938) (xy 137.383564 -223.627282) (xy 137.348071 -223.661374)
			(xy 137.307568 -223.68933) (xy 137.263106 -223.710428) (xy 137.215835 -223.72412) (xy 137.16698 -223.730052)
			(xy 137.117805 -223.728071) (xy 137.069586 -223.718227) (xy 137.02357 -223.700775) (xy 136.980949 -223.676168)
			(xy 136.942828 -223.645043) (xy 136.910193 -223.608206) (xy 136.88389 -223.56661) (xy 136.864599 -223.521334)
			(xy 136.852822 -223.47355) (xy 136.848862 -223.424496) (xy 136.214104 -223.424496) (xy 135.844534 -223.794066)
			(xy 135.841994 -223.79686) (xy 135.840978 -223.79813) (xy 135.834841 -223.80662) (xy 135.829345 -223.826813)
			(xy 135.83031 -223.837246) (xy 135.845042 -223.920812) (xy 135.846323 -223.926799) (xy 135.851336 -223.937966)
			(xy 135.854948 -223.94291) (xy 135.85825 -223.947228) (xy 135.867648 -223.954594) (xy 135.873744 -223.957642)
			(xy 135.895981 -223.968553) (xy 135.936895 -223.996469) (xy 135.97277 -224.030619) (xy 136.002666 -224.070108)
			(xy 136.025802 -224.113903) (xy 136.041571 -224.160855) (xy 136.04956 -224.209737) (xy 136.05002 -224.234502)
			(xy 136.378962 -224.234502) (xy 136.382922 -224.185448) (xy 136.394699 -224.137664) (xy 136.41399 -224.092388)
			(xy 136.440293 -224.050792) (xy 136.472928 -224.013955) (xy 136.511049 -223.98283) (xy 136.55367 -223.958223)
			(xy 136.599686 -223.940771) (xy 136.647905 -223.930927) (xy 136.69708 -223.928946) (xy 136.745935 -223.934878)
			(xy 136.793206 -223.94857) (xy 136.837668 -223.969668) (xy 136.878171 -223.997624) (xy 136.913664 -224.031716)
			(xy 136.943229 -224.07106) (xy 136.9661 -224.114637) (xy 136.981684 -224.161318) (xy 136.989579 -224.209895)
			(xy 136.990074 -224.234502) (xy 137.319016 -224.234502) (xy 137.322976 -224.185448) (xy 137.334753 -224.137664)
			(xy 137.354044 -224.092388) (xy 137.380347 -224.050792) (xy 137.412982 -224.013955) (xy 137.451103 -223.98283)
			(xy 137.493724 -223.958223) (xy 137.53974 -223.940771) (xy 137.587959 -223.930927) (xy 137.637134 -223.928946)
			(xy 137.685989 -223.934878) (xy 137.73326 -223.94857) (xy 137.777722 -223.969668) (xy 137.818225 -223.997624)
			(xy 137.853718 -224.031716) (xy 137.883283 -224.07106) (xy 137.906154 -224.114637) (xy 137.921738 -224.161318)
			(xy 137.929633 -224.209895) (xy 137.930128 -224.234502) (xy 138.25907 -224.234502) (xy 138.26303 -224.185448)
			(xy 138.274807 -224.137664) (xy 138.294098 -224.092388) (xy 138.320401 -224.050792) (xy 138.353036 -224.013955)
			(xy 138.391157 -223.98283) (xy 138.433778 -223.958223) (xy 138.479794 -223.940771) (xy 138.528013 -223.930927)
			(xy 138.577188 -223.928946) (xy 138.626043 -223.934878) (xy 138.673314 -223.94857) (xy 138.717776 -223.969668)
			(xy 138.758279 -223.997624) (xy 138.793772 -224.031716) (xy 138.823337 -224.07106) (xy 138.846208 -224.114637)
			(xy 138.861792 -224.161318) (xy 138.869687 -224.209895) (xy 138.870182 -224.234502) (xy 139.19887 -224.234502)
			(xy 139.20283 -224.185448) (xy 139.214607 -224.137664) (xy 139.233898 -224.092388) (xy 139.260201 -224.050792)
			(xy 139.292836 -224.013955) (xy 139.330957 -223.98283) (xy 139.373578 -223.958223) (xy 139.419594 -223.940771)
			(xy 139.467813 -223.930927) (xy 139.516988 -223.928946) (xy 139.565843 -223.934878) (xy 139.613114 -223.94857)
			(xy 139.657576 -223.969668) (xy 139.698079 -223.997624) (xy 139.733572 -224.031716) (xy 139.763137 -224.07106)
			(xy 139.786008 -224.114637) (xy 139.801592 -224.161318) (xy 139.809487 -224.209895) (xy 139.809982 -224.234502)
			(xy 140.138924 -224.234502) (xy 140.142884 -224.185448) (xy 140.154661 -224.137664) (xy 140.173952 -224.092388)
			(xy 140.200255 -224.050792) (xy 140.23289 -224.013955) (xy 140.271011 -223.98283) (xy 140.313632 -223.958223)
			(xy 140.359648 -223.940771) (xy 140.407867 -223.930927) (xy 140.457042 -223.928946) (xy 140.505897 -223.934878)
			(xy 140.553168 -223.94857) (xy 140.59763 -223.969668) (xy 140.638133 -223.997624) (xy 140.673626 -224.031716)
			(xy 140.703191 -224.07106) (xy 140.726062 -224.114637) (xy 140.741646 -224.161318) (xy 140.749541 -224.209895)
			(xy 140.750036 -224.234502) (xy 140.749541 -224.259109) (xy 140.741646 -224.307686) (xy 140.726062 -224.354367)
			(xy 140.703191 -224.397944) (xy 140.673626 -224.437288) (xy 140.638133 -224.47138) (xy 140.59763 -224.499336)
			(xy 140.553168 -224.520434) (xy 140.505897 -224.534126) (xy 140.457042 -224.540058) (xy 140.407867 -224.538077)
			(xy 140.359648 -224.528233) (xy 140.313632 -224.510781) (xy 140.271011 -224.486174) (xy 140.23289 -224.455049)
			(xy 140.200255 -224.418212) (xy 140.173952 -224.376616) (xy 140.154661 -224.33134) (xy 140.142884 -224.283556)
			(xy 140.138924 -224.234502) (xy 139.809982 -224.234502) (xy 139.809487 -224.259109) (xy 139.801592 -224.307686)
			(xy 139.786008 -224.354367) (xy 139.763137 -224.397944) (xy 139.733572 -224.437288) (xy 139.698079 -224.47138)
			(xy 139.657576 -224.499336) (xy 139.613114 -224.520434) (xy 139.565843 -224.534126) (xy 139.516988 -224.540058)
			(xy 139.467813 -224.538077) (xy 139.419594 -224.528233) (xy 139.373578 -224.510781) (xy 139.330957 -224.486174)
			(xy 139.292836 -224.455049) (xy 139.260201 -224.418212) (xy 139.233898 -224.376616) (xy 139.214607 -224.33134)
			(xy 139.20283 -224.283556) (xy 139.19887 -224.234502) (xy 138.870182 -224.234502) (xy 138.869687 -224.259109)
			(xy 138.861792 -224.307686) (xy 138.846208 -224.354367) (xy 138.823337 -224.397944) (xy 138.793772 -224.437288)
			(xy 138.758279 -224.47138) (xy 138.717776 -224.499336) (xy 138.673314 -224.520434) (xy 138.626043 -224.534126)
			(xy 138.577188 -224.540058) (xy 138.528013 -224.538077) (xy 138.479794 -224.528233) (xy 138.433778 -224.510781)
			(xy 138.391157 -224.486174) (xy 138.353036 -224.455049) (xy 138.320401 -224.418212) (xy 138.294098 -224.376616)
			(xy 138.274807 -224.33134) (xy 138.26303 -224.283556) (xy 138.25907 -224.234502) (xy 137.930128 -224.234502)
			(xy 137.929633 -224.259109) (xy 137.921738 -224.307686) (xy 137.906154 -224.354367) (xy 137.883283 -224.397944)
			(xy 137.853718 -224.437288) (xy 137.818225 -224.47138) (xy 137.777722 -224.499336) (xy 137.73326 -224.520434)
			(xy 137.685989 -224.534126) (xy 137.637134 -224.540058) (xy 137.587959 -224.538077) (xy 137.53974 -224.528233)
			(xy 137.493724 -224.510781) (xy 137.451103 -224.486174) (xy 137.412982 -224.455049) (xy 137.380347 -224.418212)
			(xy 137.354044 -224.376616) (xy 137.334753 -224.33134) (xy 137.322976 -224.283556) (xy 137.319016 -224.234502)
			(xy 136.990074 -224.234502) (xy 136.989579 -224.259109) (xy 136.981684 -224.307686) (xy 136.9661 -224.354367)
			(xy 136.943229 -224.397944) (xy 136.913664 -224.437288) (xy 136.878171 -224.47138) (xy 136.837668 -224.499336)
			(xy 136.793206 -224.520434) (xy 136.745935 -224.534126) (xy 136.69708 -224.540058) (xy 136.647905 -224.538077)
			(xy 136.599686 -224.528233) (xy 136.55367 -224.510781) (xy 136.511049 -224.486174) (xy 136.472928 -224.455049)
			(xy 136.440293 -224.418212) (xy 136.41399 -224.376616) (xy 136.394699 -224.33134) (xy 136.382922 -224.283556)
			(xy 136.378962 -224.234502) (xy 136.05002 -224.234502) (xy 136.049555 -224.258741) (xy 136.041897 -224.30661)
			(xy 136.026773 -224.352669) (xy 136.004563 -224.39576) (xy 135.975824 -224.434801) (xy 135.94128 -224.468813)
			(xy 135.901796 -224.49694) (xy 135.858365 -224.518477) (xy 135.812076 -224.532883) (xy 135.788146 -224.536762)
			(xy 135.774938 -224.53854) (xy 135.744712 -224.540064) (xy 135.721594 -224.539641) (xy 135.675886 -224.532679)
			(xy 135.631748 -224.518913) (xy 135.590186 -224.498656) (xy 135.55215 -224.472371) (xy 135.518506 -224.440657)
			(xy 135.50392 -224.422716) (xy 135.503666 -224.422208) (xy 135.499364 -224.417115) (xy 135.488688 -224.409141)
			(xy 135.482584 -224.40646) (xy 135.477504 -224.404174) (xy 135.464296 -224.40265) (xy 135.42518 -224.408238)
			(xy 135.369808 -224.416112) (xy 135.363263 -224.417205) (xy 135.351043 -224.422365) (xy 135.345678 -224.426272)
			(xy 135.340598 -224.430082) (xy 135.332724 -224.44075) (xy 135.330184 -224.4471) (xy 135.319299 -224.473087)
			(xy 135.293092 -224.522966) (xy 135.27786 -224.546668) (xy 135.253984 -224.579942) (xy 135.253984 -224.580196)
			(xy 135.250104 -224.585574) (xy 135.244956 -224.597792) (xy 135.243824 -224.604326) (xy 135.242046 -224.617534)
			(xy 135.280146 -224.711514) (xy 135.282793 -224.717532) (xy 135.290632 -224.728082) (xy 135.29564 -224.732342)
			(xy 135.30072 -224.736152) (xy 135.312912 -224.741486) (xy 135.319516 -224.742502) (xy 135.343351 -224.746496)
			(xy 135.389444 -224.761017) (xy 135.432673 -224.782619) (xy 135.471959 -224.810761) (xy 135.506321 -224.844741)
			(xy 135.534901 -224.88371) (xy 135.556984 -224.926695) (xy 135.572019 -224.972622) (xy 135.579632 -225.020345)
			(xy 135.58012 -225.044508) (xy 135.909062 -225.044508) (xy 135.913022 -224.995454) (xy 135.924799 -224.94767)
			(xy 135.94409 -224.902394) (xy 135.970393 -224.860798) (xy 136.003028 -224.823961) (xy 136.041149 -224.792836)
			(xy 136.08377 -224.768229) (xy 136.129786 -224.750777) (xy 136.178005 -224.740933) (xy 136.22718 -224.738952)
			(xy 136.276035 -224.744884) (xy 136.323306 -224.758576) (xy 136.367768 -224.779674) (xy 136.408271 -224.80763)
			(xy 136.443764 -224.841722) (xy 136.473329 -224.881066) (xy 136.4962 -224.924643) (xy 136.511784 -224.971324)
			(xy 136.519679 -225.019901) (xy 136.520174 -225.044508) (xy 137.788916 -225.044508) (xy 137.792876 -224.995454)
			(xy 137.804653 -224.94767) (xy 137.823944 -224.902394) (xy 137.850247 -224.860798) (xy 137.882882 -224.823961)
			(xy 137.921003 -224.792836) (xy 137.963624 -224.768229) (xy 138.00964 -224.750777) (xy 138.057859 -224.740933)
			(xy 138.107034 -224.738952) (xy 138.155889 -224.744884) (xy 138.20316 -224.758576) (xy 138.247622 -224.779674)
			(xy 138.288125 -224.80763) (xy 138.323618 -224.841722) (xy 138.353183 -224.881066) (xy 138.376054 -224.924643)
			(xy 138.391638 -224.971324) (xy 138.399533 -225.019901) (xy 138.400028 -225.044508) (xy 138.72897 -225.044508)
			(xy 138.73293 -224.995454) (xy 138.744707 -224.94767) (xy 138.763998 -224.902394) (xy 138.790301 -224.860798)
			(xy 138.822936 -224.823961) (xy 138.861057 -224.792836) (xy 138.903678 -224.768229) (xy 138.949694 -224.750777)
			(xy 138.997913 -224.740933) (xy 139.047088 -224.738952) (xy 139.095943 -224.744884) (xy 139.143214 -224.758576)
			(xy 139.187676 -224.779674) (xy 139.228179 -224.80763) (xy 139.263672 -224.841722) (xy 139.293237 -224.881066)
			(xy 139.316108 -224.924643) (xy 139.331692 -224.971324) (xy 139.339587 -225.019901) (xy 139.340082 -225.044508)
			(xy 139.669024 -225.044508) (xy 139.672984 -224.995454) (xy 139.684761 -224.94767) (xy 139.704052 -224.902394)
			(xy 139.730355 -224.860798) (xy 139.76299 -224.823961) (xy 139.801111 -224.792836) (xy 139.843732 -224.768229)
			(xy 139.889748 -224.750777) (xy 139.937967 -224.740933) (xy 139.987142 -224.738952) (xy 140.035997 -224.744884)
			(xy 140.083268 -224.758576) (xy 140.12773 -224.779674) (xy 140.168233 -224.80763) (xy 140.203726 -224.841722)
			(xy 140.233291 -224.881066) (xy 140.256162 -224.924643) (xy 140.271746 -224.971324) (xy 140.279641 -225.019901)
			(xy 140.280136 -225.044508) (xy 140.279641 -225.069115) (xy 140.271746 -225.117692) (xy 140.256162 -225.164373)
			(xy 140.233291 -225.20795) (xy 140.203726 -225.247294) (xy 140.168233 -225.281386) (xy 140.12773 -225.309342)
			(xy 140.083268 -225.33044) (xy 140.035997 -225.344132) (xy 139.987142 -225.350064) (xy 139.937967 -225.348083)
			(xy 139.889748 -225.338239) (xy 139.843732 -225.320787) (xy 139.801111 -225.29618) (xy 139.76299 -225.265055)
			(xy 139.730355 -225.228218) (xy 139.704052 -225.186622) (xy 139.684761 -225.141346) (xy 139.672984 -225.093562)
			(xy 139.669024 -225.044508) (xy 139.340082 -225.044508) (xy 139.339587 -225.069115) (xy 139.331692 -225.117692)
			(xy 139.316108 -225.164373) (xy 139.293237 -225.20795) (xy 139.263672 -225.247294) (xy 139.228179 -225.281386)
			(xy 139.187676 -225.309342) (xy 139.143214 -225.33044) (xy 139.095943 -225.344132) (xy 139.047088 -225.350064)
			(xy 138.997913 -225.348083) (xy 138.949694 -225.338239) (xy 138.903678 -225.320787) (xy 138.861057 -225.29618)
			(xy 138.822936 -225.265055) (xy 138.790301 -225.228218) (xy 138.763998 -225.186622) (xy 138.744707 -225.141346)
			(xy 138.73293 -225.093562) (xy 138.72897 -225.044508) (xy 138.400028 -225.044508) (xy 138.399533 -225.069115)
			(xy 138.391638 -225.117692) (xy 138.376054 -225.164373) (xy 138.353183 -225.20795) (xy 138.323618 -225.247294)
			(xy 138.288125 -225.281386) (xy 138.247622 -225.309342) (xy 138.20316 -225.33044) (xy 138.155889 -225.344132)
			(xy 138.107034 -225.350064) (xy 138.057859 -225.348083) (xy 138.00964 -225.338239) (xy 137.963624 -225.320787)
			(xy 137.921003 -225.29618) (xy 137.882882 -225.265055) (xy 137.850247 -225.228218) (xy 137.823944 -225.186622)
			(xy 137.804653 -225.141346) (xy 137.792876 -225.093562) (xy 137.788916 -225.044508) (xy 136.520174 -225.044508)
			(xy 136.519679 -225.069115) (xy 136.511784 -225.117692) (xy 136.4962 -225.164373) (xy 136.473329 -225.20795)
			(xy 136.443764 -225.247294) (xy 136.408271 -225.281386) (xy 136.367768 -225.309342) (xy 136.323306 -225.33044)
			(xy 136.276035 -225.344132) (xy 136.22718 -225.350064) (xy 136.178005 -225.348083) (xy 136.129786 -225.338239)
			(xy 136.08377 -225.320787) (xy 136.041149 -225.29618) (xy 136.003028 -225.265055) (xy 135.970393 -225.228218)
			(xy 135.94409 -225.186622) (xy 135.924799 -225.141346) (xy 135.913022 -225.093562) (xy 135.909062 -225.044508)
			(xy 135.58012 -225.044508) (xy 135.579649 -225.068499) (xy 135.572142 -225.115891) (xy 135.557314 -225.161524)
			(xy 135.53553 -225.204277) (xy 135.507327 -225.243095) (xy 135.473398 -225.277024) (xy 135.43458 -225.305228)
			(xy 135.391828 -225.327012) (xy 135.346194 -225.341841) (xy 135.298803 -225.349348) (xy 135.274812 -225.349816)
			(xy 135.251036 -225.349363) (xy 135.204057 -225.341992) (xy 135.15879 -225.327427) (xy 135.116328 -225.30602)
			(xy 135.077698 -225.278289) (xy 135.043835 -225.244903) (xy 135.015558 -225.206672) (xy 134.993549 -225.164518)
			(xy 134.978343 -225.119462) (xy 134.970305 -225.072594) (xy 134.969504 -225.048826) (xy 134.969504 -225.044508)
			(xy 134.970109 -225.016086) (xy 134.980597 -224.96022) (xy 134.990332 -224.93351) (xy 134.992872 -224.92716)
			(xy 134.994396 -224.913952) (xy 134.99338 -224.907602) (xy 134.992167 -224.901175) (xy 134.986894 -224.88921)
			(xy 134.982966 -224.88398) (xy 134.92861 -224.814892) (xy 134.924398 -224.809786) (xy 134.913843 -224.801805)
			(xy 134.907782 -224.799144) (xy 134.90194 -224.796858) (xy 134.88924 -224.79508) (xy 134.882128 -224.796096)
			(xy 134.867904 -224.797874) (xy 134.867396 -224.797874) (xy 134.85622 -224.79889) (xy 134.847076 -224.799906)
			(xy 134.839456 -224.803462) (xy 134.835473 -224.805441) (xy 134.828191 -224.810546) (xy 134.824978 -224.813622)
			(xy 134.779766 -224.858834) (xy 134.772369 -224.865682) (xy 134.75377 -224.873415) (xy 134.743698 -224.87382)
			(xy 134.735824 -224.87382) (xy 134.725103 -224.874245) (xy 134.705509 -224.88294) (xy 134.697978 -224.890584)
			(xy 134.686802 -224.903792) (xy 134.686802 -224.9043) (xy 134.64667 -224.951798) (xy 134.643254 -224.95604)
			(xy 134.63812 -224.965645) (xy 134.63651 -224.970848) (xy 134.633716 -224.981262) (xy 134.635748 -224.992692)
			(xy 134.637786 -225.005549) (xy 134.639949 -225.031491) (xy 134.640066 -225.044508) (xy 134.639544 -225.069763)
			(xy 134.631231 -225.119585) (xy 134.61483 -225.167359) (xy 134.590789 -225.211782) (xy 134.559765 -225.251642)
			(xy 134.522603 -225.285852) (xy 134.480317 -225.313478) (xy 134.434061 -225.333768) (xy 134.385096 -225.346168)
			(xy 134.334758 -225.350339) (xy 134.28442 -225.346168) (xy 134.235455 -225.333768) (xy 134.189199 -225.313478)
			(xy 134.146913 -225.285852) (xy 134.109751 -225.251642) (xy 134.078727 -225.211782) (xy 134.054686 -225.167359)
			(xy 134.038285 -225.119585) (xy 134.029972 -225.069763) (xy 134.02945 -225.044508) (xy 134.029551 -225.031491)
			(xy 134.03171 -225.005546) (xy 134.033768 -224.992692) (xy 134.0358 -224.981262) (xy 134.033006 -224.970848)
			(xy 134.031403 -224.965641) (xy 134.026273 -224.956033) (xy 134.022846 -224.951798) (xy 133.982714 -224.9043)
			(xy 133.982714 -224.903792) (xy 133.971538 -224.890584) (xy 133.965398 -224.884304) (xy 133.949936 -224.875999)
			(xy 133.941312 -224.874328) (xy 133.933946 -224.87382) (xy 133.795516 -224.87382) (xy 133.78815 -224.874328)
			(xy 133.779533 -224.87601) (xy 133.764086 -224.884329) (xy 133.757924 -224.890584) (xy 133.746748 -224.903792)
			(xy 133.746748 -224.9043) (xy 133.706616 -224.951798) (xy 133.703203 -224.956042) (xy 133.698075 -224.965648)
			(xy 133.696456 -224.970848) (xy 133.693662 -224.981262) (xy 133.695694 -224.992692) (xy 133.697732 -225.005549)
			(xy 133.699894 -225.031491) (xy 133.700012 -225.044508) (xy 133.69949 -225.069763) (xy 133.691177 -225.119585)
			(xy 133.674776 -225.167359) (xy 133.650735 -225.211782) (xy 133.619711 -225.251642) (xy 133.582549 -225.285852)
			(xy 133.540263 -225.313478) (xy 133.494007 -225.333768) (xy 133.445042 -225.346168) (xy 133.394704 -225.350339)
			(xy 133.344366 -225.346168) (xy 133.295401 -225.333768) (xy 133.249145 -225.313478) (xy 133.206859 -225.285852)
			(xy 133.169697 -225.251642) (xy 133.138673 -225.211782) (xy 133.114632 -225.167359) (xy 133.098231 -225.119585)
			(xy 133.089918 -225.069763) (xy 133.089396 -225.044508) (xy 133.089497 -225.031491) (xy 133.091656 -225.005546)
			(xy 133.093714 -224.992692) (xy 133.095746 -224.981262) (xy 133.092952 -224.970848) (xy 133.091351 -224.96564)
			(xy 133.086225 -224.956029) (xy 133.082792 -224.951798) (xy 133.04266 -224.9043) (xy 133.04266 -224.903792)
			(xy 133.031484 -224.890584) (xy 133.025346 -224.884298) (xy 133.009887 -224.87598) (xy 133.001258 -224.874328)
			(xy 132.993892 -224.87382) (xy 132.859526 -224.87382) (xy 132.848481 -224.87442) (xy 132.828459 -224.883763)
			(xy 132.820918 -224.891854) (xy 132.76326 -224.959926) (xy 132.760974 -224.968562) (xy 132.765344 -224.987245)
			(xy 132.770052 -225.025324) (xy 132.770372 -225.044508) (xy 132.769885 -225.069318) (xy 132.762123 -225.118326)
			(xy 132.74679 -225.165516) (xy 132.724263 -225.209727) (xy 132.695098 -225.24987) (xy 132.660012 -225.284956)
			(xy 132.619869 -225.314121) (xy 132.575658 -225.336648) (xy 132.528468 -225.351981) (xy 132.47946 -225.359743)
			(xy 132.42984 -225.359743) (xy 132.380832 -225.351981) (xy 132.333642 -225.336648) (xy 132.289431 -225.314121)
			(xy 132.249288 -225.284956) (xy 132.214202 -225.24987) (xy 132.185037 -225.209727) (xy 132.16251 -225.165516)
			(xy 132.147177 -225.118326) (xy 132.139415 -225.069318) (xy 132.138928 -225.044508) (xy 132.139241 -225.025323)
			(xy 132.143951 -224.987244) (xy 132.148326 -224.968562) (xy 132.14604 -224.959926) (xy 132.088382 -224.891854)
			(xy 132.080844 -224.883755) (xy 132.060822 -224.874396) (xy 132.049774 -224.87382) (xy 131.915662 -224.87382)
			(xy 131.908296 -224.874328) (xy 131.899675 -224.876003) (xy 131.884218 -224.884313) (xy 131.87807 -224.890584)
			(xy 131.866894 -224.903792) (xy 131.866894 -224.9043) (xy 131.826762 -224.951798) (xy 131.823346 -224.956041)
			(xy 131.818214 -224.965646) (xy 131.816602 -224.970848) (xy 131.813808 -224.981262) (xy 131.81584 -224.992692)
			(xy 131.817878 -225.005549) (xy 131.820041 -225.031491) (xy 131.820158 -225.044508) (xy 131.819636 -225.069763)
			(xy 131.811323 -225.119585) (xy 131.794922 -225.167359) (xy 131.770881 -225.211782) (xy 131.739857 -225.251642)
			(xy 131.702695 -225.285852) (xy 131.660409 -225.313478) (xy 131.614153 -225.333768) (xy 131.565188 -225.346168)
			(xy 131.51485 -225.350339) (xy 131.464512 -225.346168) (xy 131.415547 -225.333768) (xy 131.369291 -225.313478)
			(xy 131.327005 -225.285852) (xy 131.289843 -225.251642) (xy 131.258819 -225.211782) (xy 131.234778 -225.167359)
			(xy 131.218377 -225.119585) (xy 131.210064 -225.069763) (xy 131.209542 -225.044508) (xy 131.209643 -225.031491)
			(xy 131.211802 -225.005546) (xy 131.21386 -224.992692) (xy 131.215892 -224.981262) (xy 131.213098 -224.970848)
			(xy 131.211495 -224.965642) (xy 131.206365 -224.956033) (xy 131.202938 -224.951798) (xy 131.162806 -224.9043)
			(xy 131.162806 -224.903792) (xy 131.15163 -224.890584) (xy 131.145489 -224.884305) (xy 131.130027 -224.876003)
			(xy 131.121404 -224.874328) (xy 131.114038 -224.87382) (xy 130.975608 -224.87382) (xy 130.968242 -224.874328)
			(xy 130.959626 -224.876011) (xy 130.944181 -224.884332) (xy 130.938016 -224.890584) (xy 130.92684 -224.903792)
			(xy 130.92684 -224.9043) (xy 130.886708 -224.951798) (xy 130.88329 -224.956039) (xy 130.878153 -224.965643)
			(xy 130.876548 -224.970848) (xy 130.873754 -224.981262) (xy 130.875786 -224.992692) (xy 130.877824 -225.005549)
			(xy 130.879986 -225.031491) (xy 130.880104 -225.044508) (xy 130.879582 -225.069763) (xy 130.871269 -225.119585)
			(xy 130.854868 -225.167359) (xy 130.830827 -225.211782) (xy 130.799803 -225.251642) (xy 130.762641 -225.285852)
			(xy 130.720355 -225.313478) (xy 130.674099 -225.333768) (xy 130.625134 -225.346168) (xy 130.574796 -225.350339)
			(xy 130.524458 -225.346168) (xy 130.475493 -225.333768) (xy 130.429237 -225.313478) (xy 130.386951 -225.285852)
			(xy 130.349789 -225.251642) (xy 130.318765 -225.211782) (xy 130.294724 -225.167359) (xy 130.278323 -225.119585)
			(xy 130.27001 -225.069763) (xy 130.269488 -225.044508) (xy 130.269589 -225.031491) (xy 130.271748 -225.005546)
			(xy 130.273806 -224.992692) (xy 130.275838 -224.981262) (xy 130.273044 -224.970848) (xy 130.271443 -224.96564)
			(xy 130.266316 -224.956029) (xy 130.262884 -224.951798) (xy 130.222752 -224.9043) (xy 130.222752 -224.903792)
			(xy 130.211576 -224.890584) (xy 130.205438 -224.884299) (xy 130.189978 -224.875983) (xy 130.18135 -224.874328)
			(xy 130.173984 -224.87382) (xy 129.986786 -224.87382) (xy 129.980775 -224.873983) (xy 129.96909 -224.876801)
			(xy 129.963672 -224.879408) (xy 129.960198 -224.881248) (xy 129.953821 -224.885843) (xy 129.950972 -224.888552)
			(xy 129.94132 -224.898204) (xy 129.936566 -224.903351) (xy 129.929751 -224.915587) (xy 129.927858 -224.922334)
			(xy 129.92735 -224.924366) (xy 129.934208 -224.94494) (xy 129.941764 -224.969137) (xy 129.949931 -225.019164)
			(xy 129.950464 -225.044508) (xy 129.950001 -225.069312) (xy 129.942236 -225.118308) (xy 129.926898 -225.165484)
			(xy 129.904365 -225.209679) (xy 129.875192 -225.249802) (xy 129.8401 -225.284865) (xy 129.799952 -225.314004)
			(xy 129.755738 -225.3365) (xy 129.708549 -225.351798) (xy 129.659546 -225.359522) (xy 129.634742 -225.359976)
			(xy 129.607795 -225.359467) (xy 129.554671 -225.350394) (xy 129.529078 -225.341942) (xy 129.522117 -225.339726)
			(xy 129.507535 -225.338961) (xy 129.500376 -225.340418) (xy 129.498598 -225.340926) (xy 129.36474 -225.474784)
			(xy 129.363216 -225.476308) (xy 129.361438 -225.478594) (xy 129.356402 -225.485356) (xy 129.350581 -225.501169)
			(xy 129.350008 -225.509582) (xy 129.351024 -225.542602) (xy 129.352548 -225.596704) (xy 129.355088 -225.602292)
			(xy 129.36982 -225.614484) (xy 129.390211 -225.632637) (xy 129.425029 -225.67468) (xy 129.452094 -225.722087)
			(xy 129.470597 -225.773445) (xy 129.479988 -225.82722) (xy 129.480564 -225.854514) (xy 129.798838 -225.854514)
			(xy 129.802798 -225.80546) (xy 129.814575 -225.757676) (xy 129.833866 -225.7124) (xy 129.860169 -225.670804)
			(xy 129.892804 -225.633967) (xy 129.930925 -225.602842) (xy 129.973546 -225.578235) (xy 130.019562 -225.560783)
			(xy 130.067781 -225.550939) (xy 130.116956 -225.548958) (xy 130.165811 -225.55489) (xy 130.213082 -225.568582)
			(xy 130.257544 -225.58968) (xy 130.298047 -225.617636) (xy 130.33354 -225.651728) (xy 130.363105 -225.691072)
			(xy 130.385976 -225.734649) (xy 130.40156 -225.78133) (xy 130.409455 -225.829907) (xy 130.40995 -225.854514)
			(xy 130.728461 -225.854514) (xy 130.732556 -225.803786) (xy 130.744735 -225.754372) (xy 130.764683 -225.707552)
			(xy 130.791884 -225.664538) (xy 130.825632 -225.626444) (xy 130.865054 -225.594257) (xy 130.909128 -225.568811)
			(xy 130.956714 -225.550764) (xy 131.006578 -225.540584) (xy 131.05743 -225.538535) (xy 131.107951 -225.544669)
			(xy 131.156835 -225.558829) (xy 131.202814 -225.580646) (xy 131.244698 -225.609556) (xy 131.281402 -225.644811)
			(xy 131.311975 -225.685497) (xy 131.335626 -225.73056) (xy 131.351742 -225.778834) (xy 131.359906 -225.829068)
			(xy 131.360418 -225.854514) (xy 131.678946 -225.854514) (xy 131.682906 -225.80546) (xy 131.694683 -225.757676)
			(xy 131.713974 -225.7124) (xy 131.740277 -225.670804) (xy 131.772912 -225.633967) (xy 131.811033 -225.602842)
			(xy 131.853654 -225.578235) (xy 131.89967 -225.560783) (xy 131.947889 -225.550939) (xy 131.997064 -225.548958)
			(xy 132.045919 -225.55489) (xy 132.09319 -225.568582) (xy 132.137652 -225.58968) (xy 132.178155 -225.617636)
			(xy 132.213648 -225.651728) (xy 132.243213 -225.691072) (xy 132.266084 -225.734649) (xy 132.281668 -225.78133)
			(xy 132.289563 -225.829907) (xy 132.290058 -225.854514) (xy 132.608569 -225.854514) (xy 132.612664 -225.803786)
			(xy 132.624843 -225.754372) (xy 132.644791 -225.707552) (xy 132.671992 -225.664538) (xy 132.70574 -225.626444)
			(xy 132.745162 -225.594257) (xy 132.789236 -225.568811) (xy 132.836822 -225.550764) (xy 132.886686 -225.540584)
			(xy 132.937538 -225.538535) (xy 132.988059 -225.544669) (xy 133.036943 -225.558829) (xy 133.082922 -225.580646)
			(xy 133.124806 -225.609556) (xy 133.16151 -225.644811) (xy 133.192083 -225.685497) (xy 133.215734 -225.73056)
			(xy 133.23185 -225.778834) (xy 133.240014 -225.829068) (xy 133.240526 -225.854514) (xy 133.559054 -225.854514)
			(xy 133.563014 -225.80546) (xy 133.574791 -225.757676) (xy 133.594082 -225.7124) (xy 133.620385 -225.670804)
			(xy 133.65302 -225.633967) (xy 133.691141 -225.602842) (xy 133.733762 -225.578235) (xy 133.779778 -225.560783)
			(xy 133.827997 -225.550939) (xy 133.877172 -225.548958) (xy 133.926027 -225.55489) (xy 133.973298 -225.568582)
			(xy 134.01776 -225.58968) (xy 134.058263 -225.617636) (xy 134.093756 -225.651728) (xy 134.123321 -225.691072)
			(xy 134.146192 -225.734649) (xy 134.161776 -225.78133) (xy 134.169671 -225.829907) (xy 134.170166 -225.854514)
			(xy 134.498854 -225.854514) (xy 134.502814 -225.80546) (xy 134.514591 -225.757676) (xy 134.533882 -225.7124)
			(xy 134.560185 -225.670804) (xy 134.59282 -225.633967) (xy 134.630941 -225.602842) (xy 134.673562 -225.578235)
			(xy 134.719578 -225.560783) (xy 134.767797 -225.550939) (xy 134.816972 -225.548958) (xy 134.865827 -225.55489)
			(xy 134.913098 -225.568582) (xy 134.95756 -225.58968) (xy 134.998063 -225.617636) (xy 135.033556 -225.651728)
			(xy 135.063121 -225.691072) (xy 135.085992 -225.734649) (xy 135.101576 -225.78133) (xy 135.109471 -225.829907)
			(xy 135.109966 -225.854514) (xy 135.438908 -225.854514) (xy 135.442868 -225.80546) (xy 135.454645 -225.757676)
			(xy 135.473936 -225.7124) (xy 135.500239 -225.670804) (xy 135.532874 -225.633967) (xy 135.570995 -225.602842)
			(xy 135.613616 -225.578235) (xy 135.659632 -225.560783) (xy 135.707851 -225.550939) (xy 135.757026 -225.548958)
			(xy 135.805881 -225.55489) (xy 135.853152 -225.568582) (xy 135.897614 -225.58968) (xy 135.938117 -225.617636)
			(xy 135.97361 -225.651728) (xy 136.003175 -225.691072) (xy 136.026046 -225.734649) (xy 136.04163 -225.78133)
			(xy 136.049525 -225.829907) (xy 136.05002 -225.854514) (xy 136.378962 -225.854514) (xy 136.382922 -225.80546)
			(xy 136.394699 -225.757676) (xy 136.41399 -225.7124) (xy 136.440293 -225.670804) (xy 136.472928 -225.633967)
			(xy 136.511049 -225.602842) (xy 136.55367 -225.578235) (xy 136.599686 -225.560783) (xy 136.647905 -225.550939)
			(xy 136.69708 -225.548958) (xy 136.745935 -225.55489) (xy 136.793206 -225.568582) (xy 136.837668 -225.58968)
			(xy 136.878171 -225.617636) (xy 136.913664 -225.651728) (xy 136.943229 -225.691072) (xy 136.9661 -225.734649)
			(xy 136.981684 -225.78133) (xy 136.989579 -225.829907) (xy 136.990074 -225.854514) (xy 137.319016 -225.854514)
			(xy 137.322976 -225.80546) (xy 137.334753 -225.757676) (xy 137.354044 -225.7124) (xy 137.380347 -225.670804)
			(xy 137.412982 -225.633967) (xy 137.451103 -225.602842) (xy 137.493724 -225.578235) (xy 137.53974 -225.560783)
			(xy 137.587959 -225.550939) (xy 137.637134 -225.548958) (xy 137.685989 -225.55489) (xy 137.73326 -225.568582)
			(xy 137.777722 -225.58968) (xy 137.818225 -225.617636) (xy 137.853718 -225.651728) (xy 137.883283 -225.691072)
			(xy 137.906154 -225.734649) (xy 137.921738 -225.78133) (xy 137.929633 -225.829907) (xy 137.930128 -225.854514)
			(xy 138.25907 -225.854514) (xy 138.26303 -225.80546) (xy 138.274807 -225.757676) (xy 138.294098 -225.7124)
			(xy 138.320401 -225.670804) (xy 138.353036 -225.633967) (xy 138.391157 -225.602842) (xy 138.433778 -225.578235)
			(xy 138.479794 -225.560783) (xy 138.528013 -225.550939) (xy 138.577188 -225.548958) (xy 138.626043 -225.55489)
			(xy 138.673314 -225.568582) (xy 138.717776 -225.58968) (xy 138.758279 -225.617636) (xy 138.793772 -225.651728)
			(xy 138.823337 -225.691072) (xy 138.846208 -225.734649) (xy 138.861792 -225.78133) (xy 138.869687 -225.829907)
			(xy 138.870182 -225.854514) (xy 139.19887 -225.854514) (xy 139.20283 -225.80546) (xy 139.214607 -225.757676)
			(xy 139.233898 -225.7124) (xy 139.260201 -225.670804) (xy 139.292836 -225.633967) (xy 139.330957 -225.602842)
			(xy 139.373578 -225.578235) (xy 139.419594 -225.560783) (xy 139.467813 -225.550939) (xy 139.516988 -225.548958)
			(xy 139.565843 -225.55489) (xy 139.613114 -225.568582) (xy 139.657576 -225.58968) (xy 139.698079 -225.617636)
			(xy 139.733572 -225.651728) (xy 139.763137 -225.691072) (xy 139.786008 -225.734649) (xy 139.801592 -225.78133)
			(xy 139.809487 -225.829907) (xy 139.809982 -225.854514) (xy 139.809487 -225.879121) (xy 139.801592 -225.927698)
			(xy 139.786008 -225.974379) (xy 139.763137 -226.017956) (xy 139.733572 -226.0573) (xy 139.698079 -226.091392)
			(xy 139.657576 -226.119348) (xy 139.613114 -226.140446) (xy 139.565843 -226.154138) (xy 139.516988 -226.16007)
			(xy 139.467813 -226.158089) (xy 139.419594 -226.148245) (xy 139.373578 -226.130793) (xy 139.330957 -226.106186)
			(xy 139.292836 -226.075061) (xy 139.260201 -226.038224) (xy 139.233898 -225.996628) (xy 139.214607 -225.951352)
			(xy 139.20283 -225.903568) (xy 139.19887 -225.854514) (xy 138.870182 -225.854514) (xy 138.869687 -225.879121)
			(xy 138.861792 -225.927698) (xy 138.846208 -225.974379) (xy 138.823337 -226.017956) (xy 138.793772 -226.0573)
			(xy 138.758279 -226.091392) (xy 138.717776 -226.119348) (xy 138.673314 -226.140446) (xy 138.626043 -226.154138)
			(xy 138.577188 -226.16007) (xy 138.528013 -226.158089) (xy 138.479794 -226.148245) (xy 138.433778 -226.130793)
			(xy 138.391157 -226.106186) (xy 138.353036 -226.075061) (xy 138.320401 -226.038224) (xy 138.294098 -225.996628)
			(xy 138.274807 -225.951352) (xy 138.26303 -225.903568) (xy 138.25907 -225.854514) (xy 137.930128 -225.854514)
			(xy 137.929633 -225.879121) (xy 137.921738 -225.927698) (xy 137.906154 -225.974379) (xy 137.883283 -226.017956)
			(xy 137.853718 -226.0573) (xy 137.818225 -226.091392) (xy 137.777722 -226.119348) (xy 137.73326 -226.140446)
			(xy 137.685989 -226.154138) (xy 137.637134 -226.16007) (xy 137.587959 -226.158089) (xy 137.53974 -226.148245)
			(xy 137.493724 -226.130793) (xy 137.451103 -226.106186) (xy 137.412982 -226.075061) (xy 137.380347 -226.038224)
			(xy 137.354044 -225.996628) (xy 137.334753 -225.951352) (xy 137.322976 -225.903568) (xy 137.319016 -225.854514)
			(xy 136.990074 -225.854514) (xy 136.989579 -225.879121) (xy 136.981684 -225.927698) (xy 136.9661 -225.974379)
			(xy 136.943229 -226.017956) (xy 136.913664 -226.0573) (xy 136.878171 -226.091392) (xy 136.837668 -226.119348)
			(xy 136.793206 -226.140446) (xy 136.745935 -226.154138) (xy 136.69708 -226.16007) (xy 136.647905 -226.158089)
			(xy 136.599686 -226.148245) (xy 136.55367 -226.130793) (xy 136.511049 -226.106186) (xy 136.472928 -226.075061)
			(xy 136.440293 -226.038224) (xy 136.41399 -225.996628) (xy 136.394699 -225.951352) (xy 136.382922 -225.903568)
			(xy 136.378962 -225.854514) (xy 136.05002 -225.854514) (xy 136.049525 -225.879121) (xy 136.04163 -225.927698)
			(xy 136.026046 -225.974379) (xy 136.003175 -226.017956) (xy 135.97361 -226.0573) (xy 135.938117 -226.091392)
			(xy 135.897614 -226.119348) (xy 135.853152 -226.140446) (xy 135.805881 -226.154138) (xy 135.757026 -226.16007)
			(xy 135.707851 -226.158089) (xy 135.659632 -226.148245) (xy 135.613616 -226.130793) (xy 135.570995 -226.106186)
			(xy 135.532874 -226.075061) (xy 135.500239 -226.038224) (xy 135.473936 -225.996628) (xy 135.454645 -225.951352)
			(xy 135.442868 -225.903568) (xy 135.438908 -225.854514) (xy 135.109966 -225.854514) (xy 135.109471 -225.879121)
			(xy 135.101576 -225.927698) (xy 135.085992 -225.974379) (xy 135.063121 -226.017956) (xy 135.033556 -226.0573)
			(xy 134.998063 -226.091392) (xy 134.95756 -226.119348) (xy 134.913098 -226.140446) (xy 134.865827 -226.154138)
			(xy 134.816972 -226.16007) (xy 134.767797 -226.158089) (xy 134.719578 -226.148245) (xy 134.673562 -226.130793)
			(xy 134.630941 -226.106186) (xy 134.59282 -226.075061) (xy 134.560185 -226.038224) (xy 134.533882 -225.996628)
			(xy 134.514591 -225.951352) (xy 134.502814 -225.903568) (xy 134.498854 -225.854514) (xy 134.170166 -225.854514)
			(xy 134.169671 -225.879121) (xy 134.161776 -225.927698) (xy 134.146192 -225.974379) (xy 134.123321 -226.017956)
			(xy 134.093756 -226.0573) (xy 134.058263 -226.091392) (xy 134.01776 -226.119348) (xy 133.973298 -226.140446)
			(xy 133.926027 -226.154138) (xy 133.877172 -226.16007) (xy 133.827997 -226.158089) (xy 133.779778 -226.148245)
			(xy 133.733762 -226.130793) (xy 133.691141 -226.106186) (xy 133.65302 -226.075061) (xy 133.620385 -226.038224)
			(xy 133.594082 -225.996628) (xy 133.574791 -225.951352) (xy 133.563014 -225.903568) (xy 133.559054 -225.854514)
			(xy 133.240526 -225.854514) (xy 133.240014 -225.87996) (xy 133.23185 -225.930194) (xy 133.215734 -225.978468)
			(xy 133.192083 -226.023531) (xy 133.16151 -226.064217) (xy 133.124806 -226.099472) (xy 133.082922 -226.128382)
			(xy 133.036943 -226.150199) (xy 132.988059 -226.164359) (xy 132.937538 -226.170493) (xy 132.886686 -226.168444)
			(xy 132.836822 -226.158264) (xy 132.789236 -226.140217) (xy 132.745162 -226.114771) (xy 132.70574 -226.082584)
			(xy 132.671992 -226.04449) (xy 132.644791 -226.001476) (xy 132.624843 -225.954656) (xy 132.612664 -225.905242)
			(xy 132.608569 -225.854514) (xy 132.290058 -225.854514) (xy 132.289563 -225.879121) (xy 132.281668 -225.927698)
			(xy 132.266084 -225.974379) (xy 132.243213 -226.017956) (xy 132.213648 -226.0573) (xy 132.178155 -226.091392)
			(xy 132.137652 -226.119348) (xy 132.09319 -226.140446) (xy 132.045919 -226.154138) (xy 131.997064 -226.16007)
			(xy 131.947889 -226.158089) (xy 131.89967 -226.148245) (xy 131.853654 -226.130793) (xy 131.811033 -226.106186)
			(xy 131.772912 -226.075061) (xy 131.740277 -226.038224) (xy 131.713974 -225.996628) (xy 131.694683 -225.951352)
			(xy 131.682906 -225.903568) (xy 131.678946 -225.854514) (xy 131.360418 -225.854514) (xy 131.359906 -225.87996)
			(xy 131.351742 -225.930194) (xy 131.335626 -225.978468) (xy 131.311975 -226.023531) (xy 131.281402 -226.064217)
			(xy 131.244698 -226.099472) (xy 131.202814 -226.128382) (xy 131.156835 -226.150199) (xy 131.107951 -226.164359)
			(xy 131.05743 -226.170493) (xy 131.006578 -226.168444) (xy 130.956714 -226.158264) (xy 130.909128 -226.140217)
			(xy 130.865054 -226.114771) (xy 130.825632 -226.082584) (xy 130.791884 -226.04449) (xy 130.764683 -226.001476)
			(xy 130.744735 -225.954656) (xy 130.732556 -225.905242) (xy 130.728461 -225.854514) (xy 130.40995 -225.854514)
			(xy 130.409455 -225.879121) (xy 130.40156 -225.927698) (xy 130.385976 -225.974379) (xy 130.363105 -226.017956)
			(xy 130.33354 -226.0573) (xy 130.298047 -226.091392) (xy 130.257544 -226.119348) (xy 130.213082 -226.140446)
			(xy 130.165811 -226.154138) (xy 130.116956 -226.16007) (xy 130.067781 -226.158089) (xy 130.019562 -226.148245)
			(xy 129.973546 -226.130793) (xy 129.930925 -226.106186) (xy 129.892804 -226.075061) (xy 129.860169 -226.038224)
			(xy 129.833866 -225.996628) (xy 129.814575 -225.951352) (xy 129.802798 -225.903568) (xy 129.798838 -225.854514)
			(xy 129.480564 -225.854514) (xy 129.480076 -225.879324) (xy 129.472313 -225.928333) (xy 129.456979 -225.975524)
			(xy 129.434452 -226.019736) (xy 129.405287 -226.059881) (xy 129.370202 -226.094969) (xy 129.33006 -226.124137)
			(xy 129.28585 -226.146668) (xy 129.23866 -226.162006) (xy 129.189652 -226.169774) (xy 129.164842 -226.170236)
			(xy 129.13755 -226.169653) (xy 129.08378 -226.160254) (xy 129.032428 -226.141745) (xy 128.985026 -226.114679)
			(xy 128.942987 -226.079862) (xy 128.924812 -226.059492) (xy 128.91262 -226.04476) (xy 128.907032 -226.04222)
			(xy 128.82245 -226.03968) (xy 128.811989 -226.039867) (xy 128.792571 -226.047598) (xy 128.784858 -226.054666)
			(xy 128.652524 -226.187) (xy 128.651254 -226.18827) (xy 128.645619 -226.194868) (xy 128.638749 -226.210789)
			(xy 128.637565 -226.228089) (xy 128.63957 -226.23653) (xy 128.64084 -226.240594) (xy 128.673352 -226.327208)
			(xy 128.676071 -226.333923) (xy 128.684713 -226.345542) (xy 128.69037 -226.350068) (xy 128.695958 -226.354386)
			(xy 128.709674 -226.359466) (xy 128.71704 -226.359974) (xy 128.742353 -226.362339) (xy 128.791737 -226.374408)
			(xy 128.838439 -226.394492) (xy 128.881169 -226.422035) (xy 128.918745 -226.456276) (xy 128.950129 -226.49627)
			(xy 128.974453 -226.54091) (xy 128.991046 -226.588963) (xy 128.999448 -226.639101) (xy 128.999996 -226.66452)
			(xy 129.318507 -226.66452) (xy 129.322602 -226.613792) (xy 129.334781 -226.564378) (xy 129.354729 -226.517558)
			(xy 129.38193 -226.474544) (xy 129.415678 -226.43645) (xy 129.4551 -226.404263) (xy 129.499174 -226.378817)
			(xy 129.54676 -226.36077) (xy 129.596624 -226.35059) (xy 129.647476 -226.348541) (xy 129.697997 -226.354675)
			(xy 129.746881 -226.368835) (xy 129.79286 -226.390652) (xy 129.834744 -226.419562) (xy 129.871448 -226.454817)
			(xy 129.902021 -226.495503) (xy 129.925672 -226.540566) (xy 129.941788 -226.58884) (xy 129.949952 -226.639074)
			(xy 129.950464 -226.66452) (xy 130.268992 -226.66452) (xy 130.272952 -226.615466) (xy 130.284729 -226.567682)
			(xy 130.30402 -226.522406) (xy 130.330323 -226.48081) (xy 130.362958 -226.443973) (xy 130.401079 -226.412848)
			(xy 130.4437 -226.388241) (xy 130.489716 -226.370789) (xy 130.537935 -226.360945) (xy 130.58711 -226.358964)
			(xy 130.635965 -226.364896) (xy 130.683236 -226.378588) (xy 130.727698 -226.399686) (xy 130.768201 -226.427642)
			(xy 130.803694 -226.461734) (xy 130.833259 -226.501078) (xy 130.85613 -226.544655) (xy 130.871714 -226.591336)
			(xy 130.879609 -226.639913) (xy 130.880104 -226.66452) (xy 131.198615 -226.66452) (xy 131.20271 -226.613792)
			(xy 131.214889 -226.564378) (xy 131.234837 -226.517558) (xy 131.262038 -226.474544) (xy 131.295786 -226.43645)
			(xy 131.335208 -226.404263) (xy 131.379282 -226.378817) (xy 131.426868 -226.36077) (xy 131.476732 -226.35059)
			(xy 131.527584 -226.348541) (xy 131.578105 -226.354675) (xy 131.626989 -226.368835) (xy 131.672968 -226.390652)
			(xy 131.714852 -226.419562) (xy 131.751556 -226.454817) (xy 131.782129 -226.495503) (xy 131.80578 -226.540566)
			(xy 131.821896 -226.58884) (xy 131.83006 -226.639074) (xy 131.830572 -226.66452) (xy 132.138415 -226.66452)
			(xy 132.14251 -226.613792) (xy 132.154689 -226.564378) (xy 132.174637 -226.517558) (xy 132.201838 -226.474544)
			(xy 132.235586 -226.43645) (xy 132.275008 -226.404263) (xy 132.319082 -226.378817) (xy 132.366668 -226.36077)
			(xy 132.416532 -226.35059) (xy 132.467384 -226.348541) (xy 132.517905 -226.354675) (xy 132.566789 -226.368835)
			(xy 132.612768 -226.390652) (xy 132.654652 -226.419562) (xy 132.691356 -226.454817) (xy 132.721929 -226.495503)
			(xy 132.74558 -226.540566) (xy 132.761696 -226.58884) (xy 132.76986 -226.639074) (xy 132.770372 -226.66452)
			(xy 133.0889 -226.66452) (xy 133.09286 -226.615466) (xy 133.104637 -226.567682) (xy 133.123928 -226.522406)
			(xy 133.150231 -226.48081) (xy 133.182866 -226.443973) (xy 133.220987 -226.412848) (xy 133.263608 -226.388241)
			(xy 133.309624 -226.370789) (xy 133.357843 -226.360945) (xy 133.407018 -226.358964) (xy 133.455873 -226.364896)
			(xy 133.503144 -226.378588) (xy 133.547606 -226.399686) (xy 133.588109 -226.427642) (xy 133.623602 -226.461734)
			(xy 133.653167 -226.501078) (xy 133.676038 -226.544655) (xy 133.691622 -226.591336) (xy 133.699517 -226.639913)
			(xy 133.700012 -226.66452) (xy 134.028954 -226.66452) (xy 134.032914 -226.615466) (xy 134.044691 -226.567682)
			(xy 134.063982 -226.522406) (xy 134.090285 -226.48081) (xy 134.12292 -226.443973) (xy 134.161041 -226.412848)
			(xy 134.203662 -226.388241) (xy 134.249678 -226.370789) (xy 134.297897 -226.360945) (xy 134.347072 -226.358964)
			(xy 134.395927 -226.364896) (xy 134.443198 -226.378588) (xy 134.48766 -226.399686) (xy 134.528163 -226.427642)
			(xy 134.563656 -226.461734) (xy 134.593221 -226.501078) (xy 134.616092 -226.544655) (xy 134.631676 -226.591336)
			(xy 134.639571 -226.639913) (xy 134.640066 -226.66452) (xy 134.969008 -226.66452) (xy 134.972968 -226.615466)
			(xy 134.984745 -226.567682) (xy 135.004036 -226.522406) (xy 135.030339 -226.48081) (xy 135.062974 -226.443973)
			(xy 135.101095 -226.412848) (xy 135.143716 -226.388241) (xy 135.189732 -226.370789) (xy 135.237951 -226.360945)
			(xy 135.287126 -226.358964) (xy 135.335981 -226.364896) (xy 135.383252 -226.378588) (xy 135.427714 -226.399686)
			(xy 135.468217 -226.427642) (xy 135.50371 -226.461734) (xy 135.533275 -226.501078) (xy 135.556146 -226.544655)
			(xy 135.57173 -226.591336) (xy 135.579625 -226.639913) (xy 135.58012 -226.66452) (xy 135.909062 -226.66452)
			(xy 135.913022 -226.615466) (xy 135.924799 -226.567682) (xy 135.94409 -226.522406) (xy 135.970393 -226.48081)
			(xy 136.003028 -226.443973) (xy 136.041149 -226.412848) (xy 136.08377 -226.388241) (xy 136.129786 -226.370789)
			(xy 136.178005 -226.360945) (xy 136.22718 -226.358964) (xy 136.276035 -226.364896) (xy 136.323306 -226.378588)
			(xy 136.367768 -226.399686) (xy 136.408271 -226.427642) (xy 136.443764 -226.461734) (xy 136.473329 -226.501078)
			(xy 136.4962 -226.544655) (xy 136.511784 -226.591336) (xy 136.519679 -226.639913) (xy 136.520174 -226.66452)
			(xy 136.848862 -226.66452) (xy 136.852822 -226.615466) (xy 136.864599 -226.567682) (xy 136.88389 -226.522406)
			(xy 136.910193 -226.48081) (xy 136.942828 -226.443973) (xy 136.980949 -226.412848) (xy 137.02357 -226.388241)
			(xy 137.069586 -226.370789) (xy 137.117805 -226.360945) (xy 137.16698 -226.358964) (xy 137.215835 -226.364896)
			(xy 137.263106 -226.378588) (xy 137.307568 -226.399686) (xy 137.348071 -226.427642) (xy 137.383564 -226.461734)
			(xy 137.413129 -226.501078) (xy 137.436 -226.544655) (xy 137.451584 -226.591336) (xy 137.459479 -226.639913)
			(xy 137.459974 -226.66452) (xy 137.788916 -226.66452) (xy 137.792876 -226.615466) (xy 137.804653 -226.567682)
			(xy 137.823944 -226.522406) (xy 137.850247 -226.48081) (xy 137.882882 -226.443973) (xy 137.921003 -226.412848)
			(xy 137.963624 -226.388241) (xy 138.00964 -226.370789) (xy 138.057859 -226.360945) (xy 138.107034 -226.358964)
			(xy 138.155889 -226.364896) (xy 138.20316 -226.378588) (xy 138.247622 -226.399686) (xy 138.288125 -226.427642)
			(xy 138.323618 -226.461734) (xy 138.353183 -226.501078) (xy 138.376054 -226.544655) (xy 138.391638 -226.591336)
			(xy 138.399533 -226.639913) (xy 138.400028 -226.66452) (xy 138.72897 -226.66452) (xy 138.73293 -226.615466)
			(xy 138.744707 -226.567682) (xy 138.763998 -226.522406) (xy 138.790301 -226.48081) (xy 138.822936 -226.443973)
			(xy 138.861057 -226.412848) (xy 138.903678 -226.388241) (xy 138.949694 -226.370789) (xy 138.997913 -226.360945)
			(xy 139.047088 -226.358964) (xy 139.095943 -226.364896) (xy 139.143214 -226.378588) (xy 139.187676 -226.399686)
			(xy 139.228179 -226.427642) (xy 139.263672 -226.461734) (xy 139.293237 -226.501078) (xy 139.316108 -226.544655)
			(xy 139.331692 -226.591336) (xy 139.339587 -226.639913) (xy 139.340082 -226.66452) (xy 139.339587 -226.689127)
			(xy 139.331692 -226.737704) (xy 139.316108 -226.784385) (xy 139.293237 -226.827962) (xy 139.263672 -226.867306)
			(xy 139.228179 -226.901398) (xy 139.187676 -226.929354) (xy 139.143214 -226.950452) (xy 139.095943 -226.964144)
			(xy 139.047088 -226.970076) (xy 138.997913 -226.968095) (xy 138.949694 -226.958251) (xy 138.903678 -226.940799)
			(xy 138.861057 -226.916192) (xy 138.822936 -226.885067) (xy 138.790301 -226.84823) (xy 138.763998 -226.806634)
			(xy 138.744707 -226.761358) (xy 138.73293 -226.713574) (xy 138.72897 -226.66452) (xy 138.400028 -226.66452)
			(xy 138.399533 -226.689127) (xy 138.391638 -226.737704) (xy 138.376054 -226.784385) (xy 138.353183 -226.827962)
			(xy 138.323618 -226.867306) (xy 138.288125 -226.901398) (xy 138.247622 -226.929354) (xy 138.20316 -226.950452)
			(xy 138.155889 -226.964144) (xy 138.107034 -226.970076) (xy 138.057859 -226.968095) (xy 138.00964 -226.958251)
			(xy 137.963624 -226.940799) (xy 137.921003 -226.916192) (xy 137.882882 -226.885067) (xy 137.850247 -226.84823)
			(xy 137.823944 -226.806634) (xy 137.804653 -226.761358) (xy 137.792876 -226.713574) (xy 137.788916 -226.66452)
			(xy 137.459974 -226.66452) (xy 137.459479 -226.689127) (xy 137.451584 -226.737704) (xy 137.436 -226.784385)
			(xy 137.413129 -226.827962) (xy 137.383564 -226.867306) (xy 137.348071 -226.901398) (xy 137.307568 -226.929354)
			(xy 137.263106 -226.950452) (xy 137.215835 -226.964144) (xy 137.16698 -226.970076) (xy 137.117805 -226.968095)
			(xy 137.069586 -226.958251) (xy 137.02357 -226.940799) (xy 136.980949 -226.916192) (xy 136.942828 -226.885067)
			(xy 136.910193 -226.84823) (xy 136.88389 -226.806634) (xy 136.864599 -226.761358) (xy 136.852822 -226.713574)
			(xy 136.848862 -226.66452) (xy 136.520174 -226.66452) (xy 136.519679 -226.689127) (xy 136.511784 -226.737704)
			(xy 136.4962 -226.784385) (xy 136.473329 -226.827962) (xy 136.443764 -226.867306) (xy 136.408271 -226.901398)
			(xy 136.367768 -226.929354) (xy 136.323306 -226.950452) (xy 136.276035 -226.964144) (xy 136.22718 -226.970076)
			(xy 136.178005 -226.968095) (xy 136.129786 -226.958251) (xy 136.08377 -226.940799) (xy 136.041149 -226.916192)
			(xy 136.003028 -226.885067) (xy 135.970393 -226.84823) (xy 135.94409 -226.806634) (xy 135.924799 -226.761358)
			(xy 135.913022 -226.713574) (xy 135.909062 -226.66452) (xy 135.58012 -226.66452) (xy 135.579625 -226.689127)
			(xy 135.57173 -226.737704) (xy 135.556146 -226.784385) (xy 135.533275 -226.827962) (xy 135.50371 -226.867306)
			(xy 135.468217 -226.901398) (xy 135.427714 -226.929354) (xy 135.383252 -226.950452) (xy 135.335981 -226.964144)
			(xy 135.287126 -226.970076) (xy 135.237951 -226.968095) (xy 135.189732 -226.958251) (xy 135.143716 -226.940799)
			(xy 135.101095 -226.916192) (xy 135.062974 -226.885067) (xy 135.030339 -226.84823) (xy 135.004036 -226.806634)
			(xy 134.984745 -226.761358) (xy 134.972968 -226.713574) (xy 134.969008 -226.66452) (xy 134.640066 -226.66452)
			(xy 134.639571 -226.689127) (xy 134.631676 -226.737704) (xy 134.616092 -226.784385) (xy 134.593221 -226.827962)
			(xy 134.563656 -226.867306) (xy 134.528163 -226.901398) (xy 134.48766 -226.929354) (xy 134.443198 -226.950452)
			(xy 134.395927 -226.964144) (xy 134.347072 -226.970076) (xy 134.297897 -226.968095) (xy 134.249678 -226.958251)
			(xy 134.203662 -226.940799) (xy 134.161041 -226.916192) (xy 134.12292 -226.885067) (xy 134.090285 -226.84823)
			(xy 134.063982 -226.806634) (xy 134.044691 -226.761358) (xy 134.032914 -226.713574) (xy 134.028954 -226.66452)
			(xy 133.700012 -226.66452) (xy 133.699517 -226.689127) (xy 133.691622 -226.737704) (xy 133.676038 -226.784385)
			(xy 133.653167 -226.827962) (xy 133.623602 -226.867306) (xy 133.588109 -226.901398) (xy 133.547606 -226.929354)
			(xy 133.503144 -226.950452) (xy 133.455873 -226.964144) (xy 133.407018 -226.970076) (xy 133.357843 -226.968095)
			(xy 133.309624 -226.958251) (xy 133.263608 -226.940799) (xy 133.220987 -226.916192) (xy 133.182866 -226.885067)
			(xy 133.150231 -226.84823) (xy 133.123928 -226.806634) (xy 133.104637 -226.761358) (xy 133.09286 -226.713574)
			(xy 133.0889 -226.66452) (xy 132.770372 -226.66452) (xy 132.76986 -226.689966) (xy 132.761696 -226.7402)
			(xy 132.74558 -226.788474) (xy 132.721929 -226.833537) (xy 132.691356 -226.874223) (xy 132.654652 -226.909478)
			(xy 132.612768 -226.938388) (xy 132.566789 -226.960205) (xy 132.517905 -226.974365) (xy 132.467384 -226.980499)
			(xy 132.416532 -226.97845) (xy 132.366668 -226.96827) (xy 132.319082 -226.950223) (xy 132.275008 -226.924777)
			(xy 132.235586 -226.89259) (xy 132.201838 -226.854496) (xy 132.174637 -226.811482) (xy 132.154689 -226.764662)
			(xy 132.14251 -226.715248) (xy 132.138415 -226.66452) (xy 131.830572 -226.66452) (xy 131.83006 -226.689966)
			(xy 131.821896 -226.7402) (xy 131.80578 -226.788474) (xy 131.782129 -226.833537) (xy 131.751556 -226.874223)
			(xy 131.714852 -226.909478) (xy 131.672968 -226.938388) (xy 131.626989 -226.960205) (xy 131.578105 -226.974365)
			(xy 131.527584 -226.980499) (xy 131.476732 -226.97845) (xy 131.426868 -226.96827) (xy 131.379282 -226.950223)
			(xy 131.335208 -226.924777) (xy 131.295786 -226.89259) (xy 131.262038 -226.854496) (xy 131.234837 -226.811482)
			(xy 131.214889 -226.764662) (xy 131.20271 -226.715248) (xy 131.198615 -226.66452) (xy 130.880104 -226.66452)
			(xy 130.879609 -226.689127) (xy 130.871714 -226.737704) (xy 130.85613 -226.784385) (xy 130.833259 -226.827962)
			(xy 130.803694 -226.867306) (xy 130.768201 -226.901398) (xy 130.727698 -226.929354) (xy 130.683236 -226.950452)
			(xy 130.635965 -226.964144) (xy 130.58711 -226.970076) (xy 130.537935 -226.968095) (xy 130.489716 -226.958251)
			(xy 130.4437 -226.940799) (xy 130.401079 -226.916192) (xy 130.362958 -226.885067) (xy 130.330323 -226.84823)
			(xy 130.30402 -226.806634) (xy 130.284729 -226.761358) (xy 130.272952 -226.713574) (xy 130.268992 -226.66452)
			(xy 129.950464 -226.66452) (xy 129.949952 -226.689966) (xy 129.941788 -226.7402) (xy 129.925672 -226.788474)
			(xy 129.902021 -226.833537) (xy 129.871448 -226.874223) (xy 129.834744 -226.909478) (xy 129.79286 -226.938388)
			(xy 129.746881 -226.960205) (xy 129.697997 -226.974365) (xy 129.647476 -226.980499) (xy 129.596624 -226.97845)
			(xy 129.54676 -226.96827) (xy 129.499174 -226.950223) (xy 129.4551 -226.924777) (xy 129.415678 -226.89259)
			(xy 129.38193 -226.854496) (xy 129.354729 -226.811482) (xy 129.334781 -226.764662) (xy 129.322602 -226.715248)
			(xy 129.318507 -226.66452) (xy 128.999996 -226.66452) (xy 128.999524 -226.68851) (xy 128.992015 -226.735898)
			(xy 128.977186 -226.781529) (xy 128.955401 -226.824278) (xy 128.927197 -226.863093) (xy 128.893269 -226.897018)
			(xy 128.854451 -226.925218) (xy 128.811699 -226.946998) (xy 128.766067 -226.961823) (xy 128.718678 -226.969326)
			(xy 128.694688 -226.969828) (xy 128.669268 -226.969321) (xy 128.619131 -226.960901) (xy 128.571079 -226.944296)
			(xy 128.526441 -226.919963) (xy 128.486448 -226.888576) (xy 128.452204 -226.850999) (xy 128.424654 -226.808271)
			(xy 128.404559 -226.761571) (xy 128.392475 -226.712189) (xy 128.390142 -226.686872) (xy 128.389634 -226.679506)
			(xy 128.384554 -226.66579) (xy 128.380236 -226.660202) (xy 128.375668 -226.65459) (xy 128.364059 -226.645963)
			(xy 128.357376 -226.643184) (xy 128.270762 -226.610672) (xy 128.266698 -226.609402) (xy 128.258255 -226.607399)
			(xy 128.240952 -226.608567) (xy 128.225034 -226.615446) (xy 128.218438 -226.621086) (xy 128.217168 -226.622356)
			(xy 128.04013 -226.799394) (xy 128.03632 -226.80676) (xy 128.024581 -226.828934) (xy 127.995166 -226.869577)
			(xy 127.959691 -226.905054) (xy 127.91905 -226.934471) (xy 127.896874 -226.946206) (xy 127.889508 -226.950016)
			(xy 127.564896 -227.274628) (xy 127.559456 -227.280561) (xy 127.552205 -227.294921) (xy 127.550672 -227.302822)
			(xy 127.549402 -227.310696) (xy 127.551942 -227.326444) (xy 127.555752 -227.33381) (xy 127.566467 -227.355437)
			(xy 127.581677 -227.401241) (xy 127.589467 -227.448872) (xy 127.590042 -227.473002) (xy 127.590042 -227.474526)
			(xy 127.908553 -227.474526) (xy 127.912648 -227.423798) (xy 127.924827 -227.374384) (xy 127.944775 -227.327564)
			(xy 127.971976 -227.28455) (xy 128.005724 -227.246456) (xy 128.045146 -227.214269) (xy 128.08922 -227.188823)
			(xy 128.136806 -227.170776) (xy 128.18667 -227.160596) (xy 128.237522 -227.158547) (xy 128.288043 -227.164681)
			(xy 128.336927 -227.178841) (xy 128.382906 -227.200658) (xy 128.42479 -227.229568) (xy 128.461494 -227.264823)
			(xy 128.492067 -227.305509) (xy 128.515718 -227.350572) (xy 128.531834 -227.398846) (xy 128.539998 -227.44908)
			(xy 128.54051 -227.474526) (xy 128.848607 -227.474526) (xy 128.852702 -227.423798) (xy 128.864881 -227.374384)
			(xy 128.884829 -227.327564) (xy 128.91203 -227.28455) (xy 128.945778 -227.246456) (xy 128.9852 -227.214269)
			(xy 129.029274 -227.188823) (xy 129.07686 -227.170776) (xy 129.126724 -227.160596) (xy 129.177576 -227.158547)
			(xy 129.228097 -227.164681) (xy 129.276981 -227.178841) (xy 129.32296 -227.200658) (xy 129.364844 -227.229568)
			(xy 129.401548 -227.264823) (xy 129.432121 -227.305509) (xy 129.455772 -227.350572) (xy 129.471888 -227.398846)
			(xy 129.480052 -227.44908) (xy 129.480564 -227.474526) (xy 130.728461 -227.474526) (xy 130.732556 -227.423798)
			(xy 130.744735 -227.374384) (xy 130.764683 -227.327564) (xy 130.791884 -227.28455) (xy 130.825632 -227.246456)
			(xy 130.865054 -227.214269) (xy 130.909128 -227.188823) (xy 130.956714 -227.170776) (xy 131.006578 -227.160596)
			(xy 131.05743 -227.158547) (xy 131.107951 -227.164681) (xy 131.156835 -227.178841) (xy 131.202814 -227.200658)
			(xy 131.244698 -227.229568) (xy 131.281402 -227.264823) (xy 131.311975 -227.305509) (xy 131.335626 -227.350572)
			(xy 131.351742 -227.398846) (xy 131.359906 -227.44908) (xy 131.360418 -227.474526) (xy 131.678946 -227.474526)
			(xy 131.682906 -227.425472) (xy 131.694683 -227.377688) (xy 131.713974 -227.332412) (xy 131.740277 -227.290816)
			(xy 131.772912 -227.253979) (xy 131.811033 -227.222854) (xy 131.853654 -227.198247) (xy 131.89967 -227.180795)
			(xy 131.947889 -227.170951) (xy 131.997064 -227.16897) (xy 132.045919 -227.174902) (xy 132.09319 -227.188594)
			(xy 132.137652 -227.209692) (xy 132.178155 -227.237648) (xy 132.213648 -227.27174) (xy 132.243213 -227.311084)
			(xy 132.266084 -227.354661) (xy 132.281668 -227.401342) (xy 132.289563 -227.449919) (xy 132.290058 -227.474526)
			(xy 132.608569 -227.474526) (xy 132.612664 -227.423798) (xy 132.624843 -227.374384) (xy 132.644791 -227.327564)
			(xy 132.671992 -227.28455) (xy 132.70574 -227.246456) (xy 132.745162 -227.214269) (xy 132.789236 -227.188823)
			(xy 132.836822 -227.170776) (xy 132.886686 -227.160596) (xy 132.937538 -227.158547) (xy 132.988059 -227.164681)
			(xy 133.036943 -227.178841) (xy 133.082922 -227.200658) (xy 133.124806 -227.229568) (xy 133.16151 -227.264823)
			(xy 133.192083 -227.305509) (xy 133.215734 -227.350572) (xy 133.23185 -227.398846) (xy 133.240014 -227.44908)
			(xy 133.240526 -227.474526) (xy 133.559054 -227.474526) (xy 133.563014 -227.425472) (xy 133.574791 -227.377688)
			(xy 133.594082 -227.332412) (xy 133.620385 -227.290816) (xy 133.65302 -227.253979) (xy 133.691141 -227.222854)
			(xy 133.733762 -227.198247) (xy 133.779778 -227.180795) (xy 133.827997 -227.170951) (xy 133.877172 -227.16897)
			(xy 133.926027 -227.174902) (xy 133.973298 -227.188594) (xy 134.01776 -227.209692) (xy 134.058263 -227.237648)
			(xy 134.093756 -227.27174) (xy 134.123321 -227.311084) (xy 134.146192 -227.354661) (xy 134.161776 -227.401342)
			(xy 134.169671 -227.449919) (xy 134.170166 -227.474526) (xy 134.498854 -227.474526) (xy 134.502814 -227.425472)
			(xy 134.514591 -227.377688) (xy 134.533882 -227.332412) (xy 134.560185 -227.290816) (xy 134.59282 -227.253979)
			(xy 134.630941 -227.222854) (xy 134.673562 -227.198247) (xy 134.719578 -227.180795) (xy 134.767797 -227.170951)
			(xy 134.816972 -227.16897) (xy 134.865827 -227.174902) (xy 134.913098 -227.188594) (xy 134.95756 -227.209692)
			(xy 134.998063 -227.237648) (xy 135.033556 -227.27174) (xy 135.063121 -227.311084) (xy 135.085992 -227.354661)
			(xy 135.101576 -227.401342) (xy 135.109471 -227.449919) (xy 135.109966 -227.474526) (xy 135.438908 -227.474526)
			(xy 135.442868 -227.425472) (xy 135.454645 -227.377688) (xy 135.473936 -227.332412) (xy 135.500239 -227.290816)
			(xy 135.532874 -227.253979) (xy 135.570995 -227.222854) (xy 135.613616 -227.198247) (xy 135.659632 -227.180795)
			(xy 135.707851 -227.170951) (xy 135.757026 -227.16897) (xy 135.805881 -227.174902) (xy 135.853152 -227.188594)
			(xy 135.897614 -227.209692) (xy 135.938117 -227.237648) (xy 135.97361 -227.27174) (xy 136.003175 -227.311084)
			(xy 136.026046 -227.354661) (xy 136.04163 -227.401342) (xy 136.049525 -227.449919) (xy 136.05002 -227.474526)
			(xy 137.319016 -227.474526) (xy 137.322976 -227.425472) (xy 137.334753 -227.377688) (xy 137.354044 -227.332412)
			(xy 137.380347 -227.290816) (xy 137.412982 -227.253979) (xy 137.451103 -227.222854) (xy 137.493724 -227.198247)
			(xy 137.53974 -227.180795) (xy 137.587959 -227.170951) (xy 137.637134 -227.16897) (xy 137.685989 -227.174902)
			(xy 137.73326 -227.188594) (xy 137.777722 -227.209692) (xy 137.818225 -227.237648) (xy 137.853718 -227.27174)
			(xy 137.883283 -227.311084) (xy 137.906154 -227.354661) (xy 137.921738 -227.401342) (xy 137.929633 -227.449919)
			(xy 137.930128 -227.474526) (xy 138.25907 -227.474526) (xy 138.26303 -227.425472) (xy 138.274807 -227.377688)
			(xy 138.294098 -227.332412) (xy 138.320401 -227.290816) (xy 138.353036 -227.253979) (xy 138.391157 -227.222854)
			(xy 138.433778 -227.198247) (xy 138.479794 -227.180795) (xy 138.528013 -227.170951) (xy 138.577188 -227.16897)
			(xy 138.626043 -227.174902) (xy 138.673314 -227.188594) (xy 138.717776 -227.209692) (xy 138.758279 -227.237648)
			(xy 138.793772 -227.27174) (xy 138.823337 -227.311084) (xy 138.846208 -227.354661) (xy 138.861792 -227.401342)
			(xy 138.869687 -227.449919) (xy 138.870182 -227.474526) (xy 139.19887 -227.474526) (xy 139.20283 -227.425472)
			(xy 139.214607 -227.377688) (xy 139.233898 -227.332412) (xy 139.260201 -227.290816) (xy 139.292836 -227.253979)
			(xy 139.330957 -227.222854) (xy 139.373578 -227.198247) (xy 139.419594 -227.180795) (xy 139.467813 -227.170951)
			(xy 139.516988 -227.16897) (xy 139.565843 -227.174902) (xy 139.613114 -227.188594) (xy 139.657576 -227.209692)
			(xy 139.698079 -227.237648) (xy 139.733572 -227.27174) (xy 139.763137 -227.311084) (xy 139.786008 -227.354661)
			(xy 139.801592 -227.401342) (xy 139.809487 -227.449919) (xy 139.809982 -227.474526) (xy 139.809487 -227.499133)
			(xy 139.801592 -227.54771) (xy 139.786008 -227.594391) (xy 139.763137 -227.637968) (xy 139.733572 -227.677312)
			(xy 139.698079 -227.711404) (xy 139.657576 -227.73936) (xy 139.613114 -227.760458) (xy 139.565843 -227.77415)
			(xy 139.516988 -227.780082) (xy 139.467813 -227.778101) (xy 139.419594 -227.768257) (xy 139.373578 -227.750805)
			(xy 139.330957 -227.726198) (xy 139.292836 -227.695073) (xy 139.260201 -227.658236) (xy 139.233898 -227.61664)
			(xy 139.214607 -227.571364) (xy 139.20283 -227.52358) (xy 139.19887 -227.474526) (xy 138.870182 -227.474526)
			(xy 138.869687 -227.499133) (xy 138.861792 -227.54771) (xy 138.846208 -227.594391) (xy 138.823337 -227.637968)
			(xy 138.793772 -227.677312) (xy 138.758279 -227.711404) (xy 138.717776 -227.73936) (xy 138.673314 -227.760458)
			(xy 138.626043 -227.77415) (xy 138.577188 -227.780082) (xy 138.528013 -227.778101) (xy 138.479794 -227.768257)
			(xy 138.433778 -227.750805) (xy 138.391157 -227.726198) (xy 138.353036 -227.695073) (xy 138.320401 -227.658236)
			(xy 138.294098 -227.61664) (xy 138.274807 -227.571364) (xy 138.26303 -227.52358) (xy 138.25907 -227.474526)
			(xy 137.930128 -227.474526) (xy 137.929633 -227.499133) (xy 137.921738 -227.54771) (xy 137.906154 -227.594391)
			(xy 137.883283 -227.637968) (xy 137.853718 -227.677312) (xy 137.818225 -227.711404) (xy 137.777722 -227.73936)
			(xy 137.73326 -227.760458) (xy 137.685989 -227.77415) (xy 137.637134 -227.780082) (xy 137.587959 -227.778101)
			(xy 137.53974 -227.768257) (xy 137.493724 -227.750805) (xy 137.451103 -227.726198) (xy 137.412982 -227.695073)
			(xy 137.380347 -227.658236) (xy 137.354044 -227.61664) (xy 137.334753 -227.571364) (xy 137.322976 -227.52358)
			(xy 137.319016 -227.474526) (xy 136.05002 -227.474526) (xy 136.049525 -227.499133) (xy 136.04163 -227.54771)
			(xy 136.026046 -227.594391) (xy 136.003175 -227.637968) (xy 135.97361 -227.677312) (xy 135.938117 -227.711404)
			(xy 135.897614 -227.73936) (xy 135.853152 -227.760458) (xy 135.805881 -227.77415) (xy 135.757026 -227.780082)
			(xy 135.707851 -227.778101) (xy 135.659632 -227.768257) (xy 135.613616 -227.750805) (xy 135.570995 -227.726198)
			(xy 135.532874 -227.695073) (xy 135.500239 -227.658236) (xy 135.473936 -227.61664) (xy 135.454645 -227.571364)
			(xy 135.442868 -227.52358) (xy 135.438908 -227.474526) (xy 135.109966 -227.474526) (xy 135.109471 -227.499133)
			(xy 135.101576 -227.54771) (xy 135.085992 -227.594391) (xy 135.063121 -227.637968) (xy 135.033556 -227.677312)
			(xy 134.998063 -227.711404) (xy 134.95756 -227.73936) (xy 134.913098 -227.760458) (xy 134.865827 -227.77415)
			(xy 134.816972 -227.780082) (xy 134.767797 -227.778101) (xy 134.719578 -227.768257) (xy 134.673562 -227.750805)
			(xy 134.630941 -227.726198) (xy 134.59282 -227.695073) (xy 134.560185 -227.658236) (xy 134.533882 -227.61664)
			(xy 134.514591 -227.571364) (xy 134.502814 -227.52358) (xy 134.498854 -227.474526) (xy 134.170166 -227.474526)
			(xy 134.169671 -227.499133) (xy 134.161776 -227.54771) (xy 134.146192 -227.594391) (xy 134.123321 -227.637968)
			(xy 134.093756 -227.677312) (xy 134.058263 -227.711404) (xy 134.01776 -227.73936) (xy 133.973298 -227.760458)
			(xy 133.926027 -227.77415) (xy 133.877172 -227.780082) (xy 133.827997 -227.778101) (xy 133.779778 -227.768257)
			(xy 133.733762 -227.750805) (xy 133.691141 -227.726198) (xy 133.65302 -227.695073) (xy 133.620385 -227.658236)
			(xy 133.594082 -227.61664) (xy 133.574791 -227.571364) (xy 133.563014 -227.52358) (xy 133.559054 -227.474526)
			(xy 133.240526 -227.474526) (xy 133.240014 -227.499972) (xy 133.23185 -227.550206) (xy 133.215734 -227.59848)
			(xy 133.192083 -227.643543) (xy 133.16151 -227.684229) (xy 133.124806 -227.719484) (xy 133.082922 -227.748394)
			(xy 133.036943 -227.770211) (xy 132.988059 -227.784371) (xy 132.937538 -227.790505) (xy 132.886686 -227.788456)
			(xy 132.836822 -227.778276) (xy 132.789236 -227.760229) (xy 132.745162 -227.734783) (xy 132.70574 -227.702596)
			(xy 132.671992 -227.664502) (xy 132.644791 -227.621488) (xy 132.624843 -227.574668) (xy 132.612664 -227.525254)
			(xy 132.608569 -227.474526) (xy 132.290058 -227.474526) (xy 132.289563 -227.499133) (xy 132.281668 -227.54771)
			(xy 132.266084 -227.594391) (xy 132.243213 -227.637968) (xy 132.213648 -227.677312) (xy 132.178155 -227.711404)
			(xy 132.137652 -227.73936) (xy 132.09319 -227.760458) (xy 132.045919 -227.77415) (xy 131.997064 -227.780082)
			(xy 131.947889 -227.778101) (xy 131.89967 -227.768257) (xy 131.853654 -227.750805) (xy 131.811033 -227.726198)
			(xy 131.772912 -227.695073) (xy 131.740277 -227.658236) (xy 131.713974 -227.61664) (xy 131.694683 -227.571364)
			(xy 131.682906 -227.52358) (xy 131.678946 -227.474526) (xy 131.360418 -227.474526) (xy 131.359906 -227.499972)
			(xy 131.351742 -227.550206) (xy 131.335626 -227.59848) (xy 131.311975 -227.643543) (xy 131.281402 -227.684229)
			(xy 131.244698 -227.719484) (xy 131.202814 -227.748394) (xy 131.156835 -227.770211) (xy 131.107951 -227.784371)
			(xy 131.05743 -227.790505) (xy 131.006578 -227.788456) (xy 130.956714 -227.778276) (xy 130.909128 -227.760229)
			(xy 130.865054 -227.734783) (xy 130.825632 -227.702596) (xy 130.791884 -227.664502) (xy 130.764683 -227.621488)
			(xy 130.744735 -227.574668) (xy 130.732556 -227.525254) (xy 130.728461 -227.474526) (xy 129.480564 -227.474526)
			(xy 129.480052 -227.499972) (xy 129.471888 -227.550206) (xy 129.455772 -227.59848) (xy 129.432121 -227.643543)
			(xy 129.401548 -227.684229) (xy 129.364844 -227.719484) (xy 129.32296 -227.748394) (xy 129.276981 -227.770211)
			(xy 129.228097 -227.784371) (xy 129.177576 -227.790505) (xy 129.126724 -227.788456) (xy 129.07686 -227.778276)
			(xy 129.029274 -227.760229) (xy 128.9852 -227.734783) (xy 128.945778 -227.702596) (xy 128.91203 -227.664502)
			(xy 128.884829 -227.621488) (xy 128.864881 -227.574668) (xy 128.852702 -227.525254) (xy 128.848607 -227.474526)
			(xy 128.54051 -227.474526) (xy 128.539998 -227.499972) (xy 128.531834 -227.550206) (xy 128.515718 -227.59848)
			(xy 128.492067 -227.643543) (xy 128.461494 -227.684229) (xy 128.42479 -227.719484) (xy 128.382906 -227.748394)
			(xy 128.336927 -227.770211) (xy 128.288043 -227.784371) (xy 128.237522 -227.790505) (xy 128.18667 -227.788456)
			(xy 128.136806 -227.778276) (xy 128.08922 -227.760229) (xy 128.045146 -227.734783) (xy 128.005724 -227.702596)
			(xy 127.971976 -227.664502) (xy 127.944775 -227.621488) (xy 127.924827 -227.574668) (xy 127.912648 -227.525254)
			(xy 127.908553 -227.474526) (xy 127.590042 -227.474526) (xy 127.590042 -227.47986) (xy 127.589183 -227.503579)
			(xy 127.581031 -227.550334) (xy 127.565743 -227.595265) (xy 127.543685 -227.637288) (xy 127.515389 -227.675392)
			(xy 127.481538 -227.708657) (xy 127.442947 -227.736284) (xy 127.400545 -227.757605) (xy 127.355355 -227.772108)
			(xy 127.308464 -227.779442) (xy 127.284734 -227.779834) (xy 127.28448 -227.779834) (xy 127.260137 -227.779362)
			(xy 127.212069 -227.771623) (xy 127.165847 -227.756331) (xy 127.144018 -227.745544) (xy 127.136652 -227.741734)
			(xy 127.120904 -227.739194) (xy 127.11303 -227.740464) (xy 127.105109 -227.741945) (xy 127.090726 -227.74919)
			(xy 127.084836 -227.754688) (xy 126.966472 -227.873052) (xy 126.963678 -227.8761) (xy 126.9619 -227.878386)
			(xy 126.956969 -227.885567) (xy 126.951789 -227.902186) (xy 126.95174 -227.910898) (xy 126.960122 -227.990908)
			(xy 126.961392 -228.003862) (xy 126.966472 -228.012498) (xy 126.969608 -228.017552) (xy 126.977823 -228.026152)
			(xy 126.982728 -228.029516) (xy 127.003468 -228.043783) (xy 127.040403 -228.077979) (xy 127.071229 -228.117772)
			(xy 127.095108 -228.162082) (xy 127.111395 -228.20971) (xy 127.119647 -228.259364) (xy 127.120142 -228.284532)
			(xy 127.438399 -228.284532) (xy 127.442494 -228.233804) (xy 127.454673 -228.18439) (xy 127.474621 -228.13757)
			(xy 127.501822 -228.094556) (xy 127.53557 -228.056462) (xy 127.574992 -228.024275) (xy 127.619066 -227.998829)
			(xy 127.666652 -227.980782) (xy 127.716516 -227.970602) (xy 127.767368 -227.968553) (xy 127.817889 -227.974687)
			(xy 127.866773 -227.988847) (xy 127.912752 -228.010664) (xy 127.954636 -228.039574) (xy 127.99134 -228.074829)
			(xy 128.021913 -228.115515) (xy 128.045564 -228.160578) (xy 128.06168 -228.208852) (xy 128.069844 -228.259086)
			(xy 128.070356 -228.284532) (xy 128.388884 -228.284532) (xy 128.392844 -228.235478) (xy 128.404621 -228.187694)
			(xy 128.423912 -228.142418) (xy 128.450215 -228.100822) (xy 128.48285 -228.063985) (xy 128.520971 -228.03286)
			(xy 128.563592 -228.008253) (xy 128.609608 -227.990801) (xy 128.657827 -227.980957) (xy 128.707002 -227.978976)
			(xy 128.755857 -227.984908) (xy 128.803128 -227.9986) (xy 128.84759 -228.019698) (xy 128.888093 -228.047654)
			(xy 128.923586 -228.081746) (xy 128.953151 -228.12109) (xy 128.976022 -228.164667) (xy 128.991606 -228.211348)
			(xy 128.999501 -228.259925) (xy 128.999996 -228.284532) (xy 129.318507 -228.284532) (xy 129.322602 -228.233804)
			(xy 129.334781 -228.18439) (xy 129.354729 -228.13757) (xy 129.38193 -228.094556) (xy 129.415678 -228.056462)
			(xy 129.4551 -228.024275) (xy 129.499174 -227.998829) (xy 129.54676 -227.980782) (xy 129.596624 -227.970602)
			(xy 129.647476 -227.968553) (xy 129.697997 -227.974687) (xy 129.746881 -227.988847) (xy 129.79286 -228.010664)
			(xy 129.834744 -228.039574) (xy 129.871448 -228.074829) (xy 129.902021 -228.115515) (xy 129.925672 -228.160578)
			(xy 129.941788 -228.208852) (xy 129.949952 -228.259086) (xy 129.950464 -228.284532) (xy 130.268992 -228.284532)
			(xy 130.272952 -228.235478) (xy 130.284729 -228.187694) (xy 130.30402 -228.142418) (xy 130.330323 -228.100822)
			(xy 130.362958 -228.063985) (xy 130.401079 -228.03286) (xy 130.4437 -228.008253) (xy 130.489716 -227.990801)
			(xy 130.537935 -227.980957) (xy 130.58711 -227.978976) (xy 130.635965 -227.984908) (xy 130.683236 -227.9986)
			(xy 130.727698 -228.019698) (xy 130.768201 -228.047654) (xy 130.803694 -228.081746) (xy 130.833259 -228.12109)
			(xy 130.85613 -228.164667) (xy 130.871714 -228.211348) (xy 130.879609 -228.259925) (xy 130.880104 -228.284532)
			(xy 131.198615 -228.284532) (xy 131.20271 -228.233804) (xy 131.214889 -228.18439) (xy 131.234837 -228.13757)
			(xy 131.262038 -228.094556) (xy 131.295786 -228.056462) (xy 131.335208 -228.024275) (xy 131.379282 -227.998829)
			(xy 131.426868 -227.980782) (xy 131.476732 -227.970602) (xy 131.527584 -227.968553) (xy 131.578105 -227.974687)
			(xy 131.626989 -227.988847) (xy 131.672968 -228.010664) (xy 131.714852 -228.039574) (xy 131.751556 -228.074829)
			(xy 131.782129 -228.115515) (xy 131.80578 -228.160578) (xy 131.821896 -228.208852) (xy 131.83006 -228.259086)
			(xy 131.830572 -228.284532) (xy 132.138415 -228.284532) (xy 132.14251 -228.233804) (xy 132.154689 -228.18439)
			(xy 132.174637 -228.13757) (xy 132.201838 -228.094556) (xy 132.235586 -228.056462) (xy 132.275008 -228.024275)
			(xy 132.319082 -227.998829) (xy 132.366668 -227.980782) (xy 132.416532 -227.970602) (xy 132.467384 -227.968553)
			(xy 132.517905 -227.974687) (xy 132.566789 -227.988847) (xy 132.612768 -228.010664) (xy 132.654652 -228.039574)
			(xy 132.691356 -228.074829) (xy 132.721929 -228.115515) (xy 132.74558 -228.160578) (xy 132.761696 -228.208852)
			(xy 132.76986 -228.259086) (xy 132.770372 -228.284532) (xy 133.0889 -228.284532) (xy 133.09286 -228.235478)
			(xy 133.104637 -228.187694) (xy 133.123928 -228.142418) (xy 133.150231 -228.100822) (xy 133.182866 -228.063985)
			(xy 133.220987 -228.03286) (xy 133.263608 -228.008253) (xy 133.309624 -227.990801) (xy 133.357843 -227.980957)
			(xy 133.407018 -227.978976) (xy 133.455873 -227.984908) (xy 133.503144 -227.9986) (xy 133.547606 -228.019698)
			(xy 133.588109 -228.047654) (xy 133.623602 -228.081746) (xy 133.653167 -228.12109) (xy 133.676038 -228.164667)
			(xy 133.691622 -228.211348) (xy 133.699517 -228.259925) (xy 133.700012 -228.284532) (xy 134.028954 -228.284532)
			(xy 134.032914 -228.235478) (xy 134.044691 -228.187694) (xy 134.063982 -228.142418) (xy 134.090285 -228.100822)
			(xy 134.12292 -228.063985) (xy 134.161041 -228.03286) (xy 134.203662 -228.008253) (xy 134.249678 -227.990801)
			(xy 134.297897 -227.980957) (xy 134.347072 -227.978976) (xy 134.395927 -227.984908) (xy 134.443198 -227.9986)
			(xy 134.48766 -228.019698) (xy 134.528163 -228.047654) (xy 134.563656 -228.081746) (xy 134.593221 -228.12109)
			(xy 134.616092 -228.164667) (xy 134.631676 -228.211348) (xy 134.639571 -228.259925) (xy 134.640066 -228.284532)
			(xy 134.969008 -228.284532) (xy 134.972968 -228.235478) (xy 134.984745 -228.187694) (xy 135.004036 -228.142418)
			(xy 135.030339 -228.100822) (xy 135.062974 -228.063985) (xy 135.101095 -228.03286) (xy 135.143716 -228.008253)
			(xy 135.189732 -227.990801) (xy 135.237951 -227.980957) (xy 135.287126 -227.978976) (xy 135.335981 -227.984908)
			(xy 135.383252 -227.9986) (xy 135.427714 -228.019698) (xy 135.468217 -228.047654) (xy 135.50371 -228.081746)
			(xy 135.533275 -228.12109) (xy 135.556146 -228.164667) (xy 135.57173 -228.211348) (xy 135.579625 -228.259925)
			(xy 135.58012 -228.284532) (xy 135.909062 -228.284532) (xy 135.913022 -228.235478) (xy 135.924799 -228.187694)
			(xy 135.94409 -228.142418) (xy 135.970393 -228.100822) (xy 136.003028 -228.063985) (xy 136.041149 -228.03286)
			(xy 136.08377 -228.008253) (xy 136.129786 -227.990801) (xy 136.178005 -227.980957) (xy 136.22718 -227.978976)
			(xy 136.276035 -227.984908) (xy 136.323306 -227.9986) (xy 136.367768 -228.019698) (xy 136.408271 -228.047654)
			(xy 136.443764 -228.081746) (xy 136.473329 -228.12109) (xy 136.4962 -228.164667) (xy 136.511784 -228.211348)
			(xy 136.519679 -228.259925) (xy 136.520174 -228.284532) (xy 136.848862 -228.284532) (xy 136.852822 -228.235478)
			(xy 136.864599 -228.187694) (xy 136.88389 -228.142418) (xy 136.910193 -228.100822) (xy 136.942828 -228.063985)
			(xy 136.980949 -228.03286) (xy 137.02357 -228.008253) (xy 137.069586 -227.990801) (xy 137.117805 -227.980957)
			(xy 137.16698 -227.978976) (xy 137.215835 -227.984908) (xy 137.263106 -227.9986) (xy 137.307568 -228.019698)
			(xy 137.348071 -228.047654) (xy 137.383564 -228.081746) (xy 137.413129 -228.12109) (xy 137.436 -228.164667)
			(xy 137.451584 -228.211348) (xy 137.459479 -228.259925) (xy 137.459974 -228.284532) (xy 137.788916 -228.284532)
			(xy 137.792876 -228.235478) (xy 137.804653 -228.187694) (xy 137.823944 -228.142418) (xy 137.850247 -228.100822)
			(xy 137.882882 -228.063985) (xy 137.921003 -228.03286) (xy 137.963624 -228.008253) (xy 138.00964 -227.990801)
			(xy 138.057859 -227.980957) (xy 138.107034 -227.978976) (xy 138.155889 -227.984908) (xy 138.20316 -227.9986)
			(xy 138.247622 -228.019698) (xy 138.288125 -228.047654) (xy 138.323618 -228.081746) (xy 138.353183 -228.12109)
			(xy 138.376054 -228.164667) (xy 138.391638 -228.211348) (xy 138.399533 -228.259925) (xy 138.400028 -228.284532)
			(xy 138.72897 -228.284532) (xy 138.73293 -228.235478) (xy 138.744707 -228.187694) (xy 138.763998 -228.142418)
			(xy 138.790301 -228.100822) (xy 138.822936 -228.063985) (xy 138.861057 -228.03286) (xy 138.903678 -228.008253)
			(xy 138.949694 -227.990801) (xy 138.997913 -227.980957) (xy 139.047088 -227.978976) (xy 139.095943 -227.984908)
			(xy 139.143214 -227.9986) (xy 139.187676 -228.019698) (xy 139.228179 -228.047654) (xy 139.263672 -228.081746)
			(xy 139.293237 -228.12109) (xy 139.316108 -228.164667) (xy 139.331692 -228.211348) (xy 139.339587 -228.259925)
			(xy 139.340082 -228.284532) (xy 139.339587 -228.309139) (xy 139.331692 -228.357716) (xy 139.316108 -228.404397)
			(xy 139.293237 -228.447974) (xy 139.263672 -228.487318) (xy 139.228179 -228.52141) (xy 139.187676 -228.549366)
			(xy 139.143214 -228.570464) (xy 139.095943 -228.584156) (xy 139.047088 -228.590088) (xy 138.997913 -228.588107)
			(xy 138.949694 -228.578263) (xy 138.903678 -228.560811) (xy 138.861057 -228.536204) (xy 138.822936 -228.505079)
			(xy 138.790301 -228.468242) (xy 138.763998 -228.426646) (xy 138.744707 -228.38137) (xy 138.73293 -228.333586)
			(xy 138.72897 -228.284532) (xy 138.400028 -228.284532) (xy 138.399533 -228.309139) (xy 138.391638 -228.357716)
			(xy 138.376054 -228.404397) (xy 138.353183 -228.447974) (xy 138.323618 -228.487318) (xy 138.288125 -228.52141)
			(xy 138.247622 -228.549366) (xy 138.20316 -228.570464) (xy 138.155889 -228.584156) (xy 138.107034 -228.590088)
			(xy 138.057859 -228.588107) (xy 138.00964 -228.578263) (xy 137.963624 -228.560811) (xy 137.921003 -228.536204)
			(xy 137.882882 -228.505079) (xy 137.850247 -228.468242) (xy 137.823944 -228.426646) (xy 137.804653 -228.38137)
			(xy 137.792876 -228.333586) (xy 137.788916 -228.284532) (xy 137.459974 -228.284532) (xy 137.459479 -228.309139)
			(xy 137.451584 -228.357716) (xy 137.436 -228.404397) (xy 137.413129 -228.447974) (xy 137.383564 -228.487318)
			(xy 137.348071 -228.52141) (xy 137.307568 -228.549366) (xy 137.263106 -228.570464) (xy 137.215835 -228.584156)
			(xy 137.16698 -228.590088) (xy 137.117805 -228.588107) (xy 137.069586 -228.578263) (xy 137.02357 -228.560811)
			(xy 136.980949 -228.536204) (xy 136.942828 -228.505079) (xy 136.910193 -228.468242) (xy 136.88389 -228.426646)
			(xy 136.864599 -228.38137) (xy 136.852822 -228.333586) (xy 136.848862 -228.284532) (xy 136.520174 -228.284532)
			(xy 136.519679 -228.309139) (xy 136.511784 -228.357716) (xy 136.4962 -228.404397) (xy 136.473329 -228.447974)
			(xy 136.443764 -228.487318) (xy 136.408271 -228.52141) (xy 136.367768 -228.549366) (xy 136.323306 -228.570464)
			(xy 136.276035 -228.584156) (xy 136.22718 -228.590088) (xy 136.178005 -228.588107) (xy 136.129786 -228.578263)
			(xy 136.08377 -228.560811) (xy 136.041149 -228.536204) (xy 136.003028 -228.505079) (xy 135.970393 -228.468242)
			(xy 135.94409 -228.426646) (xy 135.924799 -228.38137) (xy 135.913022 -228.333586) (xy 135.909062 -228.284532)
			(xy 135.58012 -228.284532) (xy 135.579625 -228.309139) (xy 135.57173 -228.357716) (xy 135.556146 -228.404397)
			(xy 135.533275 -228.447974) (xy 135.50371 -228.487318) (xy 135.468217 -228.52141) (xy 135.427714 -228.549366)
			(xy 135.383252 -228.570464) (xy 135.335981 -228.584156) (xy 135.287126 -228.590088) (xy 135.237951 -228.588107)
			(xy 135.189732 -228.578263) (xy 135.143716 -228.560811) (xy 135.101095 -228.536204) (xy 135.062974 -228.505079)
			(xy 135.030339 -228.468242) (xy 135.004036 -228.426646) (xy 134.984745 -228.38137) (xy 134.972968 -228.333586)
			(xy 134.969008 -228.284532) (xy 134.640066 -228.284532) (xy 134.639571 -228.309139) (xy 134.631676 -228.357716)
			(xy 134.616092 -228.404397) (xy 134.593221 -228.447974) (xy 134.563656 -228.487318) (xy 134.528163 -228.52141)
			(xy 134.48766 -228.549366) (xy 134.443198 -228.570464) (xy 134.395927 -228.584156) (xy 134.347072 -228.590088)
			(xy 134.297897 -228.588107) (xy 134.249678 -228.578263) (xy 134.203662 -228.560811) (xy 134.161041 -228.536204)
			(xy 134.12292 -228.505079) (xy 134.090285 -228.468242) (xy 134.063982 -228.426646) (xy 134.044691 -228.38137)
			(xy 134.032914 -228.333586) (xy 134.028954 -228.284532) (xy 133.700012 -228.284532) (xy 133.699517 -228.309139)
			(xy 133.691622 -228.357716) (xy 133.676038 -228.404397) (xy 133.653167 -228.447974) (xy 133.623602 -228.487318)
			(xy 133.588109 -228.52141) (xy 133.547606 -228.549366) (xy 133.503144 -228.570464) (xy 133.455873 -228.584156)
			(xy 133.407018 -228.590088) (xy 133.357843 -228.588107) (xy 133.309624 -228.578263) (xy 133.263608 -228.560811)
			(xy 133.220987 -228.536204) (xy 133.182866 -228.505079) (xy 133.150231 -228.468242) (xy 133.123928 -228.426646)
			(xy 133.104637 -228.38137) (xy 133.09286 -228.333586) (xy 133.0889 -228.284532) (xy 132.770372 -228.284532)
			(xy 132.76986 -228.309978) (xy 132.761696 -228.360212) (xy 132.74558 -228.408486) (xy 132.721929 -228.453549)
			(xy 132.691356 -228.494235) (xy 132.654652 -228.52949) (xy 132.612768 -228.5584) (xy 132.566789 -228.580217)
			(xy 132.517905 -228.594377) (xy 132.467384 -228.600511) (xy 132.416532 -228.598462) (xy 132.366668 -228.588282)
			(xy 132.319082 -228.570235) (xy 132.275008 -228.544789) (xy 132.235586 -228.512602) (xy 132.201838 -228.474508)
			(xy 132.174637 -228.431494) (xy 132.154689 -228.384674) (xy 132.14251 -228.33526) (xy 132.138415 -228.284532)
			(xy 131.830572 -228.284532) (xy 131.83006 -228.309978) (xy 131.821896 -228.360212) (xy 131.80578 -228.408486)
			(xy 131.782129 -228.453549) (xy 131.751556 -228.494235) (xy 131.714852 -228.52949) (xy 131.672968 -228.5584)
			(xy 131.626989 -228.580217) (xy 131.578105 -228.594377) (xy 131.527584 -228.600511) (xy 131.476732 -228.598462)
			(xy 131.426868 -228.588282) (xy 131.379282 -228.570235) (xy 131.335208 -228.544789) (xy 131.295786 -228.512602)
			(xy 131.262038 -228.474508) (xy 131.234837 -228.431494) (xy 131.214889 -228.384674) (xy 131.20271 -228.33526)
			(xy 131.198615 -228.284532) (xy 130.880104 -228.284532) (xy 130.879609 -228.309139) (xy 130.871714 -228.357716)
			(xy 130.85613 -228.404397) (xy 130.833259 -228.447974) (xy 130.803694 -228.487318) (xy 130.768201 -228.52141)
			(xy 130.727698 -228.549366) (xy 130.683236 -228.570464) (xy 130.635965 -228.584156) (xy 130.58711 -228.590088)
			(xy 130.537935 -228.588107) (xy 130.489716 -228.578263) (xy 130.4437 -228.560811) (xy 130.401079 -228.536204)
			(xy 130.362958 -228.505079) (xy 130.330323 -228.468242) (xy 130.30402 -228.426646) (xy 130.284729 -228.38137)
			(xy 130.272952 -228.333586) (xy 130.268992 -228.284532) (xy 129.950464 -228.284532) (xy 129.949952 -228.309978)
			(xy 129.941788 -228.360212) (xy 129.925672 -228.408486) (xy 129.902021 -228.453549) (xy 129.871448 -228.494235)
			(xy 129.834744 -228.52949) (xy 129.79286 -228.5584) (xy 129.746881 -228.580217) (xy 129.697997 -228.594377)
			(xy 129.647476 -228.600511) (xy 129.596624 -228.598462) (xy 129.54676 -228.588282) (xy 129.499174 -228.570235)
			(xy 129.4551 -228.544789) (xy 129.415678 -228.512602) (xy 129.38193 -228.474508) (xy 129.354729 -228.431494)
			(xy 129.334781 -228.384674) (xy 129.322602 -228.33526) (xy 129.318507 -228.284532) (xy 128.999996 -228.284532)
			(xy 128.999501 -228.309139) (xy 128.991606 -228.357716) (xy 128.976022 -228.404397) (xy 128.953151 -228.447974)
			(xy 128.923586 -228.487318) (xy 128.888093 -228.52141) (xy 128.84759 -228.549366) (xy 128.803128 -228.570464)
			(xy 128.755857 -228.584156) (xy 128.707002 -228.590088) (xy 128.657827 -228.588107) (xy 128.609608 -228.578263)
			(xy 128.563592 -228.560811) (xy 128.520971 -228.536204) (xy 128.48285 -228.505079) (xy 128.450215 -228.468242)
			(xy 128.423912 -228.426646) (xy 128.404621 -228.38137) (xy 128.392844 -228.333586) (xy 128.388884 -228.284532)
			(xy 128.070356 -228.284532) (xy 128.069844 -228.309978) (xy 128.06168 -228.360212) (xy 128.045564 -228.408486)
			(xy 128.021913 -228.453549) (xy 127.99134 -228.494235) (xy 127.954636 -228.52949) (xy 127.912752 -228.5584)
			(xy 127.866773 -228.580217) (xy 127.817889 -228.594377) (xy 127.767368 -228.600511) (xy 127.716516 -228.598462)
			(xy 127.666652 -228.588282) (xy 127.619066 -228.570235) (xy 127.574992 -228.544789) (xy 127.53557 -228.512602)
			(xy 127.501822 -228.474508) (xy 127.474621 -228.431494) (xy 127.454673 -228.384674) (xy 127.442494 -228.33526)
			(xy 127.438399 -228.284532) (xy 127.120142 -228.284532) (xy 127.119709 -228.308014) (xy 127.112516 -228.354423)
			(xy 127.098303 -228.399185) (xy 127.077407 -228.441243) (xy 127.050319 -228.479607) (xy 127.017678 -228.513374)
			(xy 126.980254 -228.541746) (xy 126.938927 -228.564055) (xy 126.916942 -228.572314) (xy 126.909322 -228.574854)
			(xy 126.896876 -228.584252) (xy 126.892558 -228.590602) (xy 126.888229 -228.597187) (xy 126.883439 -228.612191)
			(xy 126.88316 -228.620066) (xy 126.88316 -229.094538) (xy 127.908553 -229.094538) (xy 127.912648 -229.04381)
			(xy 127.924827 -228.994396) (xy 127.944775 -228.947576) (xy 127.971976 -228.904562) (xy 128.005724 -228.866468)
			(xy 128.045146 -228.834281) (xy 128.08922 -228.808835) (xy 128.136806 -228.790788) (xy 128.18667 -228.780608)
			(xy 128.237522 -228.778559) (xy 128.288043 -228.784693) (xy 128.336927 -228.798853) (xy 128.382906 -228.82067)
			(xy 128.42479 -228.84958) (xy 128.461494 -228.884835) (xy 128.492067 -228.925521) (xy 128.515718 -228.970584)
			(xy 128.531834 -229.018858) (xy 128.539998 -229.069092) (xy 128.54051 -229.094538) (xy 128.848607 -229.094538)
			(xy 128.852702 -229.04381) (xy 128.864881 -228.994396) (xy 128.884829 -228.947576) (xy 128.91203 -228.904562)
			(xy 128.945778 -228.866468) (xy 128.9852 -228.834281) (xy 129.029274 -228.808835) (xy 129.07686 -228.790788)
			(xy 129.126724 -228.780608) (xy 129.177576 -228.778559) (xy 129.228097 -228.784693) (xy 129.276981 -228.798853)
			(xy 129.32296 -228.82067) (xy 129.364844 -228.84958) (xy 129.401548 -228.884835) (xy 129.432121 -228.925521)
			(xy 129.455772 -228.970584) (xy 129.471888 -229.018858) (xy 129.480052 -229.069092) (xy 129.480564 -229.094538)
			(xy 129.798838 -229.094538) (xy 129.802798 -229.045484) (xy 129.814575 -228.9977) (xy 129.833866 -228.952424)
			(xy 129.860169 -228.910828) (xy 129.892804 -228.873991) (xy 129.930925 -228.842866) (xy 129.973546 -228.818259)
			(xy 130.019562 -228.800807) (xy 130.067781 -228.790963) (xy 130.116956 -228.788982) (xy 130.165811 -228.794914)
			(xy 130.213082 -228.808606) (xy 130.257544 -228.829704) (xy 130.298047 -228.85766) (xy 130.33354 -228.891752)
			(xy 130.363105 -228.931096) (xy 130.385976 -228.974673) (xy 130.40156 -229.021354) (xy 130.409455 -229.069931)
			(xy 130.40995 -229.094538) (xy 130.728461 -229.094538) (xy 130.732556 -229.04381) (xy 130.744735 -228.994396)
			(xy 130.764683 -228.947576) (xy 130.791884 -228.904562) (xy 130.825632 -228.866468) (xy 130.865054 -228.834281)
			(xy 130.909128 -228.808835) (xy 130.956714 -228.790788) (xy 131.006578 -228.780608) (xy 131.05743 -228.778559)
			(xy 131.107951 -228.784693) (xy 131.156835 -228.798853) (xy 131.202814 -228.82067) (xy 131.244698 -228.84958)
			(xy 131.281402 -228.884835) (xy 131.311975 -228.925521) (xy 131.335626 -228.970584) (xy 131.351742 -229.018858)
			(xy 131.359906 -229.069092) (xy 131.360418 -229.094538) (xy 131.678946 -229.094538) (xy 131.682906 -229.045484)
			(xy 131.694683 -228.9977) (xy 131.713974 -228.952424) (xy 131.740277 -228.910828) (xy 131.772912 -228.873991)
			(xy 131.811033 -228.842866) (xy 131.853654 -228.818259) (xy 131.89967 -228.800807) (xy 131.947889 -228.790963)
			(xy 131.997064 -228.788982) (xy 132.045919 -228.794914) (xy 132.09319 -228.808606) (xy 132.137652 -228.829704)
			(xy 132.178155 -228.85766) (xy 132.213648 -228.891752) (xy 132.243213 -228.931096) (xy 132.266084 -228.974673)
			(xy 132.281668 -229.021354) (xy 132.289563 -229.069931) (xy 132.290058 -229.094538) (xy 132.608569 -229.094538)
			(xy 132.612664 -229.04381) (xy 132.624843 -228.994396) (xy 132.644791 -228.947576) (xy 132.671992 -228.904562)
			(xy 132.70574 -228.866468) (xy 132.745162 -228.834281) (xy 132.789236 -228.808835) (xy 132.836822 -228.790788)
			(xy 132.886686 -228.780608) (xy 132.937538 -228.778559) (xy 132.988059 -228.784693) (xy 133.036943 -228.798853)
			(xy 133.082922 -228.82067) (xy 133.124806 -228.84958) (xy 133.16151 -228.884835) (xy 133.192083 -228.925521)
			(xy 133.215734 -228.970584) (xy 133.23185 -229.018858) (xy 133.240014 -229.069092) (xy 133.240526 -229.094538)
			(xy 133.559054 -229.094538) (xy 133.563014 -229.045484) (xy 133.574791 -228.9977) (xy 133.594082 -228.952424)
			(xy 133.620385 -228.910828) (xy 133.65302 -228.873991) (xy 133.691141 -228.842866) (xy 133.733762 -228.818259)
			(xy 133.779778 -228.800807) (xy 133.827997 -228.790963) (xy 133.877172 -228.788982) (xy 133.926027 -228.794914)
			(xy 133.973298 -228.808606) (xy 134.01776 -228.829704) (xy 134.058263 -228.85766) (xy 134.093756 -228.891752)
			(xy 134.123321 -228.931096) (xy 134.146192 -228.974673) (xy 134.161776 -229.021354) (xy 134.169671 -229.069931)
			(xy 134.170166 -229.094538) (xy 134.498854 -229.094538) (xy 134.502814 -229.045484) (xy 134.514591 -228.9977)
			(xy 134.533882 -228.952424) (xy 134.560185 -228.910828) (xy 134.59282 -228.873991) (xy 134.630941 -228.842866)
			(xy 134.673562 -228.818259) (xy 134.719578 -228.800807) (xy 134.767797 -228.790963) (xy 134.816972 -228.788982)
			(xy 134.865827 -228.794914) (xy 134.913098 -228.808606) (xy 134.95756 -228.829704) (xy 134.998063 -228.85766)
			(xy 135.033556 -228.891752) (xy 135.063121 -228.931096) (xy 135.085992 -228.974673) (xy 135.101576 -229.021354)
			(xy 135.109471 -229.069931) (xy 135.109966 -229.094538) (xy 135.438908 -229.094538) (xy 135.442868 -229.045484)
			(xy 135.454645 -228.9977) (xy 135.473936 -228.952424) (xy 135.500239 -228.910828) (xy 135.532874 -228.873991)
			(xy 135.570995 -228.842866) (xy 135.613616 -228.818259) (xy 135.659632 -228.800807) (xy 135.707851 -228.790963)
			(xy 135.757026 -228.788982) (xy 135.805881 -228.794914) (xy 135.853152 -228.808606) (xy 135.897614 -228.829704)
			(xy 135.938117 -228.85766) (xy 135.97361 -228.891752) (xy 136.003175 -228.931096) (xy 136.026046 -228.974673)
			(xy 136.04163 -229.021354) (xy 136.049525 -229.069931) (xy 136.05002 -229.094538) (xy 136.378962 -229.094538)
			(xy 136.382922 -229.045484) (xy 136.394699 -228.9977) (xy 136.41399 -228.952424) (xy 136.440293 -228.910828)
			(xy 136.472928 -228.873991) (xy 136.511049 -228.842866) (xy 136.55367 -228.818259) (xy 136.599686 -228.800807)
			(xy 136.647905 -228.790963) (xy 136.69708 -228.788982) (xy 136.745935 -228.794914) (xy 136.793206 -228.808606)
			(xy 136.837668 -228.829704) (xy 136.878171 -228.85766) (xy 136.913664 -228.891752) (xy 136.943229 -228.931096)
			(xy 136.9661 -228.974673) (xy 136.981684 -229.021354) (xy 136.989579 -229.069931) (xy 136.990074 -229.094538)
			(xy 137.319016 -229.094538) (xy 137.322976 -229.045484) (xy 137.334753 -228.9977) (xy 137.354044 -228.952424)
			(xy 137.380347 -228.910828) (xy 137.412982 -228.873991) (xy 137.451103 -228.842866) (xy 137.493724 -228.818259)
			(xy 137.53974 -228.800807) (xy 137.587959 -228.790963) (xy 137.637134 -228.788982) (xy 137.685989 -228.794914)
			(xy 137.73326 -228.808606) (xy 137.777722 -228.829704) (xy 137.818225 -228.85766) (xy 137.853718 -228.891752)
			(xy 137.883283 -228.931096) (xy 137.906154 -228.974673) (xy 137.921738 -229.021354) (xy 137.929633 -229.069931)
			(xy 137.930128 -229.094538) (xy 138.25907 -229.094538) (xy 138.26303 -229.045484) (xy 138.274807 -228.9977)
			(xy 138.294098 -228.952424) (xy 138.320401 -228.910828) (xy 138.353036 -228.873991) (xy 138.391157 -228.842866)
			(xy 138.433778 -228.818259) (xy 138.479794 -228.800807) (xy 138.528013 -228.790963) (xy 138.577188 -228.788982)
			(xy 138.626043 -228.794914) (xy 138.673314 -228.808606) (xy 138.717776 -228.829704) (xy 138.758279 -228.85766)
			(xy 138.793772 -228.891752) (xy 138.823337 -228.931096) (xy 138.846208 -228.974673) (xy 138.861792 -229.021354)
			(xy 138.869687 -229.069931) (xy 138.870182 -229.094538) (xy 139.19887 -229.094538) (xy 139.20283 -229.045484)
			(xy 139.214607 -228.9977) (xy 139.233898 -228.952424) (xy 139.260201 -228.910828) (xy 139.292836 -228.873991)
			(xy 139.330957 -228.842866) (xy 139.373578 -228.818259) (xy 139.419594 -228.800807) (xy 139.467813 -228.790963)
			(xy 139.516988 -228.788982) (xy 139.565843 -228.794914) (xy 139.613114 -228.808606) (xy 139.657576 -228.829704)
			(xy 139.698079 -228.85766) (xy 139.733572 -228.891752) (xy 139.763137 -228.931096) (xy 139.786008 -228.974673)
			(xy 139.801592 -229.021354) (xy 139.809487 -229.069931) (xy 139.809982 -229.094538) (xy 139.809487 -229.119145)
			(xy 139.801592 -229.167722) (xy 139.786008 -229.214403) (xy 139.763137 -229.25798) (xy 139.733572 -229.297324)
			(xy 139.698079 -229.331416) (xy 139.657576 -229.359372) (xy 139.613114 -229.38047) (xy 139.565843 -229.394162)
			(xy 139.516988 -229.400094) (xy 139.467813 -229.398113) (xy 139.419594 -229.388269) (xy 139.373578 -229.370817)
			(xy 139.330957 -229.34621) (xy 139.292836 -229.315085) (xy 139.260201 -229.278248) (xy 139.233898 -229.236652)
			(xy 139.214607 -229.191376) (xy 139.20283 -229.143592) (xy 139.19887 -229.094538) (xy 138.870182 -229.094538)
			(xy 138.869687 -229.119145) (xy 138.861792 -229.167722) (xy 138.846208 -229.214403) (xy 138.823337 -229.25798)
			(xy 138.793772 -229.297324) (xy 138.758279 -229.331416) (xy 138.717776 -229.359372) (xy 138.673314 -229.38047)
			(xy 138.626043 -229.394162) (xy 138.577188 -229.400094) (xy 138.528013 -229.398113) (xy 138.479794 -229.388269)
			(xy 138.433778 -229.370817) (xy 138.391157 -229.34621) (xy 138.353036 -229.315085) (xy 138.320401 -229.278248)
			(xy 138.294098 -229.236652) (xy 138.274807 -229.191376) (xy 138.26303 -229.143592) (xy 138.25907 -229.094538)
			(xy 137.930128 -229.094538) (xy 137.929633 -229.119145) (xy 137.921738 -229.167722) (xy 137.906154 -229.214403)
			(xy 137.883283 -229.25798) (xy 137.853718 -229.297324) (xy 137.818225 -229.331416) (xy 137.777722 -229.359372)
			(xy 137.73326 -229.38047) (xy 137.685989 -229.394162) (xy 137.637134 -229.400094) (xy 137.587959 -229.398113)
			(xy 137.53974 -229.388269) (xy 137.493724 -229.370817) (xy 137.451103 -229.34621) (xy 137.412982 -229.315085)
			(xy 137.380347 -229.278248) (xy 137.354044 -229.236652) (xy 137.334753 -229.191376) (xy 137.322976 -229.143592)
			(xy 137.319016 -229.094538) (xy 136.990074 -229.094538) (xy 136.989579 -229.119145) (xy 136.981684 -229.167722)
			(xy 136.9661 -229.214403) (xy 136.943229 -229.25798) (xy 136.913664 -229.297324) (xy 136.878171 -229.331416)
			(xy 136.837668 -229.359372) (xy 136.793206 -229.38047) (xy 136.745935 -229.394162) (xy 136.69708 -229.400094)
			(xy 136.647905 -229.398113) (xy 136.599686 -229.388269) (xy 136.55367 -229.370817) (xy 136.511049 -229.34621)
			(xy 136.472928 -229.315085) (xy 136.440293 -229.278248) (xy 136.41399 -229.236652) (xy 136.394699 -229.191376)
			(xy 136.382922 -229.143592) (xy 136.378962 -229.094538) (xy 136.05002 -229.094538) (xy 136.049525 -229.119145)
			(xy 136.04163 -229.167722) (xy 136.026046 -229.214403) (xy 136.003175 -229.25798) (xy 135.97361 -229.297324)
			(xy 135.938117 -229.331416) (xy 135.897614 -229.359372) (xy 135.853152 -229.38047) (xy 135.805881 -229.394162)
			(xy 135.757026 -229.400094) (xy 135.707851 -229.398113) (xy 135.659632 -229.388269) (xy 135.613616 -229.370817)
			(xy 135.570995 -229.34621) (xy 135.532874 -229.315085) (xy 135.500239 -229.278248) (xy 135.473936 -229.236652)
			(xy 135.454645 -229.191376) (xy 135.442868 -229.143592) (xy 135.438908 -229.094538) (xy 135.109966 -229.094538)
			(xy 135.109471 -229.119145) (xy 135.101576 -229.167722) (xy 135.085992 -229.214403) (xy 135.063121 -229.25798)
			(xy 135.033556 -229.297324) (xy 134.998063 -229.331416) (xy 134.95756 -229.359372) (xy 134.913098 -229.38047)
			(xy 134.865827 -229.394162) (xy 134.816972 -229.400094) (xy 134.767797 -229.398113) (xy 134.719578 -229.388269)
			(xy 134.673562 -229.370817) (xy 134.630941 -229.34621) (xy 134.59282 -229.315085) (xy 134.560185 -229.278248)
			(xy 134.533882 -229.236652) (xy 134.514591 -229.191376) (xy 134.502814 -229.143592) (xy 134.498854 -229.094538)
			(xy 134.170166 -229.094538) (xy 134.169671 -229.119145) (xy 134.161776 -229.167722) (xy 134.146192 -229.214403)
			(xy 134.123321 -229.25798) (xy 134.093756 -229.297324) (xy 134.058263 -229.331416) (xy 134.01776 -229.359372)
			(xy 133.973298 -229.38047) (xy 133.926027 -229.394162) (xy 133.877172 -229.400094) (xy 133.827997 -229.398113)
			(xy 133.779778 -229.388269) (xy 133.733762 -229.370817) (xy 133.691141 -229.34621) (xy 133.65302 -229.315085)
			(xy 133.620385 -229.278248) (xy 133.594082 -229.236652) (xy 133.574791 -229.191376) (xy 133.563014 -229.143592)
			(xy 133.559054 -229.094538) (xy 133.240526 -229.094538) (xy 133.240014 -229.119984) (xy 133.23185 -229.170218)
			(xy 133.215734 -229.218492) (xy 133.192083 -229.263555) (xy 133.16151 -229.304241) (xy 133.124806 -229.339496)
			(xy 133.082922 -229.368406) (xy 133.036943 -229.390223) (xy 132.988059 -229.404383) (xy 132.937538 -229.410517)
			(xy 132.886686 -229.408468) (xy 132.836822 -229.398288) (xy 132.789236 -229.380241) (xy 132.745162 -229.354795)
			(xy 132.70574 -229.322608) (xy 132.671992 -229.284514) (xy 132.644791 -229.2415) (xy 132.624843 -229.19468)
			(xy 132.612664 -229.145266) (xy 132.608569 -229.094538) (xy 132.290058 -229.094538) (xy 132.289563 -229.119145)
			(xy 132.281668 -229.167722) (xy 132.266084 -229.214403) (xy 132.243213 -229.25798) (xy 132.213648 -229.297324)
			(xy 132.178155 -229.331416) (xy 132.137652 -229.359372) (xy 132.09319 -229.38047) (xy 132.045919 -229.394162)
			(xy 131.997064 -229.400094) (xy 131.947889 -229.398113) (xy 131.89967 -229.388269) (xy 131.853654 -229.370817)
			(xy 131.811033 -229.34621) (xy 131.772912 -229.315085) (xy 131.740277 -229.278248) (xy 131.713974 -229.236652)
			(xy 131.694683 -229.191376) (xy 131.682906 -229.143592) (xy 131.678946 -229.094538) (xy 131.360418 -229.094538)
			(xy 131.359906 -229.119984) (xy 131.351742 -229.170218) (xy 131.335626 -229.218492) (xy 131.311975 -229.263555)
			(xy 131.281402 -229.304241) (xy 131.244698 -229.339496) (xy 131.202814 -229.368406) (xy 131.156835 -229.390223)
			(xy 131.107951 -229.404383) (xy 131.05743 -229.410517) (xy 131.006578 -229.408468) (xy 130.956714 -229.398288)
			(xy 130.909128 -229.380241) (xy 130.865054 -229.354795) (xy 130.825632 -229.322608) (xy 130.791884 -229.284514)
			(xy 130.764683 -229.2415) (xy 130.744735 -229.19468) (xy 130.732556 -229.145266) (xy 130.728461 -229.094538)
			(xy 130.40995 -229.094538) (xy 130.409455 -229.119145) (xy 130.40156 -229.167722) (xy 130.385976 -229.214403)
			(xy 130.363105 -229.25798) (xy 130.33354 -229.297324) (xy 130.298047 -229.331416) (xy 130.257544 -229.359372)
			(xy 130.213082 -229.38047) (xy 130.165811 -229.394162) (xy 130.116956 -229.400094) (xy 130.067781 -229.398113)
			(xy 130.019562 -229.388269) (xy 129.973546 -229.370817) (xy 129.930925 -229.34621) (xy 129.892804 -229.315085)
			(xy 129.860169 -229.278248) (xy 129.833866 -229.236652) (xy 129.814575 -229.191376) (xy 129.802798 -229.143592)
			(xy 129.798838 -229.094538) (xy 129.480564 -229.094538) (xy 129.480052 -229.119984) (xy 129.471888 -229.170218)
			(xy 129.455772 -229.218492) (xy 129.432121 -229.263555) (xy 129.401548 -229.304241) (xy 129.364844 -229.339496)
			(xy 129.32296 -229.368406) (xy 129.276981 -229.390223) (xy 129.228097 -229.404383) (xy 129.177576 -229.410517)
			(xy 129.126724 -229.408468) (xy 129.07686 -229.398288) (xy 129.029274 -229.380241) (xy 128.9852 -229.354795)
			(xy 128.945778 -229.322608) (xy 128.91203 -229.284514) (xy 128.884829 -229.2415) (xy 128.864881 -229.19468)
			(xy 128.852702 -229.145266) (xy 128.848607 -229.094538) (xy 128.54051 -229.094538) (xy 128.539998 -229.119984)
			(xy 128.531834 -229.170218) (xy 128.515718 -229.218492) (xy 128.492067 -229.263555) (xy 128.461494 -229.304241)
			(xy 128.42479 -229.339496) (xy 128.382906 -229.368406) (xy 128.336927 -229.390223) (xy 128.288043 -229.404383)
			(xy 128.237522 -229.410517) (xy 128.18667 -229.408468) (xy 128.136806 -229.398288) (xy 128.08922 -229.380241)
			(xy 128.045146 -229.354795) (xy 128.005724 -229.322608) (xy 127.971976 -229.284514) (xy 127.944775 -229.2415)
			(xy 127.924827 -229.19468) (xy 127.912648 -229.145266) (xy 127.908553 -229.094538) (xy 126.88316 -229.094538)
			(xy 126.88316 -229.568756) (xy 126.883459 -229.576627) (xy 126.888253 -229.591622) (xy 126.892558 -229.59822)
			(xy 126.896876 -229.60457) (xy 126.909322 -229.613968) (xy 126.916942 -229.616508) (xy 126.940381 -229.625362)
			(xy 126.984228 -229.649602) (xy 127.023531 -229.680674) (xy 127.057234 -229.717745) (xy 127.084434 -229.759819)
			(xy 127.104402 -229.80577) (xy 127.116601 -229.854364) (xy 127.120703 -229.90429) (xy 127.438399 -229.90429)
			(xy 127.442494 -229.853562) (xy 127.454673 -229.804148) (xy 127.474621 -229.757328) (xy 127.501822 -229.714314)
			(xy 127.53557 -229.67622) (xy 127.574992 -229.644033) (xy 127.619066 -229.618587) (xy 127.666652 -229.60054)
			(xy 127.716516 -229.59036) (xy 127.767368 -229.588311) (xy 127.817889 -229.594445) (xy 127.866773 -229.608605)
			(xy 127.912752 -229.630422) (xy 127.954636 -229.659332) (xy 127.99134 -229.694587) (xy 128.021913 -229.735273)
			(xy 128.045564 -229.780336) (xy 128.06168 -229.82861) (xy 128.069844 -229.878844) (xy 128.070356 -229.90429)
			(xy 128.388884 -229.90429) (xy 128.392844 -229.855236) (xy 128.404621 -229.807452) (xy 128.423912 -229.762176)
			(xy 128.450215 -229.72058) (xy 128.48285 -229.683743) (xy 128.520971 -229.652618) (xy 128.563592 -229.628011)
			(xy 128.609608 -229.610559) (xy 128.657827 -229.600715) (xy 128.707002 -229.598734) (xy 128.755857 -229.604666)
			(xy 128.803128 -229.618358) (xy 128.84759 -229.639456) (xy 128.888093 -229.667412) (xy 128.923586 -229.701504)
			(xy 128.953151 -229.740848) (xy 128.976022 -229.784425) (xy 128.991606 -229.831106) (xy 128.999501 -229.879683)
			(xy 128.999996 -229.90429) (xy 129.318507 -229.90429) (xy 129.322602 -229.853562) (xy 129.334781 -229.804148)
			(xy 129.354729 -229.757328) (xy 129.38193 -229.714314) (xy 129.415678 -229.67622) (xy 129.4551 -229.644033)
			(xy 129.499174 -229.618587) (xy 129.54676 -229.60054) (xy 129.596624 -229.59036) (xy 129.647476 -229.588311)
			(xy 129.697997 -229.594445) (xy 129.746881 -229.608605) (xy 129.79286 -229.630422) (xy 129.834744 -229.659332)
			(xy 129.871448 -229.694587) (xy 129.902021 -229.735273) (xy 129.925672 -229.780336) (xy 129.941788 -229.82861)
			(xy 129.949952 -229.878844) (xy 129.950464 -229.90429) (xy 131.198615 -229.90429) (xy 131.20271 -229.853562)
			(xy 131.214889 -229.804148) (xy 131.234837 -229.757328) (xy 131.262038 -229.714314) (xy 131.295786 -229.67622)
			(xy 131.335208 -229.644033) (xy 131.379282 -229.618587) (xy 131.426868 -229.60054) (xy 131.476732 -229.59036)
			(xy 131.527584 -229.588311) (xy 131.578105 -229.594445) (xy 131.626989 -229.608605) (xy 131.672968 -229.630422)
			(xy 131.714852 -229.659332) (xy 131.751556 -229.694587) (xy 131.782129 -229.735273) (xy 131.80578 -229.780336)
			(xy 131.821896 -229.82861) (xy 131.83006 -229.878844) (xy 131.830572 -229.90429) (xy 132.138415 -229.90429)
			(xy 132.14251 -229.853562) (xy 132.154689 -229.804148) (xy 132.174637 -229.757328) (xy 132.201838 -229.714314)
			(xy 132.235586 -229.67622) (xy 132.275008 -229.644033) (xy 132.319082 -229.618587) (xy 132.366668 -229.60054)
			(xy 132.416532 -229.59036) (xy 132.467384 -229.588311) (xy 132.517905 -229.594445) (xy 132.566789 -229.608605)
			(xy 132.612768 -229.630422) (xy 132.654652 -229.659332) (xy 132.691356 -229.694587) (xy 132.721929 -229.735273)
			(xy 132.74558 -229.780336) (xy 132.761696 -229.82861) (xy 132.76986 -229.878844) (xy 132.770372 -229.90429)
			(xy 133.0889 -229.90429) (xy 133.09286 -229.855236) (xy 133.104637 -229.807452) (xy 133.123928 -229.762176)
			(xy 133.150231 -229.72058) (xy 133.182866 -229.683743) (xy 133.220987 -229.652618) (xy 133.263608 -229.628011)
			(xy 133.309624 -229.610559) (xy 133.357843 -229.600715) (xy 133.407018 -229.598734) (xy 133.455873 -229.604666)
			(xy 133.503144 -229.618358) (xy 133.547606 -229.639456) (xy 133.588109 -229.667412) (xy 133.623602 -229.701504)
			(xy 133.653167 -229.740848) (xy 133.676038 -229.784425) (xy 133.691622 -229.831106) (xy 133.699517 -229.879683)
			(xy 133.700012 -229.90429) (xy 134.028954 -229.90429) (xy 134.032914 -229.855236) (xy 134.044691 -229.807452)
			(xy 134.063982 -229.762176) (xy 134.090285 -229.72058) (xy 134.12292 -229.683743) (xy 134.161041 -229.652618)
			(xy 134.203662 -229.628011) (xy 134.249678 -229.610559) (xy 134.297897 -229.600715) (xy 134.347072 -229.598734)
			(xy 134.395927 -229.604666) (xy 134.443198 -229.618358) (xy 134.48766 -229.639456) (xy 134.528163 -229.667412)
			(xy 134.563656 -229.701504) (xy 134.593221 -229.740848) (xy 134.616092 -229.784425) (xy 134.631676 -229.831106)
			(xy 134.639571 -229.879683) (xy 134.640066 -229.90429) (xy 134.969008 -229.90429) (xy 134.972968 -229.855236)
			(xy 134.984745 -229.807452) (xy 135.004036 -229.762176) (xy 135.030339 -229.72058) (xy 135.062974 -229.683743)
			(xy 135.101095 -229.652618) (xy 135.143716 -229.628011) (xy 135.189732 -229.610559) (xy 135.237951 -229.600715)
			(xy 135.287126 -229.598734) (xy 135.335981 -229.604666) (xy 135.383252 -229.618358) (xy 135.427714 -229.639456)
			(xy 135.468217 -229.667412) (xy 135.50371 -229.701504) (xy 135.533275 -229.740848) (xy 135.556146 -229.784425)
			(xy 135.57173 -229.831106) (xy 135.579625 -229.879683) (xy 135.58012 -229.90429) (xy 135.909062 -229.90429)
			(xy 135.913022 -229.855236) (xy 135.924799 -229.807452) (xy 135.94409 -229.762176) (xy 135.970393 -229.72058)
			(xy 136.003028 -229.683743) (xy 136.041149 -229.652618) (xy 136.08377 -229.628011) (xy 136.129786 -229.610559)
			(xy 136.178005 -229.600715) (xy 136.22718 -229.598734) (xy 136.276035 -229.604666) (xy 136.323306 -229.618358)
			(xy 136.367768 -229.639456) (xy 136.408271 -229.667412) (xy 136.443764 -229.701504) (xy 136.473329 -229.740848)
			(xy 136.4962 -229.784425) (xy 136.511784 -229.831106) (xy 136.519679 -229.879683) (xy 136.520174 -229.90429)
			(xy 137.788916 -229.90429) (xy 137.792876 -229.855236) (xy 137.804653 -229.807452) (xy 137.823944 -229.762176)
			(xy 137.850247 -229.72058) (xy 137.882882 -229.683743) (xy 137.921003 -229.652618) (xy 137.963624 -229.628011)
			(xy 138.00964 -229.610559) (xy 138.057859 -229.600715) (xy 138.107034 -229.598734) (xy 138.155889 -229.604666)
			(xy 138.20316 -229.618358) (xy 138.247622 -229.639456) (xy 138.288125 -229.667412) (xy 138.323618 -229.701504)
			(xy 138.353183 -229.740848) (xy 138.376054 -229.784425) (xy 138.391638 -229.831106) (xy 138.399533 -229.879683)
			(xy 138.400028 -229.90429) (xy 138.72897 -229.90429) (xy 138.73293 -229.855236) (xy 138.744707 -229.807452)
			(xy 138.763998 -229.762176) (xy 138.790301 -229.72058) (xy 138.822936 -229.683743) (xy 138.861057 -229.652618)
			(xy 138.903678 -229.628011) (xy 138.949694 -229.610559) (xy 138.997913 -229.600715) (xy 139.047088 -229.598734)
			(xy 139.095943 -229.604666) (xy 139.143214 -229.618358) (xy 139.187676 -229.639456) (xy 139.228179 -229.667412)
			(xy 139.263672 -229.701504) (xy 139.293237 -229.740848) (xy 139.316108 -229.784425) (xy 139.331692 -229.831106)
			(xy 139.339587 -229.879683) (xy 139.340082 -229.90429) (xy 139.339587 -229.928897) (xy 139.331692 -229.977474)
			(xy 139.316108 -230.024155) (xy 139.293237 -230.067732) (xy 139.263672 -230.107076) (xy 139.228179 -230.141168)
			(xy 139.187676 -230.169124) (xy 139.143214 -230.190222) (xy 139.095943 -230.203914) (xy 139.047088 -230.209846)
			(xy 138.997913 -230.207865) (xy 138.949694 -230.198021) (xy 138.903678 -230.180569) (xy 138.861057 -230.155962)
			(xy 138.822936 -230.124837) (xy 138.790301 -230.088) (xy 138.763998 -230.046404) (xy 138.744707 -230.001128)
			(xy 138.73293 -229.953344) (xy 138.72897 -229.90429) (xy 138.400028 -229.90429) (xy 138.399533 -229.928897)
			(xy 138.391638 -229.977474) (xy 138.376054 -230.024155) (xy 138.353183 -230.067732) (xy 138.323618 -230.107076)
			(xy 138.288125 -230.141168) (xy 138.247622 -230.169124) (xy 138.20316 -230.190222) (xy 138.155889 -230.203914)
			(xy 138.107034 -230.209846) (xy 138.057859 -230.207865) (xy 138.00964 -230.198021) (xy 137.963624 -230.180569)
			(xy 137.921003 -230.155962) (xy 137.882882 -230.124837) (xy 137.850247 -230.088) (xy 137.823944 -230.046404)
			(xy 137.804653 -230.001128) (xy 137.792876 -229.953344) (xy 137.788916 -229.90429) (xy 136.520174 -229.90429)
			(xy 136.519679 -229.928897) (xy 136.511784 -229.977474) (xy 136.4962 -230.024155) (xy 136.473329 -230.067732)
			(xy 136.443764 -230.107076) (xy 136.408271 -230.141168) (xy 136.367768 -230.169124) (xy 136.323306 -230.190222)
			(xy 136.276035 -230.203914) (xy 136.22718 -230.209846) (xy 136.178005 -230.207865) (xy 136.129786 -230.198021)
			(xy 136.08377 -230.180569) (xy 136.041149 -230.155962) (xy 136.003028 -230.124837) (xy 135.970393 -230.088)
			(xy 135.94409 -230.046404) (xy 135.924799 -230.001128) (xy 135.913022 -229.953344) (xy 135.909062 -229.90429)
			(xy 135.58012 -229.90429) (xy 135.579625 -229.928897) (xy 135.57173 -229.977474) (xy 135.556146 -230.024155)
			(xy 135.533275 -230.067732) (xy 135.50371 -230.107076) (xy 135.468217 -230.141168) (xy 135.427714 -230.169124)
			(xy 135.383252 -230.190222) (xy 135.335981 -230.203914) (xy 135.287126 -230.209846) (xy 135.237951 -230.207865)
			(xy 135.189732 -230.198021) (xy 135.143716 -230.180569) (xy 135.101095 -230.155962) (xy 135.062974 -230.124837)
			(xy 135.030339 -230.088) (xy 135.004036 -230.046404) (xy 134.984745 -230.001128) (xy 134.972968 -229.953344)
			(xy 134.969008 -229.90429) (xy 134.640066 -229.90429) (xy 134.639571 -229.928897) (xy 134.631676 -229.977474)
			(xy 134.616092 -230.024155) (xy 134.593221 -230.067732) (xy 134.563656 -230.107076) (xy 134.528163 -230.141168)
			(xy 134.48766 -230.169124) (xy 134.443198 -230.190222) (xy 134.395927 -230.203914) (xy 134.347072 -230.209846)
			(xy 134.297897 -230.207865) (xy 134.249678 -230.198021) (xy 134.203662 -230.180569) (xy 134.161041 -230.155962)
			(xy 134.12292 -230.124837) (xy 134.090285 -230.088) (xy 134.063982 -230.046404) (xy 134.044691 -230.001128)
			(xy 134.032914 -229.953344) (xy 134.028954 -229.90429) (xy 133.700012 -229.90429) (xy 133.699517 -229.928897)
			(xy 133.691622 -229.977474) (xy 133.676038 -230.024155) (xy 133.653167 -230.067732) (xy 133.623602 -230.107076)
			(xy 133.588109 -230.141168) (xy 133.547606 -230.169124) (xy 133.503144 -230.190222) (xy 133.455873 -230.203914)
			(xy 133.407018 -230.209846) (xy 133.357843 -230.207865) (xy 133.309624 -230.198021) (xy 133.263608 -230.180569)
			(xy 133.220987 -230.155962) (xy 133.182866 -230.124837) (xy 133.150231 -230.088) (xy 133.123928 -230.046404)
			(xy 133.104637 -230.001128) (xy 133.09286 -229.953344) (xy 133.0889 -229.90429) (xy 132.770372 -229.90429)
			(xy 132.76986 -229.929736) (xy 132.761696 -229.97997) (xy 132.74558 -230.028244) (xy 132.721929 -230.073307)
			(xy 132.691356 -230.113993) (xy 132.654652 -230.149248) (xy 132.612768 -230.178158) (xy 132.566789 -230.199975)
			(xy 132.517905 -230.214135) (xy 132.467384 -230.220269) (xy 132.416532 -230.21822) (xy 132.366668 -230.20804)
			(xy 132.319082 -230.189993) (xy 132.275008 -230.164547) (xy 132.235586 -230.13236) (xy 132.201838 -230.094266)
			(xy 132.174637 -230.051252) (xy 132.154689 -230.004432) (xy 132.14251 -229.955018) (xy 132.138415 -229.90429)
			(xy 131.830572 -229.90429) (xy 131.83006 -229.929736) (xy 131.821896 -229.97997) (xy 131.80578 -230.028244)
			(xy 131.782129 -230.073307) (xy 131.751556 -230.113993) (xy 131.714852 -230.149248) (xy 131.672968 -230.178158)
			(xy 131.626989 -230.199975) (xy 131.578105 -230.214135) (xy 131.527584 -230.220269) (xy 131.476732 -230.21822)
			(xy 131.426868 -230.20804) (xy 131.379282 -230.189993) (xy 131.335208 -230.164547) (xy 131.295786 -230.13236)
			(xy 131.262038 -230.094266) (xy 131.234837 -230.051252) (xy 131.214889 -230.004432) (xy 131.20271 -229.955018)
			(xy 131.198615 -229.90429) (xy 129.950464 -229.90429) (xy 129.949952 -229.929736) (xy 129.941788 -229.97997)
			(xy 129.925672 -230.028244) (xy 129.902021 -230.073307) (xy 129.871448 -230.113993) (xy 129.834744 -230.149248)
			(xy 129.79286 -230.178158) (xy 129.746881 -230.199975) (xy 129.697997 -230.214135) (xy 129.647476 -230.220269)
			(xy 129.596624 -230.21822) (xy 129.54676 -230.20804) (xy 129.499174 -230.189993) (xy 129.4551 -230.164547)
			(xy 129.415678 -230.13236) (xy 129.38193 -230.094266) (xy 129.354729 -230.051252) (xy 129.334781 -230.004432)
			(xy 129.322602 -229.955018) (xy 129.318507 -229.90429) (xy 128.999996 -229.90429) (xy 128.999501 -229.928897)
			(xy 128.991606 -229.977474) (xy 128.976022 -230.024155) (xy 128.953151 -230.067732) (xy 128.923586 -230.107076)
			(xy 128.888093 -230.141168) (xy 128.84759 -230.169124) (xy 128.803128 -230.190222) (xy 128.755857 -230.203914)
			(xy 128.707002 -230.209846) (xy 128.657827 -230.207865) (xy 128.609608 -230.198021) (xy 128.563592 -230.180569)
			(xy 128.520971 -230.155962) (xy 128.48285 -230.124837) (xy 128.450215 -230.088) (xy 128.423912 -230.046404)
			(xy 128.404621 -230.001128) (xy 128.392844 -229.953344) (xy 128.388884 -229.90429) (xy 128.070356 -229.90429)
			(xy 128.069844 -229.929736) (xy 128.06168 -229.97997) (xy 128.045564 -230.028244) (xy 128.021913 -230.073307)
			(xy 127.99134 -230.113993) (xy 127.954636 -230.149248) (xy 127.912752 -230.178158) (xy 127.866773 -230.199975)
			(xy 127.817889 -230.214135) (xy 127.767368 -230.220269) (xy 127.716516 -230.21822) (xy 127.666652 -230.20804)
			(xy 127.619066 -230.189993) (xy 127.574992 -230.164547) (xy 127.53557 -230.13236) (xy 127.501822 -230.094266)
			(xy 127.474621 -230.051252) (xy 127.454673 -230.004432) (xy 127.442494 -229.955018) (xy 127.438399 -229.90429)
			(xy 127.120703 -229.90429) (xy 127.120704 -229.904297) (xy 127.116602 -229.95423) (xy 127.104404 -230.002824)
			(xy 127.084437 -230.048775) (xy 127.057238 -230.09085) (xy 127.023536 -230.127922) (xy 126.984234 -230.158995)
			(xy 126.940387 -230.183236) (xy 126.916942 -230.192072) (xy 126.909322 -230.194612) (xy 126.896876 -230.20401)
			(xy 126.892558 -230.21036) (xy 126.888236 -230.216947) (xy 126.883464 -230.231951) (xy 126.88316 -230.239824)
			(xy 126.88316 -230.439722) (xy 126.883688 -230.449715) (xy 126.891404 -230.468157) (xy 126.905578 -230.482253)
			(xy 126.914656 -230.486458) (xy 126.950216 -230.500682) (xy 126.950724 -230.500682) (xy 127.00381 -230.52151)
			(xy 127.011034 -230.52402) (xy 127.026287 -230.52506) (xy 127.033782 -230.523542) (xy 127.041402 -230.521764)
			(xy 127.053848 -230.514398) (xy 127.05969 -230.508302) (xy 127.077156 -230.489956) (xy 127.117054 -230.458753)
			(xy 127.16156 -230.434574) (xy 127.209451 -230.418083) (xy 127.259409 -230.409733) (xy 127.284734 -230.409242)
			(xy 127.309983 -230.409766) (xy 127.359793 -230.418083) (xy 127.407554 -230.434484) (xy 127.451964 -230.458522)
			(xy 127.491813 -230.489542) (xy 127.526013 -230.526697) (xy 127.553631 -230.568974) (xy 127.573915 -230.61522)
			(xy 127.586311 -230.664174) (xy 127.590481 -230.7145) (xy 127.590477 -230.71455) (xy 127.908553 -230.71455)
			(xy 127.912648 -230.663822) (xy 127.924827 -230.614408) (xy 127.944775 -230.567588) (xy 127.971976 -230.524574)
			(xy 128.005724 -230.48648) (xy 128.045146 -230.454293) (xy 128.08922 -230.428847) (xy 128.136806 -230.4108)
			(xy 128.18667 -230.40062) (xy 128.237522 -230.398571) (xy 128.288043 -230.404705) (xy 128.336927 -230.418865)
			(xy 128.382906 -230.440682) (xy 128.42479 -230.469592) (xy 128.461494 -230.504847) (xy 128.492067 -230.545533)
			(xy 128.515718 -230.590596) (xy 128.531834 -230.63887) (xy 128.539998 -230.689104) (xy 128.54051 -230.71455)
			(xy 128.848607 -230.71455) (xy 128.852702 -230.663822) (xy 128.864881 -230.614408) (xy 128.884829 -230.567588)
			(xy 128.91203 -230.524574) (xy 128.945778 -230.48648) (xy 128.9852 -230.454293) (xy 129.029274 -230.428847)
			(xy 129.07686 -230.4108) (xy 129.126724 -230.40062) (xy 129.177576 -230.398571) (xy 129.228097 -230.404705)
			(xy 129.276981 -230.418865) (xy 129.32296 -230.440682) (xy 129.364844 -230.469592) (xy 129.401548 -230.504847)
			(xy 129.432121 -230.545533) (xy 129.455772 -230.590596) (xy 129.471888 -230.63887) (xy 129.480052 -230.689104)
			(xy 129.480564 -230.71455) (xy 129.798838 -230.71455) (xy 129.802798 -230.665496) (xy 129.814575 -230.617712)
			(xy 129.833866 -230.572436) (xy 129.860169 -230.53084) (xy 129.892804 -230.494003) (xy 129.930925 -230.462878)
			(xy 129.973546 -230.438271) (xy 130.019562 -230.420819) (xy 130.067781 -230.410975) (xy 130.116956 -230.408994)
			(xy 130.165811 -230.414926) (xy 130.213082 -230.428618) (xy 130.257544 -230.449716) (xy 130.298047 -230.477672)
			(xy 130.33354 -230.511764) (xy 130.363105 -230.551108) (xy 130.385976 -230.594685) (xy 130.40156 -230.641366)
			(xy 130.409455 -230.689943) (xy 130.40995 -230.71455) (xy 130.728461 -230.71455) (xy 130.732556 -230.663822)
			(xy 130.744735 -230.614408) (xy 130.764683 -230.567588) (xy 130.791884 -230.524574) (xy 130.825632 -230.48648)
			(xy 130.865054 -230.454293) (xy 130.909128 -230.428847) (xy 130.956714 -230.4108) (xy 131.006578 -230.40062)
			(xy 131.05743 -230.398571) (xy 131.107951 -230.404705) (xy 131.156835 -230.418865) (xy 131.202814 -230.440682)
			(xy 131.244698 -230.469592) (xy 131.281402 -230.504847) (xy 131.311975 -230.545533) (xy 131.335626 -230.590596)
			(xy 131.351742 -230.63887) (xy 131.359906 -230.689104) (xy 131.360418 -230.71455) (xy 131.678946 -230.71455)
			(xy 131.682906 -230.665496) (xy 131.694683 -230.617712) (xy 131.713974 -230.572436) (xy 131.740277 -230.53084)
			(xy 131.772912 -230.494003) (xy 131.811033 -230.462878) (xy 131.853654 -230.438271) (xy 131.89967 -230.420819)
			(xy 131.947889 -230.410975) (xy 131.997064 -230.408994) (xy 132.045919 -230.414926) (xy 132.09319 -230.428618)
			(xy 132.137652 -230.449716) (xy 132.178155 -230.477672) (xy 132.213648 -230.511764) (xy 132.243213 -230.551108)
			(xy 132.266084 -230.594685) (xy 132.281668 -230.641366) (xy 132.289563 -230.689943) (xy 132.290058 -230.71455)
			(xy 132.608569 -230.71455) (xy 132.612664 -230.663822) (xy 132.624843 -230.614408) (xy 132.644791 -230.567588)
			(xy 132.671992 -230.524574) (xy 132.70574 -230.48648) (xy 132.745162 -230.454293) (xy 132.789236 -230.428847)
			(xy 132.836822 -230.4108) (xy 132.886686 -230.40062) (xy 132.937538 -230.398571) (xy 132.988059 -230.404705)
			(xy 133.036943 -230.418865) (xy 133.082922 -230.440682) (xy 133.124806 -230.469592) (xy 133.16151 -230.504847)
			(xy 133.192083 -230.545533) (xy 133.215734 -230.590596) (xy 133.23185 -230.63887) (xy 133.240014 -230.689104)
			(xy 133.240521 -230.714296) (xy 133.559054 -230.714296) (xy 133.563014 -230.665242) (xy 133.574791 -230.617458)
			(xy 133.594082 -230.572182) (xy 133.620385 -230.530586) (xy 133.65302 -230.493749) (xy 133.691141 -230.462624)
			(xy 133.733762 -230.438017) (xy 133.779778 -230.420565) (xy 133.827997 -230.410721) (xy 133.877172 -230.40874)
			(xy 133.926027 -230.414672) (xy 133.973298 -230.428364) (xy 134.01776 -230.449462) (xy 134.058263 -230.477418)
			(xy 134.093756 -230.51151) (xy 134.123321 -230.550854) (xy 134.146192 -230.594431) (xy 134.161776 -230.641112)
			(xy 134.169671 -230.689689) (xy 134.170166 -230.714296) (xy 134.170161 -230.71455) (xy 134.498854 -230.71455)
			(xy 134.502814 -230.665496) (xy 134.514591 -230.617712) (xy 134.533882 -230.572436) (xy 134.560185 -230.53084)
			(xy 134.59282 -230.494003) (xy 134.630941 -230.462878) (xy 134.673562 -230.438271) (xy 134.719578 -230.420819)
			(xy 134.767797 -230.410975) (xy 134.816972 -230.408994) (xy 134.865827 -230.414926) (xy 134.913098 -230.428618)
			(xy 134.95756 -230.449716) (xy 134.998063 -230.477672) (xy 135.033556 -230.511764) (xy 135.063121 -230.551108)
			(xy 135.085992 -230.594685) (xy 135.101576 -230.641366) (xy 135.109471 -230.689943) (xy 135.109966 -230.71455)
			(xy 135.438908 -230.71455) (xy 135.442868 -230.665496) (xy 135.454645 -230.617712) (xy 135.473936 -230.572436)
			(xy 135.500239 -230.53084) (xy 135.532874 -230.494003) (xy 135.570995 -230.462878) (xy 135.613616 -230.438271)
			(xy 135.659632 -230.420819) (xy 135.707851 -230.410975) (xy 135.757026 -230.408994) (xy 135.805881 -230.414926)
			(xy 135.853152 -230.428618) (xy 135.897614 -230.449716) (xy 135.938117 -230.477672) (xy 135.97361 -230.511764)
			(xy 136.003175 -230.551108) (xy 136.026046 -230.594685) (xy 136.04163 -230.641366) (xy 136.049525 -230.689943)
			(xy 136.05002 -230.71455) (xy 136.378962 -230.71455) (xy 136.382922 -230.665496) (xy 136.394699 -230.617712)
			(xy 136.41399 -230.572436) (xy 136.440293 -230.53084) (xy 136.472928 -230.494003) (xy 136.511049 -230.462878)
			(xy 136.55367 -230.438271) (xy 136.599686 -230.420819) (xy 136.647905 -230.410975) (xy 136.69708 -230.408994)
			(xy 136.745935 -230.414926) (xy 136.793206 -230.428618) (xy 136.837668 -230.449716) (xy 136.878171 -230.477672)
			(xy 136.913664 -230.511764) (xy 136.943229 -230.551108) (xy 136.9661 -230.594685) (xy 136.981684 -230.641366)
			(xy 136.989579 -230.689943) (xy 136.990074 -230.71455) (xy 137.319016 -230.71455) (xy 137.322976 -230.665496)
			(xy 137.334753 -230.617712) (xy 137.354044 -230.572436) (xy 137.380347 -230.53084) (xy 137.412982 -230.494003)
			(xy 137.451103 -230.462878) (xy 137.493724 -230.438271) (xy 137.53974 -230.420819) (xy 137.587959 -230.410975)
			(xy 137.637134 -230.408994) (xy 137.685989 -230.414926) (xy 137.73326 -230.428618) (xy 137.777722 -230.449716)
			(xy 137.818225 -230.477672) (xy 137.853718 -230.511764) (xy 137.883283 -230.551108) (xy 137.906154 -230.594685)
			(xy 137.921738 -230.641366) (xy 137.929633 -230.689943) (xy 137.930123 -230.714296) (xy 138.25907 -230.714296)
			(xy 138.26303 -230.665242) (xy 138.274807 -230.617458) (xy 138.294098 -230.572182) (xy 138.320401 -230.530586)
			(xy 138.353036 -230.493749) (xy 138.391157 -230.462624) (xy 138.433778 -230.438017) (xy 138.479794 -230.420565)
			(xy 138.528013 -230.410721) (xy 138.577188 -230.40874) (xy 138.626043 -230.414672) (xy 138.673314 -230.428364)
			(xy 138.717776 -230.449462) (xy 138.758279 -230.477418) (xy 138.793772 -230.51151) (xy 138.823337 -230.550854)
			(xy 138.846208 -230.594431) (xy 138.861792 -230.641112) (xy 138.869687 -230.689689) (xy 138.870182 -230.714296)
			(xy 138.870177 -230.71455) (xy 139.19887 -230.71455) (xy 139.20283 -230.665496) (xy 139.214607 -230.617712)
			(xy 139.233898 -230.572436) (xy 139.260201 -230.53084) (xy 139.292836 -230.494003) (xy 139.330957 -230.462878)
			(xy 139.373578 -230.438271) (xy 139.419594 -230.420819) (xy 139.467813 -230.410975) (xy 139.516988 -230.408994)
			(xy 139.565843 -230.414926) (xy 139.613114 -230.428618) (xy 139.657576 -230.449716) (xy 139.698079 -230.477672)
			(xy 139.733572 -230.511764) (xy 139.763137 -230.551108) (xy 139.786008 -230.594685) (xy 139.801592 -230.641366)
			(xy 139.809487 -230.689943) (xy 139.809982 -230.71455) (xy 139.809487 -230.739157) (xy 139.801592 -230.787734)
			(xy 139.786008 -230.834415) (xy 139.763137 -230.877992) (xy 139.733572 -230.917336) (xy 139.698079 -230.951428)
			(xy 139.657576 -230.979384) (xy 139.613114 -231.000482) (xy 139.565843 -231.014174) (xy 139.516988 -231.020106)
			(xy 139.467813 -231.018125) (xy 139.419594 -231.008281) (xy 139.373578 -230.990829) (xy 139.330957 -230.966222)
			(xy 139.292836 -230.935097) (xy 139.260201 -230.89826) (xy 139.233898 -230.856664) (xy 139.214607 -230.811388)
			(xy 139.20283 -230.763604) (xy 139.19887 -230.71455) (xy 138.870177 -230.71455) (xy 138.869687 -230.738903)
			(xy 138.861792 -230.78748) (xy 138.846208 -230.834161) (xy 138.823337 -230.877738) (xy 138.793772 -230.917082)
			(xy 138.758279 -230.951174) (xy 138.717776 -230.97913) (xy 138.673314 -231.000228) (xy 138.626043 -231.01392)
			(xy 138.577188 -231.019852) (xy 138.528013 -231.017871) (xy 138.479794 -231.008027) (xy 138.433778 -230.990575)
			(xy 138.391157 -230.965968) (xy 138.353036 -230.934843) (xy 138.320401 -230.898006) (xy 138.294098 -230.85641)
			(xy 138.274807 -230.811134) (xy 138.26303 -230.76335) (xy 138.25907 -230.714296) (xy 137.930123 -230.714296)
			(xy 137.930128 -230.71455) (xy 137.929633 -230.739157) (xy 137.921738 -230.787734) (xy 137.906154 -230.834415)
			(xy 137.883283 -230.877992) (xy 137.853718 -230.917336) (xy 137.818225 -230.951428) (xy 137.777722 -230.979384)
			(xy 137.73326 -231.000482) (xy 137.685989 -231.014174) (xy 137.637134 -231.020106) (xy 137.587959 -231.018125)
			(xy 137.53974 -231.008281) (xy 137.493724 -230.990829) (xy 137.451103 -230.966222) (xy 137.412982 -230.935097)
			(xy 137.380347 -230.89826) (xy 137.354044 -230.856664) (xy 137.334753 -230.811388) (xy 137.322976 -230.763604)
			(xy 137.319016 -230.71455) (xy 136.990074 -230.71455) (xy 136.989579 -230.739157) (xy 136.981684 -230.787734)
			(xy 136.9661 -230.834415) (xy 136.943229 -230.877992) (xy 136.913664 -230.917336) (xy 136.878171 -230.951428)
			(xy 136.837668 -230.979384) (xy 136.793206 -231.000482) (xy 136.745935 -231.014174) (xy 136.69708 -231.020106)
			(xy 136.647905 -231.018125) (xy 136.599686 -231.008281) (xy 136.55367 -230.990829) (xy 136.511049 -230.966222)
			(xy 136.472928 -230.935097) (xy 136.440293 -230.89826) (xy 136.41399 -230.856664) (xy 136.394699 -230.811388)
			(xy 136.382922 -230.763604) (xy 136.378962 -230.71455) (xy 136.05002 -230.71455) (xy 136.049525 -230.739157)
			(xy 136.04163 -230.787734) (xy 136.026046 -230.834415) (xy 136.003175 -230.877992) (xy 135.97361 -230.917336)
			(xy 135.938117 -230.951428) (xy 135.897614 -230.979384) (xy 135.853152 -231.000482) (xy 135.805881 -231.014174)
			(xy 135.757026 -231.020106) (xy 135.707851 -231.018125) (xy 135.659632 -231.008281) (xy 135.613616 -230.990829)
			(xy 135.570995 -230.966222) (xy 135.532874 -230.935097) (xy 135.500239 -230.89826) (xy 135.473936 -230.856664)
			(xy 135.454645 -230.811388) (xy 135.442868 -230.763604) (xy 135.438908 -230.71455) (xy 135.109966 -230.71455)
			(xy 135.109471 -230.739157) (xy 135.101576 -230.787734) (xy 135.085992 -230.834415) (xy 135.063121 -230.877992)
			(xy 135.033556 -230.917336) (xy 134.998063 -230.951428) (xy 134.95756 -230.979384) (xy 134.913098 -231.000482)
			(xy 134.865827 -231.014174) (xy 134.816972 -231.020106) (xy 134.767797 -231.018125) (xy 134.719578 -231.008281)
			(xy 134.673562 -230.990829) (xy 134.630941 -230.966222) (xy 134.59282 -230.935097) (xy 134.560185 -230.89826)
			(xy 134.533882 -230.856664) (xy 134.514591 -230.811388) (xy 134.502814 -230.763604) (xy 134.498854 -230.71455)
			(xy 134.170161 -230.71455) (xy 134.169671 -230.738903) (xy 134.161776 -230.78748) (xy 134.146192 -230.834161)
			(xy 134.123321 -230.877738) (xy 134.093756 -230.917082) (xy 134.058263 -230.951174) (xy 134.01776 -230.97913)
			(xy 133.973298 -231.000228) (xy 133.926027 -231.01392) (xy 133.877172 -231.019852) (xy 133.827997 -231.017871)
			(xy 133.779778 -231.008027) (xy 133.733762 -230.990575) (xy 133.691141 -230.965968) (xy 133.65302 -230.934843)
			(xy 133.620385 -230.898006) (xy 133.594082 -230.85641) (xy 133.574791 -230.811134) (xy 133.563014 -230.76335)
			(xy 133.559054 -230.714296) (xy 133.240521 -230.714296) (xy 133.240526 -230.71455) (xy 133.240014 -230.739996)
			(xy 133.23185 -230.79023) (xy 133.215734 -230.838504) (xy 133.192083 -230.883567) (xy 133.16151 -230.924253)
			(xy 133.124806 -230.959508) (xy 133.082922 -230.988418) (xy 133.036943 -231.010235) (xy 132.988059 -231.024395)
			(xy 132.937538 -231.030529) (xy 132.886686 -231.02848) (xy 132.836822 -231.0183) (xy 132.789236 -231.000253)
			(xy 132.745162 -230.974807) (xy 132.70574 -230.94262) (xy 132.671992 -230.904526) (xy 132.644791 -230.861512)
			(xy 132.624843 -230.814692) (xy 132.612664 -230.765278) (xy 132.608569 -230.71455) (xy 132.290058 -230.71455)
			(xy 132.289563 -230.739157) (xy 132.281668 -230.787734) (xy 132.266084 -230.834415) (xy 132.243213 -230.877992)
			(xy 132.213648 -230.917336) (xy 132.178155 -230.951428) (xy 132.137652 -230.979384) (xy 132.09319 -231.000482)
			(xy 132.045919 -231.014174) (xy 131.997064 -231.020106) (xy 131.947889 -231.018125) (xy 131.89967 -231.008281)
			(xy 131.853654 -230.990829) (xy 131.811033 -230.966222) (xy 131.772912 -230.935097) (xy 131.740277 -230.89826)
			(xy 131.713974 -230.856664) (xy 131.694683 -230.811388) (xy 131.682906 -230.763604) (xy 131.678946 -230.71455)
			(xy 131.360418 -230.71455) (xy 131.359906 -230.739996) (xy 131.351742 -230.79023) (xy 131.335626 -230.838504)
			(xy 131.311975 -230.883567) (xy 131.281402 -230.924253) (xy 131.244698 -230.959508) (xy 131.202814 -230.988418)
			(xy 131.156835 -231.010235) (xy 131.107951 -231.024395) (xy 131.05743 -231.030529) (xy 131.006578 -231.02848)
			(xy 130.956714 -231.0183) (xy 130.909128 -231.000253) (xy 130.865054 -230.974807) (xy 130.825632 -230.94262)
			(xy 130.791884 -230.904526) (xy 130.764683 -230.861512) (xy 130.744735 -230.814692) (xy 130.732556 -230.765278)
			(xy 130.728461 -230.71455) (xy 130.40995 -230.71455) (xy 130.409455 -230.739157) (xy 130.40156 -230.787734)
			(xy 130.385976 -230.834415) (xy 130.363105 -230.877992) (xy 130.33354 -230.917336) (xy 130.298047 -230.951428)
			(xy 130.257544 -230.979384) (xy 130.213082 -231.000482) (xy 130.165811 -231.014174) (xy 130.116956 -231.020106)
			(xy 130.067781 -231.018125) (xy 130.019562 -231.008281) (xy 129.973546 -230.990829) (xy 129.930925 -230.966222)
			(xy 129.892804 -230.935097) (xy 129.860169 -230.89826) (xy 129.833866 -230.856664) (xy 129.814575 -230.811388)
			(xy 129.802798 -230.763604) (xy 129.798838 -230.71455) (xy 129.480564 -230.71455) (xy 129.480052 -230.739996)
			(xy 129.471888 -230.79023) (xy 129.455772 -230.838504) (xy 129.432121 -230.883567) (xy 129.401548 -230.924253)
			(xy 129.364844 -230.959508) (xy 129.32296 -230.988418) (xy 129.276981 -231.010235) (xy 129.228097 -231.024395)
			(xy 129.177576 -231.030529) (xy 129.126724 -231.02848) (xy 129.07686 -231.0183) (xy 129.029274 -231.000253)
			(xy 128.9852 -230.974807) (xy 128.945778 -230.94262) (xy 128.91203 -230.904526) (xy 128.884829 -230.861512)
			(xy 128.864881 -230.814692) (xy 128.852702 -230.765278) (xy 128.848607 -230.71455) (xy 128.54051 -230.71455)
			(xy 128.539998 -230.739996) (xy 128.531834 -230.79023) (xy 128.515718 -230.838504) (xy 128.492067 -230.883567)
			(xy 128.461494 -230.924253) (xy 128.42479 -230.959508) (xy 128.382906 -230.988418) (xy 128.336927 -231.010235)
			(xy 128.288043 -231.024395) (xy 128.237522 -231.030529) (xy 128.18667 -231.02848) (xy 128.136806 -231.0183)
			(xy 128.08922 -231.000253) (xy 128.045146 -230.974807) (xy 128.005724 -230.94262) (xy 127.971976 -230.904526)
			(xy 127.944775 -230.861512) (xy 127.924827 -230.814692) (xy 127.912648 -230.765278) (xy 127.908553 -230.71455)
			(xy 127.590477 -230.71455) (xy 127.586311 -230.764826) (xy 127.573915 -230.81378) (xy 127.553631 -230.860026)
			(xy 127.526013 -230.902303) (xy 127.491813 -230.939458) (xy 127.451964 -230.970478) (xy 127.407554 -230.994516)
			(xy 127.359793 -231.010917) (xy 127.309983 -231.019234) (xy 127.284734 -231.019858) (xy 127.259448 -231.019357)
			(xy 127.20957 -231.011009) (xy 127.161751 -230.994552) (xy 127.117299 -230.970437) (xy 127.07743 -230.939324)
			(xy 127.059944 -230.921052) (xy 127.059436 -230.920544) (xy 127.059182 -230.92029) (xy 127.053889 -230.915024)
			(xy 127.040984 -230.907526) (xy 127.033782 -230.905558) (xy 127.026162 -230.90378) (xy 127.011176 -230.904796)
			(xy 126.950724 -230.928418) (xy 126.950216 -230.928418) (xy 126.914656 -230.942642) (xy 126.905608 -230.946892)
			(xy 126.891449 -230.960974) (xy 126.883742 -230.979396) (xy 126.88316 -230.989378) (xy 126.88316 -231.188768)
			(xy 126.883461 -231.196639) (xy 126.888258 -231.211632) (xy 126.892558 -231.218232) (xy 126.896876 -231.224582)
			(xy 126.909322 -231.23398) (xy 126.916942 -231.23652) (xy 126.94038 -231.245374) (xy 126.984226 -231.269613)
			(xy 127.023526 -231.300685) (xy 127.057228 -231.337755) (xy 127.084426 -231.379828) (xy 127.104392 -231.425777)
			(xy 127.11659 -231.474369) (xy 127.120693 -231.524301) (xy 127.120693 -231.524302) (xy 127.438399 -231.524302)
			(xy 127.442494 -231.473574) (xy 127.454673 -231.42416) (xy 127.474621 -231.37734) (xy 127.501822 -231.334326)
			(xy 127.53557 -231.296232) (xy 127.574992 -231.264045) (xy 127.619066 -231.238599) (xy 127.666652 -231.220552)
			(xy 127.716516 -231.210372) (xy 127.767368 -231.208323) (xy 127.817889 -231.214457) (xy 127.866773 -231.228617)
			(xy 127.912752 -231.250434) (xy 127.954636 -231.279344) (xy 127.99134 -231.314599) (xy 128.021913 -231.355285)
			(xy 128.045564 -231.400348) (xy 128.06168 -231.448622) (xy 128.069844 -231.498856) (xy 128.070356 -231.524302)
			(xy 128.388884 -231.524302) (xy 128.392844 -231.475248) (xy 128.404621 -231.427464) (xy 128.423912 -231.382188)
			(xy 128.450215 -231.340592) (xy 128.48285 -231.303755) (xy 128.520971 -231.27263) (xy 128.563592 -231.248023)
			(xy 128.609608 -231.230571) (xy 128.657827 -231.220727) (xy 128.707002 -231.218746) (xy 128.755857 -231.224678)
			(xy 128.803128 -231.23837) (xy 128.84759 -231.259468) (xy 128.888093 -231.287424) (xy 128.923586 -231.321516)
			(xy 128.953151 -231.36086) (xy 128.976022 -231.404437) (xy 128.991606 -231.451118) (xy 128.999501 -231.499695)
			(xy 128.999996 -231.524302) (xy 129.318507 -231.524302) (xy 129.322602 -231.473574) (xy 129.334781 -231.42416)
			(xy 129.354729 -231.37734) (xy 129.38193 -231.334326) (xy 129.415678 -231.296232) (xy 129.4551 -231.264045)
			(xy 129.499174 -231.238599) (xy 129.54676 -231.220552) (xy 129.596624 -231.210372) (xy 129.647476 -231.208323)
			(xy 129.697997 -231.214457) (xy 129.746881 -231.228617) (xy 129.79286 -231.250434) (xy 129.834744 -231.279344)
			(xy 129.871448 -231.314599) (xy 129.902021 -231.355285) (xy 129.925672 -231.400348) (xy 129.941788 -231.448622)
			(xy 129.949952 -231.498856) (xy 129.950464 -231.524302) (xy 130.268992 -231.524302) (xy 130.272952 -231.475248)
			(xy 130.284729 -231.427464) (xy 130.30402 -231.382188) (xy 130.330323 -231.340592) (xy 130.362958 -231.303755)
			(xy 130.401079 -231.27263) (xy 130.4437 -231.248023) (xy 130.489716 -231.230571) (xy 130.537935 -231.220727)
			(xy 130.58711 -231.218746) (xy 130.635965 -231.224678) (xy 130.683236 -231.23837) (xy 130.727698 -231.259468)
			(xy 130.768201 -231.287424) (xy 130.803694 -231.321516) (xy 130.833259 -231.36086) (xy 130.85613 -231.404437)
			(xy 130.871714 -231.451118) (xy 130.879609 -231.499695) (xy 130.880104 -231.524302) (xy 131.198615 -231.524302)
			(xy 131.20271 -231.473574) (xy 131.214889 -231.42416) (xy 131.234837 -231.37734) (xy 131.262038 -231.334326)
			(xy 131.295786 -231.296232) (xy 131.335208 -231.264045) (xy 131.379282 -231.238599) (xy 131.426868 -231.220552)
			(xy 131.476732 -231.210372) (xy 131.527584 -231.208323) (xy 131.578105 -231.214457) (xy 131.626989 -231.228617)
			(xy 131.672968 -231.250434) (xy 131.714852 -231.279344) (xy 131.751556 -231.314599) (xy 131.782129 -231.355285)
			(xy 131.80578 -231.400348) (xy 131.821896 -231.448622) (xy 131.83006 -231.498856) (xy 131.830572 -231.524302)
			(xy 132.138415 -231.524302) (xy 132.14251 -231.473574) (xy 132.154689 -231.42416) (xy 132.174637 -231.37734)
			(xy 132.201838 -231.334326) (xy 132.235586 -231.296232) (xy 132.275008 -231.264045) (xy 132.319082 -231.238599)
			(xy 132.366668 -231.220552) (xy 132.416532 -231.210372) (xy 132.467384 -231.208323) (xy 132.517905 -231.214457)
			(xy 132.566789 -231.228617) (xy 132.612768 -231.250434) (xy 132.654652 -231.279344) (xy 132.691356 -231.314599)
			(xy 132.721929 -231.355285) (xy 132.74558 -231.400348) (xy 132.761696 -231.448622) (xy 132.76986 -231.498856)
			(xy 132.770372 -231.524302) (xy 133.0889 -231.524302) (xy 133.09286 -231.475248) (xy 133.104637 -231.427464)
			(xy 133.123928 -231.382188) (xy 133.150231 -231.340592) (xy 133.182866 -231.303755) (xy 133.220987 -231.27263)
			(xy 133.263608 -231.248023) (xy 133.309624 -231.230571) (xy 133.357843 -231.220727) (xy 133.407018 -231.218746)
			(xy 133.455873 -231.224678) (xy 133.503144 -231.23837) (xy 133.547606 -231.259468) (xy 133.588109 -231.287424)
			(xy 133.623602 -231.321516) (xy 133.653167 -231.36086) (xy 133.676038 -231.404437) (xy 133.691622 -231.451118)
			(xy 133.699517 -231.499695) (xy 133.700012 -231.524302) (xy 134.028954 -231.524302) (xy 134.032914 -231.475248)
			(xy 134.044691 -231.427464) (xy 134.063982 -231.382188) (xy 134.090285 -231.340592) (xy 134.12292 -231.303755)
			(xy 134.161041 -231.27263) (xy 134.203662 -231.248023) (xy 134.249678 -231.230571) (xy 134.297897 -231.220727)
			(xy 134.347072 -231.218746) (xy 134.395927 -231.224678) (xy 134.443198 -231.23837) (xy 134.48766 -231.259468)
			(xy 134.528163 -231.287424) (xy 134.563656 -231.321516) (xy 134.593221 -231.36086) (xy 134.616092 -231.404437)
			(xy 134.631676 -231.451118) (xy 134.639571 -231.499695) (xy 134.640066 -231.524302) (xy 134.969008 -231.524302)
			(xy 134.972968 -231.475248) (xy 134.984745 -231.427464) (xy 135.004036 -231.382188) (xy 135.030339 -231.340592)
			(xy 135.062974 -231.303755) (xy 135.101095 -231.27263) (xy 135.143716 -231.248023) (xy 135.189732 -231.230571)
			(xy 135.237951 -231.220727) (xy 135.287126 -231.218746) (xy 135.335981 -231.224678) (xy 135.383252 -231.23837)
			(xy 135.427714 -231.259468) (xy 135.468217 -231.287424) (xy 135.50371 -231.321516) (xy 135.533275 -231.36086)
			(xy 135.556146 -231.404437) (xy 135.57173 -231.451118) (xy 135.579625 -231.499695) (xy 135.58012 -231.524302)
			(xy 135.909062 -231.524302) (xy 135.913022 -231.475248) (xy 135.924799 -231.427464) (xy 135.94409 -231.382188)
			(xy 135.970393 -231.340592) (xy 136.003028 -231.303755) (xy 136.041149 -231.27263) (xy 136.08377 -231.248023)
			(xy 136.129786 -231.230571) (xy 136.178005 -231.220727) (xy 136.22718 -231.218746) (xy 136.276035 -231.224678)
			(xy 136.323306 -231.23837) (xy 136.367768 -231.259468) (xy 136.408271 -231.287424) (xy 136.443764 -231.321516)
			(xy 136.473329 -231.36086) (xy 136.4962 -231.404437) (xy 136.511784 -231.451118) (xy 136.519679 -231.499695)
			(xy 136.520174 -231.524302) (xy 136.848862 -231.524302) (xy 136.852822 -231.475248) (xy 136.864599 -231.427464)
			(xy 136.88389 -231.382188) (xy 136.910193 -231.340592) (xy 136.942828 -231.303755) (xy 136.980949 -231.27263)
			(xy 137.02357 -231.248023) (xy 137.069586 -231.230571) (xy 137.117805 -231.220727) (xy 137.16698 -231.218746)
			(xy 137.215835 -231.224678) (xy 137.263106 -231.23837) (xy 137.307568 -231.259468) (xy 137.348071 -231.287424)
			(xy 137.383564 -231.321516) (xy 137.413129 -231.36086) (xy 137.436 -231.404437) (xy 137.451584 -231.451118)
			(xy 137.459479 -231.499695) (xy 137.459974 -231.524302) (xy 137.788916 -231.524302) (xy 137.792876 -231.475248)
			(xy 137.804653 -231.427464) (xy 137.823944 -231.382188) (xy 137.850247 -231.340592) (xy 137.882882 -231.303755)
			(xy 137.921003 -231.27263) (xy 137.963624 -231.248023) (xy 138.00964 -231.230571) (xy 138.057859 -231.220727)
			(xy 138.107034 -231.218746) (xy 138.155889 -231.224678) (xy 138.20316 -231.23837) (xy 138.247622 -231.259468)
			(xy 138.288125 -231.287424) (xy 138.323618 -231.321516) (xy 138.353183 -231.36086) (xy 138.376054 -231.404437)
			(xy 138.391638 -231.451118) (xy 138.399533 -231.499695) (xy 138.400028 -231.524302) (xy 138.72897 -231.524302)
			(xy 138.73293 -231.475248) (xy 138.744707 -231.427464) (xy 138.763998 -231.382188) (xy 138.790301 -231.340592)
			(xy 138.822936 -231.303755) (xy 138.861057 -231.27263) (xy 138.903678 -231.248023) (xy 138.949694 -231.230571)
			(xy 138.997913 -231.220727) (xy 139.047088 -231.218746) (xy 139.095943 -231.224678) (xy 139.143214 -231.23837)
			(xy 139.187676 -231.259468) (xy 139.228179 -231.287424) (xy 139.263672 -231.321516) (xy 139.293237 -231.36086)
			(xy 139.316108 -231.404437) (xy 139.331692 -231.451118) (xy 139.339587 -231.499695) (xy 139.340082 -231.524302)
			(xy 139.339587 -231.548909) (xy 139.331692 -231.597486) (xy 139.316108 -231.644167) (xy 139.293237 -231.687744)
			(xy 139.263672 -231.727088) (xy 139.228179 -231.76118) (xy 139.187676 -231.789136) (xy 139.143214 -231.810234)
			(xy 139.095943 -231.823926) (xy 139.047088 -231.829858) (xy 138.997913 -231.827877) (xy 138.949694 -231.818033)
			(xy 138.903678 -231.800581) (xy 138.861057 -231.775974) (xy 138.822936 -231.744849) (xy 138.790301 -231.708012)
			(xy 138.763998 -231.666416) (xy 138.744707 -231.62114) (xy 138.73293 -231.573356) (xy 138.72897 -231.524302)
			(xy 138.400028 -231.524302) (xy 138.399533 -231.548909) (xy 138.391638 -231.597486) (xy 138.376054 -231.644167)
			(xy 138.353183 -231.687744) (xy 138.323618 -231.727088) (xy 138.288125 -231.76118) (xy 138.247622 -231.789136)
			(xy 138.20316 -231.810234) (xy 138.155889 -231.823926) (xy 138.107034 -231.829858) (xy 138.057859 -231.827877)
			(xy 138.00964 -231.818033) (xy 137.963624 -231.800581) (xy 137.921003 -231.775974) (xy 137.882882 -231.744849)
			(xy 137.850247 -231.708012) (xy 137.823944 -231.666416) (xy 137.804653 -231.62114) (xy 137.792876 -231.573356)
			(xy 137.788916 -231.524302) (xy 137.459974 -231.524302) (xy 137.459479 -231.548909) (xy 137.451584 -231.597486)
			(xy 137.436 -231.644167) (xy 137.413129 -231.687744) (xy 137.383564 -231.727088) (xy 137.348071 -231.76118)
			(xy 137.307568 -231.789136) (xy 137.263106 -231.810234) (xy 137.215835 -231.823926) (xy 137.16698 -231.829858)
			(xy 137.117805 -231.827877) (xy 137.069586 -231.818033) (xy 137.02357 -231.800581) (xy 136.980949 -231.775974)
			(xy 136.942828 -231.744849) (xy 136.910193 -231.708012) (xy 136.88389 -231.666416) (xy 136.864599 -231.62114)
			(xy 136.852822 -231.573356) (xy 136.848862 -231.524302) (xy 136.520174 -231.524302) (xy 136.519679 -231.548909)
			(xy 136.511784 -231.597486) (xy 136.4962 -231.644167) (xy 136.473329 -231.687744) (xy 136.443764 -231.727088)
			(xy 136.408271 -231.76118) (xy 136.367768 -231.789136) (xy 136.323306 -231.810234) (xy 136.276035 -231.823926)
			(xy 136.22718 -231.829858) (xy 136.178005 -231.827877) (xy 136.129786 -231.818033) (xy 136.08377 -231.800581)
			(xy 136.041149 -231.775974) (xy 136.003028 -231.744849) (xy 135.970393 -231.708012) (xy 135.94409 -231.666416)
			(xy 135.924799 -231.62114) (xy 135.913022 -231.573356) (xy 135.909062 -231.524302) (xy 135.58012 -231.524302)
			(xy 135.579625 -231.548909) (xy 135.57173 -231.597486) (xy 135.556146 -231.644167) (xy 135.533275 -231.687744)
			(xy 135.50371 -231.727088) (xy 135.468217 -231.76118) (xy 135.427714 -231.789136) (xy 135.383252 -231.810234)
			(xy 135.335981 -231.823926) (xy 135.287126 -231.829858) (xy 135.237951 -231.827877) (xy 135.189732 -231.818033)
			(xy 135.143716 -231.800581) (xy 135.101095 -231.775974) (xy 135.062974 -231.744849) (xy 135.030339 -231.708012)
			(xy 135.004036 -231.666416) (xy 134.984745 -231.62114) (xy 134.972968 -231.573356) (xy 134.969008 -231.524302)
			(xy 134.640066 -231.524302) (xy 134.639571 -231.548909) (xy 134.631676 -231.597486) (xy 134.616092 -231.644167)
			(xy 134.593221 -231.687744) (xy 134.563656 -231.727088) (xy 134.528163 -231.76118) (xy 134.48766 -231.789136)
			(xy 134.443198 -231.810234) (xy 134.395927 -231.823926) (xy 134.347072 -231.829858) (xy 134.297897 -231.827877)
			(xy 134.249678 -231.818033) (xy 134.203662 -231.800581) (xy 134.161041 -231.775974) (xy 134.12292 -231.744849)
			(xy 134.090285 -231.708012) (xy 134.063982 -231.666416) (xy 134.044691 -231.62114) (xy 134.032914 -231.573356)
			(xy 134.028954 -231.524302) (xy 133.700012 -231.524302) (xy 133.699517 -231.548909) (xy 133.691622 -231.597486)
			(xy 133.676038 -231.644167) (xy 133.653167 -231.687744) (xy 133.623602 -231.727088) (xy 133.588109 -231.76118)
			(xy 133.547606 -231.789136) (xy 133.503144 -231.810234) (xy 133.455873 -231.823926) (xy 133.407018 -231.829858)
			(xy 133.357843 -231.827877) (xy 133.309624 -231.818033) (xy 133.263608 -231.800581) (xy 133.220987 -231.775974)
			(xy 133.182866 -231.744849) (xy 133.150231 -231.708012) (xy 133.123928 -231.666416) (xy 133.104637 -231.62114)
			(xy 133.09286 -231.573356) (xy 133.0889 -231.524302) (xy 132.770372 -231.524302) (xy 132.76986 -231.549748)
			(xy 132.761696 -231.599982) (xy 132.74558 -231.648256) (xy 132.721929 -231.693319) (xy 132.691356 -231.734005)
			(xy 132.654652 -231.76926) (xy 132.612768 -231.79817) (xy 132.566789 -231.819987) (xy 132.517905 -231.834147)
			(xy 132.467384 -231.840281) (xy 132.416532 -231.838232) (xy 132.366668 -231.828052) (xy 132.319082 -231.810005)
			(xy 132.275008 -231.784559) (xy 132.235586 -231.752372) (xy 132.201838 -231.714278) (xy 132.174637 -231.671264)
			(xy 132.154689 -231.624444) (xy 132.14251 -231.57503) (xy 132.138415 -231.524302) (xy 131.830572 -231.524302)
			(xy 131.83006 -231.549748) (xy 131.821896 -231.599982) (xy 131.80578 -231.648256) (xy 131.782129 -231.693319)
			(xy 131.751556 -231.734005) (xy 131.714852 -231.76926) (xy 131.672968 -231.79817) (xy 131.626989 -231.819987)
			(xy 131.578105 -231.834147) (xy 131.527584 -231.840281) (xy 131.476732 -231.838232) (xy 131.426868 -231.828052)
			(xy 131.379282 -231.810005) (xy 131.335208 -231.784559) (xy 131.295786 -231.752372) (xy 131.262038 -231.714278)
			(xy 131.234837 -231.671264) (xy 131.214889 -231.624444) (xy 131.20271 -231.57503) (xy 131.198615 -231.524302)
			(xy 130.880104 -231.524302) (xy 130.879609 -231.548909) (xy 130.871714 -231.597486) (xy 130.85613 -231.644167)
			(xy 130.833259 -231.687744) (xy 130.803694 -231.727088) (xy 130.768201 -231.76118) (xy 130.727698 -231.789136)
			(xy 130.683236 -231.810234) (xy 130.635965 -231.823926) (xy 130.58711 -231.829858) (xy 130.537935 -231.827877)
			(xy 130.489716 -231.818033) (xy 130.4437 -231.800581) (xy 130.401079 -231.775974) (xy 130.362958 -231.744849)
			(xy 130.330323 -231.708012) (xy 130.30402 -231.666416) (xy 130.284729 -231.62114) (xy 130.272952 -231.573356)
			(xy 130.268992 -231.524302) (xy 129.950464 -231.524302) (xy 129.949952 -231.549748) (xy 129.941788 -231.599982)
			(xy 129.925672 -231.648256) (xy 129.902021 -231.693319) (xy 129.871448 -231.734005) (xy 129.834744 -231.76926)
			(xy 129.79286 -231.79817) (xy 129.746881 -231.819987) (xy 129.697997 -231.834147) (xy 129.647476 -231.840281)
			(xy 129.596624 -231.838232) (xy 129.54676 -231.828052) (xy 129.499174 -231.810005) (xy 129.4551 -231.784559)
			(xy 129.415678 -231.752372) (xy 129.38193 -231.714278) (xy 129.354729 -231.671264) (xy 129.334781 -231.624444)
			(xy 129.322602 -231.57503) (xy 129.318507 -231.524302) (xy 128.999996 -231.524302) (xy 128.999501 -231.548909)
			(xy 128.991606 -231.597486) (xy 128.976022 -231.644167) (xy 128.953151 -231.687744) (xy 128.923586 -231.727088)
			(xy 128.888093 -231.76118) (xy 128.84759 -231.789136) (xy 128.803128 -231.810234) (xy 128.755857 -231.823926)
			(xy 128.707002 -231.829858) (xy 128.657827 -231.827877) (xy 128.609608 -231.818033) (xy 128.563592 -231.800581)
			(xy 128.520971 -231.775974) (xy 128.48285 -231.744849) (xy 128.450215 -231.708012) (xy 128.423912 -231.666416)
			(xy 128.404621 -231.62114) (xy 128.392844 -231.573356) (xy 128.388884 -231.524302) (xy 128.070356 -231.524302)
			(xy 128.069844 -231.549748) (xy 128.06168 -231.599982) (xy 128.045564 -231.648256) (xy 128.021913 -231.693319)
			(xy 127.99134 -231.734005) (xy 127.954636 -231.76926) (xy 127.912752 -231.79817) (xy 127.866773 -231.819987)
			(xy 127.817889 -231.834147) (xy 127.767368 -231.840281) (xy 127.716516 -231.838232) (xy 127.666652 -231.828052)
			(xy 127.619066 -231.810005) (xy 127.574992 -231.784559) (xy 127.53557 -231.752372) (xy 127.501822 -231.714278)
			(xy 127.474621 -231.671264) (xy 127.454673 -231.624444) (xy 127.442494 -231.57503) (xy 127.438399 -231.524302)
			(xy 127.120693 -231.524302) (xy 127.11659 -231.574232) (xy 127.104392 -231.622824) (xy 127.084426 -231.668773)
			(xy 127.057227 -231.710846) (xy 127.023525 -231.747916) (xy 126.984224 -231.778987) (xy 126.940379 -231.803227)
			(xy 126.916942 -231.812084) (xy 126.909322 -231.814624) (xy 126.896876 -231.824022) (xy 126.892558 -231.830372)
			(xy 126.888224 -231.836955) (xy 126.883426 -231.851959) (xy 126.88316 -231.859836) (xy 126.88316 -232.334308)
			(xy 127.908553 -232.334308) (xy 127.912648 -232.28358) (xy 127.924827 -232.234166) (xy 127.944775 -232.187346)
			(xy 127.971976 -232.144332) (xy 128.005724 -232.106238) (xy 128.045146 -232.074051) (xy 128.08922 -232.048605)
			(xy 128.136806 -232.030558) (xy 128.18667 -232.020378) (xy 128.237522 -232.018329) (xy 128.288043 -232.024463)
			(xy 128.336927 -232.038623) (xy 128.382906 -232.06044) (xy 128.42479 -232.08935) (xy 128.461494 -232.124605)
			(xy 128.492067 -232.165291) (xy 128.515718 -232.210354) (xy 128.531834 -232.258628) (xy 128.539998 -232.308862)
			(xy 128.54051 -232.334308) (xy 128.848607 -232.334308) (xy 128.852702 -232.28358) (xy 128.864881 -232.234166)
			(xy 128.884829 -232.187346) (xy 128.91203 -232.144332) (xy 128.945778 -232.106238) (xy 128.9852 -232.074051)
			(xy 129.029274 -232.048605) (xy 129.07686 -232.030558) (xy 129.126724 -232.020378) (xy 129.177576 -232.018329)
			(xy 129.228097 -232.024463) (xy 129.276981 -232.038623) (xy 129.32296 -232.06044) (xy 129.364844 -232.08935)
			(xy 129.401548 -232.124605) (xy 129.432121 -232.165291) (xy 129.455772 -232.210354) (xy 129.471888 -232.258628)
			(xy 129.480052 -232.308862) (xy 129.480564 -232.334308) (xy 130.728461 -232.334308) (xy 130.732556 -232.28358)
			(xy 130.744735 -232.234166) (xy 130.764683 -232.187346) (xy 130.791884 -232.144332) (xy 130.825632 -232.106238)
			(xy 130.865054 -232.074051) (xy 130.909128 -232.048605) (xy 130.956714 -232.030558) (xy 131.006578 -232.020378)
			(xy 131.05743 -232.018329) (xy 131.107951 -232.024463) (xy 131.156835 -232.038623) (xy 131.202814 -232.06044)
			(xy 131.244698 -232.08935) (xy 131.281402 -232.124605) (xy 131.311975 -232.165291) (xy 131.335626 -232.210354)
			(xy 131.351742 -232.258628) (xy 131.359906 -232.308862) (xy 131.360418 -232.334308) (xy 131.678946 -232.334308)
			(xy 131.682906 -232.285254) (xy 131.694683 -232.23747) (xy 131.713974 -232.192194) (xy 131.740277 -232.150598)
			(xy 131.772912 -232.113761) (xy 131.811033 -232.082636) (xy 131.853654 -232.058029) (xy 131.89967 -232.040577)
			(xy 131.947889 -232.030733) (xy 131.997064 -232.028752) (xy 132.045919 -232.034684) (xy 132.09319 -232.048376)
			(xy 132.137652 -232.069474) (xy 132.178155 -232.09743) (xy 132.213648 -232.131522) (xy 132.243213 -232.170866)
			(xy 132.266084 -232.214443) (xy 132.281668 -232.261124) (xy 132.289563 -232.309701) (xy 132.290058 -232.334308)
			(xy 132.608569 -232.334308) (xy 132.612664 -232.28358) (xy 132.624843 -232.234166) (xy 132.644791 -232.187346)
			(xy 132.671992 -232.144332) (xy 132.70574 -232.106238) (xy 132.745162 -232.074051) (xy 132.789236 -232.048605)
			(xy 132.836822 -232.030558) (xy 132.886686 -232.020378) (xy 132.937538 -232.018329) (xy 132.988059 -232.024463)
			(xy 133.036943 -232.038623) (xy 133.082922 -232.06044) (xy 133.124806 -232.08935) (xy 133.16151 -232.124605)
			(xy 133.192083 -232.165291) (xy 133.215734 -232.210354) (xy 133.23185 -232.258628) (xy 133.240014 -232.308862)
			(xy 133.240526 -232.334308) (xy 133.559054 -232.334308) (xy 133.563014 -232.285254) (xy 133.574791 -232.23747)
			(xy 133.594082 -232.192194) (xy 133.620385 -232.150598) (xy 133.65302 -232.113761) (xy 133.691141 -232.082636)
			(xy 133.733762 -232.058029) (xy 133.779778 -232.040577) (xy 133.827997 -232.030733) (xy 133.877172 -232.028752)
			(xy 133.926027 -232.034684) (xy 133.973298 -232.048376) (xy 134.01776 -232.069474) (xy 134.058263 -232.09743)
			(xy 134.093756 -232.131522) (xy 134.123321 -232.170866) (xy 134.146192 -232.214443) (xy 134.161776 -232.261124)
			(xy 134.169671 -232.309701) (xy 134.170166 -232.334308) (xy 134.498854 -232.334308) (xy 134.502814 -232.285254)
			(xy 134.514591 -232.23747) (xy 134.533882 -232.192194) (xy 134.560185 -232.150598) (xy 134.59282 -232.113761)
			(xy 134.630941 -232.082636) (xy 134.673562 -232.058029) (xy 134.719578 -232.040577) (xy 134.767797 -232.030733)
			(xy 134.816972 -232.028752) (xy 134.865827 -232.034684) (xy 134.913098 -232.048376) (xy 134.95756 -232.069474)
			(xy 134.998063 -232.09743) (xy 135.033556 -232.131522) (xy 135.063121 -232.170866) (xy 135.085992 -232.214443)
			(xy 135.101576 -232.261124) (xy 135.109471 -232.309701) (xy 135.109966 -232.334308) (xy 135.438908 -232.334308)
			(xy 135.442868 -232.285254) (xy 135.454645 -232.23747) (xy 135.473936 -232.192194) (xy 135.500239 -232.150598)
			(xy 135.532874 -232.113761) (xy 135.570995 -232.082636) (xy 135.613616 -232.058029) (xy 135.659632 -232.040577)
			(xy 135.707851 -232.030733) (xy 135.757026 -232.028752) (xy 135.805881 -232.034684) (xy 135.853152 -232.048376)
			(xy 135.897614 -232.069474) (xy 135.938117 -232.09743) (xy 135.97361 -232.131522) (xy 136.003175 -232.170866)
			(xy 136.026046 -232.214443) (xy 136.04163 -232.261124) (xy 136.049525 -232.309701) (xy 136.05002 -232.334308)
			(xy 137.319016 -232.334308) (xy 137.322976 -232.285254) (xy 137.334753 -232.23747) (xy 137.354044 -232.192194)
			(xy 137.380347 -232.150598) (xy 137.412982 -232.113761) (xy 137.451103 -232.082636) (xy 137.493724 -232.058029)
			(xy 137.53974 -232.040577) (xy 137.587959 -232.030733) (xy 137.637134 -232.028752) (xy 137.685989 -232.034684)
			(xy 137.73326 -232.048376) (xy 137.777722 -232.069474) (xy 137.818225 -232.09743) (xy 137.853718 -232.131522)
			(xy 137.883283 -232.170866) (xy 137.906154 -232.214443) (xy 137.921738 -232.261124) (xy 137.929633 -232.309701)
			(xy 137.930128 -232.334308) (xy 138.25907 -232.334308) (xy 138.26303 -232.285254) (xy 138.274807 -232.23747)
			(xy 138.294098 -232.192194) (xy 138.320401 -232.150598) (xy 138.353036 -232.113761) (xy 138.391157 -232.082636)
			(xy 138.433778 -232.058029) (xy 138.479794 -232.040577) (xy 138.528013 -232.030733) (xy 138.577188 -232.028752)
			(xy 138.626043 -232.034684) (xy 138.673314 -232.048376) (xy 138.717776 -232.069474) (xy 138.758279 -232.09743)
			(xy 138.793772 -232.131522) (xy 138.823337 -232.170866) (xy 138.846208 -232.214443) (xy 138.861792 -232.261124)
			(xy 138.869687 -232.309701) (xy 138.870182 -232.334308) (xy 139.19887 -232.334308) (xy 139.20283 -232.285254)
			(xy 139.214607 -232.23747) (xy 139.233898 -232.192194) (xy 139.260201 -232.150598) (xy 139.292836 -232.113761)
			(xy 139.330957 -232.082636) (xy 139.373578 -232.058029) (xy 139.419594 -232.040577) (xy 139.467813 -232.030733)
			(xy 139.516988 -232.028752) (xy 139.565843 -232.034684) (xy 139.613114 -232.048376) (xy 139.657576 -232.069474)
			(xy 139.698079 -232.09743) (xy 139.733572 -232.131522) (xy 139.763137 -232.170866) (xy 139.786008 -232.214443)
			(xy 139.801592 -232.261124) (xy 139.809487 -232.309701) (xy 139.809982 -232.334308) (xy 139.809487 -232.358915)
			(xy 139.801592 -232.407492) (xy 139.786008 -232.454173) (xy 139.763137 -232.49775) (xy 139.733572 -232.537094)
			(xy 139.698079 -232.571186) (xy 139.657576 -232.599142) (xy 139.613114 -232.62024) (xy 139.565843 -232.633932)
			(xy 139.516988 -232.639864) (xy 139.467813 -232.637883) (xy 139.419594 -232.628039) (xy 139.373578 -232.610587)
			(xy 139.330957 -232.58598) (xy 139.292836 -232.554855) (xy 139.260201 -232.518018) (xy 139.233898 -232.476422)
			(xy 139.214607 -232.431146) (xy 139.20283 -232.383362) (xy 139.19887 -232.334308) (xy 138.870182 -232.334308)
			(xy 138.869687 -232.358915) (xy 138.861792 -232.407492) (xy 138.846208 -232.454173) (xy 138.823337 -232.49775)
			(xy 138.793772 -232.537094) (xy 138.758279 -232.571186) (xy 138.717776 -232.599142) (xy 138.673314 -232.62024)
			(xy 138.626043 -232.633932) (xy 138.577188 -232.639864) (xy 138.528013 -232.637883) (xy 138.479794 -232.628039)
			(xy 138.433778 -232.610587) (xy 138.391157 -232.58598) (xy 138.353036 -232.554855) (xy 138.320401 -232.518018)
			(xy 138.294098 -232.476422) (xy 138.274807 -232.431146) (xy 138.26303 -232.383362) (xy 138.25907 -232.334308)
			(xy 137.930128 -232.334308) (xy 137.929633 -232.358915) (xy 137.921738 -232.407492) (xy 137.906154 -232.454173)
			(xy 137.883283 -232.49775) (xy 137.853718 -232.537094) (xy 137.818225 -232.571186) (xy 137.777722 -232.599142)
			(xy 137.73326 -232.62024) (xy 137.685989 -232.633932) (xy 137.637134 -232.639864) (xy 137.587959 -232.637883)
			(xy 137.53974 -232.628039) (xy 137.493724 -232.610587) (xy 137.451103 -232.58598) (xy 137.412982 -232.554855)
			(xy 137.380347 -232.518018) (xy 137.354044 -232.476422) (xy 137.334753 -232.431146) (xy 137.322976 -232.383362)
			(xy 137.319016 -232.334308) (xy 136.05002 -232.334308) (xy 136.049525 -232.358915) (xy 136.04163 -232.407492)
			(xy 136.026046 -232.454173) (xy 136.003175 -232.49775) (xy 135.97361 -232.537094) (xy 135.938117 -232.571186)
			(xy 135.897614 -232.599142) (xy 135.853152 -232.62024) (xy 135.805881 -232.633932) (xy 135.757026 -232.639864)
			(xy 135.707851 -232.637883) (xy 135.659632 -232.628039) (xy 135.613616 -232.610587) (xy 135.570995 -232.58598)
			(xy 135.532874 -232.554855) (xy 135.500239 -232.518018) (xy 135.473936 -232.476422) (xy 135.454645 -232.431146)
			(xy 135.442868 -232.383362) (xy 135.438908 -232.334308) (xy 135.109966 -232.334308) (xy 135.109471 -232.358915)
			(xy 135.101576 -232.407492) (xy 135.085992 -232.454173) (xy 135.063121 -232.49775) (xy 135.033556 -232.537094)
			(xy 134.998063 -232.571186) (xy 134.95756 -232.599142) (xy 134.913098 -232.62024) (xy 134.865827 -232.633932)
			(xy 134.816972 -232.639864) (xy 134.767797 -232.637883) (xy 134.719578 -232.628039) (xy 134.673562 -232.610587)
			(xy 134.630941 -232.58598) (xy 134.59282 -232.554855) (xy 134.560185 -232.518018) (xy 134.533882 -232.476422)
			(xy 134.514591 -232.431146) (xy 134.502814 -232.383362) (xy 134.498854 -232.334308) (xy 134.170166 -232.334308)
			(xy 134.169671 -232.358915) (xy 134.161776 -232.407492) (xy 134.146192 -232.454173) (xy 134.123321 -232.49775)
			(xy 134.093756 -232.537094) (xy 134.058263 -232.571186) (xy 134.01776 -232.599142) (xy 133.973298 -232.62024)
			(xy 133.926027 -232.633932) (xy 133.877172 -232.639864) (xy 133.827997 -232.637883) (xy 133.779778 -232.628039)
			(xy 133.733762 -232.610587) (xy 133.691141 -232.58598) (xy 133.65302 -232.554855) (xy 133.620385 -232.518018)
			(xy 133.594082 -232.476422) (xy 133.574791 -232.431146) (xy 133.563014 -232.383362) (xy 133.559054 -232.334308)
			(xy 133.240526 -232.334308) (xy 133.240014 -232.359754) (xy 133.23185 -232.409988) (xy 133.215734 -232.458262)
			(xy 133.192083 -232.503325) (xy 133.16151 -232.544011) (xy 133.124806 -232.579266) (xy 133.082922 -232.608176)
			(xy 133.036943 -232.629993) (xy 132.988059 -232.644153) (xy 132.937538 -232.650287) (xy 132.886686 -232.648238)
			(xy 132.836822 -232.638058) (xy 132.789236 -232.620011) (xy 132.745162 -232.594565) (xy 132.70574 -232.562378)
			(xy 132.671992 -232.524284) (xy 132.644791 -232.48127) (xy 132.624843 -232.43445) (xy 132.612664 -232.385036)
			(xy 132.608569 -232.334308) (xy 132.290058 -232.334308) (xy 132.289563 -232.358915) (xy 132.281668 -232.407492)
			(xy 132.266084 -232.454173) (xy 132.243213 -232.49775) (xy 132.213648 -232.537094) (xy 132.178155 -232.571186)
			(xy 132.137652 -232.599142) (xy 132.09319 -232.62024) (xy 132.045919 -232.633932) (xy 131.997064 -232.639864)
			(xy 131.947889 -232.637883) (xy 131.89967 -232.628039) (xy 131.853654 -232.610587) (xy 131.811033 -232.58598)
			(xy 131.772912 -232.554855) (xy 131.740277 -232.518018) (xy 131.713974 -232.476422) (xy 131.694683 -232.431146)
			(xy 131.682906 -232.383362) (xy 131.678946 -232.334308) (xy 131.360418 -232.334308) (xy 131.359906 -232.359754)
			(xy 131.351742 -232.409988) (xy 131.335626 -232.458262) (xy 131.311975 -232.503325) (xy 131.281402 -232.544011)
			(xy 131.244698 -232.579266) (xy 131.202814 -232.608176) (xy 131.156835 -232.629993) (xy 131.107951 -232.644153)
			(xy 131.05743 -232.650287) (xy 131.006578 -232.648238) (xy 130.956714 -232.638058) (xy 130.909128 -232.620011)
			(xy 130.865054 -232.594565) (xy 130.825632 -232.562378) (xy 130.791884 -232.524284) (xy 130.764683 -232.48127)
			(xy 130.744735 -232.43445) (xy 130.732556 -232.385036) (xy 130.728461 -232.334308) (xy 129.480564 -232.334308)
			(xy 129.480052 -232.359754) (xy 129.471888 -232.409988) (xy 129.455772 -232.458262) (xy 129.432121 -232.503325)
			(xy 129.401548 -232.544011) (xy 129.364844 -232.579266) (xy 129.32296 -232.608176) (xy 129.276981 -232.629993)
			(xy 129.228097 -232.644153) (xy 129.177576 -232.650287) (xy 129.126724 -232.648238) (xy 129.07686 -232.638058)
			(xy 129.029274 -232.620011) (xy 128.9852 -232.594565) (xy 128.945778 -232.562378) (xy 128.91203 -232.524284)
			(xy 128.884829 -232.48127) (xy 128.864881 -232.43445) (xy 128.852702 -232.385036) (xy 128.848607 -232.334308)
			(xy 128.54051 -232.334308) (xy 128.539998 -232.359754) (xy 128.531834 -232.409988) (xy 128.515718 -232.458262)
			(xy 128.492067 -232.503325) (xy 128.461494 -232.544011) (xy 128.42479 -232.579266) (xy 128.382906 -232.608176)
			(xy 128.336927 -232.629993) (xy 128.288043 -232.644153) (xy 128.237522 -232.650287) (xy 128.18667 -232.648238)
			(xy 128.136806 -232.638058) (xy 128.08922 -232.620011) (xy 128.045146 -232.594565) (xy 128.005724 -232.562378)
			(xy 127.971976 -232.524284) (xy 127.944775 -232.48127) (xy 127.924827 -232.43445) (xy 127.912648 -232.385036)
			(xy 127.908553 -232.334308) (xy 126.88316 -232.334308) (xy 126.88316 -232.80878) (xy 126.883448 -232.816655)
			(xy 126.888224 -232.831663) (xy 126.892558 -232.838244) (xy 126.896876 -232.844594) (xy 126.909322 -232.853992)
			(xy 126.916942 -232.856532) (xy 126.940379 -232.865386) (xy 126.984223 -232.889625) (xy 127.023521 -232.920696)
			(xy 127.057221 -232.957765) (xy 127.084418 -232.999837) (xy 127.104383 -233.045785) (xy 127.11658 -233.094375)
			(xy 127.120681 -233.144305) (xy 127.12068 -233.144314) (xy 127.438399 -233.144314) (xy 127.442494 -233.093586)
			(xy 127.454673 -233.044172) (xy 127.474621 -232.997352) (xy 127.501822 -232.954338) (xy 127.53557 -232.916244)
			(xy 127.574992 -232.884057) (xy 127.619066 -232.858611) (xy 127.666652 -232.840564) (xy 127.716516 -232.830384)
			(xy 127.767368 -232.828335) (xy 127.817889 -232.834469) (xy 127.866773 -232.848629) (xy 127.912752 -232.870446)
			(xy 127.954636 -232.899356) (xy 127.99134 -232.934611) (xy 128.021913 -232.975297) (xy 128.045564 -233.02036)
			(xy 128.06168 -233.068634) (xy 128.069844 -233.118868) (xy 128.070356 -233.144314) (xy 128.388884 -233.144314)
			(xy 128.392844 -233.09526) (xy 128.404621 -233.047476) (xy 128.423912 -233.0022) (xy 128.450215 -232.960604)
			(xy 128.48285 -232.923767) (xy 128.520971 -232.892642) (xy 128.563592 -232.868035) (xy 128.609608 -232.850583)
			(xy 128.657827 -232.840739) (xy 128.707002 -232.838758) (xy 128.755857 -232.84469) (xy 128.803128 -232.858382)
			(xy 128.84759 -232.87948) (xy 128.888093 -232.907436) (xy 128.923586 -232.941528) (xy 128.953151 -232.980872)
			(xy 128.976022 -233.024449) (xy 128.991606 -233.07113) (xy 128.999501 -233.119707) (xy 128.999996 -233.144314)
			(xy 129.318507 -233.144314) (xy 129.322602 -233.093586) (xy 129.334781 -233.044172) (xy 129.354729 -232.997352)
			(xy 129.38193 -232.954338) (xy 129.415678 -232.916244) (xy 129.4551 -232.884057) (xy 129.499174 -232.858611)
			(xy 129.54676 -232.840564) (xy 129.596624 -232.830384) (xy 129.647476 -232.828335) (xy 129.697997 -232.834469)
			(xy 129.746881 -232.848629) (xy 129.79286 -232.870446) (xy 129.834744 -232.899356) (xy 129.871448 -232.934611)
			(xy 129.902021 -232.975297) (xy 129.925672 -233.02036) (xy 129.941788 -233.068634) (xy 129.949952 -233.118868)
			(xy 129.950464 -233.144314) (xy 130.268992 -233.144314) (xy 130.272952 -233.09526) (xy 130.284729 -233.047476)
			(xy 130.30402 -233.0022) (xy 130.330323 -232.960604) (xy 130.362958 -232.923767) (xy 130.401079 -232.892642)
			(xy 130.4437 -232.868035) (xy 130.489716 -232.850583) (xy 130.537935 -232.840739) (xy 130.58711 -232.838758)
			(xy 130.635965 -232.84469) (xy 130.683236 -232.858382) (xy 130.727698 -232.87948) (xy 130.768201 -232.907436)
			(xy 130.803694 -232.941528) (xy 130.833259 -232.980872) (xy 130.85613 -233.024449) (xy 130.871714 -233.07113)
			(xy 130.879609 -233.119707) (xy 130.880104 -233.144314) (xy 131.198615 -233.144314) (xy 131.20271 -233.093586)
			(xy 131.214889 -233.044172) (xy 131.234837 -232.997352) (xy 131.262038 -232.954338) (xy 131.295786 -232.916244)
			(xy 131.335208 -232.884057) (xy 131.379282 -232.858611) (xy 131.426868 -232.840564) (xy 131.476732 -232.830384)
			(xy 131.527584 -232.828335) (xy 131.578105 -232.834469) (xy 131.626989 -232.848629) (xy 131.672968 -232.870446)
			(xy 131.714852 -232.899356) (xy 131.751556 -232.934611) (xy 131.782129 -232.975297) (xy 131.80578 -233.02036)
			(xy 131.821896 -233.068634) (xy 131.83006 -233.118868) (xy 131.830572 -233.144314) (xy 132.138415 -233.144314)
			(xy 132.14251 -233.093586) (xy 132.154689 -233.044172) (xy 132.174637 -232.997352) (xy 132.201838 -232.954338)
			(xy 132.235586 -232.916244) (xy 132.275008 -232.884057) (xy 132.319082 -232.858611) (xy 132.366668 -232.840564)
			(xy 132.416532 -232.830384) (xy 132.467384 -232.828335) (xy 132.517905 -232.834469) (xy 132.566789 -232.848629)
			(xy 132.612768 -232.870446) (xy 132.654652 -232.899356) (xy 132.691356 -232.934611) (xy 132.721929 -232.975297)
			(xy 132.74558 -233.02036) (xy 132.761696 -233.068634) (xy 132.76986 -233.118868) (xy 132.770372 -233.144314)
			(xy 133.0889 -233.144314) (xy 133.09286 -233.09526) (xy 133.104637 -233.047476) (xy 133.123928 -233.0022)
			(xy 133.150231 -232.960604) (xy 133.182866 -232.923767) (xy 133.220987 -232.892642) (xy 133.263608 -232.868035)
			(xy 133.309624 -232.850583) (xy 133.357843 -232.840739) (xy 133.407018 -232.838758) (xy 133.455873 -232.84469)
			(xy 133.503144 -232.858382) (xy 133.547606 -232.87948) (xy 133.588109 -232.907436) (xy 133.623602 -232.941528)
			(xy 133.653167 -232.980872) (xy 133.676038 -233.024449) (xy 133.691622 -233.07113) (xy 133.699517 -233.119707)
			(xy 133.700012 -233.144314) (xy 134.028954 -233.144314) (xy 134.032914 -233.09526) (xy 134.044691 -233.047476)
			(xy 134.063982 -233.0022) (xy 134.090285 -232.960604) (xy 134.12292 -232.923767) (xy 134.161041 -232.892642)
			(xy 134.203662 -232.868035) (xy 134.249678 -232.850583) (xy 134.297897 -232.840739) (xy 134.347072 -232.838758)
			(xy 134.395927 -232.84469) (xy 134.443198 -232.858382) (xy 134.48766 -232.87948) (xy 134.528163 -232.907436)
			(xy 134.563656 -232.941528) (xy 134.593221 -232.980872) (xy 134.616092 -233.024449) (xy 134.631676 -233.07113)
			(xy 134.639571 -233.119707) (xy 134.640066 -233.144314) (xy 134.969008 -233.144314) (xy 134.972968 -233.09526)
			(xy 134.984745 -233.047476) (xy 135.004036 -233.0022) (xy 135.030339 -232.960604) (xy 135.062974 -232.923767)
			(xy 135.101095 -232.892642) (xy 135.143716 -232.868035) (xy 135.189732 -232.850583) (xy 135.237951 -232.840739)
			(xy 135.287126 -232.838758) (xy 135.335981 -232.84469) (xy 135.383252 -232.858382) (xy 135.427714 -232.87948)
			(xy 135.468217 -232.907436) (xy 135.50371 -232.941528) (xy 135.533275 -232.980872) (xy 135.556146 -233.024449)
			(xy 135.57173 -233.07113) (xy 135.579625 -233.119707) (xy 135.58012 -233.144314) (xy 135.909062 -233.144314)
			(xy 135.913022 -233.09526) (xy 135.924799 -233.047476) (xy 135.94409 -233.0022) (xy 135.970393 -232.960604)
			(xy 136.003028 -232.923767) (xy 136.041149 -232.892642) (xy 136.08377 -232.868035) (xy 136.129786 -232.850583)
			(xy 136.178005 -232.840739) (xy 136.22718 -232.838758) (xy 136.276035 -232.84469) (xy 136.323306 -232.858382)
			(xy 136.367768 -232.87948) (xy 136.408271 -232.907436) (xy 136.443764 -232.941528) (xy 136.473329 -232.980872)
			(xy 136.4962 -233.024449) (xy 136.511784 -233.07113) (xy 136.519679 -233.119707) (xy 136.520174 -233.144314)
			(xy 136.848862 -233.144314) (xy 136.852822 -233.09526) (xy 136.864599 -233.047476) (xy 136.88389 -233.0022)
			(xy 136.910193 -232.960604) (xy 136.942828 -232.923767) (xy 136.980949 -232.892642) (xy 137.02357 -232.868035)
			(xy 137.069586 -232.850583) (xy 137.117805 -232.840739) (xy 137.16698 -232.838758) (xy 137.215835 -232.84469)
			(xy 137.263106 -232.858382) (xy 137.307568 -232.87948) (xy 137.348071 -232.907436) (xy 137.383564 -232.941528)
			(xy 137.413129 -232.980872) (xy 137.436 -233.024449) (xy 137.451584 -233.07113) (xy 137.459479 -233.119707)
			(xy 137.459974 -233.144314) (xy 137.788916 -233.144314) (xy 137.792876 -233.09526) (xy 137.804653 -233.047476)
			(xy 137.823944 -233.0022) (xy 137.850247 -232.960604) (xy 137.882882 -232.923767) (xy 137.921003 -232.892642)
			(xy 137.963624 -232.868035) (xy 138.00964 -232.850583) (xy 138.057859 -232.840739) (xy 138.107034 -232.838758)
			(xy 138.155889 -232.84469) (xy 138.20316 -232.858382) (xy 138.247622 -232.87948) (xy 138.288125 -232.907436)
			(xy 138.323618 -232.941528) (xy 138.353183 -232.980872) (xy 138.376054 -233.024449) (xy 138.391638 -233.07113)
			(xy 138.399533 -233.119707) (xy 138.400028 -233.144314) (xy 138.72897 -233.144314) (xy 138.73293 -233.09526)
			(xy 138.744707 -233.047476) (xy 138.763998 -233.0022) (xy 138.790301 -232.960604) (xy 138.822936 -232.923767)
			(xy 138.861057 -232.892642) (xy 138.903678 -232.868035) (xy 138.949694 -232.850583) (xy 138.997913 -232.840739)
			(xy 139.047088 -232.838758) (xy 139.095943 -232.84469) (xy 139.143214 -232.858382) (xy 139.187676 -232.87948)
			(xy 139.228179 -232.907436) (xy 139.263672 -232.941528) (xy 139.293237 -232.980872) (xy 139.316108 -233.024449)
			(xy 139.331692 -233.07113) (xy 139.339587 -233.119707) (xy 139.340082 -233.144314) (xy 139.339587 -233.168921)
			(xy 139.331692 -233.217498) (xy 139.316108 -233.264179) (xy 139.293237 -233.307756) (xy 139.263672 -233.3471)
			(xy 139.228179 -233.381192) (xy 139.187676 -233.409148) (xy 139.143214 -233.430246) (xy 139.095943 -233.443938)
			(xy 139.047088 -233.44987) (xy 138.997913 -233.447889) (xy 138.949694 -233.438045) (xy 138.903678 -233.420593)
			(xy 138.861057 -233.395986) (xy 138.822936 -233.364861) (xy 138.790301 -233.328024) (xy 138.763998 -233.286428)
			(xy 138.744707 -233.241152) (xy 138.73293 -233.193368) (xy 138.72897 -233.144314) (xy 138.400028 -233.144314)
			(xy 138.399533 -233.168921) (xy 138.391638 -233.217498) (xy 138.376054 -233.264179) (xy 138.353183 -233.307756)
			(xy 138.323618 -233.3471) (xy 138.288125 -233.381192) (xy 138.247622 -233.409148) (xy 138.20316 -233.430246)
			(xy 138.155889 -233.443938) (xy 138.107034 -233.44987) (xy 138.057859 -233.447889) (xy 138.00964 -233.438045)
			(xy 137.963624 -233.420593) (xy 137.921003 -233.395986) (xy 137.882882 -233.364861) (xy 137.850247 -233.328024)
			(xy 137.823944 -233.286428) (xy 137.804653 -233.241152) (xy 137.792876 -233.193368) (xy 137.788916 -233.144314)
			(xy 137.459974 -233.144314) (xy 137.459479 -233.168921) (xy 137.451584 -233.217498) (xy 137.436 -233.264179)
			(xy 137.413129 -233.307756) (xy 137.383564 -233.3471) (xy 137.348071 -233.381192) (xy 137.307568 -233.409148)
			(xy 137.263106 -233.430246) (xy 137.215835 -233.443938) (xy 137.16698 -233.44987) (xy 137.117805 -233.447889)
			(xy 137.069586 -233.438045) (xy 137.02357 -233.420593) (xy 136.980949 -233.395986) (xy 136.942828 -233.364861)
			(xy 136.910193 -233.328024) (xy 136.88389 -233.286428) (xy 136.864599 -233.241152) (xy 136.852822 -233.193368)
			(xy 136.848862 -233.144314) (xy 136.520174 -233.144314) (xy 136.519679 -233.168921) (xy 136.511784 -233.217498)
			(xy 136.4962 -233.264179) (xy 136.473329 -233.307756) (xy 136.443764 -233.3471) (xy 136.408271 -233.381192)
			(xy 136.367768 -233.409148) (xy 136.323306 -233.430246) (xy 136.276035 -233.443938) (xy 136.22718 -233.44987)
			(xy 136.178005 -233.447889) (xy 136.129786 -233.438045) (xy 136.08377 -233.420593) (xy 136.041149 -233.395986)
			(xy 136.003028 -233.364861) (xy 135.970393 -233.328024) (xy 135.94409 -233.286428) (xy 135.924799 -233.241152)
			(xy 135.913022 -233.193368) (xy 135.909062 -233.144314) (xy 135.58012 -233.144314) (xy 135.579625 -233.168921)
			(xy 135.57173 -233.217498) (xy 135.556146 -233.264179) (xy 135.533275 -233.307756) (xy 135.50371 -233.3471)
			(xy 135.468217 -233.381192) (xy 135.427714 -233.409148) (xy 135.383252 -233.430246) (xy 135.335981 -233.443938)
			(xy 135.287126 -233.44987) (xy 135.237951 -233.447889) (xy 135.189732 -233.438045) (xy 135.143716 -233.420593)
			(xy 135.101095 -233.395986) (xy 135.062974 -233.364861) (xy 135.030339 -233.328024) (xy 135.004036 -233.286428)
			(xy 134.984745 -233.241152) (xy 134.972968 -233.193368) (xy 134.969008 -233.144314) (xy 134.640066 -233.144314)
			(xy 134.639571 -233.168921) (xy 134.631676 -233.217498) (xy 134.616092 -233.264179) (xy 134.593221 -233.307756)
			(xy 134.563656 -233.3471) (xy 134.528163 -233.381192) (xy 134.48766 -233.409148) (xy 134.443198 -233.430246)
			(xy 134.395927 -233.443938) (xy 134.347072 -233.44987) (xy 134.297897 -233.447889) (xy 134.249678 -233.438045)
			(xy 134.203662 -233.420593) (xy 134.161041 -233.395986) (xy 134.12292 -233.364861) (xy 134.090285 -233.328024)
			(xy 134.063982 -233.286428) (xy 134.044691 -233.241152) (xy 134.032914 -233.193368) (xy 134.028954 -233.144314)
			(xy 133.700012 -233.144314) (xy 133.699517 -233.168921) (xy 133.691622 -233.217498) (xy 133.676038 -233.264179)
			(xy 133.653167 -233.307756) (xy 133.623602 -233.3471) (xy 133.588109 -233.381192) (xy 133.547606 -233.409148)
			(xy 133.503144 -233.430246) (xy 133.455873 -233.443938) (xy 133.407018 -233.44987) (xy 133.357843 -233.447889)
			(xy 133.309624 -233.438045) (xy 133.263608 -233.420593) (xy 133.220987 -233.395986) (xy 133.182866 -233.364861)
			(xy 133.150231 -233.328024) (xy 133.123928 -233.286428) (xy 133.104637 -233.241152) (xy 133.09286 -233.193368)
			(xy 133.0889 -233.144314) (xy 132.770372 -233.144314) (xy 132.76986 -233.16976) (xy 132.761696 -233.219994)
			(xy 132.74558 -233.268268) (xy 132.721929 -233.313331) (xy 132.691356 -233.354017) (xy 132.654652 -233.389272)
			(xy 132.612768 -233.418182) (xy 132.566789 -233.439999) (xy 132.517905 -233.454159) (xy 132.467384 -233.460293)
			(xy 132.416532 -233.458244) (xy 132.366668 -233.448064) (xy 132.319082 -233.430017) (xy 132.275008 -233.404571)
			(xy 132.235586 -233.372384) (xy 132.201838 -233.33429) (xy 132.174637 -233.291276) (xy 132.154689 -233.244456)
			(xy 132.14251 -233.195042) (xy 132.138415 -233.144314) (xy 131.830572 -233.144314) (xy 131.83006 -233.16976)
			(xy 131.821896 -233.219994) (xy 131.80578 -233.268268) (xy 131.782129 -233.313331) (xy 131.751556 -233.354017)
			(xy 131.714852 -233.389272) (xy 131.672968 -233.418182) (xy 131.626989 -233.439999) (xy 131.578105 -233.454159)
			(xy 131.527584 -233.460293) (xy 131.476732 -233.458244) (xy 131.426868 -233.448064) (xy 131.379282 -233.430017)
			(xy 131.335208 -233.404571) (xy 131.295786 -233.372384) (xy 131.262038 -233.33429) (xy 131.234837 -233.291276)
			(xy 131.214889 -233.244456) (xy 131.20271 -233.195042) (xy 131.198615 -233.144314) (xy 130.880104 -233.144314)
			(xy 130.879609 -233.168921) (xy 130.871714 -233.217498) (xy 130.85613 -233.264179) (xy 130.833259 -233.307756)
			(xy 130.803694 -233.3471) (xy 130.768201 -233.381192) (xy 130.727698 -233.409148) (xy 130.683236 -233.430246)
			(xy 130.635965 -233.443938) (xy 130.58711 -233.44987) (xy 130.537935 -233.447889) (xy 130.489716 -233.438045)
			(xy 130.4437 -233.420593) (xy 130.401079 -233.395986) (xy 130.362958 -233.364861) (xy 130.330323 -233.328024)
			(xy 130.30402 -233.286428) (xy 130.284729 -233.241152) (xy 130.272952 -233.193368) (xy 130.268992 -233.144314)
			(xy 129.950464 -233.144314) (xy 129.949952 -233.16976) (xy 129.941788 -233.219994) (xy 129.925672 -233.268268)
			(xy 129.902021 -233.313331) (xy 129.871448 -233.354017) (xy 129.834744 -233.389272) (xy 129.79286 -233.418182)
			(xy 129.746881 -233.439999) (xy 129.697997 -233.454159) (xy 129.647476 -233.460293) (xy 129.596624 -233.458244)
			(xy 129.54676 -233.448064) (xy 129.499174 -233.430017) (xy 129.4551 -233.404571) (xy 129.415678 -233.372384)
			(xy 129.38193 -233.33429) (xy 129.354729 -233.291276) (xy 129.334781 -233.244456) (xy 129.322602 -233.195042)
			(xy 129.318507 -233.144314) (xy 128.999996 -233.144314) (xy 128.999501 -233.168921) (xy 128.991606 -233.217498)
			(xy 128.976022 -233.264179) (xy 128.953151 -233.307756) (xy 128.923586 -233.3471) (xy 128.888093 -233.381192)
			(xy 128.84759 -233.409148) (xy 128.803128 -233.430246) (xy 128.755857 -233.443938) (xy 128.707002 -233.44987)
			(xy 128.657827 -233.447889) (xy 128.609608 -233.438045) (xy 128.563592 -233.420593) (xy 128.520971 -233.395986)
			(xy 128.48285 -233.364861) (xy 128.450215 -233.328024) (xy 128.423912 -233.286428) (xy 128.404621 -233.241152)
			(xy 128.392844 -233.193368) (xy 128.388884 -233.144314) (xy 128.070356 -233.144314) (xy 128.069844 -233.16976)
			(xy 128.06168 -233.219994) (xy 128.045564 -233.268268) (xy 128.021913 -233.313331) (xy 127.99134 -233.354017)
			(xy 127.954636 -233.389272) (xy 127.912752 -233.418182) (xy 127.866773 -233.439999) (xy 127.817889 -233.454159)
			(xy 127.767368 -233.460293) (xy 127.716516 -233.458244) (xy 127.666652 -233.448064) (xy 127.619066 -233.430017)
			(xy 127.574992 -233.404571) (xy 127.53557 -233.372384) (xy 127.501822 -233.33429) (xy 127.474621 -233.291276)
			(xy 127.454673 -233.244456) (xy 127.442494 -233.195042) (xy 127.438399 -233.144314) (xy 127.12068 -233.144314)
			(xy 127.116578 -233.194234) (xy 127.10438 -233.242824) (xy 127.084414 -233.288771) (xy 127.057215 -233.330843)
			(xy 127.023514 -233.367911) (xy 126.984215 -233.39898) (xy 126.940371 -233.423218) (xy 126.916942 -233.432096)
			(xy 126.909322 -233.434636) (xy 126.896876 -233.444034) (xy 126.892558 -233.450384) (xy 126.888226 -233.456968)
			(xy 126.883431 -233.471972) (xy 126.88316 -233.479848) (xy 126.88316 -233.679492) (xy 126.8837 -233.689477)
			(xy 126.891431 -233.707897) (xy 126.905606 -233.721972) (xy 126.914656 -233.726228) (xy 126.950216 -233.740452)
			(xy 126.950724 -233.740452) (xy 127.00381 -233.76128) (xy 127.011034 -233.763792) (xy 127.026287 -233.764832)
			(xy 127.033782 -233.763312) (xy 127.041402 -233.761534) (xy 127.053848 -233.754168) (xy 127.05969 -233.748072)
			(xy 127.077157 -233.729728) (xy 127.117056 -233.698528) (xy 127.161562 -233.674351) (xy 127.209452 -233.657862)
			(xy 127.259409 -233.649513) (xy 127.284734 -233.649012) (xy 127.309986 -233.649536) (xy 127.3598 -233.657854)
			(xy 127.407566 -233.674257) (xy 127.451981 -233.698297) (xy 127.491833 -233.72932) (xy 127.526037 -233.766478)
			(xy 127.553658 -233.80876) (xy 127.573944 -233.85501) (xy 127.586341 -233.903969) (xy 127.590511 -233.9543)
			(xy 127.590509 -233.95432) (xy 127.908553 -233.95432) (xy 127.912648 -233.903592) (xy 127.924827 -233.854178)
			(xy 127.944775 -233.807358) (xy 127.971976 -233.764344) (xy 128.005724 -233.72625) (xy 128.045146 -233.694063)
			(xy 128.08922 -233.668617) (xy 128.136806 -233.65057) (xy 128.18667 -233.64039) (xy 128.237522 -233.638341)
			(xy 128.288043 -233.644475) (xy 128.336927 -233.658635) (xy 128.382906 -233.680452) (xy 128.42479 -233.709362)
			(xy 128.461494 -233.744617) (xy 128.492067 -233.785303) (xy 128.515718 -233.830366) (xy 128.531834 -233.87864)
			(xy 128.539998 -233.928874) (xy 128.54051 -233.95432) (xy 128.848607 -233.95432) (xy 128.852702 -233.903592)
			(xy 128.864881 -233.854178) (xy 128.884829 -233.807358) (xy 128.91203 -233.764344) (xy 128.945778 -233.72625)
			(xy 128.9852 -233.694063) (xy 129.029274 -233.668617) (xy 129.07686 -233.65057) (xy 129.126724 -233.64039)
			(xy 129.177576 -233.638341) (xy 129.228097 -233.644475) (xy 129.276981 -233.658635) (xy 129.32296 -233.680452)
			(xy 129.364844 -233.709362) (xy 129.401548 -233.744617) (xy 129.432121 -233.785303) (xy 129.455772 -233.830366)
			(xy 129.471888 -233.87864) (xy 129.480052 -233.928874) (xy 129.480564 -233.95432) (xy 129.798838 -233.95432)
			(xy 129.802798 -233.905266) (xy 129.814575 -233.857482) (xy 129.833866 -233.812206) (xy 129.860169 -233.77061)
			(xy 129.892804 -233.733773) (xy 129.930925 -233.702648) (xy 129.973546 -233.678041) (xy 130.019562 -233.660589)
			(xy 130.067781 -233.650745) (xy 130.116956 -233.648764) (xy 130.165811 -233.654696) (xy 130.213082 -233.668388)
			(xy 130.257544 -233.689486) (xy 130.298047 -233.717442) (xy 130.33354 -233.751534) (xy 130.363105 -233.790878)
			(xy 130.385976 -233.834455) (xy 130.40156 -233.881136) (xy 130.409455 -233.929713) (xy 130.40995 -233.95432)
			(xy 130.728461 -233.95432) (xy 130.732556 -233.903592) (xy 130.744735 -233.854178) (xy 130.764683 -233.807358)
			(xy 130.791884 -233.764344) (xy 130.825632 -233.72625) (xy 130.865054 -233.694063) (xy 130.909128 -233.668617)
			(xy 130.956714 -233.65057) (xy 131.006578 -233.64039) (xy 131.05743 -233.638341) (xy 131.107951 -233.644475)
			(xy 131.156835 -233.658635) (xy 131.202814 -233.680452) (xy 131.244698 -233.709362) (xy 131.281402 -233.744617)
			(xy 131.311975 -233.785303) (xy 131.335626 -233.830366) (xy 131.351742 -233.87864) (xy 131.359906 -233.928874)
			(xy 131.360418 -233.95432) (xy 131.678946 -233.95432) (xy 131.682906 -233.905266) (xy 131.694683 -233.857482)
			(xy 131.713974 -233.812206) (xy 131.740277 -233.77061) (xy 131.772912 -233.733773) (xy 131.811033 -233.702648)
			(xy 131.853654 -233.678041) (xy 131.89967 -233.660589) (xy 131.947889 -233.650745) (xy 131.997064 -233.648764)
			(xy 132.045919 -233.654696) (xy 132.09319 -233.668388) (xy 132.137652 -233.689486) (xy 132.178155 -233.717442)
			(xy 132.213648 -233.751534) (xy 132.243213 -233.790878) (xy 132.266084 -233.834455) (xy 132.281668 -233.881136)
			(xy 132.289563 -233.929713) (xy 132.290058 -233.95432) (xy 132.608569 -233.95432) (xy 132.612664 -233.903592)
			(xy 132.624843 -233.854178) (xy 132.644791 -233.807358) (xy 132.671992 -233.764344) (xy 132.70574 -233.72625)
			(xy 132.745162 -233.694063) (xy 132.789236 -233.668617) (xy 132.836822 -233.65057) (xy 132.886686 -233.64039)
			(xy 132.937538 -233.638341) (xy 132.988059 -233.644475) (xy 133.036943 -233.658635) (xy 133.082922 -233.680452)
			(xy 133.124806 -233.709362) (xy 133.16151 -233.744617) (xy 133.192083 -233.785303) (xy 133.215734 -233.830366)
			(xy 133.23185 -233.87864) (xy 133.240014 -233.928874) (xy 133.240526 -233.95432) (xy 133.559054 -233.95432)
			(xy 133.563014 -233.905266) (xy 133.574791 -233.857482) (xy 133.594082 -233.812206) (xy 133.620385 -233.77061)
			(xy 133.65302 -233.733773) (xy 133.691141 -233.702648) (xy 133.733762 -233.678041) (xy 133.779778 -233.660589)
			(xy 133.827997 -233.650745) (xy 133.877172 -233.648764) (xy 133.926027 -233.654696) (xy 133.973298 -233.668388)
			(xy 134.01776 -233.689486) (xy 134.058263 -233.717442) (xy 134.093756 -233.751534) (xy 134.123321 -233.790878)
			(xy 134.146192 -233.834455) (xy 134.161776 -233.881136) (xy 134.169671 -233.929713) (xy 134.170166 -233.95432)
			(xy 134.498854 -233.95432) (xy 134.502814 -233.905266) (xy 134.514591 -233.857482) (xy 134.533882 -233.812206)
			(xy 134.560185 -233.77061) (xy 134.59282 -233.733773) (xy 134.630941 -233.702648) (xy 134.673562 -233.678041)
			(xy 134.719578 -233.660589) (xy 134.767797 -233.650745) (xy 134.816972 -233.648764) (xy 134.865827 -233.654696)
			(xy 134.913098 -233.668388) (xy 134.95756 -233.689486) (xy 134.998063 -233.717442) (xy 135.033556 -233.751534)
			(xy 135.063121 -233.790878) (xy 135.085992 -233.834455) (xy 135.101576 -233.881136) (xy 135.109471 -233.929713)
			(xy 135.109966 -233.95432) (xy 135.438908 -233.95432) (xy 135.442868 -233.905266) (xy 135.454645 -233.857482)
			(xy 135.473936 -233.812206) (xy 135.500239 -233.77061) (xy 135.532874 -233.733773) (xy 135.570995 -233.702648)
			(xy 135.613616 -233.678041) (xy 135.659632 -233.660589) (xy 135.707851 -233.650745) (xy 135.757026 -233.648764)
			(xy 135.805881 -233.654696) (xy 135.853152 -233.668388) (xy 135.897614 -233.689486) (xy 135.938117 -233.717442)
			(xy 135.97361 -233.751534) (xy 136.003175 -233.790878) (xy 136.026046 -233.834455) (xy 136.04163 -233.881136)
			(xy 136.049525 -233.929713) (xy 136.05002 -233.95432) (xy 136.378962 -233.95432) (xy 136.382922 -233.905266)
			(xy 136.394699 -233.857482) (xy 136.41399 -233.812206) (xy 136.440293 -233.77061) (xy 136.472928 -233.733773)
			(xy 136.511049 -233.702648) (xy 136.55367 -233.678041) (xy 136.599686 -233.660589) (xy 136.647905 -233.650745)
			(xy 136.69708 -233.648764) (xy 136.745935 -233.654696) (xy 136.793206 -233.668388) (xy 136.837668 -233.689486)
			(xy 136.878171 -233.717442) (xy 136.913664 -233.751534) (xy 136.943229 -233.790878) (xy 136.9661 -233.834455)
			(xy 136.981684 -233.881136) (xy 136.989579 -233.929713) (xy 136.990074 -233.95432) (xy 137.319016 -233.95432)
			(xy 137.322976 -233.905266) (xy 137.334753 -233.857482) (xy 137.354044 -233.812206) (xy 137.380347 -233.77061)
			(xy 137.412982 -233.733773) (xy 137.451103 -233.702648) (xy 137.493724 -233.678041) (xy 137.53974 -233.660589)
			(xy 137.587959 -233.650745) (xy 137.637134 -233.648764) (xy 137.685989 -233.654696) (xy 137.73326 -233.668388)
			(xy 137.777722 -233.689486) (xy 137.818225 -233.717442) (xy 137.853718 -233.751534) (xy 137.883283 -233.790878)
			(xy 137.906154 -233.834455) (xy 137.921738 -233.881136) (xy 137.929633 -233.929713) (xy 137.930128 -233.95432)
			(xy 138.25907 -233.95432) (xy 138.26303 -233.905266) (xy 138.274807 -233.857482) (xy 138.294098 -233.812206)
			(xy 138.320401 -233.77061) (xy 138.353036 -233.733773) (xy 138.391157 -233.702648) (xy 138.433778 -233.678041)
			(xy 138.479794 -233.660589) (xy 138.528013 -233.650745) (xy 138.577188 -233.648764) (xy 138.626043 -233.654696)
			(xy 138.673314 -233.668388) (xy 138.717776 -233.689486) (xy 138.758279 -233.717442) (xy 138.793772 -233.751534)
			(xy 138.823337 -233.790878) (xy 138.846208 -233.834455) (xy 138.861792 -233.881136) (xy 138.869687 -233.929713)
			(xy 138.870182 -233.95432) (xy 139.19887 -233.95432) (xy 139.20283 -233.905266) (xy 139.214607 -233.857482)
			(xy 139.233898 -233.812206) (xy 139.260201 -233.77061) (xy 139.292836 -233.733773) (xy 139.330957 -233.702648)
			(xy 139.373578 -233.678041) (xy 139.419594 -233.660589) (xy 139.467813 -233.650745) (xy 139.516988 -233.648764)
			(xy 139.565843 -233.654696) (xy 139.613114 -233.668388) (xy 139.657576 -233.689486) (xy 139.698079 -233.717442)
			(xy 139.733572 -233.751534) (xy 139.763137 -233.790878) (xy 139.786008 -233.834455) (xy 139.801592 -233.881136)
			(xy 139.809487 -233.929713) (xy 139.809982 -233.95432) (xy 139.809487 -233.978927) (xy 139.801592 -234.027504)
			(xy 139.786008 -234.074185) (xy 139.763137 -234.117762) (xy 139.733572 -234.157106) (xy 139.698079 -234.191198)
			(xy 139.657576 -234.219154) (xy 139.613114 -234.240252) (xy 139.565843 -234.253944) (xy 139.516988 -234.259876)
			(xy 139.467813 -234.257895) (xy 139.419594 -234.248051) (xy 139.373578 -234.230599) (xy 139.330957 -234.205992)
			(xy 139.292836 -234.174867) (xy 139.260201 -234.13803) (xy 139.233898 -234.096434) (xy 139.214607 -234.051158)
			(xy 139.20283 -234.003374) (xy 139.19887 -233.95432) (xy 138.870182 -233.95432) (xy 138.869687 -233.978927)
			(xy 138.861792 -234.027504) (xy 138.846208 -234.074185) (xy 138.823337 -234.117762) (xy 138.793772 -234.157106)
			(xy 138.758279 -234.191198) (xy 138.717776 -234.219154) (xy 138.673314 -234.240252) (xy 138.626043 -234.253944)
			(xy 138.577188 -234.259876) (xy 138.528013 -234.257895) (xy 138.479794 -234.248051) (xy 138.433778 -234.230599)
			(xy 138.391157 -234.205992) (xy 138.353036 -234.174867) (xy 138.320401 -234.13803) (xy 138.294098 -234.096434)
			(xy 138.274807 -234.051158) (xy 138.26303 -234.003374) (xy 138.25907 -233.95432) (xy 137.930128 -233.95432)
			(xy 137.929633 -233.978927) (xy 137.921738 -234.027504) (xy 137.906154 -234.074185) (xy 137.883283 -234.117762)
			(xy 137.853718 -234.157106) (xy 137.818225 -234.191198) (xy 137.777722 -234.219154) (xy 137.73326 -234.240252)
			(xy 137.685989 -234.253944) (xy 137.637134 -234.259876) (xy 137.587959 -234.257895) (xy 137.53974 -234.248051)
			(xy 137.493724 -234.230599) (xy 137.451103 -234.205992) (xy 137.412982 -234.174867) (xy 137.380347 -234.13803)
			(xy 137.354044 -234.096434) (xy 137.334753 -234.051158) (xy 137.322976 -234.003374) (xy 137.319016 -233.95432)
			(xy 136.990074 -233.95432) (xy 136.989579 -233.978927) (xy 136.981684 -234.027504) (xy 136.9661 -234.074185)
			(xy 136.943229 -234.117762) (xy 136.913664 -234.157106) (xy 136.878171 -234.191198) (xy 136.837668 -234.219154)
			(xy 136.793206 -234.240252) (xy 136.745935 -234.253944) (xy 136.69708 -234.259876) (xy 136.647905 -234.257895)
			(xy 136.599686 -234.248051) (xy 136.55367 -234.230599) (xy 136.511049 -234.205992) (xy 136.472928 -234.174867)
			(xy 136.440293 -234.13803) (xy 136.41399 -234.096434) (xy 136.394699 -234.051158) (xy 136.382922 -234.003374)
			(xy 136.378962 -233.95432) (xy 136.05002 -233.95432) (xy 136.049525 -233.978927) (xy 136.04163 -234.027504)
			(xy 136.026046 -234.074185) (xy 136.003175 -234.117762) (xy 135.97361 -234.157106) (xy 135.938117 -234.191198)
			(xy 135.897614 -234.219154) (xy 135.853152 -234.240252) (xy 135.805881 -234.253944) (xy 135.757026 -234.259876)
			(xy 135.707851 -234.257895) (xy 135.659632 -234.248051) (xy 135.613616 -234.230599) (xy 135.570995 -234.205992)
			(xy 135.532874 -234.174867) (xy 135.500239 -234.13803) (xy 135.473936 -234.096434) (xy 135.454645 -234.051158)
			(xy 135.442868 -234.003374) (xy 135.438908 -233.95432) (xy 135.109966 -233.95432) (xy 135.109471 -233.978927)
			(xy 135.101576 -234.027504) (xy 135.085992 -234.074185) (xy 135.063121 -234.117762) (xy 135.033556 -234.157106)
			(xy 134.998063 -234.191198) (xy 134.95756 -234.219154) (xy 134.913098 -234.240252) (xy 134.865827 -234.253944)
			(xy 134.816972 -234.259876) (xy 134.767797 -234.257895) (xy 134.719578 -234.248051) (xy 134.673562 -234.230599)
			(xy 134.630941 -234.205992) (xy 134.59282 -234.174867) (xy 134.560185 -234.13803) (xy 134.533882 -234.096434)
			(xy 134.514591 -234.051158) (xy 134.502814 -234.003374) (xy 134.498854 -233.95432) (xy 134.170166 -233.95432)
			(xy 134.169671 -233.978927) (xy 134.161776 -234.027504) (xy 134.146192 -234.074185) (xy 134.123321 -234.117762)
			(xy 134.093756 -234.157106) (xy 134.058263 -234.191198) (xy 134.01776 -234.219154) (xy 133.973298 -234.240252)
			(xy 133.926027 -234.253944) (xy 133.877172 -234.259876) (xy 133.827997 -234.257895) (xy 133.779778 -234.248051)
			(xy 133.733762 -234.230599) (xy 133.691141 -234.205992) (xy 133.65302 -234.174867) (xy 133.620385 -234.13803)
			(xy 133.594082 -234.096434) (xy 133.574791 -234.051158) (xy 133.563014 -234.003374) (xy 133.559054 -233.95432)
			(xy 133.240526 -233.95432) (xy 133.240014 -233.979766) (xy 133.23185 -234.03) (xy 133.215734 -234.078274)
			(xy 133.192083 -234.123337) (xy 133.16151 -234.164023) (xy 133.124806 -234.199278) (xy 133.082922 -234.228188)
			(xy 133.036943 -234.250005) (xy 132.988059 -234.264165) (xy 132.937538 -234.270299) (xy 132.886686 -234.26825)
			(xy 132.836822 -234.25807) (xy 132.789236 -234.240023) (xy 132.745162 -234.214577) (xy 132.70574 -234.18239)
			(xy 132.671992 -234.144296) (xy 132.644791 -234.101282) (xy 132.624843 -234.054462) (xy 132.612664 -234.005048)
			(xy 132.608569 -233.95432) (xy 132.290058 -233.95432) (xy 132.289563 -233.978927) (xy 132.281668 -234.027504)
			(xy 132.266084 -234.074185) (xy 132.243213 -234.117762) (xy 132.213648 -234.157106) (xy 132.178155 -234.191198)
			(xy 132.137652 -234.219154) (xy 132.09319 -234.240252) (xy 132.045919 -234.253944) (xy 131.997064 -234.259876)
			(xy 131.947889 -234.257895) (xy 131.89967 -234.248051) (xy 131.853654 -234.230599) (xy 131.811033 -234.205992)
			(xy 131.772912 -234.174867) (xy 131.740277 -234.13803) (xy 131.713974 -234.096434) (xy 131.694683 -234.051158)
			(xy 131.682906 -234.003374) (xy 131.678946 -233.95432) (xy 131.360418 -233.95432) (xy 131.359906 -233.979766)
			(xy 131.351742 -234.03) (xy 131.335626 -234.078274) (xy 131.311975 -234.123337) (xy 131.281402 -234.164023)
			(xy 131.244698 -234.199278) (xy 131.202814 -234.228188) (xy 131.156835 -234.250005) (xy 131.107951 -234.264165)
			(xy 131.05743 -234.270299) (xy 131.006578 -234.26825) (xy 130.956714 -234.25807) (xy 130.909128 -234.240023)
			(xy 130.865054 -234.214577) (xy 130.825632 -234.18239) (xy 130.791884 -234.144296) (xy 130.764683 -234.101282)
			(xy 130.744735 -234.054462) (xy 130.732556 -234.005048) (xy 130.728461 -233.95432) (xy 130.40995 -233.95432)
			(xy 130.409455 -233.978927) (xy 130.40156 -234.027504) (xy 130.385976 -234.074185) (xy 130.363105 -234.117762)
			(xy 130.33354 -234.157106) (xy 130.298047 -234.191198) (xy 130.257544 -234.219154) (xy 130.213082 -234.240252)
			(xy 130.165811 -234.253944) (xy 130.116956 -234.259876) (xy 130.067781 -234.257895) (xy 130.019562 -234.248051)
			(xy 129.973546 -234.230599) (xy 129.930925 -234.205992) (xy 129.892804 -234.174867) (xy 129.860169 -234.13803)
			(xy 129.833866 -234.096434) (xy 129.814575 -234.051158) (xy 129.802798 -234.003374) (xy 129.798838 -233.95432)
			(xy 129.480564 -233.95432) (xy 129.480052 -233.979766) (xy 129.471888 -234.03) (xy 129.455772 -234.078274)
			(xy 129.432121 -234.123337) (xy 129.401548 -234.164023) (xy 129.364844 -234.199278) (xy 129.32296 -234.228188)
			(xy 129.276981 -234.250005) (xy 129.228097 -234.264165) (xy 129.177576 -234.270299) (xy 129.126724 -234.26825)
			(xy 129.07686 -234.25807) (xy 129.029274 -234.240023) (xy 128.9852 -234.214577) (xy 128.945778 -234.18239)
			(xy 128.91203 -234.144296) (xy 128.884829 -234.101282) (xy 128.864881 -234.054462) (xy 128.852702 -234.005048)
			(xy 128.848607 -233.95432) (xy 128.54051 -233.95432) (xy 128.539998 -233.979766) (xy 128.531834 -234.03)
			(xy 128.515718 -234.078274) (xy 128.492067 -234.123337) (xy 128.461494 -234.164023) (xy 128.42479 -234.199278)
			(xy 128.382906 -234.228188) (xy 128.336927 -234.250005) (xy 128.288043 -234.264165) (xy 128.237522 -234.270299)
			(xy 128.18667 -234.26825) (xy 128.136806 -234.25807) (xy 128.08922 -234.240023) (xy 128.045146 -234.214577)
			(xy 128.005724 -234.18239) (xy 127.971976 -234.144296) (xy 127.944775 -234.101282) (xy 127.924827 -234.054462)
			(xy 127.912648 -234.005048) (xy 127.908553 -233.95432) (xy 127.590509 -233.95432) (xy 127.586341 -234.004631)
			(xy 127.573944 -234.05359) (xy 127.553658 -234.09984) (xy 127.526037 -234.142122) (xy 127.491833 -234.17928)
			(xy 127.451981 -234.210303) (xy 127.407566 -234.234343) (xy 127.3598 -234.250746) (xy 127.309986 -234.259064)
			(xy 127.284734 -234.259628) (xy 127.259448 -234.259126) (xy 127.209571 -234.250778) (xy 127.161753 -234.23432)
			(xy 127.117302 -234.210204) (xy 127.077436 -234.179089) (xy 127.059944 -234.160822) (xy 127.059436 -234.160314)
			(xy 127.059182 -234.16006) (xy 127.053887 -234.154796) (xy 127.040982 -234.147303) (xy 127.033782 -234.145328)
			(xy 127.026162 -234.14355) (xy 127.011176 -234.144566) (xy 126.950724 -234.168188) (xy 126.950216 -234.168188)
			(xy 126.914656 -234.182412) (xy 126.905605 -234.186661) (xy 126.891438 -234.200741) (xy 126.88372 -234.219164)
			(xy 126.88316 -234.229148) (xy 126.88316 -234.428792) (xy 126.88345 -234.436666) (xy 126.888229 -234.451673)
			(xy 126.892558 -234.458256) (xy 126.896876 -234.464606) (xy 126.909322 -234.474004) (xy 126.916942 -234.476544)
			(xy 126.940378 -234.485398) (xy 126.984219 -234.509637) (xy 127.023516 -234.540707) (xy 127.057214 -234.577775)
			(xy 127.08441 -234.619846) (xy 127.104373 -234.665793) (xy 127.116569 -234.714381) (xy 127.12067 -234.764309)
			(xy 127.120669 -234.764326) (xy 127.438399 -234.764326) (xy 127.442494 -234.713598) (xy 127.454673 -234.664184)
			(xy 127.474621 -234.617364) (xy 127.501822 -234.57435) (xy 127.53557 -234.536256) (xy 127.574992 -234.504069)
			(xy 127.619066 -234.478623) (xy 127.666652 -234.460576) (xy 127.716516 -234.450396) (xy 127.767368 -234.448347)
			(xy 127.817889 -234.454481) (xy 127.866773 -234.468641) (xy 127.912752 -234.490458) (xy 127.954636 -234.519368)
			(xy 127.99134 -234.554623) (xy 128.021913 -234.595309) (xy 128.045564 -234.640372) (xy 128.06168 -234.688646)
			(xy 128.069844 -234.73888) (xy 128.070356 -234.764326) (xy 128.388884 -234.764326) (xy 128.392844 -234.715272)
			(xy 128.404621 -234.667488) (xy 128.423912 -234.622212) (xy 128.450215 -234.580616) (xy 128.48285 -234.543779)
			(xy 128.520971 -234.512654) (xy 128.563592 -234.488047) (xy 128.609608 -234.470595) (xy 128.657827 -234.460751)
			(xy 128.707002 -234.45877) (xy 128.755857 -234.464702) (xy 128.803128 -234.478394) (xy 128.84759 -234.499492)
			(xy 128.888093 -234.527448) (xy 128.923586 -234.56154) (xy 128.953151 -234.600884) (xy 128.976022 -234.644461)
			(xy 128.991606 -234.691142) (xy 128.999501 -234.739719) (xy 128.999996 -234.764326) (xy 129.318507 -234.764326)
			(xy 129.322602 -234.713598) (xy 129.334781 -234.664184) (xy 129.354729 -234.617364) (xy 129.38193 -234.57435)
			(xy 129.415678 -234.536256) (xy 129.4551 -234.504069) (xy 129.499174 -234.478623) (xy 129.54676 -234.460576)
			(xy 129.596624 -234.450396) (xy 129.647476 -234.448347) (xy 129.697997 -234.454481) (xy 129.746881 -234.468641)
			(xy 129.79286 -234.490458) (xy 129.834744 -234.519368) (xy 129.871448 -234.554623) (xy 129.902021 -234.595309)
			(xy 129.925672 -234.640372) (xy 129.941788 -234.688646) (xy 129.949952 -234.73888) (xy 129.950464 -234.764326)
			(xy 131.198615 -234.764326) (xy 131.20271 -234.713598) (xy 131.214889 -234.664184) (xy 131.234837 -234.617364)
			(xy 131.262038 -234.57435) (xy 131.295786 -234.536256) (xy 131.335208 -234.504069) (xy 131.379282 -234.478623)
			(xy 131.426868 -234.460576) (xy 131.476732 -234.450396) (xy 131.527584 -234.448347) (xy 131.578105 -234.454481)
			(xy 131.626989 -234.468641) (xy 131.672968 -234.490458) (xy 131.714852 -234.519368) (xy 131.751556 -234.554623)
			(xy 131.782129 -234.595309) (xy 131.80578 -234.640372) (xy 131.821896 -234.688646) (xy 131.83006 -234.73888)
			(xy 131.830572 -234.764326) (xy 132.138415 -234.764326) (xy 132.14251 -234.713598) (xy 132.154689 -234.664184)
			(xy 132.174637 -234.617364) (xy 132.201838 -234.57435) (xy 132.235586 -234.536256) (xy 132.275008 -234.504069)
			(xy 132.319082 -234.478623) (xy 132.366668 -234.460576) (xy 132.416532 -234.450396) (xy 132.467384 -234.448347)
			(xy 132.517905 -234.454481) (xy 132.566789 -234.468641) (xy 132.612768 -234.490458) (xy 132.654652 -234.519368)
			(xy 132.691356 -234.554623) (xy 132.721929 -234.595309) (xy 132.74558 -234.640372) (xy 132.761696 -234.688646)
			(xy 132.76986 -234.73888) (xy 132.770372 -234.764326) (xy 133.0889 -234.764326) (xy 133.09286 -234.715272)
			(xy 133.104637 -234.667488) (xy 133.123928 -234.622212) (xy 133.150231 -234.580616) (xy 133.182866 -234.543779)
			(xy 133.220987 -234.512654) (xy 133.263608 -234.488047) (xy 133.309624 -234.470595) (xy 133.357843 -234.460751)
			(xy 133.407018 -234.45877) (xy 133.455873 -234.464702) (xy 133.503144 -234.478394) (xy 133.547606 -234.499492)
			(xy 133.588109 -234.527448) (xy 133.623602 -234.56154) (xy 133.653167 -234.600884) (xy 133.676038 -234.644461)
			(xy 133.691622 -234.691142) (xy 133.699517 -234.739719) (xy 133.700012 -234.764326) (xy 134.028954 -234.764326)
			(xy 134.032914 -234.715272) (xy 134.044691 -234.667488) (xy 134.063982 -234.622212) (xy 134.090285 -234.580616)
			(xy 134.12292 -234.543779) (xy 134.161041 -234.512654) (xy 134.203662 -234.488047) (xy 134.249678 -234.470595)
			(xy 134.297897 -234.460751) (xy 134.347072 -234.45877) (xy 134.395927 -234.464702) (xy 134.443198 -234.478394)
			(xy 134.48766 -234.499492) (xy 134.528163 -234.527448) (xy 134.563656 -234.56154) (xy 134.593221 -234.600884)
			(xy 134.616092 -234.644461) (xy 134.631676 -234.691142) (xy 134.639571 -234.739719) (xy 134.640066 -234.764326)
			(xy 134.969008 -234.764326) (xy 134.972968 -234.715272) (xy 134.984745 -234.667488) (xy 135.004036 -234.622212)
			(xy 135.030339 -234.580616) (xy 135.062974 -234.543779) (xy 135.101095 -234.512654) (xy 135.143716 -234.488047)
			(xy 135.189732 -234.470595) (xy 135.237951 -234.460751) (xy 135.287126 -234.45877) (xy 135.335981 -234.464702)
			(xy 135.383252 -234.478394) (xy 135.427714 -234.499492) (xy 135.468217 -234.527448) (xy 135.50371 -234.56154)
			(xy 135.533275 -234.600884) (xy 135.556146 -234.644461) (xy 135.57173 -234.691142) (xy 135.579625 -234.739719)
			(xy 135.58012 -234.764326) (xy 135.909062 -234.764326) (xy 135.913022 -234.715272) (xy 135.924799 -234.667488)
			(xy 135.94409 -234.622212) (xy 135.970393 -234.580616) (xy 136.003028 -234.543779) (xy 136.041149 -234.512654)
			(xy 136.08377 -234.488047) (xy 136.129786 -234.470595) (xy 136.178005 -234.460751) (xy 136.22718 -234.45877)
			(xy 136.276035 -234.464702) (xy 136.323306 -234.478394) (xy 136.367768 -234.499492) (xy 136.408271 -234.527448)
			(xy 136.443764 -234.56154) (xy 136.473329 -234.600884) (xy 136.4962 -234.644461) (xy 136.511784 -234.691142)
			(xy 136.519679 -234.739719) (xy 136.520174 -234.764326) (xy 137.788916 -234.764326) (xy 137.792876 -234.715272)
			(xy 137.804653 -234.667488) (xy 137.823944 -234.622212) (xy 137.850247 -234.580616) (xy 137.882882 -234.543779)
			(xy 137.921003 -234.512654) (xy 137.963624 -234.488047) (xy 138.00964 -234.470595) (xy 138.057859 -234.460751)
			(xy 138.107034 -234.45877) (xy 138.155889 -234.464702) (xy 138.20316 -234.478394) (xy 138.247622 -234.499492)
			(xy 138.288125 -234.527448) (xy 138.323618 -234.56154) (xy 138.353183 -234.600884) (xy 138.376054 -234.644461)
			(xy 138.391638 -234.691142) (xy 138.399533 -234.739719) (xy 138.400028 -234.764326) (xy 138.72897 -234.764326)
			(xy 138.73293 -234.715272) (xy 138.744707 -234.667488) (xy 138.763998 -234.622212) (xy 138.790301 -234.580616)
			(xy 138.822936 -234.543779) (xy 138.861057 -234.512654) (xy 138.903678 -234.488047) (xy 138.949694 -234.470595)
			(xy 138.997913 -234.460751) (xy 139.047088 -234.45877) (xy 139.095943 -234.464702) (xy 139.143214 -234.478394)
			(xy 139.187676 -234.499492) (xy 139.228179 -234.527448) (xy 139.263672 -234.56154) (xy 139.293237 -234.600884)
			(xy 139.316108 -234.644461) (xy 139.331692 -234.691142) (xy 139.339587 -234.739719) (xy 139.340082 -234.764326)
			(xy 139.339587 -234.788933) (xy 139.331692 -234.83751) (xy 139.316108 -234.884191) (xy 139.293237 -234.927768)
			(xy 139.263672 -234.967112) (xy 139.228179 -235.001204) (xy 139.187676 -235.02916) (xy 139.143214 -235.050258)
			(xy 139.095943 -235.06395) (xy 139.047088 -235.069882) (xy 138.997913 -235.067901) (xy 138.949694 -235.058057)
			(xy 138.903678 -235.040605) (xy 138.861057 -235.015998) (xy 138.822936 -234.984873) (xy 138.790301 -234.948036)
			(xy 138.763998 -234.90644) (xy 138.744707 -234.861164) (xy 138.73293 -234.81338) (xy 138.72897 -234.764326)
			(xy 138.400028 -234.764326) (xy 138.399533 -234.788933) (xy 138.391638 -234.83751) (xy 138.376054 -234.884191)
			(xy 138.353183 -234.927768) (xy 138.323618 -234.967112) (xy 138.288125 -235.001204) (xy 138.247622 -235.02916)
			(xy 138.20316 -235.050258) (xy 138.155889 -235.06395) (xy 138.107034 -235.069882) (xy 138.057859 -235.067901)
			(xy 138.00964 -235.058057) (xy 137.963624 -235.040605) (xy 137.921003 -235.015998) (xy 137.882882 -234.984873)
			(xy 137.850247 -234.948036) (xy 137.823944 -234.90644) (xy 137.804653 -234.861164) (xy 137.792876 -234.81338)
			(xy 137.788916 -234.764326) (xy 136.520174 -234.764326) (xy 136.519679 -234.788933) (xy 136.511784 -234.83751)
			(xy 136.4962 -234.884191) (xy 136.473329 -234.927768) (xy 136.443764 -234.967112) (xy 136.408271 -235.001204)
			(xy 136.367768 -235.02916) (xy 136.323306 -235.050258) (xy 136.276035 -235.06395) (xy 136.22718 -235.069882)
			(xy 136.178005 -235.067901) (xy 136.129786 -235.058057) (xy 136.08377 -235.040605) (xy 136.041149 -235.015998)
			(xy 136.003028 -234.984873) (xy 135.970393 -234.948036) (xy 135.94409 -234.90644) (xy 135.924799 -234.861164)
			(xy 135.913022 -234.81338) (xy 135.909062 -234.764326) (xy 135.58012 -234.764326) (xy 135.579625 -234.788933)
			(xy 135.57173 -234.83751) (xy 135.556146 -234.884191) (xy 135.533275 -234.927768) (xy 135.50371 -234.967112)
			(xy 135.468217 -235.001204) (xy 135.427714 -235.02916) (xy 135.383252 -235.050258) (xy 135.335981 -235.06395)
			(xy 135.287126 -235.069882) (xy 135.237951 -235.067901) (xy 135.189732 -235.058057) (xy 135.143716 -235.040605)
			(xy 135.101095 -235.015998) (xy 135.062974 -234.984873) (xy 135.030339 -234.948036) (xy 135.004036 -234.90644)
			(xy 134.984745 -234.861164) (xy 134.972968 -234.81338) (xy 134.969008 -234.764326) (xy 134.640066 -234.764326)
			(xy 134.639571 -234.788933) (xy 134.631676 -234.83751) (xy 134.616092 -234.884191) (xy 134.593221 -234.927768)
			(xy 134.563656 -234.967112) (xy 134.528163 -235.001204) (xy 134.48766 -235.02916) (xy 134.443198 -235.050258)
			(xy 134.395927 -235.06395) (xy 134.347072 -235.069882) (xy 134.297897 -235.067901) (xy 134.249678 -235.058057)
			(xy 134.203662 -235.040605) (xy 134.161041 -235.015998) (xy 134.12292 -234.984873) (xy 134.090285 -234.948036)
			(xy 134.063982 -234.90644) (xy 134.044691 -234.861164) (xy 134.032914 -234.81338) (xy 134.028954 -234.764326)
			(xy 133.700012 -234.764326) (xy 133.699517 -234.788933) (xy 133.691622 -234.83751) (xy 133.676038 -234.884191)
			(xy 133.653167 -234.927768) (xy 133.623602 -234.967112) (xy 133.588109 -235.001204) (xy 133.547606 -235.02916)
			(xy 133.503144 -235.050258) (xy 133.455873 -235.06395) (xy 133.407018 -235.069882) (xy 133.357843 -235.067901)
			(xy 133.309624 -235.058057) (xy 133.263608 -235.040605) (xy 133.220987 -235.015998) (xy 133.182866 -234.984873)
			(xy 133.150231 -234.948036) (xy 133.123928 -234.90644) (xy 133.104637 -234.861164) (xy 133.09286 -234.81338)
			(xy 133.0889 -234.764326) (xy 132.770372 -234.764326) (xy 132.76986 -234.789772) (xy 132.761696 -234.840006)
			(xy 132.74558 -234.88828) (xy 132.721929 -234.933343) (xy 132.691356 -234.974029) (xy 132.654652 -235.009284)
			(xy 132.612768 -235.038194) (xy 132.566789 -235.060011) (xy 132.517905 -235.074171) (xy 132.467384 -235.080305)
			(xy 132.416532 -235.078256) (xy 132.366668 -235.068076) (xy 132.319082 -235.050029) (xy 132.275008 -235.024583)
			(xy 132.235586 -234.992396) (xy 132.201838 -234.954302) (xy 132.174637 -234.911288) (xy 132.154689 -234.864468)
			(xy 132.14251 -234.815054) (xy 132.138415 -234.764326) (xy 131.830572 -234.764326) (xy 131.83006 -234.789772)
			(xy 131.821896 -234.840006) (xy 131.80578 -234.88828) (xy 131.782129 -234.933343) (xy 131.751556 -234.974029)
			(xy 131.714852 -235.009284) (xy 131.672968 -235.038194) (xy 131.626989 -235.060011) (xy 131.578105 -235.074171)
			(xy 131.527584 -235.080305) (xy 131.476732 -235.078256) (xy 131.426868 -235.068076) (xy 131.379282 -235.050029)
			(xy 131.335208 -235.024583) (xy 131.295786 -234.992396) (xy 131.262038 -234.954302) (xy 131.234837 -234.911288)
			(xy 131.214889 -234.864468) (xy 131.20271 -234.815054) (xy 131.198615 -234.764326) (xy 129.950464 -234.764326)
			(xy 129.949952 -234.789772) (xy 129.941788 -234.840006) (xy 129.925672 -234.88828) (xy 129.902021 -234.933343)
			(xy 129.871448 -234.974029) (xy 129.834744 -235.009284) (xy 129.79286 -235.038194) (xy 129.746881 -235.060011)
			(xy 129.697997 -235.074171) (xy 129.647476 -235.080305) (xy 129.596624 -235.078256) (xy 129.54676 -235.068076)
			(xy 129.499174 -235.050029) (xy 129.4551 -235.024583) (xy 129.415678 -234.992396) (xy 129.38193 -234.954302)
			(xy 129.354729 -234.911288) (xy 129.334781 -234.864468) (xy 129.322602 -234.815054) (xy 129.318507 -234.764326)
			(xy 128.999996 -234.764326) (xy 128.999501 -234.788933) (xy 128.991606 -234.83751) (xy 128.976022 -234.884191)
			(xy 128.953151 -234.927768) (xy 128.923586 -234.967112) (xy 128.888093 -235.001204) (xy 128.84759 -235.02916)
			(xy 128.803128 -235.050258) (xy 128.755857 -235.06395) (xy 128.707002 -235.069882) (xy 128.657827 -235.067901)
			(xy 128.609608 -235.058057) (xy 128.563592 -235.040605) (xy 128.520971 -235.015998) (xy 128.48285 -234.984873)
			(xy 128.450215 -234.948036) (xy 128.423912 -234.90644) (xy 128.404621 -234.861164) (xy 128.392844 -234.81338)
			(xy 128.388884 -234.764326) (xy 128.070356 -234.764326) (xy 128.069844 -234.789772) (xy 128.06168 -234.840006)
			(xy 128.045564 -234.88828) (xy 128.021913 -234.933343) (xy 127.99134 -234.974029) (xy 127.954636 -235.009284)
			(xy 127.912752 -235.038194) (xy 127.866773 -235.060011) (xy 127.817889 -235.074171) (xy 127.767368 -235.080305)
			(xy 127.716516 -235.078256) (xy 127.666652 -235.068076) (xy 127.619066 -235.050029) (xy 127.574992 -235.024583)
			(xy 127.53557 -234.992396) (xy 127.501822 -234.954302) (xy 127.474621 -234.911288) (xy 127.454673 -234.864468)
			(xy 127.442494 -234.815054) (xy 127.438399 -234.764326) (xy 127.120669 -234.764326) (xy 127.116566 -234.814236)
			(xy 127.104367 -234.862824) (xy 127.084401 -234.908769) (xy 127.057204 -234.950839) (xy 127.023503 -234.987905)
			(xy 126.984205 -235.018973) (xy 126.940362 -235.043209) (xy 126.916942 -235.052108) (xy 126.909322 -235.054648)
			(xy 126.896876 -235.064046) (xy 126.892558 -235.070396) (xy 126.888228 -235.076981) (xy 126.883437 -235.091984)
			(xy 126.88316 -235.09986) (xy 126.88316 -235.574332) (xy 127.908553 -235.574332) (xy 127.912648 -235.523604)
			(xy 127.924827 -235.47419) (xy 127.944775 -235.42737) (xy 127.971976 -235.384356) (xy 128.005724 -235.346262)
			(xy 128.045146 -235.314075) (xy 128.08922 -235.288629) (xy 128.136806 -235.270582) (xy 128.18667 -235.260402)
			(xy 128.237522 -235.258353) (xy 128.288043 -235.264487) (xy 128.336927 -235.278647) (xy 128.382906 -235.300464)
			(xy 128.42479 -235.329374) (xy 128.461494 -235.364629) (xy 128.492067 -235.405315) (xy 128.515718 -235.450378)
			(xy 128.531834 -235.498652) (xy 128.539998 -235.548886) (xy 128.54051 -235.574332) (xy 128.848607 -235.574332)
			(xy 128.852702 -235.523604) (xy 128.864881 -235.47419) (xy 128.884829 -235.42737) (xy 128.91203 -235.384356)
			(xy 128.945778 -235.346262) (xy 128.9852 -235.314075) (xy 129.029274 -235.288629) (xy 129.07686 -235.270582)
			(xy 129.126724 -235.260402) (xy 129.177576 -235.258353) (xy 129.228097 -235.264487) (xy 129.276981 -235.278647)
			(xy 129.32296 -235.300464) (xy 129.364844 -235.329374) (xy 129.401548 -235.364629) (xy 129.432121 -235.405315)
			(xy 129.455772 -235.450378) (xy 129.471888 -235.498652) (xy 129.480052 -235.548886) (xy 129.480564 -235.574332)
			(xy 129.798838 -235.574332) (xy 129.802798 -235.525278) (xy 129.814575 -235.477494) (xy 129.833866 -235.432218)
			(xy 129.860169 -235.390622) (xy 129.892804 -235.353785) (xy 129.930925 -235.32266) (xy 129.973546 -235.298053)
			(xy 130.019562 -235.280601) (xy 130.067781 -235.270757) (xy 130.116956 -235.268776) (xy 130.165811 -235.274708)
			(xy 130.213082 -235.2884) (xy 130.257544 -235.309498) (xy 130.298047 -235.337454) (xy 130.33354 -235.371546)
			(xy 130.363105 -235.41089) (xy 130.385976 -235.454467) (xy 130.40156 -235.501148) (xy 130.409455 -235.549725)
			(xy 130.40995 -235.574332) (xy 130.728461 -235.574332) (xy 130.732556 -235.523604) (xy 130.744735 -235.47419)
			(xy 130.764683 -235.42737) (xy 130.791884 -235.384356) (xy 130.825632 -235.346262) (xy 130.865054 -235.314075)
			(xy 130.909128 -235.288629) (xy 130.956714 -235.270582) (xy 131.006578 -235.260402) (xy 131.05743 -235.258353)
			(xy 131.107951 -235.264487) (xy 131.156835 -235.278647) (xy 131.202814 -235.300464) (xy 131.244698 -235.329374)
			(xy 131.281402 -235.364629) (xy 131.311975 -235.405315) (xy 131.335626 -235.450378) (xy 131.351742 -235.498652)
			(xy 131.359906 -235.548886) (xy 131.360418 -235.574332) (xy 131.678946 -235.574332) (xy 131.682906 -235.525278)
			(xy 131.694683 -235.477494) (xy 131.713974 -235.432218) (xy 131.740277 -235.390622) (xy 131.772912 -235.353785)
			(xy 131.811033 -235.32266) (xy 131.853654 -235.298053) (xy 131.89967 -235.280601) (xy 131.947889 -235.270757)
			(xy 131.997064 -235.268776) (xy 132.045919 -235.274708) (xy 132.09319 -235.2884) (xy 132.137652 -235.309498)
			(xy 132.178155 -235.337454) (xy 132.213648 -235.371546) (xy 132.243213 -235.41089) (xy 132.266084 -235.454467)
			(xy 132.281668 -235.501148) (xy 132.289563 -235.549725) (xy 132.290058 -235.574332) (xy 132.608569 -235.574332)
			(xy 132.612664 -235.523604) (xy 132.624843 -235.47419) (xy 132.644791 -235.42737) (xy 132.671992 -235.384356)
			(xy 132.70574 -235.346262) (xy 132.745162 -235.314075) (xy 132.789236 -235.288629) (xy 132.836822 -235.270582)
			(xy 132.886686 -235.260402) (xy 132.937538 -235.258353) (xy 132.988059 -235.264487) (xy 133.036943 -235.278647)
			(xy 133.082922 -235.300464) (xy 133.124806 -235.329374) (xy 133.16151 -235.364629) (xy 133.192083 -235.405315)
			(xy 133.215734 -235.450378) (xy 133.23185 -235.498652) (xy 133.240014 -235.548886) (xy 133.240526 -235.574332)
			(xy 133.559054 -235.574332) (xy 133.563014 -235.525278) (xy 133.574791 -235.477494) (xy 133.594082 -235.432218)
			(xy 133.620385 -235.390622) (xy 133.65302 -235.353785) (xy 133.691141 -235.32266) (xy 133.733762 -235.298053)
			(xy 133.779778 -235.280601) (xy 133.827997 -235.270757) (xy 133.877172 -235.268776) (xy 133.926027 -235.274708)
			(xy 133.973298 -235.2884) (xy 134.01776 -235.309498) (xy 134.058263 -235.337454) (xy 134.093756 -235.371546)
			(xy 134.123321 -235.41089) (xy 134.146192 -235.454467) (xy 134.161776 -235.501148) (xy 134.169671 -235.549725)
			(xy 134.170166 -235.574332) (xy 134.498854 -235.574332) (xy 134.502814 -235.525278) (xy 134.514591 -235.477494)
			(xy 134.533882 -235.432218) (xy 134.560185 -235.390622) (xy 134.59282 -235.353785) (xy 134.630941 -235.32266)
			(xy 134.673562 -235.298053) (xy 134.719578 -235.280601) (xy 134.767797 -235.270757) (xy 134.816972 -235.268776)
			(xy 134.865827 -235.274708) (xy 134.913098 -235.2884) (xy 134.95756 -235.309498) (xy 134.998063 -235.337454)
			(xy 135.033556 -235.371546) (xy 135.063121 -235.41089) (xy 135.085992 -235.454467) (xy 135.101576 -235.501148)
			(xy 135.109471 -235.549725) (xy 135.109966 -235.574332) (xy 135.438908 -235.574332) (xy 135.442868 -235.525278)
			(xy 135.454645 -235.477494) (xy 135.473936 -235.432218) (xy 135.500239 -235.390622) (xy 135.532874 -235.353785)
			(xy 135.570995 -235.32266) (xy 135.613616 -235.298053) (xy 135.659632 -235.280601) (xy 135.707851 -235.270757)
			(xy 135.757026 -235.268776) (xy 135.805881 -235.274708) (xy 135.853152 -235.2884) (xy 135.897614 -235.309498)
			(xy 135.938117 -235.337454) (xy 135.97361 -235.371546) (xy 136.003175 -235.41089) (xy 136.026046 -235.454467)
			(xy 136.04163 -235.501148) (xy 136.049525 -235.549725) (xy 136.05002 -235.574332) (xy 136.378962 -235.574332)
			(xy 136.382922 -235.525278) (xy 136.394699 -235.477494) (xy 136.41399 -235.432218) (xy 136.440293 -235.390622)
			(xy 136.472928 -235.353785) (xy 136.511049 -235.32266) (xy 136.55367 -235.298053) (xy 136.599686 -235.280601)
			(xy 136.647905 -235.270757) (xy 136.69708 -235.268776) (xy 136.745935 -235.274708) (xy 136.793206 -235.2884)
			(xy 136.837668 -235.309498) (xy 136.878171 -235.337454) (xy 136.913664 -235.371546) (xy 136.943229 -235.41089)
			(xy 136.9661 -235.454467) (xy 136.981684 -235.501148) (xy 136.989579 -235.549725) (xy 136.990074 -235.574332)
			(xy 137.319016 -235.574332) (xy 137.322976 -235.525278) (xy 137.334753 -235.477494) (xy 137.354044 -235.432218)
			(xy 137.380347 -235.390622) (xy 137.412982 -235.353785) (xy 137.451103 -235.32266) (xy 137.493724 -235.298053)
			(xy 137.53974 -235.280601) (xy 137.587959 -235.270757) (xy 137.637134 -235.268776) (xy 137.685989 -235.274708)
			(xy 137.73326 -235.2884) (xy 137.777722 -235.309498) (xy 137.818225 -235.337454) (xy 137.853718 -235.371546)
			(xy 137.883283 -235.41089) (xy 137.906154 -235.454467) (xy 137.921738 -235.501148) (xy 137.929633 -235.549725)
			(xy 137.930128 -235.574332) (xy 138.25907 -235.574332) (xy 138.26303 -235.525278) (xy 138.274807 -235.477494)
			(xy 138.294098 -235.432218) (xy 138.320401 -235.390622) (xy 138.353036 -235.353785) (xy 138.391157 -235.32266)
			(xy 138.433778 -235.298053) (xy 138.479794 -235.280601) (xy 138.528013 -235.270757) (xy 138.577188 -235.268776)
			(xy 138.626043 -235.274708) (xy 138.673314 -235.2884) (xy 138.717776 -235.309498) (xy 138.758279 -235.337454)
			(xy 138.793772 -235.371546) (xy 138.823337 -235.41089) (xy 138.846208 -235.454467) (xy 138.861792 -235.501148)
			(xy 138.869687 -235.549725) (xy 138.870182 -235.574332) (xy 139.19887 -235.574332) (xy 139.20283 -235.525278)
			(xy 139.214607 -235.477494) (xy 139.233898 -235.432218) (xy 139.260201 -235.390622) (xy 139.292836 -235.353785)
			(xy 139.330957 -235.32266) (xy 139.373578 -235.298053) (xy 139.419594 -235.280601) (xy 139.467813 -235.270757)
			(xy 139.516988 -235.268776) (xy 139.565843 -235.274708) (xy 139.613114 -235.2884) (xy 139.657576 -235.309498)
			(xy 139.698079 -235.337454) (xy 139.733572 -235.371546) (xy 139.763137 -235.41089) (xy 139.786008 -235.454467)
			(xy 139.801592 -235.501148) (xy 139.809487 -235.549725) (xy 139.809982 -235.574332) (xy 139.809487 -235.598939)
			(xy 139.801592 -235.647516) (xy 139.786008 -235.694197) (xy 139.763137 -235.737774) (xy 139.733572 -235.777118)
			(xy 139.698079 -235.81121) (xy 139.657576 -235.839166) (xy 139.613114 -235.860264) (xy 139.565843 -235.873956)
			(xy 139.516988 -235.879888) (xy 139.467813 -235.877907) (xy 139.419594 -235.868063) (xy 139.373578 -235.850611)
			(xy 139.330957 -235.826004) (xy 139.292836 -235.794879) (xy 139.260201 -235.758042) (xy 139.233898 -235.716446)
			(xy 139.214607 -235.67117) (xy 139.20283 -235.623386) (xy 139.19887 -235.574332) (xy 138.870182 -235.574332)
			(xy 138.869687 -235.598939) (xy 138.861792 -235.647516) (xy 138.846208 -235.694197) (xy 138.823337 -235.737774)
			(xy 138.793772 -235.777118) (xy 138.758279 -235.81121) (xy 138.717776 -235.839166) (xy 138.673314 -235.860264)
			(xy 138.626043 -235.873956) (xy 138.577188 -235.879888) (xy 138.528013 -235.877907) (xy 138.479794 -235.868063)
			(xy 138.433778 -235.850611) (xy 138.391157 -235.826004) (xy 138.353036 -235.794879) (xy 138.320401 -235.758042)
			(xy 138.294098 -235.716446) (xy 138.274807 -235.67117) (xy 138.26303 -235.623386) (xy 138.25907 -235.574332)
			(xy 137.930128 -235.574332) (xy 137.929633 -235.598939) (xy 137.921738 -235.647516) (xy 137.906154 -235.694197)
			(xy 137.883283 -235.737774) (xy 137.853718 -235.777118) (xy 137.818225 -235.81121) (xy 137.777722 -235.839166)
			(xy 137.73326 -235.860264) (xy 137.685989 -235.873956) (xy 137.637134 -235.879888) (xy 137.587959 -235.877907)
			(xy 137.53974 -235.868063) (xy 137.493724 -235.850611) (xy 137.451103 -235.826004) (xy 137.412982 -235.794879)
			(xy 137.380347 -235.758042) (xy 137.354044 -235.716446) (xy 137.334753 -235.67117) (xy 137.322976 -235.623386)
			(xy 137.319016 -235.574332) (xy 136.990074 -235.574332) (xy 136.989579 -235.598939) (xy 136.981684 -235.647516)
			(xy 136.9661 -235.694197) (xy 136.943229 -235.737774) (xy 136.913664 -235.777118) (xy 136.878171 -235.81121)
			(xy 136.837668 -235.839166) (xy 136.793206 -235.860264) (xy 136.745935 -235.873956) (xy 136.69708 -235.879888)
			(xy 136.647905 -235.877907) (xy 136.599686 -235.868063) (xy 136.55367 -235.850611) (xy 136.511049 -235.826004)
			(xy 136.472928 -235.794879) (xy 136.440293 -235.758042) (xy 136.41399 -235.716446) (xy 136.394699 -235.67117)
			(xy 136.382922 -235.623386) (xy 136.378962 -235.574332) (xy 136.05002 -235.574332) (xy 136.049525 -235.598939)
			(xy 136.04163 -235.647516) (xy 136.026046 -235.694197) (xy 136.003175 -235.737774) (xy 135.97361 -235.777118)
			(xy 135.938117 -235.81121) (xy 135.897614 -235.839166) (xy 135.853152 -235.860264) (xy 135.805881 -235.873956)
			(xy 135.757026 -235.879888) (xy 135.707851 -235.877907) (xy 135.659632 -235.868063) (xy 135.613616 -235.850611)
			(xy 135.570995 -235.826004) (xy 135.532874 -235.794879) (xy 135.500239 -235.758042) (xy 135.473936 -235.716446)
			(xy 135.454645 -235.67117) (xy 135.442868 -235.623386) (xy 135.438908 -235.574332) (xy 135.109966 -235.574332)
			(xy 135.109471 -235.598939) (xy 135.101576 -235.647516) (xy 135.085992 -235.694197) (xy 135.063121 -235.737774)
			(xy 135.033556 -235.777118) (xy 134.998063 -235.81121) (xy 134.95756 -235.839166) (xy 134.913098 -235.860264)
			(xy 134.865827 -235.873956) (xy 134.816972 -235.879888) (xy 134.767797 -235.877907) (xy 134.719578 -235.868063)
			(xy 134.673562 -235.850611) (xy 134.630941 -235.826004) (xy 134.59282 -235.794879) (xy 134.560185 -235.758042)
			(xy 134.533882 -235.716446) (xy 134.514591 -235.67117) (xy 134.502814 -235.623386) (xy 134.498854 -235.574332)
			(xy 134.170166 -235.574332) (xy 134.169671 -235.598939) (xy 134.161776 -235.647516) (xy 134.146192 -235.694197)
			(xy 134.123321 -235.737774) (xy 134.093756 -235.777118) (xy 134.058263 -235.81121) (xy 134.01776 -235.839166)
			(xy 133.973298 -235.860264) (xy 133.926027 -235.873956) (xy 133.877172 -235.879888) (xy 133.827997 -235.877907)
			(xy 133.779778 -235.868063) (xy 133.733762 -235.850611) (xy 133.691141 -235.826004) (xy 133.65302 -235.794879)
			(xy 133.620385 -235.758042) (xy 133.594082 -235.716446) (xy 133.574791 -235.67117) (xy 133.563014 -235.623386)
			(xy 133.559054 -235.574332) (xy 133.240526 -235.574332) (xy 133.240014 -235.599778) (xy 133.23185 -235.650012)
			(xy 133.215734 -235.698286) (xy 133.192083 -235.743349) (xy 133.16151 -235.784035) (xy 133.124806 -235.81929)
			(xy 133.082922 -235.8482) (xy 133.036943 -235.870017) (xy 132.988059 -235.884177) (xy 132.937538 -235.890311)
			(xy 132.886686 -235.888262) (xy 132.836822 -235.878082) (xy 132.789236 -235.860035) (xy 132.745162 -235.834589)
			(xy 132.70574 -235.802402) (xy 132.671992 -235.764308) (xy 132.644791 -235.721294) (xy 132.624843 -235.674474)
			(xy 132.612664 -235.62506) (xy 132.608569 -235.574332) (xy 132.290058 -235.574332) (xy 132.289563 -235.598939)
			(xy 132.281668 -235.647516) (xy 132.266084 -235.694197) (xy 132.243213 -235.737774) (xy 132.213648 -235.777118)
			(xy 132.178155 -235.81121) (xy 132.137652 -235.839166) (xy 132.09319 -235.860264) (xy 132.045919 -235.873956)
			(xy 131.997064 -235.879888) (xy 131.947889 -235.877907) (xy 131.89967 -235.868063) (xy 131.853654 -235.850611)
			(xy 131.811033 -235.826004) (xy 131.772912 -235.794879) (xy 131.740277 -235.758042) (xy 131.713974 -235.716446)
			(xy 131.694683 -235.67117) (xy 131.682906 -235.623386) (xy 131.678946 -235.574332) (xy 131.360418 -235.574332)
			(xy 131.359906 -235.599778) (xy 131.351742 -235.650012) (xy 131.335626 -235.698286) (xy 131.311975 -235.743349)
			(xy 131.281402 -235.784035) (xy 131.244698 -235.81929) (xy 131.202814 -235.8482) (xy 131.156835 -235.870017)
			(xy 131.107951 -235.884177) (xy 131.05743 -235.890311) (xy 131.006578 -235.888262) (xy 130.956714 -235.878082)
			(xy 130.909128 -235.860035) (xy 130.865054 -235.834589) (xy 130.825632 -235.802402) (xy 130.791884 -235.764308)
			(xy 130.764683 -235.721294) (xy 130.744735 -235.674474) (xy 130.732556 -235.62506) (xy 130.728461 -235.574332)
			(xy 130.40995 -235.574332) (xy 130.409455 -235.598939) (xy 130.40156 -235.647516) (xy 130.385976 -235.694197)
			(xy 130.363105 -235.737774) (xy 130.33354 -235.777118) (xy 130.298047 -235.81121) (xy 130.257544 -235.839166)
			(xy 130.213082 -235.860264) (xy 130.165811 -235.873956) (xy 130.116956 -235.879888) (xy 130.067781 -235.877907)
			(xy 130.019562 -235.868063) (xy 129.973546 -235.850611) (xy 129.930925 -235.826004) (xy 129.892804 -235.794879)
			(xy 129.860169 -235.758042) (xy 129.833866 -235.716446) (xy 129.814575 -235.67117) (xy 129.802798 -235.623386)
			(xy 129.798838 -235.574332) (xy 129.480564 -235.574332) (xy 129.480052 -235.599778) (xy 129.471888 -235.650012)
			(xy 129.455772 -235.698286) (xy 129.432121 -235.743349) (xy 129.401548 -235.784035) (xy 129.364844 -235.81929)
			(xy 129.32296 -235.8482) (xy 129.276981 -235.870017) (xy 129.228097 -235.884177) (xy 129.177576 -235.890311)
			(xy 129.126724 -235.888262) (xy 129.07686 -235.878082) (xy 129.029274 -235.860035) (xy 128.9852 -235.834589)
			(xy 128.945778 -235.802402) (xy 128.91203 -235.764308) (xy 128.884829 -235.721294) (xy 128.864881 -235.674474)
			(xy 128.852702 -235.62506) (xy 128.848607 -235.574332) (xy 128.54051 -235.574332) (xy 128.539998 -235.599778)
			(xy 128.531834 -235.650012) (xy 128.515718 -235.698286) (xy 128.492067 -235.743349) (xy 128.461494 -235.784035)
			(xy 128.42479 -235.81929) (xy 128.382906 -235.8482) (xy 128.336927 -235.870017) (xy 128.288043 -235.884177)
			(xy 128.237522 -235.890311) (xy 128.18667 -235.888262) (xy 128.136806 -235.878082) (xy 128.08922 -235.860035)
			(xy 128.045146 -235.834589) (xy 128.005724 -235.802402) (xy 127.971976 -235.764308) (xy 127.944775 -235.721294)
			(xy 127.924827 -235.674474) (xy 127.912648 -235.62506) (xy 127.908553 -235.574332) (xy 126.88316 -235.574332)
			(xy 126.88316 -236.048804) (xy 126.883451 -236.056678) (xy 126.888233 -236.071682) (xy 126.892558 -236.078268)
			(xy 126.896876 -236.084618) (xy 126.909322 -236.094016) (xy 126.916942 -236.096556) (xy 126.940377 -236.10541)
			(xy 126.984217 -236.129649) (xy 127.023511 -236.160718) (xy 127.057208 -236.197785) (xy 127.084401 -236.239855)
			(xy 127.104363 -236.2858) (xy 127.116558 -236.334387) (xy 127.120658 -236.384313) (xy 127.120656 -236.384338)
			(xy 127.438399 -236.384338) (xy 127.442494 -236.33361) (xy 127.454673 -236.284196) (xy 127.474621 -236.237376)
			(xy 127.501822 -236.194362) (xy 127.53557 -236.156268) (xy 127.574992 -236.124081) (xy 127.619066 -236.098635)
			(xy 127.666652 -236.080588) (xy 127.716516 -236.070408) (xy 127.767368 -236.068359) (xy 127.817889 -236.074493)
			(xy 127.866773 -236.088653) (xy 127.912752 -236.11047) (xy 127.954636 -236.13938) (xy 127.99134 -236.174635)
			(xy 128.021913 -236.215321) (xy 128.045564 -236.260384) (xy 128.06168 -236.308658) (xy 128.069844 -236.358892)
			(xy 128.070356 -236.384338) (xy 128.388884 -236.384338) (xy 128.392844 -236.335284) (xy 128.404621 -236.2875)
			(xy 128.423912 -236.242224) (xy 128.450215 -236.200628) (xy 128.48285 -236.163791) (xy 128.520971 -236.132666)
			(xy 128.563592 -236.108059) (xy 128.609608 -236.090607) (xy 128.657827 -236.080763) (xy 128.707002 -236.078782)
			(xy 128.755857 -236.084714) (xy 128.803128 -236.098406) (xy 128.84759 -236.119504) (xy 128.888093 -236.14746)
			(xy 128.923586 -236.181552) (xy 128.953151 -236.220896) (xy 128.976022 -236.264473) (xy 128.991606 -236.311154)
			(xy 128.999501 -236.359731) (xy 128.999996 -236.384338) (xy 129.318507 -236.384338) (xy 129.322602 -236.33361)
			(xy 129.334781 -236.284196) (xy 129.354729 -236.237376) (xy 129.38193 -236.194362) (xy 129.415678 -236.156268)
			(xy 129.4551 -236.124081) (xy 129.499174 -236.098635) (xy 129.54676 -236.080588) (xy 129.596624 -236.070408)
			(xy 129.647476 -236.068359) (xy 129.697997 -236.074493) (xy 129.746881 -236.088653) (xy 129.79286 -236.11047)
			(xy 129.834744 -236.13938) (xy 129.871448 -236.174635) (xy 129.902021 -236.215321) (xy 129.925672 -236.260384)
			(xy 129.941788 -236.308658) (xy 129.949952 -236.358892) (xy 129.950464 -236.384338) (xy 130.268992 -236.384338)
			(xy 130.272952 -236.335284) (xy 130.284729 -236.2875) (xy 130.30402 -236.242224) (xy 130.330323 -236.200628)
			(xy 130.362958 -236.163791) (xy 130.401079 -236.132666) (xy 130.4437 -236.108059) (xy 130.489716 -236.090607)
			(xy 130.537935 -236.080763) (xy 130.58711 -236.078782) (xy 130.635965 -236.084714) (xy 130.683236 -236.098406)
			(xy 130.727698 -236.119504) (xy 130.768201 -236.14746) (xy 130.803694 -236.181552) (xy 130.833259 -236.220896)
			(xy 130.85613 -236.264473) (xy 130.871714 -236.311154) (xy 130.879609 -236.359731) (xy 130.880104 -236.384338)
			(xy 131.198615 -236.384338) (xy 131.20271 -236.33361) (xy 131.214889 -236.284196) (xy 131.234837 -236.237376)
			(xy 131.262038 -236.194362) (xy 131.295786 -236.156268) (xy 131.335208 -236.124081) (xy 131.379282 -236.098635)
			(xy 131.426868 -236.080588) (xy 131.476732 -236.070408) (xy 131.527584 -236.068359) (xy 131.578105 -236.074493)
			(xy 131.626989 -236.088653) (xy 131.672968 -236.11047) (xy 131.714852 -236.13938) (xy 131.751556 -236.174635)
			(xy 131.782129 -236.215321) (xy 131.80578 -236.260384) (xy 131.821896 -236.308658) (xy 131.83006 -236.358892)
			(xy 131.830572 -236.384338) (xy 132.138415 -236.384338) (xy 132.14251 -236.33361) (xy 132.154689 -236.284196)
			(xy 132.174637 -236.237376) (xy 132.201838 -236.194362) (xy 132.235586 -236.156268) (xy 132.275008 -236.124081)
			(xy 132.319082 -236.098635) (xy 132.366668 -236.080588) (xy 132.416532 -236.070408) (xy 132.467384 -236.068359)
			(xy 132.517905 -236.074493) (xy 132.566789 -236.088653) (xy 132.612768 -236.11047) (xy 132.654652 -236.13938)
			(xy 132.691356 -236.174635) (xy 132.721929 -236.215321) (xy 132.74558 -236.260384) (xy 132.761696 -236.308658)
			(xy 132.76986 -236.358892) (xy 132.770372 -236.384338) (xy 133.0889 -236.384338) (xy 133.09286 -236.335284)
			(xy 133.104637 -236.2875) (xy 133.123928 -236.242224) (xy 133.150231 -236.200628) (xy 133.182866 -236.163791)
			(xy 133.220987 -236.132666) (xy 133.263608 -236.108059) (xy 133.309624 -236.090607) (xy 133.357843 -236.080763)
			(xy 133.407018 -236.078782) (xy 133.455873 -236.084714) (xy 133.503144 -236.098406) (xy 133.547606 -236.119504)
			(xy 133.588109 -236.14746) (xy 133.623602 -236.181552) (xy 133.653167 -236.220896) (xy 133.676038 -236.264473)
			(xy 133.691622 -236.311154) (xy 133.699517 -236.359731) (xy 133.700012 -236.384338) (xy 134.028954 -236.384338)
			(xy 134.032914 -236.335284) (xy 134.044691 -236.2875) (xy 134.063982 -236.242224) (xy 134.090285 -236.200628)
			(xy 134.12292 -236.163791) (xy 134.161041 -236.132666) (xy 134.203662 -236.108059) (xy 134.249678 -236.090607)
			(xy 134.297897 -236.080763) (xy 134.347072 -236.078782) (xy 134.395927 -236.084714) (xy 134.443198 -236.098406)
			(xy 134.48766 -236.119504) (xy 134.528163 -236.14746) (xy 134.563656 -236.181552) (xy 134.593221 -236.220896)
			(xy 134.616092 -236.264473) (xy 134.631676 -236.311154) (xy 134.639571 -236.359731) (xy 134.640066 -236.384338)
			(xy 134.969008 -236.384338) (xy 134.972968 -236.335284) (xy 134.984745 -236.2875) (xy 135.004036 -236.242224)
			(xy 135.030339 -236.200628) (xy 135.062974 -236.163791) (xy 135.101095 -236.132666) (xy 135.143716 -236.108059)
			(xy 135.189732 -236.090607) (xy 135.237951 -236.080763) (xy 135.287126 -236.078782) (xy 135.335981 -236.084714)
			(xy 135.383252 -236.098406) (xy 135.427714 -236.119504) (xy 135.468217 -236.14746) (xy 135.50371 -236.181552)
			(xy 135.533275 -236.220896) (xy 135.556146 -236.264473) (xy 135.57173 -236.311154) (xy 135.579625 -236.359731)
			(xy 135.58012 -236.384338) (xy 135.909062 -236.384338) (xy 135.913022 -236.335284) (xy 135.924799 -236.2875)
			(xy 135.94409 -236.242224) (xy 135.970393 -236.200628) (xy 136.003028 -236.163791) (xy 136.041149 -236.132666)
			(xy 136.08377 -236.108059) (xy 136.129786 -236.090607) (xy 136.178005 -236.080763) (xy 136.22718 -236.078782)
			(xy 136.276035 -236.084714) (xy 136.323306 -236.098406) (xy 136.367768 -236.119504) (xy 136.408271 -236.14746)
			(xy 136.443764 -236.181552) (xy 136.473329 -236.220896) (xy 136.4962 -236.264473) (xy 136.511784 -236.311154)
			(xy 136.519679 -236.359731) (xy 136.520174 -236.384338) (xy 136.848862 -236.384338) (xy 136.852822 -236.335284)
			(xy 136.864599 -236.2875) (xy 136.88389 -236.242224) (xy 136.910193 -236.200628) (xy 136.942828 -236.163791)
			(xy 136.980949 -236.132666) (xy 137.02357 -236.108059) (xy 137.069586 -236.090607) (xy 137.117805 -236.080763)
			(xy 137.16698 -236.078782) (xy 137.215835 -236.084714) (xy 137.263106 -236.098406) (xy 137.307568 -236.119504)
			(xy 137.348071 -236.14746) (xy 137.383564 -236.181552) (xy 137.413129 -236.220896) (xy 137.436 -236.264473)
			(xy 137.451584 -236.311154) (xy 137.459479 -236.359731) (xy 137.459974 -236.384338) (xy 137.788916 -236.384338)
			(xy 137.792876 -236.335284) (xy 137.804653 -236.2875) (xy 137.823944 -236.242224) (xy 137.850247 -236.200628)
			(xy 137.882882 -236.163791) (xy 137.921003 -236.132666) (xy 137.963624 -236.108059) (xy 138.00964 -236.090607)
			(xy 138.057859 -236.080763) (xy 138.107034 -236.078782) (xy 138.155889 -236.084714) (xy 138.20316 -236.098406)
			(xy 138.247622 -236.119504) (xy 138.288125 -236.14746) (xy 138.323618 -236.181552) (xy 138.353183 -236.220896)
			(xy 138.376054 -236.264473) (xy 138.391638 -236.311154) (xy 138.399533 -236.359731) (xy 138.400028 -236.384338)
			(xy 138.72897 -236.384338) (xy 138.73293 -236.335284) (xy 138.744707 -236.2875) (xy 138.763998 -236.242224)
			(xy 138.790301 -236.200628) (xy 138.822936 -236.163791) (xy 138.861057 -236.132666) (xy 138.903678 -236.108059)
			(xy 138.949694 -236.090607) (xy 138.997913 -236.080763) (xy 139.047088 -236.078782) (xy 139.095943 -236.084714)
			(xy 139.143214 -236.098406) (xy 139.187676 -236.119504) (xy 139.228179 -236.14746) (xy 139.263672 -236.181552)
			(xy 139.293237 -236.220896) (xy 139.316108 -236.264473) (xy 139.331692 -236.311154) (xy 139.339587 -236.359731)
			(xy 139.340082 -236.384338) (xy 139.339587 -236.408945) (xy 139.331692 -236.457522) (xy 139.316108 -236.504203)
			(xy 139.293237 -236.54778) (xy 139.263672 -236.587124) (xy 139.228179 -236.621216) (xy 139.187676 -236.649172)
			(xy 139.143214 -236.67027) (xy 139.095943 -236.683962) (xy 139.047088 -236.689894) (xy 138.997913 -236.687913)
			(xy 138.949694 -236.678069) (xy 138.903678 -236.660617) (xy 138.861057 -236.63601) (xy 138.822936 -236.604885)
			(xy 138.790301 -236.568048) (xy 138.763998 -236.526452) (xy 138.744707 -236.481176) (xy 138.73293 -236.433392)
			(xy 138.72897 -236.384338) (xy 138.400028 -236.384338) (xy 138.399533 -236.408945) (xy 138.391638 -236.457522)
			(xy 138.376054 -236.504203) (xy 138.353183 -236.54778) (xy 138.323618 -236.587124) (xy 138.288125 -236.621216)
			(xy 138.247622 -236.649172) (xy 138.20316 -236.67027) (xy 138.155889 -236.683962) (xy 138.107034 -236.689894)
			(xy 138.057859 -236.687913) (xy 138.00964 -236.678069) (xy 137.963624 -236.660617) (xy 137.921003 -236.63601)
			(xy 137.882882 -236.604885) (xy 137.850247 -236.568048) (xy 137.823944 -236.526452) (xy 137.804653 -236.481176)
			(xy 137.792876 -236.433392) (xy 137.788916 -236.384338) (xy 137.459974 -236.384338) (xy 137.459479 -236.408945)
			(xy 137.451584 -236.457522) (xy 137.436 -236.504203) (xy 137.413129 -236.54778) (xy 137.383564 -236.587124)
			(xy 137.348071 -236.621216) (xy 137.307568 -236.649172) (xy 137.263106 -236.67027) (xy 137.215835 -236.683962)
			(xy 137.16698 -236.689894) (xy 137.117805 -236.687913) (xy 137.069586 -236.678069) (xy 137.02357 -236.660617)
			(xy 136.980949 -236.63601) (xy 136.942828 -236.604885) (xy 136.910193 -236.568048) (xy 136.88389 -236.526452)
			(xy 136.864599 -236.481176) (xy 136.852822 -236.433392) (xy 136.848862 -236.384338) (xy 136.520174 -236.384338)
			(xy 136.519679 -236.408945) (xy 136.511784 -236.457522) (xy 136.4962 -236.504203) (xy 136.473329 -236.54778)
			(xy 136.443764 -236.587124) (xy 136.408271 -236.621216) (xy 136.367768 -236.649172) (xy 136.323306 -236.67027)
			(xy 136.276035 -236.683962) (xy 136.22718 -236.689894) (xy 136.178005 -236.687913) (xy 136.129786 -236.678069)
			(xy 136.08377 -236.660617) (xy 136.041149 -236.63601) (xy 136.003028 -236.604885) (xy 135.970393 -236.568048)
			(xy 135.94409 -236.526452) (xy 135.924799 -236.481176) (xy 135.913022 -236.433392) (xy 135.909062 -236.384338)
			(xy 135.58012 -236.384338) (xy 135.579625 -236.408945) (xy 135.57173 -236.457522) (xy 135.556146 -236.504203)
			(xy 135.533275 -236.54778) (xy 135.50371 -236.587124) (xy 135.468217 -236.621216) (xy 135.427714 -236.649172)
			(xy 135.383252 -236.67027) (xy 135.335981 -236.683962) (xy 135.287126 -236.689894) (xy 135.237951 -236.687913)
			(xy 135.189732 -236.678069) (xy 135.143716 -236.660617) (xy 135.101095 -236.63601) (xy 135.062974 -236.604885)
			(xy 135.030339 -236.568048) (xy 135.004036 -236.526452) (xy 134.984745 -236.481176) (xy 134.972968 -236.433392)
			(xy 134.969008 -236.384338) (xy 134.640066 -236.384338) (xy 134.639571 -236.408945) (xy 134.631676 -236.457522)
			(xy 134.616092 -236.504203) (xy 134.593221 -236.54778) (xy 134.563656 -236.587124) (xy 134.528163 -236.621216)
			(xy 134.48766 -236.649172) (xy 134.443198 -236.67027) (xy 134.395927 -236.683962) (xy 134.347072 -236.689894)
			(xy 134.297897 -236.687913) (xy 134.249678 -236.678069) (xy 134.203662 -236.660617) (xy 134.161041 -236.63601)
			(xy 134.12292 -236.604885) (xy 134.090285 -236.568048) (xy 134.063982 -236.526452) (xy 134.044691 -236.481176)
			(xy 134.032914 -236.433392) (xy 134.028954 -236.384338) (xy 133.700012 -236.384338) (xy 133.699517 -236.408945)
			(xy 133.691622 -236.457522) (xy 133.676038 -236.504203) (xy 133.653167 -236.54778) (xy 133.623602 -236.587124)
			(xy 133.588109 -236.621216) (xy 133.547606 -236.649172) (xy 133.503144 -236.67027) (xy 133.455873 -236.683962)
			(xy 133.407018 -236.689894) (xy 133.357843 -236.687913) (xy 133.309624 -236.678069) (xy 133.263608 -236.660617)
			(xy 133.220987 -236.63601) (xy 133.182866 -236.604885) (xy 133.150231 -236.568048) (xy 133.123928 -236.526452)
			(xy 133.104637 -236.481176) (xy 133.09286 -236.433392) (xy 133.0889 -236.384338) (xy 132.770372 -236.384338)
			(xy 132.76986 -236.409784) (xy 132.761696 -236.460018) (xy 132.74558 -236.508292) (xy 132.721929 -236.553355)
			(xy 132.691356 -236.594041) (xy 132.654652 -236.629296) (xy 132.612768 -236.658206) (xy 132.566789 -236.680023)
			(xy 132.517905 -236.694183) (xy 132.467384 -236.700317) (xy 132.416532 -236.698268) (xy 132.366668 -236.688088)
			(xy 132.319082 -236.670041) (xy 132.275008 -236.644595) (xy 132.235586 -236.612408) (xy 132.201838 -236.574314)
			(xy 132.174637 -236.5313) (xy 132.154689 -236.48448) (xy 132.14251 -236.435066) (xy 132.138415 -236.384338)
			(xy 131.830572 -236.384338) (xy 131.83006 -236.409784) (xy 131.821896 -236.460018) (xy 131.80578 -236.508292)
			(xy 131.782129 -236.553355) (xy 131.751556 -236.594041) (xy 131.714852 -236.629296) (xy 131.672968 -236.658206)
			(xy 131.626989 -236.680023) (xy 131.578105 -236.694183) (xy 131.527584 -236.700317) (xy 131.476732 -236.698268)
			(xy 131.426868 -236.688088) (xy 131.379282 -236.670041) (xy 131.335208 -236.644595) (xy 131.295786 -236.612408)
			(xy 131.262038 -236.574314) (xy 131.234837 -236.5313) (xy 131.214889 -236.48448) (xy 131.20271 -236.435066)
			(xy 131.198615 -236.384338) (xy 130.880104 -236.384338) (xy 130.879609 -236.408945) (xy 130.871714 -236.457522)
			(xy 130.85613 -236.504203) (xy 130.833259 -236.54778) (xy 130.803694 -236.587124) (xy 130.768201 -236.621216)
			(xy 130.727698 -236.649172) (xy 130.683236 -236.67027) (xy 130.635965 -236.683962) (xy 130.58711 -236.689894)
			(xy 130.537935 -236.687913) (xy 130.489716 -236.678069) (xy 130.4437 -236.660617) (xy 130.401079 -236.63601)
			(xy 130.362958 -236.604885) (xy 130.330323 -236.568048) (xy 130.30402 -236.526452) (xy 130.284729 -236.481176)
			(xy 130.272952 -236.433392) (xy 130.268992 -236.384338) (xy 129.950464 -236.384338) (xy 129.949952 -236.409784)
			(xy 129.941788 -236.460018) (xy 129.925672 -236.508292) (xy 129.902021 -236.553355) (xy 129.871448 -236.594041)
			(xy 129.834744 -236.629296) (xy 129.79286 -236.658206) (xy 129.746881 -236.680023) (xy 129.697997 -236.694183)
			(xy 129.647476 -236.700317) (xy 129.596624 -236.698268) (xy 129.54676 -236.688088) (xy 129.499174 -236.670041)
			(xy 129.4551 -236.644595) (xy 129.415678 -236.612408) (xy 129.38193 -236.574314) (xy 129.354729 -236.5313)
			(xy 129.334781 -236.48448) (xy 129.322602 -236.435066) (xy 129.318507 -236.384338) (xy 128.999996 -236.384338)
			(xy 128.999501 -236.408945) (xy 128.991606 -236.457522) (xy 128.976022 -236.504203) (xy 128.953151 -236.54778)
			(xy 128.923586 -236.587124) (xy 128.888093 -236.621216) (xy 128.84759 -236.649172) (xy 128.803128 -236.67027)
			(xy 128.755857 -236.683962) (xy 128.707002 -236.689894) (xy 128.657827 -236.687913) (xy 128.609608 -236.678069)
			(xy 128.563592 -236.660617) (xy 128.520971 -236.63601) (xy 128.48285 -236.604885) (xy 128.450215 -236.568048)
			(xy 128.423912 -236.526452) (xy 128.404621 -236.481176) (xy 128.392844 -236.433392) (xy 128.388884 -236.384338)
			(xy 128.070356 -236.384338) (xy 128.069844 -236.409784) (xy 128.06168 -236.460018) (xy 128.045564 -236.508292)
			(xy 128.021913 -236.553355) (xy 127.99134 -236.594041) (xy 127.954636 -236.629296) (xy 127.912752 -236.658206)
			(xy 127.866773 -236.680023) (xy 127.817889 -236.694183) (xy 127.767368 -236.700317) (xy 127.716516 -236.698268)
			(xy 127.666652 -236.688088) (xy 127.619066 -236.670041) (xy 127.574992 -236.644595) (xy 127.53557 -236.612408)
			(xy 127.501822 -236.574314) (xy 127.474621 -236.5313) (xy 127.454673 -236.48448) (xy 127.442494 -236.435066)
			(xy 127.438399 -236.384338) (xy 127.120656 -236.384338) (xy 127.116554 -236.434238) (xy 127.104355 -236.482824)
			(xy 127.084389 -236.528767) (xy 127.057192 -236.570835) (xy 127.023493 -236.607899) (xy 126.984195 -236.638965)
			(xy 126.940354 -236.6632) (xy 126.916942 -236.67212) (xy 126.909322 -236.67466) (xy 126.896876 -236.684058)
			(xy 126.892558 -236.690408) (xy 126.888229 -236.696993) (xy 126.883442 -236.711997) (xy 126.88316 -236.719872)
			(xy 126.88316 -236.919516) (xy 126.883687 -236.92951) (xy 126.891401 -236.947953) (xy 126.905576 -236.962051)
			(xy 126.914656 -236.966252) (xy 126.950216 -236.980476) (xy 126.950724 -236.980476) (xy 127.00381 -237.001304)
			(xy 127.011034 -237.003815) (xy 127.026287 -237.004855) (xy 127.033782 -237.003336) (xy 127.041402 -237.001558)
			(xy 127.053848 -236.994192) (xy 127.05969 -236.988096) (xy 127.077156 -236.969751) (xy 127.117054 -236.938548)
			(xy 127.161561 -236.914369) (xy 127.209451 -236.897879) (xy 127.259409 -236.889529) (xy 127.284734 -236.889036)
			(xy 127.309984 -236.88956) (xy 127.359794 -236.897877) (xy 127.407556 -236.914279) (xy 127.451968 -236.938317)
			(xy 127.491817 -236.969337) (xy 127.526018 -237.006493) (xy 127.553637 -237.048771) (xy 127.573921 -237.095018)
			(xy 127.586317 -237.143973) (xy 127.590487 -237.1943) (xy 127.590483 -237.194344) (xy 127.908553 -237.194344)
			(xy 127.912648 -237.143616) (xy 127.924827 -237.094202) (xy 127.944775 -237.047382) (xy 127.971976 -237.004368)
			(xy 128.005724 -236.966274) (xy 128.045146 -236.934087) (xy 128.08922 -236.908641) (xy 128.136806 -236.890594)
			(xy 128.18667 -236.880414) (xy 128.237522 -236.878365) (xy 128.288043 -236.884499) (xy 128.336927 -236.898659)
			(xy 128.382906 -236.920476) (xy 128.42479 -236.949386) (xy 128.461494 -236.984641) (xy 128.492067 -237.025327)
			(xy 128.515718 -237.07039) (xy 128.531834 -237.118664) (xy 128.539998 -237.168898) (xy 128.54051 -237.194344)
			(xy 128.848607 -237.194344) (xy 128.852702 -237.143616) (xy 128.864881 -237.094202) (xy 128.884829 -237.047382)
			(xy 128.91203 -237.004368) (xy 128.945778 -236.966274) (xy 128.9852 -236.934087) (xy 129.029274 -236.908641)
			(xy 129.07686 -236.890594) (xy 129.126724 -236.880414) (xy 129.177576 -236.878365) (xy 129.228097 -236.884499)
			(xy 129.276981 -236.898659) (xy 129.32296 -236.920476) (xy 129.364844 -236.949386) (xy 129.401548 -236.984641)
			(xy 129.432121 -237.025327) (xy 129.455772 -237.07039) (xy 129.471888 -237.118664) (xy 129.480052 -237.168898)
			(xy 129.480564 -237.194344) (xy 130.728461 -237.194344) (xy 130.732556 -237.143616) (xy 130.744735 -237.094202)
			(xy 130.764683 -237.047382) (xy 130.791884 -237.004368) (xy 130.825632 -236.966274) (xy 130.865054 -236.934087)
			(xy 130.909128 -236.908641) (xy 130.956714 -236.890594) (xy 131.006578 -236.880414) (xy 131.05743 -236.878365)
			(xy 131.107951 -236.884499) (xy 131.156835 -236.898659) (xy 131.202814 -236.920476) (xy 131.244698 -236.949386)
			(xy 131.281402 -236.984641) (xy 131.311975 -237.025327) (xy 131.335626 -237.07039) (xy 131.351742 -237.118664)
			(xy 131.359906 -237.168898) (xy 131.360418 -237.194344) (xy 131.678946 -237.194344) (xy 131.682906 -237.14529)
			(xy 131.694683 -237.097506) (xy 131.713974 -237.05223) (xy 131.740277 -237.010634) (xy 131.772912 -236.973797)
			(xy 131.811033 -236.942672) (xy 131.853654 -236.918065) (xy 131.89967 -236.900613) (xy 131.947889 -236.890769)
			(xy 131.997064 -236.888788) (xy 132.045919 -236.89472) (xy 132.09319 -236.908412) (xy 132.137652 -236.92951)
			(xy 132.178155 -236.957466) (xy 132.213648 -236.991558) (xy 132.243213 -237.030902) (xy 132.266084 -237.074479)
			(xy 132.281668 -237.12116) (xy 132.289563 -237.169737) (xy 132.290058 -237.194344) (xy 132.608569 -237.194344)
			(xy 132.612664 -237.143616) (xy 132.624843 -237.094202) (xy 132.644791 -237.047382) (xy 132.671992 -237.004368)
			(xy 132.70574 -236.966274) (xy 132.745162 -236.934087) (xy 132.789236 -236.908641) (xy 132.836822 -236.890594)
			(xy 132.886686 -236.880414) (xy 132.937538 -236.878365) (xy 132.988059 -236.884499) (xy 133.036943 -236.898659)
			(xy 133.082922 -236.920476) (xy 133.124806 -236.949386) (xy 133.16151 -236.984641) (xy 133.192083 -237.025327)
			(xy 133.215734 -237.07039) (xy 133.23185 -237.118664) (xy 133.240014 -237.168898) (xy 133.240526 -237.194344)
			(xy 133.559054 -237.194344) (xy 133.563014 -237.14529) (xy 133.574791 -237.097506) (xy 133.594082 -237.05223)
			(xy 133.620385 -237.010634) (xy 133.65302 -236.973797) (xy 133.691141 -236.942672) (xy 133.733762 -236.918065)
			(xy 133.779778 -236.900613) (xy 133.827997 -236.890769) (xy 133.877172 -236.888788) (xy 133.926027 -236.89472)
			(xy 133.973298 -236.908412) (xy 134.01776 -236.92951) (xy 134.058263 -236.957466) (xy 134.093756 -236.991558)
			(xy 134.123321 -237.030902) (xy 134.146192 -237.074479) (xy 134.161776 -237.12116) (xy 134.169671 -237.169737)
			(xy 134.170166 -237.194344) (xy 134.498854 -237.194344) (xy 134.502814 -237.14529) (xy 134.514591 -237.097506)
			(xy 134.533882 -237.05223) (xy 134.560185 -237.010634) (xy 134.59282 -236.973797) (xy 134.630941 -236.942672)
			(xy 134.673562 -236.918065) (xy 134.719578 -236.900613) (xy 134.767797 -236.890769) (xy 134.816972 -236.888788)
			(xy 134.865827 -236.89472) (xy 134.913098 -236.908412) (xy 134.95756 -236.92951) (xy 134.998063 -236.957466)
			(xy 135.033556 -236.991558) (xy 135.063121 -237.030902) (xy 135.085992 -237.074479) (xy 135.101576 -237.12116)
			(xy 135.109471 -237.169737) (xy 135.109966 -237.194344) (xy 135.438908 -237.194344) (xy 135.442868 -237.14529)
			(xy 135.454645 -237.097506) (xy 135.473936 -237.05223) (xy 135.500239 -237.010634) (xy 135.532874 -236.973797)
			(xy 135.570995 -236.942672) (xy 135.613616 -236.918065) (xy 135.659632 -236.900613) (xy 135.707851 -236.890769)
			(xy 135.757026 -236.888788) (xy 135.805881 -236.89472) (xy 135.853152 -236.908412) (xy 135.897614 -236.92951)
			(xy 135.938117 -236.957466) (xy 135.97361 -236.991558) (xy 136.003175 -237.030902) (xy 136.026046 -237.074479)
			(xy 136.04163 -237.12116) (xy 136.049525 -237.169737) (xy 136.05002 -237.194344) (xy 137.319016 -237.194344)
			(xy 137.322976 -237.14529) (xy 137.334753 -237.097506) (xy 137.354044 -237.05223) (xy 137.380347 -237.010634)
			(xy 137.412982 -236.973797) (xy 137.451103 -236.942672) (xy 137.493724 -236.918065) (xy 137.53974 -236.900613)
			(xy 137.587959 -236.890769) (xy 137.637134 -236.888788) (xy 137.685989 -236.89472) (xy 137.73326 -236.908412)
			(xy 137.777722 -236.92951) (xy 137.818225 -236.957466) (xy 137.853718 -236.991558) (xy 137.883283 -237.030902)
			(xy 137.906154 -237.074479) (xy 137.921738 -237.12116) (xy 137.929633 -237.169737) (xy 137.930128 -237.194344)
			(xy 138.25907 -237.194344) (xy 138.26303 -237.14529) (xy 138.274807 -237.097506) (xy 138.294098 -237.05223)
			(xy 138.320401 -237.010634) (xy 138.353036 -236.973797) (xy 138.391157 -236.942672) (xy 138.433778 -236.918065)
			(xy 138.479794 -236.900613) (xy 138.528013 -236.890769) (xy 138.577188 -236.888788) (xy 138.626043 -236.89472)
			(xy 138.673314 -236.908412) (xy 138.717776 -236.92951) (xy 138.758279 -236.957466) (xy 138.793772 -236.991558)
			(xy 138.823337 -237.030902) (xy 138.846208 -237.074479) (xy 138.861792 -237.12116) (xy 138.869687 -237.169737)
			(xy 138.870182 -237.194344) (xy 139.19887 -237.194344) (xy 139.20283 -237.14529) (xy 139.214607 -237.097506)
			(xy 139.233898 -237.05223) (xy 139.260201 -237.010634) (xy 139.292836 -236.973797) (xy 139.330957 -236.942672)
			(xy 139.373578 -236.918065) (xy 139.419594 -236.900613) (xy 139.467813 -236.890769) (xy 139.516988 -236.888788)
			(xy 139.565843 -236.89472) (xy 139.613114 -236.908412) (xy 139.657576 -236.92951) (xy 139.698079 -236.957466)
			(xy 139.733572 -236.991558) (xy 139.763137 -237.030902) (xy 139.786008 -237.074479) (xy 139.801592 -237.12116)
			(xy 139.809487 -237.169737) (xy 139.809982 -237.194344) (xy 139.809487 -237.218951) (xy 139.801592 -237.267528)
			(xy 139.786008 -237.314209) (xy 139.763137 -237.357786) (xy 139.733572 -237.39713) (xy 139.698079 -237.431222)
			(xy 139.657576 -237.459178) (xy 139.613114 -237.480276) (xy 139.565843 -237.493968) (xy 139.516988 -237.4999)
			(xy 139.467813 -237.497919) (xy 139.419594 -237.488075) (xy 139.373578 -237.470623) (xy 139.330957 -237.446016)
			(xy 139.292836 -237.414891) (xy 139.260201 -237.378054) (xy 139.233898 -237.336458) (xy 139.214607 -237.291182)
			(xy 139.20283 -237.243398) (xy 139.19887 -237.194344) (xy 138.870182 -237.194344) (xy 138.869687 -237.218951)
			(xy 138.861792 -237.267528) (xy 138.846208 -237.314209) (xy 138.823337 -237.357786) (xy 138.793772 -237.39713)
			(xy 138.758279 -237.431222) (xy 138.717776 -237.459178) (xy 138.673314 -237.480276) (xy 138.626043 -237.493968)
			(xy 138.577188 -237.4999) (xy 138.528013 -237.497919) (xy 138.479794 -237.488075) (xy 138.433778 -237.470623)
			(xy 138.391157 -237.446016) (xy 138.353036 -237.414891) (xy 138.320401 -237.378054) (xy 138.294098 -237.336458)
			(xy 138.274807 -237.291182) (xy 138.26303 -237.243398) (xy 138.25907 -237.194344) (xy 137.930128 -237.194344)
			(xy 137.929633 -237.218951) (xy 137.921738 -237.267528) (xy 137.906154 -237.314209) (xy 137.883283 -237.357786)
			(xy 137.853718 -237.39713) (xy 137.818225 -237.431222) (xy 137.777722 -237.459178) (xy 137.73326 -237.480276)
			(xy 137.685989 -237.493968) (xy 137.637134 -237.4999) (xy 137.587959 -237.497919) (xy 137.53974 -237.488075)
			(xy 137.493724 -237.470623) (xy 137.451103 -237.446016) (xy 137.412982 -237.414891) (xy 137.380347 -237.378054)
			(xy 137.354044 -237.336458) (xy 137.334753 -237.291182) (xy 137.322976 -237.243398) (xy 137.319016 -237.194344)
			(xy 136.05002 -237.194344) (xy 136.049525 -237.218951) (xy 136.04163 -237.267528) (xy 136.026046 -237.314209)
			(xy 136.003175 -237.357786) (xy 135.97361 -237.39713) (xy 135.938117 -237.431222) (xy 135.897614 -237.459178)
			(xy 135.853152 -237.480276) (xy 135.805881 -237.493968) (xy 135.757026 -237.4999) (xy 135.707851 -237.497919)
			(xy 135.659632 -237.488075) (xy 135.613616 -237.470623) (xy 135.570995 -237.446016) (xy 135.532874 -237.414891)
			(xy 135.500239 -237.378054) (xy 135.473936 -237.336458) (xy 135.454645 -237.291182) (xy 135.442868 -237.243398)
			(xy 135.438908 -237.194344) (xy 135.109966 -237.194344) (xy 135.109471 -237.218951) (xy 135.101576 -237.267528)
			(xy 135.085992 -237.314209) (xy 135.063121 -237.357786) (xy 135.033556 -237.39713) (xy 134.998063 -237.431222)
			(xy 134.95756 -237.459178) (xy 134.913098 -237.480276) (xy 134.865827 -237.493968) (xy 134.816972 -237.4999)
			(xy 134.767797 -237.497919) (xy 134.719578 -237.488075) (xy 134.673562 -237.470623) (xy 134.630941 -237.446016)
			(xy 134.59282 -237.414891) (xy 134.560185 -237.378054) (xy 134.533882 -237.336458) (xy 134.514591 -237.291182)
			(xy 134.502814 -237.243398) (xy 134.498854 -237.194344) (xy 134.170166 -237.194344) (xy 134.169671 -237.218951)
			(xy 134.161776 -237.267528) (xy 134.146192 -237.314209) (xy 134.123321 -237.357786) (xy 134.093756 -237.39713)
			(xy 134.058263 -237.431222) (xy 134.01776 -237.459178) (xy 133.973298 -237.480276) (xy 133.926027 -237.493968)
			(xy 133.877172 -237.4999) (xy 133.827997 -237.497919) (xy 133.779778 -237.488075) (xy 133.733762 -237.470623)
			(xy 133.691141 -237.446016) (xy 133.65302 -237.414891) (xy 133.620385 -237.378054) (xy 133.594082 -237.336458)
			(xy 133.574791 -237.291182) (xy 133.563014 -237.243398) (xy 133.559054 -237.194344) (xy 133.240526 -237.194344)
			(xy 133.240014 -237.21979) (xy 133.23185 -237.270024) (xy 133.215734 -237.318298) (xy 133.192083 -237.363361)
			(xy 133.16151 -237.404047) (xy 133.124806 -237.439302) (xy 133.082922 -237.468212) (xy 133.036943 -237.490029)
			(xy 132.988059 -237.504189) (xy 132.937538 -237.510323) (xy 132.886686 -237.508274) (xy 132.836822 -237.498094)
			(xy 132.789236 -237.480047) (xy 132.745162 -237.454601) (xy 132.70574 -237.422414) (xy 132.671992 -237.38432)
			(xy 132.644791 -237.341306) (xy 132.624843 -237.294486) (xy 132.612664 -237.245072) (xy 132.608569 -237.194344)
			(xy 132.290058 -237.194344) (xy 132.289563 -237.218951) (xy 132.281668 -237.267528) (xy 132.266084 -237.314209)
			(xy 132.243213 -237.357786) (xy 132.213648 -237.39713) (xy 132.178155 -237.431222) (xy 132.137652 -237.459178)
			(xy 132.09319 -237.480276) (xy 132.045919 -237.493968) (xy 131.997064 -237.4999) (xy 131.947889 -237.497919)
			(xy 131.89967 -237.488075) (xy 131.853654 -237.470623) (xy 131.811033 -237.446016) (xy 131.772912 -237.414891)
			(xy 131.740277 -237.378054) (xy 131.713974 -237.336458) (xy 131.694683 -237.291182) (xy 131.682906 -237.243398)
			(xy 131.678946 -237.194344) (xy 131.360418 -237.194344) (xy 131.359906 -237.21979) (xy 131.351742 -237.270024)
			(xy 131.335626 -237.318298) (xy 131.311975 -237.363361) (xy 131.281402 -237.404047) (xy 131.244698 -237.439302)
			(xy 131.202814 -237.468212) (xy 131.156835 -237.490029) (xy 131.107951 -237.504189) (xy 131.05743 -237.510323)
			(xy 131.006578 -237.508274) (xy 130.956714 -237.498094) (xy 130.909128 -237.480047) (xy 130.865054 -237.454601)
			(xy 130.825632 -237.422414) (xy 130.791884 -237.38432) (xy 130.764683 -237.341306) (xy 130.744735 -237.294486)
			(xy 130.732556 -237.245072) (xy 130.728461 -237.194344) (xy 129.480564 -237.194344) (xy 129.480052 -237.21979)
			(xy 129.471888 -237.270024) (xy 129.455772 -237.318298) (xy 129.432121 -237.363361) (xy 129.401548 -237.404047)
			(xy 129.364844 -237.439302) (xy 129.32296 -237.468212) (xy 129.276981 -237.490029) (xy 129.228097 -237.504189)
			(xy 129.177576 -237.510323) (xy 129.126724 -237.508274) (xy 129.07686 -237.498094) (xy 129.029274 -237.480047)
			(xy 128.9852 -237.454601) (xy 128.945778 -237.422414) (xy 128.91203 -237.38432) (xy 128.884829 -237.341306)
			(xy 128.864881 -237.294486) (xy 128.852702 -237.245072) (xy 128.848607 -237.194344) (xy 128.54051 -237.194344)
			(xy 128.539998 -237.21979) (xy 128.531834 -237.270024) (xy 128.515718 -237.318298) (xy 128.492067 -237.363361)
			(xy 128.461494 -237.404047) (xy 128.42479 -237.439302) (xy 128.382906 -237.468212) (xy 128.336927 -237.490029)
			(xy 128.288043 -237.504189) (xy 128.237522 -237.510323) (xy 128.18667 -237.508274) (xy 128.136806 -237.498094)
			(xy 128.08922 -237.480047) (xy 128.045146 -237.454601) (xy 128.005724 -237.422414) (xy 127.971976 -237.38432)
			(xy 127.944775 -237.341306) (xy 127.924827 -237.294486) (xy 127.912648 -237.245072) (xy 127.908553 -237.194344)
			(xy 127.590483 -237.194344) (xy 127.586317 -237.244627) (xy 127.573921 -237.293582) (xy 127.553637 -237.339829)
			(xy 127.526018 -237.382107) (xy 127.491817 -237.419263) (xy 127.451968 -237.450283) (xy 127.407556 -237.474322)
			(xy 127.359794 -237.490723) (xy 127.309984 -237.49904) (xy 127.284734 -237.499652) (xy 127.260576 -237.499187)
			(xy 127.212864 -237.491563) (xy 127.16695 -237.476515) (xy 127.123981 -237.45442) (xy 127.085031 -237.425829)
			(xy 127.051072 -237.391458) (xy 127.022955 -237.352165) (xy 127.001381 -237.308932) (xy 126.99365 -237.286038)
			(xy 126.989672 -237.275156) (xy 126.973791 -237.258319) (xy 126.952133 -237.250157) (xy 126.940564 -237.250732)
			(xy 126.929388 -237.251748) (xy 126.920042 -237.253033) (xy 126.903157 -237.261405) (xy 126.890434 -237.27531)
			(xy 126.883591 -237.292871) (xy 126.88316 -237.302294) (xy 126.88316 -237.334298) (xy 126.882736 -237.344367)
			(xy 126.875018 -237.362969) (xy 126.868174 -237.370366) (xy 126.626112 -237.612428) (xy 126.623408 -237.615281)
			(xy 126.61882 -237.621661) (xy 126.616968 -237.625128) (xy 126.614385 -237.630555) (xy 126.611559 -237.642234)
			(xy 126.61138 -237.648242) (xy 126.61138 -238.00435) (xy 127.438399 -238.00435) (xy 127.442494 -237.953622)
			(xy 127.454673 -237.904208) (xy 127.474621 -237.857388) (xy 127.501822 -237.814374) (xy 127.53557 -237.77628)
			(xy 127.574992 -237.744093) (xy 127.619066 -237.718647) (xy 127.666652 -237.7006) (xy 127.716516 -237.69042)
			(xy 127.767368 -237.688371) (xy 127.817889 -237.694505) (xy 127.866773 -237.708665) (xy 127.912752 -237.730482)
			(xy 127.954636 -237.759392) (xy 127.99134 -237.794647) (xy 128.021913 -237.835333) (xy 128.045564 -237.880396)
			(xy 128.06168 -237.92867) (xy 128.069844 -237.978904) (xy 128.070356 -238.00435) (xy 128.388884 -238.00435)
			(xy 128.392844 -237.955296) (xy 128.404621 -237.907512) (xy 128.423912 -237.862236) (xy 128.450215 -237.82064)
			(xy 128.48285 -237.783803) (xy 128.520971 -237.752678) (xy 128.563592 -237.728071) (xy 128.609608 -237.710619)
			(xy 128.657827 -237.700775) (xy 128.707002 -237.698794) (xy 128.755857 -237.704726) (xy 128.803128 -237.718418)
			(xy 128.84759 -237.739516) (xy 128.888093 -237.767472) (xy 128.923586 -237.801564) (xy 128.953151 -237.840908)
			(xy 128.976022 -237.884485) (xy 128.991606 -237.931166) (xy 128.999501 -237.979743) (xy 128.999996 -238.00435)
			(xy 129.318507 -238.00435) (xy 129.322602 -237.953622) (xy 129.334781 -237.904208) (xy 129.354729 -237.857388)
			(xy 129.38193 -237.814374) (xy 129.415678 -237.77628) (xy 129.4551 -237.744093) (xy 129.499174 -237.718647)
			(xy 129.54676 -237.7006) (xy 129.596624 -237.69042) (xy 129.647476 -237.688371) (xy 129.697997 -237.694505)
			(xy 129.746881 -237.708665) (xy 129.79286 -237.730482) (xy 129.834744 -237.759392) (xy 129.871448 -237.794647)
			(xy 129.902021 -237.835333) (xy 129.925672 -237.880396) (xy 129.941788 -237.92867) (xy 129.949952 -237.978904)
			(xy 129.950464 -238.00435) (xy 130.268992 -238.00435) (xy 130.272952 -237.955296) (xy 130.284729 -237.907512)
			(xy 130.30402 -237.862236) (xy 130.330323 -237.82064) (xy 130.362958 -237.783803) (xy 130.401079 -237.752678)
			(xy 130.4437 -237.728071) (xy 130.489716 -237.710619) (xy 130.537935 -237.700775) (xy 130.58711 -237.698794)
			(xy 130.635965 -237.704726) (xy 130.683236 -237.718418) (xy 130.727698 -237.739516) (xy 130.768201 -237.767472)
			(xy 130.803694 -237.801564) (xy 130.833259 -237.840908) (xy 130.85613 -237.884485) (xy 130.871714 -237.931166)
			(xy 130.879609 -237.979743) (xy 130.880104 -238.00435) (xy 131.198615 -238.00435) (xy 131.20271 -237.953622)
			(xy 131.214889 -237.904208) (xy 131.234837 -237.857388) (xy 131.262038 -237.814374) (xy 131.295786 -237.77628)
			(xy 131.335208 -237.744093) (xy 131.379282 -237.718647) (xy 131.426868 -237.7006) (xy 131.476732 -237.69042)
			(xy 131.527584 -237.688371) (xy 131.578105 -237.694505) (xy 131.626989 -237.708665) (xy 131.672968 -237.730482)
			(xy 131.714852 -237.759392) (xy 131.751556 -237.794647) (xy 131.782129 -237.835333) (xy 131.80578 -237.880396)
			(xy 131.821896 -237.92867) (xy 131.83006 -237.978904) (xy 131.830572 -238.00435) (xy 132.138415 -238.00435)
			(xy 132.14251 -237.953622) (xy 132.154689 -237.904208) (xy 132.174637 -237.857388) (xy 132.201838 -237.814374)
			(xy 132.235586 -237.77628) (xy 132.275008 -237.744093) (xy 132.319082 -237.718647) (xy 132.366668 -237.7006)
			(xy 132.416532 -237.69042) (xy 132.467384 -237.688371) (xy 132.517905 -237.694505) (xy 132.566789 -237.708665)
			(xy 132.612768 -237.730482) (xy 132.654652 -237.759392) (xy 132.691356 -237.794647) (xy 132.721929 -237.835333)
			(xy 132.74558 -237.880396) (xy 132.761696 -237.92867) (xy 132.76986 -237.978904) (xy 132.770372 -238.00435)
			(xy 133.0889 -238.00435) (xy 133.09286 -237.955296) (xy 133.104637 -237.907512) (xy 133.123928 -237.862236)
			(xy 133.150231 -237.82064) (xy 133.182866 -237.783803) (xy 133.220987 -237.752678) (xy 133.263608 -237.728071)
			(xy 133.309624 -237.710619) (xy 133.357843 -237.700775) (xy 133.407018 -237.698794) (xy 133.455873 -237.704726)
			(xy 133.503144 -237.718418) (xy 133.547606 -237.739516) (xy 133.588109 -237.767472) (xy 133.623602 -237.801564)
			(xy 133.653167 -237.840908) (xy 133.676038 -237.884485) (xy 133.691622 -237.931166) (xy 133.699517 -237.979743)
			(xy 133.700012 -238.00435) (xy 134.028954 -238.00435) (xy 134.032914 -237.955296) (xy 134.044691 -237.907512)
			(xy 134.063982 -237.862236) (xy 134.090285 -237.82064) (xy 134.12292 -237.783803) (xy 134.161041 -237.752678)
			(xy 134.203662 -237.728071) (xy 134.249678 -237.710619) (xy 134.297897 -237.700775) (xy 134.347072 -237.698794)
			(xy 134.395927 -237.704726) (xy 134.443198 -237.718418) (xy 134.48766 -237.739516) (xy 134.528163 -237.767472)
			(xy 134.563656 -237.801564) (xy 134.593221 -237.840908) (xy 134.616092 -237.884485) (xy 134.631676 -237.931166)
			(xy 134.639571 -237.979743) (xy 134.640066 -238.00435) (xy 134.969008 -238.00435) (xy 134.972968 -237.955296)
			(xy 134.984745 -237.907512) (xy 135.004036 -237.862236) (xy 135.030339 -237.82064) (xy 135.062974 -237.783803)
			(xy 135.101095 -237.752678) (xy 135.143716 -237.728071) (xy 135.189732 -237.710619) (xy 135.237951 -237.700775)
			(xy 135.287126 -237.698794) (xy 135.335981 -237.704726) (xy 135.383252 -237.718418) (xy 135.427714 -237.739516)
			(xy 135.468217 -237.767472) (xy 135.50371 -237.801564) (xy 135.533275 -237.840908) (xy 135.556146 -237.884485)
			(xy 135.57173 -237.931166) (xy 135.579625 -237.979743) (xy 135.58012 -238.00435) (xy 135.909062 -238.00435)
			(xy 135.913022 -237.955296) (xy 135.924799 -237.907512) (xy 135.94409 -237.862236) (xy 135.970393 -237.82064)
			(xy 136.003028 -237.783803) (xy 136.041149 -237.752678) (xy 136.08377 -237.728071) (xy 136.129786 -237.710619)
			(xy 136.178005 -237.700775) (xy 136.22718 -237.698794) (xy 136.276035 -237.704726) (xy 136.323306 -237.718418)
			(xy 136.367768 -237.739516) (xy 136.408271 -237.767472) (xy 136.443764 -237.801564) (xy 136.473329 -237.840908)
			(xy 136.4962 -237.884485) (xy 136.511784 -237.931166) (xy 136.519679 -237.979743) (xy 136.520174 -238.00435)
			(xy 136.848862 -238.00435) (xy 136.852822 -237.955296) (xy 136.864599 -237.907512) (xy 136.88389 -237.862236)
			(xy 136.910193 -237.82064) (xy 136.942828 -237.783803) (xy 136.980949 -237.752678) (xy 137.02357 -237.728071)
			(xy 137.069586 -237.710619) (xy 137.117805 -237.700775) (xy 137.16698 -237.698794) (xy 137.215835 -237.704726)
			(xy 137.263106 -237.718418) (xy 137.307568 -237.739516) (xy 137.348071 -237.767472) (xy 137.383564 -237.801564)
			(xy 137.413129 -237.840908) (xy 137.436 -237.884485) (xy 137.451584 -237.931166) (xy 137.459479 -237.979743)
			(xy 137.459974 -238.00435) (xy 137.788916 -238.00435) (xy 137.792876 -237.955296) (xy 137.804653 -237.907512)
			(xy 137.823944 -237.862236) (xy 137.850247 -237.82064) (xy 137.882882 -237.783803) (xy 137.921003 -237.752678)
			(xy 137.963624 -237.728071) (xy 138.00964 -237.710619) (xy 138.057859 -237.700775) (xy 138.107034 -237.698794)
			(xy 138.155889 -237.704726) (xy 138.20316 -237.718418) (xy 138.247622 -237.739516) (xy 138.288125 -237.767472)
			(xy 138.323618 -237.801564) (xy 138.353183 -237.840908) (xy 138.376054 -237.884485) (xy 138.391638 -237.931166)
			(xy 138.399533 -237.979743) (xy 138.400028 -238.00435) (xy 138.72897 -238.00435) (xy 138.73293 -237.955296)
			(xy 138.744707 -237.907512) (xy 138.763998 -237.862236) (xy 138.790301 -237.82064) (xy 138.822936 -237.783803)
			(xy 138.861057 -237.752678) (xy 138.903678 -237.728071) (xy 138.949694 -237.710619) (xy 138.997913 -237.700775)
			(xy 139.047088 -237.698794) (xy 139.095943 -237.704726) (xy 139.143214 -237.718418) (xy 139.187676 -237.739516)
			(xy 139.228179 -237.767472) (xy 139.263672 -237.801564) (xy 139.293237 -237.840908) (xy 139.316108 -237.884485)
			(xy 139.331692 -237.931166) (xy 139.339587 -237.979743) (xy 139.340082 -238.00435) (xy 139.339587 -238.028957)
			(xy 139.331692 -238.077534) (xy 139.316108 -238.124215) (xy 139.293237 -238.167792) (xy 139.263672 -238.207136)
			(xy 139.228179 -238.241228) (xy 139.187676 -238.269184) (xy 139.143214 -238.290282) (xy 139.095943 -238.303974)
			(xy 139.047088 -238.309906) (xy 138.997913 -238.307925) (xy 138.949694 -238.298081) (xy 138.903678 -238.280629)
			(xy 138.861057 -238.256022) (xy 138.822936 -238.224897) (xy 138.790301 -238.18806) (xy 138.763998 -238.146464)
			(xy 138.744707 -238.101188) (xy 138.73293 -238.053404) (xy 138.72897 -238.00435) (xy 138.400028 -238.00435)
			(xy 138.399533 -238.028957) (xy 138.391638 -238.077534) (xy 138.376054 -238.124215) (xy 138.353183 -238.167792)
			(xy 138.323618 -238.207136) (xy 138.288125 -238.241228) (xy 138.247622 -238.269184) (xy 138.20316 -238.290282)
			(xy 138.155889 -238.303974) (xy 138.107034 -238.309906) (xy 138.057859 -238.307925) (xy 138.00964 -238.298081)
			(xy 137.963624 -238.280629) (xy 137.921003 -238.256022) (xy 137.882882 -238.224897) (xy 137.850247 -238.18806)
			(xy 137.823944 -238.146464) (xy 137.804653 -238.101188) (xy 137.792876 -238.053404) (xy 137.788916 -238.00435)
			(xy 137.459974 -238.00435) (xy 137.459479 -238.028957) (xy 137.451584 -238.077534) (xy 137.436 -238.124215)
			(xy 137.413129 -238.167792) (xy 137.383564 -238.207136) (xy 137.348071 -238.241228) (xy 137.307568 -238.269184)
			(xy 137.263106 -238.290282) (xy 137.215835 -238.303974) (xy 137.16698 -238.309906) (xy 137.117805 -238.307925)
			(xy 137.069586 -238.298081) (xy 137.02357 -238.280629) (xy 136.980949 -238.256022) (xy 136.942828 -238.224897)
			(xy 136.910193 -238.18806) (xy 136.88389 -238.146464) (xy 136.864599 -238.101188) (xy 136.852822 -238.053404)
			(xy 136.848862 -238.00435) (xy 136.520174 -238.00435) (xy 136.519679 -238.028957) (xy 136.511784 -238.077534)
			(xy 136.4962 -238.124215) (xy 136.473329 -238.167792) (xy 136.443764 -238.207136) (xy 136.408271 -238.241228)
			(xy 136.367768 -238.269184) (xy 136.323306 -238.290282) (xy 136.276035 -238.303974) (xy 136.22718 -238.309906)
			(xy 136.178005 -238.307925) (xy 136.129786 -238.298081) (xy 136.08377 -238.280629) (xy 136.041149 -238.256022)
			(xy 136.003028 -238.224897) (xy 135.970393 -238.18806) (xy 135.94409 -238.146464) (xy 135.924799 -238.101188)
			(xy 135.913022 -238.053404) (xy 135.909062 -238.00435) (xy 135.58012 -238.00435) (xy 135.579625 -238.028957)
			(xy 135.57173 -238.077534) (xy 135.556146 -238.124215) (xy 135.533275 -238.167792) (xy 135.50371 -238.207136)
			(xy 135.468217 -238.241228) (xy 135.427714 -238.269184) (xy 135.383252 -238.290282) (xy 135.335981 -238.303974)
			(xy 135.287126 -238.309906) (xy 135.237951 -238.307925) (xy 135.189732 -238.298081) (xy 135.143716 -238.280629)
			(xy 135.101095 -238.256022) (xy 135.062974 -238.224897) (xy 135.030339 -238.18806) (xy 135.004036 -238.146464)
			(xy 134.984745 -238.101188) (xy 134.972968 -238.053404) (xy 134.969008 -238.00435) (xy 134.640066 -238.00435)
			(xy 134.639571 -238.028957) (xy 134.631676 -238.077534) (xy 134.616092 -238.124215) (xy 134.593221 -238.167792)
			(xy 134.563656 -238.207136) (xy 134.528163 -238.241228) (xy 134.48766 -238.269184) (xy 134.443198 -238.290282)
			(xy 134.395927 -238.303974) (xy 134.347072 -238.309906) (xy 134.297897 -238.307925) (xy 134.249678 -238.298081)
			(xy 134.203662 -238.280629) (xy 134.161041 -238.256022) (xy 134.12292 -238.224897) (xy 134.090285 -238.18806)
			(xy 134.063982 -238.146464) (xy 134.044691 -238.101188) (xy 134.032914 -238.053404) (xy 134.028954 -238.00435)
			(xy 133.700012 -238.00435) (xy 133.699517 -238.028957) (xy 133.691622 -238.077534) (xy 133.676038 -238.124215)
			(xy 133.653167 -238.167792) (xy 133.623602 -238.207136) (xy 133.588109 -238.241228) (xy 133.547606 -238.269184)
			(xy 133.503144 -238.290282) (xy 133.455873 -238.303974) (xy 133.407018 -238.309906) (xy 133.357843 -238.307925)
			(xy 133.309624 -238.298081) (xy 133.263608 -238.280629) (xy 133.220987 -238.256022) (xy 133.182866 -238.224897)
			(xy 133.150231 -238.18806) (xy 133.123928 -238.146464) (xy 133.104637 -238.101188) (xy 133.09286 -238.053404)
			(xy 133.0889 -238.00435) (xy 132.770372 -238.00435) (xy 132.76986 -238.029796) (xy 132.761696 -238.08003)
			(xy 132.74558 -238.128304) (xy 132.721929 -238.173367) (xy 132.691356 -238.214053) (xy 132.654652 -238.249308)
			(xy 132.612768 -238.278218) (xy 132.566789 -238.300035) (xy 132.517905 -238.314195) (xy 132.467384 -238.320329)
			(xy 132.416532 -238.31828) (xy 132.366668 -238.3081) (xy 132.319082 -238.290053) (xy 132.275008 -238.264607)
			(xy 132.235586 -238.23242) (xy 132.201838 -238.194326) (xy 132.174637 -238.151312) (xy 132.154689 -238.104492)
			(xy 132.14251 -238.055078) (xy 132.138415 -238.00435) (xy 131.830572 -238.00435) (xy 131.83006 -238.029796)
			(xy 131.821896 -238.08003) (xy 131.80578 -238.128304) (xy 131.782129 -238.173367) (xy 131.751556 -238.214053)
			(xy 131.714852 -238.249308) (xy 131.672968 -238.278218) (xy 131.626989 -238.300035) (xy 131.578105 -238.314195)
			(xy 131.527584 -238.320329) (xy 131.476732 -238.31828) (xy 131.426868 -238.3081) (xy 131.379282 -238.290053)
			(xy 131.335208 -238.264607) (xy 131.295786 -238.23242) (xy 131.262038 -238.194326) (xy 131.234837 -238.151312)
			(xy 131.214889 -238.104492) (xy 131.20271 -238.055078) (xy 131.198615 -238.00435) (xy 130.880104 -238.00435)
			(xy 130.879609 -238.028957) (xy 130.871714 -238.077534) (xy 130.85613 -238.124215) (xy 130.833259 -238.167792)
			(xy 130.803694 -238.207136) (xy 130.768201 -238.241228) (xy 130.727698 -238.269184) (xy 130.683236 -238.290282)
			(xy 130.635965 -238.303974) (xy 130.58711 -238.309906) (xy 130.537935 -238.307925) (xy 130.489716 -238.298081)
			(xy 130.4437 -238.280629) (xy 130.401079 -238.256022) (xy 130.362958 -238.224897) (xy 130.330323 -238.18806)
			(xy 130.30402 -238.146464) (xy 130.284729 -238.101188) (xy 130.272952 -238.053404) (xy 130.268992 -238.00435)
			(xy 129.950464 -238.00435) (xy 129.949952 -238.029796) (xy 129.941788 -238.08003) (xy 129.925672 -238.128304)
			(xy 129.902021 -238.173367) (xy 129.871448 -238.214053) (xy 129.834744 -238.249308) (xy 129.79286 -238.278218)
			(xy 129.746881 -238.300035) (xy 129.697997 -238.314195) (xy 129.647476 -238.320329) (xy 129.596624 -238.31828)
			(xy 129.54676 -238.3081) (xy 129.499174 -238.290053) (xy 129.4551 -238.264607) (xy 129.415678 -238.23242)
			(xy 129.38193 -238.194326) (xy 129.354729 -238.151312) (xy 129.334781 -238.104492) (xy 129.322602 -238.055078)
			(xy 129.318507 -238.00435) (xy 128.999996 -238.00435) (xy 128.999501 -238.028957) (xy 128.991606 -238.077534)
			(xy 128.976022 -238.124215) (xy 128.953151 -238.167792) (xy 128.923586 -238.207136) (xy 128.888093 -238.241228)
			(xy 128.84759 -238.269184) (xy 128.803128 -238.290282) (xy 128.755857 -238.303974) (xy 128.707002 -238.309906)
			(xy 128.657827 -238.307925) (xy 128.609608 -238.298081) (xy 128.563592 -238.280629) (xy 128.520971 -238.256022)
			(xy 128.48285 -238.224897) (xy 128.450215 -238.18806) (xy 128.423912 -238.146464) (xy 128.404621 -238.101188)
			(xy 128.392844 -238.053404) (xy 128.388884 -238.00435) (xy 128.070356 -238.00435) (xy 128.069844 -238.029796)
			(xy 128.06168 -238.08003) (xy 128.045564 -238.128304) (xy 128.021913 -238.173367) (xy 127.99134 -238.214053)
			(xy 127.954636 -238.249308) (xy 127.912752 -238.278218) (xy 127.866773 -238.300035) (xy 127.817889 -238.314195)
			(xy 127.767368 -238.320329) (xy 127.716516 -238.31828) (xy 127.666652 -238.3081) (xy 127.619066 -238.290053)
			(xy 127.574992 -238.264607) (xy 127.53557 -238.23242) (xy 127.501822 -238.194326) (xy 127.474621 -238.151312)
			(xy 127.454673 -238.104492) (xy 127.442494 -238.055078) (xy 127.438399 -238.00435) (xy 126.61138 -238.00435)
			(xy 126.61138 -238.246158) (xy 126.612396 -238.25581) (xy 126.614017 -238.263058) (xy 126.620847 -238.276238)
			(xy 126.625858 -238.281718) (xy 126.88443 -238.54029) (xy 126.891286 -238.547685) (xy 126.899035 -238.566283)
			(xy 126.899416 -238.576358) (xy 126.899416 -238.692182) (xy 126.899832 -238.702205) (xy 126.9075 -238.720725)
			(xy 126.921673 -238.734899) (xy 126.940193 -238.742567) (xy 126.950216 -238.742982) (xy 126.95047 -238.742982)
			(xy 126.958264 -238.742739) (xy 126.973134 -238.738076) (xy 126.97968 -238.733838) (xy 126.985776 -238.72952)
			(xy 126.995174 -238.717328) (xy 126.997968 -238.709708) (xy 127.006372 -238.687966) (xy 127.028823 -238.647118)
			(xy 127.057221 -238.610157) (xy 127.090907 -238.577941) (xy 127.129097 -238.551219) (xy 127.170906 -238.530612)
			(xy 127.21536 -238.516598) (xy 127.261429 -238.509504) (xy 127.284734 -238.509048) (xy 127.309991 -238.509572)
			(xy 127.359816 -238.517891) (xy 127.407592 -238.534297) (xy 127.452016 -238.558343) (xy 127.491877 -238.589372)
			(xy 127.526088 -238.626539) (xy 127.553715 -238.668829) (xy 127.574005 -238.715089) (xy 127.586404 -238.764058)
			(xy 127.590572 -238.814356) (xy 127.908553 -238.814356) (xy 127.912648 -238.763628) (xy 127.924827 -238.714214)
			(xy 127.944775 -238.667394) (xy 127.971976 -238.62438) (xy 128.005724 -238.586286) (xy 128.045146 -238.554099)
			(xy 128.08922 -238.528653) (xy 128.136806 -238.510606) (xy 128.18667 -238.500426) (xy 128.237522 -238.498377)
			(xy 128.288043 -238.504511) (xy 128.336927 -238.518671) (xy 128.382906 -238.540488) (xy 128.42479 -238.569398)
			(xy 128.461494 -238.604653) (xy 128.492067 -238.645339) (xy 128.515718 -238.690402) (xy 128.531834 -238.738676)
			(xy 128.539998 -238.78891) (xy 128.54051 -238.814356) (xy 128.848607 -238.814356) (xy 128.852702 -238.763628)
			(xy 128.864881 -238.714214) (xy 128.884829 -238.667394) (xy 128.91203 -238.62438) (xy 128.945778 -238.586286)
			(xy 128.9852 -238.554099) (xy 129.029274 -238.528653) (xy 129.07686 -238.510606) (xy 129.126724 -238.500426)
			(xy 129.177576 -238.498377) (xy 129.228097 -238.504511) (xy 129.276981 -238.518671) (xy 129.32296 -238.540488)
			(xy 129.364844 -238.569398) (xy 129.401548 -238.604653) (xy 129.432121 -238.645339) (xy 129.455772 -238.690402)
			(xy 129.471888 -238.738676) (xy 129.480052 -238.78891) (xy 129.480564 -238.814356) (xy 129.798838 -238.814356)
			(xy 129.802798 -238.765302) (xy 129.814575 -238.717518) (xy 129.833866 -238.672242) (xy 129.860169 -238.630646)
			(xy 129.892804 -238.593809) (xy 129.930925 -238.562684) (xy 129.973546 -238.538077) (xy 130.019562 -238.520625)
			(xy 130.067781 -238.510781) (xy 130.116956 -238.5088) (xy 130.165811 -238.514732) (xy 130.213082 -238.528424)
			(xy 130.257544 -238.549522) (xy 130.298047 -238.577478) (xy 130.33354 -238.61157) (xy 130.363105 -238.650914)
			(xy 130.385976 -238.694491) (xy 130.40156 -238.741172) (xy 130.409455 -238.789749) (xy 130.40995 -238.814356)
			(xy 130.728461 -238.814356) (xy 130.732556 -238.763628) (xy 130.744735 -238.714214) (xy 130.764683 -238.667394)
			(xy 130.791884 -238.62438) (xy 130.825632 -238.586286) (xy 130.865054 -238.554099) (xy 130.909128 -238.528653)
			(xy 130.956714 -238.510606) (xy 131.006578 -238.500426) (xy 131.05743 -238.498377) (xy 131.107951 -238.504511)
			(xy 131.156835 -238.518671) (xy 131.202814 -238.540488) (xy 131.244698 -238.569398) (xy 131.281402 -238.604653)
			(xy 131.311975 -238.645339) (xy 131.335626 -238.690402) (xy 131.351742 -238.738676) (xy 131.359906 -238.78891)
			(xy 131.360418 -238.814356) (xy 131.678946 -238.814356) (xy 131.682906 -238.765302) (xy 131.694683 -238.717518)
			(xy 131.713974 -238.672242) (xy 131.740277 -238.630646) (xy 131.772912 -238.593809) (xy 131.811033 -238.562684)
			(xy 131.853654 -238.538077) (xy 131.89967 -238.520625) (xy 131.947889 -238.510781) (xy 131.997064 -238.5088)
			(xy 132.045919 -238.514732) (xy 132.09319 -238.528424) (xy 132.137652 -238.549522) (xy 132.178155 -238.577478)
			(xy 132.213648 -238.61157) (xy 132.243213 -238.650914) (xy 132.266084 -238.694491) (xy 132.281668 -238.741172)
			(xy 132.289563 -238.789749) (xy 132.290058 -238.814356) (xy 132.608569 -238.814356) (xy 132.612664 -238.763628)
			(xy 132.624843 -238.714214) (xy 132.644791 -238.667394) (xy 132.671992 -238.62438) (xy 132.70574 -238.586286)
			(xy 132.745162 -238.554099) (xy 132.789236 -238.528653) (xy 132.836822 -238.510606) (xy 132.886686 -238.500426)
			(xy 132.937538 -238.498377) (xy 132.988059 -238.504511) (xy 133.036943 -238.518671) (xy 133.082922 -238.540488)
			(xy 133.124806 -238.569398) (xy 133.16151 -238.604653) (xy 133.192083 -238.645339) (xy 133.215734 -238.690402)
			(xy 133.23185 -238.738676) (xy 133.240014 -238.78891) (xy 133.240526 -238.814356) (xy 133.559054 -238.814356)
			(xy 133.563014 -238.765302) (xy 133.574791 -238.717518) (xy 133.594082 -238.672242) (xy 133.620385 -238.630646)
			(xy 133.65302 -238.593809) (xy 133.691141 -238.562684) (xy 133.733762 -238.538077) (xy 133.779778 -238.520625)
			(xy 133.827997 -238.510781) (xy 133.877172 -238.5088) (xy 133.926027 -238.514732) (xy 133.973298 -238.528424)
			(xy 134.01776 -238.549522) (xy 134.058263 -238.577478) (xy 134.093756 -238.61157) (xy 134.123321 -238.650914)
			(xy 134.146192 -238.694491) (xy 134.161776 -238.741172) (xy 134.169671 -238.789749) (xy 134.170166 -238.814356)
			(xy 134.498854 -238.814356) (xy 134.502814 -238.765302) (xy 134.514591 -238.717518) (xy 134.533882 -238.672242)
			(xy 134.560185 -238.630646) (xy 134.59282 -238.593809) (xy 134.630941 -238.562684) (xy 134.673562 -238.538077)
			(xy 134.719578 -238.520625) (xy 134.767797 -238.510781) (xy 134.816972 -238.5088) (xy 134.865827 -238.514732)
			(xy 134.913098 -238.528424) (xy 134.95756 -238.549522) (xy 134.998063 -238.577478) (xy 135.033556 -238.61157)
			(xy 135.063121 -238.650914) (xy 135.085992 -238.694491) (xy 135.101576 -238.741172) (xy 135.109471 -238.789749)
			(xy 135.109966 -238.814356) (xy 135.438908 -238.814356) (xy 135.442868 -238.765302) (xy 135.454645 -238.717518)
			(xy 135.473936 -238.672242) (xy 135.500239 -238.630646) (xy 135.532874 -238.593809) (xy 135.570995 -238.562684)
			(xy 135.613616 -238.538077) (xy 135.659632 -238.520625) (xy 135.707851 -238.510781) (xy 135.757026 -238.5088)
			(xy 135.805881 -238.514732) (xy 135.853152 -238.528424) (xy 135.897614 -238.549522) (xy 135.938117 -238.577478)
			(xy 135.97361 -238.61157) (xy 136.003175 -238.650914) (xy 136.026046 -238.694491) (xy 136.04163 -238.741172)
			(xy 136.049525 -238.789749) (xy 136.05002 -238.814356) (xy 136.378962 -238.814356) (xy 136.382922 -238.765302)
			(xy 136.394699 -238.717518) (xy 136.41399 -238.672242) (xy 136.440293 -238.630646) (xy 136.472928 -238.593809)
			(xy 136.511049 -238.562684) (xy 136.55367 -238.538077) (xy 136.599686 -238.520625) (xy 136.647905 -238.510781)
			(xy 136.69708 -238.5088) (xy 136.745935 -238.514732) (xy 136.793206 -238.528424) (xy 136.837668 -238.549522)
			(xy 136.878171 -238.577478) (xy 136.913664 -238.61157) (xy 136.943229 -238.650914) (xy 136.9661 -238.694491)
			(xy 136.981684 -238.741172) (xy 136.989579 -238.789749) (xy 136.990074 -238.814356) (xy 137.319016 -238.814356)
			(xy 137.322976 -238.765302) (xy 137.334753 -238.717518) (xy 137.354044 -238.672242) (xy 137.380347 -238.630646)
			(xy 137.412982 -238.593809) (xy 137.451103 -238.562684) (xy 137.493724 -238.538077) (xy 137.53974 -238.520625)
			(xy 137.587959 -238.510781) (xy 137.637134 -238.5088) (xy 137.685989 -238.514732) (xy 137.73326 -238.528424)
			(xy 137.777722 -238.549522) (xy 137.818225 -238.577478) (xy 137.853718 -238.61157) (xy 137.883283 -238.650914)
			(xy 137.906154 -238.694491) (xy 137.921738 -238.741172) (xy 137.929633 -238.789749) (xy 137.930128 -238.814356)
			(xy 138.25907 -238.814356) (xy 138.26303 -238.765302) (xy 138.274807 -238.717518) (xy 138.294098 -238.672242)
			(xy 138.320401 -238.630646) (xy 138.353036 -238.593809) (xy 138.391157 -238.562684) (xy 138.433778 -238.538077)
			(xy 138.479794 -238.520625) (xy 138.528013 -238.510781) (xy 138.577188 -238.5088) (xy 138.626043 -238.514732)
			(xy 138.673314 -238.528424) (xy 138.717776 -238.549522) (xy 138.758279 -238.577478) (xy 138.793772 -238.61157)
			(xy 138.823337 -238.650914) (xy 138.846208 -238.694491) (xy 138.861792 -238.741172) (xy 138.869687 -238.789749)
			(xy 138.870182 -238.814356) (xy 139.19887 -238.814356) (xy 139.20283 -238.765302) (xy 139.214607 -238.717518)
			(xy 139.233898 -238.672242) (xy 139.260201 -238.630646) (xy 139.292836 -238.593809) (xy 139.330957 -238.562684)
			(xy 139.373578 -238.538077) (xy 139.419594 -238.520625) (xy 139.467813 -238.510781) (xy 139.516988 -238.5088)
			(xy 139.565843 -238.514732) (xy 139.613114 -238.528424) (xy 139.657576 -238.549522) (xy 139.698079 -238.577478)
			(xy 139.733572 -238.61157) (xy 139.763137 -238.650914) (xy 139.786008 -238.694491) (xy 139.801592 -238.741172)
			(xy 139.809487 -238.789749) (xy 139.809982 -238.814356) (xy 139.809487 -238.838963) (xy 139.801592 -238.88754)
			(xy 139.786008 -238.934221) (xy 139.763137 -238.977798) (xy 139.733572 -239.017142) (xy 139.698079 -239.051234)
			(xy 139.657576 -239.07919) (xy 139.613114 -239.100288) (xy 139.565843 -239.11398) (xy 139.516988 -239.119912)
			(xy 139.467813 -239.117931) (xy 139.419594 -239.108087) (xy 139.373578 -239.090635) (xy 139.330957 -239.066028)
			(xy 139.292836 -239.034903) (xy 139.260201 -238.998066) (xy 139.233898 -238.95647) (xy 139.214607 -238.911194)
			(xy 139.20283 -238.86341) (xy 139.19887 -238.814356) (xy 138.870182 -238.814356) (xy 138.869687 -238.838963)
			(xy 138.861792 -238.88754) (xy 138.846208 -238.934221) (xy 138.823337 -238.977798) (xy 138.793772 -239.017142)
			(xy 138.758279 -239.051234) (xy 138.717776 -239.07919) (xy 138.673314 -239.100288) (xy 138.626043 -239.11398)
			(xy 138.577188 -239.119912) (xy 138.528013 -239.117931) (xy 138.479794 -239.108087) (xy 138.433778 -239.090635)
			(xy 138.391157 -239.066028) (xy 138.353036 -239.034903) (xy 138.320401 -238.998066) (xy 138.294098 -238.95647)
			(xy 138.274807 -238.911194) (xy 138.26303 -238.86341) (xy 138.25907 -238.814356) (xy 137.930128 -238.814356)
			(xy 137.929633 -238.838963) (xy 137.921738 -238.88754) (xy 137.906154 -238.934221) (xy 137.883283 -238.977798)
			(xy 137.853718 -239.017142) (xy 137.818225 -239.051234) (xy 137.777722 -239.07919) (xy 137.73326 -239.100288)
			(xy 137.685989 -239.11398) (xy 137.637134 -239.119912) (xy 137.587959 -239.117931) (xy 137.53974 -239.108087)
			(xy 137.493724 -239.090635) (xy 137.451103 -239.066028) (xy 137.412982 -239.034903) (xy 137.380347 -238.998066)
			(xy 137.354044 -238.95647) (xy 137.334753 -238.911194) (xy 137.322976 -238.86341) (xy 137.319016 -238.814356)
			(xy 136.990074 -238.814356) (xy 136.989579 -238.838963) (xy 136.981684 -238.88754) (xy 136.9661 -238.934221)
			(xy 136.943229 -238.977798) (xy 136.913664 -239.017142) (xy 136.878171 -239.051234) (xy 136.837668 -239.07919)
			(xy 136.793206 -239.100288) (xy 136.745935 -239.11398) (xy 136.69708 -239.119912) (xy 136.647905 -239.117931)
			(xy 136.599686 -239.108087) (xy 136.55367 -239.090635) (xy 136.511049 -239.066028) (xy 136.472928 -239.034903)
			(xy 136.440293 -238.998066) (xy 136.41399 -238.95647) (xy 136.394699 -238.911194) (xy 136.382922 -238.86341)
			(xy 136.378962 -238.814356) (xy 136.05002 -238.814356) (xy 136.049525 -238.838963) (xy 136.04163 -238.88754)
			(xy 136.026046 -238.934221) (xy 136.003175 -238.977798) (xy 135.97361 -239.017142) (xy 135.938117 -239.051234)
			(xy 135.897614 -239.07919) (xy 135.853152 -239.100288) (xy 135.805881 -239.11398) (xy 135.757026 -239.119912)
			(xy 135.707851 -239.117931) (xy 135.659632 -239.108087) (xy 135.613616 -239.090635) (xy 135.570995 -239.066028)
			(xy 135.532874 -239.034903) (xy 135.500239 -238.998066) (xy 135.473936 -238.95647) (xy 135.454645 -238.911194)
			(xy 135.442868 -238.86341) (xy 135.438908 -238.814356) (xy 135.109966 -238.814356) (xy 135.109471 -238.838963)
			(xy 135.101576 -238.88754) (xy 135.085992 -238.934221) (xy 135.063121 -238.977798) (xy 135.033556 -239.017142)
			(xy 134.998063 -239.051234) (xy 134.95756 -239.07919) (xy 134.913098 -239.100288) (xy 134.865827 -239.11398)
			(xy 134.816972 -239.119912) (xy 134.767797 -239.117931) (xy 134.719578 -239.108087) (xy 134.673562 -239.090635)
			(xy 134.630941 -239.066028) (xy 134.59282 -239.034903) (xy 134.560185 -238.998066) (xy 134.533882 -238.95647)
			(xy 134.514591 -238.911194) (xy 134.502814 -238.86341) (xy 134.498854 -238.814356) (xy 134.170166 -238.814356)
			(xy 134.169671 -238.838963) (xy 134.161776 -238.88754) (xy 134.146192 -238.934221) (xy 134.123321 -238.977798)
			(xy 134.093756 -239.017142) (xy 134.058263 -239.051234) (xy 134.01776 -239.07919) (xy 133.973298 -239.100288)
			(xy 133.926027 -239.11398) (xy 133.877172 -239.119912) (xy 133.827997 -239.117931) (xy 133.779778 -239.108087)
			(xy 133.733762 -239.090635) (xy 133.691141 -239.066028) (xy 133.65302 -239.034903) (xy 133.620385 -238.998066)
			(xy 133.594082 -238.95647) (xy 133.574791 -238.911194) (xy 133.563014 -238.86341) (xy 133.559054 -238.814356)
			(xy 133.240526 -238.814356) (xy 133.240014 -238.839802) (xy 133.23185 -238.890036) (xy 133.215734 -238.93831)
			(xy 133.192083 -238.983373) (xy 133.16151 -239.024059) (xy 133.124806 -239.059314) (xy 133.082922 -239.088224)
			(xy 133.036943 -239.110041) (xy 132.988059 -239.124201) (xy 132.937538 -239.130335) (xy 132.886686 -239.128286)
			(xy 132.836822 -239.118106) (xy 132.789236 -239.100059) (xy 132.745162 -239.074613) (xy 132.70574 -239.042426)
			(xy 132.671992 -239.004332) (xy 132.644791 -238.961318) (xy 132.624843 -238.914498) (xy 132.612664 -238.865084)
			(xy 132.608569 -238.814356) (xy 132.290058 -238.814356) (xy 132.289563 -238.838963) (xy 132.281668 -238.88754)
			(xy 132.266084 -238.934221) (xy 132.243213 -238.977798) (xy 132.213648 -239.017142) (xy 132.178155 -239.051234)
			(xy 132.137652 -239.07919) (xy 132.09319 -239.100288) (xy 132.045919 -239.11398) (xy 131.997064 -239.119912)
			(xy 131.947889 -239.117931) (xy 131.89967 -239.108087) (xy 131.853654 -239.090635) (xy 131.811033 -239.066028)
			(xy 131.772912 -239.034903) (xy 131.740277 -238.998066) (xy 131.713974 -238.95647) (xy 131.694683 -238.911194)
			(xy 131.682906 -238.86341) (xy 131.678946 -238.814356) (xy 131.360418 -238.814356) (xy 131.359906 -238.839802)
			(xy 131.351742 -238.890036) (xy 131.335626 -238.93831) (xy 131.311975 -238.983373) (xy 131.281402 -239.024059)
			(xy 131.244698 -239.059314) (xy 131.202814 -239.088224) (xy 131.156835 -239.110041) (xy 131.107951 -239.124201)
			(xy 131.05743 -239.130335) (xy 131.006578 -239.128286) (xy 130.956714 -239.118106) (xy 130.909128 -239.100059)
			(xy 130.865054 -239.074613) (xy 130.825632 -239.042426) (xy 130.791884 -239.004332) (xy 130.764683 -238.961318)
			(xy 130.744735 -238.914498) (xy 130.732556 -238.865084) (xy 130.728461 -238.814356) (xy 130.40995 -238.814356)
			(xy 130.409455 -238.838963) (xy 130.40156 -238.88754) (xy 130.385976 -238.934221) (xy 130.363105 -238.977798)
			(xy 130.33354 -239.017142) (xy 130.298047 -239.051234) (xy 130.257544 -239.07919) (xy 130.213082 -239.100288)
			(xy 130.165811 -239.11398) (xy 130.116956 -239.119912) (xy 130.067781 -239.117931) (xy 130.019562 -239.108087)
			(xy 129.973546 -239.090635) (xy 129.930925 -239.066028) (xy 129.892804 -239.034903) (xy 129.860169 -238.998066)
			(xy 129.833866 -238.95647) (xy 129.814575 -238.911194) (xy 129.802798 -238.86341) (xy 129.798838 -238.814356)
			(xy 129.480564 -238.814356) (xy 129.480052 -238.839802) (xy 129.471888 -238.890036) (xy 129.455772 -238.93831)
			(xy 129.432121 -238.983373) (xy 129.401548 -239.024059) (xy 129.364844 -239.059314) (xy 129.32296 -239.088224)
			(xy 129.276981 -239.110041) (xy 129.228097 -239.124201) (xy 129.177576 -239.130335) (xy 129.126724 -239.128286)
			(xy 129.07686 -239.118106) (xy 129.029274 -239.100059) (xy 128.9852 -239.074613) (xy 128.945778 -239.042426)
			(xy 128.91203 -239.004332) (xy 128.884829 -238.961318) (xy 128.864881 -238.914498) (xy 128.852702 -238.865084)
			(xy 128.848607 -238.814356) (xy 128.54051 -238.814356) (xy 128.539998 -238.839802) (xy 128.531834 -238.890036)
			(xy 128.515718 -238.93831) (xy 128.492067 -238.983373) (xy 128.461494 -239.024059) (xy 128.42479 -239.059314)
			(xy 128.382906 -239.088224) (xy 128.336927 -239.110041) (xy 128.288043 -239.124201) (xy 128.237522 -239.130335)
			(xy 128.18667 -239.128286) (xy 128.136806 -239.118106) (xy 128.08922 -239.100059) (xy 128.045146 -239.074613)
			(xy 128.005724 -239.042426) (xy 127.971976 -239.004332) (xy 127.944775 -238.961318) (xy 127.924827 -238.914498)
			(xy 127.912648 -238.865084) (xy 127.908553 -238.814356) (xy 127.590572 -238.814356) (xy 127.590576 -238.8144)
			(xy 127.586404 -238.864742) (xy 127.574005 -238.913711) (xy 127.553715 -238.959971) (xy 127.526088 -239.002261)
			(xy 127.491877 -239.039428) (xy 127.452016 -239.070457) (xy 127.407592 -239.094503) (xy 127.359816 -239.110909)
			(xy 127.309991 -239.119228) (xy 127.284734 -239.119664) (xy 127.271971 -239.119528) (xy 127.246536 -239.11737)
			(xy 127.233934 -239.115346) (xy 127.233934 -239.1156) (xy 127.211262 -239.111345) (xy 127.167448 -239.096921)
			(xy 127.126296 -239.076085) (xy 127.088737 -239.049306) (xy 127.071882 -239.033558) (xy 127.071374 -239.03305)
			(xy 127.065873 -239.028066) (xy 127.052705 -239.021229) (xy 127.045466 -239.019588) (xy 127.038354 -239.018318)
			(xy 127.023876 -239.019842) (xy 126.92761 -239.060482) (xy 126.919652 -239.064867) (xy 126.90724 -239.078121)
			(xy 126.900207 -239.094862) (xy 126.899416 -239.103916) (xy 126.899416 -239.294924) (xy 126.899696 -239.302478)
			(xy 126.904085 -239.316937) (xy 126.908052 -239.323372) (xy 126.91237 -239.329722) (xy 126.9238 -239.338866)
			(xy 126.930912 -239.341914) (xy 126.952991 -239.351476) (xy 126.994072 -239.376518) (xy 127.030719 -239.407691)
			(xy 127.062026 -239.444224) (xy 127.087218 -239.485214) (xy 127.105671 -239.529646) (xy 127.11693 -239.576423)
			(xy 127.120713 -239.624362) (xy 127.438399 -239.624362) (xy 127.442494 -239.573634) (xy 127.454673 -239.52422)
			(xy 127.474621 -239.4774) (xy 127.501822 -239.434386) (xy 127.53557 -239.396292) (xy 127.574992 -239.364105)
			(xy 127.619066 -239.338659) (xy 127.666652 -239.320612) (xy 127.716516 -239.310432) (xy 127.767368 -239.308383)
			(xy 127.817889 -239.314517) (xy 127.866773 -239.328677) (xy 127.912752 -239.350494) (xy 127.954636 -239.379404)
			(xy 127.99134 -239.414659) (xy 128.021913 -239.455345) (xy 128.045564 -239.500408) (xy 128.06168 -239.548682)
			(xy 128.069844 -239.598916) (xy 128.070356 -239.624362) (xy 128.388884 -239.624362) (xy 128.392844 -239.575308)
			(xy 128.404621 -239.527524) (xy 128.423912 -239.482248) (xy 128.450215 -239.440652) (xy 128.48285 -239.403815)
			(xy 128.520971 -239.37269) (xy 128.563592 -239.348083) (xy 128.609608 -239.330631) (xy 128.657827 -239.320787)
			(xy 128.707002 -239.318806) (xy 128.755857 -239.324738) (xy 128.803128 -239.33843) (xy 128.84759 -239.359528)
			(xy 128.888093 -239.387484) (xy 128.923586 -239.421576) (xy 128.953151 -239.46092) (xy 128.976022 -239.504497)
			(xy 128.991606 -239.551178) (xy 128.999501 -239.599755) (xy 128.999996 -239.624362) (xy 129.318507 -239.624362)
			(xy 129.322602 -239.573634) (xy 129.334781 -239.52422) (xy 129.354729 -239.4774) (xy 129.38193 -239.434386)
			(xy 129.415678 -239.396292) (xy 129.4551 -239.364105) (xy 129.499174 -239.338659) (xy 129.54676 -239.320612)
			(xy 129.596624 -239.310432) (xy 129.647476 -239.308383) (xy 129.697997 -239.314517) (xy 129.746881 -239.328677)
			(xy 129.79286 -239.350494) (xy 129.834744 -239.379404) (xy 129.871448 -239.414659) (xy 129.902021 -239.455345)
			(xy 129.925672 -239.500408) (xy 129.941788 -239.548682) (xy 129.949952 -239.598916) (xy 129.950464 -239.624362)
			(xy 131.198615 -239.624362) (xy 131.20271 -239.573634) (xy 131.214889 -239.52422) (xy 131.234837 -239.4774)
			(xy 131.262038 -239.434386) (xy 131.295786 -239.396292) (xy 131.335208 -239.364105) (xy 131.379282 -239.338659)
			(xy 131.426868 -239.320612) (xy 131.476732 -239.310432) (xy 131.527584 -239.308383) (xy 131.578105 -239.314517)
			(xy 131.626989 -239.328677) (xy 131.672968 -239.350494) (xy 131.714852 -239.379404) (xy 131.751556 -239.414659)
			(xy 131.782129 -239.455345) (xy 131.80578 -239.500408) (xy 131.821896 -239.548682) (xy 131.83006 -239.598916)
			(xy 131.830572 -239.624362) (xy 132.138415 -239.624362) (xy 132.14251 -239.573634) (xy 132.154689 -239.52422)
			(xy 132.174637 -239.4774) (xy 132.201838 -239.434386) (xy 132.235586 -239.396292) (xy 132.275008 -239.364105)
			(xy 132.319082 -239.338659) (xy 132.366668 -239.320612) (xy 132.416532 -239.310432) (xy 132.467384 -239.308383)
			(xy 132.517905 -239.314517) (xy 132.566789 -239.328677) (xy 132.612768 -239.350494) (xy 132.654652 -239.379404)
			(xy 132.691356 -239.414659) (xy 132.721929 -239.455345) (xy 132.74558 -239.500408) (xy 132.761696 -239.548682)
			(xy 132.76986 -239.598916) (xy 132.770372 -239.624362) (xy 133.0889 -239.624362) (xy 133.09286 -239.575308)
			(xy 133.104637 -239.527524) (xy 133.123928 -239.482248) (xy 133.150231 -239.440652) (xy 133.182866 -239.403815)
			(xy 133.220987 -239.37269) (xy 133.263608 -239.348083) (xy 133.309624 -239.330631) (xy 133.357843 -239.320787)
			(xy 133.407018 -239.318806) (xy 133.455873 -239.324738) (xy 133.503144 -239.33843) (xy 133.547606 -239.359528)
			(xy 133.588109 -239.387484) (xy 133.623602 -239.421576) (xy 133.653167 -239.46092) (xy 133.676038 -239.504497)
			(xy 133.691622 -239.551178) (xy 133.699517 -239.599755) (xy 133.700012 -239.624362) (xy 134.028954 -239.624362)
			(xy 134.032914 -239.575308) (xy 134.044691 -239.527524) (xy 134.063982 -239.482248) (xy 134.090285 -239.440652)
			(xy 134.12292 -239.403815) (xy 134.161041 -239.37269) (xy 134.203662 -239.348083) (xy 134.249678 -239.330631)
			(xy 134.297897 -239.320787) (xy 134.347072 -239.318806) (xy 134.395927 -239.324738) (xy 134.443198 -239.33843)
			(xy 134.48766 -239.359528) (xy 134.528163 -239.387484) (xy 134.563656 -239.421576) (xy 134.593221 -239.46092)
			(xy 134.616092 -239.504497) (xy 134.631676 -239.551178) (xy 134.639571 -239.599755) (xy 134.640066 -239.624362)
			(xy 134.969008 -239.624362) (xy 134.972968 -239.575308) (xy 134.984745 -239.527524) (xy 135.004036 -239.482248)
			(xy 135.030339 -239.440652) (xy 135.062974 -239.403815) (xy 135.101095 -239.37269) (xy 135.143716 -239.348083)
			(xy 135.189732 -239.330631) (xy 135.237951 -239.320787) (xy 135.287126 -239.318806) (xy 135.335981 -239.324738)
			(xy 135.383252 -239.33843) (xy 135.427714 -239.359528) (xy 135.468217 -239.387484) (xy 135.50371 -239.421576)
			(xy 135.533275 -239.46092) (xy 135.556146 -239.504497) (xy 135.57173 -239.551178) (xy 135.579625 -239.599755)
			(xy 135.58012 -239.624362) (xy 135.909062 -239.624362) (xy 135.913022 -239.575308) (xy 135.924799 -239.527524)
			(xy 135.94409 -239.482248) (xy 135.970393 -239.440652) (xy 136.003028 -239.403815) (xy 136.041149 -239.37269)
			(xy 136.08377 -239.348083) (xy 136.129786 -239.330631) (xy 136.178005 -239.320787) (xy 136.22718 -239.318806)
			(xy 136.276035 -239.324738) (xy 136.323306 -239.33843) (xy 136.367768 -239.359528) (xy 136.408271 -239.387484)
			(xy 136.443764 -239.421576) (xy 136.473329 -239.46092) (xy 136.4962 -239.504497) (xy 136.511784 -239.551178)
			(xy 136.519679 -239.599755) (xy 136.520174 -239.624362) (xy 137.788916 -239.624362) (xy 137.792876 -239.575308)
			(xy 137.804653 -239.527524) (xy 137.823944 -239.482248) (xy 137.850247 -239.440652) (xy 137.882882 -239.403815)
			(xy 137.921003 -239.37269) (xy 137.963624 -239.348083) (xy 138.00964 -239.330631) (xy 138.057859 -239.320787)
			(xy 138.107034 -239.318806) (xy 138.155889 -239.324738) (xy 138.20316 -239.33843) (xy 138.247622 -239.359528)
			(xy 138.288125 -239.387484) (xy 138.323618 -239.421576) (xy 138.353183 -239.46092) (xy 138.376054 -239.504497)
			(xy 138.391638 -239.551178) (xy 138.399533 -239.599755) (xy 138.400028 -239.624362) (xy 138.72897 -239.624362)
			(xy 138.73293 -239.575308) (xy 138.744707 -239.527524) (xy 138.763998 -239.482248) (xy 138.790301 -239.440652)
			(xy 138.822936 -239.403815) (xy 138.861057 -239.37269) (xy 138.903678 -239.348083) (xy 138.949694 -239.330631)
			(xy 138.997913 -239.320787) (xy 139.047088 -239.318806) (xy 139.095943 -239.324738) (xy 139.143214 -239.33843)
			(xy 139.187676 -239.359528) (xy 139.228179 -239.387484) (xy 139.263672 -239.421576) (xy 139.293237 -239.46092)
			(xy 139.316108 -239.504497) (xy 139.331692 -239.551178) (xy 139.339587 -239.599755) (xy 139.340082 -239.624362)
			(xy 139.339587 -239.648969) (xy 139.331692 -239.697546) (xy 139.316108 -239.744227) (xy 139.293237 -239.787804)
			(xy 139.263672 -239.827148) (xy 139.228179 -239.86124) (xy 139.187676 -239.889196) (xy 139.143214 -239.910294)
			(xy 139.095943 -239.923986) (xy 139.047088 -239.929918) (xy 138.997913 -239.927937) (xy 138.949694 -239.918093)
			(xy 138.903678 -239.900641) (xy 138.861057 -239.876034) (xy 138.822936 -239.844909) (xy 138.790301 -239.808072)
			(xy 138.763998 -239.766476) (xy 138.744707 -239.7212) (xy 138.73293 -239.673416) (xy 138.72897 -239.624362)
			(xy 138.400028 -239.624362) (xy 138.399533 -239.648969) (xy 138.391638 -239.697546) (xy 138.376054 -239.744227)
			(xy 138.353183 -239.787804) (xy 138.323618 -239.827148) (xy 138.288125 -239.86124) (xy 138.247622 -239.889196)
			(xy 138.20316 -239.910294) (xy 138.155889 -239.923986) (xy 138.107034 -239.929918) (xy 138.057859 -239.927937)
			(xy 138.00964 -239.918093) (xy 137.963624 -239.900641) (xy 137.921003 -239.876034) (xy 137.882882 -239.844909)
			(xy 137.850247 -239.808072) (xy 137.823944 -239.766476) (xy 137.804653 -239.7212) (xy 137.792876 -239.673416)
			(xy 137.788916 -239.624362) (xy 136.520174 -239.624362) (xy 136.519679 -239.648969) (xy 136.511784 -239.697546)
			(xy 136.4962 -239.744227) (xy 136.473329 -239.787804) (xy 136.443764 -239.827148) (xy 136.408271 -239.86124)
			(xy 136.367768 -239.889196) (xy 136.323306 -239.910294) (xy 136.276035 -239.923986) (xy 136.22718 -239.929918)
			(xy 136.178005 -239.927937) (xy 136.129786 -239.918093) (xy 136.08377 -239.900641) (xy 136.041149 -239.876034)
			(xy 136.003028 -239.844909) (xy 135.970393 -239.808072) (xy 135.94409 -239.766476) (xy 135.924799 -239.7212)
			(xy 135.913022 -239.673416) (xy 135.909062 -239.624362) (xy 135.58012 -239.624362) (xy 135.579625 -239.648969)
			(xy 135.57173 -239.697546) (xy 135.556146 -239.744227) (xy 135.533275 -239.787804) (xy 135.50371 -239.827148)
			(xy 135.468217 -239.86124) (xy 135.427714 -239.889196) (xy 135.383252 -239.910294) (xy 135.335981 -239.923986)
			(xy 135.287126 -239.929918) (xy 135.237951 -239.927937) (xy 135.189732 -239.918093) (xy 135.143716 -239.900641)
			(xy 135.101095 -239.876034) (xy 135.062974 -239.844909) (xy 135.030339 -239.808072) (xy 135.004036 -239.766476)
			(xy 134.984745 -239.7212) (xy 134.972968 -239.673416) (xy 134.969008 -239.624362) (xy 134.640066 -239.624362)
			(xy 134.639571 -239.648969) (xy 134.631676 -239.697546) (xy 134.616092 -239.744227) (xy 134.593221 -239.787804)
			(xy 134.563656 -239.827148) (xy 134.528163 -239.86124) (xy 134.48766 -239.889196) (xy 134.443198 -239.910294)
			(xy 134.395927 -239.923986) (xy 134.347072 -239.929918) (xy 134.297897 -239.927937) (xy 134.249678 -239.918093)
			(xy 134.203662 -239.900641) (xy 134.161041 -239.876034) (xy 134.12292 -239.844909) (xy 134.090285 -239.808072)
			(xy 134.063982 -239.766476) (xy 134.044691 -239.7212) (xy 134.032914 -239.673416) (xy 134.028954 -239.624362)
			(xy 133.700012 -239.624362) (xy 133.699517 -239.648969) (xy 133.691622 -239.697546) (xy 133.676038 -239.744227)
			(xy 133.653167 -239.787804) (xy 133.623602 -239.827148) (xy 133.588109 -239.86124) (xy 133.547606 -239.889196)
			(xy 133.503144 -239.910294) (xy 133.455873 -239.923986) (xy 133.407018 -239.929918) (xy 133.357843 -239.927937)
			(xy 133.309624 -239.918093) (xy 133.263608 -239.900641) (xy 133.220987 -239.876034) (xy 133.182866 -239.844909)
			(xy 133.150231 -239.808072) (xy 133.123928 -239.766476) (xy 133.104637 -239.7212) (xy 133.09286 -239.673416)
			(xy 133.0889 -239.624362) (xy 132.770372 -239.624362) (xy 132.76986 -239.649808) (xy 132.761696 -239.700042)
			(xy 132.74558 -239.748316) (xy 132.721929 -239.793379) (xy 132.691356 -239.834065) (xy 132.654652 -239.86932)
			(xy 132.612768 -239.89823) (xy 132.566789 -239.920047) (xy 132.517905 -239.934207) (xy 132.467384 -239.940341)
			(xy 132.416532 -239.938292) (xy 132.366668 -239.928112) (xy 132.319082 -239.910065) (xy 132.275008 -239.884619)
			(xy 132.235586 -239.852432) (xy 132.201838 -239.814338) (xy 132.174637 -239.771324) (xy 132.154689 -239.724504)
			(xy 132.14251 -239.67509) (xy 132.138415 -239.624362) (xy 131.830572 -239.624362) (xy 131.83006 -239.649808)
			(xy 131.821896 -239.700042) (xy 131.80578 -239.748316) (xy 131.782129 -239.793379) (xy 131.751556 -239.834065)
			(xy 131.714852 -239.86932) (xy 131.672968 -239.89823) (xy 131.626989 -239.920047) (xy 131.578105 -239.934207)
			(xy 131.527584 -239.940341) (xy 131.476732 -239.938292) (xy 131.426868 -239.928112) (xy 131.379282 -239.910065)
			(xy 131.335208 -239.884619) (xy 131.295786 -239.852432) (xy 131.262038 -239.814338) (xy 131.234837 -239.771324)
			(xy 131.214889 -239.724504) (xy 131.20271 -239.67509) (xy 131.198615 -239.624362) (xy 129.950464 -239.624362)
			(xy 129.949952 -239.649808) (xy 129.941788 -239.700042) (xy 129.925672 -239.748316) (xy 129.902021 -239.793379)
			(xy 129.871448 -239.834065) (xy 129.834744 -239.86932) (xy 129.79286 -239.89823) (xy 129.746881 -239.920047)
			(xy 129.697997 -239.934207) (xy 129.647476 -239.940341) (xy 129.596624 -239.938292) (xy 129.54676 -239.928112)
			(xy 129.499174 -239.910065) (xy 129.4551 -239.884619) (xy 129.415678 -239.852432) (xy 129.38193 -239.814338)
			(xy 129.354729 -239.771324) (xy 129.334781 -239.724504) (xy 129.322602 -239.67509) (xy 129.318507 -239.624362)
			(xy 128.999996 -239.624362) (xy 128.999501 -239.648969) (xy 128.991606 -239.697546) (xy 128.976022 -239.744227)
			(xy 128.953151 -239.787804) (xy 128.923586 -239.827148) (xy 128.888093 -239.86124) (xy 128.84759 -239.889196)
			(xy 128.803128 -239.910294) (xy 128.755857 -239.923986) (xy 128.707002 -239.929918) (xy 128.657827 -239.927937)
			(xy 128.609608 -239.918093) (xy 128.563592 -239.900641) (xy 128.520971 -239.876034) (xy 128.48285 -239.844909)
			(xy 128.450215 -239.808072) (xy 128.423912 -239.766476) (xy 128.404621 -239.7212) (xy 128.392844 -239.673416)
			(xy 128.388884 -239.624362) (xy 128.070356 -239.624362) (xy 128.069844 -239.649808) (xy 128.06168 -239.700042)
			(xy 128.045564 -239.748316) (xy 128.021913 -239.793379) (xy 127.99134 -239.834065) (xy 127.954636 -239.86932)
			(xy 127.912752 -239.89823) (xy 127.866773 -239.920047) (xy 127.817889 -239.934207) (xy 127.767368 -239.940341)
			(xy 127.716516 -239.938292) (xy 127.666652 -239.928112) (xy 127.619066 -239.910065) (xy 127.574992 -239.884619)
			(xy 127.53557 -239.852432) (xy 127.501822 -239.814338) (xy 127.474621 -239.771324) (xy 127.454673 -239.724504)
			(xy 127.442494 -239.67509) (xy 127.438399 -239.624362) (xy 127.120713 -239.624362) (xy 127.120715 -239.624386)
			(xy 127.116934 -239.672349) (xy 127.10568 -239.719126) (xy 127.087231 -239.763561) (xy 127.062043 -239.804553)
			(xy 127.03074 -239.841089) (xy 126.994096 -239.872265) (xy 126.953016 -239.897311) (xy 126.930912 -239.90681)
			(xy 126.9238 -239.909858) (xy 126.91237 -239.919002) (xy 126.908052 -239.925352) (xy 126.904022 -239.931758)
			(xy 126.899627 -239.946234) (xy 126.899416 -239.9538) (xy 126.899416 -240.434368) (xy 127.908553 -240.434368)
			(xy 127.912648 -240.38364) (xy 127.924827 -240.334226) (xy 127.944775 -240.287406) (xy 127.971976 -240.244392)
			(xy 128.005724 -240.206298) (xy 128.045146 -240.174111) (xy 128.08922 -240.148665) (xy 128.136806 -240.130618)
			(xy 128.18667 -240.120438) (xy 128.237522 -240.118389) (xy 128.288043 -240.124523) (xy 128.336927 -240.138683)
			(xy 128.382906 -240.1605) (xy 128.42479 -240.18941) (xy 128.461494 -240.224665) (xy 128.492067 -240.265351)
			(xy 128.515718 -240.310414) (xy 128.531834 -240.358688) (xy 128.539998 -240.408922) (xy 128.54051 -240.434368)
			(xy 128.848607 -240.434368) (xy 128.852702 -240.38364) (xy 128.864881 -240.334226) (xy 128.884829 -240.287406)
			(xy 128.91203 -240.244392) (xy 128.945778 -240.206298) (xy 128.9852 -240.174111) (xy 129.029274 -240.148665)
			(xy 129.07686 -240.130618) (xy 129.126724 -240.120438) (xy 129.177576 -240.118389) (xy 129.228097 -240.124523)
			(xy 129.276981 -240.138683) (xy 129.32296 -240.1605) (xy 129.364844 -240.18941) (xy 129.401548 -240.224665)
			(xy 129.432121 -240.265351) (xy 129.455772 -240.310414) (xy 129.471888 -240.358688) (xy 129.480052 -240.408922)
			(xy 129.480564 -240.434368) (xy 129.798838 -240.434368) (xy 129.802798 -240.385314) (xy 129.814575 -240.33753)
			(xy 129.833866 -240.292254) (xy 129.860169 -240.250658) (xy 129.892804 -240.213821) (xy 129.930925 -240.182696)
			(xy 129.973546 -240.158089) (xy 130.019562 -240.140637) (xy 130.067781 -240.130793) (xy 130.116956 -240.128812)
			(xy 130.165811 -240.134744) (xy 130.213082 -240.148436) (xy 130.257544 -240.169534) (xy 130.298047 -240.19749)
			(xy 130.33354 -240.231582) (xy 130.363105 -240.270926) (xy 130.385976 -240.314503) (xy 130.40156 -240.361184)
			(xy 130.409455 -240.409761) (xy 130.40995 -240.434368) (xy 130.728461 -240.434368) (xy 130.732556 -240.38364)
			(xy 130.744735 -240.334226) (xy 130.764683 -240.287406) (xy 130.791884 -240.244392) (xy 130.825632 -240.206298)
			(xy 130.865054 -240.174111) (xy 130.909128 -240.148665) (xy 130.956714 -240.130618) (xy 131.006578 -240.120438)
			(xy 131.05743 -240.118389) (xy 131.107951 -240.124523) (xy 131.156835 -240.138683) (xy 131.202814 -240.1605)
			(xy 131.244698 -240.18941) (xy 131.281402 -240.224665) (xy 131.311975 -240.265351) (xy 131.335626 -240.310414)
			(xy 131.351742 -240.358688) (xy 131.359906 -240.408922) (xy 131.360418 -240.434368) (xy 131.678946 -240.434368)
			(xy 131.682906 -240.385314) (xy 131.694683 -240.33753) (xy 131.713974 -240.292254) (xy 131.740277 -240.250658)
			(xy 131.772912 -240.213821) (xy 131.811033 -240.182696) (xy 131.853654 -240.158089) (xy 131.89967 -240.140637)
			(xy 131.947889 -240.130793) (xy 131.997064 -240.128812) (xy 132.045919 -240.134744) (xy 132.09319 -240.148436)
			(xy 132.137652 -240.169534) (xy 132.178155 -240.19749) (xy 132.213648 -240.231582) (xy 132.243213 -240.270926)
			(xy 132.266084 -240.314503) (xy 132.281668 -240.361184) (xy 132.289563 -240.409761) (xy 132.290058 -240.434368)
			(xy 132.608569 -240.434368) (xy 132.612664 -240.38364) (xy 132.624843 -240.334226) (xy 132.644791 -240.287406)
			(xy 132.671992 -240.244392) (xy 132.70574 -240.206298) (xy 132.745162 -240.174111) (xy 132.789236 -240.148665)
			(xy 132.836822 -240.130618) (xy 132.886686 -240.120438) (xy 132.937538 -240.118389) (xy 132.988059 -240.124523)
			(xy 133.036943 -240.138683) (xy 133.082922 -240.1605) (xy 133.124806 -240.18941) (xy 133.16151 -240.224665)
			(xy 133.192083 -240.265351) (xy 133.215734 -240.310414) (xy 133.23185 -240.358688) (xy 133.240014 -240.408922)
			(xy 133.240526 -240.434368) (xy 133.559054 -240.434368) (xy 133.563014 -240.385314) (xy 133.574791 -240.33753)
			(xy 133.594082 -240.292254) (xy 133.620385 -240.250658) (xy 133.65302 -240.213821) (xy 133.691141 -240.182696)
			(xy 133.733762 -240.158089) (xy 133.779778 -240.140637) (xy 133.827997 -240.130793) (xy 133.877172 -240.128812)
			(xy 133.926027 -240.134744) (xy 133.973298 -240.148436) (xy 134.01776 -240.169534) (xy 134.058263 -240.19749)
			(xy 134.093756 -240.231582) (xy 134.123321 -240.270926) (xy 134.146192 -240.314503) (xy 134.161776 -240.361184)
			(xy 134.169671 -240.409761) (xy 134.170166 -240.434368) (xy 134.498854 -240.434368) (xy 134.502814 -240.385314)
			(xy 134.514591 -240.33753) (xy 134.533882 -240.292254) (xy 134.560185 -240.250658) (xy 134.59282 -240.213821)
			(xy 134.630941 -240.182696) (xy 134.673562 -240.158089) (xy 134.719578 -240.140637) (xy 134.767797 -240.130793)
			(xy 134.816972 -240.128812) (xy 134.865827 -240.134744) (xy 134.913098 -240.148436) (xy 134.95756 -240.169534)
			(xy 134.998063 -240.19749) (xy 135.033556 -240.231582) (xy 135.063121 -240.270926) (xy 135.085992 -240.314503)
			(xy 135.101576 -240.361184) (xy 135.109471 -240.409761) (xy 135.109966 -240.434368) (xy 135.438908 -240.434368)
			(xy 135.442868 -240.385314) (xy 135.454645 -240.33753) (xy 135.473936 -240.292254) (xy 135.500239 -240.250658)
			(xy 135.532874 -240.213821) (xy 135.570995 -240.182696) (xy 135.613616 -240.158089) (xy 135.659632 -240.140637)
			(xy 135.707851 -240.130793) (xy 135.757026 -240.128812) (xy 135.805881 -240.134744) (xy 135.853152 -240.148436)
			(xy 135.897614 -240.169534) (xy 135.938117 -240.19749) (xy 135.97361 -240.231582) (xy 136.003175 -240.270926)
			(xy 136.026046 -240.314503) (xy 136.04163 -240.361184) (xy 136.049525 -240.409761) (xy 136.05002 -240.434368)
			(xy 136.378962 -240.434368) (xy 136.382922 -240.385314) (xy 136.394699 -240.33753) (xy 136.41399 -240.292254)
			(xy 136.440293 -240.250658) (xy 136.472928 -240.213821) (xy 136.511049 -240.182696) (xy 136.55367 -240.158089)
			(xy 136.599686 -240.140637) (xy 136.647905 -240.130793) (xy 136.69708 -240.128812) (xy 136.745935 -240.134744)
			(xy 136.793206 -240.148436) (xy 136.837668 -240.169534) (xy 136.878171 -240.19749) (xy 136.913664 -240.231582)
			(xy 136.943229 -240.270926) (xy 136.9661 -240.314503) (xy 136.981684 -240.361184) (xy 136.989579 -240.409761)
			(xy 136.990074 -240.434368) (xy 137.319016 -240.434368) (xy 137.322976 -240.385314) (xy 137.334753 -240.33753)
			(xy 137.354044 -240.292254) (xy 137.380347 -240.250658) (xy 137.412982 -240.213821) (xy 137.451103 -240.182696)
			(xy 137.493724 -240.158089) (xy 137.53974 -240.140637) (xy 137.587959 -240.130793) (xy 137.637134 -240.128812)
			(xy 137.685989 -240.134744) (xy 137.73326 -240.148436) (xy 137.777722 -240.169534) (xy 137.818225 -240.19749)
			(xy 137.853718 -240.231582) (xy 137.883283 -240.270926) (xy 137.906154 -240.314503) (xy 137.921738 -240.361184)
			(xy 137.929633 -240.409761) (xy 137.930128 -240.434368) (xy 138.25907 -240.434368) (xy 138.26303 -240.385314)
			(xy 138.274807 -240.33753) (xy 138.294098 -240.292254) (xy 138.320401 -240.250658) (xy 138.353036 -240.213821)
			(xy 138.391157 -240.182696) (xy 138.433778 -240.158089) (xy 138.479794 -240.140637) (xy 138.528013 -240.130793)
			(xy 138.577188 -240.128812) (xy 138.626043 -240.134744) (xy 138.673314 -240.148436) (xy 138.717776 -240.169534)
			(xy 138.758279 -240.19749) (xy 138.793772 -240.231582) (xy 138.823337 -240.270926) (xy 138.846208 -240.314503)
			(xy 138.861792 -240.361184) (xy 138.869687 -240.409761) (xy 138.870182 -240.434368) (xy 139.19887 -240.434368)
			(xy 139.20283 -240.385314) (xy 139.214607 -240.33753) (xy 139.233898 -240.292254) (xy 139.260201 -240.250658)
			(xy 139.292836 -240.213821) (xy 139.330957 -240.182696) (xy 139.373578 -240.158089) (xy 139.419594 -240.140637)
			(xy 139.467813 -240.130793) (xy 139.516988 -240.128812) (xy 139.565843 -240.134744) (xy 139.613114 -240.148436)
			(xy 139.657576 -240.169534) (xy 139.698079 -240.19749) (xy 139.733572 -240.231582) (xy 139.763137 -240.270926)
			(xy 139.786008 -240.314503) (xy 139.801592 -240.361184) (xy 139.809487 -240.409761) (xy 139.809982 -240.434368)
			(xy 139.809487 -240.458975) (xy 139.801592 -240.507552) (xy 139.786008 -240.554233) (xy 139.763137 -240.59781)
			(xy 139.733572 -240.637154) (xy 139.698079 -240.671246) (xy 139.657576 -240.699202) (xy 139.613114 -240.7203)
			(xy 139.565843 -240.733992) (xy 139.516988 -240.739924) (xy 139.467813 -240.737943) (xy 139.419594 -240.728099)
			(xy 139.373578 -240.710647) (xy 139.330957 -240.68604) (xy 139.292836 -240.654915) (xy 139.260201 -240.618078)
			(xy 139.233898 -240.576482) (xy 139.214607 -240.531206) (xy 139.20283 -240.483422) (xy 139.19887 -240.434368)
			(xy 138.870182 -240.434368) (xy 138.869687 -240.458975) (xy 138.861792 -240.507552) (xy 138.846208 -240.554233)
			(xy 138.823337 -240.59781) (xy 138.793772 -240.637154) (xy 138.758279 -240.671246) (xy 138.717776 -240.699202)
			(xy 138.673314 -240.7203) (xy 138.626043 -240.733992) (xy 138.577188 -240.739924) (xy 138.528013 -240.737943)
			(xy 138.479794 -240.728099) (xy 138.433778 -240.710647) (xy 138.391157 -240.68604) (xy 138.353036 -240.654915)
			(xy 138.320401 -240.618078) (xy 138.294098 -240.576482) (xy 138.274807 -240.531206) (xy 138.26303 -240.483422)
			(xy 138.25907 -240.434368) (xy 137.930128 -240.434368) (xy 137.929633 -240.458975) (xy 137.921738 -240.507552)
			(xy 137.906154 -240.554233) (xy 137.883283 -240.59781) (xy 137.853718 -240.637154) (xy 137.818225 -240.671246)
			(xy 137.777722 -240.699202) (xy 137.73326 -240.7203) (xy 137.685989 -240.733992) (xy 137.637134 -240.739924)
			(xy 137.587959 -240.737943) (xy 137.53974 -240.728099) (xy 137.493724 -240.710647) (xy 137.451103 -240.68604)
			(xy 137.412982 -240.654915) (xy 137.380347 -240.618078) (xy 137.354044 -240.576482) (xy 137.334753 -240.531206)
			(xy 137.322976 -240.483422) (xy 137.319016 -240.434368) (xy 136.990074 -240.434368) (xy 136.989579 -240.458975)
			(xy 136.981684 -240.507552) (xy 136.9661 -240.554233) (xy 136.943229 -240.59781) (xy 136.913664 -240.637154)
			(xy 136.878171 -240.671246) (xy 136.837668 -240.699202) (xy 136.793206 -240.7203) (xy 136.745935 -240.733992)
			(xy 136.69708 -240.739924) (xy 136.647905 -240.737943) (xy 136.599686 -240.728099) (xy 136.55367 -240.710647)
			(xy 136.511049 -240.68604) (xy 136.472928 -240.654915) (xy 136.440293 -240.618078) (xy 136.41399 -240.576482)
			(xy 136.394699 -240.531206) (xy 136.382922 -240.483422) (xy 136.378962 -240.434368) (xy 136.05002 -240.434368)
			(xy 136.049525 -240.458975) (xy 136.04163 -240.507552) (xy 136.026046 -240.554233) (xy 136.003175 -240.59781)
			(xy 135.97361 -240.637154) (xy 135.938117 -240.671246) (xy 135.897614 -240.699202) (xy 135.853152 -240.7203)
			(xy 135.805881 -240.733992) (xy 135.757026 -240.739924) (xy 135.707851 -240.737943) (xy 135.659632 -240.728099)
			(xy 135.613616 -240.710647) (xy 135.570995 -240.68604) (xy 135.532874 -240.654915) (xy 135.500239 -240.618078)
			(xy 135.473936 -240.576482) (xy 135.454645 -240.531206) (xy 135.442868 -240.483422) (xy 135.438908 -240.434368)
			(xy 135.109966 -240.434368) (xy 135.109471 -240.458975) (xy 135.101576 -240.507552) (xy 135.085992 -240.554233)
			(xy 135.063121 -240.59781) (xy 135.033556 -240.637154) (xy 134.998063 -240.671246) (xy 134.95756 -240.699202)
			(xy 134.913098 -240.7203) (xy 134.865827 -240.733992) (xy 134.816972 -240.739924) (xy 134.767797 -240.737943)
			(xy 134.719578 -240.728099) (xy 134.673562 -240.710647) (xy 134.630941 -240.68604) (xy 134.59282 -240.654915)
			(xy 134.560185 -240.618078) (xy 134.533882 -240.576482) (xy 134.514591 -240.531206) (xy 134.502814 -240.483422)
			(xy 134.498854 -240.434368) (xy 134.170166 -240.434368) (xy 134.169671 -240.458975) (xy 134.161776 -240.507552)
			(xy 134.146192 -240.554233) (xy 134.123321 -240.59781) (xy 134.093756 -240.637154) (xy 134.058263 -240.671246)
			(xy 134.01776 -240.699202) (xy 133.973298 -240.7203) (xy 133.926027 -240.733992) (xy 133.877172 -240.739924)
			(xy 133.827997 -240.737943) (xy 133.779778 -240.728099) (xy 133.733762 -240.710647) (xy 133.691141 -240.68604)
			(xy 133.65302 -240.654915) (xy 133.620385 -240.618078) (xy 133.594082 -240.576482) (xy 133.574791 -240.531206)
			(xy 133.563014 -240.483422) (xy 133.559054 -240.434368) (xy 133.240526 -240.434368) (xy 133.240014 -240.459814)
			(xy 133.23185 -240.510048) (xy 133.215734 -240.558322) (xy 133.192083 -240.603385) (xy 133.16151 -240.644071)
			(xy 133.124806 -240.679326) (xy 133.082922 -240.708236) (xy 133.036943 -240.730053) (xy 132.988059 -240.744213)
			(xy 132.937538 -240.750347) (xy 132.886686 -240.748298) (xy 132.836822 -240.738118) (xy 132.789236 -240.720071)
			(xy 132.745162 -240.694625) (xy 132.70574 -240.662438) (xy 132.671992 -240.624344) (xy 132.644791 -240.58133)
			(xy 132.624843 -240.53451) (xy 132.612664 -240.485096) (xy 132.608569 -240.434368) (xy 132.290058 -240.434368)
			(xy 132.289563 -240.458975) (xy 132.281668 -240.507552) (xy 132.266084 -240.554233) (xy 132.243213 -240.59781)
			(xy 132.213648 -240.637154) (xy 132.178155 -240.671246) (xy 132.137652 -240.699202) (xy 132.09319 -240.7203)
			(xy 132.045919 -240.733992) (xy 131.997064 -240.739924) (xy 131.947889 -240.737943) (xy 131.89967 -240.728099)
			(xy 131.853654 -240.710647) (xy 131.811033 -240.68604) (xy 131.772912 -240.654915) (xy 131.740277 -240.618078)
			(xy 131.713974 -240.576482) (xy 131.694683 -240.531206) (xy 131.682906 -240.483422) (xy 131.678946 -240.434368)
			(xy 131.360418 -240.434368) (xy 131.359906 -240.459814) (xy 131.351742 -240.510048) (xy 131.335626 -240.558322)
			(xy 131.311975 -240.603385) (xy 131.281402 -240.644071) (xy 131.244698 -240.679326) (xy 131.202814 -240.708236)
			(xy 131.156835 -240.730053) (xy 131.107951 -240.744213) (xy 131.05743 -240.750347) (xy 131.006578 -240.748298)
			(xy 130.956714 -240.738118) (xy 130.909128 -240.720071) (xy 130.865054 -240.694625) (xy 130.825632 -240.662438)
			(xy 130.791884 -240.624344) (xy 130.764683 -240.58133) (xy 130.744735 -240.53451) (xy 130.732556 -240.485096)
			(xy 130.728461 -240.434368) (xy 130.40995 -240.434368) (xy 130.409455 -240.458975) (xy 130.40156 -240.507552)
			(xy 130.385976 -240.554233) (xy 130.363105 -240.59781) (xy 130.33354 -240.637154) (xy 130.298047 -240.671246)
			(xy 130.257544 -240.699202) (xy 130.213082 -240.7203) (xy 130.165811 -240.733992) (xy 130.116956 -240.739924)
			(xy 130.067781 -240.737943) (xy 130.019562 -240.728099) (xy 129.973546 -240.710647) (xy 129.930925 -240.68604)
			(xy 129.892804 -240.654915) (xy 129.860169 -240.618078) (xy 129.833866 -240.576482) (xy 129.814575 -240.531206)
			(xy 129.802798 -240.483422) (xy 129.798838 -240.434368) (xy 129.480564 -240.434368) (xy 129.480052 -240.459814)
			(xy 129.471888 -240.510048) (xy 129.455772 -240.558322) (xy 129.432121 -240.603385) (xy 129.401548 -240.644071)
			(xy 129.364844 -240.679326) (xy 129.32296 -240.708236) (xy 129.276981 -240.730053) (xy 129.228097 -240.744213)
			(xy 129.177576 -240.750347) (xy 129.126724 -240.748298) (xy 129.07686 -240.738118) (xy 129.029274 -240.720071)
			(xy 128.9852 -240.694625) (xy 128.945778 -240.662438) (xy 128.91203 -240.624344) (xy 128.884829 -240.58133)
			(xy 128.864881 -240.53451) (xy 128.852702 -240.485096) (xy 128.848607 -240.434368) (xy 128.54051 -240.434368)
			(xy 128.539998 -240.459814) (xy 128.531834 -240.510048) (xy 128.515718 -240.558322) (xy 128.492067 -240.603385)
			(xy 128.461494 -240.644071) (xy 128.42479 -240.679326) (xy 128.382906 -240.708236) (xy 128.336927 -240.730053)
			(xy 128.288043 -240.744213) (xy 128.237522 -240.750347) (xy 128.18667 -240.748298) (xy 128.136806 -240.738118)
			(xy 128.08922 -240.720071) (xy 128.045146 -240.694625) (xy 128.005724 -240.662438) (xy 127.971976 -240.624344)
			(xy 127.944775 -240.58133) (xy 127.924827 -240.53451) (xy 127.912648 -240.485096) (xy 127.908553 -240.434368)
			(xy 126.899416 -240.434368) (xy 126.899416 -240.914936) (xy 126.899697 -240.92249) (xy 126.904089 -240.936947)
			(xy 126.908052 -240.943384) (xy 126.91237 -240.949734) (xy 126.9238 -240.958878) (xy 126.930912 -240.961926)
			(xy 126.95299 -240.971488) (xy 126.994069 -240.996529) (xy 127.030715 -241.027702) (xy 127.06202 -241.064234)
			(xy 127.08721 -241.105223) (xy 127.105662 -241.149654) (xy 127.116919 -241.196429) (xy 127.120703 -241.244374)
			(xy 127.438399 -241.244374) (xy 127.442494 -241.193646) (xy 127.454673 -241.144232) (xy 127.474621 -241.097412)
			(xy 127.501822 -241.054398) (xy 127.53557 -241.016304) (xy 127.574992 -240.984117) (xy 127.619066 -240.958671)
			(xy 127.666652 -240.940624) (xy 127.716516 -240.930444) (xy 127.767368 -240.928395) (xy 127.817889 -240.934529)
			(xy 127.866773 -240.948689) (xy 127.912752 -240.970506) (xy 127.954636 -240.999416) (xy 127.99134 -241.034671)
			(xy 128.021913 -241.075357) (xy 128.045564 -241.12042) (xy 128.06168 -241.168694) (xy 128.069844 -241.218928)
			(xy 128.070356 -241.244374) (xy 128.388884 -241.244374) (xy 128.392844 -241.19532) (xy 128.404621 -241.147536)
			(xy 128.423912 -241.10226) (xy 128.450215 -241.060664) (xy 128.48285 -241.023827) (xy 128.520971 -240.992702)
			(xy 128.563592 -240.968095) (xy 128.609608 -240.950643) (xy 128.657827 -240.940799) (xy 128.707002 -240.938818)
			(xy 128.755857 -240.94475) (xy 128.803128 -240.958442) (xy 128.84759 -240.97954) (xy 128.888093 -241.007496)
			(xy 128.923586 -241.041588) (xy 128.953151 -241.080932) (xy 128.976022 -241.124509) (xy 128.991606 -241.17119)
			(xy 128.999501 -241.219767) (xy 128.999996 -241.244374) (xy 129.318507 -241.244374) (xy 129.322602 -241.193646)
			(xy 129.334781 -241.144232) (xy 129.354729 -241.097412) (xy 129.38193 -241.054398) (xy 129.415678 -241.016304)
			(xy 129.4551 -240.984117) (xy 129.499174 -240.958671) (xy 129.54676 -240.940624) (xy 129.596624 -240.930444)
			(xy 129.647476 -240.928395) (xy 129.697997 -240.934529) (xy 129.746881 -240.948689) (xy 129.79286 -240.970506)
			(xy 129.834744 -240.999416) (xy 129.871448 -241.034671) (xy 129.902021 -241.075357) (xy 129.925672 -241.12042)
			(xy 129.941788 -241.168694) (xy 129.949952 -241.218928) (xy 129.950464 -241.244374) (xy 130.268992 -241.244374)
			(xy 130.272952 -241.19532) (xy 130.284729 -241.147536) (xy 130.30402 -241.10226) (xy 130.330323 -241.060664)
			(xy 130.362958 -241.023827) (xy 130.401079 -240.992702) (xy 130.4437 -240.968095) (xy 130.489716 -240.950643)
			(xy 130.537935 -240.940799) (xy 130.58711 -240.938818) (xy 130.635965 -240.94475) (xy 130.683236 -240.958442)
			(xy 130.727698 -240.97954) (xy 130.768201 -241.007496) (xy 130.803694 -241.041588) (xy 130.833259 -241.080932)
			(xy 130.85613 -241.124509) (xy 130.871714 -241.17119) (xy 130.879609 -241.219767) (xy 130.880104 -241.244374)
			(xy 131.198615 -241.244374) (xy 131.20271 -241.193646) (xy 131.214889 -241.144232) (xy 131.234837 -241.097412)
			(xy 131.262038 -241.054398) (xy 131.295786 -241.016304) (xy 131.335208 -240.984117) (xy 131.379282 -240.958671)
			(xy 131.426868 -240.940624) (xy 131.476732 -240.930444) (xy 131.527584 -240.928395) (xy 131.578105 -240.934529)
			(xy 131.626989 -240.948689) (xy 131.672968 -240.970506) (xy 131.714852 -240.999416) (xy 131.751556 -241.034671)
			(xy 131.782129 -241.075357) (xy 131.80578 -241.12042) (xy 131.821896 -241.168694) (xy 131.83006 -241.218928)
			(xy 131.830572 -241.244374) (xy 132.138415 -241.244374) (xy 132.14251 -241.193646) (xy 132.154689 -241.144232)
			(xy 132.174637 -241.097412) (xy 132.201838 -241.054398) (xy 132.235586 -241.016304) (xy 132.275008 -240.984117)
			(xy 132.319082 -240.958671) (xy 132.366668 -240.940624) (xy 132.416532 -240.930444) (xy 132.467384 -240.928395)
			(xy 132.517905 -240.934529) (xy 132.566789 -240.948689) (xy 132.612768 -240.970506) (xy 132.654652 -240.999416)
			(xy 132.691356 -241.034671) (xy 132.721929 -241.075357) (xy 132.74558 -241.12042) (xy 132.761696 -241.168694)
			(xy 132.76986 -241.218928) (xy 132.770372 -241.244374) (xy 133.0889 -241.244374) (xy 133.09286 -241.19532)
			(xy 133.104637 -241.147536) (xy 133.123928 -241.10226) (xy 133.150231 -241.060664) (xy 133.182866 -241.023827)
			(xy 133.220987 -240.992702) (xy 133.263608 -240.968095) (xy 133.309624 -240.950643) (xy 133.357843 -240.940799)
			(xy 133.407018 -240.938818) (xy 133.455873 -240.94475) (xy 133.503144 -240.958442) (xy 133.547606 -240.97954)
			(xy 133.588109 -241.007496) (xy 133.623602 -241.041588) (xy 133.653167 -241.080932) (xy 133.676038 -241.124509)
			(xy 133.691622 -241.17119) (xy 133.699517 -241.219767) (xy 133.700012 -241.244374) (xy 134.028954 -241.244374)
			(xy 134.032914 -241.19532) (xy 134.044691 -241.147536) (xy 134.063982 -241.10226) (xy 134.090285 -241.060664)
			(xy 134.12292 -241.023827) (xy 134.161041 -240.992702) (xy 134.203662 -240.968095) (xy 134.249678 -240.950643)
			(xy 134.297897 -240.940799) (xy 134.347072 -240.938818) (xy 134.395927 -240.94475) (xy 134.443198 -240.958442)
			(xy 134.48766 -240.97954) (xy 134.528163 -241.007496) (xy 134.563656 -241.041588) (xy 134.593221 -241.080932)
			(xy 134.616092 -241.124509) (xy 134.631676 -241.17119) (xy 134.639571 -241.219767) (xy 134.640066 -241.244374)
			(xy 134.969008 -241.244374) (xy 134.972968 -241.19532) (xy 134.984745 -241.147536) (xy 135.004036 -241.10226)
			(xy 135.030339 -241.060664) (xy 135.062974 -241.023827) (xy 135.101095 -240.992702) (xy 135.143716 -240.968095)
			(xy 135.189732 -240.950643) (xy 135.237951 -240.940799) (xy 135.287126 -240.938818) (xy 135.335981 -240.94475)
			(xy 135.383252 -240.958442) (xy 135.427714 -240.97954) (xy 135.468217 -241.007496) (xy 135.50371 -241.041588)
			(xy 135.533275 -241.080932) (xy 135.556146 -241.124509) (xy 135.57173 -241.17119) (xy 135.579625 -241.219767)
			(xy 135.58012 -241.244374) (xy 135.909062 -241.244374) (xy 135.913022 -241.19532) (xy 135.924799 -241.147536)
			(xy 135.94409 -241.10226) (xy 135.970393 -241.060664) (xy 136.003028 -241.023827) (xy 136.041149 -240.992702)
			(xy 136.08377 -240.968095) (xy 136.129786 -240.950643) (xy 136.178005 -240.940799) (xy 136.22718 -240.938818)
			(xy 136.276035 -240.94475) (xy 136.323306 -240.958442) (xy 136.367768 -240.97954) (xy 136.408271 -241.007496)
			(xy 136.443764 -241.041588) (xy 136.473329 -241.080932) (xy 136.4962 -241.124509) (xy 136.511784 -241.17119)
			(xy 136.519679 -241.219767) (xy 136.520174 -241.244374) (xy 136.848862 -241.244374) (xy 136.852822 -241.19532)
			(xy 136.864599 -241.147536) (xy 136.88389 -241.10226) (xy 136.910193 -241.060664) (xy 136.942828 -241.023827)
			(xy 136.980949 -240.992702) (xy 137.02357 -240.968095) (xy 137.069586 -240.950643) (xy 137.117805 -240.940799)
			(xy 137.16698 -240.938818) (xy 137.215835 -240.94475) (xy 137.263106 -240.958442) (xy 137.307568 -240.97954)
			(xy 137.348071 -241.007496) (xy 137.383564 -241.041588) (xy 137.413129 -241.080932) (xy 137.436 -241.124509)
			(xy 137.451584 -241.17119) (xy 137.459479 -241.219767) (xy 137.459974 -241.244374) (xy 137.788916 -241.244374)
			(xy 137.792876 -241.19532) (xy 137.804653 -241.147536) (xy 137.823944 -241.10226) (xy 137.850247 -241.060664)
			(xy 137.882882 -241.023827) (xy 137.921003 -240.992702) (xy 137.963624 -240.968095) (xy 138.00964 -240.950643)
			(xy 138.057859 -240.940799) (xy 138.107034 -240.938818) (xy 138.155889 -240.94475) (xy 138.20316 -240.958442)
			(xy 138.247622 -240.97954) (xy 138.288125 -241.007496) (xy 138.323618 -241.041588) (xy 138.353183 -241.080932)
			(xy 138.376054 -241.124509) (xy 138.391638 -241.17119) (xy 138.399533 -241.219767) (xy 138.400028 -241.244374)
			(xy 138.72897 -241.244374) (xy 138.73293 -241.19532) (xy 138.744707 -241.147536) (xy 138.763998 -241.10226)
			(xy 138.790301 -241.060664) (xy 138.822936 -241.023827) (xy 138.861057 -240.992702) (xy 138.903678 -240.968095)
			(xy 138.949694 -240.950643) (xy 138.997913 -240.940799) (xy 139.047088 -240.938818) (xy 139.095943 -240.94475)
			(xy 139.143214 -240.958442) (xy 139.187676 -240.97954) (xy 139.228179 -241.007496) (xy 139.263672 -241.041588)
			(xy 139.293237 -241.080932) (xy 139.316108 -241.124509) (xy 139.331692 -241.17119) (xy 139.339587 -241.219767)
			(xy 139.340082 -241.244374) (xy 139.339587 -241.268981) (xy 139.331692 -241.317558) (xy 139.316108 -241.364239)
			(xy 139.293237 -241.407816) (xy 139.263672 -241.44716) (xy 139.228179 -241.481252) (xy 139.187676 -241.509208)
			(xy 139.143214 -241.530306) (xy 139.095943 -241.543998) (xy 139.047088 -241.54993) (xy 138.997913 -241.547949)
			(xy 138.949694 -241.538105) (xy 138.903678 -241.520653) (xy 138.861057 -241.496046) (xy 138.822936 -241.464921)
			(xy 138.790301 -241.428084) (xy 138.763998 -241.386488) (xy 138.744707 -241.341212) (xy 138.73293 -241.293428)
			(xy 138.72897 -241.244374) (xy 138.400028 -241.244374) (xy 138.399533 -241.268981) (xy 138.391638 -241.317558)
			(xy 138.376054 -241.364239) (xy 138.353183 -241.407816) (xy 138.323618 -241.44716) (xy 138.288125 -241.481252)
			(xy 138.247622 -241.509208) (xy 138.20316 -241.530306) (xy 138.155889 -241.543998) (xy 138.107034 -241.54993)
			(xy 138.057859 -241.547949) (xy 138.00964 -241.538105) (xy 137.963624 -241.520653) (xy 137.921003 -241.496046)
			(xy 137.882882 -241.464921) (xy 137.850247 -241.428084) (xy 137.823944 -241.386488) (xy 137.804653 -241.341212)
			(xy 137.792876 -241.293428) (xy 137.788916 -241.244374) (xy 137.459974 -241.244374) (xy 137.459479 -241.268981)
			(xy 137.451584 -241.317558) (xy 137.436 -241.364239) (xy 137.413129 -241.407816) (xy 137.383564 -241.44716)
			(xy 137.348071 -241.481252) (xy 137.307568 -241.509208) (xy 137.263106 -241.530306) (xy 137.215835 -241.543998)
			(xy 137.16698 -241.54993) (xy 137.117805 -241.547949) (xy 137.069586 -241.538105) (xy 137.02357 -241.520653)
			(xy 136.980949 -241.496046) (xy 136.942828 -241.464921) (xy 136.910193 -241.428084) (xy 136.88389 -241.386488)
			(xy 136.864599 -241.341212) (xy 136.852822 -241.293428) (xy 136.848862 -241.244374) (xy 136.520174 -241.244374)
			(xy 136.519679 -241.268981) (xy 136.511784 -241.317558) (xy 136.4962 -241.364239) (xy 136.473329 -241.407816)
			(xy 136.443764 -241.44716) (xy 136.408271 -241.481252) (xy 136.367768 -241.509208) (xy 136.323306 -241.530306)
			(xy 136.276035 -241.543998) (xy 136.22718 -241.54993) (xy 136.178005 -241.547949) (xy 136.129786 -241.538105)
			(xy 136.08377 -241.520653) (xy 136.041149 -241.496046) (xy 136.003028 -241.464921) (xy 135.970393 -241.428084)
			(xy 135.94409 -241.386488) (xy 135.924799 -241.341212) (xy 135.913022 -241.293428) (xy 135.909062 -241.244374)
			(xy 135.58012 -241.244374) (xy 135.579625 -241.268981) (xy 135.57173 -241.317558) (xy 135.556146 -241.364239)
			(xy 135.533275 -241.407816) (xy 135.50371 -241.44716) (xy 135.468217 -241.481252) (xy 135.427714 -241.509208)
			(xy 135.383252 -241.530306) (xy 135.335981 -241.543998) (xy 135.287126 -241.54993) (xy 135.237951 -241.547949)
			(xy 135.189732 -241.538105) (xy 135.143716 -241.520653) (xy 135.101095 -241.496046) (xy 135.062974 -241.464921)
			(xy 135.030339 -241.428084) (xy 135.004036 -241.386488) (xy 134.984745 -241.341212) (xy 134.972968 -241.293428)
			(xy 134.969008 -241.244374) (xy 134.640066 -241.244374) (xy 134.639571 -241.268981) (xy 134.631676 -241.317558)
			(xy 134.616092 -241.364239) (xy 134.593221 -241.407816) (xy 134.563656 -241.44716) (xy 134.528163 -241.481252)
			(xy 134.48766 -241.509208) (xy 134.443198 -241.530306) (xy 134.395927 -241.543998) (xy 134.347072 -241.54993)
			(xy 134.297897 -241.547949) (xy 134.249678 -241.538105) (xy 134.203662 -241.520653) (xy 134.161041 -241.496046)
			(xy 134.12292 -241.464921) (xy 134.090285 -241.428084) (xy 134.063982 -241.386488) (xy 134.044691 -241.341212)
			(xy 134.032914 -241.293428) (xy 134.028954 -241.244374) (xy 133.700012 -241.244374) (xy 133.699517 -241.268981)
			(xy 133.691622 -241.317558) (xy 133.676038 -241.364239) (xy 133.653167 -241.407816) (xy 133.623602 -241.44716)
			(xy 133.588109 -241.481252) (xy 133.547606 -241.509208) (xy 133.503144 -241.530306) (xy 133.455873 -241.543998)
			(xy 133.407018 -241.54993) (xy 133.357843 -241.547949) (xy 133.309624 -241.538105) (xy 133.263608 -241.520653)
			(xy 133.220987 -241.496046) (xy 133.182866 -241.464921) (xy 133.150231 -241.428084) (xy 133.123928 -241.386488)
			(xy 133.104637 -241.341212) (xy 133.09286 -241.293428) (xy 133.0889 -241.244374) (xy 132.770372 -241.244374)
			(xy 132.76986 -241.26982) (xy 132.761696 -241.320054) (xy 132.74558 -241.368328) (xy 132.721929 -241.413391)
			(xy 132.691356 -241.454077) (xy 132.654652 -241.489332) (xy 132.612768 -241.518242) (xy 132.566789 -241.540059)
			(xy 132.517905 -241.554219) (xy 132.467384 -241.560353) (xy 132.416532 -241.558304) (xy 132.366668 -241.548124)
			(xy 132.319082 -241.530077) (xy 132.275008 -241.504631) (xy 132.235586 -241.472444) (xy 132.201838 -241.43435)
			(xy 132.174637 -241.391336) (xy 132.154689 -241.344516) (xy 132.14251 -241.295102) (xy 132.138415 -241.244374)
			(xy 131.830572 -241.244374) (xy 131.83006 -241.26982) (xy 131.821896 -241.320054) (xy 131.80578 -241.368328)
			(xy 131.782129 -241.413391) (xy 131.751556 -241.454077) (xy 131.714852 -241.489332) (xy 131.672968 -241.518242)
			(xy 131.626989 -241.540059) (xy 131.578105 -241.554219) (xy 131.527584 -241.560353) (xy 131.476732 -241.558304)
			(xy 131.426868 -241.548124) (xy 131.379282 -241.530077) (xy 131.335208 -241.504631) (xy 131.295786 -241.472444)
			(xy 131.262038 -241.43435) (xy 131.234837 -241.391336) (xy 131.214889 -241.344516) (xy 131.20271 -241.295102)
			(xy 131.198615 -241.244374) (xy 130.880104 -241.244374) (xy 130.879609 -241.268981) (xy 130.871714 -241.317558)
			(xy 130.85613 -241.364239) (xy 130.833259 -241.407816) (xy 130.803694 -241.44716) (xy 130.768201 -241.481252)
			(xy 130.727698 -241.509208) (xy 130.683236 -241.530306) (xy 130.635965 -241.543998) (xy 130.58711 -241.54993)
			(xy 130.537935 -241.547949) (xy 130.489716 -241.538105) (xy 130.4437 -241.520653) (xy 130.401079 -241.496046)
			(xy 130.362958 -241.464921) (xy 130.330323 -241.428084) (xy 130.30402 -241.386488) (xy 130.284729 -241.341212)
			(xy 130.272952 -241.293428) (xy 130.268992 -241.244374) (xy 129.950464 -241.244374) (xy 129.949952 -241.26982)
			(xy 129.941788 -241.320054) (xy 129.925672 -241.368328) (xy 129.902021 -241.413391) (xy 129.871448 -241.454077)
			(xy 129.834744 -241.489332) (xy 129.79286 -241.518242) (xy 129.746881 -241.540059) (xy 129.697997 -241.554219)
			(xy 129.647476 -241.560353) (xy 129.596624 -241.558304) (xy 129.54676 -241.548124) (xy 129.499174 -241.530077)
			(xy 129.4551 -241.504631) (xy 129.415678 -241.472444) (xy 129.38193 -241.43435) (xy 129.354729 -241.391336)
			(xy 129.334781 -241.344516) (xy 129.322602 -241.295102) (xy 129.318507 -241.244374) (xy 128.999996 -241.244374)
			(xy 128.999501 -241.268981) (xy 128.991606 -241.317558) (xy 128.976022 -241.364239) (xy 128.953151 -241.407816)
			(xy 128.923586 -241.44716) (xy 128.888093 -241.481252) (xy 128.84759 -241.509208) (xy 128.803128 -241.530306)
			(xy 128.755857 -241.543998) (xy 128.707002 -241.54993) (xy 128.657827 -241.547949) (xy 128.609608 -241.538105)
			(xy 128.563592 -241.520653) (xy 128.520971 -241.496046) (xy 128.48285 -241.464921) (xy 128.450215 -241.428084)
			(xy 128.423912 -241.386488) (xy 128.404621 -241.341212) (xy 128.392844 -241.293428) (xy 128.388884 -241.244374)
			(xy 128.070356 -241.244374) (xy 128.069844 -241.26982) (xy 128.06168 -241.320054) (xy 128.045564 -241.368328)
			(xy 128.021913 -241.413391) (xy 127.99134 -241.454077) (xy 127.954636 -241.489332) (xy 127.912752 -241.518242)
			(xy 127.866773 -241.540059) (xy 127.817889 -241.554219) (xy 127.767368 -241.560353) (xy 127.716516 -241.558304)
			(xy 127.666652 -241.548124) (xy 127.619066 -241.530077) (xy 127.574992 -241.504631) (xy 127.53557 -241.472444)
			(xy 127.501822 -241.43435) (xy 127.474621 -241.391336) (xy 127.454673 -241.344516) (xy 127.442494 -241.295102)
			(xy 127.438399 -241.244374) (xy 127.120703 -241.244374) (xy 127.120704 -241.24439) (xy 127.116923 -241.292352)
			(xy 127.105668 -241.339127) (xy 127.087219 -241.38356) (xy 127.062031 -241.42455) (xy 127.030729 -241.461084)
			(xy 126.994085 -241.492259) (xy 126.953007 -241.517303) (xy 126.930912 -241.526822) (xy 126.9238 -241.52987)
			(xy 126.91237 -241.539014) (xy 126.908052 -241.545364) (xy 126.904024 -241.551771) (xy 126.899633 -241.566247)
			(xy 126.899416 -241.573812) (xy 126.899416 -241.762788) (xy 126.899416 -241.76482) (xy 126.900138 -241.773892)
			(xy 126.907154 -241.790671) (xy 126.919605 -241.803927) (xy 126.92761 -241.808254) (xy 127.016764 -241.8461)
			(xy 127.023753 -241.848724) (xy 127.038594 -241.850271) (xy 127.045974 -241.849148) (xy 127.05334 -241.847878)
			(xy 127.06604 -241.84102) (xy 127.071882 -241.835432) (xy 127.089092 -241.819335) (xy 127.12754 -241.792093)
			(xy 127.169713 -241.771074) (xy 127.214612 -241.756775) (xy 127.261174 -241.749534) (xy 127.284734 -241.749072)
			(xy 127.309989 -241.749596) (xy 127.35981 -241.757915) (xy 127.407582 -241.77432) (xy 127.452003 -241.798364)
			(xy 127.49186 -241.82939) (xy 127.526068 -241.866554) (xy 127.553693 -241.90884) (xy 127.573981 -241.955097)
			(xy 127.58638 -242.004062) (xy 127.590549 -242.05438) (xy 127.908553 -242.05438) (xy 127.912648 -242.003652)
			(xy 127.924827 -241.954238) (xy 127.944775 -241.907418) (xy 127.971976 -241.864404) (xy 128.005724 -241.82631)
			(xy 128.045146 -241.794123) (xy 128.08922 -241.768677) (xy 128.136806 -241.75063) (xy 128.18667 -241.74045)
			(xy 128.237522 -241.738401) (xy 128.288043 -241.744535) (xy 128.336927 -241.758695) (xy 128.382906 -241.780512)
			(xy 128.42479 -241.809422) (xy 128.461494 -241.844677) (xy 128.492067 -241.885363) (xy 128.515718 -241.930426)
			(xy 128.531834 -241.9787) (xy 128.539998 -242.028934) (xy 128.54051 -242.05438) (xy 128.848607 -242.05438)
			(xy 128.852702 -242.003652) (xy 128.864881 -241.954238) (xy 128.884829 -241.907418) (xy 128.91203 -241.864404)
			(xy 128.945778 -241.82631) (xy 128.9852 -241.794123) (xy 129.029274 -241.768677) (xy 129.07686 -241.75063)
			(xy 129.126724 -241.74045) (xy 129.177576 -241.738401) (xy 129.228097 -241.744535) (xy 129.276981 -241.758695)
			(xy 129.32296 -241.780512) (xy 129.364844 -241.809422) (xy 129.401548 -241.844677) (xy 129.432121 -241.885363)
			(xy 129.455772 -241.930426) (xy 129.471888 -241.9787) (xy 129.480052 -242.028934) (xy 129.480564 -242.05438)
			(xy 130.728461 -242.05438) (xy 130.732556 -242.003652) (xy 130.744735 -241.954238) (xy 130.764683 -241.907418)
			(xy 130.791884 -241.864404) (xy 130.825632 -241.82631) (xy 130.865054 -241.794123) (xy 130.909128 -241.768677)
			(xy 130.956714 -241.75063) (xy 131.006578 -241.74045) (xy 131.05743 -241.738401) (xy 131.107951 -241.744535)
			(xy 131.156835 -241.758695) (xy 131.202814 -241.780512) (xy 131.244698 -241.809422) (xy 131.281402 -241.844677)
			(xy 131.311975 -241.885363) (xy 131.335626 -241.930426) (xy 131.351742 -241.9787) (xy 131.359906 -242.028934)
			(xy 131.360418 -242.05438) (xy 131.678946 -242.05438) (xy 131.682906 -242.005326) (xy 131.694683 -241.957542)
			(xy 131.713974 -241.912266) (xy 131.740277 -241.87067) (xy 131.772912 -241.833833) (xy 131.811033 -241.802708)
			(xy 131.853654 -241.778101) (xy 131.89967 -241.760649) (xy 131.947889 -241.750805) (xy 131.997064 -241.748824)
			(xy 132.045919 -241.754756) (xy 132.09319 -241.768448) (xy 132.137652 -241.789546) (xy 132.178155 -241.817502)
			(xy 132.213648 -241.851594) (xy 132.243213 -241.890938) (xy 132.266084 -241.934515) (xy 132.281668 -241.981196)
			(xy 132.289563 -242.029773) (xy 132.290058 -242.05438) (xy 132.608569 -242.05438) (xy 132.612664 -242.003652)
			(xy 132.624843 -241.954238) (xy 132.644791 -241.907418) (xy 132.671992 -241.864404) (xy 132.70574 -241.82631)
			(xy 132.745162 -241.794123) (xy 132.789236 -241.768677) (xy 132.836822 -241.75063) (xy 132.886686 -241.74045)
			(xy 132.937538 -241.738401) (xy 132.988059 -241.744535) (xy 133.036943 -241.758695) (xy 133.082922 -241.780512)
			(xy 133.124806 -241.809422) (xy 133.16151 -241.844677) (xy 133.192083 -241.885363) (xy 133.215734 -241.930426)
			(xy 133.23185 -241.9787) (xy 133.240014 -242.028934) (xy 133.240526 -242.05438) (xy 133.559054 -242.05438)
			(xy 133.563014 -242.005326) (xy 133.574791 -241.957542) (xy 133.594082 -241.912266) (xy 133.620385 -241.87067)
			(xy 133.65302 -241.833833) (xy 133.691141 -241.802708) (xy 133.733762 -241.778101) (xy 133.779778 -241.760649)
			(xy 133.827997 -241.750805) (xy 133.877172 -241.748824) (xy 133.926027 -241.754756) (xy 133.973298 -241.768448)
			(xy 134.01776 -241.789546) (xy 134.058263 -241.817502) (xy 134.093756 -241.851594) (xy 134.123321 -241.890938)
			(xy 134.146192 -241.934515) (xy 134.161776 -241.981196) (xy 134.169671 -242.029773) (xy 134.170166 -242.05438)
			(xy 134.498854 -242.05438) (xy 134.502814 -242.005326) (xy 134.514591 -241.957542) (xy 134.533882 -241.912266)
			(xy 134.560185 -241.87067) (xy 134.59282 -241.833833) (xy 134.630941 -241.802708) (xy 134.673562 -241.778101)
			(xy 134.719578 -241.760649) (xy 134.767797 -241.750805) (xy 134.816972 -241.748824) (xy 134.865827 -241.754756)
			(xy 134.913098 -241.768448) (xy 134.95756 -241.789546) (xy 134.998063 -241.817502) (xy 135.033556 -241.851594)
			(xy 135.063121 -241.890938) (xy 135.085992 -241.934515) (xy 135.101576 -241.981196) (xy 135.109471 -242.029773)
			(xy 135.109966 -242.05438) (xy 135.438908 -242.05438) (xy 135.442868 -242.005326) (xy 135.454645 -241.957542)
			(xy 135.473936 -241.912266) (xy 135.500239 -241.87067) (xy 135.532874 -241.833833) (xy 135.570995 -241.802708)
			(xy 135.613616 -241.778101) (xy 135.659632 -241.760649) (xy 135.707851 -241.750805) (xy 135.757026 -241.748824)
			(xy 135.805881 -241.754756) (xy 135.853152 -241.768448) (xy 135.897614 -241.789546) (xy 135.938117 -241.817502)
			(xy 135.97361 -241.851594) (xy 136.003175 -241.890938) (xy 136.026046 -241.934515) (xy 136.04163 -241.981196)
			(xy 136.049525 -242.029773) (xy 136.05002 -242.05438) (xy 137.319016 -242.05438) (xy 137.322976 -242.005326)
			(xy 137.334753 -241.957542) (xy 137.354044 -241.912266) (xy 137.380347 -241.87067) (xy 137.412982 -241.833833)
			(xy 137.451103 -241.802708) (xy 137.493724 -241.778101) (xy 137.53974 -241.760649) (xy 137.587959 -241.750805)
			(xy 137.637134 -241.748824) (xy 137.685989 -241.754756) (xy 137.73326 -241.768448) (xy 137.777722 -241.789546)
			(xy 137.818225 -241.817502) (xy 137.853718 -241.851594) (xy 137.883283 -241.890938) (xy 137.906154 -241.934515)
			(xy 137.921738 -241.981196) (xy 137.929633 -242.029773) (xy 137.930128 -242.05438) (xy 138.25907 -242.05438)
			(xy 138.26303 -242.005326) (xy 138.274807 -241.957542) (xy 138.294098 -241.912266) (xy 138.320401 -241.87067)
			(xy 138.353036 -241.833833) (xy 138.391157 -241.802708) (xy 138.433778 -241.778101) (xy 138.479794 -241.760649)
			(xy 138.528013 -241.750805) (xy 138.577188 -241.748824) (xy 138.626043 -241.754756) (xy 138.673314 -241.768448)
			(xy 138.717776 -241.789546) (xy 138.758279 -241.817502) (xy 138.793772 -241.851594) (xy 138.823337 -241.890938)
			(xy 138.846208 -241.934515) (xy 138.861792 -241.981196) (xy 138.869687 -242.029773) (xy 138.870182 -242.05438)
			(xy 139.19887 -242.05438) (xy 139.20283 -242.005326) (xy 139.214607 -241.957542) (xy 139.233898 -241.912266)
			(xy 139.260201 -241.87067) (xy 139.292836 -241.833833) (xy 139.330957 -241.802708) (xy 139.373578 -241.778101)
			(xy 139.419594 -241.760649) (xy 139.467813 -241.750805) (xy 139.516988 -241.748824) (xy 139.565843 -241.754756)
			(xy 139.613114 -241.768448) (xy 139.657576 -241.789546) (xy 139.698079 -241.817502) (xy 139.733572 -241.851594)
			(xy 139.763137 -241.890938) (xy 139.786008 -241.934515) (xy 139.801592 -241.981196) (xy 139.809487 -242.029773)
			(xy 139.809982 -242.05438) (xy 139.809487 -242.078987) (xy 139.801592 -242.127564) (xy 139.786008 -242.174245)
			(xy 139.763137 -242.217822) (xy 139.733572 -242.257166) (xy 139.698079 -242.291258) (xy 139.657576 -242.319214)
			(xy 139.613114 -242.340312) (xy 139.565843 -242.354004) (xy 139.516988 -242.359936) (xy 139.467813 -242.357955)
			(xy 139.419594 -242.348111) (xy 139.373578 -242.330659) (xy 139.330957 -242.306052) (xy 139.292836 -242.274927)
			(xy 139.260201 -242.23809) (xy 139.233898 -242.196494) (xy 139.214607 -242.151218) (xy 139.20283 -242.103434)
			(xy 139.19887 -242.05438) (xy 138.870182 -242.05438) (xy 138.869687 -242.078987) (xy 138.861792 -242.127564)
			(xy 138.846208 -242.174245) (xy 138.823337 -242.217822) (xy 138.793772 -242.257166) (xy 138.758279 -242.291258)
			(xy 138.717776 -242.319214) (xy 138.673314 -242.340312) (xy 138.626043 -242.354004) (xy 138.577188 -242.359936)
			(xy 138.528013 -242.357955) (xy 138.479794 -242.348111) (xy 138.433778 -242.330659) (xy 138.391157 -242.306052)
			(xy 138.353036 -242.274927) (xy 138.320401 -242.23809) (xy 138.294098 -242.196494) (xy 138.274807 -242.151218)
			(xy 138.26303 -242.103434) (xy 138.25907 -242.05438) (xy 137.930128 -242.05438) (xy 137.929633 -242.078987)
			(xy 137.921738 -242.127564) (xy 137.906154 -242.174245) (xy 137.883283 -242.217822) (xy 137.853718 -242.257166)
			(xy 137.818225 -242.291258) (xy 137.777722 -242.319214) (xy 137.73326 -242.340312) (xy 137.685989 -242.354004)
			(xy 137.637134 -242.359936) (xy 137.587959 -242.357955) (xy 137.53974 -242.348111) (xy 137.493724 -242.330659)
			(xy 137.451103 -242.306052) (xy 137.412982 -242.274927) (xy 137.380347 -242.23809) (xy 137.354044 -242.196494)
			(xy 137.334753 -242.151218) (xy 137.322976 -242.103434) (xy 137.319016 -242.05438) (xy 136.05002 -242.05438)
			(xy 136.049525 -242.078987) (xy 136.04163 -242.127564) (xy 136.026046 -242.174245) (xy 136.003175 -242.217822)
			(xy 135.97361 -242.257166) (xy 135.938117 -242.291258) (xy 135.897614 -242.319214) (xy 135.853152 -242.340312)
			(xy 135.805881 -242.354004) (xy 135.757026 -242.359936) (xy 135.707851 -242.357955) (xy 135.659632 -242.348111)
			(xy 135.613616 -242.330659) (xy 135.570995 -242.306052) (xy 135.532874 -242.274927) (xy 135.500239 -242.23809)
			(xy 135.473936 -242.196494) (xy 135.454645 -242.151218) (xy 135.442868 -242.103434) (xy 135.438908 -242.05438)
			(xy 135.109966 -242.05438) (xy 135.109471 -242.078987) (xy 135.101576 -242.127564) (xy 135.085992 -242.174245)
			(xy 135.063121 -242.217822) (xy 135.033556 -242.257166) (xy 134.998063 -242.291258) (xy 134.95756 -242.319214)
			(xy 134.913098 -242.340312) (xy 134.865827 -242.354004) (xy 134.816972 -242.359936) (xy 134.767797 -242.357955)
			(xy 134.719578 -242.348111) (xy 134.673562 -242.330659) (xy 134.630941 -242.306052) (xy 134.59282 -242.274927)
			(xy 134.560185 -242.23809) (xy 134.533882 -242.196494) (xy 134.514591 -242.151218) (xy 134.502814 -242.103434)
			(xy 134.498854 -242.05438) (xy 134.170166 -242.05438) (xy 134.169671 -242.078987) (xy 134.161776 -242.127564)
			(xy 134.146192 -242.174245) (xy 134.123321 -242.217822) (xy 134.093756 -242.257166) (xy 134.058263 -242.291258)
			(xy 134.01776 -242.319214) (xy 133.973298 -242.340312) (xy 133.926027 -242.354004) (xy 133.877172 -242.359936)
			(xy 133.827997 -242.357955) (xy 133.779778 -242.348111) (xy 133.733762 -242.330659) (xy 133.691141 -242.306052)
			(xy 133.65302 -242.274927) (xy 133.620385 -242.23809) (xy 133.594082 -242.196494) (xy 133.574791 -242.151218)
			(xy 133.563014 -242.103434) (xy 133.559054 -242.05438) (xy 133.240526 -242.05438) (xy 133.240014 -242.079826)
			(xy 133.23185 -242.13006) (xy 133.215734 -242.178334) (xy 133.192083 -242.223397) (xy 133.16151 -242.264083)
			(xy 133.124806 -242.299338) (xy 133.082922 -242.328248) (xy 133.036943 -242.350065) (xy 132.988059 -242.364225)
			(xy 132.937538 -242.370359) (xy 132.886686 -242.36831) (xy 132.836822 -242.35813) (xy 132.789236 -242.340083)
			(xy 132.745162 -242.314637) (xy 132.70574 -242.28245) (xy 132.671992 -242.244356) (xy 132.644791 -242.201342)
			(xy 132.624843 -242.154522) (xy 132.612664 -242.105108) (xy 132.608569 -242.05438) (xy 132.290058 -242.05438)
			(xy 132.289563 -242.078987) (xy 132.281668 -242.127564) (xy 132.266084 -242.174245) (xy 132.243213 -242.217822)
			(xy 132.213648 -242.257166) (xy 132.178155 -242.291258) (xy 132.137652 -242.319214) (xy 132.09319 -242.340312)
			(xy 132.045919 -242.354004) (xy 131.997064 -242.359936) (xy 131.947889 -242.357955) (xy 131.89967 -242.348111)
			(xy 131.853654 -242.330659) (xy 131.811033 -242.306052) (xy 131.772912 -242.274927) (xy 131.740277 -242.23809)
			(xy 131.713974 -242.196494) (xy 131.694683 -242.151218) (xy 131.682906 -242.103434) (xy 131.678946 -242.05438)
			(xy 131.360418 -242.05438) (xy 131.359906 -242.079826) (xy 131.351742 -242.13006) (xy 131.335626 -242.178334)
			(xy 131.311975 -242.223397) (xy 131.281402 -242.264083) (xy 131.244698 -242.299338) (xy 131.202814 -242.328248)
			(xy 131.156835 -242.350065) (xy 131.107951 -242.364225) (xy 131.05743 -242.370359) (xy 131.006578 -242.36831)
			(xy 130.956714 -242.35813) (xy 130.909128 -242.340083) (xy 130.865054 -242.314637) (xy 130.825632 -242.28245)
			(xy 130.791884 -242.244356) (xy 130.764683 -242.201342) (xy 130.744735 -242.154522) (xy 130.732556 -242.105108)
			(xy 130.728461 -242.05438) (xy 129.480564 -242.05438) (xy 129.480052 -242.079826) (xy 129.471888 -242.13006)
			(xy 129.455772 -242.178334) (xy 129.432121 -242.223397) (xy 129.401548 -242.264083) (xy 129.364844 -242.299338)
			(xy 129.32296 -242.328248) (xy 129.276981 -242.350065) (xy 129.228097 -242.364225) (xy 129.177576 -242.370359)
			(xy 129.126724 -242.36831) (xy 129.07686 -242.35813) (xy 129.029274 -242.340083) (xy 128.9852 -242.314637)
			(xy 128.945778 -242.28245) (xy 128.91203 -242.244356) (xy 128.884829 -242.201342) (xy 128.864881 -242.154522)
			(xy 128.852702 -242.105108) (xy 128.848607 -242.05438) (xy 128.54051 -242.05438) (xy 128.539998 -242.079826)
			(xy 128.531834 -242.13006) (xy 128.515718 -242.178334) (xy 128.492067 -242.223397) (xy 128.461494 -242.264083)
			(xy 128.42479 -242.299338) (xy 128.382906 -242.328248) (xy 128.336927 -242.350065) (xy 128.288043 -242.364225)
			(xy 128.237522 -242.370359) (xy 128.18667 -242.36831) (xy 128.136806 -242.35813) (xy 128.08922 -242.340083)
			(xy 128.045146 -242.314637) (xy 128.005724 -242.28245) (xy 127.971976 -242.244356) (xy 127.944775 -242.201342)
			(xy 127.924827 -242.154522) (xy 127.912648 -242.105108) (xy 127.908553 -242.05438) (xy 127.590549 -242.05438)
			(xy 127.590551 -242.0544) (xy 127.58638 -242.104738) (xy 127.573981 -242.153703) (xy 127.553693 -242.19996)
			(xy 127.526068 -242.242246) (xy 127.49186 -242.27941) (xy 127.452003 -242.310436) (xy 127.407582 -242.33448)
			(xy 127.35981 -242.350885) (xy 127.309989 -242.359204) (xy 127.284734 -242.359688) (xy 127.271971 -242.359552)
			(xy 127.246536 -242.357393) (xy 127.233934 -242.35537) (xy 127.233934 -242.355624) (xy 127.211262 -242.35137)
			(xy 127.167447 -242.336947) (xy 127.126294 -242.316111) (xy 127.088733 -242.289335) (xy 127.071882 -242.273582)
			(xy 127.071374 -242.273074) (xy 127.065874 -242.268088) (xy 127.052707 -242.261248) (xy 127.045466 -242.259612)
			(xy 127.038354 -242.258342) (xy 127.023876 -242.259866) (xy 126.92761 -242.300506) (xy 126.919644 -242.304888)
			(xy 126.907213 -242.318138) (xy 126.900156 -242.33488) (xy 126.899416 -242.34394) (xy 126.899416 -242.534948)
			(xy 126.899699 -242.542501) (xy 126.904094 -242.556956) (xy 126.908052 -242.563396) (xy 126.91237 -242.569746)
			(xy 126.9238 -242.57889) (xy 126.930912 -242.581938) (xy 126.952989 -242.5915) (xy 126.994067 -242.616541)
			(xy 127.03071 -242.647713) (xy 127.062014 -242.684244) (xy 127.087202 -242.725232) (xy 127.105653 -242.769662)
			(xy 127.116909 -242.816435) (xy 127.120692 -242.864386) (xy 127.438399 -242.864386) (xy 127.442494 -242.813658)
			(xy 127.454673 -242.764244) (xy 127.474621 -242.717424) (xy 127.501822 -242.67441) (xy 127.53557 -242.636316)
			(xy 127.574992 -242.604129) (xy 127.619066 -242.578683) (xy 127.666652 -242.560636) (xy 127.716516 -242.550456)
			(xy 127.767368 -242.548407) (xy 127.817889 -242.554541) (xy 127.866773 -242.568701) (xy 127.912752 -242.590518)
			(xy 127.954636 -242.619428) (xy 127.99134 -242.654683) (xy 128.021913 -242.695369) (xy 128.045564 -242.740432)
			(xy 128.06168 -242.788706) (xy 128.069844 -242.83894) (xy 128.070356 -242.864386) (xy 128.388884 -242.864386)
			(xy 128.392844 -242.815332) (xy 128.404621 -242.767548) (xy 128.423912 -242.722272) (xy 128.450215 -242.680676)
			(xy 128.48285 -242.643839) (xy 128.520971 -242.612714) (xy 128.563592 -242.588107) (xy 128.609608 -242.570655)
			(xy 128.657827 -242.560811) (xy 128.707002 -242.55883) (xy 128.755857 -242.564762) (xy 128.803128 -242.578454)
			(xy 128.84759 -242.599552) (xy 128.888093 -242.627508) (xy 128.923586 -242.6616) (xy 128.953151 -242.700944)
			(xy 128.976022 -242.744521) (xy 128.991606 -242.791202) (xy 128.999501 -242.839779) (xy 128.999996 -242.864386)
			(xy 129.318507 -242.864386) (xy 129.322602 -242.813658) (xy 129.334781 -242.764244) (xy 129.354729 -242.717424)
			(xy 129.38193 -242.67441) (xy 129.415678 -242.636316) (xy 129.4551 -242.604129) (xy 129.499174 -242.578683)
			(xy 129.54676 -242.560636) (xy 129.596624 -242.550456) (xy 129.647476 -242.548407) (xy 129.697997 -242.554541)
			(xy 129.746881 -242.568701) (xy 129.79286 -242.590518) (xy 129.834744 -242.619428) (xy 129.871448 -242.654683)
			(xy 129.902021 -242.695369) (xy 129.925672 -242.740432) (xy 129.941788 -242.788706) (xy 129.949952 -242.83894)
			(xy 129.950464 -242.864386) (xy 130.268992 -242.864386) (xy 130.272952 -242.815332) (xy 130.284729 -242.767548)
			(xy 130.30402 -242.722272) (xy 130.330323 -242.680676) (xy 130.362958 -242.643839) (xy 130.401079 -242.612714)
			(xy 130.4437 -242.588107) (xy 130.489716 -242.570655) (xy 130.537935 -242.560811) (xy 130.58711 -242.55883)
			(xy 130.635965 -242.564762) (xy 130.683236 -242.578454) (xy 130.727698 -242.599552) (xy 130.768201 -242.627508)
			(xy 130.803694 -242.6616) (xy 130.833259 -242.700944) (xy 130.85613 -242.744521) (xy 130.871714 -242.791202)
			(xy 130.879609 -242.839779) (xy 130.880104 -242.864386) (xy 131.198615 -242.864386) (xy 131.20271 -242.813658)
			(xy 131.214889 -242.764244) (xy 131.234837 -242.717424) (xy 131.262038 -242.67441) (xy 131.295786 -242.636316)
			(xy 131.335208 -242.604129) (xy 131.379282 -242.578683) (xy 131.426868 -242.560636) (xy 131.476732 -242.550456)
			(xy 131.527584 -242.548407) (xy 131.578105 -242.554541) (xy 131.626989 -242.568701) (xy 131.672968 -242.590518)
			(xy 131.714852 -242.619428) (xy 131.751556 -242.654683) (xy 131.782129 -242.695369) (xy 131.80578 -242.740432)
			(xy 131.821896 -242.788706) (xy 131.83006 -242.83894) (xy 131.830572 -242.864386) (xy 132.138415 -242.864386)
			(xy 132.14251 -242.813658) (xy 132.154689 -242.764244) (xy 132.174637 -242.717424) (xy 132.201838 -242.67441)
			(xy 132.235586 -242.636316) (xy 132.275008 -242.604129) (xy 132.319082 -242.578683) (xy 132.366668 -242.560636)
			(xy 132.416532 -242.550456) (xy 132.467384 -242.548407) (xy 132.517905 -242.554541) (xy 132.566789 -242.568701)
			(xy 132.612768 -242.590518) (xy 132.654652 -242.619428) (xy 132.691356 -242.654683) (xy 132.721929 -242.695369)
			(xy 132.74558 -242.740432) (xy 132.761696 -242.788706) (xy 132.76986 -242.83894) (xy 132.770372 -242.864386)
			(xy 133.0889 -242.864386) (xy 133.09286 -242.815332) (xy 133.104637 -242.767548) (xy 133.123928 -242.722272)
			(xy 133.150231 -242.680676) (xy 133.182866 -242.643839) (xy 133.220987 -242.612714) (xy 133.263608 -242.588107)
			(xy 133.309624 -242.570655) (xy 133.357843 -242.560811) (xy 133.407018 -242.55883) (xy 133.455873 -242.564762)
			(xy 133.503144 -242.578454) (xy 133.547606 -242.599552) (xy 133.588109 -242.627508) (xy 133.623602 -242.6616)
			(xy 133.653167 -242.700944) (xy 133.676038 -242.744521) (xy 133.691622 -242.791202) (xy 133.699517 -242.839779)
			(xy 133.700012 -242.864386) (xy 134.028954 -242.864386) (xy 134.032914 -242.815332) (xy 134.044691 -242.767548)
			(xy 134.063982 -242.722272) (xy 134.090285 -242.680676) (xy 134.12292 -242.643839) (xy 134.161041 -242.612714)
			(xy 134.203662 -242.588107) (xy 134.249678 -242.570655) (xy 134.297897 -242.560811) (xy 134.347072 -242.55883)
			(xy 134.395927 -242.564762) (xy 134.443198 -242.578454) (xy 134.48766 -242.599552) (xy 134.528163 -242.627508)
			(xy 134.563656 -242.6616) (xy 134.593221 -242.700944) (xy 134.616092 -242.744521) (xy 134.631676 -242.791202)
			(xy 134.639571 -242.839779) (xy 134.640066 -242.864386) (xy 134.969008 -242.864386) (xy 134.972968 -242.815332)
			(xy 134.984745 -242.767548) (xy 135.004036 -242.722272) (xy 135.030339 -242.680676) (xy 135.062974 -242.643839)
			(xy 135.101095 -242.612714) (xy 135.143716 -242.588107) (xy 135.189732 -242.570655) (xy 135.237951 -242.560811)
			(xy 135.287126 -242.55883) (xy 135.335981 -242.564762) (xy 135.383252 -242.578454) (xy 135.427714 -242.599552)
			(xy 135.468217 -242.627508) (xy 135.50371 -242.6616) (xy 135.533275 -242.700944) (xy 135.556146 -242.744521)
			(xy 135.57173 -242.791202) (xy 135.579625 -242.839779) (xy 135.58012 -242.864386) (xy 135.909062 -242.864386)
			(xy 135.913022 -242.815332) (xy 135.924799 -242.767548) (xy 135.94409 -242.722272) (xy 135.970393 -242.680676)
			(xy 136.003028 -242.643839) (xy 136.041149 -242.612714) (xy 136.08377 -242.588107) (xy 136.129786 -242.570655)
			(xy 136.178005 -242.560811) (xy 136.22718 -242.55883) (xy 136.276035 -242.564762) (xy 136.323306 -242.578454)
			(xy 136.367768 -242.599552) (xy 136.408271 -242.627508) (xy 136.443764 -242.6616) (xy 136.473329 -242.700944)
			(xy 136.4962 -242.744521) (xy 136.511784 -242.791202) (xy 136.519679 -242.839779) (xy 136.520174 -242.864386)
			(xy 136.848862 -242.864386) (xy 136.852822 -242.815332) (xy 136.864599 -242.767548) (xy 136.88389 -242.722272)
			(xy 136.910193 -242.680676) (xy 136.942828 -242.643839) (xy 136.980949 -242.612714) (xy 137.02357 -242.588107)
			(xy 137.069586 -242.570655) (xy 137.117805 -242.560811) (xy 137.16698 -242.55883) (xy 137.215835 -242.564762)
			(xy 137.263106 -242.578454) (xy 137.307568 -242.599552) (xy 137.348071 -242.627508) (xy 137.383564 -242.6616)
			(xy 137.413129 -242.700944) (xy 137.436 -242.744521) (xy 137.451584 -242.791202) (xy 137.459479 -242.839779)
			(xy 137.459974 -242.864386) (xy 137.788916 -242.864386) (xy 137.792876 -242.815332) (xy 137.804653 -242.767548)
			(xy 137.823944 -242.722272) (xy 137.850247 -242.680676) (xy 137.882882 -242.643839) (xy 137.921003 -242.612714)
			(xy 137.963624 -242.588107) (xy 138.00964 -242.570655) (xy 138.057859 -242.560811) (xy 138.107034 -242.55883)
			(xy 138.155889 -242.564762) (xy 138.20316 -242.578454) (xy 138.247622 -242.599552) (xy 138.288125 -242.627508)
			(xy 138.323618 -242.6616) (xy 138.353183 -242.700944) (xy 138.376054 -242.744521) (xy 138.391638 -242.791202)
			(xy 138.399533 -242.839779) (xy 138.400028 -242.864386) (xy 138.72897 -242.864386) (xy 138.73293 -242.815332)
			(xy 138.744707 -242.767548) (xy 138.763998 -242.722272) (xy 138.790301 -242.680676) (xy 138.822936 -242.643839)
			(xy 138.861057 -242.612714) (xy 138.903678 -242.588107) (xy 138.949694 -242.570655) (xy 138.997913 -242.560811)
			(xy 139.047088 -242.55883) (xy 139.095943 -242.564762) (xy 139.143214 -242.578454) (xy 139.187676 -242.599552)
			(xy 139.228179 -242.627508) (xy 139.263672 -242.6616) (xy 139.293237 -242.700944) (xy 139.316108 -242.744521)
			(xy 139.331692 -242.791202) (xy 139.339587 -242.839779) (xy 139.340082 -242.864386) (xy 139.339587 -242.888993)
			(xy 139.331692 -242.93757) (xy 139.316108 -242.984251) (xy 139.293237 -243.027828) (xy 139.263672 -243.067172)
			(xy 139.228179 -243.101264) (xy 139.187676 -243.12922) (xy 139.143214 -243.150318) (xy 139.095943 -243.16401)
			(xy 139.047088 -243.169942) (xy 138.997913 -243.167961) (xy 138.949694 -243.158117) (xy 138.903678 -243.140665)
			(xy 138.861057 -243.116058) (xy 138.822936 -243.084933) (xy 138.790301 -243.048096) (xy 138.763998 -243.0065)
			(xy 138.744707 -242.961224) (xy 138.73293 -242.91344) (xy 138.72897 -242.864386) (xy 138.400028 -242.864386)
			(xy 138.399533 -242.888993) (xy 138.391638 -242.93757) (xy 138.376054 -242.984251) (xy 138.353183 -243.027828)
			(xy 138.323618 -243.067172) (xy 138.288125 -243.101264) (xy 138.247622 -243.12922) (xy 138.20316 -243.150318)
			(xy 138.155889 -243.16401) (xy 138.107034 -243.169942) (xy 138.057859 -243.167961) (xy 138.00964 -243.158117)
			(xy 137.963624 -243.140665) (xy 137.921003 -243.116058) (xy 137.882882 -243.084933) (xy 137.850247 -243.048096)
			(xy 137.823944 -243.0065) (xy 137.804653 -242.961224) (xy 137.792876 -242.91344) (xy 137.788916 -242.864386)
			(xy 137.459974 -242.864386) (xy 137.459479 -242.888993) (xy 137.451584 -242.93757) (xy 137.436 -242.984251)
			(xy 137.413129 -243.027828) (xy 137.383564 -243.067172) (xy 137.348071 -243.101264) (xy 137.307568 -243.12922)
			(xy 137.263106 -243.150318) (xy 137.215835 -243.16401) (xy 137.16698 -243.169942) (xy 137.117805 -243.167961)
			(xy 137.069586 -243.158117) (xy 137.02357 -243.140665) (xy 136.980949 -243.116058) (xy 136.942828 -243.084933)
			(xy 136.910193 -243.048096) (xy 136.88389 -243.0065) (xy 136.864599 -242.961224) (xy 136.852822 -242.91344)
			(xy 136.848862 -242.864386) (xy 136.520174 -242.864386) (xy 136.519679 -242.888993) (xy 136.511784 -242.93757)
			(xy 136.4962 -242.984251) (xy 136.473329 -243.027828) (xy 136.443764 -243.067172) (xy 136.408271 -243.101264)
			(xy 136.367768 -243.12922) (xy 136.323306 -243.150318) (xy 136.276035 -243.16401) (xy 136.22718 -243.169942)
			(xy 136.178005 -243.167961) (xy 136.129786 -243.158117) (xy 136.08377 -243.140665) (xy 136.041149 -243.116058)
			(xy 136.003028 -243.084933) (xy 135.970393 -243.048096) (xy 135.94409 -243.0065) (xy 135.924799 -242.961224)
			(xy 135.913022 -242.91344) (xy 135.909062 -242.864386) (xy 135.58012 -242.864386) (xy 135.579625 -242.888993)
			(xy 135.57173 -242.93757) (xy 135.556146 -242.984251) (xy 135.533275 -243.027828) (xy 135.50371 -243.067172)
			(xy 135.468217 -243.101264) (xy 135.427714 -243.12922) (xy 135.383252 -243.150318) (xy 135.335981 -243.16401)
			(xy 135.287126 -243.169942) (xy 135.237951 -243.167961) (xy 135.189732 -243.158117) (xy 135.143716 -243.140665)
			(xy 135.101095 -243.116058) (xy 135.062974 -243.084933) (xy 135.030339 -243.048096) (xy 135.004036 -243.0065)
			(xy 134.984745 -242.961224) (xy 134.972968 -242.91344) (xy 134.969008 -242.864386) (xy 134.640066 -242.864386)
			(xy 134.639571 -242.888993) (xy 134.631676 -242.93757) (xy 134.616092 -242.984251) (xy 134.593221 -243.027828)
			(xy 134.563656 -243.067172) (xy 134.528163 -243.101264) (xy 134.48766 -243.12922) (xy 134.443198 -243.150318)
			(xy 134.395927 -243.16401) (xy 134.347072 -243.169942) (xy 134.297897 -243.167961) (xy 134.249678 -243.158117)
			(xy 134.203662 -243.140665) (xy 134.161041 -243.116058) (xy 134.12292 -243.084933) (xy 134.090285 -243.048096)
			(xy 134.063982 -243.0065) (xy 134.044691 -242.961224) (xy 134.032914 -242.91344) (xy 134.028954 -242.864386)
			(xy 133.700012 -242.864386) (xy 133.699517 -242.888993) (xy 133.691622 -242.93757) (xy 133.676038 -242.984251)
			(xy 133.653167 -243.027828) (xy 133.623602 -243.067172) (xy 133.588109 -243.101264) (xy 133.547606 -243.12922)
			(xy 133.503144 -243.150318) (xy 133.455873 -243.16401) (xy 133.407018 -243.169942) (xy 133.357843 -243.167961)
			(xy 133.309624 -243.158117) (xy 133.263608 -243.140665) (xy 133.220987 -243.116058) (xy 133.182866 -243.084933)
			(xy 133.150231 -243.048096) (xy 133.123928 -243.0065) (xy 133.104637 -242.961224) (xy 133.09286 -242.91344)
			(xy 133.0889 -242.864386) (xy 132.770372 -242.864386) (xy 132.76986 -242.889832) (xy 132.761696 -242.940066)
			(xy 132.74558 -242.98834) (xy 132.721929 -243.033403) (xy 132.691356 -243.074089) (xy 132.654652 -243.109344)
			(xy 132.612768 -243.138254) (xy 132.566789 -243.160071) (xy 132.517905 -243.174231) (xy 132.467384 -243.180365)
			(xy 132.416532 -243.178316) (xy 132.366668 -243.168136) (xy 132.319082 -243.150089) (xy 132.275008 -243.124643)
			(xy 132.235586 -243.092456) (xy 132.201838 -243.054362) (xy 132.174637 -243.011348) (xy 132.154689 -242.964528)
			(xy 132.14251 -242.915114) (xy 132.138415 -242.864386) (xy 131.830572 -242.864386) (xy 131.83006 -242.889832)
			(xy 131.821896 -242.940066) (xy 131.80578 -242.98834) (xy 131.782129 -243.033403) (xy 131.751556 -243.074089)
			(xy 131.714852 -243.109344) (xy 131.672968 -243.138254) (xy 131.626989 -243.160071) (xy 131.578105 -243.174231)
			(xy 131.527584 -243.180365) (xy 131.476732 -243.178316) (xy 131.426868 -243.168136) (xy 131.379282 -243.150089)
			(xy 131.335208 -243.124643) (xy 131.295786 -243.092456) (xy 131.262038 -243.054362) (xy 131.234837 -243.011348)
			(xy 131.214889 -242.964528) (xy 131.20271 -242.915114) (xy 131.198615 -242.864386) (xy 130.880104 -242.864386)
			(xy 130.879609 -242.888993) (xy 130.871714 -242.93757) (xy 130.85613 -242.984251) (xy 130.833259 -243.027828)
			(xy 130.803694 -243.067172) (xy 130.768201 -243.101264) (xy 130.727698 -243.12922) (xy 130.683236 -243.150318)
			(xy 130.635965 -243.16401) (xy 130.58711 -243.169942) (xy 130.537935 -243.167961) (xy 130.489716 -243.158117)
			(xy 130.4437 -243.140665) (xy 130.401079 -243.116058) (xy 130.362958 -243.084933) (xy 130.330323 -243.048096)
			(xy 130.30402 -243.0065) (xy 130.284729 -242.961224) (xy 130.272952 -242.91344) (xy 130.268992 -242.864386)
			(xy 129.950464 -242.864386) (xy 129.949952 -242.889832) (xy 129.941788 -242.940066) (xy 129.925672 -242.98834)
			(xy 129.902021 -243.033403) (xy 129.871448 -243.074089) (xy 129.834744 -243.109344) (xy 129.79286 -243.138254)
			(xy 129.746881 -243.160071) (xy 129.697997 -243.174231) (xy 129.647476 -243.180365) (xy 129.596624 -243.178316)
			(xy 129.54676 -243.168136) (xy 129.499174 -243.150089) (xy 129.4551 -243.124643) (xy 129.415678 -243.092456)
			(xy 129.38193 -243.054362) (xy 129.354729 -243.011348) (xy 129.334781 -242.964528) (xy 129.322602 -242.915114)
			(xy 129.318507 -242.864386) (xy 128.999996 -242.864386) (xy 128.999501 -242.888993) (xy 128.991606 -242.93757)
			(xy 128.976022 -242.984251) (xy 128.953151 -243.027828) (xy 128.923586 -243.067172) (xy 128.888093 -243.101264)
			(xy 128.84759 -243.12922) (xy 128.803128 -243.150318) (xy 128.755857 -243.16401) (xy 128.707002 -243.169942)
			(xy 128.657827 -243.167961) (xy 128.609608 -243.158117) (xy 128.563592 -243.140665) (xy 128.520971 -243.116058)
			(xy 128.48285 -243.084933) (xy 128.450215 -243.048096) (xy 128.423912 -243.0065) (xy 128.404621 -242.961224)
			(xy 128.392844 -242.91344) (xy 128.388884 -242.864386) (xy 128.070356 -242.864386) (xy 128.069844 -242.889832)
			(xy 128.06168 -242.940066) (xy 128.045564 -242.98834) (xy 128.021913 -243.033403) (xy 127.99134 -243.074089)
			(xy 127.954636 -243.109344) (xy 127.912752 -243.138254) (xy 127.866773 -243.160071) (xy 127.817889 -243.174231)
			(xy 127.767368 -243.180365) (xy 127.716516 -243.178316) (xy 127.666652 -243.168136) (xy 127.619066 -243.150089)
			(xy 127.574992 -243.124643) (xy 127.53557 -243.092456) (xy 127.501822 -243.054362) (xy 127.474621 -243.011348)
			(xy 127.454673 -242.964528) (xy 127.442494 -242.915114) (xy 127.438399 -242.864386) (xy 127.120692 -242.864386)
			(xy 127.120693 -242.864395) (xy 127.116911 -242.912354) (xy 127.105656 -242.959128) (xy 127.087207 -243.003559)
			(xy 127.06202 -243.044547) (xy 127.030718 -243.08108) (xy 126.994075 -243.112253) (xy 126.952998 -243.137295)
			(xy 126.930912 -243.146834) (xy 126.9238 -243.149882) (xy 126.91237 -243.159026) (xy 126.908052 -243.165376)
			(xy 126.904025 -243.171783) (xy 126.899638 -243.186259) (xy 126.899416 -243.193824) (xy 126.899416 -243.674392)
			(xy 127.908553 -243.674392) (xy 127.912648 -243.623664) (xy 127.924827 -243.57425) (xy 127.944775 -243.52743)
			(xy 127.971976 -243.484416) (xy 128.005724 -243.446322) (xy 128.045146 -243.414135) (xy 128.08922 -243.388689)
			(xy 128.136806 -243.370642) (xy 128.18667 -243.360462) (xy 128.237522 -243.358413) (xy 128.288043 -243.364547)
			(xy 128.336927 -243.378707) (xy 128.382906 -243.400524) (xy 128.42479 -243.429434) (xy 128.461494 -243.464689)
			(xy 128.492067 -243.505375) (xy 128.515718 -243.550438) (xy 128.531834 -243.598712) (xy 128.539998 -243.648946)
			(xy 128.54051 -243.674392) (xy 128.848607 -243.674392) (xy 128.852702 -243.623664) (xy 128.864881 -243.57425)
			(xy 128.884829 -243.52743) (xy 128.91203 -243.484416) (xy 128.945778 -243.446322) (xy 128.9852 -243.414135)
			(xy 129.029274 -243.388689) (xy 129.07686 -243.370642) (xy 129.126724 -243.360462) (xy 129.177576 -243.358413)
			(xy 129.228097 -243.364547) (xy 129.276981 -243.378707) (xy 129.32296 -243.400524) (xy 129.364844 -243.429434)
			(xy 129.401548 -243.464689) (xy 129.432121 -243.505375) (xy 129.455772 -243.550438) (xy 129.471888 -243.598712)
			(xy 129.480052 -243.648946) (xy 129.480564 -243.674392) (xy 129.798838 -243.674392) (xy 129.802798 -243.625338)
			(xy 129.814575 -243.577554) (xy 129.833866 -243.532278) (xy 129.860169 -243.490682) (xy 129.892804 -243.453845)
			(xy 129.930925 -243.42272) (xy 129.973546 -243.398113) (xy 130.019562 -243.380661) (xy 130.067781 -243.370817)
			(xy 130.116956 -243.368836) (xy 130.165811 -243.374768) (xy 130.213082 -243.38846) (xy 130.257544 -243.409558)
			(xy 130.298047 -243.437514) (xy 130.33354 -243.471606) (xy 130.363105 -243.51095) (xy 130.385976 -243.554527)
			(xy 130.40156 -243.601208) (xy 130.409455 -243.649785) (xy 130.40995 -243.674392) (xy 130.728461 -243.674392)
			(xy 130.732556 -243.623664) (xy 130.744735 -243.57425) (xy 130.764683 -243.52743) (xy 130.791884 -243.484416)
			(xy 130.825632 -243.446322) (xy 130.865054 -243.414135) (xy 130.909128 -243.388689) (xy 130.956714 -243.370642)
			(xy 131.006578 -243.360462) (xy 131.05743 -243.358413) (xy 131.107951 -243.364547) (xy 131.156835 -243.378707)
			(xy 131.202814 -243.400524) (xy 131.244698 -243.429434) (xy 131.281402 -243.464689) (xy 131.311975 -243.505375)
			(xy 131.335626 -243.550438) (xy 131.351742 -243.598712) (xy 131.359906 -243.648946) (xy 131.360418 -243.674392)
			(xy 131.678946 -243.674392) (xy 131.682906 -243.625338) (xy 131.694683 -243.577554) (xy 131.713974 -243.532278)
			(xy 131.740277 -243.490682) (xy 131.772912 -243.453845) (xy 131.811033 -243.42272) (xy 131.853654 -243.398113)
			(xy 131.89967 -243.380661) (xy 131.947889 -243.370817) (xy 131.997064 -243.368836) (xy 132.045919 -243.374768)
			(xy 132.09319 -243.38846) (xy 132.137652 -243.409558) (xy 132.178155 -243.437514) (xy 132.213648 -243.471606)
			(xy 132.243213 -243.51095) (xy 132.266084 -243.554527) (xy 132.281668 -243.601208) (xy 132.289563 -243.649785)
			(xy 132.290058 -243.674392) (xy 132.608569 -243.674392) (xy 132.612664 -243.623664) (xy 132.624843 -243.57425)
			(xy 132.644791 -243.52743) (xy 132.671992 -243.484416) (xy 132.70574 -243.446322) (xy 132.745162 -243.414135)
			(xy 132.789236 -243.388689) (xy 132.836822 -243.370642) (xy 132.886686 -243.360462) (xy 132.937538 -243.358413)
			(xy 132.988059 -243.364547) (xy 133.036943 -243.378707) (xy 133.082922 -243.400524) (xy 133.124806 -243.429434)
			(xy 133.16151 -243.464689) (xy 133.192083 -243.505375) (xy 133.215734 -243.550438) (xy 133.23185 -243.598712)
			(xy 133.240014 -243.648946) (xy 133.240526 -243.674392) (xy 133.559054 -243.674392) (xy 133.563014 -243.625338)
			(xy 133.574791 -243.577554) (xy 133.594082 -243.532278) (xy 133.620385 -243.490682) (xy 133.65302 -243.453845)
			(xy 133.691141 -243.42272) (xy 133.733762 -243.398113) (xy 133.779778 -243.380661) (xy 133.827997 -243.370817)
			(xy 133.877172 -243.368836) (xy 133.926027 -243.374768) (xy 133.973298 -243.38846) (xy 134.01776 -243.409558)
			(xy 134.058263 -243.437514) (xy 134.093756 -243.471606) (xy 134.123321 -243.51095) (xy 134.146192 -243.554527)
			(xy 134.161776 -243.601208) (xy 134.169671 -243.649785) (xy 134.170166 -243.674392) (xy 134.498854 -243.674392)
			(xy 134.502814 -243.625338) (xy 134.514591 -243.577554) (xy 134.533882 -243.532278) (xy 134.560185 -243.490682)
			(xy 134.59282 -243.453845) (xy 134.630941 -243.42272) (xy 134.673562 -243.398113) (xy 134.719578 -243.380661)
			(xy 134.767797 -243.370817) (xy 134.816972 -243.368836) (xy 134.865827 -243.374768) (xy 134.913098 -243.38846)
			(xy 134.95756 -243.409558) (xy 134.998063 -243.437514) (xy 135.033556 -243.471606) (xy 135.063121 -243.51095)
			(xy 135.085992 -243.554527) (xy 135.101576 -243.601208) (xy 135.109471 -243.649785) (xy 135.109966 -243.674392)
			(xy 135.438908 -243.674392) (xy 135.442868 -243.625338) (xy 135.454645 -243.577554) (xy 135.473936 -243.532278)
			(xy 135.500239 -243.490682) (xy 135.532874 -243.453845) (xy 135.570995 -243.42272) (xy 135.613616 -243.398113)
			(xy 135.659632 -243.380661) (xy 135.707851 -243.370817) (xy 135.757026 -243.368836) (xy 135.805881 -243.374768)
			(xy 135.853152 -243.38846) (xy 135.897614 -243.409558) (xy 135.938117 -243.437514) (xy 135.97361 -243.471606)
			(xy 136.003175 -243.51095) (xy 136.026046 -243.554527) (xy 136.04163 -243.601208) (xy 136.049525 -243.649785)
			(xy 136.05002 -243.674392) (xy 136.378962 -243.674392) (xy 136.382922 -243.625338) (xy 136.394699 -243.577554)
			(xy 136.41399 -243.532278) (xy 136.440293 -243.490682) (xy 136.472928 -243.453845) (xy 136.511049 -243.42272)
			(xy 136.55367 -243.398113) (xy 136.599686 -243.380661) (xy 136.647905 -243.370817) (xy 136.69708 -243.368836)
			(xy 136.745935 -243.374768) (xy 136.793206 -243.38846) (xy 136.837668 -243.409558) (xy 136.878171 -243.437514)
			(xy 136.913664 -243.471606) (xy 136.943229 -243.51095) (xy 136.9661 -243.554527) (xy 136.981684 -243.601208)
			(xy 136.989579 -243.649785) (xy 136.990074 -243.674392) (xy 137.319016 -243.674392) (xy 137.322976 -243.625338)
			(xy 137.334753 -243.577554) (xy 137.354044 -243.532278) (xy 137.380347 -243.490682) (xy 137.412982 -243.453845)
			(xy 137.451103 -243.42272) (xy 137.493724 -243.398113) (xy 137.53974 -243.380661) (xy 137.587959 -243.370817)
			(xy 137.637134 -243.368836) (xy 137.685989 -243.374768) (xy 137.73326 -243.38846) (xy 137.777722 -243.409558)
			(xy 137.818225 -243.437514) (xy 137.853718 -243.471606) (xy 137.883283 -243.51095) (xy 137.906154 -243.554527)
			(xy 137.921738 -243.601208) (xy 137.929633 -243.649785) (xy 137.930128 -243.674392) (xy 138.25907 -243.674392)
			(xy 138.26303 -243.625338) (xy 138.274807 -243.577554) (xy 138.294098 -243.532278) (xy 138.320401 -243.490682)
			(xy 138.353036 -243.453845) (xy 138.391157 -243.42272) (xy 138.433778 -243.398113) (xy 138.479794 -243.380661)
			(xy 138.528013 -243.370817) (xy 138.577188 -243.368836) (xy 138.626043 -243.374768) (xy 138.673314 -243.38846)
			(xy 138.717776 -243.409558) (xy 138.758279 -243.437514) (xy 138.793772 -243.471606) (xy 138.823337 -243.51095)
			(xy 138.846208 -243.554527) (xy 138.861792 -243.601208) (xy 138.869687 -243.649785) (xy 138.870182 -243.674392)
			(xy 139.19887 -243.674392) (xy 139.20283 -243.625338) (xy 139.214607 -243.577554) (xy 139.233898 -243.532278)
			(xy 139.260201 -243.490682) (xy 139.292836 -243.453845) (xy 139.330957 -243.42272) (xy 139.373578 -243.398113)
			(xy 139.419594 -243.380661) (xy 139.467813 -243.370817) (xy 139.516988 -243.368836) (xy 139.565843 -243.374768)
			(xy 139.613114 -243.38846) (xy 139.657576 -243.409558) (xy 139.698079 -243.437514) (xy 139.733572 -243.471606)
			(xy 139.763137 -243.51095) (xy 139.786008 -243.554527) (xy 139.801592 -243.601208) (xy 139.809487 -243.649785)
			(xy 139.809982 -243.674392) (xy 139.809487 -243.698999) (xy 139.801592 -243.747576) (xy 139.786008 -243.794257)
			(xy 139.763137 -243.837834) (xy 139.733572 -243.877178) (xy 139.698079 -243.91127) (xy 139.657576 -243.939226)
			(xy 139.613114 -243.960324) (xy 139.565843 -243.974016) (xy 139.516988 -243.979948) (xy 139.467813 -243.977967)
			(xy 139.419594 -243.968123) (xy 139.373578 -243.950671) (xy 139.330957 -243.926064) (xy 139.292836 -243.894939)
			(xy 139.260201 -243.858102) (xy 139.233898 -243.816506) (xy 139.214607 -243.77123) (xy 139.20283 -243.723446)
			(xy 139.19887 -243.674392) (xy 138.870182 -243.674392) (xy 138.869687 -243.698999) (xy 138.861792 -243.747576)
			(xy 138.846208 -243.794257) (xy 138.823337 -243.837834) (xy 138.793772 -243.877178) (xy 138.758279 -243.91127)
			(xy 138.717776 -243.939226) (xy 138.673314 -243.960324) (xy 138.626043 -243.974016) (xy 138.577188 -243.979948)
			(xy 138.528013 -243.977967) (xy 138.479794 -243.968123) (xy 138.433778 -243.950671) (xy 138.391157 -243.926064)
			(xy 138.353036 -243.894939) (xy 138.320401 -243.858102) (xy 138.294098 -243.816506) (xy 138.274807 -243.77123)
			(xy 138.26303 -243.723446) (xy 138.25907 -243.674392) (xy 137.930128 -243.674392) (xy 137.929633 -243.698999)
			(xy 137.921738 -243.747576) (xy 137.906154 -243.794257) (xy 137.883283 -243.837834) (xy 137.853718 -243.877178)
			(xy 137.818225 -243.91127) (xy 137.777722 -243.939226) (xy 137.73326 -243.960324) (xy 137.685989 -243.974016)
			(xy 137.637134 -243.979948) (xy 137.587959 -243.977967) (xy 137.53974 -243.968123) (xy 137.493724 -243.950671)
			(xy 137.451103 -243.926064) (xy 137.412982 -243.894939) (xy 137.380347 -243.858102) (xy 137.354044 -243.816506)
			(xy 137.334753 -243.77123) (xy 137.322976 -243.723446) (xy 137.319016 -243.674392) (xy 136.990074 -243.674392)
			(xy 136.989579 -243.698999) (xy 136.981684 -243.747576) (xy 136.9661 -243.794257) (xy 136.943229 -243.837834)
			(xy 136.913664 -243.877178) (xy 136.878171 -243.91127) (xy 136.837668 -243.939226) (xy 136.793206 -243.960324)
			(xy 136.745935 -243.974016) (xy 136.69708 -243.979948) (xy 136.647905 -243.977967) (xy 136.599686 -243.968123)
			(xy 136.55367 -243.950671) (xy 136.511049 -243.926064) (xy 136.472928 -243.894939) (xy 136.440293 -243.858102)
			(xy 136.41399 -243.816506) (xy 136.394699 -243.77123) (xy 136.382922 -243.723446) (xy 136.378962 -243.674392)
			(xy 136.05002 -243.674392) (xy 136.049525 -243.698999) (xy 136.04163 -243.747576) (xy 136.026046 -243.794257)
			(xy 136.003175 -243.837834) (xy 135.97361 -243.877178) (xy 135.938117 -243.91127) (xy 135.897614 -243.939226)
			(xy 135.853152 -243.960324) (xy 135.805881 -243.974016) (xy 135.757026 -243.979948) (xy 135.707851 -243.977967)
			(xy 135.659632 -243.968123) (xy 135.613616 -243.950671) (xy 135.570995 -243.926064) (xy 135.532874 -243.894939)
			(xy 135.500239 -243.858102) (xy 135.473936 -243.816506) (xy 135.454645 -243.77123) (xy 135.442868 -243.723446)
			(xy 135.438908 -243.674392) (xy 135.109966 -243.674392) (xy 135.109471 -243.698999) (xy 135.101576 -243.747576)
			(xy 135.085992 -243.794257) (xy 135.063121 -243.837834) (xy 135.033556 -243.877178) (xy 134.998063 -243.91127)
			(xy 134.95756 -243.939226) (xy 134.913098 -243.960324) (xy 134.865827 -243.974016) (xy 134.816972 -243.979948)
			(xy 134.767797 -243.977967) (xy 134.719578 -243.968123) (xy 134.673562 -243.950671) (xy 134.630941 -243.926064)
			(xy 134.59282 -243.894939) (xy 134.560185 -243.858102) (xy 134.533882 -243.816506) (xy 134.514591 -243.77123)
			(xy 134.502814 -243.723446) (xy 134.498854 -243.674392) (xy 134.170166 -243.674392) (xy 134.169671 -243.698999)
			(xy 134.161776 -243.747576) (xy 134.146192 -243.794257) (xy 134.123321 -243.837834) (xy 134.093756 -243.877178)
			(xy 134.058263 -243.91127) (xy 134.01776 -243.939226) (xy 133.973298 -243.960324) (xy 133.926027 -243.974016)
			(xy 133.877172 -243.979948) (xy 133.827997 -243.977967) (xy 133.779778 -243.968123) (xy 133.733762 -243.950671)
			(xy 133.691141 -243.926064) (xy 133.65302 -243.894939) (xy 133.620385 -243.858102) (xy 133.594082 -243.816506)
			(xy 133.574791 -243.77123) (xy 133.563014 -243.723446) (xy 133.559054 -243.674392) (xy 133.240526 -243.674392)
			(xy 133.240014 -243.699838) (xy 133.23185 -243.750072) (xy 133.215734 -243.798346) (xy 133.192083 -243.843409)
			(xy 133.16151 -243.884095) (xy 133.124806 -243.91935) (xy 133.082922 -243.94826) (xy 133.036943 -243.970077)
			(xy 132.988059 -243.984237) (xy 132.937538 -243.990371) (xy 132.886686 -243.988322) (xy 132.836822 -243.978142)
			(xy 132.789236 -243.960095) (xy 132.745162 -243.934649) (xy 132.70574 -243.902462) (xy 132.671992 -243.864368)
			(xy 132.644791 -243.821354) (xy 132.624843 -243.774534) (xy 132.612664 -243.72512) (xy 132.608569 -243.674392)
			(xy 132.290058 -243.674392) (xy 132.289563 -243.698999) (xy 132.281668 -243.747576) (xy 132.266084 -243.794257)
			(xy 132.243213 -243.837834) (xy 132.213648 -243.877178) (xy 132.178155 -243.91127) (xy 132.137652 -243.939226)
			(xy 132.09319 -243.960324) (xy 132.045919 -243.974016) (xy 131.997064 -243.979948) (xy 131.947889 -243.977967)
			(xy 131.89967 -243.968123) (xy 131.853654 -243.950671) (xy 131.811033 -243.926064) (xy 131.772912 -243.894939)
			(xy 131.740277 -243.858102) (xy 131.713974 -243.816506) (xy 131.694683 -243.77123) (xy 131.682906 -243.723446)
			(xy 131.678946 -243.674392) (xy 131.360418 -243.674392) (xy 131.359906 -243.699838) (xy 131.351742 -243.750072)
			(xy 131.335626 -243.798346) (xy 131.311975 -243.843409) (xy 131.281402 -243.884095) (xy 131.244698 -243.91935)
			(xy 131.202814 -243.94826) (xy 131.156835 -243.970077) (xy 131.107951 -243.984237) (xy 131.05743 -243.990371)
			(xy 131.006578 -243.988322) (xy 130.956714 -243.978142) (xy 130.909128 -243.960095) (xy 130.865054 -243.934649)
			(xy 130.825632 -243.902462) (xy 130.791884 -243.864368) (xy 130.764683 -243.821354) (xy 130.744735 -243.774534)
			(xy 130.732556 -243.72512) (xy 130.728461 -243.674392) (xy 130.40995 -243.674392) (xy 130.409455 -243.698999)
			(xy 130.40156 -243.747576) (xy 130.385976 -243.794257) (xy 130.363105 -243.837834) (xy 130.33354 -243.877178)
			(xy 130.298047 -243.91127) (xy 130.257544 -243.939226) (xy 130.213082 -243.960324) (xy 130.165811 -243.974016)
			(xy 130.116956 -243.979948) (xy 130.067781 -243.977967) (xy 130.019562 -243.968123) (xy 129.973546 -243.950671)
			(xy 129.930925 -243.926064) (xy 129.892804 -243.894939) (xy 129.860169 -243.858102) (xy 129.833866 -243.816506)
			(xy 129.814575 -243.77123) (xy 129.802798 -243.723446) (xy 129.798838 -243.674392) (xy 129.480564 -243.674392)
			(xy 129.480052 -243.699838) (xy 129.471888 -243.750072) (xy 129.455772 -243.798346) (xy 129.432121 -243.843409)
			(xy 129.401548 -243.884095) (xy 129.364844 -243.91935) (xy 129.32296 -243.94826) (xy 129.276981 -243.970077)
			(xy 129.228097 -243.984237) (xy 129.177576 -243.990371) (xy 129.126724 -243.988322) (xy 129.07686 -243.978142)
			(xy 129.029274 -243.960095) (xy 128.9852 -243.934649) (xy 128.945778 -243.902462) (xy 128.91203 -243.864368)
			(xy 128.884829 -243.821354) (xy 128.864881 -243.774534) (xy 128.852702 -243.72512) (xy 128.848607 -243.674392)
			(xy 128.54051 -243.674392) (xy 128.539998 -243.699838) (xy 128.531834 -243.750072) (xy 128.515718 -243.798346)
			(xy 128.492067 -243.843409) (xy 128.461494 -243.884095) (xy 128.42479 -243.91935) (xy 128.382906 -243.94826)
			(xy 128.336927 -243.970077) (xy 128.288043 -243.984237) (xy 128.237522 -243.990371) (xy 128.18667 -243.988322)
			(xy 128.136806 -243.978142) (xy 128.08922 -243.960095) (xy 128.045146 -243.934649) (xy 128.005724 -243.902462)
			(xy 127.971976 -243.864368) (xy 127.944775 -243.821354) (xy 127.924827 -243.774534) (xy 127.912648 -243.72512)
			(xy 127.908553 -243.674392) (xy 126.899416 -243.674392) (xy 126.899416 -244.15496) (xy 126.899701 -244.162513)
			(xy 126.904098 -244.176966) (xy 126.908052 -244.183408) (xy 126.91237 -244.189758) (xy 126.9238 -244.198902)
			(xy 126.930912 -244.20195) (xy 126.952988 -244.211512) (xy 126.994063 -244.236553) (xy 127.030705 -244.267724)
			(xy 127.062007 -244.304255) (xy 127.087194 -244.345241) (xy 127.105643 -244.38967) (xy 127.116898 -244.436441)
			(xy 127.120682 -244.484398) (xy 127.438399 -244.484398) (xy 127.442494 -244.43367) (xy 127.454673 -244.384256)
			(xy 127.474621 -244.337436) (xy 127.501822 -244.294422) (xy 127.53557 -244.256328) (xy 127.574992 -244.224141)
			(xy 127.619066 -244.198695) (xy 127.666652 -244.180648) (xy 127.716516 -244.170468) (xy 127.767368 -244.168419)
			(xy 127.817889 -244.174553) (xy 127.866773 -244.188713) (xy 127.912752 -244.21053) (xy 127.954636 -244.23944)
			(xy 127.99134 -244.274695) (xy 128.021913 -244.315381) (xy 128.045564 -244.360444) (xy 128.06168 -244.408718)
			(xy 128.069844 -244.458952) (xy 128.070356 -244.484398) (xy 128.388884 -244.484398) (xy 128.392844 -244.435344)
			(xy 128.404621 -244.38756) (xy 128.423912 -244.342284) (xy 128.450215 -244.300688) (xy 128.48285 -244.263851)
			(xy 128.520971 -244.232726) (xy 128.563592 -244.208119) (xy 128.609608 -244.190667) (xy 128.657827 -244.180823)
			(xy 128.707002 -244.178842) (xy 128.755857 -244.184774) (xy 128.803128 -244.198466) (xy 128.84759 -244.219564)
			(xy 128.888093 -244.24752) (xy 128.923586 -244.281612) (xy 128.953151 -244.320956) (xy 128.976022 -244.364533)
			(xy 128.991606 -244.411214) (xy 128.999501 -244.459791) (xy 128.999996 -244.484398) (xy 129.318507 -244.484398)
			(xy 129.322602 -244.43367) (xy 129.334781 -244.384256) (xy 129.354729 -244.337436) (xy 129.38193 -244.294422)
			(xy 129.415678 -244.256328) (xy 129.4551 -244.224141) (xy 129.499174 -244.198695) (xy 129.54676 -244.180648)
			(xy 129.596624 -244.170468) (xy 129.647476 -244.168419) (xy 129.697997 -244.174553) (xy 129.746881 -244.188713)
			(xy 129.79286 -244.21053) (xy 129.834744 -244.23944) (xy 129.871448 -244.274695) (xy 129.902021 -244.315381)
			(xy 129.925672 -244.360444) (xy 129.941788 -244.408718) (xy 129.949952 -244.458952) (xy 129.950464 -244.484398)
			(xy 131.198615 -244.484398) (xy 131.20271 -244.43367) (xy 131.214889 -244.384256) (xy 131.234837 -244.337436)
			(xy 131.262038 -244.294422) (xy 131.295786 -244.256328) (xy 131.335208 -244.224141) (xy 131.379282 -244.198695)
			(xy 131.426868 -244.180648) (xy 131.476732 -244.170468) (xy 131.527584 -244.168419) (xy 131.578105 -244.174553)
			(xy 131.626989 -244.188713) (xy 131.672968 -244.21053) (xy 131.714852 -244.23944) (xy 131.751556 -244.274695)
			(xy 131.782129 -244.315381) (xy 131.80578 -244.360444) (xy 131.821896 -244.408718) (xy 131.83006 -244.458952)
			(xy 131.830572 -244.484398) (xy 132.138415 -244.484398) (xy 132.14251 -244.43367) (xy 132.154689 -244.384256)
			(xy 132.174637 -244.337436) (xy 132.201838 -244.294422) (xy 132.235586 -244.256328) (xy 132.275008 -244.224141)
			(xy 132.319082 -244.198695) (xy 132.366668 -244.180648) (xy 132.416532 -244.170468) (xy 132.467384 -244.168419)
			(xy 132.517905 -244.174553) (xy 132.566789 -244.188713) (xy 132.612768 -244.21053) (xy 132.654652 -244.23944)
			(xy 132.691356 -244.274695) (xy 132.721929 -244.315381) (xy 132.74558 -244.360444) (xy 132.761696 -244.408718)
			(xy 132.76986 -244.458952) (xy 132.770372 -244.484398) (xy 133.0889 -244.484398) (xy 133.09286 -244.435344)
			(xy 133.104637 -244.38756) (xy 133.123928 -244.342284) (xy 133.150231 -244.300688) (xy 133.182866 -244.263851)
			(xy 133.220987 -244.232726) (xy 133.263608 -244.208119) (xy 133.309624 -244.190667) (xy 133.357843 -244.180823)
			(xy 133.407018 -244.178842) (xy 133.455873 -244.184774) (xy 133.503144 -244.198466) (xy 133.547606 -244.219564)
			(xy 133.588109 -244.24752) (xy 133.623602 -244.281612) (xy 133.653167 -244.320956) (xy 133.676038 -244.364533)
			(xy 133.691622 -244.411214) (xy 133.699517 -244.459791) (xy 133.700012 -244.484398) (xy 134.028954 -244.484398)
			(xy 134.032914 -244.435344) (xy 134.044691 -244.38756) (xy 134.063982 -244.342284) (xy 134.090285 -244.300688)
			(xy 134.12292 -244.263851) (xy 134.161041 -244.232726) (xy 134.203662 -244.208119) (xy 134.249678 -244.190667)
			(xy 134.297897 -244.180823) (xy 134.347072 -244.178842) (xy 134.395927 -244.184774) (xy 134.443198 -244.198466)
			(xy 134.48766 -244.219564) (xy 134.528163 -244.24752) (xy 134.563656 -244.281612) (xy 134.593221 -244.320956)
			(xy 134.616092 -244.364533) (xy 134.631676 -244.411214) (xy 134.639571 -244.459791) (xy 134.640066 -244.484398)
			(xy 134.969008 -244.484398) (xy 134.972968 -244.435344) (xy 134.984745 -244.38756) (xy 135.004036 -244.342284)
			(xy 135.030339 -244.300688) (xy 135.062974 -244.263851) (xy 135.101095 -244.232726) (xy 135.143716 -244.208119)
			(xy 135.189732 -244.190667) (xy 135.237951 -244.180823) (xy 135.287126 -244.178842) (xy 135.335981 -244.184774)
			(xy 135.383252 -244.198466) (xy 135.427714 -244.219564) (xy 135.468217 -244.24752) (xy 135.50371 -244.281612)
			(xy 135.533275 -244.320956) (xy 135.556146 -244.364533) (xy 135.57173 -244.411214) (xy 135.579625 -244.459791)
			(xy 135.58012 -244.484398) (xy 135.909062 -244.484398) (xy 135.913022 -244.435344) (xy 135.924799 -244.38756)
			(xy 135.94409 -244.342284) (xy 135.970393 -244.300688) (xy 136.003028 -244.263851) (xy 136.041149 -244.232726)
			(xy 136.08377 -244.208119) (xy 136.129786 -244.190667) (xy 136.178005 -244.180823) (xy 136.22718 -244.178842)
			(xy 136.276035 -244.184774) (xy 136.323306 -244.198466) (xy 136.367768 -244.219564) (xy 136.408271 -244.24752)
			(xy 136.443764 -244.281612) (xy 136.473329 -244.320956) (xy 136.4962 -244.364533) (xy 136.511784 -244.411214)
			(xy 136.519679 -244.459791) (xy 136.520174 -244.484398) (xy 137.788916 -244.484398) (xy 137.792876 -244.435344)
			(xy 137.804653 -244.38756) (xy 137.823944 -244.342284) (xy 137.850247 -244.300688) (xy 137.882882 -244.263851)
			(xy 137.921003 -244.232726) (xy 137.963624 -244.208119) (xy 138.00964 -244.190667) (xy 138.057859 -244.180823)
			(xy 138.107034 -244.178842) (xy 138.155889 -244.184774) (xy 138.20316 -244.198466) (xy 138.247622 -244.219564)
			(xy 138.288125 -244.24752) (xy 138.323618 -244.281612) (xy 138.353183 -244.320956) (xy 138.376054 -244.364533)
			(xy 138.391638 -244.411214) (xy 138.399533 -244.459791) (xy 138.400028 -244.484398) (xy 138.72897 -244.484398)
			(xy 138.73293 -244.435344) (xy 138.744707 -244.38756) (xy 138.763998 -244.342284) (xy 138.790301 -244.300688)
			(xy 138.822936 -244.263851) (xy 138.861057 -244.232726) (xy 138.903678 -244.208119) (xy 138.949694 -244.190667)
			(xy 138.997913 -244.180823) (xy 139.047088 -244.178842) (xy 139.095943 -244.184774) (xy 139.143214 -244.198466)
			(xy 139.187676 -244.219564) (xy 139.228179 -244.24752) (xy 139.263672 -244.281612) (xy 139.293237 -244.320956)
			(xy 139.316108 -244.364533) (xy 139.331692 -244.411214) (xy 139.339587 -244.459791) (xy 139.340082 -244.484398)
			(xy 139.339587 -244.509005) (xy 139.331692 -244.557582) (xy 139.316108 -244.604263) (xy 139.293237 -244.64784)
			(xy 139.263672 -244.687184) (xy 139.228179 -244.721276) (xy 139.187676 -244.749232) (xy 139.143214 -244.77033)
			(xy 139.095943 -244.784022) (xy 139.047088 -244.789954) (xy 138.997913 -244.787973) (xy 138.949694 -244.778129)
			(xy 138.903678 -244.760677) (xy 138.861057 -244.73607) (xy 138.822936 -244.704945) (xy 138.790301 -244.668108)
			(xy 138.763998 -244.626512) (xy 138.744707 -244.581236) (xy 138.73293 -244.533452) (xy 138.72897 -244.484398)
			(xy 138.400028 -244.484398) (xy 138.399533 -244.509005) (xy 138.391638 -244.557582) (xy 138.376054 -244.604263)
			(xy 138.353183 -244.64784) (xy 138.323618 -244.687184) (xy 138.288125 -244.721276) (xy 138.247622 -244.749232)
			(xy 138.20316 -244.77033) (xy 138.155889 -244.784022) (xy 138.107034 -244.789954) (xy 138.057859 -244.787973)
			(xy 138.00964 -244.778129) (xy 137.963624 -244.760677) (xy 137.921003 -244.73607) (xy 137.882882 -244.704945)
			(xy 137.850247 -244.668108) (xy 137.823944 -244.626512) (xy 137.804653 -244.581236) (xy 137.792876 -244.533452)
			(xy 137.788916 -244.484398) (xy 136.520174 -244.484398) (xy 136.519679 -244.509005) (xy 136.511784 -244.557582)
			(xy 136.4962 -244.604263) (xy 136.473329 -244.64784) (xy 136.443764 -244.687184) (xy 136.408271 -244.721276)
			(xy 136.367768 -244.749232) (xy 136.323306 -244.77033) (xy 136.276035 -244.784022) (xy 136.22718 -244.789954)
			(xy 136.178005 -244.787973) (xy 136.129786 -244.778129) (xy 136.08377 -244.760677) (xy 136.041149 -244.73607)
			(xy 136.003028 -244.704945) (xy 135.970393 -244.668108) (xy 135.94409 -244.626512) (xy 135.924799 -244.581236)
			(xy 135.913022 -244.533452) (xy 135.909062 -244.484398) (xy 135.58012 -244.484398) (xy 135.579625 -244.509005)
			(xy 135.57173 -244.557582) (xy 135.556146 -244.604263) (xy 135.533275 -244.64784) (xy 135.50371 -244.687184)
			(xy 135.468217 -244.721276) (xy 135.427714 -244.749232) (xy 135.383252 -244.77033) (xy 135.335981 -244.784022)
			(xy 135.287126 -244.789954) (xy 135.237951 -244.787973) (xy 135.189732 -244.778129) (xy 135.143716 -244.760677)
			(xy 135.101095 -244.73607) (xy 135.062974 -244.704945) (xy 135.030339 -244.668108) (xy 135.004036 -244.626512)
			(xy 134.984745 -244.581236) (xy 134.972968 -244.533452) (xy 134.969008 -244.484398) (xy 134.640066 -244.484398)
			(xy 134.639571 -244.509005) (xy 134.631676 -244.557582) (xy 134.616092 -244.604263) (xy 134.593221 -244.64784)
			(xy 134.563656 -244.687184) (xy 134.528163 -244.721276) (xy 134.48766 -244.749232) (xy 134.443198 -244.77033)
			(xy 134.395927 -244.784022) (xy 134.347072 -244.789954) (xy 134.297897 -244.787973) (xy 134.249678 -244.778129)
			(xy 134.203662 -244.760677) (xy 134.161041 -244.73607) (xy 134.12292 -244.704945) (xy 134.090285 -244.668108)
			(xy 134.063982 -244.626512) (xy 134.044691 -244.581236) (xy 134.032914 -244.533452) (xy 134.028954 -244.484398)
			(xy 133.700012 -244.484398) (xy 133.699517 -244.509005) (xy 133.691622 -244.557582) (xy 133.676038 -244.604263)
			(xy 133.653167 -244.64784) (xy 133.623602 -244.687184) (xy 133.588109 -244.721276) (xy 133.547606 -244.749232)
			(xy 133.503144 -244.77033) (xy 133.455873 -244.784022) (xy 133.407018 -244.789954) (xy 133.357843 -244.787973)
			(xy 133.309624 -244.778129) (xy 133.263608 -244.760677) (xy 133.220987 -244.73607) (xy 133.182866 -244.704945)
			(xy 133.150231 -244.668108) (xy 133.123928 -244.626512) (xy 133.104637 -244.581236) (xy 133.09286 -244.533452)
			(xy 133.0889 -244.484398) (xy 132.770372 -244.484398) (xy 132.76986 -244.509844) (xy 132.761696 -244.560078)
			(xy 132.74558 -244.608352) (xy 132.721929 -244.653415) (xy 132.691356 -244.694101) (xy 132.654652 -244.729356)
			(xy 132.612768 -244.758266) (xy 132.566789 -244.780083) (xy 132.517905 -244.794243) (xy 132.467384 -244.800377)
			(xy 132.416532 -244.798328) (xy 132.366668 -244.788148) (xy 132.319082 -244.770101) (xy 132.275008 -244.744655)
			(xy 132.235586 -244.712468) (xy 132.201838 -244.674374) (xy 132.174637 -244.63136) (xy 132.154689 -244.58454)
			(xy 132.14251 -244.535126) (xy 132.138415 -244.484398) (xy 131.830572 -244.484398) (xy 131.83006 -244.509844)
			(xy 131.821896 -244.560078) (xy 131.80578 -244.608352) (xy 131.782129 -244.653415) (xy 131.751556 -244.694101)
			(xy 131.714852 -244.729356) (xy 131.672968 -244.758266) (xy 131.626989 -244.780083) (xy 131.578105 -244.794243)
			(xy 131.527584 -244.800377) (xy 131.476732 -244.798328) (xy 131.426868 -244.788148) (xy 131.379282 -244.770101)
			(xy 131.335208 -244.744655) (xy 131.295786 -244.712468) (xy 131.262038 -244.674374) (xy 131.234837 -244.63136)
			(xy 131.214889 -244.58454) (xy 131.20271 -244.535126) (xy 131.198615 -244.484398) (xy 129.950464 -244.484398)
			(xy 129.949952 -244.509844) (xy 129.941788 -244.560078) (xy 129.925672 -244.608352) (xy 129.902021 -244.653415)
			(xy 129.871448 -244.694101) (xy 129.834744 -244.729356) (xy 129.79286 -244.758266) (xy 129.746881 -244.780083)
			(xy 129.697997 -244.794243) (xy 129.647476 -244.800377) (xy 129.596624 -244.798328) (xy 129.54676 -244.788148)
			(xy 129.499174 -244.770101) (xy 129.4551 -244.744655) (xy 129.415678 -244.712468) (xy 129.38193 -244.674374)
			(xy 129.354729 -244.63136) (xy 129.334781 -244.58454) (xy 129.322602 -244.535126) (xy 129.318507 -244.484398)
			(xy 128.999996 -244.484398) (xy 128.999501 -244.509005) (xy 128.991606 -244.557582) (xy 128.976022 -244.604263)
			(xy 128.953151 -244.64784) (xy 128.923586 -244.687184) (xy 128.888093 -244.721276) (xy 128.84759 -244.749232)
			(xy 128.803128 -244.77033) (xy 128.755857 -244.784022) (xy 128.707002 -244.789954) (xy 128.657827 -244.787973)
			(xy 128.609608 -244.778129) (xy 128.563592 -244.760677) (xy 128.520971 -244.73607) (xy 128.48285 -244.704945)
			(xy 128.450215 -244.668108) (xy 128.423912 -244.626512) (xy 128.404621 -244.581236) (xy 128.392844 -244.533452)
			(xy 128.388884 -244.484398) (xy 128.070356 -244.484398) (xy 128.069844 -244.509844) (xy 128.06168 -244.560078)
			(xy 128.045564 -244.608352) (xy 128.021913 -244.653415) (xy 127.99134 -244.694101) (xy 127.954636 -244.729356)
			(xy 127.912752 -244.758266) (xy 127.866773 -244.780083) (xy 127.817889 -244.794243) (xy 127.767368 -244.800377)
			(xy 127.716516 -244.798328) (xy 127.666652 -244.788148) (xy 127.619066 -244.770101) (xy 127.574992 -244.744655)
			(xy 127.53557 -244.712468) (xy 127.501822 -244.674374) (xy 127.474621 -244.63136) (xy 127.454673 -244.58454)
			(xy 127.442494 -244.535126) (xy 127.438399 -244.484398) (xy 127.120682 -244.484398) (xy 127.120682 -244.484399)
			(xy 127.116899 -244.532357) (xy 127.105644 -244.579129) (xy 127.087194 -244.623557) (xy 127.062008 -244.664544)
			(xy 127.030706 -244.701075) (xy 126.994065 -244.732246) (xy 126.952989 -244.757287) (xy 126.930912 -244.766846)
			(xy 126.9238 -244.769894) (xy 126.91237 -244.779038) (xy 126.908052 -244.785388) (xy 126.904027 -244.791796)
			(xy 126.899643 -244.806272) (xy 126.899416 -244.813836) (xy 126.899416 -245.002812) (xy 126.899416 -245.004844)
			(xy 126.900142 -245.013914) (xy 126.907163 -245.030686) (xy 126.919615 -245.043935) (xy 126.92761 -245.048278)
			(xy 127.016764 -245.086124) (xy 127.023753 -245.088747) (xy 127.038594 -245.090293) (xy 127.045974 -245.089172)
			(xy 127.05334 -245.087902) (xy 127.06604 -245.081044) (xy 127.071882 -245.075456) (xy 127.089091 -245.059358)
			(xy 127.127539 -245.032114) (xy 127.169712 -245.011093) (xy 127.214611 -244.996792) (xy 127.261173 -244.989551)
			(xy 127.284734 -244.989096) (xy 127.309987 -244.98962) (xy 127.359804 -244.997938) (xy 127.407572 -245.014342)
			(xy 127.45199 -245.038384) (xy 127.491844 -245.069408) (xy 127.526049 -245.106568) (xy 127.553672 -245.148852)
			(xy 127.573959 -245.195105) (xy 127.586357 -245.244066) (xy 127.590527 -245.2944) (xy 127.590527 -245.294404)
			(xy 127.908553 -245.294404) (xy 127.912648 -245.243676) (xy 127.924827 -245.194262) (xy 127.944775 -245.147442)
			(xy 127.971976 -245.104428) (xy 128.005724 -245.066334) (xy 128.045146 -245.034147) (xy 128.08922 -245.008701)
			(xy 128.136806 -244.990654) (xy 128.18667 -244.980474) (xy 128.237522 -244.978425) (xy 128.288043 -244.984559)
			(xy 128.336927 -244.998719) (xy 128.382906 -245.020536) (xy 128.42479 -245.049446) (xy 128.461494 -245.084701)
			(xy 128.492067 -245.125387) (xy 128.515718 -245.17045) (xy 128.531834 -245.218724) (xy 128.539998 -245.268958)
			(xy 128.54051 -245.294404) (xy 128.848607 -245.294404) (xy 128.852702 -245.243676) (xy 128.864881 -245.194262)
			(xy 128.884829 -245.147442) (xy 128.91203 -245.104428) (xy 128.945778 -245.066334) (xy 128.9852 -245.034147)
			(xy 129.029274 -245.008701) (xy 129.07686 -244.990654) (xy 129.126724 -244.980474) (xy 129.177576 -244.978425)
			(xy 129.228097 -244.984559) (xy 129.276981 -244.998719) (xy 129.32296 -245.020536) (xy 129.364844 -245.049446)
			(xy 129.401548 -245.084701) (xy 129.432121 -245.125387) (xy 129.455772 -245.17045) (xy 129.471888 -245.218724)
			(xy 129.480052 -245.268958) (xy 129.480564 -245.294404) (xy 129.798838 -245.294404) (xy 129.802798 -245.24535)
			(xy 129.814575 -245.197566) (xy 129.833866 -245.15229) (xy 129.860169 -245.110694) (xy 129.892804 -245.073857)
			(xy 129.930925 -245.042732) (xy 129.973546 -245.018125) (xy 130.019562 -245.000673) (xy 130.067781 -244.990829)
			(xy 130.116956 -244.988848) (xy 130.165811 -244.99478) (xy 130.213082 -245.008472) (xy 130.257544 -245.02957)
			(xy 130.298047 -245.057526) (xy 130.33354 -245.091618) (xy 130.363105 -245.130962) (xy 130.385976 -245.174539)
			(xy 130.40156 -245.22122) (xy 130.409455 -245.269797) (xy 130.40995 -245.294404) (xy 130.728461 -245.294404)
			(xy 130.732556 -245.243676) (xy 130.744735 -245.194262) (xy 130.764683 -245.147442) (xy 130.791884 -245.104428)
			(xy 130.825632 -245.066334) (xy 130.865054 -245.034147) (xy 130.909128 -245.008701) (xy 130.956714 -244.990654)
			(xy 131.006578 -244.980474) (xy 131.05743 -244.978425) (xy 131.107951 -244.984559) (xy 131.156835 -244.998719)
			(xy 131.202814 -245.020536) (xy 131.244698 -245.049446) (xy 131.281402 -245.084701) (xy 131.311975 -245.125387)
			(xy 131.335626 -245.17045) (xy 131.351742 -245.218724) (xy 131.359906 -245.268958) (xy 131.360418 -245.294404)
			(xy 131.678946 -245.294404) (xy 131.682906 -245.24535) (xy 131.694683 -245.197566) (xy 131.713974 -245.15229)
			(xy 131.740277 -245.110694) (xy 131.772912 -245.073857) (xy 131.811033 -245.042732) (xy 131.853654 -245.018125)
			(xy 131.89967 -245.000673) (xy 131.947889 -244.990829) (xy 131.997064 -244.988848) (xy 132.045919 -244.99478)
			(xy 132.09319 -245.008472) (xy 132.137652 -245.02957) (xy 132.178155 -245.057526) (xy 132.213648 -245.091618)
			(xy 132.243213 -245.130962) (xy 132.266084 -245.174539) (xy 132.281668 -245.22122) (xy 132.289563 -245.269797)
			(xy 132.290058 -245.294404) (xy 132.608569 -245.294404) (xy 132.612664 -245.243676) (xy 132.624843 -245.194262)
			(xy 132.644791 -245.147442) (xy 132.671992 -245.104428) (xy 132.70574 -245.066334) (xy 132.745162 -245.034147)
			(xy 132.789236 -245.008701) (xy 132.836822 -244.990654) (xy 132.886686 -244.980474) (xy 132.937538 -244.978425)
			(xy 132.988059 -244.984559) (xy 133.036943 -244.998719) (xy 133.082922 -245.020536) (xy 133.124806 -245.049446)
			(xy 133.16151 -245.084701) (xy 133.192083 -245.125387) (xy 133.215734 -245.17045) (xy 133.23185 -245.218724)
			(xy 133.240014 -245.268958) (xy 133.240526 -245.294404) (xy 133.559054 -245.294404) (xy 133.563014 -245.24535)
			(xy 133.574791 -245.197566) (xy 133.594082 -245.15229) (xy 133.620385 -245.110694) (xy 133.65302 -245.073857)
			(xy 133.691141 -245.042732) (xy 133.733762 -245.018125) (xy 133.779778 -245.000673) (xy 133.827997 -244.990829)
			(xy 133.877172 -244.988848) (xy 133.926027 -244.99478) (xy 133.973298 -245.008472) (xy 134.01776 -245.02957)
			(xy 134.058263 -245.057526) (xy 134.093756 -245.091618) (xy 134.123321 -245.130962) (xy 134.146192 -245.174539)
			(xy 134.161776 -245.22122) (xy 134.169671 -245.269797) (xy 134.170166 -245.294404) (xy 134.498854 -245.294404)
			(xy 134.502814 -245.24535) (xy 134.514591 -245.197566) (xy 134.533882 -245.15229) (xy 134.560185 -245.110694)
			(xy 134.59282 -245.073857) (xy 134.630941 -245.042732) (xy 134.673562 -245.018125) (xy 134.719578 -245.000673)
			(xy 134.767797 -244.990829) (xy 134.816972 -244.988848) (xy 134.865827 -244.99478) (xy 134.913098 -245.008472)
			(xy 134.95756 -245.02957) (xy 134.998063 -245.057526) (xy 135.033556 -245.091618) (xy 135.063121 -245.130962)
			(xy 135.085992 -245.174539) (xy 135.101576 -245.22122) (xy 135.109471 -245.269797) (xy 135.109966 -245.294404)
			(xy 135.438908 -245.294404) (xy 135.442868 -245.24535) (xy 135.454645 -245.197566) (xy 135.473936 -245.15229)
			(xy 135.500239 -245.110694) (xy 135.532874 -245.073857) (xy 135.570995 -245.042732) (xy 135.613616 -245.018125)
			(xy 135.659632 -245.000673) (xy 135.707851 -244.990829) (xy 135.757026 -244.988848) (xy 135.805881 -244.99478)
			(xy 135.853152 -245.008472) (xy 135.897614 -245.02957) (xy 135.938117 -245.057526) (xy 135.97361 -245.091618)
			(xy 136.003175 -245.130962) (xy 136.026046 -245.174539) (xy 136.04163 -245.22122) (xy 136.049525 -245.269797)
			(xy 136.05002 -245.294404) (xy 136.378962 -245.294404) (xy 136.382922 -245.24535) (xy 136.394699 -245.197566)
			(xy 136.41399 -245.15229) (xy 136.440293 -245.110694) (xy 136.472928 -245.073857) (xy 136.511049 -245.042732)
			(xy 136.55367 -245.018125) (xy 136.599686 -245.000673) (xy 136.647905 -244.990829) (xy 136.69708 -244.988848)
			(xy 136.745935 -244.99478) (xy 136.793206 -245.008472) (xy 136.837668 -245.02957) (xy 136.878171 -245.057526)
			(xy 136.913664 -245.091618) (xy 136.943229 -245.130962) (xy 136.9661 -245.174539) (xy 136.981684 -245.22122)
			(xy 136.989579 -245.269797) (xy 136.990074 -245.294404) (xy 137.319016 -245.294404) (xy 137.322976 -245.24535)
			(xy 137.334753 -245.197566) (xy 137.354044 -245.15229) (xy 137.380347 -245.110694) (xy 137.412982 -245.073857)
			(xy 137.451103 -245.042732) (xy 137.493724 -245.018125) (xy 137.53974 -245.000673) (xy 137.587959 -244.990829)
			(xy 137.637134 -244.988848) (xy 137.685989 -244.99478) (xy 137.73326 -245.008472) (xy 137.777722 -245.02957)
			(xy 137.818225 -245.057526) (xy 137.853718 -245.091618) (xy 137.883283 -245.130962) (xy 137.906154 -245.174539)
			(xy 137.921738 -245.22122) (xy 137.929633 -245.269797) (xy 137.930128 -245.294404) (xy 138.25907 -245.294404)
			(xy 138.26303 -245.24535) (xy 138.274807 -245.197566) (xy 138.294098 -245.15229) (xy 138.320401 -245.110694)
			(xy 138.353036 -245.073857) (xy 138.391157 -245.042732) (xy 138.433778 -245.018125) (xy 138.479794 -245.000673)
			(xy 138.528013 -244.990829) (xy 138.577188 -244.988848) (xy 138.626043 -244.99478) (xy 138.673314 -245.008472)
			(xy 138.717776 -245.02957) (xy 138.758279 -245.057526) (xy 138.793772 -245.091618) (xy 138.823337 -245.130962)
			(xy 138.846208 -245.174539) (xy 138.861792 -245.22122) (xy 138.869687 -245.269797) (xy 138.870182 -245.294404)
			(xy 139.19887 -245.294404) (xy 139.20283 -245.24535) (xy 139.214607 -245.197566) (xy 139.233898 -245.15229)
			(xy 139.260201 -245.110694) (xy 139.292836 -245.073857) (xy 139.330957 -245.042732) (xy 139.373578 -245.018125)
			(xy 139.419594 -245.000673) (xy 139.467813 -244.990829) (xy 139.516988 -244.988848) (xy 139.565843 -244.99478)
			(xy 139.613114 -245.008472) (xy 139.657576 -245.02957) (xy 139.698079 -245.057526) (xy 139.733572 -245.091618)
			(xy 139.763137 -245.130962) (xy 139.786008 -245.174539) (xy 139.801592 -245.22122) (xy 139.809487 -245.269797)
			(xy 139.809982 -245.294404) (xy 139.809487 -245.319011) (xy 139.801592 -245.367588) (xy 139.786008 -245.414269)
			(xy 139.763137 -245.457846) (xy 139.733572 -245.49719) (xy 139.698079 -245.531282) (xy 139.657576 -245.559238)
			(xy 139.613114 -245.580336) (xy 139.565843 -245.594028) (xy 139.516988 -245.59996) (xy 139.467813 -245.597979)
			(xy 139.419594 -245.588135) (xy 139.373578 -245.570683) (xy 139.330957 -245.546076) (xy 139.292836 -245.514951)
			(xy 139.260201 -245.478114) (xy 139.233898 -245.436518) (xy 139.214607 -245.391242) (xy 139.20283 -245.343458)
			(xy 139.19887 -245.294404) (xy 138.870182 -245.294404) (xy 138.869687 -245.319011) (xy 138.861792 -245.367588)
			(xy 138.846208 -245.414269) (xy 138.823337 -245.457846) (xy 138.793772 -245.49719) (xy 138.758279 -245.531282)
			(xy 138.717776 -245.559238) (xy 138.673314 -245.580336) (xy 138.626043 -245.594028) (xy 138.577188 -245.59996)
			(xy 138.528013 -245.597979) (xy 138.479794 -245.588135) (xy 138.433778 -245.570683) (xy 138.391157 -245.546076)
			(xy 138.353036 -245.514951) (xy 138.320401 -245.478114) (xy 138.294098 -245.436518) (xy 138.274807 -245.391242)
			(xy 138.26303 -245.343458) (xy 138.25907 -245.294404) (xy 137.930128 -245.294404) (xy 137.929633 -245.319011)
			(xy 137.921738 -245.367588) (xy 137.906154 -245.414269) (xy 137.883283 -245.457846) (xy 137.853718 -245.49719)
			(xy 137.818225 -245.531282) (xy 137.777722 -245.559238) (xy 137.73326 -245.580336) (xy 137.685989 -245.594028)
			(xy 137.637134 -245.59996) (xy 137.587959 -245.597979) (xy 137.53974 -245.588135) (xy 137.493724 -245.570683)
			(xy 137.451103 -245.546076) (xy 137.412982 -245.514951) (xy 137.380347 -245.478114) (xy 137.354044 -245.436518)
			(xy 137.334753 -245.391242) (xy 137.322976 -245.343458) (xy 137.319016 -245.294404) (xy 136.990074 -245.294404)
			(xy 136.989579 -245.319011) (xy 136.981684 -245.367588) (xy 136.9661 -245.414269) (xy 136.943229 -245.457846)
			(xy 136.913664 -245.49719) (xy 136.878171 -245.531282) (xy 136.837668 -245.559238) (xy 136.793206 -245.580336)
			(xy 136.745935 -245.594028) (xy 136.69708 -245.59996) (xy 136.647905 -245.597979) (xy 136.599686 -245.588135)
			(xy 136.55367 -245.570683) (xy 136.511049 -245.546076) (xy 136.472928 -245.514951) (xy 136.440293 -245.478114)
			(xy 136.41399 -245.436518) (xy 136.394699 -245.391242) (xy 136.382922 -245.343458) (xy 136.378962 -245.294404)
			(xy 136.05002 -245.294404) (xy 136.049525 -245.319011) (xy 136.04163 -245.367588) (xy 136.026046 -245.414269)
			(xy 136.003175 -245.457846) (xy 135.97361 -245.49719) (xy 135.938117 -245.531282) (xy 135.897614 -245.559238)
			(xy 135.853152 -245.580336) (xy 135.805881 -245.594028) (xy 135.757026 -245.59996) (xy 135.707851 -245.597979)
			(xy 135.659632 -245.588135) (xy 135.613616 -245.570683) (xy 135.570995 -245.546076) (xy 135.532874 -245.514951)
			(xy 135.500239 -245.478114) (xy 135.473936 -245.436518) (xy 135.454645 -245.391242) (xy 135.442868 -245.343458)
			(xy 135.438908 -245.294404) (xy 135.109966 -245.294404) (xy 135.109471 -245.319011) (xy 135.101576 -245.367588)
			(xy 135.085992 -245.414269) (xy 135.063121 -245.457846) (xy 135.033556 -245.49719) (xy 134.998063 -245.531282)
			(xy 134.95756 -245.559238) (xy 134.913098 -245.580336) (xy 134.865827 -245.594028) (xy 134.816972 -245.59996)
			(xy 134.767797 -245.597979) (xy 134.719578 -245.588135) (xy 134.673562 -245.570683) (xy 134.630941 -245.546076)
			(xy 134.59282 -245.514951) (xy 134.560185 -245.478114) (xy 134.533882 -245.436518) (xy 134.514591 -245.391242)
			(xy 134.502814 -245.343458) (xy 134.498854 -245.294404) (xy 134.170166 -245.294404) (xy 134.169671 -245.319011)
			(xy 134.161776 -245.367588) (xy 134.146192 -245.414269) (xy 134.123321 -245.457846) (xy 134.093756 -245.49719)
			(xy 134.058263 -245.531282) (xy 134.01776 -245.559238) (xy 133.973298 -245.580336) (xy 133.926027 -245.594028)
			(xy 133.877172 -245.59996) (xy 133.827997 -245.597979) (xy 133.779778 -245.588135) (xy 133.733762 -245.570683)
			(xy 133.691141 -245.546076) (xy 133.65302 -245.514951) (xy 133.620385 -245.478114) (xy 133.594082 -245.436518)
			(xy 133.574791 -245.391242) (xy 133.563014 -245.343458) (xy 133.559054 -245.294404) (xy 133.240526 -245.294404)
			(xy 133.240014 -245.31985) (xy 133.23185 -245.370084) (xy 133.215734 -245.418358) (xy 133.192083 -245.463421)
			(xy 133.16151 -245.504107) (xy 133.124806 -245.539362) (xy 133.082922 -245.568272) (xy 133.036943 -245.590089)
			(xy 132.988059 -245.604249) (xy 132.937538 -245.610383) (xy 132.886686 -245.608334) (xy 132.836822 -245.598154)
			(xy 132.789236 -245.580107) (xy 132.745162 -245.554661) (xy 132.70574 -245.522474) (xy 132.671992 -245.48438)
			(xy 132.644791 -245.441366) (xy 132.624843 -245.394546) (xy 132.612664 -245.345132) (xy 132.608569 -245.294404)
			(xy 132.290058 -245.294404) (xy 132.289563 -245.319011) (xy 132.281668 -245.367588) (xy 132.266084 -245.414269)
			(xy 132.243213 -245.457846) (xy 132.213648 -245.49719) (xy 132.178155 -245.531282) (xy 132.137652 -245.559238)
			(xy 132.09319 -245.580336) (xy 132.045919 -245.594028) (xy 131.997064 -245.59996) (xy 131.947889 -245.597979)
			(xy 131.89967 -245.588135) (xy 131.853654 -245.570683) (xy 131.811033 -245.546076) (xy 131.772912 -245.514951)
			(xy 131.740277 -245.478114) (xy 131.713974 -245.436518) (xy 131.694683 -245.391242) (xy 131.682906 -245.343458)
			(xy 131.678946 -245.294404) (xy 131.360418 -245.294404) (xy 131.359906 -245.31985) (xy 131.351742 -245.370084)
			(xy 131.335626 -245.418358) (xy 131.311975 -245.463421) (xy 131.281402 -245.504107) (xy 131.244698 -245.539362)
			(xy 131.202814 -245.568272) (xy 131.156835 -245.590089) (xy 131.107951 -245.604249) (xy 131.05743 -245.610383)
			(xy 131.006578 -245.608334) (xy 130.956714 -245.598154) (xy 130.909128 -245.580107) (xy 130.865054 -245.554661)
			(xy 130.825632 -245.522474) (xy 130.791884 -245.48438) (xy 130.764683 -245.441366) (xy 130.744735 -245.394546)
			(xy 130.732556 -245.345132) (xy 130.728461 -245.294404) (xy 130.40995 -245.294404) (xy 130.409455 -245.319011)
			(xy 130.40156 -245.367588) (xy 130.385976 -245.414269) (xy 130.363105 -245.457846) (xy 130.33354 -245.49719)
			(xy 130.298047 -245.531282) (xy 130.257544 -245.559238) (xy 130.213082 -245.580336) (xy 130.165811 -245.594028)
			(xy 130.116956 -245.59996) (xy 130.067781 -245.597979) (xy 130.019562 -245.588135) (xy 129.973546 -245.570683)
			(xy 129.930925 -245.546076) (xy 129.892804 -245.514951) (xy 129.860169 -245.478114) (xy 129.833866 -245.436518)
			(xy 129.814575 -245.391242) (xy 129.802798 -245.343458) (xy 129.798838 -245.294404) (xy 129.480564 -245.294404)
			(xy 129.480052 -245.31985) (xy 129.471888 -245.370084) (xy 129.455772 -245.418358) (xy 129.432121 -245.463421)
			(xy 129.401548 -245.504107) (xy 129.364844 -245.539362) (xy 129.32296 -245.568272) (xy 129.276981 -245.590089)
			(xy 129.228097 -245.604249) (xy 129.177576 -245.610383) (xy 129.126724 -245.608334) (xy 129.07686 -245.598154)
			(xy 129.029274 -245.580107) (xy 128.9852 -245.554661) (xy 128.945778 -245.522474) (xy 128.91203 -245.48438)
			(xy 128.884829 -245.441366) (xy 128.864881 -245.394546) (xy 128.852702 -245.345132) (xy 128.848607 -245.294404)
			(xy 128.54051 -245.294404) (xy 128.539998 -245.31985) (xy 128.531834 -245.370084) (xy 128.515718 -245.418358)
			(xy 128.492067 -245.463421) (xy 128.461494 -245.504107) (xy 128.42479 -245.539362) (xy 128.382906 -245.568272)
			(xy 128.336927 -245.590089) (xy 128.288043 -245.604249) (xy 128.237522 -245.610383) (xy 128.18667 -245.608334)
			(xy 128.136806 -245.598154) (xy 128.08922 -245.580107) (xy 128.045146 -245.554661) (xy 128.005724 -245.522474)
			(xy 127.971976 -245.48438) (xy 127.944775 -245.441366) (xy 127.924827 -245.394546) (xy 127.912648 -245.345132)
			(xy 127.908553 -245.294404) (xy 127.590527 -245.294404) (xy 127.586357 -245.344734) (xy 127.573959 -245.393695)
			(xy 127.553672 -245.439948) (xy 127.526049 -245.482232) (xy 127.491844 -245.519392) (xy 127.45199 -245.550416)
			(xy 127.407572 -245.574458) (xy 127.359804 -245.590862) (xy 127.309987 -245.59918) (xy 127.284734 -245.599712)
			(xy 127.271971 -245.599576) (xy 127.246536 -245.597418) (xy 127.233934 -245.595394) (xy 127.233934 -245.595648)
			(xy 127.211262 -245.591394) (xy 127.167446 -245.576972) (xy 127.126292 -245.556138) (xy 127.08873 -245.529363)
			(xy 127.071882 -245.513606) (xy 127.071374 -245.513098) (xy 127.065875 -245.508111) (xy 127.052708 -245.501267)
			(xy 127.045466 -245.499636) (xy 127.038354 -245.498366) (xy 127.023876 -245.49989) (xy 126.92761 -245.54053)
			(xy 126.919646 -245.544913) (xy 126.907221 -245.558164) (xy 126.900172 -245.574906) (xy 126.899416 -245.583964)
			(xy 126.899416 -245.774972) (xy 126.899688 -245.782529) (xy 126.904065 -245.796996) (xy 126.908052 -245.80342)
			(xy 126.91237 -245.80977) (xy 126.9238 -245.818914) (xy 126.930912 -245.821962) (xy 126.952987 -245.831524)
			(xy 126.994061 -245.856565) (xy 127.030701 -245.887735) (xy 127.062001 -245.924265) (xy 127.087186 -245.96525)
			(xy 127.105634 -246.009678) (xy 127.116888 -246.056448) (xy 127.12067 -246.104404) (xy 127.12067 -246.10441)
			(xy 127.438399 -246.10441) (xy 127.442494 -246.053682) (xy 127.454673 -246.004268) (xy 127.474621 -245.957448)
			(xy 127.501822 -245.914434) (xy 127.53557 -245.87634) (xy 127.574992 -245.844153) (xy 127.619066 -245.818707)
			(xy 127.666652 -245.80066) (xy 127.716516 -245.79048) (xy 127.767368 -245.788431) (xy 127.817889 -245.794565)
			(xy 127.866773 -245.808725) (xy 127.912752 -245.830542) (xy 127.954636 -245.859452) (xy 127.99134 -245.894707)
			(xy 128.021913 -245.935393) (xy 128.045564 -245.980456) (xy 128.06168 -246.02873) (xy 128.069844 -246.078964)
			(xy 128.070356 -246.10441) (xy 128.388884 -246.10441) (xy 128.392844 -246.055356) (xy 128.404621 -246.007572)
			(xy 128.423912 -245.962296) (xy 128.450215 -245.9207) (xy 128.48285 -245.883863) (xy 128.520971 -245.852738)
			(xy 128.563592 -245.828131) (xy 128.609608 -245.810679) (xy 128.657827 -245.800835) (xy 128.707002 -245.798854)
			(xy 128.755857 -245.804786) (xy 128.803128 -245.818478) (xy 128.84759 -245.839576) (xy 128.888093 -245.867532)
			(xy 128.923586 -245.901624) (xy 128.953151 -245.940968) (xy 128.976022 -245.984545) (xy 128.991606 -246.031226)
			(xy 128.999501 -246.079803) (xy 128.999996 -246.10441) (xy 129.318507 -246.10441) (xy 129.322602 -246.053682)
			(xy 129.334781 -246.004268) (xy 129.354729 -245.957448) (xy 129.38193 -245.914434) (xy 129.415678 -245.87634)
			(xy 129.4551 -245.844153) (xy 129.499174 -245.818707) (xy 129.54676 -245.80066) (xy 129.596624 -245.79048)
			(xy 129.647476 -245.788431) (xy 129.697997 -245.794565) (xy 129.746881 -245.808725) (xy 129.79286 -245.830542)
			(xy 129.834744 -245.859452) (xy 129.871448 -245.894707) (xy 129.902021 -245.935393) (xy 129.925672 -245.980456)
			(xy 129.941788 -246.02873) (xy 129.949952 -246.078964) (xy 129.950464 -246.10441) (xy 130.268992 -246.10441)
			(xy 130.272952 -246.055356) (xy 130.284729 -246.007572) (xy 130.30402 -245.962296) (xy 130.330323 -245.9207)
			(xy 130.362958 -245.883863) (xy 130.401079 -245.852738) (xy 130.4437 -245.828131) (xy 130.489716 -245.810679)
			(xy 130.537935 -245.800835) (xy 130.58711 -245.798854) (xy 130.635965 -245.804786) (xy 130.683236 -245.818478)
			(xy 130.727698 -245.839576) (xy 130.768201 -245.867532) (xy 130.803694 -245.901624) (xy 130.833259 -245.940968)
			(xy 130.85613 -245.984545) (xy 130.871714 -246.031226) (xy 130.879609 -246.079803) (xy 130.880104 -246.10441)
			(xy 131.198615 -246.10441) (xy 131.20271 -246.053682) (xy 131.214889 -246.004268) (xy 131.234837 -245.957448)
			(xy 131.262038 -245.914434) (xy 131.295786 -245.87634) (xy 131.335208 -245.844153) (xy 131.379282 -245.818707)
			(xy 131.426868 -245.80066) (xy 131.476732 -245.79048) (xy 131.527584 -245.788431) (xy 131.578105 -245.794565)
			(xy 131.626989 -245.808725) (xy 131.672968 -245.830542) (xy 131.714852 -245.859452) (xy 131.751556 -245.894707)
			(xy 131.782129 -245.935393) (xy 131.80578 -245.980456) (xy 131.821896 -246.02873) (xy 131.83006 -246.078964)
			(xy 131.830572 -246.10441) (xy 132.138415 -246.10441) (xy 132.14251 -246.053682) (xy 132.154689 -246.004268)
			(xy 132.174637 -245.957448) (xy 132.201838 -245.914434) (xy 132.235586 -245.87634) (xy 132.275008 -245.844153)
			(xy 132.319082 -245.818707) (xy 132.366668 -245.80066) (xy 132.416532 -245.79048) (xy 132.467384 -245.788431)
			(xy 132.517905 -245.794565) (xy 132.566789 -245.808725) (xy 132.612768 -245.830542) (xy 132.654652 -245.859452)
			(xy 132.691356 -245.894707) (xy 132.721929 -245.935393) (xy 132.74558 -245.980456) (xy 132.761696 -246.02873)
			(xy 132.76986 -246.078964) (xy 132.770372 -246.10441) (xy 133.0889 -246.10441) (xy 133.09286 -246.055356)
			(xy 133.104637 -246.007572) (xy 133.123928 -245.962296) (xy 133.150231 -245.9207) (xy 133.182866 -245.883863)
			(xy 133.220987 -245.852738) (xy 133.263608 -245.828131) (xy 133.309624 -245.810679) (xy 133.357843 -245.800835)
			(xy 133.407018 -245.798854) (xy 133.455873 -245.804786) (xy 133.503144 -245.818478) (xy 133.547606 -245.839576)
			(xy 133.588109 -245.867532) (xy 133.623602 -245.901624) (xy 133.653167 -245.940968) (xy 133.676038 -245.984545)
			(xy 133.691622 -246.031226) (xy 133.699517 -246.079803) (xy 133.700012 -246.10441) (xy 134.028954 -246.10441)
			(xy 134.032914 -246.055356) (xy 134.044691 -246.007572) (xy 134.063982 -245.962296) (xy 134.090285 -245.9207)
			(xy 134.12292 -245.883863) (xy 134.161041 -245.852738) (xy 134.203662 -245.828131) (xy 134.249678 -245.810679)
			(xy 134.297897 -245.800835) (xy 134.347072 -245.798854) (xy 134.395927 -245.804786) (xy 134.443198 -245.818478)
			(xy 134.48766 -245.839576) (xy 134.528163 -245.867532) (xy 134.563656 -245.901624) (xy 134.593221 -245.940968)
			(xy 134.616092 -245.984545) (xy 134.631676 -246.031226) (xy 134.639571 -246.079803) (xy 134.640066 -246.10441)
			(xy 134.969008 -246.10441) (xy 134.972968 -246.055356) (xy 134.984745 -246.007572) (xy 135.004036 -245.962296)
			(xy 135.030339 -245.9207) (xy 135.062974 -245.883863) (xy 135.101095 -245.852738) (xy 135.143716 -245.828131)
			(xy 135.189732 -245.810679) (xy 135.237951 -245.800835) (xy 135.287126 -245.798854) (xy 135.335981 -245.804786)
			(xy 135.383252 -245.818478) (xy 135.427714 -245.839576) (xy 135.468217 -245.867532) (xy 135.50371 -245.901624)
			(xy 135.533275 -245.940968) (xy 135.556146 -245.984545) (xy 135.57173 -246.031226) (xy 135.579625 -246.079803)
			(xy 135.58012 -246.10441) (xy 135.909062 -246.10441) (xy 135.913022 -246.055356) (xy 135.924799 -246.007572)
			(xy 135.94409 -245.962296) (xy 135.970393 -245.9207) (xy 136.003028 -245.883863) (xy 136.041149 -245.852738)
			(xy 136.08377 -245.828131) (xy 136.129786 -245.810679) (xy 136.178005 -245.800835) (xy 136.22718 -245.798854)
			(xy 136.276035 -245.804786) (xy 136.323306 -245.818478) (xy 136.367768 -245.839576) (xy 136.408271 -245.867532)
			(xy 136.443764 -245.901624) (xy 136.473329 -245.940968) (xy 136.4962 -245.984545) (xy 136.511784 -246.031226)
			(xy 136.519679 -246.079803) (xy 136.520174 -246.10441) (xy 136.848862 -246.10441) (xy 136.852822 -246.055356)
			(xy 136.864599 -246.007572) (xy 136.88389 -245.962296) (xy 136.910193 -245.9207) (xy 136.942828 -245.883863)
			(xy 136.980949 -245.852738) (xy 137.02357 -245.828131) (xy 137.069586 -245.810679) (xy 137.117805 -245.800835)
			(xy 137.16698 -245.798854) (xy 137.215835 -245.804786) (xy 137.263106 -245.818478) (xy 137.307568 -245.839576)
			(xy 137.348071 -245.867532) (xy 137.383564 -245.901624) (xy 137.413129 -245.940968) (xy 137.436 -245.984545)
			(xy 137.451584 -246.031226) (xy 137.459479 -246.079803) (xy 137.459974 -246.10441) (xy 137.788916 -246.10441)
			(xy 137.792876 -246.055356) (xy 137.804653 -246.007572) (xy 137.823944 -245.962296) (xy 137.850247 -245.9207)
			(xy 137.882882 -245.883863) (xy 137.921003 -245.852738) (xy 137.963624 -245.828131) (xy 138.00964 -245.810679)
			(xy 138.057859 -245.800835) (xy 138.107034 -245.798854) (xy 138.155889 -245.804786) (xy 138.20316 -245.818478)
			(xy 138.247622 -245.839576) (xy 138.288125 -245.867532) (xy 138.323618 -245.901624) (xy 138.353183 -245.940968)
			(xy 138.376054 -245.984545) (xy 138.391638 -246.031226) (xy 138.399533 -246.079803) (xy 138.400028 -246.10441)
			(xy 138.72897 -246.10441) (xy 138.73293 -246.055356) (xy 138.744707 -246.007572) (xy 138.763998 -245.962296)
			(xy 138.790301 -245.9207) (xy 138.822936 -245.883863) (xy 138.861057 -245.852738) (xy 138.903678 -245.828131)
			(xy 138.949694 -245.810679) (xy 138.997913 -245.800835) (xy 139.047088 -245.798854) (xy 139.095943 -245.804786)
			(xy 139.143214 -245.818478) (xy 139.187676 -245.839576) (xy 139.228179 -245.867532) (xy 139.263672 -245.901624)
			(xy 139.293237 -245.940968) (xy 139.316108 -245.984545) (xy 139.331692 -246.031226) (xy 139.339587 -246.079803)
			(xy 139.340082 -246.10441) (xy 139.339587 -246.129017) (xy 139.331692 -246.177594) (xy 139.316108 -246.224275)
			(xy 139.293237 -246.267852) (xy 139.263672 -246.307196) (xy 139.228179 -246.341288) (xy 139.187676 -246.369244)
			(xy 139.143214 -246.390342) (xy 139.095943 -246.404034) (xy 139.047088 -246.409966) (xy 138.997913 -246.407985)
			(xy 138.949694 -246.398141) (xy 138.903678 -246.380689) (xy 138.861057 -246.356082) (xy 138.822936 -246.324957)
			(xy 138.790301 -246.28812) (xy 138.763998 -246.246524) (xy 138.744707 -246.201248) (xy 138.73293 -246.153464)
			(xy 138.72897 -246.10441) (xy 138.400028 -246.10441) (xy 138.399533 -246.129017) (xy 138.391638 -246.177594)
			(xy 138.376054 -246.224275) (xy 138.353183 -246.267852) (xy 138.323618 -246.307196) (xy 138.288125 -246.341288)
			(xy 138.247622 -246.369244) (xy 138.20316 -246.390342) (xy 138.155889 -246.404034) (xy 138.107034 -246.409966)
			(xy 138.057859 -246.407985) (xy 138.00964 -246.398141) (xy 137.963624 -246.380689) (xy 137.921003 -246.356082)
			(xy 137.882882 -246.324957) (xy 137.850247 -246.28812) (xy 137.823944 -246.246524) (xy 137.804653 -246.201248)
			(xy 137.792876 -246.153464) (xy 137.788916 -246.10441) (xy 137.459974 -246.10441) (xy 137.459479 -246.129017)
			(xy 137.451584 -246.177594) (xy 137.436 -246.224275) (xy 137.413129 -246.267852) (xy 137.383564 -246.307196)
			(xy 137.348071 -246.341288) (xy 137.307568 -246.369244) (xy 137.263106 -246.390342) (xy 137.215835 -246.404034)
			(xy 137.16698 -246.409966) (xy 137.117805 -246.407985) (xy 137.069586 -246.398141) (xy 137.02357 -246.380689)
			(xy 136.980949 -246.356082) (xy 136.942828 -246.324957) (xy 136.910193 -246.28812) (xy 136.88389 -246.246524)
			(xy 136.864599 -246.201248) (xy 136.852822 -246.153464) (xy 136.848862 -246.10441) (xy 136.520174 -246.10441)
			(xy 136.519679 -246.129017) (xy 136.511784 -246.177594) (xy 136.4962 -246.224275) (xy 136.473329 -246.267852)
			(xy 136.443764 -246.307196) (xy 136.408271 -246.341288) (xy 136.367768 -246.369244) (xy 136.323306 -246.390342)
			(xy 136.276035 -246.404034) (xy 136.22718 -246.409966) (xy 136.178005 -246.407985) (xy 136.129786 -246.398141)
			(xy 136.08377 -246.380689) (xy 136.041149 -246.356082) (xy 136.003028 -246.324957) (xy 135.970393 -246.28812)
			(xy 135.94409 -246.246524) (xy 135.924799 -246.201248) (xy 135.913022 -246.153464) (xy 135.909062 -246.10441)
			(xy 135.58012 -246.10441) (xy 135.579625 -246.129017) (xy 135.57173 -246.177594) (xy 135.556146 -246.224275)
			(xy 135.533275 -246.267852) (xy 135.50371 -246.307196) (xy 135.468217 -246.341288) (xy 135.427714 -246.369244)
			(xy 135.383252 -246.390342) (xy 135.335981 -246.404034) (xy 135.287126 -246.409966) (xy 135.237951 -246.407985)
			(xy 135.189732 -246.398141) (xy 135.143716 -246.380689) (xy 135.101095 -246.356082) (xy 135.062974 -246.324957)
			(xy 135.030339 -246.28812) (xy 135.004036 -246.246524) (xy 134.984745 -246.201248) (xy 134.972968 -246.153464)
			(xy 134.969008 -246.10441) (xy 134.640066 -246.10441) (xy 134.639571 -246.129017) (xy 134.631676 -246.177594)
			(xy 134.616092 -246.224275) (xy 134.593221 -246.267852) (xy 134.563656 -246.307196) (xy 134.528163 -246.341288)
			(xy 134.48766 -246.369244) (xy 134.443198 -246.390342) (xy 134.395927 -246.404034) (xy 134.347072 -246.409966)
			(xy 134.297897 -246.407985) (xy 134.249678 -246.398141) (xy 134.203662 -246.380689) (xy 134.161041 -246.356082)
			(xy 134.12292 -246.324957) (xy 134.090285 -246.28812) (xy 134.063982 -246.246524) (xy 134.044691 -246.201248)
			(xy 134.032914 -246.153464) (xy 134.028954 -246.10441) (xy 133.700012 -246.10441) (xy 133.699517 -246.129017)
			(xy 133.691622 -246.177594) (xy 133.676038 -246.224275) (xy 133.653167 -246.267852) (xy 133.623602 -246.307196)
			(xy 133.588109 -246.341288) (xy 133.547606 -246.369244) (xy 133.503144 -246.390342) (xy 133.455873 -246.404034)
			(xy 133.407018 -246.409966) (xy 133.357843 -246.407985) (xy 133.309624 -246.398141) (xy 133.263608 -246.380689)
			(xy 133.220987 -246.356082) (xy 133.182866 -246.324957) (xy 133.150231 -246.28812) (xy 133.123928 -246.246524)
			(xy 133.104637 -246.201248) (xy 133.09286 -246.153464) (xy 133.0889 -246.10441) (xy 132.770372 -246.10441)
			(xy 132.76986 -246.129856) (xy 132.761696 -246.18009) (xy 132.74558 -246.228364) (xy 132.721929 -246.273427)
			(xy 132.691356 -246.314113) (xy 132.654652 -246.349368) (xy 132.612768 -246.378278) (xy 132.566789 -246.400095)
			(xy 132.517905 -246.414255) (xy 132.467384 -246.420389) (xy 132.416532 -246.41834) (xy 132.366668 -246.40816)
			(xy 132.319082 -246.390113) (xy 132.275008 -246.364667) (xy 132.235586 -246.33248) (xy 132.201838 -246.294386)
			(xy 132.174637 -246.251372) (xy 132.154689 -246.204552) (xy 132.14251 -246.155138) (xy 132.138415 -246.10441)
			(xy 131.830572 -246.10441) (xy 131.83006 -246.129856) (xy 131.821896 -246.18009) (xy 131.80578 -246.228364)
			(xy 131.782129 -246.273427) (xy 131.751556 -246.314113) (xy 131.714852 -246.349368) (xy 131.672968 -246.378278)
			(xy 131.626989 -246.400095) (xy 131.578105 -246.414255) (xy 131.527584 -246.420389) (xy 131.476732 -246.41834)
			(xy 131.426868 -246.40816) (xy 131.379282 -246.390113) (xy 131.335208 -246.364667) (xy 131.295786 -246.33248)
			(xy 131.262038 -246.294386) (xy 131.234837 -246.251372) (xy 131.214889 -246.204552) (xy 131.20271 -246.155138)
			(xy 131.198615 -246.10441) (xy 130.880104 -246.10441) (xy 130.879609 -246.129017) (xy 130.871714 -246.177594)
			(xy 130.85613 -246.224275) (xy 130.833259 -246.267852) (xy 130.803694 -246.307196) (xy 130.768201 -246.341288)
			(xy 130.727698 -246.369244) (xy 130.683236 -246.390342) (xy 130.635965 -246.404034) (xy 130.58711 -246.409966)
			(xy 130.537935 -246.407985) (xy 130.489716 -246.398141) (xy 130.4437 -246.380689) (xy 130.401079 -246.356082)
			(xy 130.362958 -246.324957) (xy 130.330323 -246.28812) (xy 130.30402 -246.246524) (xy 130.284729 -246.201248)
			(xy 130.272952 -246.153464) (xy 130.268992 -246.10441) (xy 129.950464 -246.10441) (xy 129.949952 -246.129856)
			(xy 129.941788 -246.18009) (xy 129.925672 -246.228364) (xy 129.902021 -246.273427) (xy 129.871448 -246.314113)
			(xy 129.834744 -246.349368) (xy 129.79286 -246.378278) (xy 129.746881 -246.400095) (xy 129.697997 -246.414255)
			(xy 129.647476 -246.420389) (xy 129.596624 -246.41834) (xy 129.54676 -246.40816) (xy 129.499174 -246.390113)
			(xy 129.4551 -246.364667) (xy 129.415678 -246.33248) (xy 129.38193 -246.294386) (xy 129.354729 -246.251372)
			(xy 129.334781 -246.204552) (xy 129.322602 -246.155138) (xy 129.318507 -246.10441) (xy 128.999996 -246.10441)
			(xy 128.999501 -246.129017) (xy 128.991606 -246.177594) (xy 128.976022 -246.224275) (xy 128.953151 -246.267852)
			(xy 128.923586 -246.307196) (xy 128.888093 -246.341288) (xy 128.84759 -246.369244) (xy 128.803128 -246.390342)
			(xy 128.755857 -246.404034) (xy 128.707002 -246.409966) (xy 128.657827 -246.407985) (xy 128.609608 -246.398141)
			(xy 128.563592 -246.380689) (xy 128.520971 -246.356082) (xy 128.48285 -246.324957) (xy 128.450215 -246.28812)
			(xy 128.423912 -246.246524) (xy 128.404621 -246.201248) (xy 128.392844 -246.153464) (xy 128.388884 -246.10441)
			(xy 128.070356 -246.10441) (xy 128.069844 -246.129856) (xy 128.06168 -246.18009) (xy 128.045564 -246.228364)
			(xy 128.021913 -246.273427) (xy 127.99134 -246.314113) (xy 127.954636 -246.349368) (xy 127.912752 -246.378278)
			(xy 127.866773 -246.400095) (xy 127.817889 -246.414255) (xy 127.767368 -246.420389) (xy 127.716516 -246.41834)
			(xy 127.666652 -246.40816) (xy 127.619066 -246.390113) (xy 127.574992 -246.364667) (xy 127.53557 -246.33248)
			(xy 127.501822 -246.294386) (xy 127.474621 -246.251372) (xy 127.454673 -246.204552) (xy 127.442494 -246.155138)
			(xy 127.438399 -246.10441) (xy 127.12067 -246.10441) (xy 127.116887 -246.15236) (xy 127.105632 -246.19913)
			(xy 127.087182 -246.243556) (xy 127.061996 -246.284541) (xy 127.030695 -246.32107) (xy 126.994055 -246.35224)
			(xy 126.95298 -246.377279) (xy 126.930912 -246.386858) (xy 126.9238 -246.389906) (xy 126.91237 -246.39905)
			(xy 126.908052 -246.4054) (xy 126.904029 -246.411808) (xy 126.899648 -246.426284) (xy 126.899416 -246.433848)
			(xy 126.899416 -246.914416) (xy 127.908553 -246.914416) (xy 127.912648 -246.863688) (xy 127.924827 -246.814274)
			(xy 127.944775 -246.767454) (xy 127.971976 -246.72444) (xy 128.005724 -246.686346) (xy 128.045146 -246.654159)
			(xy 128.08922 -246.628713) (xy 128.136806 -246.610666) (xy 128.18667 -246.600486) (xy 128.237522 -246.598437)
			(xy 128.288043 -246.604571) (xy 128.336927 -246.618731) (xy 128.382906 -246.640548) (xy 128.42479 -246.669458)
			(xy 128.461494 -246.704713) (xy 128.492067 -246.745399) (xy 128.515718 -246.790462) (xy 128.531834 -246.838736)
			(xy 128.539998 -246.88897) (xy 128.54051 -246.914416) (xy 128.848607 -246.914416) (xy 128.852702 -246.863688)
			(xy 128.864881 -246.814274) (xy 128.884829 -246.767454) (xy 128.91203 -246.72444) (xy 128.945778 -246.686346)
			(xy 128.9852 -246.654159) (xy 129.029274 -246.628713) (xy 129.07686 -246.610666) (xy 129.126724 -246.600486)
			(xy 129.177576 -246.598437) (xy 129.228097 -246.604571) (xy 129.276981 -246.618731) (xy 129.32296 -246.640548)
			(xy 129.364844 -246.669458) (xy 129.401548 -246.704713) (xy 129.432121 -246.745399) (xy 129.455772 -246.790462)
			(xy 129.471888 -246.838736) (xy 129.480052 -246.88897) (xy 129.480564 -246.914416) (xy 130.728461 -246.914416)
			(xy 130.732556 -246.863688) (xy 130.744735 -246.814274) (xy 130.764683 -246.767454) (xy 130.791884 -246.72444)
			(xy 130.825632 -246.686346) (xy 130.865054 -246.654159) (xy 130.909128 -246.628713) (xy 130.956714 -246.610666)
			(xy 131.006578 -246.600486) (xy 131.05743 -246.598437) (xy 131.107951 -246.604571) (xy 131.156835 -246.618731)
			(xy 131.202814 -246.640548) (xy 131.244698 -246.669458) (xy 131.281402 -246.704713) (xy 131.311975 -246.745399)
			(xy 131.335626 -246.790462) (xy 131.351742 -246.838736) (xy 131.359906 -246.88897) (xy 131.360418 -246.914416)
			(xy 131.678946 -246.914416) (xy 131.682906 -246.865362) (xy 131.694683 -246.817578) (xy 131.713974 -246.772302)
			(xy 131.740277 -246.730706) (xy 131.772912 -246.693869) (xy 131.811033 -246.662744) (xy 131.853654 -246.638137)
			(xy 131.89967 -246.620685) (xy 131.947889 -246.610841) (xy 131.997064 -246.60886) (xy 132.045919 -246.614792)
			(xy 132.09319 -246.628484) (xy 132.137652 -246.649582) (xy 132.178155 -246.677538) (xy 132.213648 -246.71163)
			(xy 132.243213 -246.750974) (xy 132.266084 -246.794551) (xy 132.281668 -246.841232) (xy 132.289563 -246.889809)
			(xy 132.290058 -246.914416) (xy 132.608569 -246.914416) (xy 132.612664 -246.863688) (xy 132.624843 -246.814274)
			(xy 132.644791 -246.767454) (xy 132.671992 -246.72444) (xy 132.70574 -246.686346) (xy 132.745162 -246.654159)
			(xy 132.789236 -246.628713) (xy 132.836822 -246.610666) (xy 132.886686 -246.600486) (xy 132.937538 -246.598437)
			(xy 132.988059 -246.604571) (xy 133.036943 -246.618731) (xy 133.082922 -246.640548) (xy 133.124806 -246.669458)
			(xy 133.16151 -246.704713) (xy 133.192083 -246.745399) (xy 133.215734 -246.790462) (xy 133.23185 -246.838736)
			(xy 133.240014 -246.88897) (xy 133.240526 -246.914416) (xy 133.559054 -246.914416) (xy 133.563014 -246.865362)
			(xy 133.574791 -246.817578) (xy 133.594082 -246.772302) (xy 133.620385 -246.730706) (xy 133.65302 -246.693869)
			(xy 133.691141 -246.662744) (xy 133.733762 -246.638137) (xy 133.779778 -246.620685) (xy 133.827997 -246.610841)
			(xy 133.877172 -246.60886) (xy 133.926027 -246.614792) (xy 133.973298 -246.628484) (xy 134.01776 -246.649582)
			(xy 134.058263 -246.677538) (xy 134.093756 -246.71163) (xy 134.123321 -246.750974) (xy 134.146192 -246.794551)
			(xy 134.161776 -246.841232) (xy 134.169671 -246.889809) (xy 134.170166 -246.914416) (xy 134.498854 -246.914416)
			(xy 134.502814 -246.865362) (xy 134.514591 -246.817578) (xy 134.533882 -246.772302) (xy 134.560185 -246.730706)
			(xy 134.59282 -246.693869) (xy 134.630941 -246.662744) (xy 134.673562 -246.638137) (xy 134.719578 -246.620685)
			(xy 134.767797 -246.610841) (xy 134.816972 -246.60886) (xy 134.865827 -246.614792) (xy 134.913098 -246.628484)
			(xy 134.95756 -246.649582) (xy 134.998063 -246.677538) (xy 135.033556 -246.71163) (xy 135.063121 -246.750974)
			(xy 135.085992 -246.794551) (xy 135.101576 -246.841232) (xy 135.109471 -246.889809) (xy 135.109966 -246.914416)
			(xy 135.438908 -246.914416) (xy 135.442868 -246.865362) (xy 135.454645 -246.817578) (xy 135.473936 -246.772302)
			(xy 135.500239 -246.730706) (xy 135.532874 -246.693869) (xy 135.570995 -246.662744) (xy 135.613616 -246.638137)
			(xy 135.659632 -246.620685) (xy 135.707851 -246.610841) (xy 135.757026 -246.60886) (xy 135.805881 -246.614792)
			(xy 135.853152 -246.628484) (xy 135.897614 -246.649582) (xy 135.938117 -246.677538) (xy 135.97361 -246.71163)
			(xy 136.003175 -246.750974) (xy 136.026046 -246.794551) (xy 136.04163 -246.841232) (xy 136.049525 -246.889809)
			(xy 136.05002 -246.914416) (xy 137.319016 -246.914416) (xy 137.322976 -246.865362) (xy 137.334753 -246.817578)
			(xy 137.354044 -246.772302) (xy 137.380347 -246.730706) (xy 137.412982 -246.693869) (xy 137.451103 -246.662744)
			(xy 137.493724 -246.638137) (xy 137.53974 -246.620685) (xy 137.587959 -246.610841) (xy 137.637134 -246.60886)
			(xy 137.685989 -246.614792) (xy 137.73326 -246.628484) (xy 137.777722 -246.649582) (xy 137.818225 -246.677538)
			(xy 137.853718 -246.71163) (xy 137.883283 -246.750974) (xy 137.906154 -246.794551) (xy 137.921738 -246.841232)
			(xy 137.929633 -246.889809) (xy 137.930128 -246.914416) (xy 138.25907 -246.914416) (xy 138.26303 -246.865362)
			(xy 138.274807 -246.817578) (xy 138.294098 -246.772302) (xy 138.320401 -246.730706) (xy 138.353036 -246.693869)
			(xy 138.391157 -246.662744) (xy 138.433778 -246.638137) (xy 138.479794 -246.620685) (xy 138.528013 -246.610841)
			(xy 138.577188 -246.60886) (xy 138.626043 -246.614792) (xy 138.673314 -246.628484) (xy 138.717776 -246.649582)
			(xy 138.758279 -246.677538) (xy 138.793772 -246.71163) (xy 138.823337 -246.750974) (xy 138.846208 -246.794551)
			(xy 138.861792 -246.841232) (xy 138.869687 -246.889809) (xy 138.870182 -246.914416) (xy 139.19887 -246.914416)
			(xy 139.20283 -246.865362) (xy 139.214607 -246.817578) (xy 139.233898 -246.772302) (xy 139.260201 -246.730706)
			(xy 139.292836 -246.693869) (xy 139.330957 -246.662744) (xy 139.373578 -246.638137) (xy 139.419594 -246.620685)
			(xy 139.467813 -246.610841) (xy 139.516988 -246.60886) (xy 139.565843 -246.614792) (xy 139.613114 -246.628484)
			(xy 139.657576 -246.649582) (xy 139.698079 -246.677538) (xy 139.733572 -246.71163) (xy 139.763137 -246.750974)
			(xy 139.786008 -246.794551) (xy 139.801592 -246.841232) (xy 139.809487 -246.889809) (xy 139.809982 -246.914416)
			(xy 139.809487 -246.939023) (xy 139.801592 -246.9876) (xy 139.786008 -247.034281) (xy 139.763137 -247.077858)
			(xy 139.733572 -247.117202) (xy 139.698079 -247.151294) (xy 139.657576 -247.17925) (xy 139.613114 -247.200348)
			(xy 139.565843 -247.21404) (xy 139.516988 -247.219972) (xy 139.467813 -247.217991) (xy 139.419594 -247.208147)
			(xy 139.373578 -247.190695) (xy 139.330957 -247.166088) (xy 139.292836 -247.134963) (xy 139.260201 -247.098126)
			(xy 139.233898 -247.05653) (xy 139.214607 -247.011254) (xy 139.20283 -246.96347) (xy 139.19887 -246.914416)
			(xy 138.870182 -246.914416) (xy 138.869687 -246.939023) (xy 138.861792 -246.9876) (xy 138.846208 -247.034281)
			(xy 138.823337 -247.077858) (xy 138.793772 -247.117202) (xy 138.758279 -247.151294) (xy 138.717776 -247.17925)
			(xy 138.673314 -247.200348) (xy 138.626043 -247.21404) (xy 138.577188 -247.219972) (xy 138.528013 -247.217991)
			(xy 138.479794 -247.208147) (xy 138.433778 -247.190695) (xy 138.391157 -247.166088) (xy 138.353036 -247.134963)
			(xy 138.320401 -247.098126) (xy 138.294098 -247.05653) (xy 138.274807 -247.011254) (xy 138.26303 -246.96347)
			(xy 138.25907 -246.914416) (xy 137.930128 -246.914416) (xy 137.929633 -246.939023) (xy 137.921738 -246.9876)
			(xy 137.906154 -247.034281) (xy 137.883283 -247.077858) (xy 137.853718 -247.117202) (xy 137.818225 -247.151294)
			(xy 137.777722 -247.17925) (xy 137.73326 -247.200348) (xy 137.685989 -247.21404) (xy 137.637134 -247.219972)
			(xy 137.587959 -247.217991) (xy 137.53974 -247.208147) (xy 137.493724 -247.190695) (xy 137.451103 -247.166088)
			(xy 137.412982 -247.134963) (xy 137.380347 -247.098126) (xy 137.354044 -247.05653) (xy 137.334753 -247.011254)
			(xy 137.322976 -246.96347) (xy 137.319016 -246.914416) (xy 136.05002 -246.914416) (xy 136.049525 -246.939023)
			(xy 136.04163 -246.9876) (xy 136.026046 -247.034281) (xy 136.003175 -247.077858) (xy 135.97361 -247.117202)
			(xy 135.938117 -247.151294) (xy 135.897614 -247.17925) (xy 135.853152 -247.200348) (xy 135.805881 -247.21404)
			(xy 135.757026 -247.219972) (xy 135.707851 -247.217991) (xy 135.659632 -247.208147) (xy 135.613616 -247.190695)
			(xy 135.570995 -247.166088) (xy 135.532874 -247.134963) (xy 135.500239 -247.098126) (xy 135.473936 -247.05653)
			(xy 135.454645 -247.011254) (xy 135.442868 -246.96347) (xy 135.438908 -246.914416) (xy 135.109966 -246.914416)
			(xy 135.109471 -246.939023) (xy 135.101576 -246.9876) (xy 135.085992 -247.034281) (xy 135.063121 -247.077858)
			(xy 135.033556 -247.117202) (xy 134.998063 -247.151294) (xy 134.95756 -247.17925) (xy 134.913098 -247.200348)
			(xy 134.865827 -247.21404) (xy 134.816972 -247.219972) (xy 134.767797 -247.217991) (xy 134.719578 -247.208147)
			(xy 134.673562 -247.190695) (xy 134.630941 -247.166088) (xy 134.59282 -247.134963) (xy 134.560185 -247.098126)
			(xy 134.533882 -247.05653) (xy 134.514591 -247.011254) (xy 134.502814 -246.96347) (xy 134.498854 -246.914416)
			(xy 134.170166 -246.914416) (xy 134.169671 -246.939023) (xy 134.161776 -246.9876) (xy 134.146192 -247.034281)
			(xy 134.123321 -247.077858) (xy 134.093756 -247.117202) (xy 134.058263 -247.151294) (xy 134.01776 -247.17925)
			(xy 133.973298 -247.200348) (xy 133.926027 -247.21404) (xy 133.877172 -247.219972) (xy 133.827997 -247.217991)
			(xy 133.779778 -247.208147) (xy 133.733762 -247.190695) (xy 133.691141 -247.166088) (xy 133.65302 -247.134963)
			(xy 133.620385 -247.098126) (xy 133.594082 -247.05653) (xy 133.574791 -247.011254) (xy 133.563014 -246.96347)
			(xy 133.559054 -246.914416) (xy 133.240526 -246.914416) (xy 133.240014 -246.939862) (xy 133.23185 -246.990096)
			(xy 133.215734 -247.03837) (xy 133.192083 -247.083433) (xy 133.16151 -247.124119) (xy 133.124806 -247.159374)
			(xy 133.082922 -247.188284) (xy 133.036943 -247.210101) (xy 132.988059 -247.224261) (xy 132.937538 -247.230395)
			(xy 132.886686 -247.228346) (xy 132.836822 -247.218166) (xy 132.789236 -247.200119) (xy 132.745162 -247.174673)
			(xy 132.70574 -247.142486) (xy 132.671992 -247.104392) (xy 132.644791 -247.061378) (xy 132.624843 -247.014558)
			(xy 132.612664 -246.965144) (xy 132.608569 -246.914416) (xy 132.290058 -246.914416) (xy 132.289563 -246.939023)
			(xy 132.281668 -246.9876) (xy 132.266084 -247.034281) (xy 132.243213 -247.077858) (xy 132.213648 -247.117202)
			(xy 132.178155 -247.151294) (xy 132.137652 -247.17925) (xy 132.09319 -247.200348) (xy 132.045919 -247.21404)
			(xy 131.997064 -247.219972) (xy 131.947889 -247.217991) (xy 131.89967 -247.208147) (xy 131.853654 -247.190695)
			(xy 131.811033 -247.166088) (xy 131.772912 -247.134963) (xy 131.740277 -247.098126) (xy 131.713974 -247.05653)
			(xy 131.694683 -247.011254) (xy 131.682906 -246.96347) (xy 131.678946 -246.914416) (xy 131.360418 -246.914416)
			(xy 131.359906 -246.939862) (xy 131.351742 -246.990096) (xy 131.335626 -247.03837) (xy 131.311975 -247.083433)
			(xy 131.281402 -247.124119) (xy 131.244698 -247.159374) (xy 131.202814 -247.188284) (xy 131.156835 -247.210101)
			(xy 131.107951 -247.224261) (xy 131.05743 -247.230395) (xy 131.006578 -247.228346) (xy 130.956714 -247.218166)
			(xy 130.909128 -247.200119) (xy 130.865054 -247.174673) (xy 130.825632 -247.142486) (xy 130.791884 -247.104392)
			(xy 130.764683 -247.061378) (xy 130.744735 -247.014558) (xy 130.732556 -246.965144) (xy 130.728461 -246.914416)
			(xy 129.480564 -246.914416) (xy 129.480052 -246.939862) (xy 129.471888 -246.990096) (xy 129.455772 -247.03837)
			(xy 129.432121 -247.083433) (xy 129.401548 -247.124119) (xy 129.364844 -247.159374) (xy 129.32296 -247.188284)
			(xy 129.276981 -247.210101) (xy 129.228097 -247.224261) (xy 129.177576 -247.230395) (xy 129.126724 -247.228346)
			(xy 129.07686 -247.218166) (xy 129.029274 -247.200119) (xy 128.9852 -247.174673) (xy 128.945778 -247.142486)
			(xy 128.91203 -247.104392) (xy 128.884829 -247.061378) (xy 128.864881 -247.014558) (xy 128.852702 -246.965144)
			(xy 128.848607 -246.914416) (xy 128.54051 -246.914416) (xy 128.539998 -246.939862) (xy 128.531834 -246.990096)
			(xy 128.515718 -247.03837) (xy 128.492067 -247.083433) (xy 128.461494 -247.124119) (xy 128.42479 -247.159374)
			(xy 128.382906 -247.188284) (xy 128.336927 -247.210101) (xy 128.288043 -247.224261) (xy 128.237522 -247.230395)
			(xy 128.18667 -247.228346) (xy 128.136806 -247.218166) (xy 128.08922 -247.200119) (xy 128.045146 -247.174673)
			(xy 128.005724 -247.142486) (xy 127.971976 -247.104392) (xy 127.944775 -247.061378) (xy 127.924827 -247.014558)
			(xy 127.912648 -246.965144) (xy 127.908553 -246.914416) (xy 126.899416 -246.914416) (xy 126.899416 -247.394984)
			(xy 126.89969 -247.40254) (xy 126.90407 -247.417005) (xy 126.908052 -247.423432) (xy 126.91237 -247.429782)
			(xy 126.9238 -247.438926) (xy 126.930912 -247.441974) (xy 126.952986 -247.451536) (xy 126.994058 -247.476576)
			(xy 127.030696 -247.507746) (xy 127.061994 -247.544275) (xy 127.087178 -247.58526) (xy 127.105625 -247.629685)
			(xy 127.116878 -247.676454) (xy 127.120659 -247.724408) (xy 127.120658 -247.724422) (xy 127.438399 -247.724422)
			(xy 127.442494 -247.673694) (xy 127.454673 -247.62428) (xy 127.474621 -247.57746) (xy 127.501822 -247.534446)
			(xy 127.53557 -247.496352) (xy 127.574992 -247.464165) (xy 127.619066 -247.438719) (xy 127.666652 -247.420672)
			(xy 127.716516 -247.410492) (xy 127.767368 -247.408443) (xy 127.817889 -247.414577) (xy 127.866773 -247.428737)
			(xy 127.912752 -247.450554) (xy 127.954636 -247.479464) (xy 127.99134 -247.514719) (xy 128.021913 -247.555405)
			(xy 128.045564 -247.600468) (xy 128.06168 -247.648742) (xy 128.069844 -247.698976) (xy 128.070356 -247.724422)
			(xy 128.388884 -247.724422) (xy 128.392844 -247.675368) (xy 128.404621 -247.627584) (xy 128.423912 -247.582308)
			(xy 128.450215 -247.540712) (xy 128.48285 -247.503875) (xy 128.520971 -247.47275) (xy 128.563592 -247.448143)
			(xy 128.609608 -247.430691) (xy 128.657827 -247.420847) (xy 128.707002 -247.418866) (xy 128.755857 -247.424798)
			(xy 128.803128 -247.43849) (xy 128.84759 -247.459588) (xy 128.888093 -247.487544) (xy 128.923586 -247.521636)
			(xy 128.953151 -247.56098) (xy 128.976022 -247.604557) (xy 128.991606 -247.651238) (xy 128.999501 -247.699815)
			(xy 128.999996 -247.724422) (xy 129.318507 -247.724422) (xy 129.322602 -247.673694) (xy 129.334781 -247.62428)
			(xy 129.354729 -247.57746) (xy 129.38193 -247.534446) (xy 129.415678 -247.496352) (xy 129.4551 -247.464165)
			(xy 129.499174 -247.438719) (xy 129.54676 -247.420672) (xy 129.596624 -247.410492) (xy 129.647476 -247.408443)
			(xy 129.697997 -247.414577) (xy 129.746881 -247.428737) (xy 129.79286 -247.450554) (xy 129.834744 -247.479464)
			(xy 129.871448 -247.514719) (xy 129.902021 -247.555405) (xy 129.925672 -247.600468) (xy 129.941788 -247.648742)
			(xy 129.949952 -247.698976) (xy 129.950464 -247.724422) (xy 130.268992 -247.724422) (xy 130.272952 -247.675368)
			(xy 130.284729 -247.627584) (xy 130.30402 -247.582308) (xy 130.330323 -247.540712) (xy 130.362958 -247.503875)
			(xy 130.401079 -247.47275) (xy 130.4437 -247.448143) (xy 130.489716 -247.430691) (xy 130.537935 -247.420847)
			(xy 130.58711 -247.418866) (xy 130.635965 -247.424798) (xy 130.683236 -247.43849) (xy 130.727698 -247.459588)
			(xy 130.768201 -247.487544) (xy 130.803694 -247.521636) (xy 130.833259 -247.56098) (xy 130.85613 -247.604557)
			(xy 130.871714 -247.651238) (xy 130.879609 -247.699815) (xy 130.880104 -247.724422) (xy 131.198615 -247.724422)
			(xy 131.20271 -247.673694) (xy 131.214889 -247.62428) (xy 131.234837 -247.57746) (xy 131.262038 -247.534446)
			(xy 131.295786 -247.496352) (xy 131.335208 -247.464165) (xy 131.379282 -247.438719) (xy 131.426868 -247.420672)
			(xy 131.476732 -247.410492) (xy 131.527584 -247.408443) (xy 131.578105 -247.414577) (xy 131.626989 -247.428737)
			(xy 131.672968 -247.450554) (xy 131.714852 -247.479464) (xy 131.751556 -247.514719) (xy 131.782129 -247.555405)
			(xy 131.80578 -247.600468) (xy 131.821896 -247.648742) (xy 131.83006 -247.698976) (xy 131.830572 -247.724422)
			(xy 132.138415 -247.724422) (xy 132.14251 -247.673694) (xy 132.154689 -247.62428) (xy 132.174637 -247.57746)
			(xy 132.201838 -247.534446) (xy 132.235586 -247.496352) (xy 132.275008 -247.464165) (xy 132.319082 -247.438719)
			(xy 132.366668 -247.420672) (xy 132.416532 -247.410492) (xy 132.467384 -247.408443) (xy 132.517905 -247.414577)
			(xy 132.566789 -247.428737) (xy 132.612768 -247.450554) (xy 132.654652 -247.479464) (xy 132.691356 -247.514719)
			(xy 132.721929 -247.555405) (xy 132.74558 -247.600468) (xy 132.761696 -247.648742) (xy 132.76986 -247.698976)
			(xy 132.770372 -247.724422) (xy 133.0889 -247.724422) (xy 133.09286 -247.675368) (xy 133.104637 -247.627584)
			(xy 133.123928 -247.582308) (xy 133.150231 -247.540712) (xy 133.182866 -247.503875) (xy 133.220987 -247.47275)
			(xy 133.263608 -247.448143) (xy 133.309624 -247.430691) (xy 133.357843 -247.420847) (xy 133.407018 -247.418866)
			(xy 133.455873 -247.424798) (xy 133.503144 -247.43849) (xy 133.547606 -247.459588) (xy 133.588109 -247.487544)
			(xy 133.623602 -247.521636) (xy 133.653167 -247.56098) (xy 133.676038 -247.604557) (xy 133.691622 -247.651238)
			(xy 133.699517 -247.699815) (xy 133.700012 -247.724422) (xy 134.028954 -247.724422) (xy 134.032914 -247.675368)
			(xy 134.044691 -247.627584) (xy 134.063982 -247.582308) (xy 134.090285 -247.540712) (xy 134.12292 -247.503875)
			(xy 134.161041 -247.47275) (xy 134.203662 -247.448143) (xy 134.249678 -247.430691) (xy 134.297897 -247.420847)
			(xy 134.347072 -247.418866) (xy 134.395927 -247.424798) (xy 134.443198 -247.43849) (xy 134.48766 -247.459588)
			(xy 134.528163 -247.487544) (xy 134.563656 -247.521636) (xy 134.593221 -247.56098) (xy 134.616092 -247.604557)
			(xy 134.631676 -247.651238) (xy 134.639571 -247.699815) (xy 134.640066 -247.724422) (xy 134.969008 -247.724422)
			(xy 134.972968 -247.675368) (xy 134.984745 -247.627584) (xy 135.004036 -247.582308) (xy 135.030339 -247.540712)
			(xy 135.062974 -247.503875) (xy 135.101095 -247.47275) (xy 135.143716 -247.448143) (xy 135.189732 -247.430691)
			(xy 135.237951 -247.420847) (xy 135.287126 -247.418866) (xy 135.335981 -247.424798) (xy 135.383252 -247.43849)
			(xy 135.427714 -247.459588) (xy 135.468217 -247.487544) (xy 135.50371 -247.521636) (xy 135.533275 -247.56098)
			(xy 135.556146 -247.604557) (xy 135.57173 -247.651238) (xy 135.579625 -247.699815) (xy 135.58012 -247.724422)
			(xy 135.909062 -247.724422) (xy 135.913022 -247.675368) (xy 135.924799 -247.627584) (xy 135.94409 -247.582308)
			(xy 135.970393 -247.540712) (xy 136.003028 -247.503875) (xy 136.041149 -247.47275) (xy 136.08377 -247.448143)
			(xy 136.129786 -247.430691) (xy 136.178005 -247.420847) (xy 136.22718 -247.418866) (xy 136.276035 -247.424798)
			(xy 136.323306 -247.43849) (xy 136.367768 -247.459588) (xy 136.408271 -247.487544) (xy 136.443764 -247.521636)
			(xy 136.473329 -247.56098) (xy 136.4962 -247.604557) (xy 136.511784 -247.651238) (xy 136.519679 -247.699815)
			(xy 136.520174 -247.724422) (xy 136.848862 -247.724422) (xy 136.852822 -247.675368) (xy 136.864599 -247.627584)
			(xy 136.88389 -247.582308) (xy 136.910193 -247.540712) (xy 136.942828 -247.503875) (xy 136.980949 -247.47275)
			(xy 137.02357 -247.448143) (xy 137.069586 -247.430691) (xy 137.117805 -247.420847) (xy 137.16698 -247.418866)
			(xy 137.215835 -247.424798) (xy 137.263106 -247.43849) (xy 137.307568 -247.459588) (xy 137.348071 -247.487544)
			(xy 137.383564 -247.521636) (xy 137.413129 -247.56098) (xy 137.436 -247.604557) (xy 137.451584 -247.651238)
			(xy 137.459479 -247.699815) (xy 137.459974 -247.724422) (xy 137.788916 -247.724422) (xy 137.792876 -247.675368)
			(xy 137.804653 -247.627584) (xy 137.823944 -247.582308) (xy 137.850247 -247.540712) (xy 137.882882 -247.503875)
			(xy 137.921003 -247.47275) (xy 137.963624 -247.448143) (xy 138.00964 -247.430691) (xy 138.057859 -247.420847)
			(xy 138.107034 -247.418866) (xy 138.155889 -247.424798) (xy 138.20316 -247.43849) (xy 138.247622 -247.459588)
			(xy 138.288125 -247.487544) (xy 138.323618 -247.521636) (xy 138.353183 -247.56098) (xy 138.376054 -247.604557)
			(xy 138.391638 -247.651238) (xy 138.399533 -247.699815) (xy 138.400028 -247.724422) (xy 138.72897 -247.724422)
			(xy 138.73293 -247.675368) (xy 138.744707 -247.627584) (xy 138.763998 -247.582308) (xy 138.790301 -247.540712)
			(xy 138.822936 -247.503875) (xy 138.861057 -247.47275) (xy 138.903678 -247.448143) (xy 138.949694 -247.430691)
			(xy 138.997913 -247.420847) (xy 139.047088 -247.418866) (xy 139.095943 -247.424798) (xy 139.143214 -247.43849)
			(xy 139.187676 -247.459588) (xy 139.228179 -247.487544) (xy 139.263672 -247.521636) (xy 139.293237 -247.56098)
			(xy 139.316108 -247.604557) (xy 139.331692 -247.651238) (xy 139.339587 -247.699815) (xy 139.340082 -247.724422)
			(xy 139.339587 -247.749029) (xy 139.331692 -247.797606) (xy 139.316108 -247.844287) (xy 139.293237 -247.887864)
			(xy 139.263672 -247.927208) (xy 139.228179 -247.9613) (xy 139.187676 -247.989256) (xy 139.143214 -248.010354)
			(xy 139.095943 -248.024046) (xy 139.047088 -248.029978) (xy 138.997913 -248.027997) (xy 138.949694 -248.018153)
			(xy 138.903678 -248.000701) (xy 138.861057 -247.976094) (xy 138.822936 -247.944969) (xy 138.790301 -247.908132)
			(xy 138.763998 -247.866536) (xy 138.744707 -247.82126) (xy 138.73293 -247.773476) (xy 138.72897 -247.724422)
			(xy 138.400028 -247.724422) (xy 138.399533 -247.749029) (xy 138.391638 -247.797606) (xy 138.376054 -247.844287)
			(xy 138.353183 -247.887864) (xy 138.323618 -247.927208) (xy 138.288125 -247.9613) (xy 138.247622 -247.989256)
			(xy 138.20316 -248.010354) (xy 138.155889 -248.024046) (xy 138.107034 -248.029978) (xy 138.057859 -248.027997)
			(xy 138.00964 -248.018153) (xy 137.963624 -248.000701) (xy 137.921003 -247.976094) (xy 137.882882 -247.944969)
			(xy 137.850247 -247.908132) (xy 137.823944 -247.866536) (xy 137.804653 -247.82126) (xy 137.792876 -247.773476)
			(xy 137.788916 -247.724422) (xy 137.459974 -247.724422) (xy 137.459479 -247.749029) (xy 137.451584 -247.797606)
			(xy 137.436 -247.844287) (xy 137.413129 -247.887864) (xy 137.383564 -247.927208) (xy 137.348071 -247.9613)
			(xy 137.307568 -247.989256) (xy 137.263106 -248.010354) (xy 137.215835 -248.024046) (xy 137.16698 -248.029978)
			(xy 137.117805 -248.027997) (xy 137.069586 -248.018153) (xy 137.02357 -248.000701) (xy 136.980949 -247.976094)
			(xy 136.942828 -247.944969) (xy 136.910193 -247.908132) (xy 136.88389 -247.866536) (xy 136.864599 -247.82126)
			(xy 136.852822 -247.773476) (xy 136.848862 -247.724422) (xy 136.520174 -247.724422) (xy 136.519679 -247.749029)
			(xy 136.511784 -247.797606) (xy 136.4962 -247.844287) (xy 136.473329 -247.887864) (xy 136.443764 -247.927208)
			(xy 136.408271 -247.9613) (xy 136.367768 -247.989256) (xy 136.323306 -248.010354) (xy 136.276035 -248.024046)
			(xy 136.22718 -248.029978) (xy 136.178005 -248.027997) (xy 136.129786 -248.018153) (xy 136.08377 -248.000701)
			(xy 136.041149 -247.976094) (xy 136.003028 -247.944969) (xy 135.970393 -247.908132) (xy 135.94409 -247.866536)
			(xy 135.924799 -247.82126) (xy 135.913022 -247.773476) (xy 135.909062 -247.724422) (xy 135.58012 -247.724422)
			(xy 135.579625 -247.749029) (xy 135.57173 -247.797606) (xy 135.556146 -247.844287) (xy 135.533275 -247.887864)
			(xy 135.50371 -247.927208) (xy 135.468217 -247.9613) (xy 135.427714 -247.989256) (xy 135.383252 -248.010354)
			(xy 135.335981 -248.024046) (xy 135.287126 -248.029978) (xy 135.237951 -248.027997) (xy 135.189732 -248.018153)
			(xy 135.143716 -248.000701) (xy 135.101095 -247.976094) (xy 135.062974 -247.944969) (xy 135.030339 -247.908132)
			(xy 135.004036 -247.866536) (xy 134.984745 -247.82126) (xy 134.972968 -247.773476) (xy 134.969008 -247.724422)
			(xy 134.640066 -247.724422) (xy 134.639571 -247.749029) (xy 134.631676 -247.797606) (xy 134.616092 -247.844287)
			(xy 134.593221 -247.887864) (xy 134.563656 -247.927208) (xy 134.528163 -247.9613) (xy 134.48766 -247.989256)
			(xy 134.443198 -248.010354) (xy 134.395927 -248.024046) (xy 134.347072 -248.029978) (xy 134.297897 -248.027997)
			(xy 134.249678 -248.018153) (xy 134.203662 -248.000701) (xy 134.161041 -247.976094) (xy 134.12292 -247.944969)
			(xy 134.090285 -247.908132) (xy 134.063982 -247.866536) (xy 134.044691 -247.82126) (xy 134.032914 -247.773476)
			(xy 134.028954 -247.724422) (xy 133.700012 -247.724422) (xy 133.699517 -247.749029) (xy 133.691622 -247.797606)
			(xy 133.676038 -247.844287) (xy 133.653167 -247.887864) (xy 133.623602 -247.927208) (xy 133.588109 -247.9613)
			(xy 133.547606 -247.989256) (xy 133.503144 -248.010354) (xy 133.455873 -248.024046) (xy 133.407018 -248.029978)
			(xy 133.357843 -248.027997) (xy 133.309624 -248.018153) (xy 133.263608 -248.000701) (xy 133.220987 -247.976094)
			(xy 133.182866 -247.944969) (xy 133.150231 -247.908132) (xy 133.123928 -247.866536) (xy 133.104637 -247.82126)
			(xy 133.09286 -247.773476) (xy 133.0889 -247.724422) (xy 132.770372 -247.724422) (xy 132.76986 -247.749868)
			(xy 132.761696 -247.800102) (xy 132.74558 -247.848376) (xy 132.721929 -247.893439) (xy 132.691356 -247.934125)
			(xy 132.654652 -247.96938) (xy 132.612768 -247.99829) (xy 132.566789 -248.020107) (xy 132.517905 -248.034267)
			(xy 132.467384 -248.040401) (xy 132.416532 -248.038352) (xy 132.366668 -248.028172) (xy 132.319082 -248.010125)
			(xy 132.275008 -247.984679) (xy 132.235586 -247.952492) (xy 132.201838 -247.914398) (xy 132.174637 -247.871384)
			(xy 132.154689 -247.824564) (xy 132.14251 -247.77515) (xy 132.138415 -247.724422) (xy 131.830572 -247.724422)
			(xy 131.83006 -247.749868) (xy 131.821896 -247.800102) (xy 131.80578 -247.848376) (xy 131.782129 -247.893439)
			(xy 131.751556 -247.934125) (xy 131.714852 -247.96938) (xy 131.672968 -247.99829) (xy 131.626989 -248.020107)
			(xy 131.578105 -248.034267) (xy 131.527584 -248.040401) (xy 131.476732 -248.038352) (xy 131.426868 -248.028172)
			(xy 131.379282 -248.010125) (xy 131.335208 -247.984679) (xy 131.295786 -247.952492) (xy 131.262038 -247.914398)
			(xy 131.234837 -247.871384) (xy 131.214889 -247.824564) (xy 131.20271 -247.77515) (xy 131.198615 -247.724422)
			(xy 130.880104 -247.724422) (xy 130.879609 -247.749029) (xy 130.871714 -247.797606) (xy 130.85613 -247.844287)
			(xy 130.833259 -247.887864) (xy 130.803694 -247.927208) (xy 130.768201 -247.9613) (xy 130.727698 -247.989256)
			(xy 130.683236 -248.010354) (xy 130.635965 -248.024046) (xy 130.58711 -248.029978) (xy 130.537935 -248.027997)
			(xy 130.489716 -248.018153) (xy 130.4437 -248.000701) (xy 130.401079 -247.976094) (xy 130.362958 -247.944969)
			(xy 130.330323 -247.908132) (xy 130.30402 -247.866536) (xy 130.284729 -247.82126) (xy 130.272952 -247.773476)
			(xy 130.268992 -247.724422) (xy 129.950464 -247.724422) (xy 129.949952 -247.749868) (xy 129.941788 -247.800102)
			(xy 129.925672 -247.848376) (xy 129.902021 -247.893439) (xy 129.871448 -247.934125) (xy 129.834744 -247.96938)
			(xy 129.79286 -247.99829) (xy 129.746881 -248.020107) (xy 129.697997 -248.034267) (xy 129.647476 -248.040401)
			(xy 129.596624 -248.038352) (xy 129.54676 -248.028172) (xy 129.499174 -248.010125) (xy 129.4551 -247.984679)
			(xy 129.415678 -247.952492) (xy 129.38193 -247.914398) (xy 129.354729 -247.871384) (xy 129.334781 -247.824564)
			(xy 129.322602 -247.77515) (xy 129.318507 -247.724422) (xy 128.999996 -247.724422) (xy 128.999501 -247.749029)
			(xy 128.991606 -247.797606) (xy 128.976022 -247.844287) (xy 128.953151 -247.887864) (xy 128.923586 -247.927208)
			(xy 128.888093 -247.9613) (xy 128.84759 -247.989256) (xy 128.803128 -248.010354) (xy 128.755857 -248.024046)
			(xy 128.707002 -248.029978) (xy 128.657827 -248.027997) (xy 128.609608 -248.018153) (xy 128.563592 -248.000701)
			(xy 128.520971 -247.976094) (xy 128.48285 -247.944969) (xy 128.450215 -247.908132) (xy 128.423912 -247.866536)
			(xy 128.404621 -247.82126) (xy 128.392844 -247.773476) (xy 128.388884 -247.724422) (xy 128.070356 -247.724422)
			(xy 128.069844 -247.749868) (xy 128.06168 -247.800102) (xy 128.045564 -247.848376) (xy 128.021913 -247.893439)
			(xy 127.99134 -247.934125) (xy 127.954636 -247.96938) (xy 127.912752 -247.99829) (xy 127.866773 -248.020107)
			(xy 127.817889 -248.034267) (xy 127.767368 -248.040401) (xy 127.716516 -248.038352) (xy 127.666652 -248.028172)
			(xy 127.619066 -248.010125) (xy 127.574992 -247.984679) (xy 127.53557 -247.952492) (xy 127.501822 -247.914398)
			(xy 127.474621 -247.871384) (xy 127.454673 -247.824564) (xy 127.442494 -247.77515) (xy 127.438399 -247.724422)
			(xy 127.120658 -247.724422) (xy 127.116875 -247.772363) (xy 127.10562 -247.819131) (xy 127.08717 -247.863555)
			(xy 127.061984 -247.904538) (xy 127.030684 -247.941065) (xy 126.994044 -247.972233) (xy 126.952971 -247.997271)
			(xy 126.930912 -248.00687) (xy 126.9238 -248.009918) (xy 126.91237 -248.019062) (xy 126.908052 -248.025412)
			(xy 126.90403 -248.031821) (xy 126.899653 -248.046296) (xy 126.899416 -248.05386) (xy 126.899416 -248.242836)
			(xy 126.899416 -248.244868) (xy 126.900146 -248.253936) (xy 126.907171 -248.270701) (xy 126.919625 -248.283944)
			(xy 126.92761 -248.288302) (xy 127.016764 -248.326148) (xy 127.023753 -248.32877) (xy 127.038594 -248.330316)
			(xy 127.045974 -248.329196) (xy 127.05334 -248.327926) (xy 127.06604 -248.321068) (xy 127.071882 -248.31548)
			(xy 127.089091 -248.299381) (xy 127.127538 -248.272135) (xy 127.169711 -248.251112) (xy 127.21461 -248.23681)
			(xy 127.261173 -248.229569) (xy 127.284734 -248.22912) (xy 127.309985 -248.229644) (xy 127.359798 -248.237962)
			(xy 127.407563 -248.254364) (xy 127.451976 -248.278404) (xy 127.491828 -248.309426) (xy 127.52603 -248.346583)
			(xy 127.553651 -248.388863) (xy 127.573936 -248.435113) (xy 127.586333 -248.48407) (xy 127.590503 -248.5344)
			(xy 127.590501 -248.534428) (xy 127.908553 -248.534428) (xy 127.912648 -248.4837) (xy 127.924827 -248.434286)
			(xy 127.944775 -248.387466) (xy 127.971976 -248.344452) (xy 128.005724 -248.306358) (xy 128.045146 -248.274171)
			(xy 128.08922 -248.248725) (xy 128.136806 -248.230678) (xy 128.18667 -248.220498) (xy 128.237522 -248.218449)
			(xy 128.288043 -248.224583) (xy 128.336927 -248.238743) (xy 128.382906 -248.26056) (xy 128.42479 -248.28947)
			(xy 128.461494 -248.324725) (xy 128.492067 -248.365411) (xy 128.515718 -248.410474) (xy 128.531834 -248.458748)
			(xy 128.539998 -248.508982) (xy 128.54051 -248.534428) (xy 128.848607 -248.534428) (xy 128.852702 -248.4837)
			(xy 128.864881 -248.434286) (xy 128.884829 -248.387466) (xy 128.91203 -248.344452) (xy 128.945778 -248.306358)
			(xy 128.9852 -248.274171) (xy 129.029274 -248.248725) (xy 129.07686 -248.230678) (xy 129.126724 -248.220498)
			(xy 129.177576 -248.218449) (xy 129.228097 -248.224583) (xy 129.276981 -248.238743) (xy 129.32296 -248.26056)
			(xy 129.364844 -248.28947) (xy 129.401548 -248.324725) (xy 129.432121 -248.365411) (xy 129.455772 -248.410474)
			(xy 129.471888 -248.458748) (xy 129.480052 -248.508982) (xy 129.480564 -248.534428) (xy 129.798838 -248.534428)
			(xy 129.802798 -248.485374) (xy 129.814575 -248.43759) (xy 129.833866 -248.392314) (xy 129.860169 -248.350718)
			(xy 129.892804 -248.313881) (xy 129.930925 -248.282756) (xy 129.973546 -248.258149) (xy 130.019562 -248.240697)
			(xy 130.067781 -248.230853) (xy 130.116956 -248.228872) (xy 130.165811 -248.234804) (xy 130.213082 -248.248496)
			(xy 130.257544 -248.269594) (xy 130.298047 -248.29755) (xy 130.33354 -248.331642) (xy 130.363105 -248.370986)
			(xy 130.385976 -248.414563) (xy 130.40156 -248.461244) (xy 130.409455 -248.509821) (xy 130.40995 -248.534428)
			(xy 130.728461 -248.534428) (xy 130.732556 -248.4837) (xy 130.744735 -248.434286) (xy 130.764683 -248.387466)
			(xy 130.791884 -248.344452) (xy 130.825632 -248.306358) (xy 130.865054 -248.274171) (xy 130.909128 -248.248725)
			(xy 130.956714 -248.230678) (xy 131.006578 -248.220498) (xy 131.05743 -248.218449) (xy 131.107951 -248.224583)
			(xy 131.156835 -248.238743) (xy 131.202814 -248.26056) (xy 131.244698 -248.28947) (xy 131.281402 -248.324725)
			(xy 131.311975 -248.365411) (xy 131.335626 -248.410474) (xy 131.351742 -248.458748) (xy 131.359906 -248.508982)
			(xy 131.360418 -248.534428) (xy 131.678946 -248.534428) (xy 131.682906 -248.485374) (xy 131.694683 -248.43759)
			(xy 131.713974 -248.392314) (xy 131.740277 -248.350718) (xy 131.772912 -248.313881) (xy 131.811033 -248.282756)
			(xy 131.853654 -248.258149) (xy 131.89967 -248.240697) (xy 131.947889 -248.230853) (xy 131.997064 -248.228872)
			(xy 132.045919 -248.234804) (xy 132.09319 -248.248496) (xy 132.137652 -248.269594) (xy 132.178155 -248.29755)
			(xy 132.213648 -248.331642) (xy 132.243213 -248.370986) (xy 132.266084 -248.414563) (xy 132.281668 -248.461244)
			(xy 132.289563 -248.509821) (xy 132.290058 -248.534428) (xy 132.608569 -248.534428) (xy 132.612664 -248.4837)
			(xy 132.624843 -248.434286) (xy 132.644791 -248.387466) (xy 132.671992 -248.344452) (xy 132.70574 -248.306358)
			(xy 132.745162 -248.274171) (xy 132.789236 -248.248725) (xy 132.836822 -248.230678) (xy 132.886686 -248.220498)
			(xy 132.937538 -248.218449) (xy 132.988059 -248.224583) (xy 133.036943 -248.238743) (xy 133.082922 -248.26056)
			(xy 133.124806 -248.28947) (xy 133.16151 -248.324725) (xy 133.192083 -248.365411) (xy 133.215734 -248.410474)
			(xy 133.23185 -248.458748) (xy 133.240014 -248.508982) (xy 133.240526 -248.534428) (xy 133.559054 -248.534428)
			(xy 133.563014 -248.485374) (xy 133.574791 -248.43759) (xy 133.594082 -248.392314) (xy 133.620385 -248.350718)
			(xy 133.65302 -248.313881) (xy 133.691141 -248.282756) (xy 133.733762 -248.258149) (xy 133.779778 -248.240697)
			(xy 133.827997 -248.230853) (xy 133.877172 -248.228872) (xy 133.926027 -248.234804) (xy 133.973298 -248.248496)
			(xy 134.01776 -248.269594) (xy 134.058263 -248.29755) (xy 134.093756 -248.331642) (xy 134.123321 -248.370986)
			(xy 134.146192 -248.414563) (xy 134.161776 -248.461244) (xy 134.169671 -248.509821) (xy 134.170166 -248.534428)
			(xy 134.498854 -248.534428) (xy 134.502814 -248.485374) (xy 134.514591 -248.43759) (xy 134.533882 -248.392314)
			(xy 134.560185 -248.350718) (xy 134.59282 -248.313881) (xy 134.630941 -248.282756) (xy 134.673562 -248.258149)
			(xy 134.719578 -248.240697) (xy 134.767797 -248.230853) (xy 134.816972 -248.228872) (xy 134.865827 -248.234804)
			(xy 134.913098 -248.248496) (xy 134.95756 -248.269594) (xy 134.998063 -248.29755) (xy 135.033556 -248.331642)
			(xy 135.063121 -248.370986) (xy 135.085992 -248.414563) (xy 135.101576 -248.461244) (xy 135.109471 -248.509821)
			(xy 135.109966 -248.534428) (xy 135.438908 -248.534428) (xy 135.442868 -248.485374) (xy 135.454645 -248.43759)
			(xy 135.473936 -248.392314) (xy 135.500239 -248.350718) (xy 135.532874 -248.313881) (xy 135.570995 -248.282756)
			(xy 135.613616 -248.258149) (xy 135.659632 -248.240697) (xy 135.707851 -248.230853) (xy 135.757026 -248.228872)
			(xy 135.805881 -248.234804) (xy 135.853152 -248.248496) (xy 135.897614 -248.269594) (xy 135.938117 -248.29755)
			(xy 135.97361 -248.331642) (xy 136.003175 -248.370986) (xy 136.026046 -248.414563) (xy 136.04163 -248.461244)
			(xy 136.049525 -248.509821) (xy 136.05002 -248.534428) (xy 136.378962 -248.534428) (xy 136.382922 -248.485374)
			(xy 136.394699 -248.43759) (xy 136.41399 -248.392314) (xy 136.440293 -248.350718) (xy 136.472928 -248.313881)
			(xy 136.511049 -248.282756) (xy 136.55367 -248.258149) (xy 136.599686 -248.240697) (xy 136.647905 -248.230853)
			(xy 136.69708 -248.228872) (xy 136.745935 -248.234804) (xy 136.793206 -248.248496) (xy 136.837668 -248.269594)
			(xy 136.878171 -248.29755) (xy 136.913664 -248.331642) (xy 136.943229 -248.370986) (xy 136.9661 -248.414563)
			(xy 136.981684 -248.461244) (xy 136.989579 -248.509821) (xy 136.990074 -248.534428) (xy 137.319016 -248.534428)
			(xy 137.322976 -248.485374) (xy 137.334753 -248.43759) (xy 137.354044 -248.392314) (xy 137.380347 -248.350718)
			(xy 137.412982 -248.313881) (xy 137.451103 -248.282756) (xy 137.493724 -248.258149) (xy 137.53974 -248.240697)
			(xy 137.587959 -248.230853) (xy 137.637134 -248.228872) (xy 137.685989 -248.234804) (xy 137.73326 -248.248496)
			(xy 137.777722 -248.269594) (xy 137.818225 -248.29755) (xy 137.853718 -248.331642) (xy 137.883283 -248.370986)
			(xy 137.906154 -248.414563) (xy 137.921738 -248.461244) (xy 137.929633 -248.509821) (xy 137.930128 -248.534428)
			(xy 138.25907 -248.534428) (xy 138.26303 -248.485374) (xy 138.274807 -248.43759) (xy 138.294098 -248.392314)
			(xy 138.320401 -248.350718) (xy 138.353036 -248.313881) (xy 138.391157 -248.282756) (xy 138.433778 -248.258149)
			(xy 138.479794 -248.240697) (xy 138.528013 -248.230853) (xy 138.577188 -248.228872) (xy 138.626043 -248.234804)
			(xy 138.673314 -248.248496) (xy 138.717776 -248.269594) (xy 138.758279 -248.29755) (xy 138.793772 -248.331642)
			(xy 138.823337 -248.370986) (xy 138.846208 -248.414563) (xy 138.861792 -248.461244) (xy 138.869687 -248.509821)
			(xy 138.870182 -248.534428) (xy 139.19887 -248.534428) (xy 139.20283 -248.485374) (xy 139.214607 -248.43759)
			(xy 139.233898 -248.392314) (xy 139.260201 -248.350718) (xy 139.292836 -248.313881) (xy 139.330957 -248.282756)
			(xy 139.373578 -248.258149) (xy 139.419594 -248.240697) (xy 139.467813 -248.230853) (xy 139.516988 -248.228872)
			(xy 139.565843 -248.234804) (xy 139.613114 -248.248496) (xy 139.657576 -248.269594) (xy 139.698079 -248.29755)
			(xy 139.733572 -248.331642) (xy 139.763137 -248.370986) (xy 139.786008 -248.414563) (xy 139.801592 -248.461244)
			(xy 139.809487 -248.509821) (xy 139.809982 -248.534428) (xy 139.809487 -248.559035) (xy 139.801592 -248.607612)
			(xy 139.786008 -248.654293) (xy 139.763137 -248.69787) (xy 139.733572 -248.737214) (xy 139.698079 -248.771306)
			(xy 139.657576 -248.799262) (xy 139.613114 -248.82036) (xy 139.565843 -248.834052) (xy 139.516988 -248.839984)
			(xy 139.467813 -248.838003) (xy 139.419594 -248.828159) (xy 139.373578 -248.810707) (xy 139.330957 -248.7861)
			(xy 139.292836 -248.754975) (xy 139.260201 -248.718138) (xy 139.233898 -248.676542) (xy 139.214607 -248.631266)
			(xy 139.20283 -248.583482) (xy 139.19887 -248.534428) (xy 138.870182 -248.534428) (xy 138.869687 -248.559035)
			(xy 138.861792 -248.607612) (xy 138.846208 -248.654293) (xy 138.823337 -248.69787) (xy 138.793772 -248.737214)
			(xy 138.758279 -248.771306) (xy 138.717776 -248.799262) (xy 138.673314 -248.82036) (xy 138.626043 -248.834052)
			(xy 138.577188 -248.839984) (xy 138.528013 -248.838003) (xy 138.479794 -248.828159) (xy 138.433778 -248.810707)
			(xy 138.391157 -248.7861) (xy 138.353036 -248.754975) (xy 138.320401 -248.718138) (xy 138.294098 -248.676542)
			(xy 138.274807 -248.631266) (xy 138.26303 -248.583482) (xy 138.25907 -248.534428) (xy 137.930128 -248.534428)
			(xy 137.929633 -248.559035) (xy 137.921738 -248.607612) (xy 137.906154 -248.654293) (xy 137.883283 -248.69787)
			(xy 137.853718 -248.737214) (xy 137.818225 -248.771306) (xy 137.777722 -248.799262) (xy 137.73326 -248.82036)
			(xy 137.685989 -248.834052) (xy 137.637134 -248.839984) (xy 137.587959 -248.838003) (xy 137.53974 -248.828159)
			(xy 137.493724 -248.810707) (xy 137.451103 -248.7861) (xy 137.412982 -248.754975) (xy 137.380347 -248.718138)
			(xy 137.354044 -248.676542) (xy 137.334753 -248.631266) (xy 137.322976 -248.583482) (xy 137.319016 -248.534428)
			(xy 136.990074 -248.534428) (xy 136.989579 -248.559035) (xy 136.981684 -248.607612) (xy 136.9661 -248.654293)
			(xy 136.943229 -248.69787) (xy 136.913664 -248.737214) (xy 136.878171 -248.771306) (xy 136.837668 -248.799262)
			(xy 136.793206 -248.82036) (xy 136.745935 -248.834052) (xy 136.69708 -248.839984) (xy 136.647905 -248.838003)
			(xy 136.599686 -248.828159) (xy 136.55367 -248.810707) (xy 136.511049 -248.7861) (xy 136.472928 -248.754975)
			(xy 136.440293 -248.718138) (xy 136.41399 -248.676542) (xy 136.394699 -248.631266) (xy 136.382922 -248.583482)
			(xy 136.378962 -248.534428) (xy 136.05002 -248.534428) (xy 136.049525 -248.559035) (xy 136.04163 -248.607612)
			(xy 136.026046 -248.654293) (xy 136.003175 -248.69787) (xy 135.97361 -248.737214) (xy 135.938117 -248.771306)
			(xy 135.897614 -248.799262) (xy 135.853152 -248.82036) (xy 135.805881 -248.834052) (xy 135.757026 -248.839984)
			(xy 135.707851 -248.838003) (xy 135.659632 -248.828159) (xy 135.613616 -248.810707) (xy 135.570995 -248.7861)
			(xy 135.532874 -248.754975) (xy 135.500239 -248.718138) (xy 135.473936 -248.676542) (xy 135.454645 -248.631266)
			(xy 135.442868 -248.583482) (xy 135.438908 -248.534428) (xy 135.109966 -248.534428) (xy 135.109471 -248.559035)
			(xy 135.101576 -248.607612) (xy 135.085992 -248.654293) (xy 135.063121 -248.69787) (xy 135.033556 -248.737214)
			(xy 134.998063 -248.771306) (xy 134.95756 -248.799262) (xy 134.913098 -248.82036) (xy 134.865827 -248.834052)
			(xy 134.816972 -248.839984) (xy 134.767797 -248.838003) (xy 134.719578 -248.828159) (xy 134.673562 -248.810707)
			(xy 134.630941 -248.7861) (xy 134.59282 -248.754975) (xy 134.560185 -248.718138) (xy 134.533882 -248.676542)
			(xy 134.514591 -248.631266) (xy 134.502814 -248.583482) (xy 134.498854 -248.534428) (xy 134.170166 -248.534428)
			(xy 134.169671 -248.559035) (xy 134.161776 -248.607612) (xy 134.146192 -248.654293) (xy 134.123321 -248.69787)
			(xy 134.093756 -248.737214) (xy 134.058263 -248.771306) (xy 134.01776 -248.799262) (xy 133.973298 -248.82036)
			(xy 133.926027 -248.834052) (xy 133.877172 -248.839984) (xy 133.827997 -248.838003) (xy 133.779778 -248.828159)
			(xy 133.733762 -248.810707) (xy 133.691141 -248.7861) (xy 133.65302 -248.754975) (xy 133.620385 -248.718138)
			(xy 133.594082 -248.676542) (xy 133.574791 -248.631266) (xy 133.563014 -248.583482) (xy 133.559054 -248.534428)
			(xy 133.240526 -248.534428) (xy 133.240014 -248.559874) (xy 133.23185 -248.610108) (xy 133.215734 -248.658382)
			(xy 133.192083 -248.703445) (xy 133.16151 -248.744131) (xy 133.124806 -248.779386) (xy 133.082922 -248.808296)
			(xy 133.036943 -248.830113) (xy 132.988059 -248.844273) (xy 132.937538 -248.850407) (xy 132.886686 -248.848358)
			(xy 132.836822 -248.838178) (xy 132.789236 -248.820131) (xy 132.745162 -248.794685) (xy 132.70574 -248.762498)
			(xy 132.671992 -248.724404) (xy 132.644791 -248.68139) (xy 132.624843 -248.63457) (xy 132.612664 -248.585156)
			(xy 132.608569 -248.534428) (xy 132.290058 -248.534428) (xy 132.289563 -248.559035) (xy 132.281668 -248.607612)
			(xy 132.266084 -248.654293) (xy 132.243213 -248.69787) (xy 132.213648 -248.737214) (xy 132.178155 -248.771306)
			(xy 132.137652 -248.799262) (xy 132.09319 -248.82036) (xy 132.045919 -248.834052) (xy 131.997064 -248.839984)
			(xy 131.947889 -248.838003) (xy 131.89967 -248.828159) (xy 131.853654 -248.810707) (xy 131.811033 -248.7861)
			(xy 131.772912 -248.754975) (xy 131.740277 -248.718138) (xy 131.713974 -248.676542) (xy 131.694683 -248.631266)
			(xy 131.682906 -248.583482) (xy 131.678946 -248.534428) (xy 131.360418 -248.534428) (xy 131.359906 -248.559874)
			(xy 131.351742 -248.610108) (xy 131.335626 -248.658382) (xy 131.311975 -248.703445) (xy 131.281402 -248.744131)
			(xy 131.244698 -248.779386) (xy 131.202814 -248.808296) (xy 131.156835 -248.830113) (xy 131.107951 -248.844273)
			(xy 131.05743 -248.850407) (xy 131.006578 -248.848358) (xy 130.956714 -248.838178) (xy 130.909128 -248.820131)
			(xy 130.865054 -248.794685) (xy 130.825632 -248.762498) (xy 130.791884 -248.724404) (xy 130.764683 -248.68139)
			(xy 130.744735 -248.63457) (xy 130.732556 -248.585156) (xy 130.728461 -248.534428) (xy 130.40995 -248.534428)
			(xy 130.409455 -248.559035) (xy 130.40156 -248.607612) (xy 130.385976 -248.654293) (xy 130.363105 -248.69787)
			(xy 130.33354 -248.737214) (xy 130.298047 -248.771306) (xy 130.257544 -248.799262) (xy 130.213082 -248.82036)
			(xy 130.165811 -248.834052) (xy 130.116956 -248.839984) (xy 130.067781 -248.838003) (xy 130.019562 -248.828159)
			(xy 129.973546 -248.810707) (xy 129.930925 -248.7861) (xy 129.892804 -248.754975) (xy 129.860169 -248.718138)
			(xy 129.833866 -248.676542) (xy 129.814575 -248.631266) (xy 129.802798 -248.583482) (xy 129.798838 -248.534428)
			(xy 129.480564 -248.534428) (xy 129.480052 -248.559874) (xy 129.471888 -248.610108) (xy 129.455772 -248.658382)
			(xy 129.432121 -248.703445) (xy 129.401548 -248.744131) (xy 129.364844 -248.779386) (xy 129.32296 -248.808296)
			(xy 129.276981 -248.830113) (xy 129.228097 -248.844273) (xy 129.177576 -248.850407) (xy 129.126724 -248.848358)
			(xy 129.07686 -248.838178) (xy 129.029274 -248.820131) (xy 128.9852 -248.794685) (xy 128.945778 -248.762498)
			(xy 128.91203 -248.724404) (xy 128.884829 -248.68139) (xy 128.864881 -248.63457) (xy 128.852702 -248.585156)
			(xy 128.848607 -248.534428) (xy 128.54051 -248.534428) (xy 128.539998 -248.559874) (xy 128.531834 -248.610108)
			(xy 128.515718 -248.658382) (xy 128.492067 -248.703445) (xy 128.461494 -248.744131) (xy 128.42479 -248.779386)
			(xy 128.382906 -248.808296) (xy 128.336927 -248.830113) (xy 128.288043 -248.844273) (xy 128.237522 -248.850407)
			(xy 128.18667 -248.848358) (xy 128.136806 -248.838178) (xy 128.08922 -248.820131) (xy 128.045146 -248.794685)
			(xy 128.005724 -248.762498) (xy 127.971976 -248.724404) (xy 127.944775 -248.68139) (xy 127.924827 -248.63457)
			(xy 127.912648 -248.585156) (xy 127.908553 -248.534428) (xy 127.590501 -248.534428) (xy 127.586333 -248.58473)
			(xy 127.573936 -248.633687) (xy 127.553651 -248.679937) (xy 127.52603 -248.722217) (xy 127.491828 -248.759374)
			(xy 127.451976 -248.790396) (xy 127.407563 -248.814436) (xy 127.359798 -248.830838) (xy 127.309985 -248.839156)
			(xy 127.284734 -248.839736) (xy 127.271971 -248.8396) (xy 127.246536 -248.837442) (xy 127.233934 -248.835418)
			(xy 127.233934 -248.835672) (xy 127.211263 -248.831417) (xy 127.16745 -248.816992) (xy 127.126298 -248.796154)
			(xy 127.088741 -248.769374) (xy 127.071882 -248.75363) (xy 127.071374 -248.753122) (xy 127.065876 -248.748133)
			(xy 127.05271 -248.741286) (xy 127.045466 -248.73966) (xy 127.038354 -248.73839) (xy 127.023876 -248.739914)
			(xy 126.92761 -248.780554) (xy 126.919649 -248.784938) (xy 126.90723 -248.79819) (xy 126.900188 -248.814932)
			(xy 126.899416 -248.823988) (xy 126.899416 -249.014996) (xy 126.899692 -249.022552) (xy 126.904074 -249.037015)
			(xy 126.908052 -249.043444) (xy 126.91237 -249.049794) (xy 126.9238 -249.058938) (xy 126.930912 -249.061986)
			(xy 126.952985 -249.071548) (xy 126.994055 -249.096588) (xy 127.030692 -249.127758) (xy 127.061988 -249.164286)
			(xy 127.08717 -249.205269) (xy 127.105616 -249.249693) (xy 127.116868 -249.29646) (xy 127.120648 -249.344413)
			(xy 127.120646 -249.344434) (xy 127.438399 -249.344434) (xy 127.442494 -249.293706) (xy 127.454673 -249.244292)
			(xy 127.474621 -249.197472) (xy 127.501822 -249.154458) (xy 127.53557 -249.116364) (xy 127.574992 -249.084177)
			(xy 127.619066 -249.058731) (xy 127.666652 -249.040684) (xy 127.716516 -249.030504) (xy 127.767368 -249.028455)
			(xy 127.817889 -249.034589) (xy 127.866773 -249.048749) (xy 127.912752 -249.070566) (xy 127.954636 -249.099476)
			(xy 127.99134 -249.134731) (xy 128.021913 -249.175417) (xy 128.045564 -249.22048) (xy 128.06168 -249.268754)
			(xy 128.069844 -249.318988) (xy 128.070356 -249.344434) (xy 128.388884 -249.344434) (xy 128.392844 -249.29538)
			(xy 128.404621 -249.247596) (xy 128.423912 -249.20232) (xy 128.450215 -249.160724) (xy 128.48285 -249.123887)
			(xy 128.520971 -249.092762) (xy 128.563592 -249.068155) (xy 128.609608 -249.050703) (xy 128.657827 -249.040859)
			(xy 128.707002 -249.038878) (xy 128.755857 -249.04481) (xy 128.803128 -249.058502) (xy 128.84759 -249.0796)
			(xy 128.888093 -249.107556) (xy 128.923586 -249.141648) (xy 128.953151 -249.180992) (xy 128.976022 -249.224569)
			(xy 128.991606 -249.27125) (xy 128.999501 -249.319827) (xy 128.999996 -249.344434) (xy 129.328938 -249.344434)
			(xy 129.332898 -249.29538) (xy 129.344675 -249.247596) (xy 129.363966 -249.20232) (xy 129.390269 -249.160724)
			(xy 129.422904 -249.123887) (xy 129.461025 -249.092762) (xy 129.503646 -249.068155) (xy 129.549662 -249.050703)
			(xy 129.597881 -249.040859) (xy 129.647056 -249.038878) (xy 129.695911 -249.04481) (xy 129.743182 -249.058502)
			(xy 129.787644 -249.0796) (xy 129.828147 -249.107556) (xy 129.86364 -249.141648) (xy 129.893205 -249.180992)
			(xy 129.916076 -249.224569) (xy 129.93166 -249.27125) (xy 129.939555 -249.319827) (xy 129.94005 -249.344434)
			(xy 131.198615 -249.344434) (xy 131.20271 -249.293706) (xy 131.214889 -249.244292) (xy 131.234837 -249.197472)
			(xy 131.262038 -249.154458) (xy 131.295786 -249.116364) (xy 131.335208 -249.084177) (xy 131.379282 -249.058731)
			(xy 131.426868 -249.040684) (xy 131.476732 -249.030504) (xy 131.527584 -249.028455) (xy 131.578105 -249.034589)
			(xy 131.626989 -249.048749) (xy 131.672968 -249.070566) (xy 131.714852 -249.099476) (xy 131.751556 -249.134731)
			(xy 131.782129 -249.175417) (xy 131.80578 -249.22048) (xy 131.821896 -249.268754) (xy 131.83006 -249.318988)
			(xy 131.830572 -249.344434) (xy 132.148846 -249.344434) (xy 132.152806 -249.29538) (xy 132.164583 -249.247596)
			(xy 132.183874 -249.20232) (xy 132.210177 -249.160724) (xy 132.242812 -249.123887) (xy 132.280933 -249.092762)
			(xy 132.323554 -249.068155) (xy 132.36957 -249.050703) (xy 132.417789 -249.040859) (xy 132.466964 -249.038878)
			(xy 132.515819 -249.04481) (xy 132.56309 -249.058502) (xy 132.607552 -249.0796) (xy 132.648055 -249.107556)
			(xy 132.683548 -249.141648) (xy 132.713113 -249.180992) (xy 132.735984 -249.224569) (xy 132.751568 -249.27125)
			(xy 132.759463 -249.319827) (xy 132.759958 -249.344434) (xy 133.0889 -249.344434) (xy 133.09286 -249.29538)
			(xy 133.104637 -249.247596) (xy 133.123928 -249.20232) (xy 133.150231 -249.160724) (xy 133.182866 -249.123887)
			(xy 133.220987 -249.092762) (xy 133.263608 -249.068155) (xy 133.309624 -249.050703) (xy 133.357843 -249.040859)
			(xy 133.407018 -249.038878) (xy 133.455873 -249.04481) (xy 133.503144 -249.058502) (xy 133.547606 -249.0796)
			(xy 133.588109 -249.107556) (xy 133.623602 -249.141648) (xy 133.653167 -249.180992) (xy 133.676038 -249.224569)
			(xy 133.691622 -249.27125) (xy 133.699517 -249.319827) (xy 133.700012 -249.344434) (xy 134.028954 -249.344434)
			(xy 134.032914 -249.29538) (xy 134.044691 -249.247596) (xy 134.063982 -249.20232) (xy 134.090285 -249.160724)
			(xy 134.12292 -249.123887) (xy 134.161041 -249.092762) (xy 134.203662 -249.068155) (xy 134.249678 -249.050703)
			(xy 134.297897 -249.040859) (xy 134.347072 -249.038878) (xy 134.395927 -249.04481) (xy 134.443198 -249.058502)
			(xy 134.48766 -249.0796) (xy 134.528163 -249.107556) (xy 134.563656 -249.141648) (xy 134.593221 -249.180992)
			(xy 134.616092 -249.224569) (xy 134.631676 -249.27125) (xy 134.639571 -249.319827) (xy 134.640066 -249.344434)
			(xy 134.969008 -249.344434) (xy 134.972968 -249.29538) (xy 134.984745 -249.247596) (xy 135.004036 -249.20232)
			(xy 135.030339 -249.160724) (xy 135.062974 -249.123887) (xy 135.101095 -249.092762) (xy 135.143716 -249.068155)
			(xy 135.189732 -249.050703) (xy 135.237951 -249.040859) (xy 135.287126 -249.038878) (xy 135.335981 -249.04481)
			(xy 135.383252 -249.058502) (xy 135.427714 -249.0796) (xy 135.468217 -249.107556) (xy 135.50371 -249.141648)
			(xy 135.533275 -249.180992) (xy 135.556146 -249.224569) (xy 135.57173 -249.27125) (xy 135.579625 -249.319827)
			(xy 135.58012 -249.344434) (xy 135.909062 -249.344434) (xy 135.913022 -249.29538) (xy 135.924799 -249.247596)
			(xy 135.94409 -249.20232) (xy 135.970393 -249.160724) (xy 136.003028 -249.123887) (xy 136.041149 -249.092762)
			(xy 136.08377 -249.068155) (xy 136.129786 -249.050703) (xy 136.178005 -249.040859) (xy 136.22718 -249.038878)
			(xy 136.276035 -249.04481) (xy 136.323306 -249.058502) (xy 136.367768 -249.0796) (xy 136.408271 -249.107556)
			(xy 136.443764 -249.141648) (xy 136.473329 -249.180992) (xy 136.4962 -249.224569) (xy 136.511784 -249.27125)
			(xy 136.519679 -249.319827) (xy 136.520174 -249.344434) (xy 137.788916 -249.344434) (xy 137.792876 -249.29538)
			(xy 137.804653 -249.247596) (xy 137.823944 -249.20232) (xy 137.850247 -249.160724) (xy 137.882882 -249.123887)
			(xy 137.921003 -249.092762) (xy 137.963624 -249.068155) (xy 138.00964 -249.050703) (xy 138.057859 -249.040859)
			(xy 138.107034 -249.038878) (xy 138.155889 -249.04481) (xy 138.20316 -249.058502) (xy 138.247622 -249.0796)
			(xy 138.288125 -249.107556) (xy 138.323618 -249.141648) (xy 138.353183 -249.180992) (xy 138.376054 -249.224569)
			(xy 138.391638 -249.27125) (xy 138.399533 -249.319827) (xy 138.400028 -249.344434) (xy 138.72897 -249.344434)
			(xy 138.73293 -249.29538) (xy 138.744707 -249.247596) (xy 138.763998 -249.20232) (xy 138.790301 -249.160724)
			(xy 138.822936 -249.123887) (xy 138.861057 -249.092762) (xy 138.903678 -249.068155) (xy 138.949694 -249.050703)
			(xy 138.997913 -249.040859) (xy 139.047088 -249.038878) (xy 139.095943 -249.04481) (xy 139.143214 -249.058502)
			(xy 139.187676 -249.0796) (xy 139.228179 -249.107556) (xy 139.263672 -249.141648) (xy 139.293237 -249.180992)
			(xy 139.316108 -249.224569) (xy 139.331692 -249.27125) (xy 139.339587 -249.319827) (xy 139.340082 -249.344434)
			(xy 139.339587 -249.369041) (xy 139.331692 -249.417618) (xy 139.316108 -249.464299) (xy 139.293237 -249.507876)
			(xy 139.263672 -249.54722) (xy 139.228179 -249.581312) (xy 139.187676 -249.609268) (xy 139.143214 -249.630366)
			(xy 139.095943 -249.644058) (xy 139.047088 -249.64999) (xy 138.997913 -249.648009) (xy 138.949694 -249.638165)
			(xy 138.903678 -249.620713) (xy 138.861057 -249.596106) (xy 138.822936 -249.564981) (xy 138.790301 -249.528144)
			(xy 138.763998 -249.486548) (xy 138.744707 -249.441272) (xy 138.73293 -249.393488) (xy 138.72897 -249.344434)
			(xy 138.400028 -249.344434) (xy 138.399533 -249.369041) (xy 138.391638 -249.417618) (xy 138.376054 -249.464299)
			(xy 138.353183 -249.507876) (xy 138.323618 -249.54722) (xy 138.288125 -249.581312) (xy 138.247622 -249.609268)
			(xy 138.20316 -249.630366) (xy 138.155889 -249.644058) (xy 138.107034 -249.64999) (xy 138.057859 -249.648009)
			(xy 138.00964 -249.638165) (xy 137.963624 -249.620713) (xy 137.921003 -249.596106) (xy 137.882882 -249.564981)
			(xy 137.850247 -249.528144) (xy 137.823944 -249.486548) (xy 137.804653 -249.441272) (xy 137.792876 -249.393488)
			(xy 137.788916 -249.344434) (xy 136.520174 -249.344434) (xy 136.519679 -249.369041) (xy 136.511784 -249.417618)
			(xy 136.4962 -249.464299) (xy 136.473329 -249.507876) (xy 136.443764 -249.54722) (xy 136.408271 -249.581312)
			(xy 136.367768 -249.609268) (xy 136.323306 -249.630366) (xy 136.276035 -249.644058) (xy 136.22718 -249.64999)
			(xy 136.178005 -249.648009) (xy 136.129786 -249.638165) (xy 136.08377 -249.620713) (xy 136.041149 -249.596106)
			(xy 136.003028 -249.564981) (xy 135.970393 -249.528144) (xy 135.94409 -249.486548) (xy 135.924799 -249.441272)
			(xy 135.913022 -249.393488) (xy 135.909062 -249.344434) (xy 135.58012 -249.344434) (xy 135.579625 -249.369041)
			(xy 135.57173 -249.417618) (xy 135.556146 -249.464299) (xy 135.533275 -249.507876) (xy 135.50371 -249.54722)
			(xy 135.468217 -249.581312) (xy 135.427714 -249.609268) (xy 135.383252 -249.630366) (xy 135.335981 -249.644058)
			(xy 135.287126 -249.64999) (xy 135.237951 -249.648009) (xy 135.189732 -249.638165) (xy 135.143716 -249.620713)
			(xy 135.101095 -249.596106) (xy 135.062974 -249.564981) (xy 135.030339 -249.528144) (xy 135.004036 -249.486548)
			(xy 134.984745 -249.441272) (xy 134.972968 -249.393488) (xy 134.969008 -249.344434) (xy 134.640066 -249.344434)
			(xy 134.639571 -249.369041) (xy 134.631676 -249.417618) (xy 134.616092 -249.464299) (xy 134.593221 -249.507876)
			(xy 134.563656 -249.54722) (xy 134.528163 -249.581312) (xy 134.48766 -249.609268) (xy 134.443198 -249.630366)
			(xy 134.395927 -249.644058) (xy 134.347072 -249.64999) (xy 134.297897 -249.648009) (xy 134.249678 -249.638165)
			(xy 134.203662 -249.620713) (xy 134.161041 -249.596106) (xy 134.12292 -249.564981) (xy 134.090285 -249.528144)
			(xy 134.063982 -249.486548) (xy 134.044691 -249.441272) (xy 134.032914 -249.393488) (xy 134.028954 -249.344434)
			(xy 133.700012 -249.344434) (xy 133.699517 -249.369041) (xy 133.691622 -249.417618) (xy 133.676038 -249.464299)
			(xy 133.653167 -249.507876) (xy 133.623602 -249.54722) (xy 133.588109 -249.581312) (xy 133.547606 -249.609268)
			(xy 133.503144 -249.630366) (xy 133.455873 -249.644058) (xy 133.407018 -249.64999) (xy 133.357843 -249.648009)
			(xy 133.309624 -249.638165) (xy 133.263608 -249.620713) (xy 133.220987 -249.596106) (xy 133.182866 -249.564981)
			(xy 133.150231 -249.528144) (xy 133.123928 -249.486548) (xy 133.104637 -249.441272) (xy 133.09286 -249.393488)
			(xy 133.0889 -249.344434) (xy 132.759958 -249.344434) (xy 132.759463 -249.369041) (xy 132.751568 -249.417618)
			(xy 132.735984 -249.464299) (xy 132.713113 -249.507876) (xy 132.683548 -249.54722) (xy 132.648055 -249.581312)
			(xy 132.607552 -249.609268) (xy 132.56309 -249.630366) (xy 132.515819 -249.644058) (xy 132.466964 -249.64999)
			(xy 132.417789 -249.648009) (xy 132.36957 -249.638165) (xy 132.323554 -249.620713) (xy 132.280933 -249.596106)
			(xy 132.242812 -249.564981) (xy 132.210177 -249.528144) (xy 132.183874 -249.486548) (xy 132.164583 -249.441272)
			(xy 132.152806 -249.393488) (xy 132.148846 -249.344434) (xy 131.830572 -249.344434) (xy 131.83006 -249.36988)
			(xy 131.821896 -249.420114) (xy 131.80578 -249.468388) (xy 131.782129 -249.513451) (xy 131.751556 -249.554137)
			(xy 131.714852 -249.589392) (xy 131.672968 -249.618302) (xy 131.626989 -249.640119) (xy 131.578105 -249.654279)
			(xy 131.527584 -249.660413) (xy 131.476732 -249.658364) (xy 131.426868 -249.648184) (xy 131.379282 -249.630137)
			(xy 131.335208 -249.604691) (xy 131.295786 -249.572504) (xy 131.262038 -249.53441) (xy 131.234837 -249.491396)
			(xy 131.214889 -249.444576) (xy 131.20271 -249.395162) (xy 131.198615 -249.344434) (xy 129.94005 -249.344434)
			(xy 129.939555 -249.369041) (xy 129.93166 -249.417618) (xy 129.916076 -249.464299) (xy 129.893205 -249.507876)
			(xy 129.86364 -249.54722) (xy 129.828147 -249.581312) (xy 129.787644 -249.609268) (xy 129.743182 -249.630366)
			(xy 129.695911 -249.644058) (xy 129.647056 -249.64999) (xy 129.597881 -249.648009) (xy 129.549662 -249.638165)
			(xy 129.503646 -249.620713) (xy 129.461025 -249.596106) (xy 129.422904 -249.564981) (xy 129.390269 -249.528144)
			(xy 129.363966 -249.486548) (xy 129.344675 -249.441272) (xy 129.332898 -249.393488) (xy 129.328938 -249.344434)
			(xy 128.999996 -249.344434) (xy 128.999501 -249.369041) (xy 128.991606 -249.417618) (xy 128.976022 -249.464299)
			(xy 128.953151 -249.507876) (xy 128.923586 -249.54722) (xy 128.888093 -249.581312) (xy 128.84759 -249.609268)
			(xy 128.803128 -249.630366) (xy 128.755857 -249.644058) (xy 128.707002 -249.64999) (xy 128.657827 -249.648009)
			(xy 128.609608 -249.638165) (xy 128.563592 -249.620713) (xy 128.520971 -249.596106) (xy 128.48285 -249.564981)
			(xy 128.450215 -249.528144) (xy 128.423912 -249.486548) (xy 128.404621 -249.441272) (xy 128.392844 -249.393488)
			(xy 128.388884 -249.344434) (xy 128.070356 -249.344434) (xy 128.069844 -249.36988) (xy 128.06168 -249.420114)
			(xy 128.045564 -249.468388) (xy 128.021913 -249.513451) (xy 127.99134 -249.554137) (xy 127.954636 -249.589392)
			(xy 127.912752 -249.618302) (xy 127.866773 -249.640119) (xy 127.817889 -249.654279) (xy 127.767368 -249.660413)
			(xy 127.716516 -249.658364) (xy 127.666652 -249.648184) (xy 127.619066 -249.630137) (xy 127.574992 -249.604691)
			(xy 127.53557 -249.572504) (xy 127.501822 -249.53441) (xy 127.474621 -249.491396) (xy 127.454673 -249.444576)
			(xy 127.442494 -249.395162) (xy 127.438399 -249.344434) (xy 127.120646 -249.344434) (xy 127.116864 -249.392365)
			(xy 127.105608 -249.439132) (xy 127.087159 -249.483554) (xy 127.061973 -249.524535) (xy 127.030673 -249.561061)
			(xy 126.994034 -249.592227) (xy 126.952962 -249.617263) (xy 126.930912 -249.626882) (xy 126.9238 -249.62993)
			(xy 126.91237 -249.639074) (xy 126.908052 -249.645424) (xy 126.904018 -249.651829) (xy 126.899616 -249.666305)
			(xy 126.899416 -249.673872) (xy 126.899416 -250.15444) (xy 127.908553 -250.15444) (xy 127.912648 -250.103712)
			(xy 127.924827 -250.054298) (xy 127.944775 -250.007478) (xy 127.971976 -249.964464) (xy 128.005724 -249.92637)
			(xy 128.045146 -249.894183) (xy 128.08922 -249.868737) (xy 128.136806 -249.85069) (xy 128.18667 -249.84051)
			(xy 128.237522 -249.838461) (xy 128.288043 -249.844595) (xy 128.336927 -249.858755) (xy 128.382906 -249.880572)
			(xy 128.42479 -249.909482) (xy 128.461494 -249.944737) (xy 128.492067 -249.985423) (xy 128.515718 -250.030486)
			(xy 128.531834 -250.07876) (xy 128.539998 -250.128994) (xy 128.54051 -250.15444) (xy 128.859038 -250.15444)
			(xy 128.862998 -250.105386) (xy 128.874775 -250.057602) (xy 128.894066 -250.012326) (xy 128.920369 -249.97073)
			(xy 128.953004 -249.933893) (xy 128.991125 -249.902768) (xy 129.033746 -249.878161) (xy 129.079762 -249.860709)
			(xy 129.127981 -249.850865) (xy 129.177156 -249.848884) (xy 129.226011 -249.854816) (xy 129.273282 -249.868508)
			(xy 129.317744 -249.889606) (xy 129.358247 -249.917562) (xy 129.39374 -249.951654) (xy 129.423305 -249.990998)
			(xy 129.446176 -250.034575) (xy 129.46176 -250.081256) (xy 129.469655 -250.129833) (xy 129.47015 -250.15444)
			(xy 129.798838 -250.15444) (xy 129.802798 -250.105386) (xy 129.814575 -250.057602) (xy 129.833866 -250.012326)
			(xy 129.860169 -249.97073) (xy 129.892804 -249.933893) (xy 129.930925 -249.902768) (xy 129.973546 -249.878161)
			(xy 130.019562 -249.860709) (xy 130.067781 -249.850865) (xy 130.116956 -249.848884) (xy 130.165811 -249.854816)
			(xy 130.213082 -249.868508) (xy 130.257544 -249.889606) (xy 130.298047 -249.917562) (xy 130.33354 -249.951654)
			(xy 130.363105 -249.990998) (xy 130.385976 -250.034575) (xy 130.40156 -250.081256) (xy 130.409455 -250.129833)
			(xy 130.40995 -250.15444) (xy 130.728461 -250.15444) (xy 130.732556 -250.103712) (xy 130.744735 -250.054298)
			(xy 130.764683 -250.007478) (xy 130.791884 -249.964464) (xy 130.825632 -249.92637) (xy 130.865054 -249.894183)
			(xy 130.909128 -249.868737) (xy 130.956714 -249.85069) (xy 131.006578 -249.84051) (xy 131.05743 -249.838461)
			(xy 131.107951 -249.844595) (xy 131.156835 -249.858755) (xy 131.202814 -249.880572) (xy 131.244698 -249.909482)
			(xy 131.281402 -249.944737) (xy 131.311975 -249.985423) (xy 131.335626 -250.030486) (xy 131.351742 -250.07876)
			(xy 131.359906 -250.128994) (xy 131.360418 -250.15444) (xy 131.678946 -250.15444) (xy 131.682906 -250.105386)
			(xy 131.694683 -250.057602) (xy 131.713974 -250.012326) (xy 131.740277 -249.97073) (xy 131.772912 -249.933893)
			(xy 131.811033 -249.902768) (xy 131.853654 -249.878161) (xy 131.89967 -249.860709) (xy 131.947889 -249.850865)
			(xy 131.997064 -249.848884) (xy 132.045919 -249.854816) (xy 132.09319 -249.868508) (xy 132.137652 -249.889606)
			(xy 132.178155 -249.917562) (xy 132.213648 -249.951654) (xy 132.243213 -249.990998) (xy 132.266084 -250.034575)
			(xy 132.281668 -250.081256) (xy 132.289563 -250.129833) (xy 132.290058 -250.15444) (xy 132.619 -250.15444)
			(xy 132.62296 -250.105386) (xy 132.634737 -250.057602) (xy 132.654028 -250.012326) (xy 132.680331 -249.97073)
			(xy 132.712966 -249.933893) (xy 132.751087 -249.902768) (xy 132.793708 -249.878161) (xy 132.839724 -249.860709)
			(xy 132.887943 -249.850865) (xy 132.937118 -249.848884) (xy 132.985973 -249.854816) (xy 133.033244 -249.868508)
			(xy 133.077706 -249.889606) (xy 133.118209 -249.917562) (xy 133.153702 -249.951654) (xy 133.183267 -249.990998)
			(xy 133.206138 -250.034575) (xy 133.221722 -250.081256) (xy 133.229617 -250.129833) (xy 133.230112 -250.15444)
			(xy 133.559054 -250.15444) (xy 133.563014 -250.105386) (xy 133.574791 -250.057602) (xy 133.594082 -250.012326)
			(xy 133.620385 -249.97073) (xy 133.65302 -249.933893) (xy 133.691141 -249.902768) (xy 133.733762 -249.878161)
			(xy 133.779778 -249.860709) (xy 133.827997 -249.850865) (xy 133.877172 -249.848884) (xy 133.926027 -249.854816)
			(xy 133.973298 -249.868508) (xy 134.01776 -249.889606) (xy 134.058263 -249.917562) (xy 134.093756 -249.951654)
			(xy 134.123321 -249.990998) (xy 134.146192 -250.034575) (xy 134.161776 -250.081256) (xy 134.169671 -250.129833)
			(xy 134.170166 -250.15444) (xy 134.498854 -250.15444) (xy 134.502814 -250.105386) (xy 134.514591 -250.057602)
			(xy 134.533882 -250.012326) (xy 134.560185 -249.97073) (xy 134.59282 -249.933893) (xy 134.630941 -249.902768)
			(xy 134.673562 -249.878161) (xy 134.719578 -249.860709) (xy 134.767797 -249.850865) (xy 134.816972 -249.848884)
			(xy 134.865827 -249.854816) (xy 134.913098 -249.868508) (xy 134.95756 -249.889606) (xy 134.998063 -249.917562)
			(xy 135.033556 -249.951654) (xy 135.063121 -249.990998) (xy 135.085992 -250.034575) (xy 135.101576 -250.081256)
			(xy 135.109471 -250.129833) (xy 135.109966 -250.15444) (xy 135.438908 -250.15444) (xy 135.442868 -250.105386)
			(xy 135.454645 -250.057602) (xy 135.473936 -250.012326) (xy 135.500239 -249.97073) (xy 135.532874 -249.933893)
			(xy 135.570995 -249.902768) (xy 135.613616 -249.878161) (xy 135.659632 -249.860709) (xy 135.707851 -249.850865)
			(xy 135.757026 -249.848884) (xy 135.805881 -249.854816) (xy 135.853152 -249.868508) (xy 135.897614 -249.889606)
			(xy 135.938117 -249.917562) (xy 135.97361 -249.951654) (xy 136.003175 -249.990998) (xy 136.026046 -250.034575)
			(xy 136.04163 -250.081256) (xy 136.049525 -250.129833) (xy 136.05002 -250.15444) (xy 136.378962 -250.15444)
			(xy 136.382922 -250.105386) (xy 136.394699 -250.057602) (xy 136.41399 -250.012326) (xy 136.440293 -249.97073)
			(xy 136.472928 -249.933893) (xy 136.511049 -249.902768) (xy 136.55367 -249.878161) (xy 136.599686 -249.860709)
			(xy 136.647905 -249.850865) (xy 136.69708 -249.848884) (xy 136.745935 -249.854816) (xy 136.793206 -249.868508)
			(xy 136.837668 -249.889606) (xy 136.878171 -249.917562) (xy 136.913664 -249.951654) (xy 136.943229 -249.990998)
			(xy 136.9661 -250.034575) (xy 136.981684 -250.081256) (xy 136.989579 -250.129833) (xy 136.990074 -250.15444)
			(xy 137.319016 -250.15444) (xy 137.322976 -250.105386) (xy 137.334753 -250.057602) (xy 137.354044 -250.012326)
			(xy 137.380347 -249.97073) (xy 137.412982 -249.933893) (xy 137.451103 -249.902768) (xy 137.493724 -249.878161)
			(xy 137.53974 -249.860709) (xy 137.587959 -249.850865) (xy 137.637134 -249.848884) (xy 137.685989 -249.854816)
			(xy 137.73326 -249.868508) (xy 137.777722 -249.889606) (xy 137.818225 -249.917562) (xy 137.853718 -249.951654)
			(xy 137.883283 -249.990998) (xy 137.906154 -250.034575) (xy 137.921738 -250.081256) (xy 137.929633 -250.129833)
			(xy 137.930128 -250.15444) (xy 138.25907 -250.15444) (xy 138.26303 -250.105386) (xy 138.274807 -250.057602)
			(xy 138.294098 -250.012326) (xy 138.320401 -249.97073) (xy 138.353036 -249.933893) (xy 138.391157 -249.902768)
			(xy 138.433778 -249.878161) (xy 138.479794 -249.860709) (xy 138.528013 -249.850865) (xy 138.577188 -249.848884)
			(xy 138.626043 -249.854816) (xy 138.673314 -249.868508) (xy 138.717776 -249.889606) (xy 138.758279 -249.917562)
			(xy 138.793772 -249.951654) (xy 138.823337 -249.990998) (xy 138.846208 -250.034575) (xy 138.861792 -250.081256)
			(xy 138.869687 -250.129833) (xy 138.870182 -250.15444) (xy 139.19887 -250.15444) (xy 139.20283 -250.105386)
			(xy 139.214607 -250.057602) (xy 139.233898 -250.012326) (xy 139.260201 -249.97073) (xy 139.292836 -249.933893)
			(xy 139.330957 -249.902768) (xy 139.373578 -249.878161) (xy 139.419594 -249.860709) (xy 139.467813 -249.850865)
			(xy 139.516988 -249.848884) (xy 139.565843 -249.854816) (xy 139.613114 -249.868508) (xy 139.657576 -249.889606)
			(xy 139.698079 -249.917562) (xy 139.733572 -249.951654) (xy 139.763137 -249.990998) (xy 139.786008 -250.034575)
			(xy 139.801592 -250.081256) (xy 139.809487 -250.129833) (xy 139.809982 -250.15444) (xy 139.809487 -250.179047)
			(xy 139.801592 -250.227624) (xy 139.786008 -250.274305) (xy 139.763137 -250.317882) (xy 139.733572 -250.357226)
			(xy 139.698079 -250.391318) (xy 139.657576 -250.419274) (xy 139.613114 -250.440372) (xy 139.565843 -250.454064)
			(xy 139.516988 -250.459996) (xy 139.467813 -250.458015) (xy 139.419594 -250.448171) (xy 139.373578 -250.430719)
			(xy 139.330957 -250.406112) (xy 139.292836 -250.374987) (xy 139.260201 -250.33815) (xy 139.233898 -250.296554)
			(xy 139.214607 -250.251278) (xy 139.20283 -250.203494) (xy 139.19887 -250.15444) (xy 138.870182 -250.15444)
			(xy 138.869687 -250.179047) (xy 138.861792 -250.227624) (xy 138.846208 -250.274305) (xy 138.823337 -250.317882)
			(xy 138.793772 -250.357226) (xy 138.758279 -250.391318) (xy 138.717776 -250.419274) (xy 138.673314 -250.440372)
			(xy 138.626043 -250.454064) (xy 138.577188 -250.459996) (xy 138.528013 -250.458015) (xy 138.479794 -250.448171)
			(xy 138.433778 -250.430719) (xy 138.391157 -250.406112) (xy 138.353036 -250.374987) (xy 138.320401 -250.33815)
			(xy 138.294098 -250.296554) (xy 138.274807 -250.251278) (xy 138.26303 -250.203494) (xy 138.25907 -250.15444)
			(xy 137.930128 -250.15444) (xy 137.929633 -250.179047) (xy 137.921738 -250.227624) (xy 137.906154 -250.274305)
			(xy 137.883283 -250.317882) (xy 137.853718 -250.357226) (xy 137.818225 -250.391318) (xy 137.777722 -250.419274)
			(xy 137.73326 -250.440372) (xy 137.685989 -250.454064) (xy 137.637134 -250.459996) (xy 137.587959 -250.458015)
			(xy 137.53974 -250.448171) (xy 137.493724 -250.430719) (xy 137.451103 -250.406112) (xy 137.412982 -250.374987)
			(xy 137.380347 -250.33815) (xy 137.354044 -250.296554) (xy 137.334753 -250.251278) (xy 137.322976 -250.203494)
			(xy 137.319016 -250.15444) (xy 136.990074 -250.15444) (xy 136.989579 -250.179047) (xy 136.981684 -250.227624)
			(xy 136.9661 -250.274305) (xy 136.943229 -250.317882) (xy 136.913664 -250.357226) (xy 136.878171 -250.391318)
			(xy 136.837668 -250.419274) (xy 136.793206 -250.440372) (xy 136.745935 -250.454064) (xy 136.69708 -250.459996)
			(xy 136.647905 -250.458015) (xy 136.599686 -250.448171) (xy 136.55367 -250.430719) (xy 136.511049 -250.406112)
			(xy 136.472928 -250.374987) (xy 136.440293 -250.33815) (xy 136.41399 -250.296554) (xy 136.394699 -250.251278)
			(xy 136.382922 -250.203494) (xy 136.378962 -250.15444) (xy 136.05002 -250.15444) (xy 136.049525 -250.179047)
			(xy 136.04163 -250.227624) (xy 136.026046 -250.274305) (xy 136.003175 -250.317882) (xy 135.97361 -250.357226)
			(xy 135.938117 -250.391318) (xy 135.897614 -250.419274) (xy 135.853152 -250.440372) (xy 135.805881 -250.454064)
			(xy 135.757026 -250.459996) (xy 135.707851 -250.458015) (xy 135.659632 -250.448171) (xy 135.613616 -250.430719)
			(xy 135.570995 -250.406112) (xy 135.532874 -250.374987) (xy 135.500239 -250.33815) (xy 135.473936 -250.296554)
			(xy 135.454645 -250.251278) (xy 135.442868 -250.203494) (xy 135.438908 -250.15444) (xy 135.109966 -250.15444)
			(xy 135.109471 -250.179047) (xy 135.101576 -250.227624) (xy 135.085992 -250.274305) (xy 135.063121 -250.317882)
			(xy 135.033556 -250.357226) (xy 134.998063 -250.391318) (xy 134.95756 -250.419274) (xy 134.913098 -250.440372)
			(xy 134.865827 -250.454064) (xy 134.816972 -250.459996) (xy 134.767797 -250.458015) (xy 134.719578 -250.448171)
			(xy 134.673562 -250.430719) (xy 134.630941 -250.406112) (xy 134.59282 -250.374987) (xy 134.560185 -250.33815)
			(xy 134.533882 -250.296554) (xy 134.514591 -250.251278) (xy 134.502814 -250.203494) (xy 134.498854 -250.15444)
			(xy 134.170166 -250.15444) (xy 134.169671 -250.179047) (xy 134.161776 -250.227624) (xy 134.146192 -250.274305)
			(xy 134.123321 -250.317882) (xy 134.093756 -250.357226) (xy 134.058263 -250.391318) (xy 134.01776 -250.419274)
			(xy 133.973298 -250.440372) (xy 133.926027 -250.454064) (xy 133.877172 -250.459996) (xy 133.827997 -250.458015)
			(xy 133.779778 -250.448171) (xy 133.733762 -250.430719) (xy 133.691141 -250.406112) (xy 133.65302 -250.374987)
			(xy 133.620385 -250.33815) (xy 133.594082 -250.296554) (xy 133.574791 -250.251278) (xy 133.563014 -250.203494)
			(xy 133.559054 -250.15444) (xy 133.230112 -250.15444) (xy 133.229617 -250.179047) (xy 133.221722 -250.227624)
			(xy 133.206138 -250.274305) (xy 133.183267 -250.317882) (xy 133.153702 -250.357226) (xy 133.118209 -250.391318)
			(xy 133.077706 -250.419274) (xy 133.033244 -250.440372) (xy 132.985973 -250.454064) (xy 132.937118 -250.459996)
			(xy 132.887943 -250.458015) (xy 132.839724 -250.448171) (xy 132.793708 -250.430719) (xy 132.751087 -250.406112)
			(xy 132.712966 -250.374987) (xy 132.680331 -250.33815) (xy 132.654028 -250.296554) (xy 132.634737 -250.251278)
			(xy 132.62296 -250.203494) (xy 132.619 -250.15444) (xy 132.290058 -250.15444) (xy 132.289563 -250.179047)
			(xy 132.281668 -250.227624) (xy 132.266084 -250.274305) (xy 132.243213 -250.317882) (xy 132.213648 -250.357226)
			(xy 132.178155 -250.391318) (xy 132.137652 -250.419274) (xy 132.09319 -250.440372) (xy 132.045919 -250.454064)
			(xy 131.997064 -250.459996) (xy 131.947889 -250.458015) (xy 131.89967 -250.448171) (xy 131.853654 -250.430719)
			(xy 131.811033 -250.406112) (xy 131.772912 -250.374987) (xy 131.740277 -250.33815) (xy 131.713974 -250.296554)
			(xy 131.694683 -250.251278) (xy 131.682906 -250.203494) (xy 131.678946 -250.15444) (xy 131.360418 -250.15444)
			(xy 131.359906 -250.179886) (xy 131.351742 -250.23012) (xy 131.335626 -250.278394) (xy 131.311975 -250.323457)
			(xy 131.281402 -250.364143) (xy 131.244698 -250.399398) (xy 131.202814 -250.428308) (xy 131.156835 -250.450125)
			(xy 131.107951 -250.464285) (xy 131.05743 -250.470419) (xy 131.006578 -250.46837) (xy 130.956714 -250.45819)
			(xy 130.909128 -250.440143) (xy 130.865054 -250.414697) (xy 130.825632 -250.38251) (xy 130.791884 -250.344416)
			(xy 130.764683 -250.301402) (xy 130.744735 -250.254582) (xy 130.732556 -250.205168) (xy 130.728461 -250.15444)
			(xy 130.40995 -250.15444) (xy 130.409455 -250.179047) (xy 130.40156 -250.227624) (xy 130.385976 -250.274305)
			(xy 130.363105 -250.317882) (xy 130.33354 -250.357226) (xy 130.298047 -250.391318) (xy 130.257544 -250.419274)
			(xy 130.213082 -250.440372) (xy 130.165811 -250.454064) (xy 130.116956 -250.459996) (xy 130.067781 -250.458015)
			(xy 130.019562 -250.448171) (xy 129.973546 -250.430719) (xy 129.930925 -250.406112) (xy 129.892804 -250.374987)
			(xy 129.860169 -250.33815) (xy 129.833866 -250.296554) (xy 129.814575 -250.251278) (xy 129.802798 -250.203494)
			(xy 129.798838 -250.15444) (xy 129.47015 -250.15444) (xy 129.469655 -250.179047) (xy 129.46176 -250.227624)
			(xy 129.446176 -250.274305) (xy 129.423305 -250.317882) (xy 129.39374 -250.357226) (xy 129.358247 -250.391318)
			(xy 129.317744 -250.419274) (xy 129.273282 -250.440372) (xy 129.226011 -250.454064) (xy 129.177156 -250.459996)
			(xy 129.127981 -250.458015) (xy 129.079762 -250.448171) (xy 129.033746 -250.430719) (xy 128.991125 -250.406112)
			(xy 128.953004 -250.374987) (xy 128.920369 -250.33815) (xy 128.894066 -250.296554) (xy 128.874775 -250.251278)
			(xy 128.862998 -250.203494) (xy 128.859038 -250.15444) (xy 128.54051 -250.15444) (xy 128.539998 -250.179886)
			(xy 128.531834 -250.23012) (xy 128.515718 -250.278394) (xy 128.492067 -250.323457) (xy 128.461494 -250.364143)
			(xy 128.42479 -250.399398) (xy 128.382906 -250.428308) (xy 128.336927 -250.450125) (xy 128.288043 -250.464285)
			(xy 128.237522 -250.470419) (xy 128.18667 -250.46837) (xy 128.136806 -250.45819) (xy 128.08922 -250.440143)
			(xy 128.045146 -250.414697) (xy 128.005724 -250.38251) (xy 127.971976 -250.344416) (xy 127.944775 -250.301402)
			(xy 127.924827 -250.254582) (xy 127.912648 -250.205168) (xy 127.908553 -250.15444) (xy 126.899416 -250.15444)
			(xy 126.899416 -250.276614) (xy 126.898991 -250.286683) (xy 126.891275 -250.305286) (xy 126.88443 -250.312682)
			(xy 126.576074 -250.621292) (xy 126.553722 -250.628404) (xy 126.55169 -250.624848) (xy 126.546987 -250.617267)
			(xy 126.533392 -250.605729) (xy 126.516662 -250.59956) (xy 126.507748 -250.599194) (xy 125.807978 -250.599194)
			(xy 125.798225 -250.599703) (xy 125.780189 -250.607145) (xy 125.772926 -250.613672) (xy 125.422152 -250.964446)
			(xy 126.50903 -250.964446) (xy 126.51299 -250.915392) (xy 126.524767 -250.867608) (xy 126.544058 -250.822332)
			(xy 126.570361 -250.780736) (xy 126.602996 -250.743899) (xy 126.641117 -250.712774) (xy 126.683738 -250.688167)
			(xy 126.729754 -250.670715) (xy 126.777973 -250.660871) (xy 126.827148 -250.65889) (xy 126.876003 -250.664822)
			(xy 126.923274 -250.678514) (xy 126.967736 -250.699612) (xy 127.008239 -250.727568) (xy 127.043732 -250.76166)
			(xy 127.073297 -250.801004) (xy 127.096168 -250.844581) (xy 127.111752 -250.891262) (xy 127.119647 -250.939839)
			(xy 127.120142 -250.964446) (xy 127.438399 -250.964446) (xy 127.442494 -250.913718) (xy 127.454673 -250.864304)
			(xy 127.474621 -250.817484) (xy 127.501822 -250.77447) (xy 127.53557 -250.736376) (xy 127.574992 -250.704189)
			(xy 127.619066 -250.678743) (xy 127.666652 -250.660696) (xy 127.716516 -250.650516) (xy 127.767368 -250.648467)
			(xy 127.817889 -250.654601) (xy 127.866773 -250.668761) (xy 127.912752 -250.690578) (xy 127.954636 -250.719488)
			(xy 127.99134 -250.754743) (xy 128.021913 -250.795429) (xy 128.045564 -250.840492) (xy 128.06168 -250.888766)
			(xy 128.069844 -250.939) (xy 128.070356 -250.964446) (xy 128.388884 -250.964446) (xy 128.392844 -250.915392)
			(xy 128.404621 -250.867608) (xy 128.423912 -250.822332) (xy 128.450215 -250.780736) (xy 128.48285 -250.743899)
			(xy 128.520971 -250.712774) (xy 128.563592 -250.688167) (xy 128.609608 -250.670715) (xy 128.657827 -250.660871)
			(xy 128.707002 -250.65889) (xy 128.755857 -250.664822) (xy 128.803128 -250.678514) (xy 128.84759 -250.699612)
			(xy 128.888093 -250.727568) (xy 128.923586 -250.76166) (xy 128.953151 -250.801004) (xy 128.976022 -250.844581)
			(xy 128.991606 -250.891262) (xy 128.999501 -250.939839) (xy 128.999996 -250.964446) (xy 129.318507 -250.964446)
			(xy 129.322602 -250.913718) (xy 129.334781 -250.864304) (xy 129.354729 -250.817484) (xy 129.38193 -250.77447)
			(xy 129.415678 -250.736376) (xy 129.4551 -250.704189) (xy 129.499174 -250.678743) (xy 129.54676 -250.660696)
			(xy 129.596624 -250.650516) (xy 129.647476 -250.648467) (xy 129.697997 -250.654601) (xy 129.746881 -250.668761)
			(xy 129.79286 -250.690578) (xy 129.834744 -250.719488) (xy 129.871448 -250.754743) (xy 129.902021 -250.795429)
			(xy 129.925672 -250.840492) (xy 129.941788 -250.888766) (xy 129.949952 -250.939) (xy 129.950464 -250.964446)
			(xy 130.268992 -250.964446) (xy 130.272952 -250.915392) (xy 130.284729 -250.867608) (xy 130.30402 -250.822332)
			(xy 130.330323 -250.780736) (xy 130.362958 -250.743899) (xy 130.401079 -250.712774) (xy 130.4437 -250.688167)
			(xy 130.489716 -250.670715) (xy 130.537935 -250.660871) (xy 130.58711 -250.65889) (xy 130.635965 -250.664822)
			(xy 130.683236 -250.678514) (xy 130.727698 -250.699612) (xy 130.768201 -250.727568) (xy 130.803694 -250.76166)
			(xy 130.833259 -250.801004) (xy 130.85613 -250.844581) (xy 130.871714 -250.891262) (xy 130.879609 -250.939839)
			(xy 130.880104 -250.964446) (xy 131.198615 -250.964446) (xy 131.20271 -250.913718) (xy 131.214889 -250.864304)
			(xy 131.234837 -250.817484) (xy 131.262038 -250.77447) (xy 131.295786 -250.736376) (xy 131.335208 -250.704189)
			(xy 131.379282 -250.678743) (xy 131.426868 -250.660696) (xy 131.476732 -250.650516) (xy 131.527584 -250.648467)
			(xy 131.578105 -250.654601) (xy 131.626989 -250.668761) (xy 131.672968 -250.690578) (xy 131.714852 -250.719488)
			(xy 131.751556 -250.754743) (xy 131.782129 -250.795429) (xy 131.80578 -250.840492) (xy 131.821896 -250.888766)
			(xy 131.83006 -250.939) (xy 131.830572 -250.964446) (xy 132.138415 -250.964446) (xy 132.14251 -250.913718)
			(xy 132.154689 -250.864304) (xy 132.174637 -250.817484) (xy 132.201838 -250.77447) (xy 132.235586 -250.736376)
			(xy 132.275008 -250.704189) (xy 132.319082 -250.678743) (xy 132.366668 -250.660696) (xy 132.416532 -250.650516)
			(xy 132.467384 -250.648467) (xy 132.517905 -250.654601) (xy 132.566789 -250.668761) (xy 132.612768 -250.690578)
			(xy 132.654652 -250.719488) (xy 132.691356 -250.754743) (xy 132.721929 -250.795429) (xy 132.74558 -250.840492)
			(xy 132.761696 -250.888766) (xy 132.76986 -250.939) (xy 132.770372 -250.964446) (xy 133.0889 -250.964446)
			(xy 133.09286 -250.915392) (xy 133.104637 -250.867608) (xy 133.123928 -250.822332) (xy 133.150231 -250.780736)
			(xy 133.182866 -250.743899) (xy 133.220987 -250.712774) (xy 133.263608 -250.688167) (xy 133.309624 -250.670715)
			(xy 133.357843 -250.660871) (xy 133.407018 -250.65889) (xy 133.455873 -250.664822) (xy 133.503144 -250.678514)
			(xy 133.547606 -250.699612) (xy 133.588109 -250.727568) (xy 133.623602 -250.76166) (xy 133.653167 -250.801004)
			(xy 133.676038 -250.844581) (xy 133.691622 -250.891262) (xy 133.699517 -250.939839) (xy 133.700012 -250.964446)
			(xy 134.028954 -250.964446) (xy 134.032914 -250.915392) (xy 134.044691 -250.867608) (xy 134.063982 -250.822332)
			(xy 134.090285 -250.780736) (xy 134.12292 -250.743899) (xy 134.161041 -250.712774) (xy 134.203662 -250.688167)
			(xy 134.249678 -250.670715) (xy 134.297897 -250.660871) (xy 134.347072 -250.65889) (xy 134.395927 -250.664822)
			(xy 134.443198 -250.678514) (xy 134.48766 -250.699612) (xy 134.528163 -250.727568) (xy 134.563656 -250.76166)
			(xy 134.593221 -250.801004) (xy 134.616092 -250.844581) (xy 134.631676 -250.891262) (xy 134.639571 -250.939839)
			(xy 134.640066 -250.964446) (xy 134.969008 -250.964446) (xy 134.972968 -250.915392) (xy 134.984745 -250.867608)
			(xy 135.004036 -250.822332) (xy 135.030339 -250.780736) (xy 135.062974 -250.743899) (xy 135.101095 -250.712774)
			(xy 135.143716 -250.688167) (xy 135.189732 -250.670715) (xy 135.237951 -250.660871) (xy 135.287126 -250.65889)
			(xy 135.335981 -250.664822) (xy 135.383252 -250.678514) (xy 135.427714 -250.699612) (xy 135.468217 -250.727568)
			(xy 135.50371 -250.76166) (xy 135.533275 -250.801004) (xy 135.556146 -250.844581) (xy 135.57173 -250.891262)
			(xy 135.579625 -250.939839) (xy 135.58012 -250.964446) (xy 135.909062 -250.964446) (xy 135.913022 -250.915392)
			(xy 135.924799 -250.867608) (xy 135.94409 -250.822332) (xy 135.970393 -250.780736) (xy 136.003028 -250.743899)
			(xy 136.041149 -250.712774) (xy 136.08377 -250.688167) (xy 136.129786 -250.670715) (xy 136.178005 -250.660871)
			(xy 136.22718 -250.65889) (xy 136.276035 -250.664822) (xy 136.323306 -250.678514) (xy 136.367768 -250.699612)
			(xy 136.408271 -250.727568) (xy 136.443764 -250.76166) (xy 136.473329 -250.801004) (xy 136.4962 -250.844581)
			(xy 136.511784 -250.891262) (xy 136.519679 -250.939839) (xy 136.520174 -250.964446) (xy 136.848862 -250.964446)
			(xy 136.852822 -250.915392) (xy 136.864599 -250.867608) (xy 136.88389 -250.822332) (xy 136.910193 -250.780736)
			(xy 136.942828 -250.743899) (xy 136.980949 -250.712774) (xy 137.02357 -250.688167) (xy 137.069586 -250.670715)
			(xy 137.117805 -250.660871) (xy 137.16698 -250.65889) (xy 137.215835 -250.664822) (xy 137.263106 -250.678514)
			(xy 137.307568 -250.699612) (xy 137.348071 -250.727568) (xy 137.383564 -250.76166) (xy 137.413129 -250.801004)
			(xy 137.436 -250.844581) (xy 137.451584 -250.891262) (xy 137.459479 -250.939839) (xy 137.459974 -250.964446)
			(xy 137.788916 -250.964446) (xy 137.792876 -250.915392) (xy 137.804653 -250.867608) (xy 137.823944 -250.822332)
			(xy 137.850247 -250.780736) (xy 137.882882 -250.743899) (xy 137.921003 -250.712774) (xy 137.963624 -250.688167)
			(xy 138.00964 -250.670715) (xy 138.057859 -250.660871) (xy 138.107034 -250.65889) (xy 138.155889 -250.664822)
			(xy 138.20316 -250.678514) (xy 138.247622 -250.699612) (xy 138.288125 -250.727568) (xy 138.323618 -250.76166)
			(xy 138.353183 -250.801004) (xy 138.376054 -250.844581) (xy 138.391638 -250.891262) (xy 138.399533 -250.939839)
			(xy 138.400028 -250.964446) (xy 138.72897 -250.964446) (xy 138.73293 -250.915392) (xy 138.744707 -250.867608)
			(xy 138.763998 -250.822332) (xy 138.790301 -250.780736) (xy 138.822936 -250.743899) (xy 138.861057 -250.712774)
			(xy 138.903678 -250.688167) (xy 138.949694 -250.670715) (xy 138.997913 -250.660871) (xy 139.047088 -250.65889)
			(xy 139.095943 -250.664822) (xy 139.143214 -250.678514) (xy 139.187676 -250.699612) (xy 139.228179 -250.727568)
			(xy 139.263672 -250.76166) (xy 139.293237 -250.801004) (xy 139.316108 -250.844581) (xy 139.331692 -250.891262)
			(xy 139.339587 -250.939839) (xy 139.340082 -250.964446) (xy 139.339587 -250.989053) (xy 139.331692 -251.03763)
			(xy 139.316108 -251.084311) (xy 139.293237 -251.127888) (xy 139.263672 -251.167232) (xy 139.228179 -251.201324)
			(xy 139.187676 -251.22928) (xy 139.143214 -251.250378) (xy 139.095943 -251.26407) (xy 139.047088 -251.270002)
			(xy 138.997913 -251.268021) (xy 138.949694 -251.258177) (xy 138.903678 -251.240725) (xy 138.861057 -251.216118)
			(xy 138.822936 -251.184993) (xy 138.790301 -251.148156) (xy 138.763998 -251.10656) (xy 138.744707 -251.061284)
			(xy 138.73293 -251.0135) (xy 138.72897 -250.964446) (xy 138.400028 -250.964446) (xy 138.399533 -250.989053)
			(xy 138.391638 -251.03763) (xy 138.376054 -251.084311) (xy 138.353183 -251.127888) (xy 138.323618 -251.167232)
			(xy 138.288125 -251.201324) (xy 138.247622 -251.22928) (xy 138.20316 -251.250378) (xy 138.155889 -251.26407)
			(xy 138.107034 -251.270002) (xy 138.057859 -251.268021) (xy 138.00964 -251.258177) (xy 137.963624 -251.240725)
			(xy 137.921003 -251.216118) (xy 137.882882 -251.184993) (xy 137.850247 -251.148156) (xy 137.823944 -251.10656)
			(xy 137.804653 -251.061284) (xy 137.792876 -251.0135) (xy 137.788916 -250.964446) (xy 137.459974 -250.964446)
			(xy 137.459479 -250.989053) (xy 137.451584 -251.03763) (xy 137.436 -251.084311) (xy 137.413129 -251.127888)
			(xy 137.383564 -251.167232) (xy 137.348071 -251.201324) (xy 137.307568 -251.22928) (xy 137.263106 -251.250378)
			(xy 137.215835 -251.26407) (xy 137.16698 -251.270002) (xy 137.117805 -251.268021) (xy 137.069586 -251.258177)
			(xy 137.02357 -251.240725) (xy 136.980949 -251.216118) (xy 136.942828 -251.184993) (xy 136.910193 -251.148156)
			(xy 136.88389 -251.10656) (xy 136.864599 -251.061284) (xy 136.852822 -251.0135) (xy 136.848862 -250.964446)
			(xy 136.520174 -250.964446) (xy 136.519679 -250.989053) (xy 136.511784 -251.03763) (xy 136.4962 -251.084311)
			(xy 136.473329 -251.127888) (xy 136.443764 -251.167232) (xy 136.408271 -251.201324) (xy 136.367768 -251.22928)
			(xy 136.323306 -251.250378) (xy 136.276035 -251.26407) (xy 136.22718 -251.270002) (xy 136.178005 -251.268021)
			(xy 136.129786 -251.258177) (xy 136.08377 -251.240725) (xy 136.041149 -251.216118) (xy 136.003028 -251.184993)
			(xy 135.970393 -251.148156) (xy 135.94409 -251.10656) (xy 135.924799 -251.061284) (xy 135.913022 -251.0135)
			(xy 135.909062 -250.964446) (xy 135.58012 -250.964446) (xy 135.579625 -250.989053) (xy 135.57173 -251.03763)
			(xy 135.556146 -251.084311) (xy 135.533275 -251.127888) (xy 135.50371 -251.167232) (xy 135.468217 -251.201324)
			(xy 135.427714 -251.22928) (xy 135.383252 -251.250378) (xy 135.335981 -251.26407) (xy 135.287126 -251.270002)
			(xy 135.237951 -251.268021) (xy 135.189732 -251.258177) (xy 135.143716 -251.240725) (xy 135.101095 -251.216118)
			(xy 135.062974 -251.184993) (xy 135.030339 -251.148156) (xy 135.004036 -251.10656) (xy 134.984745 -251.061284)
			(xy 134.972968 -251.0135) (xy 134.969008 -250.964446) (xy 134.640066 -250.964446) (xy 134.639571 -250.989053)
			(xy 134.631676 -251.03763) (xy 134.616092 -251.084311) (xy 134.593221 -251.127888) (xy 134.563656 -251.167232)
			(xy 134.528163 -251.201324) (xy 134.48766 -251.22928) (xy 134.443198 -251.250378) (xy 134.395927 -251.26407)
			(xy 134.347072 -251.270002) (xy 134.297897 -251.268021) (xy 134.249678 -251.258177) (xy 134.203662 -251.240725)
			(xy 134.161041 -251.216118) (xy 134.12292 -251.184993) (xy 134.090285 -251.148156) (xy 134.063982 -251.10656)
			(xy 134.044691 -251.061284) (xy 134.032914 -251.0135) (xy 134.028954 -250.964446) (xy 133.700012 -250.964446)
			(xy 133.699517 -250.989053) (xy 133.691622 -251.03763) (xy 133.676038 -251.084311) (xy 133.653167 -251.127888)
			(xy 133.623602 -251.167232) (xy 133.588109 -251.201324) (xy 133.547606 -251.22928) (xy 133.503144 -251.250378)
			(xy 133.455873 -251.26407) (xy 133.407018 -251.270002) (xy 133.357843 -251.268021) (xy 133.309624 -251.258177)
			(xy 133.263608 -251.240725) (xy 133.220987 -251.216118) (xy 133.182866 -251.184993) (xy 133.150231 -251.148156)
			(xy 133.123928 -251.10656) (xy 133.104637 -251.061284) (xy 133.09286 -251.0135) (xy 133.0889 -250.964446)
			(xy 132.770372 -250.964446) (xy 132.76986 -250.989892) (xy 132.761696 -251.040126) (xy 132.74558 -251.0884)
			(xy 132.721929 -251.133463) (xy 132.691356 -251.174149) (xy 132.654652 -251.209404) (xy 132.612768 -251.238314)
			(xy 132.566789 -251.260131) (xy 132.517905 -251.274291) (xy 132.467384 -251.280425) (xy 132.416532 -251.278376)
			(xy 132.366668 -251.268196) (xy 132.319082 -251.250149) (xy 132.275008 -251.224703) (xy 132.235586 -251.192516)
			(xy 132.201838 -251.154422) (xy 132.174637 -251.111408) (xy 132.154689 -251.064588) (xy 132.14251 -251.015174)
			(xy 132.138415 -250.964446) (xy 131.830572 -250.964446) (xy 131.83006 -250.989892) (xy 131.821896 -251.040126)
			(xy 131.80578 -251.0884) (xy 131.782129 -251.133463) (xy 131.751556 -251.174149) (xy 131.714852 -251.209404)
			(xy 131.672968 -251.238314) (xy 131.626989 -251.260131) (xy 131.578105 -251.274291) (xy 131.527584 -251.280425)
			(xy 131.476732 -251.278376) (xy 131.426868 -251.268196) (xy 131.379282 -251.250149) (xy 131.335208 -251.224703)
			(xy 131.295786 -251.192516) (xy 131.262038 -251.154422) (xy 131.234837 -251.111408) (xy 131.214889 -251.064588)
			(xy 131.20271 -251.015174) (xy 131.198615 -250.964446) (xy 130.880104 -250.964446) (xy 130.879609 -250.989053)
			(xy 130.871714 -251.03763) (xy 130.85613 -251.084311) (xy 130.833259 -251.127888) (xy 130.803694 -251.167232)
			(xy 130.768201 -251.201324) (xy 130.727698 -251.22928) (xy 130.683236 -251.250378) (xy 130.635965 -251.26407)
			(xy 130.58711 -251.270002) (xy 130.537935 -251.268021) (xy 130.489716 -251.258177) (xy 130.4437 -251.240725)
			(xy 130.401079 -251.216118) (xy 130.362958 -251.184993) (xy 130.330323 -251.148156) (xy 130.30402 -251.10656)
			(xy 130.284729 -251.061284) (xy 130.272952 -251.0135) (xy 130.268992 -250.964446) (xy 129.950464 -250.964446)
			(xy 129.949952 -250.989892) (xy 129.941788 -251.040126) (xy 129.925672 -251.0884) (xy 129.902021 -251.133463)
			(xy 129.871448 -251.174149) (xy 129.834744 -251.209404) (xy 129.79286 -251.238314) (xy 129.746881 -251.260131)
			(xy 129.697997 -251.274291) (xy 129.647476 -251.280425) (xy 129.596624 -251.278376) (xy 129.54676 -251.268196)
			(xy 129.499174 -251.250149) (xy 129.4551 -251.224703) (xy 129.415678 -251.192516) (xy 129.38193 -251.154422)
			(xy 129.354729 -251.111408) (xy 129.334781 -251.064588) (xy 129.322602 -251.015174) (xy 129.318507 -250.964446)
			(xy 128.999996 -250.964446) (xy 128.999501 -250.989053) (xy 128.991606 -251.03763) (xy 128.976022 -251.084311)
			(xy 128.953151 -251.127888) (xy 128.923586 -251.167232) (xy 128.888093 -251.201324) (xy 128.84759 -251.22928)
			(xy 128.803128 -251.250378) (xy 128.755857 -251.26407) (xy 128.707002 -251.270002) (xy 128.657827 -251.268021)
			(xy 128.609608 -251.258177) (xy 128.563592 -251.240725) (xy 128.520971 -251.216118) (xy 128.48285 -251.184993)
			(xy 128.450215 -251.148156) (xy 128.423912 -251.10656) (xy 128.404621 -251.061284) (xy 128.392844 -251.0135)
			(xy 128.388884 -250.964446) (xy 128.070356 -250.964446) (xy 128.069844 -250.989892) (xy 128.06168 -251.040126)
			(xy 128.045564 -251.0884) (xy 128.021913 -251.133463) (xy 127.99134 -251.174149) (xy 127.954636 -251.209404)
			(xy 127.912752 -251.238314) (xy 127.866773 -251.260131) (xy 127.817889 -251.274291) (xy 127.767368 -251.280425)
			(xy 127.716516 -251.278376) (xy 127.666652 -251.268196) (xy 127.619066 -251.250149) (xy 127.574992 -251.224703)
			(xy 127.53557 -251.192516) (xy 127.501822 -251.154422) (xy 127.474621 -251.111408) (xy 127.454673 -251.064588)
			(xy 127.442494 -251.015174) (xy 127.438399 -250.964446) (xy 127.120142 -250.964446) (xy 127.119647 -250.989053)
			(xy 127.111752 -251.03763) (xy 127.096168 -251.084311) (xy 127.073297 -251.127888) (xy 127.043732 -251.167232)
			(xy 127.008239 -251.201324) (xy 126.967736 -251.22928) (xy 126.923274 -251.250378) (xy 126.876003 -251.26407)
			(xy 126.827148 -251.270002) (xy 126.777973 -251.268021) (xy 126.729754 -251.258177) (xy 126.683738 -251.240725)
			(xy 126.641117 -251.216118) (xy 126.602996 -251.184993) (xy 126.570361 -251.148156) (xy 126.544058 -251.10656)
			(xy 126.524767 -251.061284) (xy 126.51299 -251.0135) (xy 126.50903 -250.964446) (xy 125.422152 -250.964446)
			(xy 124.876306 -251.510292) (xy 124.869123 -251.516974) (xy 124.851054 -251.524576) (xy 124.841254 -251.525024)
			(xy 124.8283 -251.525024) (xy 124.817378 -251.53112) (xy 124.812227 -251.534188) (xy 124.803379 -251.542273)
			(xy 124.799852 -251.547122) (xy 124.753878 -251.615702) (xy 124.750643 -251.620796) (xy 124.746396 -251.632088)
			(xy 124.745496 -251.638054) (xy 124.744226 -251.649992) (xy 124.749052 -251.662184) (xy 124.758881 -251.689007)
			(xy 124.769498 -251.745131) (xy 124.770134 -251.77369) (xy 124.770134 -251.774452) (xy 126.038876 -251.774452)
			(xy 126.042836 -251.725398) (xy 126.054613 -251.677614) (xy 126.073904 -251.632338) (xy 126.100207 -251.590742)
			(xy 126.132842 -251.553905) (xy 126.170963 -251.52278) (xy 126.213584 -251.498173) (xy 126.2596 -251.480721)
			(xy 126.307819 -251.470877) (xy 126.356994 -251.468896) (xy 126.405849 -251.474828) (xy 126.45312 -251.48852)
			(xy 126.497582 -251.509618) (xy 126.538085 -251.537574) (xy 126.573578 -251.571666) (xy 126.603143 -251.61101)
			(xy 126.626014 -251.654587) (xy 126.641598 -251.701268) (xy 126.649493 -251.749845) (xy 126.649988 -251.774452)
			(xy 127.908553 -251.774452) (xy 127.912648 -251.723724) (xy 127.924827 -251.67431) (xy 127.944775 -251.62749)
			(xy 127.971976 -251.584476) (xy 128.005724 -251.546382) (xy 128.045146 -251.514195) (xy 128.08922 -251.488749)
			(xy 128.136806 -251.470702) (xy 128.18667 -251.460522) (xy 128.237522 -251.458473) (xy 128.288043 -251.464607)
			(xy 128.336927 -251.478767) (xy 128.382906 -251.500584) (xy 128.42479 -251.529494) (xy 128.461494 -251.564749)
			(xy 128.492067 -251.605435) (xy 128.515718 -251.650498) (xy 128.531834 -251.698772) (xy 128.539998 -251.749006)
			(xy 128.54051 -251.774452) (xy 128.859038 -251.774452) (xy 128.862998 -251.725398) (xy 128.874775 -251.677614)
			(xy 128.894066 -251.632338) (xy 128.920369 -251.590742) (xy 128.953004 -251.553905) (xy 128.991125 -251.52278)
			(xy 129.033746 -251.498173) (xy 129.079762 -251.480721) (xy 129.127981 -251.470877) (xy 129.177156 -251.468896)
			(xy 129.226011 -251.474828) (xy 129.273282 -251.48852) (xy 129.317744 -251.509618) (xy 129.358247 -251.537574)
			(xy 129.39374 -251.571666) (xy 129.423305 -251.61101) (xy 129.446176 -251.654587) (xy 129.46176 -251.701268)
			(xy 129.469655 -251.749845) (xy 129.47015 -251.774452) (xy 130.728461 -251.774452) (xy 130.732556 -251.723724)
			(xy 130.744735 -251.67431) (xy 130.764683 -251.62749) (xy 130.791884 -251.584476) (xy 130.825632 -251.546382)
			(xy 130.865054 -251.514195) (xy 130.909128 -251.488749) (xy 130.956714 -251.470702) (xy 131.006578 -251.460522)
			(xy 131.05743 -251.458473) (xy 131.107951 -251.464607) (xy 131.156835 -251.478767) (xy 131.202814 -251.500584)
			(xy 131.244698 -251.529494) (xy 131.281402 -251.564749) (xy 131.311975 -251.605435) (xy 131.335626 -251.650498)
			(xy 131.351742 -251.698772) (xy 131.359906 -251.749006) (xy 131.360418 -251.774452) (xy 131.678946 -251.774452)
			(xy 131.682906 -251.725398) (xy 131.694683 -251.677614) (xy 131.713974 -251.632338) (xy 131.740277 -251.590742)
			(xy 131.772912 -251.553905) (xy 131.811033 -251.52278) (xy 131.853654 -251.498173) (xy 131.89967 -251.480721)
			(xy 131.947889 -251.470877) (xy 131.997064 -251.468896) (xy 132.045919 -251.474828) (xy 132.09319 -251.48852)
			(xy 132.137652 -251.509618) (xy 132.178155 -251.537574) (xy 132.213648 -251.571666) (xy 132.243213 -251.61101)
			(xy 132.266084 -251.654587) (xy 132.281668 -251.701268) (xy 132.289563 -251.749845) (xy 132.290058 -251.774452)
			(xy 132.619 -251.774452) (xy 132.62296 -251.725398) (xy 132.634737 -251.677614) (xy 132.654028 -251.632338)
			(xy 132.680331 -251.590742) (xy 132.712966 -251.553905) (xy 132.751087 -251.52278) (xy 132.793708 -251.498173)
			(xy 132.839724 -251.480721) (xy 132.887943 -251.470877) (xy 132.937118 -251.468896) (xy 132.985973 -251.474828)
			(xy 133.033244 -251.48852) (xy 133.077706 -251.509618) (xy 133.118209 -251.537574) (xy 133.153702 -251.571666)
			(xy 133.183267 -251.61101) (xy 133.206138 -251.654587) (xy 133.221722 -251.701268) (xy 133.229617 -251.749845)
			(xy 133.230112 -251.774452) (xy 133.559054 -251.774452) (xy 133.563014 -251.725398) (xy 133.574791 -251.677614)
			(xy 133.594082 -251.632338) (xy 133.620385 -251.590742) (xy 133.65302 -251.553905) (xy 133.691141 -251.52278)
			(xy 133.733762 -251.498173) (xy 133.779778 -251.480721) (xy 133.827997 -251.470877) (xy 133.877172 -251.468896)
			(xy 133.926027 -251.474828) (xy 133.973298 -251.48852) (xy 134.01776 -251.509618) (xy 134.058263 -251.537574)
			(xy 134.093756 -251.571666) (xy 134.123321 -251.61101) (xy 134.146192 -251.654587) (xy 134.161776 -251.701268)
			(xy 134.169671 -251.749845) (xy 134.170166 -251.774452) (xy 134.498854 -251.774452) (xy 134.502814 -251.725398)
			(xy 134.514591 -251.677614) (xy 134.533882 -251.632338) (xy 134.560185 -251.590742) (xy 134.59282 -251.553905)
			(xy 134.630941 -251.52278) (xy 134.673562 -251.498173) (xy 134.719578 -251.480721) (xy 134.767797 -251.470877)
			(xy 134.816972 -251.468896) (xy 134.865827 -251.474828) (xy 134.913098 -251.48852) (xy 134.95756 -251.509618)
			(xy 134.998063 -251.537574) (xy 135.033556 -251.571666) (xy 135.063121 -251.61101) (xy 135.085992 -251.654587)
			(xy 135.101576 -251.701268) (xy 135.109471 -251.749845) (xy 135.109966 -251.774452) (xy 135.438908 -251.774452)
			(xy 135.442868 -251.725398) (xy 135.454645 -251.677614) (xy 135.473936 -251.632338) (xy 135.500239 -251.590742)
			(xy 135.532874 -251.553905) (xy 135.570995 -251.52278) (xy 135.613616 -251.498173) (xy 135.659632 -251.480721)
			(xy 135.707851 -251.470877) (xy 135.757026 -251.468896) (xy 135.805881 -251.474828) (xy 135.853152 -251.48852)
			(xy 135.897614 -251.509618) (xy 135.938117 -251.537574) (xy 135.97361 -251.571666) (xy 136.003175 -251.61101)
			(xy 136.026046 -251.654587) (xy 136.04163 -251.701268) (xy 136.049525 -251.749845) (xy 136.05002 -251.774452)
			(xy 137.319016 -251.774452) (xy 137.322976 -251.725398) (xy 137.334753 -251.677614) (xy 137.354044 -251.632338)
			(xy 137.380347 -251.590742) (xy 137.412982 -251.553905) (xy 137.451103 -251.52278) (xy 137.493724 -251.498173)
			(xy 137.53974 -251.480721) (xy 137.587959 -251.470877) (xy 137.637134 -251.468896) (xy 137.685989 -251.474828)
			(xy 137.73326 -251.48852) (xy 137.777722 -251.509618) (xy 137.818225 -251.537574) (xy 137.853718 -251.571666)
			(xy 137.883283 -251.61101) (xy 137.906154 -251.654587) (xy 137.921738 -251.701268) (xy 137.929633 -251.749845)
			(xy 137.930128 -251.774452) (xy 138.25907 -251.774452) (xy 138.26303 -251.725398) (xy 138.274807 -251.677614)
			(xy 138.294098 -251.632338) (xy 138.320401 -251.590742) (xy 138.353036 -251.553905) (xy 138.391157 -251.52278)
			(xy 138.433778 -251.498173) (xy 138.479794 -251.480721) (xy 138.528013 -251.470877) (xy 138.577188 -251.468896)
			(xy 138.626043 -251.474828) (xy 138.673314 -251.48852) (xy 138.717776 -251.509618) (xy 138.758279 -251.537574)
			(xy 138.793772 -251.571666) (xy 138.823337 -251.61101) (xy 138.846208 -251.654587) (xy 138.861792 -251.701268)
			(xy 138.869687 -251.749845) (xy 138.870182 -251.774452) (xy 139.19887 -251.774452) (xy 139.20283 -251.725398)
			(xy 139.214607 -251.677614) (xy 139.233898 -251.632338) (xy 139.260201 -251.590742) (xy 139.292836 -251.553905)
			(xy 139.330957 -251.52278) (xy 139.373578 -251.498173) (xy 139.419594 -251.480721) (xy 139.467813 -251.470877)
			(xy 139.516988 -251.468896) (xy 139.565843 -251.474828) (xy 139.613114 -251.48852) (xy 139.657576 -251.509618)
			(xy 139.698079 -251.537574) (xy 139.733572 -251.571666) (xy 139.763137 -251.61101) (xy 139.786008 -251.654587)
			(xy 139.801592 -251.701268) (xy 139.809487 -251.749845) (xy 139.809982 -251.774452) (xy 139.809487 -251.799059)
			(xy 139.801592 -251.847636) (xy 139.786008 -251.894317) (xy 139.763137 -251.937894) (xy 139.733572 -251.977238)
			(xy 139.698079 -252.01133) (xy 139.657576 -252.039286) (xy 139.613114 -252.060384) (xy 139.565843 -252.074076)
			(xy 139.516988 -252.080008) (xy 139.467813 -252.078027) (xy 139.419594 -252.068183) (xy 139.373578 -252.050731)
			(xy 139.330957 -252.026124) (xy 139.292836 -251.994999) (xy 139.260201 -251.958162) (xy 139.233898 -251.916566)
			(xy 139.214607 -251.87129) (xy 139.20283 -251.823506) (xy 139.19887 -251.774452) (xy 138.870182 -251.774452)
			(xy 138.869687 -251.799059) (xy 138.861792 -251.847636) (xy 138.846208 -251.894317) (xy 138.823337 -251.937894)
			(xy 138.793772 -251.977238) (xy 138.758279 -252.01133) (xy 138.717776 -252.039286) (xy 138.673314 -252.060384)
			(xy 138.626043 -252.074076) (xy 138.577188 -252.080008) (xy 138.528013 -252.078027) (xy 138.479794 -252.068183)
			(xy 138.433778 -252.050731) (xy 138.391157 -252.026124) (xy 138.353036 -251.994999) (xy 138.320401 -251.958162)
			(xy 138.294098 -251.916566) (xy 138.274807 -251.87129) (xy 138.26303 -251.823506) (xy 138.25907 -251.774452)
			(xy 137.930128 -251.774452) (xy 137.929633 -251.799059) (xy 137.921738 -251.847636) (xy 137.906154 -251.894317)
			(xy 137.883283 -251.937894) (xy 137.853718 -251.977238) (xy 137.818225 -252.01133) (xy 137.777722 -252.039286)
			(xy 137.73326 -252.060384) (xy 137.685989 -252.074076) (xy 137.637134 -252.080008) (xy 137.587959 -252.078027)
			(xy 137.53974 -252.068183) (xy 137.493724 -252.050731) (xy 137.451103 -252.026124) (xy 137.412982 -251.994999)
			(xy 137.380347 -251.958162) (xy 137.354044 -251.916566) (xy 137.334753 -251.87129) (xy 137.322976 -251.823506)
			(xy 137.319016 -251.774452) (xy 136.05002 -251.774452) (xy 136.049525 -251.799059) (xy 136.04163 -251.847636)
			(xy 136.026046 -251.894317) (xy 136.003175 -251.937894) (xy 135.97361 -251.977238) (xy 135.938117 -252.01133)
			(xy 135.897614 -252.039286) (xy 135.853152 -252.060384) (xy 135.805881 -252.074076) (xy 135.757026 -252.080008)
			(xy 135.707851 -252.078027) (xy 135.659632 -252.068183) (xy 135.613616 -252.050731) (xy 135.570995 -252.026124)
			(xy 135.532874 -251.994999) (xy 135.500239 -251.958162) (xy 135.473936 -251.916566) (xy 135.454645 -251.87129)
			(xy 135.442868 -251.823506) (xy 135.438908 -251.774452) (xy 135.109966 -251.774452) (xy 135.109471 -251.799059)
			(xy 135.101576 -251.847636) (xy 135.085992 -251.894317) (xy 135.063121 -251.937894) (xy 135.033556 -251.977238)
			(xy 134.998063 -252.01133) (xy 134.95756 -252.039286) (xy 134.913098 -252.060384) (xy 134.865827 -252.074076)
			(xy 134.816972 -252.080008) (xy 134.767797 -252.078027) (xy 134.719578 -252.068183) (xy 134.673562 -252.050731)
			(xy 134.630941 -252.026124) (xy 134.59282 -251.994999) (xy 134.560185 -251.958162) (xy 134.533882 -251.916566)
			(xy 134.514591 -251.87129) (xy 134.502814 -251.823506) (xy 134.498854 -251.774452) (xy 134.170166 -251.774452)
			(xy 134.169671 -251.799059) (xy 134.161776 -251.847636) (xy 134.146192 -251.894317) (xy 134.123321 -251.937894)
			(xy 134.093756 -251.977238) (xy 134.058263 -252.01133) (xy 134.01776 -252.039286) (xy 133.973298 -252.060384)
			(xy 133.926027 -252.074076) (xy 133.877172 -252.080008) (xy 133.827997 -252.078027) (xy 133.779778 -252.068183)
			(xy 133.733762 -252.050731) (xy 133.691141 -252.026124) (xy 133.65302 -251.994999) (xy 133.620385 -251.958162)
			(xy 133.594082 -251.916566) (xy 133.574791 -251.87129) (xy 133.563014 -251.823506) (xy 133.559054 -251.774452)
			(xy 133.230112 -251.774452) (xy 133.229617 -251.799059) (xy 133.221722 -251.847636) (xy 133.206138 -251.894317)
			(xy 133.183267 -251.937894) (xy 133.153702 -251.977238) (xy 133.118209 -252.01133) (xy 133.077706 -252.039286)
			(xy 133.033244 -252.060384) (xy 132.985973 -252.074076) (xy 132.937118 -252.080008) (xy 132.887943 -252.078027)
			(xy 132.839724 -252.068183) (xy 132.793708 -252.050731) (xy 132.751087 -252.026124) (xy 132.712966 -251.994999)
			(xy 132.680331 -251.958162) (xy 132.654028 -251.916566) (xy 132.634737 -251.87129) (xy 132.62296 -251.823506)
			(xy 132.619 -251.774452) (xy 132.290058 -251.774452) (xy 132.289563 -251.799059) (xy 132.281668 -251.847636)
			(xy 132.266084 -251.894317) (xy 132.243213 -251.937894) (xy 132.213648 -251.977238) (xy 132.178155 -252.01133)
			(xy 132.137652 -252.039286) (xy 132.09319 -252.060384) (xy 132.045919 -252.074076) (xy 131.997064 -252.080008)
			(xy 131.947889 -252.078027) (xy 131.89967 -252.068183) (xy 131.853654 -252.050731) (xy 131.811033 -252.026124)
			(xy 131.772912 -251.994999) (xy 131.740277 -251.958162) (xy 131.713974 -251.916566) (xy 131.694683 -251.87129)
			(xy 131.682906 -251.823506) (xy 131.678946 -251.774452) (xy 131.360418 -251.774452) (xy 131.359906 -251.799898)
			(xy 131.351742 -251.850132) (xy 131.335626 -251.898406) (xy 131.311975 -251.943469) (xy 131.281402 -251.984155)
			(xy 131.244698 -252.01941) (xy 131.202814 -252.04832) (xy 131.156835 -252.070137) (xy 131.107951 -252.084297)
			(xy 131.05743 -252.090431) (xy 131.006578 -252.088382) (xy 130.956714 -252.078202) (xy 130.909128 -252.060155)
			(xy 130.865054 -252.034709) (xy 130.825632 -252.002522) (xy 130.791884 -251.964428) (xy 130.764683 -251.921414)
			(xy 130.744735 -251.874594) (xy 130.732556 -251.82518) (xy 130.728461 -251.774452) (xy 129.47015 -251.774452)
			(xy 129.469655 -251.799059) (xy 129.46176 -251.847636) (xy 129.446176 -251.894317) (xy 129.423305 -251.937894)
			(xy 129.39374 -251.977238) (xy 129.358247 -252.01133) (xy 129.317744 -252.039286) (xy 129.273282 -252.060384)
			(xy 129.226011 -252.074076) (xy 129.177156 -252.080008) (xy 129.127981 -252.078027) (xy 129.079762 -252.068183)
			(xy 129.033746 -252.050731) (xy 128.991125 -252.026124) (xy 128.953004 -251.994999) (xy 128.920369 -251.958162)
			(xy 128.894066 -251.916566) (xy 128.874775 -251.87129) (xy 128.862998 -251.823506) (xy 128.859038 -251.774452)
			(xy 128.54051 -251.774452) (xy 128.539998 -251.799898) (xy 128.531834 -251.850132) (xy 128.515718 -251.898406)
			(xy 128.492067 -251.943469) (xy 128.461494 -251.984155) (xy 128.42479 -252.01941) (xy 128.382906 -252.04832)
			(xy 128.336927 -252.070137) (xy 128.288043 -252.084297) (xy 128.237522 -252.090431) (xy 128.18667 -252.088382)
			(xy 128.136806 -252.078202) (xy 128.08922 -252.060155) (xy 128.045146 -252.034709) (xy 128.005724 -252.002522)
			(xy 127.971976 -251.964428) (xy 127.944775 -251.921414) (xy 127.924827 -251.874594) (xy 127.912648 -251.82518)
			(xy 127.908553 -251.774452) (xy 126.649988 -251.774452) (xy 126.649493 -251.799059) (xy 126.641598 -251.847636)
			(xy 126.626014 -251.894317) (xy 126.603143 -251.937894) (xy 126.573578 -251.977238) (xy 126.538085 -252.01133)
			(xy 126.497582 -252.039286) (xy 126.45312 -252.060384) (xy 126.405849 -252.074076) (xy 126.356994 -252.080008)
			(xy 126.307819 -252.078027) (xy 126.2596 -252.068183) (xy 126.213584 -252.050731) (xy 126.170963 -252.026124)
			(xy 126.132842 -251.994999) (xy 126.100207 -251.958162) (xy 126.073904 -251.916566) (xy 126.054613 -251.87129)
			(xy 126.042836 -251.823506) (xy 126.038876 -251.774452) (xy 124.770134 -251.774452) (xy 124.769691 -251.798448)
			(xy 124.762191 -251.845851) (xy 124.747367 -251.891497) (xy 124.725584 -251.934262) (xy 124.69738 -251.973092)
			(xy 124.663448 -252.007032) (xy 124.624625 -252.035246) (xy 124.581865 -252.057038) (xy 124.536223 -252.071874)
			(xy 124.488822 -252.079386) (xy 124.464826 -252.07976) (xy 124.440959 -252.079301) (xy 124.393805 -252.071878)
			(xy 124.348381 -252.057207) (xy 124.305793 -252.035647) (xy 124.267079 -252.007723) (xy 124.233181 -251.974115)
			(xy 124.204926 -251.935641) (xy 124.183002 -251.89324) (xy 124.167942 -251.847943) (xy 124.160114 -251.800855)
			(xy 124.159518 -251.776992) (xy 124.159518 -251.77369) (xy 124.160152 -251.746145) (xy 124.17012 -251.691962)
			(xy 124.17933 -251.665994) (xy 124.180854 -251.661676) (xy 124.182886 -251.649738) (xy 124.183795 -251.641108)
			(xy 124.180408 -251.624099) (xy 124.176282 -251.616464) (xy 124.128022 -251.545344) (xy 124.120469 -251.53628)
			(xy 124.099416 -251.52569) (xy 124.087636 -251.525024) (xy 123.393708 -251.525024) (xy 123.383872 -251.524485)
			(xy 123.365714 -251.516895) (xy 123.358402 -251.510292) (xy 123.13031 -251.2822) (xy 123.126175 -251.278312)
			(xy 123.116564 -251.272282) (xy 123.11126 -251.270262) (xy 123.100592 -251.266452) (xy 123.088908 -251.267722)
			(xy 123.054618 -251.269754) (xy 123.030625 -251.269285) (xy 122.983228 -251.261781) (xy 122.937589 -251.246956)
			(xy 122.89483 -251.225174) (xy 122.856005 -251.196972) (xy 122.82207 -251.163044) (xy 122.793859 -251.124225)
			(xy 122.772069 -251.081471) (xy 122.757234 -251.035834) (xy 122.74972 -250.988439) (xy 122.74931 -250.964446)
			(xy 122.751342 -250.930156) (xy 122.752612 -250.918472) (xy 122.748802 -250.907804) (xy 122.746794 -250.902494)
			(xy 122.740763 -250.89288) (xy 122.736864 -250.888754) (xy 122.462036 -250.613926) (xy 122.459186 -250.611219)
			(xy 122.452809 -250.606623) (xy 122.449336 -250.604782) (xy 122.443908 -250.602202) (xy 122.432229 -250.599384)
			(xy 122.426222 -250.599194) (xy 121.575322 -250.599194) (xy 121.565416 -250.60021) (xy 121.542048 -250.603004)
			(xy 121.520458 -250.603004) (xy 121.511415 -250.603499) (xy 121.494699 -250.610429) (xy 121.487946 -250.616466)
			(xy 121.42978 -250.674124) (xy 121.40565 -250.698254) (xy 121.399188 -250.705349) (xy 121.391635 -250.722973)
			(xy 121.390918 -250.732544) (xy 121.39041 -250.747276) (xy 121.403872 -250.762516) (xy 121.42167 -250.783616)
			(xy 121.450123 -250.830912) (xy 121.469619 -250.882549) (xy 121.479524 -250.936848) (xy 121.480072 -250.964446)
			(xy 121.479598 -250.988434) (xy 121.472086 -251.035818) (xy 121.457254 -251.081443) (xy 121.435467 -251.124187)
			(xy 121.407263 -251.162996) (xy 121.373334 -251.196916) (xy 121.334517 -251.22511) (xy 121.291768 -251.246885)
			(xy 121.246138 -251.261705) (xy 121.198752 -251.269204) (xy 121.174764 -251.269754) (xy 121.174002 -251.269754)
			(xy 121.145089 -251.269033) (xy 121.088318 -251.258035) (xy 121.061226 -251.24791) (xy 121.060972 -251.24791)
			(xy 121.054114 -251.245116) (xy 121.053606 -251.244862) (xy 121.053352 -251.244862) (xy 121.037186 -251.237545)
			(xy 121.006504 -251.219718) (xy 120.992138 -251.209302) (xy 120.99036 -251.208032) (xy 120.985534 -251.204476)
			(xy 120.963436 -251.196856) (xy 120.959549 -251.195615) (xy 120.951511 -251.194218) (xy 120.947434 -251.194062)
			(xy 120.922542 -251.194824) (xy 120.917948 -251.195163) (xy 120.908996 -251.197329) (xy 120.904762 -251.199142)
			(xy 120.894602 -251.209556) (xy 120.889452 -251.214563) (xy 120.878386 -251.223721) (xy 120.872504 -251.227844)
			(xy 120.865138 -251.23394) (xy 120.775476 -251.323602) (xy 120.774968 -251.32411) (xy 120.766977 -251.333423)
			(xy 120.759945 -251.356896) (xy 120.761506 -251.369068) (xy 120.767348 -251.395484) (xy 120.77954 -251.451872)
			(xy 120.781097 -251.457942) (xy 120.786747 -251.469122) (xy 120.790716 -251.47397) (xy 120.794526 -251.478542)
			(xy 120.80494 -251.485908) (xy 120.81129 -251.488194) (xy 120.835917 -251.497995) (xy 120.881624 -251.524825)
			(xy 120.922018 -251.559136) (xy 120.955888 -251.599901) (xy 120.982219 -251.645897) (xy 121.00022 -251.695746)
			(xy 121.009354 -251.747952) (xy 121.009918 -251.774452) (xy 122.278914 -251.774452) (xy 122.282874 -251.725398)
			(xy 122.294651 -251.677614) (xy 122.313942 -251.632338) (xy 122.340245 -251.590742) (xy 122.37288 -251.553905)
			(xy 122.411001 -251.52278) (xy 122.453622 -251.498173) (xy 122.499638 -251.480721) (xy 122.547857 -251.470877)
			(xy 122.597032 -251.468896) (xy 122.645887 -251.474828) (xy 122.693158 -251.48852) (xy 122.73762 -251.509618)
			(xy 122.778123 -251.537574) (xy 122.813616 -251.571666) (xy 122.843181 -251.61101) (xy 122.866052 -251.654587)
			(xy 122.881636 -251.701268) (xy 122.889531 -251.749845) (xy 122.890026 -251.774452) (xy 122.889531 -251.799059)
			(xy 122.881636 -251.847636) (xy 122.866052 -251.894317) (xy 122.843181 -251.937894) (xy 122.813616 -251.977238)
			(xy 122.778123 -252.01133) (xy 122.73762 -252.039286) (xy 122.693158 -252.060384) (xy 122.645887 -252.074076)
			(xy 122.597032 -252.080008) (xy 122.547857 -252.078027) (xy 122.499638 -252.068183) (xy 122.453622 -252.050731)
			(xy 122.411001 -252.026124) (xy 122.37288 -251.994999) (xy 122.340245 -251.958162) (xy 122.313942 -251.916566)
			(xy 122.294651 -251.87129) (xy 122.282874 -251.823506) (xy 122.278914 -251.774452) (xy 121.009918 -251.774452)
			(xy 121.009396 -251.799707) (xy 121.001083 -251.849529) (xy 120.984682 -251.897303) (xy 120.960641 -251.941726)
			(xy 120.929617 -251.981586) (xy 120.892455 -252.015796) (xy 120.850169 -252.043422) (xy 120.803913 -252.063712)
			(xy 120.754948 -252.076112) (xy 120.70461 -252.080283) (xy 120.654272 -252.076112) (xy 120.605307 -252.063712)
			(xy 120.559051 -252.043422) (xy 120.516765 -252.015796) (xy 120.479603 -251.981586) (xy 120.448579 -251.941726)
			(xy 120.424538 -251.897303) (xy 120.408137 -251.849529) (xy 120.399824 -251.799707) (xy 120.399302 -251.774452)
			(xy 120.399302 -251.77369) (xy 120.399419 -251.7608) (xy 120.401579 -251.73511) (xy 120.40362 -251.722382)
			(xy 120.404128 -251.71908) (xy 120.407686 -251.701224) (xy 120.418516 -251.66646) (xy 120.425718 -251.649738)
			(xy 120.437402 -251.62637) (xy 120.43791 -251.625608) (xy 120.440704 -251.620274) (xy 120.445177 -251.608955)
			(xy 120.444114 -251.584678) (xy 120.438672 -251.573792) (xy 120.395492 -251.499624) (xy 120.39092 -251.492766)
			(xy 120.384583 -251.485685) (xy 120.368016 -251.476402) (xy 120.358662 -251.474732) (xy 120.35155 -251.474224)
			(xy 119.685308 -251.474224) (xy 119.675472 -251.473685) (xy 119.657314 -251.466095) (xy 119.650002 -251.459492)
			(xy 119.453152 -251.262642) (xy 119.447907 -251.257675) (xy 119.435261 -251.250707) (xy 119.42826 -251.248926)
			(xy 119.421148 -251.247402) (xy 119.407178 -251.248418) (xy 119.399812 -251.250958) (xy 119.374406 -251.259704)
			(xy 119.321519 -251.269162) (xy 119.294656 -251.269754) (xy 119.290846 -251.269754) (xy 119.267242 -251.269015)
			(xy 119.220676 -251.261157) (xy 119.175876 -251.246225) (xy 119.133908 -251.224574) (xy 119.095773 -251.19672)
			(xy 119.062381 -251.163328) (xy 119.034527 -251.125194) (xy 119.012876 -251.083226) (xy 118.997943 -251.038426)
			(xy 118.990085 -250.99186) (xy 118.989348 -250.968256) (xy 118.989348 -250.964446) (xy 118.989876 -250.938543)
			(xy 118.99856 -250.887469) (xy 119.00662 -250.862846) (xy 119.008144 -250.858274) (xy 119.010176 -250.84659)
			(xy 119.010657 -250.840106) (xy 119.00872 -250.827252) (xy 119.006366 -250.82119) (xy 119.004394 -250.816767)
			(xy 118.999015 -250.808716) (xy 118.995698 -250.805188) (xy 118.804436 -250.613926) (xy 118.801586 -250.611219)
			(xy 118.795209 -250.606623) (xy 118.791736 -250.604782) (xy 118.786308 -250.602202) (xy 118.774629 -250.599384)
			(xy 118.768622 -250.599194) (xy 117.827298 -250.599194) (xy 117.817552 -250.599718) (xy 117.799536 -250.607179)
			(xy 117.792246 -250.613672) (xy 117.668548 -250.73737) (xy 117.661182 -250.752864) (xy 117.660674 -250.75896)
			(xy 117.678066 -250.780738) (xy 117.705835 -250.829054) (xy 117.724833 -250.881443) (xy 117.734486 -250.936328)
			(xy 117.735096 -250.964192) (xy 117.735096 -250.964446) (xy 117.734599 -250.989613) (xy 117.726718 -251.039325)
			(xy 117.711159 -251.087193) (xy 117.688304 -251.132038) (xy 117.658716 -251.172756) (xy 117.623122 -251.208344)
			(xy 117.5824 -251.237927) (xy 117.537552 -251.260776) (xy 117.489682 -251.276329) (xy 117.439969 -251.284202)
			(xy 117.414802 -251.28474) (xy 117.414548 -251.28474) (xy 117.386682 -251.284143) (xy 117.33179 -251.274504)
			(xy 117.279395 -251.255509) (xy 117.231079 -251.227732) (xy 117.209316 -251.210318) (xy 117.20322 -251.210826)
			(xy 117.187726 -251.218192) (xy 117.061742 -251.344176) (xy 117.060726 -251.345192) (xy 117.059202 -251.34697)
			(xy 117.052827 -251.355164) (xy 117.046645 -251.374962) (xy 117.047264 -251.385324) (xy 117.05971 -251.466604)
			(xy 117.060763 -251.472472) (xy 117.065263 -251.483508) (xy 117.0686 -251.488448) (xy 117.0721 -251.493097)
			(xy 117.080821 -251.500799) (xy 117.085872 -251.503688) (xy 117.08638 -251.503942) (xy 117.086634 -251.503942)
			(xy 117.107438 -251.51538) (xy 117.145543 -251.543697) (xy 117.178806 -251.577569) (xy 117.206428 -251.616181)
			(xy 117.227742 -251.658601) (xy 117.242235 -251.703809) (xy 117.249558 -251.750715) (xy 117.249956 -251.774452)
			(xy 118.518952 -251.774452) (xy 118.522912 -251.725398) (xy 118.534689 -251.677614) (xy 118.55398 -251.632338)
			(xy 118.580283 -251.590742) (xy 118.612918 -251.553905) (xy 118.651039 -251.52278) (xy 118.69366 -251.498173)
			(xy 118.739676 -251.480721) (xy 118.787895 -251.470877) (xy 118.83707 -251.468896) (xy 118.885925 -251.474828)
			(xy 118.933196 -251.48852) (xy 118.977658 -251.509618) (xy 119.018161 -251.537574) (xy 119.053654 -251.571666)
			(xy 119.083219 -251.61101) (xy 119.10609 -251.654587) (xy 119.121674 -251.701268) (xy 119.129569 -251.749845)
			(xy 119.130064 -251.774452) (xy 119.129569 -251.799059) (xy 119.121674 -251.847636) (xy 119.10609 -251.894317)
			(xy 119.083219 -251.937894) (xy 119.053654 -251.977238) (xy 119.018161 -252.01133) (xy 118.977658 -252.039286)
			(xy 118.933196 -252.060384) (xy 118.885925 -252.074076) (xy 118.83707 -252.080008) (xy 118.787895 -252.078027)
			(xy 118.739676 -252.068183) (xy 118.69366 -252.050731) (xy 118.651039 -252.026124) (xy 118.612918 -251.994999)
			(xy 118.580283 -251.958162) (xy 118.55398 -251.916566) (xy 118.534689 -251.87129) (xy 118.522912 -251.823506)
			(xy 118.518952 -251.774452) (xy 117.249956 -251.774452) (xy 117.249434 -251.799707) (xy 117.241121 -251.849529)
			(xy 117.22472 -251.897303) (xy 117.200679 -251.941726) (xy 117.169655 -251.981586) (xy 117.132493 -252.015796)
			(xy 117.090207 -252.043422) (xy 117.043951 -252.063712) (xy 116.994986 -252.076112) (xy 116.944648 -252.080283)
			(xy 116.89431 -252.076112) (xy 116.845345 -252.063712) (xy 116.799089 -252.043422) (xy 116.756803 -252.015796)
			(xy 116.719641 -251.981586) (xy 116.688617 -251.941726) (xy 116.664576 -251.897303) (xy 116.648175 -251.849529)
			(xy 116.639862 -251.799707) (xy 116.63934 -251.774452) (xy 116.63934 -251.77369) (xy 116.639458 -251.7608)
			(xy 116.641618 -251.73511) (xy 116.643658 -251.722382) (xy 116.644166 -251.71908) (xy 116.647724 -251.701223)
			(xy 116.658551 -251.666459) (xy 116.665756 -251.649738) (xy 116.67744 -251.62637) (xy 116.677948 -251.625608)
			(xy 116.680742 -251.620274) (xy 116.685213 -251.608955) (xy 116.68415 -251.584679) (xy 116.67871 -251.573792)
			(xy 116.63553 -251.499624) (xy 116.630958 -251.492766) (xy 116.624617 -251.485693) (xy 116.608047 -251.476429)
			(xy 116.5987 -251.474732) (xy 116.591588 -251.474224) (xy 116.197888 -251.474224) (xy 116.188045 -251.473699)
			(xy 116.169867 -251.46613) (xy 116.162582 -251.459492) (xy 115.928902 -251.225812) (xy 115.925092 -251.22251)
			(xy 115.918799 -251.217669) (xy 115.904038 -251.211847) (xy 115.896136 -251.21108) (xy 115.821968 -251.210318)
			(xy 115.816949 -251.210408) (xy 115.807096 -251.212326) (xy 115.80241 -251.214128) (xy 115.793774 -251.217684)
			(xy 115.786408 -251.224796) (xy 115.766039 -251.243796) (xy 115.72055 -251.275942) (xy 115.670674 -251.30074)
			(xy 115.617588 -251.317605) (xy 115.562544 -251.326137) (xy 115.534694 -251.32665) (xy 115.508821 -251.326188)
			(xy 115.457601 -251.318824) (xy 115.40795 -251.304245) (xy 115.36088 -251.28275) (xy 115.317347 -251.254775)
			(xy 115.278238 -251.220891) (xy 115.244349 -251.181785) (xy 115.216369 -251.138255) (xy 115.194869 -251.091187)
			(xy 115.180285 -251.041538) (xy 115.172915 -250.990319) (xy 115.17249 -250.964446) (xy 115.17249 -250.963938)
			(xy 115.17289 -250.939424) (xy 115.179501 -250.890845) (xy 115.19262 -250.843606) (xy 115.201954 -250.820936)
			(xy 115.201954 -250.820682) (xy 115.204477 -250.814399) (xy 115.206416 -250.801005) (xy 115.205764 -250.794266)
			(xy 115.20424 -250.78182) (xy 115.189508 -250.7615) (xy 115.186207 -250.757226) (xy 115.178142 -250.750046)
			(xy 115.173506 -250.747276) (xy 115.168367 -250.744533) (xy 115.15721 -250.741189) (xy 115.151408 -250.740672)
			(xy 114.041174 -250.740672) (xy 114.03584 -250.740926) (xy 114.0273 -250.742171) (xy 114.011724 -250.749575)
			(xy 114.00536 -250.755404) (xy 113.999772 -250.761754) (xy 113.953036 -250.82627) (xy 113.94966 -250.83121)
			(xy 113.945039 -250.842242) (xy 113.943892 -250.848114) (xy 113.942114 -250.859798) (xy 113.944146 -250.866148)
			(xy 113.951145 -250.888187) (xy 113.959182 -250.933723) (xy 113.960148 -250.956826) (xy 113.960148 -250.968002)
			(xy 113.95935 -250.993065) (xy 113.950582 -251.042432) (xy 113.933866 -251.089704) (xy 113.909651 -251.13361)
			(xy 113.878588 -251.172969) (xy 113.841512 -251.206724) (xy 113.799419 -251.233968) (xy 113.75344 -251.253968)
			(xy 113.704812 -251.266188) (xy 113.65484 -251.270298) (xy 113.604868 -251.266188) (xy 113.55624 -251.253968)
			(xy 113.510261 -251.233968) (xy 113.468168 -251.206724) (xy 113.431092 -251.172969) (xy 113.400029 -251.13361)
			(xy 113.375814 -251.089704) (xy 113.359098 -251.042432) (xy 113.35033 -250.993065) (xy 113.349532 -250.968002)
			(xy 113.349532 -250.963938) (xy 113.349901 -250.941047) (xy 113.356662 -250.895769) (xy 113.362994 -250.873768)
			(xy 113.364264 -250.870466) (xy 113.36528 -250.8631) (xy 113.366408 -250.853527) (xy 113.362212 -250.83473)
			(xy 113.357152 -250.826524) (xy 113.339626 -250.802648) (xy 113.3094 -250.7615) (xy 113.301799 -250.752233)
			(xy 113.280471 -250.741364) (xy 113.268506 -250.740672) (xy 109.29747 -250.740672) (xy 109.287718 -250.741182)
			(xy 109.269681 -250.748623) (xy 109.262418 -250.75515) (xy 109.245146 -250.772422) (xy 109.23976 -250.778169)
			(xy 109.232504 -250.792139) (xy 109.230922 -250.799854) (xy 109.229946 -250.807648) (xy 109.23227 -250.823172)
			(xy 109.235494 -250.830334) (xy 109.235494 -250.830588) (xy 109.245262 -250.851536) (xy 109.259062 -250.895647)
			(xy 109.266039 -250.941336) (xy 109.266482 -250.964446) (xy 109.266008 -250.988434) (xy 109.258496 -251.035819)
			(xy 109.243664 -251.081445) (xy 109.221878 -251.124189) (xy 109.193673 -251.163) (xy 109.159745 -251.19692)
			(xy 109.120928 -251.225115) (xy 109.078178 -251.246892) (xy 109.032549 -251.261713) (xy 108.985162 -251.269214)
			(xy 108.961174 -251.269754) (xy 108.938066 -251.269308) (xy 108.892381 -251.26231) (xy 108.848268 -251.248522)
			(xy 108.827316 -251.238766) (xy 108.827062 -251.238766) (xy 108.819893 -251.235564) (xy 108.804374 -251.233231)
			(xy 108.796582 -251.234194) (xy 108.788884 -251.235826) (xy 108.774926 -251.243073) (xy 108.76915 -251.248418)
			(xy 108.661708 -251.35586) (xy 108.654469 -251.362571) (xy 108.636264 -251.370165) (xy 108.626402 -251.370592)
			(xy 108.407708 -251.370592) (xy 108.402628 -251.375672) (xy 107.825286 -251.375672) (xy 107.815094 -251.376182)
			(xy 107.796344 -251.384196) (xy 107.782164 -251.398848) (xy 107.781406 -251.400564) (xy 111.932723 -251.400564)
			(xy 111.936753 -251.348066) (xy 111.94875 -251.296798) (xy 111.968433 -251.247963) (xy 111.995339 -251.202704)
			(xy 112.028839 -251.162083) (xy 112.068147 -251.127052) (xy 112.112342 -251.098432) (xy 112.160387 -251.076893)
			(xy 112.211158 -251.062941) (xy 112.263463 -251.056903) (xy 112.316077 -251.05892) (xy 112.367767 -251.068944)
			(xy 112.41732 -251.086742) (xy 112.463576 -251.111895) (xy 112.50545 -251.143814) (xy 112.541962 -251.181752)
			(xy 112.572254 -251.224818) (xy 112.595617 -251.272003) (xy 112.611503 -251.322202) (xy 112.61954 -251.374238)
			(xy 112.620044 -251.400564) (xy 112.61954 -251.42689) (xy 112.611503 -251.478926) (xy 112.595617 -251.529125)
			(xy 112.572254 -251.57631) (xy 112.541962 -251.619376) (xy 112.50545 -251.657314) (xy 112.463576 -251.689233)
			(xy 112.41732 -251.714386) (xy 112.367767 -251.732184) (xy 112.316077 -251.742208) (xy 112.263463 -251.744225)
			(xy 112.211158 -251.738187) (xy 112.160387 -251.724235) (xy 112.112342 -251.702696) (xy 112.068147 -251.674076)
			(xy 112.028839 -251.639045) (xy 111.995339 -251.598424) (xy 111.968433 -251.553165) (xy 111.94875 -251.50433)
			(xy 111.936753 -251.453062) (xy 111.932723 -251.400564) (xy 107.781406 -251.400564) (xy 107.778042 -251.408184)
			(xy 107.744768 -251.494036) (xy 107.742167 -251.501238) (xy 107.740989 -251.516498) (xy 107.742482 -251.524008)
			(xy 107.74426 -251.531374) (xy 107.75188 -251.544328) (xy 107.757722 -251.549662) (xy 107.775982 -251.567145)
			(xy 107.807027 -251.60704) (xy 107.831081 -251.6515) (xy 107.847488 -251.699314) (xy 107.855801 -251.749177)
			(xy 107.856274 -251.774452) (xy 109.12527 -251.774452) (xy 109.12923 -251.725398) (xy 109.141007 -251.677614)
			(xy 109.160298 -251.632338) (xy 109.186601 -251.590742) (xy 109.219236 -251.553905) (xy 109.257357 -251.52278)
			(xy 109.299978 -251.498173) (xy 109.345994 -251.480721) (xy 109.394213 -251.470877) (xy 109.443388 -251.468896)
			(xy 109.492243 -251.474828) (xy 109.539514 -251.48852) (xy 109.583976 -251.509618) (xy 109.624479 -251.537574)
			(xy 109.659972 -251.571666) (xy 109.689537 -251.61101) (xy 109.712408 -251.654587) (xy 109.727992 -251.701268)
			(xy 109.735887 -251.749845) (xy 109.736382 -251.774452) (xy 112.878882 -251.774452) (xy 112.882842 -251.725398)
			(xy 112.894619 -251.677614) (xy 112.91391 -251.632338) (xy 112.940213 -251.590742) (xy 112.972848 -251.553905)
			(xy 113.010969 -251.52278) (xy 113.05359 -251.498173) (xy 113.099606 -251.480721) (xy 113.147825 -251.470877)
			(xy 113.197 -251.468896) (xy 113.245855 -251.474828) (xy 113.293126 -251.48852) (xy 113.337588 -251.509618)
			(xy 113.378091 -251.537574) (xy 113.413584 -251.571666) (xy 113.443149 -251.61101) (xy 113.46602 -251.654587)
			(xy 113.481604 -251.701268) (xy 113.489499 -251.749845) (xy 113.489994 -251.774452) (xy 114.75899 -251.774452)
			(xy 114.76295 -251.725398) (xy 114.774727 -251.677614) (xy 114.794018 -251.632338) (xy 114.820321 -251.590742)
			(xy 114.852956 -251.553905) (xy 114.891077 -251.52278) (xy 114.933698 -251.498173) (xy 114.979714 -251.480721)
			(xy 115.027933 -251.470877) (xy 115.077108 -251.468896) (xy 115.125963 -251.474828) (xy 115.173234 -251.48852)
			(xy 115.217696 -251.509618) (xy 115.258199 -251.537574) (xy 115.293692 -251.571666) (xy 115.323257 -251.61101)
			(xy 115.346128 -251.654587) (xy 115.361712 -251.701268) (xy 115.369607 -251.749845) (xy 115.370102 -251.774452)
			(xy 115.369607 -251.799059) (xy 115.361712 -251.847636) (xy 115.346128 -251.894317) (xy 115.323257 -251.937894)
			(xy 115.293692 -251.977238) (xy 115.258199 -252.01133) (xy 115.217696 -252.039286) (xy 115.173234 -252.060384)
			(xy 115.125963 -252.074076) (xy 115.077108 -252.080008) (xy 115.027933 -252.078027) (xy 114.979714 -252.068183)
			(xy 114.933698 -252.050731) (xy 114.891077 -252.026124) (xy 114.852956 -251.994999) (xy 114.820321 -251.958162)
			(xy 114.794018 -251.916566) (xy 114.774727 -251.87129) (xy 114.76295 -251.823506) (xy 114.75899 -251.774452)
			(xy 113.489994 -251.774452) (xy 113.489499 -251.799059) (xy 113.481604 -251.847636) (xy 113.46602 -251.894317)
			(xy 113.443149 -251.937894) (xy 113.413584 -251.977238) (xy 113.378091 -252.01133) (xy 113.337588 -252.039286)
			(xy 113.293126 -252.060384) (xy 113.245855 -252.074076) (xy 113.197 -252.080008) (xy 113.147825 -252.078027)
			(xy 113.099606 -252.068183) (xy 113.05359 -252.050731) (xy 113.010969 -252.026124) (xy 112.972848 -251.994999)
			(xy 112.940213 -251.958162) (xy 112.91391 -251.916566) (xy 112.894619 -251.87129) (xy 112.882842 -251.823506)
			(xy 112.878882 -251.774452) (xy 109.736382 -251.774452) (xy 109.735887 -251.799059) (xy 109.727992 -251.847636)
			(xy 109.712408 -251.894317) (xy 109.689537 -251.937894) (xy 109.659972 -251.977238) (xy 109.624479 -252.01133)
			(xy 109.583976 -252.039286) (xy 109.539514 -252.060384) (xy 109.492243 -252.074076) (xy 109.443388 -252.080008)
			(xy 109.394213 -252.078027) (xy 109.345994 -252.068183) (xy 109.299978 -252.050731) (xy 109.257357 -252.026124)
			(xy 109.219236 -251.994999) (xy 109.186601 -251.958162) (xy 109.160298 -251.916566) (xy 109.141007 -251.87129)
			(xy 109.12923 -251.823506) (xy 109.12527 -251.774452) (xy 107.856274 -251.774452) (xy 107.855752 -251.799707)
			(xy 107.847439 -251.849529) (xy 107.831038 -251.897303) (xy 107.806997 -251.941726) (xy 107.775973 -251.981586)
			(xy 107.738811 -252.015796) (xy 107.696525 -252.043422) (xy 107.650269 -252.063712) (xy 107.601304 -252.076112)
			(xy 107.550966 -252.080283) (xy 107.500628 -252.076112) (xy 107.451663 -252.063712) (xy 107.405407 -252.043422)
			(xy 107.363121 -252.015796) (xy 107.325959 -251.981586) (xy 107.294935 -251.941726) (xy 107.270894 -251.897303)
			(xy 107.254493 -251.849529) (xy 107.24618 -251.799707) (xy 107.245658 -251.774452) (xy 107.246155 -251.749202)
			(xy 107.25448 -251.699394) (xy 107.270893 -251.651637) (xy 107.294947 -251.607234) (xy 107.325985 -251.5674)
			(xy 107.34421 -251.549916) (xy 107.344718 -251.549408) (xy 107.344972 -251.549154) (xy 107.35023 -251.543856)
			(xy 107.357712 -251.530948) (xy 107.359704 -251.523754) (xy 107.361482 -251.516134) (xy 107.360466 -251.501148)
			(xy 107.322874 -251.405898) (xy 107.318519 -251.397144) (xy 107.304503 -251.383537) (xy 107.286412 -251.376168)
			(xy 107.276646 -251.375672) (xy 105.945432 -251.375672) (xy 105.935246 -251.376192) (xy 105.916514 -251.384217)
			(xy 105.902349 -251.398869) (xy 105.898188 -251.408184) (xy 105.864914 -251.494036) (xy 105.862315 -251.501239)
			(xy 105.861138 -251.516498) (xy 105.862628 -251.524008) (xy 105.864406 -251.531374) (xy 105.872026 -251.544328)
			(xy 105.877868 -251.549662) (xy 105.896131 -251.567144) (xy 105.927181 -251.607036) (xy 105.951239 -251.651497)
			(xy 105.967649 -251.699312) (xy 105.975964 -251.749176) (xy 105.97642 -251.774452) (xy 105.975898 -251.799707)
			(xy 105.967585 -251.849529) (xy 105.951184 -251.897303) (xy 105.927143 -251.941726) (xy 105.896119 -251.981586)
			(xy 105.858957 -252.015796) (xy 105.816671 -252.043422) (xy 105.770415 -252.063712) (xy 105.72145 -252.076112)
			(xy 105.671112 -252.080283) (xy 105.620774 -252.076112) (xy 105.571809 -252.063712) (xy 105.525553 -252.043422)
			(xy 105.483267 -252.015796) (xy 105.446105 -251.981586) (xy 105.415081 -251.941726) (xy 105.39104 -251.897303)
			(xy 105.374639 -251.849529) (xy 105.366326 -251.799707) (xy 105.365804 -251.774452) (xy 105.366301 -251.749202)
			(xy 105.374624 -251.699392) (xy 105.391035 -251.651633) (xy 105.415087 -251.607228) (xy 105.446121 -251.567389)
			(xy 105.464356 -251.549916) (xy 105.464864 -251.549408) (xy 105.465118 -251.549154) (xy 105.470381 -251.543859)
			(xy 105.47787 -251.530952) (xy 105.47985 -251.523754) (xy 105.481628 -251.516134) (xy 105.480612 -251.501148)
			(xy 105.44302 -251.405898) (xy 105.438667 -251.397139) (xy 105.424654 -251.383519) (xy 105.406561 -251.376135)
			(xy 105.396792 -251.375672) (xy 104.065324 -251.375672) (xy 104.055139 -251.376193) (xy 104.036409 -251.38422)
			(xy 104.022247 -251.398873) (xy 104.01808 -251.408184) (xy 103.984806 -251.494036) (xy 103.982207 -251.501239)
			(xy 103.981031 -251.516498) (xy 103.98252 -251.524008) (xy 103.984298 -251.531374) (xy 103.991918 -251.544328)
			(xy 103.99776 -251.549662) (xy 104.016023 -251.567143) (xy 104.047074 -251.607036) (xy 104.071133 -251.651496)
			(xy 104.087544 -251.699311) (xy 104.095858 -251.749176) (xy 104.096312 -251.774452) (xy 104.09579 -251.799707)
			(xy 104.087477 -251.849529) (xy 104.071076 -251.897303) (xy 104.047035 -251.941726) (xy 104.016011 -251.981586)
			(xy 103.978849 -252.015796) (xy 103.936563 -252.043422) (xy 103.890307 -252.063712) (xy 103.841342 -252.076112)
			(xy 103.791004 -252.080283) (xy 103.740666 -252.076112) (xy 103.691701 -252.063712) (xy 103.645445 -252.043422)
			(xy 103.603159 -252.015796) (xy 103.565997 -251.981586) (xy 103.534973 -251.941726) (xy 103.510932 -251.897303)
			(xy 103.494531 -251.849529) (xy 103.486218 -251.799707) (xy 103.485696 -251.774452) (xy 103.486193 -251.749202)
			(xy 103.494516 -251.699392) (xy 103.510927 -251.651633) (xy 103.534978 -251.607227) (xy 103.566012 -251.567388)
			(xy 103.584248 -251.549916) (xy 103.584756 -251.549408) (xy 103.58501 -251.549154) (xy 103.590273 -251.543859)
			(xy 103.597764 -251.530953) (xy 103.599742 -251.523754) (xy 103.60152 -251.516134) (xy 103.600504 -251.501148)
			(xy 103.562912 -251.405898) (xy 103.558559 -251.39714) (xy 103.544545 -251.383522) (xy 103.526453 -251.37614)
			(xy 103.516684 -251.375672) (xy 102.793546 -251.375672) (xy 102.783796 -251.376186) (xy 102.765765 -251.383633)
			(xy 102.758494 -251.39015) (xy 102.664006 -251.484892) (xy 102.657288 -251.492128) (xy 102.649684 -251.510333)
			(xy 102.649274 -251.520198) (xy 102.649274 -251.807472) (xy 102.65029 -251.817124) (xy 102.651913 -251.824371)
			(xy 102.658745 -251.837549) (xy 102.663752 -251.843032) (xy 103.237284 -252.416564) (xy 111.913673 -252.416564)
			(xy 111.917703 -252.364066) (xy 111.9297 -252.312798) (xy 111.949383 -252.263963) (xy 111.976289 -252.218704)
			(xy 112.009789 -252.178083) (xy 112.049097 -252.143052) (xy 112.093292 -252.114432) (xy 112.141337 -252.092893)
			(xy 112.192108 -252.078941) (xy 112.244413 -252.072903) (xy 112.297027 -252.07492) (xy 112.348717 -252.084944)
			(xy 112.39827 -252.102742) (xy 112.444526 -252.127895) (xy 112.4864 -252.159814) (xy 112.522912 -252.197752)
			(xy 112.553204 -252.240818) (xy 112.576567 -252.288003) (xy 112.592453 -252.338202) (xy 112.60049 -252.390238)
			(xy 112.600994 -252.416564) (xy 112.60049 -252.44289) (xy 112.592453 -252.494926) (xy 112.576567 -252.545125)
			(xy 112.557092 -252.584458) (xy 120.86896 -252.584458) (xy 120.87292 -252.535404) (xy 120.884697 -252.48762)
			(xy 120.903988 -252.442344) (xy 120.930291 -252.400748) (xy 120.962926 -252.363911) (xy 121.001047 -252.332786)
			(xy 121.043668 -252.308179) (xy 121.089684 -252.290727) (xy 121.137903 -252.280883) (xy 121.187078 -252.278902)
			(xy 121.235933 -252.284834) (xy 121.283204 -252.298526) (xy 121.327666 -252.319624) (xy 121.368169 -252.34758)
			(xy 121.403662 -252.381672) (xy 121.433227 -252.421016) (xy 121.456098 -252.464593) (xy 121.471682 -252.511274)
			(xy 121.479577 -252.559851) (xy 121.480072 -252.584458) (xy 122.748814 -252.584458) (xy 122.752774 -252.535404)
			(xy 122.764551 -252.48762) (xy 122.783842 -252.442344) (xy 122.810145 -252.400748) (xy 122.84278 -252.363911)
			(xy 122.880901 -252.332786) (xy 122.923522 -252.308179) (xy 122.969538 -252.290727) (xy 123.017757 -252.280883)
			(xy 123.066932 -252.278902) (xy 123.115787 -252.284834) (xy 123.163058 -252.298526) (xy 123.20752 -252.319624)
			(xy 123.248023 -252.34758) (xy 123.283516 -252.381672) (xy 123.313081 -252.421016) (xy 123.335952 -252.464593)
			(xy 123.351536 -252.511274) (xy 123.359431 -252.559851) (xy 123.359926 -252.584458) (xy 124.628922 -252.584458)
			(xy 124.632882 -252.535404) (xy 124.644659 -252.48762) (xy 124.66395 -252.442344) (xy 124.690253 -252.400748)
			(xy 124.722888 -252.363911) (xy 124.761009 -252.332786) (xy 124.80363 -252.308179) (xy 124.849646 -252.290727)
			(xy 124.897865 -252.280883) (xy 124.94704 -252.278902) (xy 124.995895 -252.284834) (xy 125.043166 -252.298526)
			(xy 125.087628 -252.319624) (xy 125.128131 -252.34758) (xy 125.163624 -252.381672) (xy 125.193189 -252.421016)
			(xy 125.21606 -252.464593) (xy 125.231644 -252.511274) (xy 125.239539 -252.559851) (xy 125.240034 -252.584458)
			(xy 126.50903 -252.584458) (xy 126.51299 -252.535404) (xy 126.524767 -252.48762) (xy 126.544058 -252.442344)
			(xy 126.570361 -252.400748) (xy 126.602996 -252.363911) (xy 126.641117 -252.332786) (xy 126.683738 -252.308179)
			(xy 126.729754 -252.290727) (xy 126.777973 -252.280883) (xy 126.827148 -252.278902) (xy 126.876003 -252.284834)
			(xy 126.923274 -252.298526) (xy 126.967736 -252.319624) (xy 127.008239 -252.34758) (xy 127.043732 -252.381672)
			(xy 127.073297 -252.421016) (xy 127.096168 -252.464593) (xy 127.111752 -252.511274) (xy 127.119647 -252.559851)
			(xy 127.120142 -252.584458) (xy 127.44883 -252.584458) (xy 127.45279 -252.535404) (xy 127.464567 -252.48762)
			(xy 127.483858 -252.442344) (xy 127.510161 -252.400748) (xy 127.542796 -252.363911) (xy 127.580917 -252.332786)
			(xy 127.623538 -252.308179) (xy 127.669554 -252.290727) (xy 127.717773 -252.280883) (xy 127.766948 -252.278902)
			(xy 127.815803 -252.284834) (xy 127.863074 -252.298526) (xy 127.907536 -252.319624) (xy 127.948039 -252.34758)
			(xy 127.983532 -252.381672) (xy 128.013097 -252.421016) (xy 128.035968 -252.464593) (xy 128.051552 -252.511274)
			(xy 128.059447 -252.559851) (xy 128.059942 -252.584458) (xy 128.388884 -252.584458) (xy 128.392844 -252.535404)
			(xy 128.404621 -252.48762) (xy 128.423912 -252.442344) (xy 128.450215 -252.400748) (xy 128.48285 -252.363911)
			(xy 128.520971 -252.332786) (xy 128.563592 -252.308179) (xy 128.609608 -252.290727) (xy 128.657827 -252.280883)
			(xy 128.707002 -252.278902) (xy 128.755857 -252.284834) (xy 128.803128 -252.298526) (xy 128.84759 -252.319624)
			(xy 128.888093 -252.34758) (xy 128.923586 -252.381672) (xy 128.953151 -252.421016) (xy 128.976022 -252.464593)
			(xy 128.991606 -252.511274) (xy 128.999501 -252.559851) (xy 128.999996 -252.584458) (xy 129.318507 -252.584458)
			(xy 129.322602 -252.53373) (xy 129.334781 -252.484316) (xy 129.354729 -252.437496) (xy 129.38193 -252.394482)
			(xy 129.415678 -252.356388) (xy 129.4551 -252.324201) (xy 129.499174 -252.298755) (xy 129.54676 -252.280708)
			(xy 129.596624 -252.270528) (xy 129.647476 -252.268479) (xy 129.697997 -252.274613) (xy 129.746881 -252.288773)
			(xy 129.79286 -252.31059) (xy 129.834744 -252.3395) (xy 129.871448 -252.374755) (xy 129.902021 -252.415441)
			(xy 129.925672 -252.460504) (xy 129.941788 -252.508778) (xy 129.949952 -252.559012) (xy 129.950464 -252.584458)
			(xy 130.268992 -252.584458) (xy 130.272952 -252.535404) (xy 130.284729 -252.48762) (xy 130.30402 -252.442344)
			(xy 130.330323 -252.400748) (xy 130.362958 -252.363911) (xy 130.401079 -252.332786) (xy 130.4437 -252.308179)
			(xy 130.489716 -252.290727) (xy 130.537935 -252.280883) (xy 130.58711 -252.278902) (xy 130.635965 -252.284834)
			(xy 130.683236 -252.298526) (xy 130.727698 -252.319624) (xy 130.768201 -252.34758) (xy 130.803694 -252.381672)
			(xy 130.833259 -252.421016) (xy 130.85613 -252.464593) (xy 130.871714 -252.511274) (xy 130.879609 -252.559851)
			(xy 130.880104 -252.584458) (xy 131.209046 -252.584458) (xy 131.213006 -252.535404) (xy 131.224783 -252.48762)
			(xy 131.244074 -252.442344) (xy 131.270377 -252.400748) (xy 131.303012 -252.363911) (xy 131.341133 -252.332786)
			(xy 131.383754 -252.308179) (xy 131.42977 -252.290727) (xy 131.477989 -252.280883) (xy 131.527164 -252.278902)
			(xy 131.576019 -252.284834) (xy 131.62329 -252.298526) (xy 131.667752 -252.319624) (xy 131.708255 -252.34758)
			(xy 131.743748 -252.381672) (xy 131.773313 -252.421016) (xy 131.796184 -252.464593) (xy 131.811768 -252.511274)
			(xy 131.819663 -252.559851) (xy 131.820158 -252.584458) (xy 132.138415 -252.584458) (xy 132.14251 -252.53373)
			(xy 132.154689 -252.484316) (xy 132.174637 -252.437496) (xy 132.201838 -252.394482) (xy 132.235586 -252.356388)
			(xy 132.275008 -252.324201) (xy 132.319082 -252.298755) (xy 132.366668 -252.280708) (xy 132.416532 -252.270528)
			(xy 132.467384 -252.268479) (xy 132.517905 -252.274613) (xy 132.566789 -252.288773) (xy 132.612768 -252.31059)
			(xy 132.654652 -252.3395) (xy 132.691356 -252.374755) (xy 132.721929 -252.415441) (xy 132.74558 -252.460504)
			(xy 132.761696 -252.508778) (xy 132.76986 -252.559012) (xy 132.770372 -252.584458) (xy 133.0889 -252.584458)
			(xy 133.09286 -252.535404) (xy 133.104637 -252.48762) (xy 133.123928 -252.442344) (xy 133.150231 -252.400748)
			(xy 133.182866 -252.363911) (xy 133.220987 -252.332786) (xy 133.263608 -252.308179) (xy 133.309624 -252.290727)
			(xy 133.357843 -252.280883) (xy 133.407018 -252.278902) (xy 133.455873 -252.284834) (xy 133.503144 -252.298526)
			(xy 133.547606 -252.319624) (xy 133.588109 -252.34758) (xy 133.623602 -252.381672) (xy 133.653167 -252.421016)
			(xy 133.676038 -252.464593) (xy 133.691622 -252.511274) (xy 133.699517 -252.559851) (xy 133.700012 -252.584458)
			(xy 134.028954 -252.584458) (xy 134.032914 -252.535404) (xy 134.044691 -252.48762) (xy 134.063982 -252.442344)
			(xy 134.090285 -252.400748) (xy 134.12292 -252.363911) (xy 134.161041 -252.332786) (xy 134.203662 -252.308179)
			(xy 134.249678 -252.290727) (xy 134.297897 -252.280883) (xy 134.347072 -252.278902) (xy 134.395927 -252.284834)
			(xy 134.443198 -252.298526) (xy 134.48766 -252.319624) (xy 134.528163 -252.34758) (xy 134.563656 -252.381672)
			(xy 134.593221 -252.421016) (xy 134.616092 -252.464593) (xy 134.631676 -252.511274) (xy 134.639571 -252.559851)
			(xy 134.640066 -252.584458) (xy 134.969008 -252.584458) (xy 134.972968 -252.535404) (xy 134.984745 -252.48762)
			(xy 135.004036 -252.442344) (xy 135.030339 -252.400748) (xy 135.062974 -252.363911) (xy 135.101095 -252.332786)
			(xy 135.143716 -252.308179) (xy 135.189732 -252.290727) (xy 135.237951 -252.280883) (xy 135.287126 -252.278902)
			(xy 135.335981 -252.284834) (xy 135.383252 -252.298526) (xy 135.427714 -252.319624) (xy 135.468217 -252.34758)
			(xy 135.50371 -252.381672) (xy 135.533275 -252.421016) (xy 135.556146 -252.464593) (xy 135.57173 -252.511274)
			(xy 135.579625 -252.559851) (xy 135.58012 -252.584458) (xy 135.909062 -252.584458) (xy 135.913022 -252.535404)
			(xy 135.924799 -252.48762) (xy 135.94409 -252.442344) (xy 135.970393 -252.400748) (xy 136.003028 -252.363911)
			(xy 136.041149 -252.332786) (xy 136.08377 -252.308179) (xy 136.129786 -252.290727) (xy 136.178005 -252.280883)
			(xy 136.22718 -252.278902) (xy 136.276035 -252.284834) (xy 136.323306 -252.298526) (xy 136.367768 -252.319624)
			(xy 136.408271 -252.34758) (xy 136.443764 -252.381672) (xy 136.473329 -252.421016) (xy 136.4962 -252.464593)
			(xy 136.511784 -252.511274) (xy 136.519679 -252.559851) (xy 136.520174 -252.584458) (xy 136.848862 -252.584458)
			(xy 136.852822 -252.535404) (xy 136.864599 -252.48762) (xy 136.88389 -252.442344) (xy 136.910193 -252.400748)
			(xy 136.942828 -252.363911) (xy 136.980949 -252.332786) (xy 137.02357 -252.308179) (xy 137.069586 -252.290727)
			(xy 137.117805 -252.280883) (xy 137.16698 -252.278902) (xy 137.215835 -252.284834) (xy 137.263106 -252.298526)
			(xy 137.307568 -252.319624) (xy 137.348071 -252.34758) (xy 137.383564 -252.381672) (xy 137.413129 -252.421016)
			(xy 137.436 -252.464593) (xy 137.451584 -252.511274) (xy 137.459479 -252.559851) (xy 137.459974 -252.584458)
			(xy 137.788916 -252.584458) (xy 137.792876 -252.535404) (xy 137.804653 -252.48762) (xy 137.823944 -252.442344)
			(xy 137.850247 -252.400748) (xy 137.882882 -252.363911) (xy 137.921003 -252.332786) (xy 137.963624 -252.308179)
			(xy 138.00964 -252.290727) (xy 138.057859 -252.280883) (xy 138.107034 -252.278902) (xy 138.155889 -252.284834)
			(xy 138.20316 -252.298526) (xy 138.247622 -252.319624) (xy 138.288125 -252.34758) (xy 138.323618 -252.381672)
			(xy 138.353183 -252.421016) (xy 138.376054 -252.464593) (xy 138.391638 -252.511274) (xy 138.399533 -252.559851)
			(xy 138.400028 -252.584458) (xy 138.72897 -252.584458) (xy 138.73293 -252.535404) (xy 138.744707 -252.48762)
			(xy 138.763998 -252.442344) (xy 138.790301 -252.400748) (xy 138.822936 -252.363911) (xy 138.861057 -252.332786)
			(xy 138.903678 -252.308179) (xy 138.949694 -252.290727) (xy 138.997913 -252.280883) (xy 139.047088 -252.278902)
			(xy 139.095943 -252.284834) (xy 139.143214 -252.298526) (xy 139.187676 -252.319624) (xy 139.228179 -252.34758)
			(xy 139.263672 -252.381672) (xy 139.293237 -252.421016) (xy 139.316108 -252.464593) (xy 139.331692 -252.511274)
			(xy 139.339587 -252.559851) (xy 139.340082 -252.584458) (xy 139.669024 -252.584458) (xy 139.672984 -252.535404)
			(xy 139.684761 -252.48762) (xy 139.704052 -252.442344) (xy 139.730355 -252.400748) (xy 139.76299 -252.363911)
			(xy 139.801111 -252.332786) (xy 139.843732 -252.308179) (xy 139.889748 -252.290727) (xy 139.937967 -252.280883)
			(xy 139.987142 -252.278902) (xy 140.035997 -252.284834) (xy 140.083268 -252.298526) (xy 140.12773 -252.319624)
			(xy 140.168233 -252.34758) (xy 140.203726 -252.381672) (xy 140.233291 -252.421016) (xy 140.256162 -252.464593)
			(xy 140.271746 -252.511274) (xy 140.279641 -252.559851) (xy 140.280136 -252.584458) (xy 140.279641 -252.609065)
			(xy 140.271746 -252.657642) (xy 140.256162 -252.704323) (xy 140.233291 -252.7479) (xy 140.203726 -252.787244)
			(xy 140.168233 -252.821336) (xy 140.12773 -252.849292) (xy 140.083268 -252.87039) (xy 140.035997 -252.884082)
			(xy 139.987142 -252.890014) (xy 139.937967 -252.888033) (xy 139.889748 -252.878189) (xy 139.843732 -252.860737)
			(xy 139.801111 -252.83613) (xy 139.76299 -252.805005) (xy 139.730355 -252.768168) (xy 139.704052 -252.726572)
			(xy 139.684761 -252.681296) (xy 139.672984 -252.633512) (xy 139.669024 -252.584458) (xy 139.340082 -252.584458)
			(xy 139.339587 -252.609065) (xy 139.331692 -252.657642) (xy 139.316108 -252.704323) (xy 139.293237 -252.7479)
			(xy 139.263672 -252.787244) (xy 139.228179 -252.821336) (xy 139.187676 -252.849292) (xy 139.143214 -252.87039)
			(xy 139.095943 -252.884082) (xy 139.047088 -252.890014) (xy 138.997913 -252.888033) (xy 138.949694 -252.878189)
			(xy 138.903678 -252.860737) (xy 138.861057 -252.83613) (xy 138.822936 -252.805005) (xy 138.790301 -252.768168)
			(xy 138.763998 -252.726572) (xy 138.744707 -252.681296) (xy 138.73293 -252.633512) (xy 138.72897 -252.584458)
			(xy 138.400028 -252.584458) (xy 138.399533 -252.609065) (xy 138.391638 -252.657642) (xy 138.376054 -252.704323)
			(xy 138.353183 -252.7479) (xy 138.323618 -252.787244) (xy 138.288125 -252.821336) (xy 138.247622 -252.849292)
			(xy 138.20316 -252.87039) (xy 138.155889 -252.884082) (xy 138.107034 -252.890014) (xy 138.057859 -252.888033)
			(xy 138.00964 -252.878189) (xy 137.963624 -252.860737) (xy 137.921003 -252.83613) (xy 137.882882 -252.805005)
			(xy 137.850247 -252.768168) (xy 137.823944 -252.726572) (xy 137.804653 -252.681296) (xy 137.792876 -252.633512)
			(xy 137.788916 -252.584458) (xy 137.459974 -252.584458) (xy 137.459479 -252.609065) (xy 137.451584 -252.657642)
			(xy 137.436 -252.704323) (xy 137.413129 -252.7479) (xy 137.383564 -252.787244) (xy 137.348071 -252.821336)
			(xy 137.307568 -252.849292) (xy 137.263106 -252.87039) (xy 137.215835 -252.884082) (xy 137.16698 -252.890014)
			(xy 137.117805 -252.888033) (xy 137.069586 -252.878189) (xy 137.02357 -252.860737) (xy 136.980949 -252.83613)
			(xy 136.942828 -252.805005) (xy 136.910193 -252.768168) (xy 136.88389 -252.726572) (xy 136.864599 -252.681296)
			(xy 136.852822 -252.633512) (xy 136.848862 -252.584458) (xy 136.520174 -252.584458) (xy 136.519679 -252.609065)
			(xy 136.511784 -252.657642) (xy 136.4962 -252.704323) (xy 136.473329 -252.7479) (xy 136.443764 -252.787244)
			(xy 136.408271 -252.821336) (xy 136.367768 -252.849292) (xy 136.323306 -252.87039) (xy 136.276035 -252.884082)
			(xy 136.22718 -252.890014) (xy 136.178005 -252.888033) (xy 136.129786 -252.878189) (xy 136.08377 -252.860737)
			(xy 136.041149 -252.83613) (xy 136.003028 -252.805005) (xy 135.970393 -252.768168) (xy 135.94409 -252.726572)
			(xy 135.924799 -252.681296) (xy 135.913022 -252.633512) (xy 135.909062 -252.584458) (xy 135.58012 -252.584458)
			(xy 135.579625 -252.609065) (xy 135.57173 -252.657642) (xy 135.556146 -252.704323) (xy 135.533275 -252.7479)
			(xy 135.50371 -252.787244) (xy 135.468217 -252.821336) (xy 135.427714 -252.849292) (xy 135.383252 -252.87039)
			(xy 135.335981 -252.884082) (xy 135.287126 -252.890014) (xy 135.237951 -252.888033) (xy 135.189732 -252.878189)
			(xy 135.143716 -252.860737) (xy 135.101095 -252.83613) (xy 135.062974 -252.805005) (xy 135.030339 -252.768168)
			(xy 135.004036 -252.726572) (xy 134.984745 -252.681296) (xy 134.972968 -252.633512) (xy 134.969008 -252.584458)
			(xy 134.640066 -252.584458) (xy 134.639571 -252.609065) (xy 134.631676 -252.657642) (xy 134.616092 -252.704323)
			(xy 134.593221 -252.7479) (xy 134.563656 -252.787244) (xy 134.528163 -252.821336) (xy 134.48766 -252.849292)
			(xy 134.443198 -252.87039) (xy 134.395927 -252.884082) (xy 134.347072 -252.890014) (xy 134.297897 -252.888033)
			(xy 134.249678 -252.878189) (xy 134.203662 -252.860737) (xy 134.161041 -252.83613) (xy 134.12292 -252.805005)
			(xy 134.090285 -252.768168) (xy 134.063982 -252.726572) (xy 134.044691 -252.681296) (xy 134.032914 -252.633512)
			(xy 134.028954 -252.584458) (xy 133.700012 -252.584458) (xy 133.699517 -252.609065) (xy 133.691622 -252.657642)
			(xy 133.676038 -252.704323) (xy 133.653167 -252.7479) (xy 133.623602 -252.787244) (xy 133.588109 -252.821336)
			(xy 133.547606 -252.849292) (xy 133.503144 -252.87039) (xy 133.455873 -252.884082) (xy 133.407018 -252.890014)
			(xy 133.357843 -252.888033) (xy 133.309624 -252.878189) (xy 133.263608 -252.860737) (xy 133.220987 -252.83613)
			(xy 133.182866 -252.805005) (xy 133.150231 -252.768168) (xy 133.123928 -252.726572) (xy 133.104637 -252.681296)
			(xy 133.09286 -252.633512) (xy 133.0889 -252.584458) (xy 132.770372 -252.584458) (xy 132.76986 -252.609904)
			(xy 132.761696 -252.660138) (xy 132.74558 -252.708412) (xy 132.721929 -252.753475) (xy 132.691356 -252.794161)
			(xy 132.654652 -252.829416) (xy 132.612768 -252.858326) (xy 132.566789 -252.880143) (xy 132.517905 -252.894303)
			(xy 132.467384 -252.900437) (xy 132.416532 -252.898388) (xy 132.366668 -252.888208) (xy 132.319082 -252.870161)
			(xy 132.275008 -252.844715) (xy 132.235586 -252.812528) (xy 132.201838 -252.774434) (xy 132.174637 -252.73142)
			(xy 132.154689 -252.6846) (xy 132.14251 -252.635186) (xy 132.138415 -252.584458) (xy 131.820158 -252.584458)
			(xy 131.819663 -252.609065) (xy 131.811768 -252.657642) (xy 131.796184 -252.704323) (xy 131.773313 -252.7479)
			(xy 131.743748 -252.787244) (xy 131.708255 -252.821336) (xy 131.667752 -252.849292) (xy 131.62329 -252.87039)
			(xy 131.576019 -252.884082) (xy 131.527164 -252.890014) (xy 131.477989 -252.888033) (xy 131.42977 -252.878189)
			(xy 131.383754 -252.860737) (xy 131.341133 -252.83613) (xy 131.303012 -252.805005) (xy 131.270377 -252.768168)
			(xy 131.244074 -252.726572) (xy 131.224783 -252.681296) (xy 131.213006 -252.633512) (xy 131.209046 -252.584458)
			(xy 130.880104 -252.584458) (xy 130.879609 -252.609065) (xy 130.871714 -252.657642) (xy 130.85613 -252.704323)
			(xy 130.833259 -252.7479) (xy 130.803694 -252.787244) (xy 130.768201 -252.821336) (xy 130.727698 -252.849292)
			(xy 130.683236 -252.87039) (xy 130.635965 -252.884082) (xy 130.58711 -252.890014) (xy 130.537935 -252.888033)
			(xy 130.489716 -252.878189) (xy 130.4437 -252.860737) (xy 130.401079 -252.83613) (xy 130.362958 -252.805005)
			(xy 130.330323 -252.768168) (xy 130.30402 -252.726572) (xy 130.284729 -252.681296) (xy 130.272952 -252.633512)
			(xy 130.268992 -252.584458) (xy 129.950464 -252.584458) (xy 129.949952 -252.609904) (xy 129.941788 -252.660138)
			(xy 129.925672 -252.708412) (xy 129.902021 -252.753475) (xy 129.871448 -252.794161) (xy 129.834744 -252.829416)
			(xy 129.79286 -252.858326) (xy 129.746881 -252.880143) (xy 129.697997 -252.894303) (xy 129.647476 -252.900437)
			(xy 129.596624 -252.898388) (xy 129.54676 -252.888208) (xy 129.499174 -252.870161) (xy 129.4551 -252.844715)
			(xy 129.415678 -252.812528) (xy 129.38193 -252.774434) (xy 129.354729 -252.73142) (xy 129.334781 -252.6846)
			(xy 129.322602 -252.635186) (xy 129.318507 -252.584458) (xy 128.999996 -252.584458) (xy 128.999501 -252.609065)
			(xy 128.991606 -252.657642) (xy 128.976022 -252.704323) (xy 128.953151 -252.7479) (xy 128.923586 -252.787244)
			(xy 128.888093 -252.821336) (xy 128.84759 -252.849292) (xy 128.803128 -252.87039) (xy 128.755857 -252.884082)
			(xy 128.707002 -252.890014) (xy 128.657827 -252.888033) (xy 128.609608 -252.878189) (xy 128.563592 -252.860737)
			(xy 128.520971 -252.83613) (xy 128.48285 -252.805005) (xy 128.450215 -252.768168) (xy 128.423912 -252.726572)
			(xy 128.404621 -252.681296) (xy 128.392844 -252.633512) (xy 128.388884 -252.584458) (xy 128.059942 -252.584458)
			(xy 128.059447 -252.609065) (xy 128.051552 -252.657642) (xy 128.035968 -252.704323) (xy 128.013097 -252.7479)
			(xy 127.983532 -252.787244) (xy 127.948039 -252.821336) (xy 127.907536 -252.849292) (xy 127.863074 -252.87039)
			(xy 127.815803 -252.884082) (xy 127.766948 -252.890014) (xy 127.717773 -252.888033) (xy 127.669554 -252.878189)
			(xy 127.623538 -252.860737) (xy 127.580917 -252.83613) (xy 127.542796 -252.805005) (xy 127.510161 -252.768168)
			(xy 127.483858 -252.726572) (xy 127.464567 -252.681296) (xy 127.45279 -252.633512) (xy 127.44883 -252.584458)
			(xy 127.120142 -252.584458) (xy 127.119647 -252.609065) (xy 127.111752 -252.657642) (xy 127.096168 -252.704323)
			(xy 127.073297 -252.7479) (xy 127.043732 -252.787244) (xy 127.008239 -252.821336) (xy 126.967736 -252.849292)
			(xy 126.923274 -252.87039) (xy 126.876003 -252.884082) (xy 126.827148 -252.890014) (xy 126.777973 -252.888033)
			(xy 126.729754 -252.878189) (xy 126.683738 -252.860737) (xy 126.641117 -252.83613) (xy 126.602996 -252.805005)
			(xy 126.570361 -252.768168) (xy 126.544058 -252.726572) (xy 126.524767 -252.681296) (xy 126.51299 -252.633512)
			(xy 126.50903 -252.584458) (xy 125.240034 -252.584458) (xy 125.239539 -252.609065) (xy 125.231644 -252.657642)
			(xy 125.21606 -252.704323) (xy 125.193189 -252.7479) (xy 125.163624 -252.787244) (xy 125.128131 -252.821336)
			(xy 125.087628 -252.849292) (xy 125.043166 -252.87039) (xy 124.995895 -252.884082) (xy 124.94704 -252.890014)
			(xy 124.897865 -252.888033) (xy 124.849646 -252.878189) (xy 124.80363 -252.860737) (xy 124.761009 -252.83613)
			(xy 124.722888 -252.805005) (xy 124.690253 -252.768168) (xy 124.66395 -252.726572) (xy 124.644659 -252.681296)
			(xy 124.632882 -252.633512) (xy 124.628922 -252.584458) (xy 123.359926 -252.584458) (xy 123.359431 -252.609065)
			(xy 123.351536 -252.657642) (xy 123.335952 -252.704323) (xy 123.313081 -252.7479) (xy 123.283516 -252.787244)
			(xy 123.248023 -252.821336) (xy 123.20752 -252.849292) (xy 123.163058 -252.87039) (xy 123.115787 -252.884082)
			(xy 123.066932 -252.890014) (xy 123.017757 -252.888033) (xy 122.969538 -252.878189) (xy 122.923522 -252.860737)
			(xy 122.880901 -252.83613) (xy 122.84278 -252.805005) (xy 122.810145 -252.768168) (xy 122.783842 -252.726572)
			(xy 122.764551 -252.681296) (xy 122.752774 -252.633512) (xy 122.748814 -252.584458) (xy 121.480072 -252.584458)
			(xy 121.479577 -252.609065) (xy 121.471682 -252.657642) (xy 121.456098 -252.704323) (xy 121.433227 -252.7479)
			(xy 121.403662 -252.787244) (xy 121.368169 -252.821336) (xy 121.327666 -252.849292) (xy 121.283204 -252.87039)
			(xy 121.235933 -252.884082) (xy 121.187078 -252.890014) (xy 121.137903 -252.888033) (xy 121.089684 -252.878189)
			(xy 121.043668 -252.860737) (xy 121.001047 -252.83613) (xy 120.962926 -252.805005) (xy 120.930291 -252.768168)
			(xy 120.903988 -252.726572) (xy 120.884697 -252.681296) (xy 120.87292 -252.633512) (xy 120.86896 -252.584458)
			(xy 112.557092 -252.584458) (xy 112.553204 -252.59231) (xy 112.522912 -252.635376) (xy 112.4864 -252.673314)
			(xy 112.444526 -252.705233) (xy 112.39827 -252.730386) (xy 112.348717 -252.748184) (xy 112.297027 -252.758208)
			(xy 112.244413 -252.760225) (xy 112.192108 -252.754187) (xy 112.141337 -252.740235) (xy 112.093292 -252.718696)
			(xy 112.049097 -252.690076) (xy 112.009789 -252.655045) (xy 111.976289 -252.614424) (xy 111.949383 -252.569165)
			(xy 111.9297 -252.52033) (xy 111.917703 -252.469062) (xy 111.913673 -252.416564) (xy 103.237284 -252.416564)
			(xy 103.960168 -253.139448) (xy 103.966264 -253.144528) (xy 103.967534 -253.145544) (xy 103.968296 -253.146052)
			(xy 103.96982 -253.147068) (xy 103.970328 -253.147576) (xy 103.98592 -253.159525) (xy 104.014201 -253.18679)
			(xy 104.026716 -253.201932) (xy 104.035352 -253.213362) (xy 104.036368 -253.214632) (xy 104.041702 -253.220982)
			(xy 104.213152 -253.392432) (xy 105.362006 -253.392432) (xy 105.365966 -253.343378) (xy 105.377743 -253.295594)
			(xy 105.397034 -253.250318) (xy 105.423337 -253.208722) (xy 105.455972 -253.171885) (xy 105.494093 -253.14076)
			(xy 105.536714 -253.116153) (xy 105.58273 -253.098701) (xy 105.630949 -253.088857) (xy 105.680124 -253.086876)
			(xy 105.728979 -253.092808) (xy 105.77625 -253.1065) (xy 105.820712 -253.127598) (xy 105.861215 -253.155554)
			(xy 105.896708 -253.189646) (xy 105.926273 -253.22899) (xy 105.949144 -253.272567) (xy 105.964728 -253.319248)
			(xy 105.972623 -253.367825) (xy 105.973118 -253.392432) (xy 107.242114 -253.392432) (xy 107.246074 -253.343378)
			(xy 107.257851 -253.295594) (xy 107.277142 -253.250318) (xy 107.303445 -253.208722) (xy 107.33608 -253.171885)
			(xy 107.374201 -253.14076) (xy 107.416822 -253.116153) (xy 107.462838 -253.098701) (xy 107.511057 -253.088857)
			(xy 107.560232 -253.086876) (xy 107.609087 -253.092808) (xy 107.656358 -253.1065) (xy 107.70082 -253.127598)
			(xy 107.741323 -253.155554) (xy 107.776816 -253.189646) (xy 107.806381 -253.22899) (xy 107.829252 -253.272567)
			(xy 107.844836 -253.319248) (xy 107.852731 -253.367825) (xy 107.853226 -253.392432) (xy 109.122222 -253.392432)
			(xy 109.126182 -253.343378) (xy 109.137959 -253.295594) (xy 109.15725 -253.250318) (xy 109.183553 -253.208722)
			(xy 109.216188 -253.171885) (xy 109.254309 -253.14076) (xy 109.29693 -253.116153) (xy 109.342946 -253.098701)
			(xy 109.391165 -253.088857) (xy 109.44034 -253.086876) (xy 109.489195 -253.092808) (xy 109.536466 -253.1065)
			(xy 109.580928 -253.127598) (xy 109.621431 -253.155554) (xy 109.656924 -253.189646) (xy 109.686489 -253.22899)
			(xy 109.70936 -253.272567) (xy 109.724944 -253.319248) (xy 109.732839 -253.367825) (xy 109.733334 -253.392432)
			(xy 109.732839 -253.417039) (xy 109.730316 -253.432564) (xy 111.913673 -253.432564) (xy 111.917703 -253.380066)
			(xy 111.9297 -253.328798) (xy 111.949383 -253.279963) (xy 111.976289 -253.234704) (xy 112.009789 -253.194083)
			(xy 112.049097 -253.159052) (xy 112.093292 -253.130432) (xy 112.141337 -253.108893) (xy 112.192108 -253.094941)
			(xy 112.244413 -253.088903) (xy 112.297027 -253.09092) (xy 112.348717 -253.100944) (xy 112.39827 -253.118742)
			(xy 112.444526 -253.143895) (xy 112.4864 -253.175814) (xy 112.522912 -253.213752) (xy 112.553204 -253.256818)
			(xy 112.576567 -253.304003) (xy 112.592453 -253.354202) (xy 112.598358 -253.392432) (xy 112.882184 -253.392432)
			(xy 112.886144 -253.343378) (xy 112.897921 -253.295594) (xy 112.917212 -253.250318) (xy 112.943515 -253.208722)
			(xy 112.97615 -253.171885) (xy 113.014271 -253.14076) (xy 113.056892 -253.116153) (xy 113.102908 -253.098701)
			(xy 113.151127 -253.088857) (xy 113.200302 -253.086876) (xy 113.249157 -253.092808) (xy 113.296428 -253.1065)
			(xy 113.34089 -253.127598) (xy 113.381393 -253.155554) (xy 113.416886 -253.189646) (xy 113.446451 -253.22899)
			(xy 113.469322 -253.272567) (xy 113.484906 -253.319248) (xy 113.492801 -253.367825) (xy 113.493296 -253.392432)
			(xy 114.762038 -253.392432) (xy 114.765998 -253.343378) (xy 114.777775 -253.295594) (xy 114.797066 -253.250318)
			(xy 114.823369 -253.208722) (xy 114.856004 -253.171885) (xy 114.894125 -253.14076) (xy 114.936746 -253.116153)
			(xy 114.982762 -253.098701) (xy 115.030981 -253.088857) (xy 115.080156 -253.086876) (xy 115.129011 -253.092808)
			(xy 115.176282 -253.1065) (xy 115.220744 -253.127598) (xy 115.261247 -253.155554) (xy 115.29674 -253.189646)
			(xy 115.326305 -253.22899) (xy 115.349176 -253.272567) (xy 115.36476 -253.319248) (xy 115.372655 -253.367825)
			(xy 115.37315 -253.392432) (xy 116.642146 -253.392432) (xy 116.646106 -253.343378) (xy 116.657883 -253.295594)
			(xy 116.677174 -253.250318) (xy 116.703477 -253.208722) (xy 116.736112 -253.171885) (xy 116.774233 -253.14076)
			(xy 116.816854 -253.116153) (xy 116.86287 -253.098701) (xy 116.911089 -253.088857) (xy 116.960264 -253.086876)
			(xy 117.009119 -253.092808) (xy 117.05639 -253.1065) (xy 117.100852 -253.127598) (xy 117.141355 -253.155554)
			(xy 117.176848 -253.189646) (xy 117.206413 -253.22899) (xy 117.229284 -253.272567) (xy 117.244868 -253.319248)
			(xy 117.252763 -253.367825) (xy 117.253258 -253.392432) (xy 118.522 -253.392432) (xy 118.52596 -253.343378)
			(xy 118.537737 -253.295594) (xy 118.557028 -253.250318) (xy 118.583331 -253.208722) (xy 118.615966 -253.171885)
			(xy 118.654087 -253.14076) (xy 118.696708 -253.116153) (xy 118.742724 -253.098701) (xy 118.790943 -253.088857)
			(xy 118.840118 -253.086876) (xy 118.888973 -253.092808) (xy 118.936244 -253.1065) (xy 118.980706 -253.127598)
			(xy 119.021209 -253.155554) (xy 119.056702 -253.189646) (xy 119.086267 -253.22899) (xy 119.109138 -253.272567)
			(xy 119.124722 -253.319248) (xy 119.132617 -253.367825) (xy 119.133112 -253.392432) (xy 119.133071 -253.394464)
			(xy 122.278914 -253.394464) (xy 122.282874 -253.34541) (xy 122.294651 -253.297626) (xy 122.313942 -253.25235)
			(xy 122.340245 -253.210754) (xy 122.37288 -253.173917) (xy 122.411001 -253.142792) (xy 122.453622 -253.118185)
			(xy 122.499638 -253.100733) (xy 122.547857 -253.090889) (xy 122.597032 -253.088908) (xy 122.645887 -253.09484)
			(xy 122.693158 -253.108532) (xy 122.73762 -253.12963) (xy 122.778123 -253.157586) (xy 122.813616 -253.191678)
			(xy 122.843181 -253.231022) (xy 122.866052 -253.274599) (xy 122.881636 -253.32128) (xy 122.889531 -253.369857)
			(xy 122.890026 -253.394464) (xy 124.159022 -253.394464) (xy 124.162982 -253.34541) (xy 124.174759 -253.297626)
			(xy 124.19405 -253.25235) (xy 124.220353 -253.210754) (xy 124.252988 -253.173917) (xy 124.291109 -253.142792)
			(xy 124.33373 -253.118185) (xy 124.379746 -253.100733) (xy 124.427965 -253.090889) (xy 124.47714 -253.088908)
			(xy 124.525995 -253.09484) (xy 124.573266 -253.108532) (xy 124.617728 -253.12963) (xy 124.658231 -253.157586)
			(xy 124.693724 -253.191678) (xy 124.723289 -253.231022) (xy 124.74616 -253.274599) (xy 124.761744 -253.32128)
			(xy 124.769639 -253.369857) (xy 124.770134 -253.394464) (xy 126.038876 -253.394464) (xy 126.042836 -253.34541)
			(xy 126.054613 -253.297626) (xy 126.073904 -253.25235) (xy 126.100207 -253.210754) (xy 126.132842 -253.173917)
			(xy 126.170963 -253.142792) (xy 126.213584 -253.118185) (xy 126.2596 -253.100733) (xy 126.307819 -253.090889)
			(xy 126.356994 -253.088908) (xy 126.405849 -253.09484) (xy 126.45312 -253.108532) (xy 126.497582 -253.12963)
			(xy 126.538085 -253.157586) (xy 126.573578 -253.191678) (xy 126.603143 -253.231022) (xy 126.626014 -253.274599)
			(xy 126.641598 -253.32128) (xy 126.649493 -253.369857) (xy 126.649988 -253.394464) (xy 127.908553 -253.394464)
			(xy 127.912648 -253.343736) (xy 127.924827 -253.294322) (xy 127.944775 -253.247502) (xy 127.971976 -253.204488)
			(xy 128.005724 -253.166394) (xy 128.045146 -253.134207) (xy 128.08922 -253.108761) (xy 128.136806 -253.090714)
			(xy 128.18667 -253.080534) (xy 128.237522 -253.078485) (xy 128.288043 -253.084619) (xy 128.336927 -253.098779)
			(xy 128.382906 -253.120596) (xy 128.42479 -253.149506) (xy 128.461494 -253.184761) (xy 128.492067 -253.225447)
			(xy 128.515718 -253.27051) (xy 128.531834 -253.318784) (xy 128.539998 -253.369018) (xy 128.54051 -253.394464)
			(xy 128.848607 -253.394464) (xy 128.852702 -253.343736) (xy 128.864881 -253.294322) (xy 128.884829 -253.247502)
			(xy 128.91203 -253.204488) (xy 128.945778 -253.166394) (xy 128.9852 -253.134207) (xy 129.029274 -253.108761)
			(xy 129.07686 -253.090714) (xy 129.126724 -253.080534) (xy 129.177576 -253.078485) (xy 129.228097 -253.084619)
			(xy 129.276981 -253.098779) (xy 129.32296 -253.120596) (xy 129.364844 -253.149506) (xy 129.401548 -253.184761)
			(xy 129.432121 -253.225447) (xy 129.455772 -253.27051) (xy 129.471888 -253.318784) (xy 129.480052 -253.369018)
			(xy 129.480564 -253.394464) (xy 129.798838 -253.394464) (xy 129.802798 -253.34541) (xy 129.814575 -253.297626)
			(xy 129.833866 -253.25235) (xy 129.860169 -253.210754) (xy 129.892804 -253.173917) (xy 129.930925 -253.142792)
			(xy 129.973546 -253.118185) (xy 130.019562 -253.100733) (xy 130.067781 -253.090889) (xy 130.116956 -253.088908)
			(xy 130.165811 -253.09484) (xy 130.213082 -253.108532) (xy 130.257544 -253.12963) (xy 130.298047 -253.157586)
			(xy 130.33354 -253.191678) (xy 130.363105 -253.231022) (xy 130.385976 -253.274599) (xy 130.40156 -253.32128)
			(xy 130.409455 -253.369857) (xy 130.40995 -253.394464) (xy 130.728461 -253.394464) (xy 130.732556 -253.343736)
			(xy 130.744735 -253.294322) (xy 130.764683 -253.247502) (xy 130.791884 -253.204488) (xy 130.825632 -253.166394)
			(xy 130.865054 -253.134207) (xy 130.909128 -253.108761) (xy 130.956714 -253.090714) (xy 131.006578 -253.080534)
			(xy 131.05743 -253.078485) (xy 131.107951 -253.084619) (xy 131.156835 -253.098779) (xy 131.202814 -253.120596)
			(xy 131.244698 -253.149506) (xy 131.281402 -253.184761) (xy 131.311975 -253.225447) (xy 131.335626 -253.27051)
			(xy 131.351742 -253.318784) (xy 131.359906 -253.369018) (xy 131.360418 -253.394464) (xy 131.678946 -253.394464)
			(xy 131.682906 -253.34541) (xy 131.694683 -253.297626) (xy 131.713974 -253.25235) (xy 131.740277 -253.210754)
			(xy 131.772912 -253.173917) (xy 131.811033 -253.142792) (xy 131.853654 -253.118185) (xy 131.89967 -253.100733)
			(xy 131.947889 -253.090889) (xy 131.997064 -253.088908) (xy 132.045919 -253.09484) (xy 132.09319 -253.108532)
			(xy 132.137652 -253.12963) (xy 132.178155 -253.157586) (xy 132.213648 -253.191678) (xy 132.243213 -253.231022)
			(xy 132.266084 -253.274599) (xy 132.281668 -253.32128) (xy 132.289563 -253.369857) (xy 132.290058 -253.394464)
			(xy 132.608569 -253.394464) (xy 132.612664 -253.343736) (xy 132.624843 -253.294322) (xy 132.644791 -253.247502)
			(xy 132.671992 -253.204488) (xy 132.70574 -253.166394) (xy 132.745162 -253.134207) (xy 132.789236 -253.108761)
			(xy 132.836822 -253.090714) (xy 132.886686 -253.080534) (xy 132.937538 -253.078485) (xy 132.988059 -253.084619)
			(xy 133.036943 -253.098779) (xy 133.082922 -253.120596) (xy 133.124806 -253.149506) (xy 133.16151 -253.184761)
			(xy 133.192083 -253.225447) (xy 133.215734 -253.27051) (xy 133.23185 -253.318784) (xy 133.240014 -253.369018)
			(xy 133.240526 -253.394464) (xy 133.559054 -253.394464) (xy 133.563014 -253.34541) (xy 133.574791 -253.297626)
			(xy 133.594082 -253.25235) (xy 133.620385 -253.210754) (xy 133.65302 -253.173917) (xy 133.691141 -253.142792)
			(xy 133.733762 -253.118185) (xy 133.779778 -253.100733) (xy 133.827997 -253.090889) (xy 133.877172 -253.088908)
			(xy 133.926027 -253.09484) (xy 133.973298 -253.108532) (xy 134.01776 -253.12963) (xy 134.058263 -253.157586)
			(xy 134.093756 -253.191678) (xy 134.123321 -253.231022) (xy 134.146192 -253.274599) (xy 134.161776 -253.32128)
			(xy 134.169671 -253.369857) (xy 134.170166 -253.394464) (xy 134.498854 -253.394464) (xy 134.502814 -253.34541)
			(xy 134.514591 -253.297626) (xy 134.533882 -253.25235) (xy 134.560185 -253.210754) (xy 134.59282 -253.173917)
			(xy 134.630941 -253.142792) (xy 134.673562 -253.118185) (xy 134.719578 -253.100733) (xy 134.767797 -253.090889)
			(xy 134.816972 -253.088908) (xy 134.865827 -253.09484) (xy 134.913098 -253.108532) (xy 134.95756 -253.12963)
			(xy 134.998063 -253.157586) (xy 135.033556 -253.191678) (xy 135.063121 -253.231022) (xy 135.085992 -253.274599)
			(xy 135.101576 -253.32128) (xy 135.109471 -253.369857) (xy 135.109966 -253.394464) (xy 135.438908 -253.394464)
			(xy 135.442868 -253.34541) (xy 135.454645 -253.297626) (xy 135.473936 -253.25235) (xy 135.500239 -253.210754)
			(xy 135.532874 -253.173917) (xy 135.570995 -253.142792) (xy 135.613616 -253.118185) (xy 135.659632 -253.100733)
			(xy 135.707851 -253.090889) (xy 135.757026 -253.088908) (xy 135.805881 -253.09484) (xy 135.853152 -253.108532)
			(xy 135.897614 -253.12963) (xy 135.938117 -253.157586) (xy 135.97361 -253.191678) (xy 136.003175 -253.231022)
			(xy 136.026046 -253.274599) (xy 136.04163 -253.32128) (xy 136.049525 -253.369857) (xy 136.05002 -253.394464)
			(xy 136.378962 -253.394464) (xy 136.382922 -253.34541) (xy 136.394699 -253.297626) (xy 136.41399 -253.25235)
			(xy 136.440293 -253.210754) (xy 136.472928 -253.173917) (xy 136.511049 -253.142792) (xy 136.55367 -253.118185)
			(xy 136.599686 -253.100733) (xy 136.647905 -253.090889) (xy 136.69708 -253.088908) (xy 136.745935 -253.09484)
			(xy 136.793206 -253.108532) (xy 136.837668 -253.12963) (xy 136.878171 -253.157586) (xy 136.913664 -253.191678)
			(xy 136.943229 -253.231022) (xy 136.9661 -253.274599) (xy 136.981684 -253.32128) (xy 136.989579 -253.369857)
			(xy 136.990074 -253.394464) (xy 137.319016 -253.394464) (xy 137.322976 -253.34541) (xy 137.334753 -253.297626)
			(xy 137.354044 -253.25235) (xy 137.380347 -253.210754) (xy 137.412982 -253.173917) (xy 137.451103 -253.142792)
			(xy 137.493724 -253.118185) (xy 137.53974 -253.100733) (xy 137.587959 -253.090889) (xy 137.637134 -253.088908)
			(xy 137.685989 -253.09484) (xy 137.73326 -253.108532) (xy 137.777722 -253.12963) (xy 137.818225 -253.157586)
			(xy 137.853718 -253.191678) (xy 137.883283 -253.231022) (xy 137.906154 -253.274599) (xy 137.921738 -253.32128)
			(xy 137.929633 -253.369857) (xy 137.930128 -253.394464) (xy 138.25907 -253.394464) (xy 138.26303 -253.34541)
			(xy 138.274807 -253.297626) (xy 138.294098 -253.25235) (xy 138.320401 -253.210754) (xy 138.353036 -253.173917)
			(xy 138.391157 -253.142792) (xy 138.433778 -253.118185) (xy 138.479794 -253.100733) (xy 138.528013 -253.090889)
			(xy 138.577188 -253.088908) (xy 138.626043 -253.09484) (xy 138.673314 -253.108532) (xy 138.717776 -253.12963)
			(xy 138.758279 -253.157586) (xy 138.793772 -253.191678) (xy 138.823337 -253.231022) (xy 138.846208 -253.274599)
			(xy 138.861792 -253.32128) (xy 138.869687 -253.369857) (xy 138.870182 -253.394464) (xy 139.19887 -253.394464)
			(xy 139.20283 -253.34541) (xy 139.214607 -253.297626) (xy 139.233898 -253.25235) (xy 139.260201 -253.210754)
			(xy 139.292836 -253.173917) (xy 139.330957 -253.142792) (xy 139.373578 -253.118185) (xy 139.419594 -253.100733)
			(xy 139.467813 -253.090889) (xy 139.516988 -253.088908) (xy 139.565843 -253.09484) (xy 139.613114 -253.108532)
			(xy 139.657576 -253.12963) (xy 139.698079 -253.157586) (xy 139.733572 -253.191678) (xy 139.763137 -253.231022)
			(xy 139.786008 -253.274599) (xy 139.801592 -253.32128) (xy 139.809487 -253.369857) (xy 139.809982 -253.394464)
			(xy 139.809487 -253.419071) (xy 139.801592 -253.467648) (xy 139.786008 -253.514329) (xy 139.763137 -253.557906)
			(xy 139.733572 -253.59725) (xy 139.698079 -253.631342) (xy 139.657576 -253.659298) (xy 139.613114 -253.680396)
			(xy 139.565843 -253.694088) (xy 139.516988 -253.70002) (xy 139.467813 -253.698039) (xy 139.419594 -253.688195)
			(xy 139.373578 -253.670743) (xy 139.330957 -253.646136) (xy 139.292836 -253.615011) (xy 139.260201 -253.578174)
			(xy 139.233898 -253.536578) (xy 139.214607 -253.491302) (xy 139.20283 -253.443518) (xy 139.19887 -253.394464)
			(xy 138.870182 -253.394464) (xy 138.869687 -253.419071) (xy 138.861792 -253.467648) (xy 138.846208 -253.514329)
			(xy 138.823337 -253.557906) (xy 138.793772 -253.59725) (xy 138.758279 -253.631342) (xy 138.717776 -253.659298)
			(xy 138.673314 -253.680396) (xy 138.626043 -253.694088) (xy 138.577188 -253.70002) (xy 138.528013 -253.698039)
			(xy 138.479794 -253.688195) (xy 138.433778 -253.670743) (xy 138.391157 -253.646136) (xy 138.353036 -253.615011)
			(xy 138.320401 -253.578174) (xy 138.294098 -253.536578) (xy 138.274807 -253.491302) (xy 138.26303 -253.443518)
			(xy 138.25907 -253.394464) (xy 137.930128 -253.394464) (xy 137.929633 -253.419071) (xy 137.921738 -253.467648)
			(xy 137.906154 -253.514329) (xy 137.883283 -253.557906) (xy 137.853718 -253.59725) (xy 137.818225 -253.631342)
			(xy 137.777722 -253.659298) (xy 137.73326 -253.680396) (xy 137.685989 -253.694088) (xy 137.637134 -253.70002)
			(xy 137.587959 -253.698039) (xy 137.53974 -253.688195) (xy 137.493724 -253.670743) (xy 137.451103 -253.646136)
			(xy 137.412982 -253.615011) (xy 137.380347 -253.578174) (xy 137.354044 -253.536578) (xy 137.334753 -253.491302)
			(xy 137.322976 -253.443518) (xy 137.319016 -253.394464) (xy 136.990074 -253.394464) (xy 136.989579 -253.419071)
			(xy 136.981684 -253.467648) (xy 136.9661 -253.514329) (xy 136.943229 -253.557906) (xy 136.913664 -253.59725)
			(xy 136.878171 -253.631342) (xy 136.837668 -253.659298) (xy 136.793206 -253.680396) (xy 136.745935 -253.694088)
			(xy 136.69708 -253.70002) (xy 136.647905 -253.698039) (xy 136.599686 -253.688195) (xy 136.55367 -253.670743)
			(xy 136.511049 -253.646136) (xy 136.472928 -253.615011) (xy 136.440293 -253.578174) (xy 136.41399 -253.536578)
			(xy 136.394699 -253.491302) (xy 136.382922 -253.443518) (xy 136.378962 -253.394464) (xy 136.05002 -253.394464)
			(xy 136.049525 -253.419071) (xy 136.04163 -253.467648) (xy 136.026046 -253.514329) (xy 136.003175 -253.557906)
			(xy 135.97361 -253.59725) (xy 135.938117 -253.631342) (xy 135.897614 -253.659298) (xy 135.853152 -253.680396)
			(xy 135.805881 -253.694088) (xy 135.757026 -253.70002) (xy 135.707851 -253.698039) (xy 135.659632 -253.688195)
			(xy 135.613616 -253.670743) (xy 135.570995 -253.646136) (xy 135.532874 -253.615011) (xy 135.500239 -253.578174)
			(xy 135.473936 -253.536578) (xy 135.454645 -253.491302) (xy 135.442868 -253.443518) (xy 135.438908 -253.394464)
			(xy 135.109966 -253.394464) (xy 135.109471 -253.419071) (xy 135.101576 -253.467648) (xy 135.085992 -253.514329)
			(xy 135.063121 -253.557906) (xy 135.033556 -253.59725) (xy 134.998063 -253.631342) (xy 134.95756 -253.659298)
			(xy 134.913098 -253.680396) (xy 134.865827 -253.694088) (xy 134.816972 -253.70002) (xy 134.767797 -253.698039)
			(xy 134.719578 -253.688195) (xy 134.673562 -253.670743) (xy 134.630941 -253.646136) (xy 134.59282 -253.615011)
			(xy 134.560185 -253.578174) (xy 134.533882 -253.536578) (xy 134.514591 -253.491302) (xy 134.502814 -253.443518)
			(xy 134.498854 -253.394464) (xy 134.170166 -253.394464) (xy 134.169671 -253.419071) (xy 134.161776 -253.467648)
			(xy 134.146192 -253.514329) (xy 134.123321 -253.557906) (xy 134.093756 -253.59725) (xy 134.058263 -253.631342)
			(xy 134.01776 -253.659298) (xy 133.973298 -253.680396) (xy 133.926027 -253.694088) (xy 133.877172 -253.70002)
			(xy 133.827997 -253.698039) (xy 133.779778 -253.688195) (xy 133.733762 -253.670743) (xy 133.691141 -253.646136)
			(xy 133.65302 -253.615011) (xy 133.620385 -253.578174) (xy 133.594082 -253.536578) (xy 133.574791 -253.491302)
			(xy 133.563014 -253.443518) (xy 133.559054 -253.394464) (xy 133.240526 -253.394464) (xy 133.240014 -253.41991)
			(xy 133.23185 -253.470144) (xy 133.215734 -253.518418) (xy 133.192083 -253.563481) (xy 133.16151 -253.604167)
			(xy 133.124806 -253.639422) (xy 133.082922 -253.668332) (xy 133.036943 -253.690149) (xy 132.988059 -253.704309)
			(xy 132.937538 -253.710443) (xy 132.886686 -253.708394) (xy 132.836822 -253.698214) (xy 132.789236 -253.680167)
			(xy 132.745162 -253.654721) (xy 132.70574 -253.622534) (xy 132.671992 -253.58444) (xy 132.644791 -253.541426)
			(xy 132.624843 -253.494606) (xy 132.612664 -253.445192) (xy 132.608569 -253.394464) (xy 132.290058 -253.394464)
			(xy 132.289563 -253.419071) (xy 132.281668 -253.467648) (xy 132.266084 -253.514329) (xy 132.243213 -253.557906)
			(xy 132.213648 -253.59725) (xy 132.178155 -253.631342) (xy 132.137652 -253.659298) (xy 132.09319 -253.680396)
			(xy 132.045919 -253.694088) (xy 131.997064 -253.70002) (xy 131.947889 -253.698039) (xy 131.89967 -253.688195)
			(xy 131.853654 -253.670743) (xy 131.811033 -253.646136) (xy 131.772912 -253.615011) (xy 131.740277 -253.578174)
			(xy 131.713974 -253.536578) (xy 131.694683 -253.491302) (xy 131.682906 -253.443518) (xy 131.678946 -253.394464)
			(xy 131.360418 -253.394464) (xy 131.359906 -253.41991) (xy 131.351742 -253.470144) (xy 131.335626 -253.518418)
			(xy 131.311975 -253.563481) (xy 131.281402 -253.604167) (xy 131.244698 -253.639422) (xy 131.202814 -253.668332)
			(xy 131.156835 -253.690149) (xy 131.107951 -253.704309) (xy 131.05743 -253.710443) (xy 131.006578 -253.708394)
			(xy 130.956714 -253.698214) (xy 130.909128 -253.680167) (xy 130.865054 -253.654721) (xy 130.825632 -253.622534)
			(xy 130.791884 -253.58444) (xy 130.764683 -253.541426) (xy 130.744735 -253.494606) (xy 130.732556 -253.445192)
			(xy 130.728461 -253.394464) (xy 130.40995 -253.394464) (xy 130.409455 -253.419071) (xy 130.40156 -253.467648)
			(xy 130.385976 -253.514329) (xy 130.363105 -253.557906) (xy 130.33354 -253.59725) (xy 130.298047 -253.631342)
			(xy 130.257544 -253.659298) (xy 130.213082 -253.680396) (xy 130.165811 -253.694088) (xy 130.116956 -253.70002)
			(xy 130.067781 -253.698039) (xy 130.019562 -253.688195) (xy 129.973546 -253.670743) (xy 129.930925 -253.646136)
			(xy 129.892804 -253.615011) (xy 129.860169 -253.578174) (xy 129.833866 -253.536578) (xy 129.814575 -253.491302)
			(xy 129.802798 -253.443518) (xy 129.798838 -253.394464) (xy 129.480564 -253.394464) (xy 129.480052 -253.41991)
			(xy 129.471888 -253.470144) (xy 129.455772 -253.518418) (xy 129.432121 -253.563481) (xy 129.401548 -253.604167)
			(xy 129.364844 -253.639422) (xy 129.32296 -253.668332) (xy 129.276981 -253.690149) (xy 129.228097 -253.704309)
			(xy 129.177576 -253.710443) (xy 129.126724 -253.708394) (xy 129.07686 -253.698214) (xy 129.029274 -253.680167)
			(xy 128.9852 -253.654721) (xy 128.945778 -253.622534) (xy 128.91203 -253.58444) (xy 128.884829 -253.541426)
			(xy 128.864881 -253.494606) (xy 128.852702 -253.445192) (xy 128.848607 -253.394464) (xy 128.54051 -253.394464)
			(xy 128.539998 -253.41991) (xy 128.531834 -253.470144) (xy 128.515718 -253.518418) (xy 128.492067 -253.563481)
			(xy 128.461494 -253.604167) (xy 128.42479 -253.639422) (xy 128.382906 -253.668332) (xy 128.336927 -253.690149)
			(xy 128.288043 -253.704309) (xy 128.237522 -253.710443) (xy 128.18667 -253.708394) (xy 128.136806 -253.698214)
			(xy 128.08922 -253.680167) (xy 128.045146 -253.654721) (xy 128.005724 -253.622534) (xy 127.971976 -253.58444)
			(xy 127.944775 -253.541426) (xy 127.924827 -253.494606) (xy 127.912648 -253.445192) (xy 127.908553 -253.394464)
			(xy 126.649988 -253.394464) (xy 126.649493 -253.419071) (xy 126.641598 -253.467648) (xy 126.626014 -253.514329)
			(xy 126.603143 -253.557906) (xy 126.573578 -253.59725) (xy 126.538085 -253.631342) (xy 126.497582 -253.659298)
			(xy 126.45312 -253.680396) (xy 126.405849 -253.694088) (xy 126.356994 -253.70002) (xy 126.307819 -253.698039)
			(xy 126.2596 -253.688195) (xy 126.213584 -253.670743) (xy 126.170963 -253.646136) (xy 126.132842 -253.615011)
			(xy 126.100207 -253.578174) (xy 126.073904 -253.536578) (xy 126.054613 -253.491302) (xy 126.042836 -253.443518)
			(xy 126.038876 -253.394464) (xy 124.770134 -253.394464) (xy 124.769639 -253.419071) (xy 124.761744 -253.467648)
			(xy 124.74616 -253.514329) (xy 124.723289 -253.557906) (xy 124.693724 -253.59725) (xy 124.658231 -253.631342)
			(xy 124.617728 -253.659298) (xy 124.573266 -253.680396) (xy 124.525995 -253.694088) (xy 124.47714 -253.70002)
			(xy 124.427965 -253.698039) (xy 124.379746 -253.688195) (xy 124.33373 -253.670743) (xy 124.291109 -253.646136)
			(xy 124.252988 -253.615011) (xy 124.220353 -253.578174) (xy 124.19405 -253.536578) (xy 124.174759 -253.491302)
			(xy 124.162982 -253.443518) (xy 124.159022 -253.394464) (xy 122.890026 -253.394464) (xy 122.889531 -253.419071)
			(xy 122.881636 -253.467648) (xy 122.866052 -253.514329) (xy 122.843181 -253.557906) (xy 122.813616 -253.59725)
			(xy 122.778123 -253.631342) (xy 122.73762 -253.659298) (xy 122.693158 -253.680396) (xy 122.645887 -253.694088)
			(xy 122.597032 -253.70002) (xy 122.547857 -253.698039) (xy 122.499638 -253.688195) (xy 122.453622 -253.670743)
			(xy 122.411001 -253.646136) (xy 122.37288 -253.615011) (xy 122.340245 -253.578174) (xy 122.313942 -253.536578)
			(xy 122.294651 -253.491302) (xy 122.282874 -253.443518) (xy 122.278914 -253.394464) (xy 119.133071 -253.394464)
			(xy 119.132617 -253.417039) (xy 119.124722 -253.465616) (xy 119.109138 -253.512297) (xy 119.086267 -253.555874)
			(xy 119.056702 -253.595218) (xy 119.021209 -253.62931) (xy 118.980706 -253.657266) (xy 118.936244 -253.678364)
			(xy 118.888973 -253.692056) (xy 118.840118 -253.697988) (xy 118.790943 -253.696007) (xy 118.742724 -253.686163)
			(xy 118.696708 -253.668711) (xy 118.654087 -253.644104) (xy 118.615966 -253.612979) (xy 118.583331 -253.576142)
			(xy 118.557028 -253.534546) (xy 118.537737 -253.48927) (xy 118.52596 -253.441486) (xy 118.522 -253.392432)
			(xy 117.253258 -253.392432) (xy 117.252763 -253.417039) (xy 117.244868 -253.465616) (xy 117.229284 -253.512297)
			(xy 117.206413 -253.555874) (xy 117.176848 -253.595218) (xy 117.141355 -253.62931) (xy 117.100852 -253.657266)
			(xy 117.05639 -253.678364) (xy 117.009119 -253.692056) (xy 116.960264 -253.697988) (xy 116.911089 -253.696007)
			(xy 116.86287 -253.686163) (xy 116.816854 -253.668711) (xy 116.774233 -253.644104) (xy 116.736112 -253.612979)
			(xy 116.703477 -253.576142) (xy 116.677174 -253.534546) (xy 116.657883 -253.48927) (xy 116.646106 -253.441486)
			(xy 116.642146 -253.392432) (xy 115.37315 -253.392432) (xy 115.372655 -253.417039) (xy 115.36476 -253.465616)
			(xy 115.349176 -253.512297) (xy 115.326305 -253.555874) (xy 115.29674 -253.595218) (xy 115.261247 -253.62931)
			(xy 115.220744 -253.657266) (xy 115.176282 -253.678364) (xy 115.129011 -253.692056) (xy 115.080156 -253.697988)
			(xy 115.030981 -253.696007) (xy 114.982762 -253.686163) (xy 114.936746 -253.668711) (xy 114.894125 -253.644104)
			(xy 114.856004 -253.612979) (xy 114.823369 -253.576142) (xy 114.797066 -253.534546) (xy 114.777775 -253.48927)
			(xy 114.765998 -253.441486) (xy 114.762038 -253.392432) (xy 113.493296 -253.392432) (xy 113.492801 -253.417039)
			(xy 113.484906 -253.465616) (xy 113.469322 -253.512297) (xy 113.446451 -253.555874) (xy 113.416886 -253.595218)
			(xy 113.381393 -253.62931) (xy 113.34089 -253.657266) (xy 113.296428 -253.678364) (xy 113.249157 -253.692056)
			(xy 113.200302 -253.697988) (xy 113.151127 -253.696007) (xy 113.102908 -253.686163) (xy 113.056892 -253.668711)
			(xy 113.014271 -253.644104) (xy 112.97615 -253.612979) (xy 112.943515 -253.576142) (xy 112.917212 -253.534546)
			(xy 112.897921 -253.48927) (xy 112.886144 -253.441486) (xy 112.882184 -253.392432) (xy 112.598358 -253.392432)
			(xy 112.60049 -253.406238) (xy 112.600994 -253.432564) (xy 112.60049 -253.45889) (xy 112.592453 -253.510926)
			(xy 112.576567 -253.561125) (xy 112.553204 -253.60831) (xy 112.522912 -253.651376) (xy 112.4864 -253.689314)
			(xy 112.444526 -253.721233) (xy 112.39827 -253.746386) (xy 112.348717 -253.764184) (xy 112.297027 -253.774208)
			(xy 112.244413 -253.776225) (xy 112.192108 -253.770187) (xy 112.141337 -253.756235) (xy 112.093292 -253.734696)
			(xy 112.049097 -253.706076) (xy 112.009789 -253.671045) (xy 111.976289 -253.630424) (xy 111.949383 -253.585165)
			(xy 111.9297 -253.53633) (xy 111.917703 -253.485062) (xy 111.913673 -253.432564) (xy 109.730316 -253.432564)
			(xy 109.724944 -253.465616) (xy 109.70936 -253.512297) (xy 109.686489 -253.555874) (xy 109.656924 -253.595218)
			(xy 109.621431 -253.62931) (xy 109.580928 -253.657266) (xy 109.536466 -253.678364) (xy 109.489195 -253.692056)
			(xy 109.44034 -253.697988) (xy 109.391165 -253.696007) (xy 109.342946 -253.686163) (xy 109.29693 -253.668711)
			(xy 109.254309 -253.644104) (xy 109.216188 -253.612979) (xy 109.183553 -253.576142) (xy 109.15725 -253.534546)
			(xy 109.137959 -253.48927) (xy 109.126182 -253.441486) (xy 109.122222 -253.392432) (xy 107.853226 -253.392432)
			(xy 107.852731 -253.417039) (xy 107.844836 -253.465616) (xy 107.829252 -253.512297) (xy 107.806381 -253.555874)
			(xy 107.776816 -253.595218) (xy 107.741323 -253.62931) (xy 107.70082 -253.657266) (xy 107.656358 -253.678364)
			(xy 107.609087 -253.692056) (xy 107.560232 -253.697988) (xy 107.511057 -253.696007) (xy 107.462838 -253.686163)
			(xy 107.416822 -253.668711) (xy 107.374201 -253.644104) (xy 107.33608 -253.612979) (xy 107.303445 -253.576142)
			(xy 107.277142 -253.534546) (xy 107.257851 -253.48927) (xy 107.246074 -253.441486) (xy 107.242114 -253.392432)
			(xy 105.973118 -253.392432) (xy 105.972623 -253.417039) (xy 105.964728 -253.465616) (xy 105.949144 -253.512297)
			(xy 105.926273 -253.555874) (xy 105.896708 -253.595218) (xy 105.861215 -253.62931) (xy 105.820712 -253.657266)
			(xy 105.77625 -253.678364) (xy 105.728979 -253.692056) (xy 105.680124 -253.697988) (xy 105.630949 -253.696007)
			(xy 105.58273 -253.686163) (xy 105.536714 -253.668711) (xy 105.494093 -253.644104) (xy 105.455972 -253.612979)
			(xy 105.423337 -253.576142) (xy 105.397034 -253.534546) (xy 105.377743 -253.48927) (xy 105.365966 -253.441486)
			(xy 105.362006 -253.392432) (xy 104.213152 -253.392432) (xy 105.269284 -254.448564) (xy 111.913673 -254.448564)
			(xy 111.917703 -254.396066) (xy 111.9297 -254.344798) (xy 111.949383 -254.295963) (xy 111.976289 -254.250704)
			(xy 112.009789 -254.210083) (xy 112.049097 -254.175052) (xy 112.093292 -254.146432) (xy 112.141337 -254.124893)
			(xy 112.192108 -254.110941) (xy 112.244413 -254.104903) (xy 112.297027 -254.10692) (xy 112.348717 -254.116944)
			(xy 112.39827 -254.134742) (xy 112.444526 -254.159895) (xy 112.4864 -254.191814) (xy 112.49858 -254.20447)
			(xy 120.86896 -254.20447) (xy 120.87292 -254.155416) (xy 120.884697 -254.107632) (xy 120.903988 -254.062356)
			(xy 120.930291 -254.02076) (xy 120.962926 -253.983923) (xy 121.001047 -253.952798) (xy 121.043668 -253.928191)
			(xy 121.089684 -253.910739) (xy 121.137903 -253.900895) (xy 121.187078 -253.898914) (xy 121.235933 -253.904846)
			(xy 121.283204 -253.918538) (xy 121.327666 -253.939636) (xy 121.368169 -253.967592) (xy 121.403662 -254.001684)
			(xy 121.433227 -254.041028) (xy 121.456098 -254.084605) (xy 121.471682 -254.131286) (xy 121.479577 -254.179863)
			(xy 121.480072 -254.20447) (xy 122.748814 -254.20447) (xy 122.752774 -254.155416) (xy 122.764551 -254.107632)
			(xy 122.783842 -254.062356) (xy 122.810145 -254.02076) (xy 122.84278 -253.983923) (xy 122.880901 -253.952798)
			(xy 122.923522 -253.928191) (xy 122.969538 -253.910739) (xy 123.017757 -253.900895) (xy 123.066932 -253.898914)
			(xy 123.115787 -253.904846) (xy 123.163058 -253.918538) (xy 123.20752 -253.939636) (xy 123.248023 -253.967592)
			(xy 123.283516 -254.001684) (xy 123.313081 -254.041028) (xy 123.335952 -254.084605) (xy 123.351536 -254.131286)
			(xy 123.359431 -254.179863) (xy 123.359926 -254.20447) (xy 124.628922 -254.20447) (xy 124.632882 -254.155416)
			(xy 124.644659 -254.107632) (xy 124.66395 -254.062356) (xy 124.690253 -254.02076) (xy 124.722888 -253.983923)
			(xy 124.761009 -253.952798) (xy 124.80363 -253.928191) (xy 124.849646 -253.910739) (xy 124.897865 -253.900895)
			(xy 124.94704 -253.898914) (xy 124.995895 -253.904846) (xy 125.043166 -253.918538) (xy 125.087628 -253.939636)
			(xy 125.128131 -253.967592) (xy 125.163624 -254.001684) (xy 125.193189 -254.041028) (xy 125.21606 -254.084605)
			(xy 125.231644 -254.131286) (xy 125.239539 -254.179863) (xy 125.240034 -254.20447) (xy 126.50903 -254.20447)
			(xy 126.51299 -254.155416) (xy 126.524767 -254.107632) (xy 126.544058 -254.062356) (xy 126.570361 -254.02076)
			(xy 126.602996 -253.983923) (xy 126.641117 -253.952798) (xy 126.683738 -253.928191) (xy 126.729754 -253.910739)
			(xy 126.777973 -253.900895) (xy 126.827148 -253.898914) (xy 126.876003 -253.904846) (xy 126.923274 -253.918538)
			(xy 126.967736 -253.939636) (xy 127.008239 -253.967592) (xy 127.043732 -254.001684) (xy 127.073297 -254.041028)
			(xy 127.096168 -254.084605) (xy 127.111752 -254.131286) (xy 127.119647 -254.179863) (xy 127.120142 -254.20447)
			(xy 127.438399 -254.20447) (xy 127.442494 -254.153742) (xy 127.454673 -254.104328) (xy 127.474621 -254.057508)
			(xy 127.501822 -254.014494) (xy 127.53557 -253.9764) (xy 127.574992 -253.944213) (xy 127.619066 -253.918767)
			(xy 127.666652 -253.90072) (xy 127.716516 -253.89054) (xy 127.767368 -253.888491) (xy 127.817889 -253.894625)
			(xy 127.866773 -253.908785) (xy 127.912752 -253.930602) (xy 127.954636 -253.959512) (xy 127.99134 -253.994767)
			(xy 128.021913 -254.035453) (xy 128.045564 -254.080516) (xy 128.06168 -254.12879) (xy 128.069844 -254.179024)
			(xy 128.070356 -254.20447) (xy 128.388884 -254.20447) (xy 128.392844 -254.155416) (xy 128.404621 -254.107632)
			(xy 128.423912 -254.062356) (xy 128.450215 -254.02076) (xy 128.48285 -253.983923) (xy 128.520971 -253.952798)
			(xy 128.563592 -253.928191) (xy 128.609608 -253.910739) (xy 128.657827 -253.900895) (xy 128.707002 -253.898914)
			(xy 128.755857 -253.904846) (xy 128.803128 -253.918538) (xy 128.84759 -253.939636) (xy 128.888093 -253.967592)
			(xy 128.923586 -254.001684) (xy 128.953151 -254.041028) (xy 128.976022 -254.084605) (xy 128.991606 -254.131286)
			(xy 128.999501 -254.179863) (xy 128.999996 -254.20447) (xy 129.318507 -254.20447) (xy 129.322602 -254.153742)
			(xy 129.334781 -254.104328) (xy 129.354729 -254.057508) (xy 129.38193 -254.014494) (xy 129.415678 -253.9764)
			(xy 129.4551 -253.944213) (xy 129.499174 -253.918767) (xy 129.54676 -253.90072) (xy 129.596624 -253.89054)
			(xy 129.647476 -253.888491) (xy 129.697997 -253.894625) (xy 129.746881 -253.908785) (xy 129.79286 -253.930602)
			(xy 129.834744 -253.959512) (xy 129.871448 -253.994767) (xy 129.902021 -254.035453) (xy 129.925672 -254.080516)
			(xy 129.941788 -254.12879) (xy 129.949952 -254.179024) (xy 129.950464 -254.20447) (xy 131.198615 -254.20447)
			(xy 131.20271 -254.153742) (xy 131.214889 -254.104328) (xy 131.234837 -254.057508) (xy 131.262038 -254.014494)
			(xy 131.295786 -253.9764) (xy 131.335208 -253.944213) (xy 131.379282 -253.918767) (xy 131.426868 -253.90072)
			(xy 131.476732 -253.89054) (xy 131.527584 -253.888491) (xy 131.578105 -253.894625) (xy 131.626989 -253.908785)
			(xy 131.672968 -253.930602) (xy 131.714852 -253.959512) (xy 131.751556 -253.994767) (xy 131.782129 -254.035453)
			(xy 131.80578 -254.080516) (xy 131.821896 -254.12879) (xy 131.83006 -254.179024) (xy 131.830572 -254.20447)
			(xy 132.138415 -254.20447) (xy 132.14251 -254.153742) (xy 132.154689 -254.104328) (xy 132.174637 -254.057508)
			(xy 132.201838 -254.014494) (xy 132.235586 -253.9764) (xy 132.275008 -253.944213) (xy 132.319082 -253.918767)
			(xy 132.366668 -253.90072) (xy 132.416532 -253.89054) (xy 132.467384 -253.888491) (xy 132.517905 -253.894625)
			(xy 132.566789 -253.908785) (xy 132.612768 -253.930602) (xy 132.654652 -253.959512) (xy 132.691356 -253.994767)
			(xy 132.721929 -254.035453) (xy 132.74558 -254.080516) (xy 132.761696 -254.12879) (xy 132.76986 -254.179024)
			(xy 132.770372 -254.20447) (xy 133.0889 -254.20447) (xy 133.09286 -254.155416) (xy 133.104637 -254.107632)
			(xy 133.123928 -254.062356) (xy 133.150231 -254.02076) (xy 133.182866 -253.983923) (xy 133.220987 -253.952798)
			(xy 133.263608 -253.928191) (xy 133.309624 -253.910739) (xy 133.357843 -253.900895) (xy 133.407018 -253.898914)
			(xy 133.455873 -253.904846) (xy 133.503144 -253.918538) (xy 133.547606 -253.939636) (xy 133.588109 -253.967592)
			(xy 133.623602 -254.001684) (xy 133.653167 -254.041028) (xy 133.676038 -254.084605) (xy 133.691622 -254.131286)
			(xy 133.699517 -254.179863) (xy 133.700012 -254.20447) (xy 134.028954 -254.20447) (xy 134.032914 -254.155416)
			(xy 134.044691 -254.107632) (xy 134.063982 -254.062356) (xy 134.090285 -254.02076) (xy 134.12292 -253.983923)
			(xy 134.161041 -253.952798) (xy 134.203662 -253.928191) (xy 134.249678 -253.910739) (xy 134.297897 -253.900895)
			(xy 134.347072 -253.898914) (xy 134.395927 -253.904846) (xy 134.443198 -253.918538) (xy 134.48766 -253.939636)
			(xy 134.528163 -253.967592) (xy 134.563656 -254.001684) (xy 134.593221 -254.041028) (xy 134.616092 -254.084605)
			(xy 134.631676 -254.131286) (xy 134.639571 -254.179863) (xy 134.640066 -254.20447) (xy 134.969008 -254.20447)
			(xy 134.972968 -254.155416) (xy 134.984745 -254.107632) (xy 135.004036 -254.062356) (xy 135.030339 -254.02076)
			(xy 135.062974 -253.983923) (xy 135.101095 -253.952798) (xy 135.143716 -253.928191) (xy 135.189732 -253.910739)
			(xy 135.237951 -253.900895) (xy 135.287126 -253.898914) (xy 135.335981 -253.904846) (xy 135.383252 -253.918538)
			(xy 135.427714 -253.939636) (xy 135.468217 -253.967592) (xy 135.50371 -254.001684) (xy 135.533275 -254.041028)
			(xy 135.556146 -254.084605) (xy 135.57173 -254.131286) (xy 135.579625 -254.179863) (xy 135.58012 -254.20447)
			(xy 135.909062 -254.20447) (xy 135.913022 -254.155416) (xy 135.924799 -254.107632) (xy 135.94409 -254.062356)
			(xy 135.970393 -254.02076) (xy 136.003028 -253.983923) (xy 136.041149 -253.952798) (xy 136.08377 -253.928191)
			(xy 136.129786 -253.910739) (xy 136.178005 -253.900895) (xy 136.22718 -253.898914) (xy 136.276035 -253.904846)
			(xy 136.323306 -253.918538) (xy 136.367768 -253.939636) (xy 136.408271 -253.967592) (xy 136.443764 -254.001684)
			(xy 136.473329 -254.041028) (xy 136.4962 -254.084605) (xy 136.511784 -254.131286) (xy 136.519679 -254.179863)
			(xy 136.520174 -254.20447) (xy 137.788916 -254.20447) (xy 137.792876 -254.155416) (xy 137.804653 -254.107632)
			(xy 137.823944 -254.062356) (xy 137.850247 -254.02076) (xy 137.882882 -253.983923) (xy 137.921003 -253.952798)
			(xy 137.963624 -253.928191) (xy 138.00964 -253.910739) (xy 138.057859 -253.900895) (xy 138.107034 -253.898914)
			(xy 138.155889 -253.904846) (xy 138.20316 -253.918538) (xy 138.247622 -253.939636) (xy 138.288125 -253.967592)
			(xy 138.323618 -254.001684) (xy 138.353183 -254.041028) (xy 138.376054 -254.084605) (xy 138.391638 -254.131286)
			(xy 138.399533 -254.179863) (xy 138.400028 -254.20447) (xy 138.72897 -254.20447) (xy 138.73293 -254.155416)
			(xy 138.744707 -254.107632) (xy 138.763998 -254.062356) (xy 138.790301 -254.02076) (xy 138.822936 -253.983923)
			(xy 138.861057 -253.952798) (xy 138.903678 -253.928191) (xy 138.949694 -253.910739) (xy 138.997913 -253.900895)
			(xy 139.047088 -253.898914) (xy 139.095943 -253.904846) (xy 139.143214 -253.918538) (xy 139.187676 -253.939636)
			(xy 139.228179 -253.967592) (xy 139.263672 -254.001684) (xy 139.293237 -254.041028) (xy 139.316108 -254.084605)
			(xy 139.331692 -254.131286) (xy 139.339587 -254.179863) (xy 139.340082 -254.20447) (xy 139.339587 -254.229077)
			(xy 139.331692 -254.277654) (xy 139.316108 -254.324335) (xy 139.293237 -254.367912) (xy 139.263672 -254.407256)
			(xy 139.228179 -254.441348) (xy 139.187676 -254.469304) (xy 139.143214 -254.490402) (xy 139.095943 -254.504094)
			(xy 139.047088 -254.510026) (xy 138.997913 -254.508045) (xy 138.949694 -254.498201) (xy 138.903678 -254.480749)
			(xy 138.861057 -254.456142) (xy 138.822936 -254.425017) (xy 138.790301 -254.38818) (xy 138.763998 -254.346584)
			(xy 138.744707 -254.301308) (xy 138.73293 -254.253524) (xy 138.72897 -254.20447) (xy 138.400028 -254.20447)
			(xy 138.399533 -254.229077) (xy 138.391638 -254.277654) (xy 138.376054 -254.324335) (xy 138.353183 -254.367912)
			(xy 138.323618 -254.407256) (xy 138.288125 -254.441348) (xy 138.247622 -254.469304) (xy 138.20316 -254.490402)
			(xy 138.155889 -254.504094) (xy 138.107034 -254.510026) (xy 138.057859 -254.508045) (xy 138.00964 -254.498201)
			(xy 137.963624 -254.480749) (xy 137.921003 -254.456142) (xy 137.882882 -254.425017) (xy 137.850247 -254.38818)
			(xy 137.823944 -254.346584) (xy 137.804653 -254.301308) (xy 137.792876 -254.253524) (xy 137.788916 -254.20447)
			(xy 136.520174 -254.20447) (xy 136.519679 -254.229077) (xy 136.511784 -254.277654) (xy 136.4962 -254.324335)
			(xy 136.473329 -254.367912) (xy 136.443764 -254.407256) (xy 136.408271 -254.441348) (xy 136.367768 -254.469304)
			(xy 136.323306 -254.490402) (xy 136.276035 -254.504094) (xy 136.22718 -254.510026) (xy 136.178005 -254.508045)
			(xy 136.129786 -254.498201) (xy 136.08377 -254.480749) (xy 136.041149 -254.456142) (xy 136.003028 -254.425017)
			(xy 135.970393 -254.38818) (xy 135.94409 -254.346584) (xy 135.924799 -254.301308) (xy 135.913022 -254.253524)
			(xy 135.909062 -254.20447) (xy 135.58012 -254.20447) (xy 135.579625 -254.229077) (xy 135.57173 -254.277654)
			(xy 135.556146 -254.324335) (xy 135.533275 -254.367912) (xy 135.50371 -254.407256) (xy 135.468217 -254.441348)
			(xy 135.427714 -254.469304) (xy 135.383252 -254.490402) (xy 135.335981 -254.504094) (xy 135.287126 -254.510026)
			(xy 135.237951 -254.508045) (xy 135.189732 -254.498201) (xy 135.143716 -254.480749) (xy 135.101095 -254.456142)
			(xy 135.062974 -254.425017) (xy 135.030339 -254.38818) (xy 135.004036 -254.346584) (xy 134.984745 -254.301308)
			(xy 134.972968 -254.253524) (xy 134.969008 -254.20447) (xy 134.640066 -254.20447) (xy 134.639571 -254.229077)
			(xy 134.631676 -254.277654) (xy 134.616092 -254.324335) (xy 134.593221 -254.367912) (xy 134.563656 -254.407256)
			(xy 134.528163 -254.441348) (xy 134.48766 -254.469304) (xy 134.443198 -254.490402) (xy 134.395927 -254.504094)
			(xy 134.347072 -254.510026) (xy 134.297897 -254.508045) (xy 134.249678 -254.498201) (xy 134.203662 -254.480749)
			(xy 134.161041 -254.456142) (xy 134.12292 -254.425017) (xy 134.090285 -254.38818) (xy 134.063982 -254.346584)
			(xy 134.044691 -254.301308) (xy 134.032914 -254.253524) (xy 134.028954 -254.20447) (xy 133.700012 -254.20447)
			(xy 133.699517 -254.229077) (xy 133.691622 -254.277654) (xy 133.676038 -254.324335) (xy 133.653167 -254.367912)
			(xy 133.623602 -254.407256) (xy 133.588109 -254.441348) (xy 133.547606 -254.469304) (xy 133.503144 -254.490402)
			(xy 133.455873 -254.504094) (xy 133.407018 -254.510026) (xy 133.357843 -254.508045) (xy 133.309624 -254.498201)
			(xy 133.263608 -254.480749) (xy 133.220987 -254.456142) (xy 133.182866 -254.425017) (xy 133.150231 -254.38818)
			(xy 133.123928 -254.346584) (xy 133.104637 -254.301308) (xy 133.09286 -254.253524) (xy 133.0889 -254.20447)
			(xy 132.770372 -254.20447) (xy 132.76986 -254.229916) (xy 132.761696 -254.28015) (xy 132.74558 -254.328424)
			(xy 132.721929 -254.373487) (xy 132.691356 -254.414173) (xy 132.654652 -254.449428) (xy 132.612768 -254.478338)
			(xy 132.566789 -254.500155) (xy 132.517905 -254.514315) (xy 132.467384 -254.520449) (xy 132.416532 -254.5184)
			(xy 132.366668 -254.50822) (xy 132.319082 -254.490173) (xy 132.275008 -254.464727) (xy 132.235586 -254.43254)
			(xy 132.201838 -254.394446) (xy 132.174637 -254.351432) (xy 132.154689 -254.304612) (xy 132.14251 -254.255198)
			(xy 132.138415 -254.20447) (xy 131.830572 -254.20447) (xy 131.83006 -254.229916) (xy 131.821896 -254.28015)
			(xy 131.80578 -254.328424) (xy 131.782129 -254.373487) (xy 131.751556 -254.414173) (xy 131.714852 -254.449428)
			(xy 131.672968 -254.478338) (xy 131.626989 -254.500155) (xy 131.578105 -254.514315) (xy 131.527584 -254.520449)
			(xy 131.476732 -254.5184) (xy 131.426868 -254.50822) (xy 131.379282 -254.490173) (xy 131.335208 -254.464727)
			(xy 131.295786 -254.43254) (xy 131.262038 -254.394446) (xy 131.234837 -254.351432) (xy 131.214889 -254.304612)
			(xy 131.20271 -254.255198) (xy 131.198615 -254.20447) (xy 129.950464 -254.20447) (xy 129.949952 -254.229916)
			(xy 129.941788 -254.28015) (xy 129.925672 -254.328424) (xy 129.902021 -254.373487) (xy 129.871448 -254.414173)
			(xy 129.834744 -254.449428) (xy 129.79286 -254.478338) (xy 129.746881 -254.500155) (xy 129.697997 -254.514315)
			(xy 129.647476 -254.520449) (xy 129.596624 -254.5184) (xy 129.54676 -254.50822) (xy 129.499174 -254.490173)
			(xy 129.4551 -254.464727) (xy 129.415678 -254.43254) (xy 129.38193 -254.394446) (xy 129.354729 -254.351432)
			(xy 129.334781 -254.304612) (xy 129.322602 -254.255198) (xy 129.318507 -254.20447) (xy 128.999996 -254.20447)
			(xy 128.999501 -254.229077) (xy 128.991606 -254.277654) (xy 128.976022 -254.324335) (xy 128.953151 -254.367912)
			(xy 128.923586 -254.407256) (xy 128.888093 -254.441348) (xy 128.84759 -254.469304) (xy 128.803128 -254.490402)
			(xy 128.755857 -254.504094) (xy 128.707002 -254.510026) (xy 128.657827 -254.508045) (xy 128.609608 -254.498201)
			(xy 128.563592 -254.480749) (xy 128.520971 -254.456142) (xy 128.48285 -254.425017) (xy 128.450215 -254.38818)
			(xy 128.423912 -254.346584) (xy 128.404621 -254.301308) (xy 128.392844 -254.253524) (xy 128.388884 -254.20447)
			(xy 128.070356 -254.20447) (xy 128.069844 -254.229916) (xy 128.06168 -254.28015) (xy 128.045564 -254.328424)
			(xy 128.021913 -254.373487) (xy 127.99134 -254.414173) (xy 127.954636 -254.449428) (xy 127.912752 -254.478338)
			(xy 127.866773 -254.500155) (xy 127.817889 -254.514315) (xy 127.767368 -254.520449) (xy 127.716516 -254.5184)
			(xy 127.666652 -254.50822) (xy 127.619066 -254.490173) (xy 127.574992 -254.464727) (xy 127.53557 -254.43254)
			(xy 127.501822 -254.394446) (xy 127.474621 -254.351432) (xy 127.454673 -254.304612) (xy 127.442494 -254.255198)
			(xy 127.438399 -254.20447) (xy 127.120142 -254.20447) (xy 127.119647 -254.229077) (xy 127.111752 -254.277654)
			(xy 127.096168 -254.324335) (xy 127.073297 -254.367912) (xy 127.043732 -254.407256) (xy 127.008239 -254.441348)
			(xy 126.967736 -254.469304) (xy 126.923274 -254.490402) (xy 126.876003 -254.504094) (xy 126.827148 -254.510026)
			(xy 126.777973 -254.508045) (xy 126.729754 -254.498201) (xy 126.683738 -254.480749) (xy 126.641117 -254.456142)
			(xy 126.602996 -254.425017) (xy 126.570361 -254.38818) (xy 126.544058 -254.346584) (xy 126.524767 -254.301308)
			(xy 126.51299 -254.253524) (xy 126.50903 -254.20447) (xy 125.240034 -254.20447) (xy 125.239539 -254.229077)
			(xy 125.231644 -254.277654) (xy 125.21606 -254.324335) (xy 125.193189 -254.367912) (xy 125.163624 -254.407256)
			(xy 125.128131 -254.441348) (xy 125.087628 -254.469304) (xy 125.043166 -254.490402) (xy 124.995895 -254.504094)
			(xy 124.94704 -254.510026) (xy 124.897865 -254.508045) (xy 124.849646 -254.498201) (xy 124.80363 -254.480749)
			(xy 124.761009 -254.456142) (xy 124.722888 -254.425017) (xy 124.690253 -254.38818) (xy 124.66395 -254.346584)
			(xy 124.644659 -254.301308) (xy 124.632882 -254.253524) (xy 124.628922 -254.20447) (xy 123.359926 -254.20447)
			(xy 123.359431 -254.229077) (xy 123.351536 -254.277654) (xy 123.335952 -254.324335) (xy 123.313081 -254.367912)
			(xy 123.283516 -254.407256) (xy 123.248023 -254.441348) (xy 123.20752 -254.469304) (xy 123.163058 -254.490402)
			(xy 123.115787 -254.504094) (xy 123.066932 -254.510026) (xy 123.017757 -254.508045) (xy 122.969538 -254.498201)
			(xy 122.923522 -254.480749) (xy 122.880901 -254.456142) (xy 122.84278 -254.425017) (xy 122.810145 -254.38818)
			(xy 122.783842 -254.346584) (xy 122.764551 -254.301308) (xy 122.752774 -254.253524) (xy 122.748814 -254.20447)
			(xy 121.480072 -254.20447) (xy 121.479577 -254.229077) (xy 121.471682 -254.277654) (xy 121.456098 -254.324335)
			(xy 121.433227 -254.367912) (xy 121.403662 -254.407256) (xy 121.368169 -254.441348) (xy 121.327666 -254.469304)
			(xy 121.283204 -254.490402) (xy 121.235933 -254.504094) (xy 121.187078 -254.510026) (xy 121.137903 -254.508045)
			(xy 121.089684 -254.498201) (xy 121.043668 -254.480749) (xy 121.001047 -254.456142) (xy 120.962926 -254.425017)
			(xy 120.930291 -254.38818) (xy 120.903988 -254.346584) (xy 120.884697 -254.301308) (xy 120.87292 -254.253524)
			(xy 120.86896 -254.20447) (xy 112.49858 -254.20447) (xy 112.522912 -254.229752) (xy 112.553204 -254.272818)
			(xy 112.576567 -254.320003) (xy 112.592453 -254.370202) (xy 112.60049 -254.422238) (xy 112.600994 -254.448564)
			(xy 112.60049 -254.47489) (xy 112.592453 -254.526926) (xy 112.576567 -254.577125) (xy 112.553204 -254.62431)
			(xy 112.522912 -254.667376) (xy 112.4864 -254.705314) (xy 112.444526 -254.737233) (xy 112.39827 -254.762386)
			(xy 112.348717 -254.780184) (xy 112.297027 -254.790208) (xy 112.244413 -254.792225) (xy 112.192108 -254.786187)
			(xy 112.141337 -254.772235) (xy 112.093292 -254.750696) (xy 112.049097 -254.722076) (xy 112.009789 -254.687045)
			(xy 111.976289 -254.646424) (xy 111.949383 -254.601165) (xy 111.9297 -254.55233) (xy 111.917703 -254.501062)
			(xy 111.913673 -254.448564) (xy 105.269284 -254.448564) (xy 105.446322 -254.625602) (xy 105.451821 -254.63059)
			(xy 105.464987 -254.637434) (xy 105.47223 -254.639064) (xy 105.481882 -254.64008) (xy 106.470958 -254.64008)
			(xy 106.481024 -254.640513) (xy 106.499615 -254.64824) (xy 106.507026 -254.655066) (xy 106.866436 -255.014476)
			(xy 122.278914 -255.014476) (xy 122.282874 -254.965422) (xy 122.294651 -254.917638) (xy 122.313942 -254.872362)
			(xy 122.340245 -254.830766) (xy 122.37288 -254.793929) (xy 122.411001 -254.762804) (xy 122.453622 -254.738197)
			(xy 122.499638 -254.720745) (xy 122.547857 -254.710901) (xy 122.597032 -254.70892) (xy 122.645887 -254.714852)
			(xy 122.693158 -254.728544) (xy 122.73762 -254.749642) (xy 122.778123 -254.777598) (xy 122.813616 -254.81169)
			(xy 122.843181 -254.851034) (xy 122.866052 -254.894611) (xy 122.881636 -254.941292) (xy 122.889531 -254.989869)
			(xy 122.890026 -255.014476) (xy 124.159022 -255.014476) (xy 124.162982 -254.965422) (xy 124.174759 -254.917638)
			(xy 124.19405 -254.872362) (xy 124.220353 -254.830766) (xy 124.252988 -254.793929) (xy 124.291109 -254.762804)
			(xy 124.33373 -254.738197) (xy 124.379746 -254.720745) (xy 124.427965 -254.710901) (xy 124.47714 -254.70892)
			(xy 124.525995 -254.714852) (xy 124.573266 -254.728544) (xy 124.617728 -254.749642) (xy 124.658231 -254.777598)
			(xy 124.693724 -254.81169) (xy 124.723289 -254.851034) (xy 124.74616 -254.894611) (xy 124.761744 -254.941292)
			(xy 124.769639 -254.989869) (xy 124.770134 -255.014476) (xy 126.038876 -255.014476) (xy 126.042836 -254.965422)
			(xy 126.054613 -254.917638) (xy 126.073904 -254.872362) (xy 126.100207 -254.830766) (xy 126.132842 -254.793929)
			(xy 126.170963 -254.762804) (xy 126.213584 -254.738197) (xy 126.2596 -254.720745) (xy 126.307819 -254.710901)
			(xy 126.356994 -254.70892) (xy 126.405849 -254.714852) (xy 126.45312 -254.728544) (xy 126.497582 -254.749642)
			(xy 126.538085 -254.777598) (xy 126.573578 -254.81169) (xy 126.603143 -254.851034) (xy 126.626014 -254.894611)
			(xy 126.641598 -254.941292) (xy 126.649493 -254.989869) (xy 126.649988 -255.014476) (xy 127.908553 -255.014476)
			(xy 127.912648 -254.963748) (xy 127.924827 -254.914334) (xy 127.944775 -254.867514) (xy 127.971976 -254.8245)
			(xy 128.005724 -254.786406) (xy 128.045146 -254.754219) (xy 128.08922 -254.728773) (xy 128.136806 -254.710726)
			(xy 128.18667 -254.700546) (xy 128.237522 -254.698497) (xy 128.288043 -254.704631) (xy 128.336927 -254.718791)
			(xy 128.382906 -254.740608) (xy 128.42479 -254.769518) (xy 128.461494 -254.804773) (xy 128.492067 -254.845459)
			(xy 128.515718 -254.890522) (xy 128.531834 -254.938796) (xy 128.539998 -254.98903) (xy 128.54051 -255.014476)
			(xy 128.848607 -255.014476) (xy 128.852702 -254.963748) (xy 128.864881 -254.914334) (xy 128.884829 -254.867514)
			(xy 128.91203 -254.8245) (xy 128.945778 -254.786406) (xy 128.9852 -254.754219) (xy 129.029274 -254.728773)
			(xy 129.07686 -254.710726) (xy 129.126724 -254.700546) (xy 129.177576 -254.698497) (xy 129.228097 -254.704631)
			(xy 129.276981 -254.718791) (xy 129.32296 -254.740608) (xy 129.364844 -254.769518) (xy 129.401548 -254.804773)
			(xy 129.432121 -254.845459) (xy 129.455772 -254.890522) (xy 129.471888 -254.938796) (xy 129.480052 -254.98903)
			(xy 129.480564 -255.014476) (xy 129.798838 -255.014476) (xy 129.802798 -254.965422) (xy 129.814575 -254.917638)
			(xy 129.833866 -254.872362) (xy 129.860169 -254.830766) (xy 129.892804 -254.793929) (xy 129.930925 -254.762804)
			(xy 129.973546 -254.738197) (xy 130.019562 -254.720745) (xy 130.067781 -254.710901) (xy 130.116956 -254.70892)
			(xy 130.165811 -254.714852) (xy 130.213082 -254.728544) (xy 130.257544 -254.749642) (xy 130.298047 -254.777598)
			(xy 130.33354 -254.81169) (xy 130.363105 -254.851034) (xy 130.385976 -254.894611) (xy 130.40156 -254.941292)
			(xy 130.409455 -254.989869) (xy 130.40995 -255.014476) (xy 130.728461 -255.014476) (xy 130.732556 -254.963748)
			(xy 130.744735 -254.914334) (xy 130.764683 -254.867514) (xy 130.791884 -254.8245) (xy 130.825632 -254.786406)
			(xy 130.865054 -254.754219) (xy 130.909128 -254.728773) (xy 130.956714 -254.710726) (xy 131.006578 -254.700546)
			(xy 131.05743 -254.698497) (xy 131.107951 -254.704631) (xy 131.156835 -254.718791) (xy 131.202814 -254.740608)
			(xy 131.244698 -254.769518) (xy 131.281402 -254.804773) (xy 131.311975 -254.845459) (xy 131.335626 -254.890522)
			(xy 131.351742 -254.938796) (xy 131.359906 -254.98903) (xy 131.360418 -255.014476) (xy 131.678946 -255.014476)
			(xy 131.682906 -254.965422) (xy 131.694683 -254.917638) (xy 131.713974 -254.872362) (xy 131.740277 -254.830766)
			(xy 131.772912 -254.793929) (xy 131.811033 -254.762804) (xy 131.853654 -254.738197) (xy 131.89967 -254.720745)
			(xy 131.947889 -254.710901) (xy 131.997064 -254.70892) (xy 132.045919 -254.714852) (xy 132.09319 -254.728544)
			(xy 132.137652 -254.749642) (xy 132.178155 -254.777598) (xy 132.213648 -254.81169) (xy 132.243213 -254.851034)
			(xy 132.266084 -254.894611) (xy 132.281668 -254.941292) (xy 132.289563 -254.989869) (xy 132.290058 -255.014476)
			(xy 132.608569 -255.014476) (xy 132.612664 -254.963748) (xy 132.624843 -254.914334) (xy 132.644791 -254.867514)
			(xy 132.671992 -254.8245) (xy 132.70574 -254.786406) (xy 132.745162 -254.754219) (xy 132.789236 -254.728773)
			(xy 132.836822 -254.710726) (xy 132.886686 -254.700546) (xy 132.937538 -254.698497) (xy 132.988059 -254.704631)
			(xy 133.036943 -254.718791) (xy 133.082922 -254.740608) (xy 133.124806 -254.769518) (xy 133.16151 -254.804773)
			(xy 133.192083 -254.845459) (xy 133.215734 -254.890522) (xy 133.23185 -254.938796) (xy 133.240014 -254.98903)
			(xy 133.240526 -255.014476) (xy 133.559054 -255.014476) (xy 133.563014 -254.965422) (xy 133.574791 -254.917638)
			(xy 133.594082 -254.872362) (xy 133.620385 -254.830766) (xy 133.65302 -254.793929) (xy 133.691141 -254.762804)
			(xy 133.733762 -254.738197) (xy 133.779778 -254.720745) (xy 133.827997 -254.710901) (xy 133.877172 -254.70892)
			(xy 133.926027 -254.714852) (xy 133.973298 -254.728544) (xy 134.01776 -254.749642) (xy 134.058263 -254.777598)
			(xy 134.093756 -254.81169) (xy 134.123321 -254.851034) (xy 134.146192 -254.894611) (xy 134.161776 -254.941292)
			(xy 134.169671 -254.989869) (xy 134.170166 -255.014476) (xy 134.498854 -255.014476) (xy 134.502814 -254.965422)
			(xy 134.514591 -254.917638) (xy 134.533882 -254.872362) (xy 134.560185 -254.830766) (xy 134.59282 -254.793929)
			(xy 134.630941 -254.762804) (xy 134.673562 -254.738197) (xy 134.719578 -254.720745) (xy 134.767797 -254.710901)
			(xy 134.816972 -254.70892) (xy 134.865827 -254.714852) (xy 134.913098 -254.728544) (xy 134.95756 -254.749642)
			(xy 134.998063 -254.777598) (xy 135.033556 -254.81169) (xy 135.063121 -254.851034) (xy 135.085992 -254.894611)
			(xy 135.101576 -254.941292) (xy 135.109471 -254.989869) (xy 135.109966 -255.014476) (xy 135.438908 -255.014476)
			(xy 135.442868 -254.965422) (xy 135.454645 -254.917638) (xy 135.473936 -254.872362) (xy 135.500239 -254.830766)
			(xy 135.532874 -254.793929) (xy 135.570995 -254.762804) (xy 135.613616 -254.738197) (xy 135.659632 -254.720745)
			(xy 135.707851 -254.710901) (xy 135.757026 -254.70892) (xy 135.805881 -254.714852) (xy 135.853152 -254.728544)
			(xy 135.897614 -254.749642) (xy 135.938117 -254.777598) (xy 135.97361 -254.81169) (xy 136.003175 -254.851034)
			(xy 136.026046 -254.894611) (xy 136.04163 -254.941292) (xy 136.049525 -254.989869) (xy 136.05002 -255.014476)
			(xy 136.378962 -255.014476) (xy 136.382922 -254.965422) (xy 136.394699 -254.917638) (xy 136.41399 -254.872362)
			(xy 136.440293 -254.830766) (xy 136.472928 -254.793929) (xy 136.511049 -254.762804) (xy 136.55367 -254.738197)
			(xy 136.599686 -254.720745) (xy 136.647905 -254.710901) (xy 136.69708 -254.70892) (xy 136.745935 -254.714852)
			(xy 136.793206 -254.728544) (xy 136.837668 -254.749642) (xy 136.878171 -254.777598) (xy 136.913664 -254.81169)
			(xy 136.943229 -254.851034) (xy 136.9661 -254.894611) (xy 136.981684 -254.941292) (xy 136.989579 -254.989869)
			(xy 136.990074 -255.014476) (xy 137.319016 -255.014476) (xy 137.322976 -254.965422) (xy 137.334753 -254.917638)
			(xy 137.354044 -254.872362) (xy 137.380347 -254.830766) (xy 137.412982 -254.793929) (xy 137.451103 -254.762804)
			(xy 137.493724 -254.738197) (xy 137.53974 -254.720745) (xy 137.587959 -254.710901) (xy 137.637134 -254.70892)
			(xy 137.685989 -254.714852) (xy 137.73326 -254.728544) (xy 137.777722 -254.749642) (xy 137.818225 -254.777598)
			(xy 137.853718 -254.81169) (xy 137.883283 -254.851034) (xy 137.906154 -254.894611) (xy 137.921738 -254.941292)
			(xy 137.929633 -254.989869) (xy 137.930128 -255.014476) (xy 138.25907 -255.014476) (xy 138.26303 -254.965422)
			(xy 138.274807 -254.917638) (xy 138.294098 -254.872362) (xy 138.320401 -254.830766) (xy 138.353036 -254.793929)
			(xy 138.391157 -254.762804) (xy 138.433778 -254.738197) (xy 138.479794 -254.720745) (xy 138.528013 -254.710901)
			(xy 138.577188 -254.70892) (xy 138.626043 -254.714852) (xy 138.673314 -254.728544) (xy 138.717776 -254.749642)
			(xy 138.758279 -254.777598) (xy 138.793772 -254.81169) (xy 138.823337 -254.851034) (xy 138.846208 -254.894611)
			(xy 138.861792 -254.941292) (xy 138.869687 -254.989869) (xy 138.870182 -255.014476) (xy 139.19887 -255.014476)
			(xy 139.20283 -254.965422) (xy 139.214607 -254.917638) (xy 139.233898 -254.872362) (xy 139.260201 -254.830766)
			(xy 139.292836 -254.793929) (xy 139.330957 -254.762804) (xy 139.373578 -254.738197) (xy 139.419594 -254.720745)
			(xy 139.467813 -254.710901) (xy 139.516988 -254.70892) (xy 139.565843 -254.714852) (xy 139.613114 -254.728544)
			(xy 139.657576 -254.749642) (xy 139.698079 -254.777598) (xy 139.733572 -254.81169) (xy 139.763137 -254.851034)
			(xy 139.786008 -254.894611) (xy 139.801592 -254.941292) (xy 139.809487 -254.989869) (xy 139.809982 -255.014476)
			(xy 139.809487 -255.039083) (xy 139.801592 -255.08766) (xy 139.786008 -255.134341) (xy 139.763137 -255.177918)
			(xy 139.733572 -255.217262) (xy 139.698079 -255.251354) (xy 139.657576 -255.27931) (xy 139.613114 -255.300408)
			(xy 139.565843 -255.3141) (xy 139.516988 -255.320032) (xy 139.467813 -255.318051) (xy 139.419594 -255.308207)
			(xy 139.373578 -255.290755) (xy 139.330957 -255.266148) (xy 139.292836 -255.235023) (xy 139.260201 -255.198186)
			(xy 139.233898 -255.15659) (xy 139.214607 -255.111314) (xy 139.20283 -255.06353) (xy 139.19887 -255.014476)
			(xy 138.870182 -255.014476) (xy 138.869687 -255.039083) (xy 138.861792 -255.08766) (xy 138.846208 -255.134341)
			(xy 138.823337 -255.177918) (xy 138.793772 -255.217262) (xy 138.758279 -255.251354) (xy 138.717776 -255.27931)
			(xy 138.673314 -255.300408) (xy 138.626043 -255.3141) (xy 138.577188 -255.320032) (xy 138.528013 -255.318051)
			(xy 138.479794 -255.308207) (xy 138.433778 -255.290755) (xy 138.391157 -255.266148) (xy 138.353036 -255.235023)
			(xy 138.320401 -255.198186) (xy 138.294098 -255.15659) (xy 138.274807 -255.111314) (xy 138.26303 -255.06353)
			(xy 138.25907 -255.014476) (xy 137.930128 -255.014476) (xy 137.929633 -255.039083) (xy 137.921738 -255.08766)
			(xy 137.906154 -255.134341) (xy 137.883283 -255.177918) (xy 137.853718 -255.217262) (xy 137.818225 -255.251354)
			(xy 137.777722 -255.27931) (xy 137.73326 -255.300408) (xy 137.685989 -255.3141) (xy 137.637134 -255.320032)
			(xy 137.587959 -255.318051) (xy 137.53974 -255.308207) (xy 137.493724 -255.290755) (xy 137.451103 -255.266148)
			(xy 137.412982 -255.235023) (xy 137.380347 -255.198186) (xy 137.354044 -255.15659) (xy 137.334753 -255.111314)
			(xy 137.322976 -255.06353) (xy 137.319016 -255.014476) (xy 136.990074 -255.014476) (xy 136.989579 -255.039083)
			(xy 136.981684 -255.08766) (xy 136.9661 -255.134341) (xy 136.943229 -255.177918) (xy 136.913664 -255.217262)
			(xy 136.878171 -255.251354) (xy 136.837668 -255.27931) (xy 136.793206 -255.300408) (xy 136.745935 -255.3141)
			(xy 136.69708 -255.320032) (xy 136.647905 -255.318051) (xy 136.599686 -255.308207) (xy 136.55367 -255.290755)
			(xy 136.511049 -255.266148) (xy 136.472928 -255.235023) (xy 136.440293 -255.198186) (xy 136.41399 -255.15659)
			(xy 136.394699 -255.111314) (xy 136.382922 -255.06353) (xy 136.378962 -255.014476) (xy 136.05002 -255.014476)
			(xy 136.049525 -255.039083) (xy 136.04163 -255.08766) (xy 136.026046 -255.134341) (xy 136.003175 -255.177918)
			(xy 135.97361 -255.217262) (xy 135.938117 -255.251354) (xy 135.897614 -255.27931) (xy 135.853152 -255.300408)
			(xy 135.805881 -255.3141) (xy 135.757026 -255.320032) (xy 135.707851 -255.318051) (xy 135.659632 -255.308207)
			(xy 135.613616 -255.290755) (xy 135.570995 -255.266148) (xy 135.532874 -255.235023) (xy 135.500239 -255.198186)
			(xy 135.473936 -255.15659) (xy 135.454645 -255.111314) (xy 135.442868 -255.06353) (xy 135.438908 -255.014476)
			(xy 135.109966 -255.014476) (xy 135.109471 -255.039083) (xy 135.101576 -255.08766) (xy 135.085992 -255.134341)
			(xy 135.063121 -255.177918) (xy 135.033556 -255.217262) (xy 134.998063 -255.251354) (xy 134.95756 -255.27931)
			(xy 134.913098 -255.300408) (xy 134.865827 -255.3141) (xy 134.816972 -255.320032) (xy 134.767797 -255.318051)
			(xy 134.719578 -255.308207) (xy 134.673562 -255.290755) (xy 134.630941 -255.266148) (xy 134.59282 -255.235023)
			(xy 134.560185 -255.198186) (xy 134.533882 -255.15659) (xy 134.514591 -255.111314) (xy 134.502814 -255.06353)
			(xy 134.498854 -255.014476) (xy 134.170166 -255.014476) (xy 134.169671 -255.039083) (xy 134.161776 -255.08766)
			(xy 134.146192 -255.134341) (xy 134.123321 -255.177918) (xy 134.093756 -255.217262) (xy 134.058263 -255.251354)
			(xy 134.01776 -255.27931) (xy 133.973298 -255.300408) (xy 133.926027 -255.3141) (xy 133.877172 -255.320032)
			(xy 133.827997 -255.318051) (xy 133.779778 -255.308207) (xy 133.733762 -255.290755) (xy 133.691141 -255.266148)
			(xy 133.65302 -255.235023) (xy 133.620385 -255.198186) (xy 133.594082 -255.15659) (xy 133.574791 -255.111314)
			(xy 133.563014 -255.06353) (xy 133.559054 -255.014476) (xy 133.240526 -255.014476) (xy 133.240014 -255.039922)
			(xy 133.23185 -255.090156) (xy 133.215734 -255.13843) (xy 133.192083 -255.183493) (xy 133.16151 -255.224179)
			(xy 133.124806 -255.259434) (xy 133.082922 -255.288344) (xy 133.036943 -255.310161) (xy 132.988059 -255.324321)
			(xy 132.937538 -255.330455) (xy 132.886686 -255.328406) (xy 132.836822 -255.318226) (xy 132.789236 -255.300179)
			(xy 132.745162 -255.274733) (xy 132.70574 -255.242546) (xy 132.671992 -255.204452) (xy 132.644791 -255.161438)
			(xy 132.624843 -255.114618) (xy 132.612664 -255.065204) (xy 132.608569 -255.014476) (xy 132.290058 -255.014476)
			(xy 132.289563 -255.039083) (xy 132.281668 -255.08766) (xy 132.266084 -255.134341) (xy 132.243213 -255.177918)
			(xy 132.213648 -255.217262) (xy 132.178155 -255.251354) (xy 132.137652 -255.27931) (xy 132.09319 -255.300408)
			(xy 132.045919 -255.3141) (xy 131.997064 -255.320032) (xy 131.947889 -255.318051) (xy 131.89967 -255.308207)
			(xy 131.853654 -255.290755) (xy 131.811033 -255.266148) (xy 131.772912 -255.235023) (xy 131.740277 -255.198186)
			(xy 131.713974 -255.15659) (xy 131.694683 -255.111314) (xy 131.682906 -255.06353) (xy 131.678946 -255.014476)
			(xy 131.360418 -255.014476) (xy 131.359906 -255.039922) (xy 131.351742 -255.090156) (xy 131.335626 -255.13843)
			(xy 131.311975 -255.183493) (xy 131.281402 -255.224179) (xy 131.244698 -255.259434) (xy 131.202814 -255.288344)
			(xy 131.156835 -255.310161) (xy 131.107951 -255.324321) (xy 131.05743 -255.330455) (xy 131.006578 -255.328406)
			(xy 130.956714 -255.318226) (xy 130.909128 -255.300179) (xy 130.865054 -255.274733) (xy 130.825632 -255.242546)
			(xy 130.791884 -255.204452) (xy 130.764683 -255.161438) (xy 130.744735 -255.114618) (xy 130.732556 -255.065204)
			(xy 130.728461 -255.014476) (xy 130.40995 -255.014476) (xy 130.409455 -255.039083) (xy 130.40156 -255.08766)
			(xy 130.385976 -255.134341) (xy 130.363105 -255.177918) (xy 130.33354 -255.217262) (xy 130.298047 -255.251354)
			(xy 130.257544 -255.27931) (xy 130.213082 -255.300408) (xy 130.165811 -255.3141) (xy 130.116956 -255.320032)
			(xy 130.067781 -255.318051) (xy 130.019562 -255.308207) (xy 129.973546 -255.290755) (xy 129.930925 -255.266148)
			(xy 129.892804 -255.235023) (xy 129.860169 -255.198186) (xy 129.833866 -255.15659) (xy 129.814575 -255.111314)
			(xy 129.802798 -255.06353) (xy 129.798838 -255.014476) (xy 129.480564 -255.014476) (xy 129.480052 -255.039922)
			(xy 129.471888 -255.090156) (xy 129.455772 -255.13843) (xy 129.432121 -255.183493) (xy 129.401548 -255.224179)
			(xy 129.364844 -255.259434) (xy 129.32296 -255.288344) (xy 129.276981 -255.310161) (xy 129.228097 -255.324321)
			(xy 129.177576 -255.330455) (xy 129.126724 -255.328406) (xy 129.07686 -255.318226) (xy 129.029274 -255.300179)
			(xy 128.9852 -255.274733) (xy 128.945778 -255.242546) (xy 128.91203 -255.204452) (xy 128.884829 -255.161438)
			(xy 128.864881 -255.114618) (xy 128.852702 -255.065204) (xy 128.848607 -255.014476) (xy 128.54051 -255.014476)
			(xy 128.539998 -255.039922) (xy 128.531834 -255.090156) (xy 128.515718 -255.13843) (xy 128.492067 -255.183493)
			(xy 128.461494 -255.224179) (xy 128.42479 -255.259434) (xy 128.382906 -255.288344) (xy 128.336927 -255.310161)
			(xy 128.288043 -255.324321) (xy 128.237522 -255.330455) (xy 128.18667 -255.328406) (xy 128.136806 -255.318226)
			(xy 128.08922 -255.300179) (xy 128.045146 -255.274733) (xy 128.005724 -255.242546) (xy 127.971976 -255.204452)
			(xy 127.944775 -255.161438) (xy 127.924827 -255.114618) (xy 127.912648 -255.065204) (xy 127.908553 -255.014476)
			(xy 126.649988 -255.014476) (xy 126.649493 -255.039083) (xy 126.641598 -255.08766) (xy 126.626014 -255.134341)
			(xy 126.603143 -255.177918) (xy 126.573578 -255.217262) (xy 126.538085 -255.251354) (xy 126.497582 -255.27931)
			(xy 126.45312 -255.300408) (xy 126.405849 -255.3141) (xy 126.356994 -255.320032) (xy 126.307819 -255.318051)
			(xy 126.2596 -255.308207) (xy 126.213584 -255.290755) (xy 126.170963 -255.266148) (xy 126.132842 -255.235023)
			(xy 126.100207 -255.198186) (xy 126.073904 -255.15659) (xy 126.054613 -255.111314) (xy 126.042836 -255.06353)
			(xy 126.038876 -255.014476) (xy 124.770134 -255.014476) (xy 124.769639 -255.039083) (xy 124.761744 -255.08766)
			(xy 124.74616 -255.134341) (xy 124.723289 -255.177918) (xy 124.693724 -255.217262) (xy 124.658231 -255.251354)
			(xy 124.617728 -255.27931) (xy 124.573266 -255.300408) (xy 124.525995 -255.3141) (xy 124.47714 -255.320032)
			(xy 124.427965 -255.318051) (xy 124.379746 -255.308207) (xy 124.33373 -255.290755) (xy 124.291109 -255.266148)
			(xy 124.252988 -255.235023) (xy 124.220353 -255.198186) (xy 124.19405 -255.15659) (xy 124.174759 -255.111314)
			(xy 124.162982 -255.06353) (xy 124.159022 -255.014476) (xy 122.890026 -255.014476) (xy 122.889531 -255.039083)
			(xy 122.881636 -255.08766) (xy 122.866052 -255.134341) (xy 122.843181 -255.177918) (xy 122.813616 -255.217262)
			(xy 122.778123 -255.251354) (xy 122.73762 -255.27931) (xy 122.693158 -255.300408) (xy 122.645887 -255.3141)
			(xy 122.597032 -255.320032) (xy 122.547857 -255.318051) (xy 122.499638 -255.308207) (xy 122.453622 -255.290755)
			(xy 122.411001 -255.266148) (xy 122.37288 -255.235023) (xy 122.340245 -255.198186) (xy 122.313942 -255.15659)
			(xy 122.294651 -255.111314) (xy 122.282874 -255.06353) (xy 122.278914 -255.014476) (xy 106.866436 -255.014476)
			(xy 107.38231 -255.53035) (xy 117.096797 -255.53035) (xy 117.100827 -255.477852) (xy 117.112824 -255.426584)
			(xy 117.132507 -255.377749) (xy 117.159413 -255.33249) (xy 117.192913 -255.291869) (xy 117.232221 -255.256838)
			(xy 117.276416 -255.228218) (xy 117.324461 -255.206679) (xy 117.375232 -255.192727) (xy 117.427537 -255.186689)
			(xy 117.480151 -255.188706) (xy 117.531841 -255.19873) (xy 117.581394 -255.216528) (xy 117.62765 -255.241681)
			(xy 117.669524 -255.2736) (xy 117.706036 -255.311538) (xy 117.736328 -255.354604) (xy 117.759691 -255.401789)
			(xy 117.775577 -255.451988) (xy 117.783614 -255.504024) (xy 117.784118 -255.53035) (xy 117.783614 -255.556676)
			(xy 117.775577 -255.608712) (xy 117.759691 -255.658911) (xy 117.736328 -255.706096) (xy 117.706036 -255.749162)
			(xy 117.669524 -255.7871) (xy 117.62765 -255.819019) (xy 117.617604 -255.824482) (xy 120.86896 -255.824482)
			(xy 120.87292 -255.775428) (xy 120.884697 -255.727644) (xy 120.903988 -255.682368) (xy 120.930291 -255.640772)
			(xy 120.962926 -255.603935) (xy 121.001047 -255.57281) (xy 121.043668 -255.548203) (xy 121.089684 -255.530751)
			(xy 121.137903 -255.520907) (xy 121.187078 -255.518926) (xy 121.235933 -255.524858) (xy 121.283204 -255.53855)
			(xy 121.327666 -255.559648) (xy 121.368169 -255.587604) (xy 121.403662 -255.621696) (xy 121.433227 -255.66104)
			(xy 121.456098 -255.704617) (xy 121.471682 -255.751298) (xy 121.479577 -255.799875) (xy 121.480072 -255.824482)
			(xy 122.748814 -255.824482) (xy 122.752774 -255.775428) (xy 122.764551 -255.727644) (xy 122.783842 -255.682368)
			(xy 122.810145 -255.640772) (xy 122.84278 -255.603935) (xy 122.880901 -255.57281) (xy 122.923522 -255.548203)
			(xy 122.969538 -255.530751) (xy 123.017757 -255.520907) (xy 123.066932 -255.518926) (xy 123.115787 -255.524858)
			(xy 123.163058 -255.53855) (xy 123.20752 -255.559648) (xy 123.248023 -255.587604) (xy 123.283516 -255.621696)
			(xy 123.313081 -255.66104) (xy 123.335952 -255.704617) (xy 123.351536 -255.751298) (xy 123.359431 -255.799875)
			(xy 123.359926 -255.824482) (xy 124.628922 -255.824482) (xy 124.632882 -255.775428) (xy 124.644659 -255.727644)
			(xy 124.66395 -255.682368) (xy 124.690253 -255.640772) (xy 124.722888 -255.603935) (xy 124.761009 -255.57281)
			(xy 124.80363 -255.548203) (xy 124.849646 -255.530751) (xy 124.897865 -255.520907) (xy 124.94704 -255.518926)
			(xy 124.995895 -255.524858) (xy 125.043166 -255.53855) (xy 125.087628 -255.559648) (xy 125.128131 -255.587604)
			(xy 125.163624 -255.621696) (xy 125.193189 -255.66104) (xy 125.21606 -255.704617) (xy 125.231644 -255.751298)
			(xy 125.239539 -255.799875) (xy 125.240034 -255.824482) (xy 126.50903 -255.824482) (xy 126.51299 -255.775428)
			(xy 126.524767 -255.727644) (xy 126.544058 -255.682368) (xy 126.570361 -255.640772) (xy 126.602996 -255.603935)
			(xy 126.641117 -255.57281) (xy 126.683738 -255.548203) (xy 126.729754 -255.530751) (xy 126.777973 -255.520907)
			(xy 126.827148 -255.518926) (xy 126.876003 -255.524858) (xy 126.923274 -255.53855) (xy 126.967736 -255.559648)
			(xy 127.008239 -255.587604) (xy 127.043732 -255.621696) (xy 127.073297 -255.66104) (xy 127.096168 -255.704617)
			(xy 127.111752 -255.751298) (xy 127.119647 -255.799875) (xy 127.120142 -255.824482) (xy 127.438399 -255.824482)
			(xy 127.442494 -255.773754) (xy 127.454673 -255.72434) (xy 127.474621 -255.67752) (xy 127.501822 -255.634506)
			(xy 127.53557 -255.596412) (xy 127.574992 -255.564225) (xy 127.619066 -255.538779) (xy 127.666652 -255.520732)
			(xy 127.716516 -255.510552) (xy 127.767368 -255.508503) (xy 127.817889 -255.514637) (xy 127.866773 -255.528797)
			(xy 127.912752 -255.550614) (xy 127.954636 -255.579524) (xy 127.99134 -255.614779) (xy 128.021913 -255.655465)
			(xy 128.045564 -255.700528) (xy 128.06168 -255.748802) (xy 128.069844 -255.799036) (xy 128.070356 -255.824482)
			(xy 128.388884 -255.824482) (xy 128.392844 -255.775428) (xy 128.404621 -255.727644) (xy 128.423912 -255.682368)
			(xy 128.450215 -255.640772) (xy 128.48285 -255.603935) (xy 128.520971 -255.57281) (xy 128.563592 -255.548203)
			(xy 128.609608 -255.530751) (xy 128.657827 -255.520907) (xy 128.707002 -255.518926) (xy 128.755857 -255.524858)
			(xy 128.803128 -255.53855) (xy 128.84759 -255.559648) (xy 128.888093 -255.587604) (xy 128.923586 -255.621696)
			(xy 128.953151 -255.66104) (xy 128.976022 -255.704617) (xy 128.991606 -255.751298) (xy 128.999501 -255.799875)
			(xy 128.999996 -255.824482) (xy 129.318507 -255.824482) (xy 129.322602 -255.773754) (xy 129.334781 -255.72434)
			(xy 129.354729 -255.67752) (xy 129.38193 -255.634506) (xy 129.415678 -255.596412) (xy 129.4551 -255.564225)
			(xy 129.499174 -255.538779) (xy 129.54676 -255.520732) (xy 129.596624 -255.510552) (xy 129.647476 -255.508503)
			(xy 129.697997 -255.514637) (xy 129.746881 -255.528797) (xy 129.79286 -255.550614) (xy 129.834744 -255.579524)
			(xy 129.871448 -255.614779) (xy 129.902021 -255.655465) (xy 129.925672 -255.700528) (xy 129.941788 -255.748802)
			(xy 129.949952 -255.799036) (xy 129.950464 -255.824482) (xy 130.268992 -255.824482) (xy 130.272952 -255.775428)
			(xy 130.284729 -255.727644) (xy 130.30402 -255.682368) (xy 130.330323 -255.640772) (xy 130.362958 -255.603935)
			(xy 130.401079 -255.57281) (xy 130.4437 -255.548203) (xy 130.489716 -255.530751) (xy 130.537935 -255.520907)
			(xy 130.58711 -255.518926) (xy 130.635965 -255.524858) (xy 130.683236 -255.53855) (xy 130.727698 -255.559648)
			(xy 130.768201 -255.587604) (xy 130.803694 -255.621696) (xy 130.833259 -255.66104) (xy 130.85613 -255.704617)
			(xy 130.871714 -255.751298) (xy 130.879609 -255.799875) (xy 130.880104 -255.824482) (xy 131.198615 -255.824482)
			(xy 131.20271 -255.773754) (xy 131.214889 -255.72434) (xy 131.234837 -255.67752) (xy 131.262038 -255.634506)
			(xy 131.295786 -255.596412) (xy 131.335208 -255.564225) (xy 131.379282 -255.538779) (xy 131.426868 -255.520732)
			(xy 131.476732 -255.510552) (xy 131.527584 -255.508503) (xy 131.578105 -255.514637) (xy 131.626989 -255.528797)
			(xy 131.672968 -255.550614) (xy 131.714852 -255.579524) (xy 131.751556 -255.614779) (xy 131.782129 -255.655465)
			(xy 131.80578 -255.700528) (xy 131.821896 -255.748802) (xy 131.83006 -255.799036) (xy 131.830572 -255.824482)
			(xy 132.138415 -255.824482) (xy 132.14251 -255.773754) (xy 132.154689 -255.72434) (xy 132.174637 -255.67752)
			(xy 132.201838 -255.634506) (xy 132.235586 -255.596412) (xy 132.275008 -255.564225) (xy 132.319082 -255.538779)
			(xy 132.366668 -255.520732) (xy 132.416532 -255.510552) (xy 132.467384 -255.508503) (xy 132.517905 -255.514637)
			(xy 132.566789 -255.528797) (xy 132.612768 -255.550614) (xy 132.654652 -255.579524) (xy 132.691356 -255.614779)
			(xy 132.721929 -255.655465) (xy 132.74558 -255.700528) (xy 132.761696 -255.748802) (xy 132.76986 -255.799036)
			(xy 132.770372 -255.824482) (xy 133.0889 -255.824482) (xy 133.09286 -255.775428) (xy 133.104637 -255.727644)
			(xy 133.123928 -255.682368) (xy 133.150231 -255.640772) (xy 133.182866 -255.603935) (xy 133.220987 -255.57281)
			(xy 133.263608 -255.548203) (xy 133.309624 -255.530751) (xy 133.357843 -255.520907) (xy 133.407018 -255.518926)
			(xy 133.455873 -255.524858) (xy 133.503144 -255.53855) (xy 133.547606 -255.559648) (xy 133.588109 -255.587604)
			(xy 133.623602 -255.621696) (xy 133.653167 -255.66104) (xy 133.676038 -255.704617) (xy 133.691622 -255.751298)
			(xy 133.699517 -255.799875) (xy 133.700012 -255.824482) (xy 134.028954 -255.824482) (xy 134.032914 -255.775428)
			(xy 134.044691 -255.727644) (xy 134.063982 -255.682368) (xy 134.090285 -255.640772) (xy 134.12292 -255.603935)
			(xy 134.161041 -255.57281) (xy 134.203662 -255.548203) (xy 134.249678 -255.530751) (xy 134.297897 -255.520907)
			(xy 134.347072 -255.518926) (xy 134.395927 -255.524858) (xy 134.443198 -255.53855) (xy 134.48766 -255.559648)
			(xy 134.528163 -255.587604) (xy 134.563656 -255.621696) (xy 134.593221 -255.66104) (xy 134.616092 -255.704617)
			(xy 134.631676 -255.751298) (xy 134.639571 -255.799875) (xy 134.640066 -255.824482) (xy 134.969008 -255.824482)
			(xy 134.972968 -255.775428) (xy 134.984745 -255.727644) (xy 135.004036 -255.682368) (xy 135.030339 -255.640772)
			(xy 135.062974 -255.603935) (xy 135.101095 -255.57281) (xy 135.143716 -255.548203) (xy 135.189732 -255.530751)
			(xy 135.237951 -255.520907) (xy 135.287126 -255.518926) (xy 135.335981 -255.524858) (xy 135.383252 -255.53855)
			(xy 135.427714 -255.559648) (xy 135.468217 -255.587604) (xy 135.50371 -255.621696) (xy 135.533275 -255.66104)
			(xy 135.556146 -255.704617) (xy 135.57173 -255.751298) (xy 135.579625 -255.799875) (xy 135.58012 -255.824482)
			(xy 135.909062 -255.824482) (xy 135.913022 -255.775428) (xy 135.924799 -255.727644) (xy 135.94409 -255.682368)
			(xy 135.970393 -255.640772) (xy 136.003028 -255.603935) (xy 136.041149 -255.57281) (xy 136.08377 -255.548203)
			(xy 136.129786 -255.530751) (xy 136.178005 -255.520907) (xy 136.22718 -255.518926) (xy 136.276035 -255.524858)
			(xy 136.323306 -255.53855) (xy 136.367768 -255.559648) (xy 136.408271 -255.587604) (xy 136.443764 -255.621696)
			(xy 136.473329 -255.66104) (xy 136.4962 -255.704617) (xy 136.511784 -255.751298) (xy 136.519679 -255.799875)
			(xy 136.520174 -255.824482) (xy 136.520169 -255.824736) (xy 136.848608 -255.824736) (xy 136.852568 -255.775682)
			(xy 136.864345 -255.727898) (xy 136.883636 -255.682622) (xy 136.909939 -255.641026) (xy 136.942574 -255.604189)
			(xy 136.980695 -255.573064) (xy 137.023316 -255.548457) (xy 137.069332 -255.531005) (xy 137.117551 -255.521161)
			(xy 137.166726 -255.51918) (xy 137.215581 -255.525112) (xy 137.262852 -255.538804) (xy 137.307314 -255.559902)
			(xy 137.347817 -255.587858) (xy 137.38331 -255.62195) (xy 137.412875 -255.661294) (xy 137.435746 -255.704871)
			(xy 137.45133 -255.751552) (xy 137.459225 -255.800129) (xy 137.459715 -255.824482) (xy 137.788916 -255.824482)
			(xy 137.792876 -255.775428) (xy 137.804653 -255.727644) (xy 137.823944 -255.682368) (xy 137.850247 -255.640772)
			(xy 137.882882 -255.603935) (xy 137.921003 -255.57281) (xy 137.963624 -255.548203) (xy 138.00964 -255.530751)
			(xy 138.057859 -255.520907) (xy 138.107034 -255.518926) (xy 138.155889 -255.524858) (xy 138.20316 -255.53855)
			(xy 138.247622 -255.559648) (xy 138.288125 -255.587604) (xy 138.323618 -255.621696) (xy 138.353183 -255.66104)
			(xy 138.376054 -255.704617) (xy 138.391638 -255.751298) (xy 138.399533 -255.799875) (xy 138.400028 -255.824482)
			(xy 138.72897 -255.824482) (xy 138.73293 -255.775428) (xy 138.744707 -255.727644) (xy 138.763998 -255.682368)
			(xy 138.790301 -255.640772) (xy 138.822936 -255.603935) (xy 138.861057 -255.57281) (xy 138.903678 -255.548203)
			(xy 138.949694 -255.530751) (xy 138.997913 -255.520907) (xy 139.047088 -255.518926) (xy 139.095943 -255.524858)
			(xy 139.143214 -255.53855) (xy 139.187676 -255.559648) (xy 139.228179 -255.587604) (xy 139.263672 -255.621696)
			(xy 139.293237 -255.66104) (xy 139.316108 -255.704617) (xy 139.331692 -255.751298) (xy 139.339587 -255.799875)
			(xy 139.340082 -255.824482) (xy 139.339587 -255.849089) (xy 139.331692 -255.897666) (xy 139.316108 -255.944347)
			(xy 139.293237 -255.987924) (xy 139.263672 -256.027268) (xy 139.228179 -256.06136) (xy 139.187676 -256.089316)
			(xy 139.143214 -256.110414) (xy 139.095943 -256.124106) (xy 139.047088 -256.130038) (xy 138.997913 -256.128057)
			(xy 138.949694 -256.118213) (xy 138.903678 -256.100761) (xy 138.861057 -256.076154) (xy 138.822936 -256.045029)
			(xy 138.790301 -256.008192) (xy 138.763998 -255.966596) (xy 138.744707 -255.92132) (xy 138.73293 -255.873536)
			(xy 138.72897 -255.824482) (xy 138.400028 -255.824482) (xy 138.399533 -255.849089) (xy 138.391638 -255.897666)
			(xy 138.376054 -255.944347) (xy 138.353183 -255.987924) (xy 138.323618 -256.027268) (xy 138.288125 -256.06136)
			(xy 138.247622 -256.089316) (xy 138.20316 -256.110414) (xy 138.155889 -256.124106) (xy 138.107034 -256.130038)
			(xy 138.057859 -256.128057) (xy 138.00964 -256.118213) (xy 137.963624 -256.100761) (xy 137.921003 -256.076154)
			(xy 137.882882 -256.045029) (xy 137.850247 -256.008192) (xy 137.823944 -255.966596) (xy 137.804653 -255.92132)
			(xy 137.792876 -255.873536) (xy 137.788916 -255.824482) (xy 137.459715 -255.824482) (xy 137.45972 -255.824736)
			(xy 137.459225 -255.849343) (xy 137.45133 -255.89792) (xy 137.435746 -255.944601) (xy 137.412875 -255.988178)
			(xy 137.38331 -256.027522) (xy 137.347817 -256.061614) (xy 137.307314 -256.08957) (xy 137.262852 -256.110668)
			(xy 137.215581 -256.12436) (xy 137.166726 -256.130292) (xy 137.117551 -256.128311) (xy 137.069332 -256.118467)
			(xy 137.023316 -256.101015) (xy 136.980695 -256.076408) (xy 136.942574 -256.045283) (xy 136.909939 -256.008446)
			(xy 136.883636 -255.96685) (xy 136.864345 -255.921574) (xy 136.852568 -255.87379) (xy 136.848608 -255.824736)
			(xy 136.520169 -255.824736) (xy 136.519679 -255.849089) (xy 136.511784 -255.897666) (xy 136.4962 -255.944347)
			(xy 136.473329 -255.987924) (xy 136.443764 -256.027268) (xy 136.408271 -256.06136) (xy 136.367768 -256.089316)
			(xy 136.323306 -256.110414) (xy 136.276035 -256.124106) (xy 136.22718 -256.130038) (xy 136.178005 -256.128057)
			(xy 136.129786 -256.118213) (xy 136.08377 -256.100761) (xy 136.041149 -256.076154) (xy 136.003028 -256.045029)
			(xy 135.970393 -256.008192) (xy 135.94409 -255.966596) (xy 135.924799 -255.92132) (xy 135.913022 -255.873536)
			(xy 135.909062 -255.824482) (xy 135.58012 -255.824482) (xy 135.579625 -255.849089) (xy 135.57173 -255.897666)
			(xy 135.556146 -255.944347) (xy 135.533275 -255.987924) (xy 135.50371 -256.027268) (xy 135.468217 -256.06136)
			(xy 135.427714 -256.089316) (xy 135.383252 -256.110414) (xy 135.335981 -256.124106) (xy 135.287126 -256.130038)
			(xy 135.237951 -256.128057) (xy 135.189732 -256.118213) (xy 135.143716 -256.100761) (xy 135.101095 -256.076154)
			(xy 135.062974 -256.045029) (xy 135.030339 -256.008192) (xy 135.004036 -255.966596) (xy 134.984745 -255.92132)
			(xy 134.972968 -255.873536) (xy 134.969008 -255.824482) (xy 134.640066 -255.824482) (xy 134.639571 -255.849089)
			(xy 134.631676 -255.897666) (xy 134.616092 -255.944347) (xy 134.593221 -255.987924) (xy 134.563656 -256.027268)
			(xy 134.528163 -256.06136) (xy 134.48766 -256.089316) (xy 134.443198 -256.110414) (xy 134.395927 -256.124106)
			(xy 134.347072 -256.130038) (xy 134.297897 -256.128057) (xy 134.249678 -256.118213) (xy 134.203662 -256.100761)
			(xy 134.161041 -256.076154) (xy 134.12292 -256.045029) (xy 134.090285 -256.008192) (xy 134.063982 -255.966596)
			(xy 134.044691 -255.92132) (xy 134.032914 -255.873536) (xy 134.028954 -255.824482) (xy 133.700012 -255.824482)
			(xy 133.699517 -255.849089) (xy 133.691622 -255.897666) (xy 133.676038 -255.944347) (xy 133.653167 -255.987924)
			(xy 133.623602 -256.027268) (xy 133.588109 -256.06136) (xy 133.547606 -256.089316) (xy 133.503144 -256.110414)
			(xy 133.455873 -256.124106) (xy 133.407018 -256.130038) (xy 133.357843 -256.128057) (xy 133.309624 -256.118213)
			(xy 133.263608 -256.100761) (xy 133.220987 -256.076154) (xy 133.182866 -256.045029) (xy 133.150231 -256.008192)
			(xy 133.123928 -255.966596) (xy 133.104637 -255.92132) (xy 133.09286 -255.873536) (xy 133.0889 -255.824482)
			(xy 132.770372 -255.824482) (xy 132.76986 -255.849928) (xy 132.761696 -255.900162) (xy 132.74558 -255.948436)
			(xy 132.721929 -255.993499) (xy 132.691356 -256.034185) (xy 132.654652 -256.06944) (xy 132.612768 -256.09835)
			(xy 132.566789 -256.120167) (xy 132.517905 -256.134327) (xy 132.467384 -256.140461) (xy 132.416532 -256.138412)
			(xy 132.366668 -256.128232) (xy 132.319082 -256.110185) (xy 132.275008 -256.084739) (xy 132.235586 -256.052552)
			(xy 132.201838 -256.014458) (xy 132.174637 -255.971444) (xy 132.154689 -255.924624) (xy 132.14251 -255.87521)
			(xy 132.138415 -255.824482) (xy 131.830572 -255.824482) (xy 131.83006 -255.849928) (xy 131.821896 -255.900162)
			(xy 131.80578 -255.948436) (xy 131.782129 -255.993499) (xy 131.751556 -256.034185) (xy 131.714852 -256.06944)
			(xy 131.672968 -256.09835) (xy 131.626989 -256.120167) (xy 131.578105 -256.134327) (xy 131.527584 -256.140461)
			(xy 131.476732 -256.138412) (xy 131.426868 -256.128232) (xy 131.379282 -256.110185) (xy 131.335208 -256.084739)
			(xy 131.295786 -256.052552) (xy 131.262038 -256.014458) (xy 131.234837 -255.971444) (xy 131.214889 -255.924624)
			(xy 131.20271 -255.87521) (xy 131.198615 -255.824482) (xy 130.880104 -255.824482) (xy 130.879609 -255.849089)
			(xy 130.871714 -255.897666) (xy 130.85613 -255.944347) (xy 130.833259 -255.987924) (xy 130.803694 -256.027268)
			(xy 130.768201 -256.06136) (xy 130.727698 -256.089316) (xy 130.683236 -256.110414) (xy 130.635965 -256.124106)
			(xy 130.58711 -256.130038) (xy 130.537935 -256.128057) (xy 130.489716 -256.118213) (xy 130.4437 -256.100761)
			(xy 130.401079 -256.076154) (xy 130.362958 -256.045029) (xy 130.330323 -256.008192) (xy 130.30402 -255.966596)
			(xy 130.284729 -255.92132) (xy 130.272952 -255.873536) (xy 130.268992 -255.824482) (xy 129.950464 -255.824482)
			(xy 129.949952 -255.849928) (xy 129.941788 -255.900162) (xy 129.925672 -255.948436) (xy 129.902021 -255.993499)
			(xy 129.871448 -256.034185) (xy 129.834744 -256.06944) (xy 129.79286 -256.09835) (xy 129.746881 -256.120167)
			(xy 129.697997 -256.134327) (xy 129.647476 -256.140461) (xy 129.596624 -256.138412) (xy 129.54676 -256.128232)
			(xy 129.499174 -256.110185) (xy 129.4551 -256.084739) (xy 129.415678 -256.052552) (xy 129.38193 -256.014458)
			(xy 129.354729 -255.971444) (xy 129.334781 -255.924624) (xy 129.322602 -255.87521) (xy 129.318507 -255.824482)
			(xy 128.999996 -255.824482) (xy 128.999501 -255.849089) (xy 128.991606 -255.897666) (xy 128.976022 -255.944347)
			(xy 128.953151 -255.987924) (xy 128.923586 -256.027268) (xy 128.888093 -256.06136) (xy 128.84759 -256.089316)
			(xy 128.803128 -256.110414) (xy 128.755857 -256.124106) (xy 128.707002 -256.130038) (xy 128.657827 -256.128057)
			(xy 128.609608 -256.118213) (xy 128.563592 -256.100761) (xy 128.520971 -256.076154) (xy 128.48285 -256.045029)
			(xy 128.450215 -256.008192) (xy 128.423912 -255.966596) (xy 128.404621 -255.92132) (xy 128.392844 -255.873536)
			(xy 128.388884 -255.824482) (xy 128.070356 -255.824482) (xy 128.069844 -255.849928) (xy 128.06168 -255.900162)
			(xy 128.045564 -255.948436) (xy 128.021913 -255.993499) (xy 127.99134 -256.034185) (xy 127.954636 -256.06944)
			(xy 127.912752 -256.09835) (xy 127.866773 -256.120167) (xy 127.817889 -256.134327) (xy 127.767368 -256.140461)
			(xy 127.716516 -256.138412) (xy 127.666652 -256.128232) (xy 127.619066 -256.110185) (xy 127.574992 -256.084739)
			(xy 127.53557 -256.052552) (xy 127.501822 -256.014458) (xy 127.474621 -255.971444) (xy 127.454673 -255.924624)
			(xy 127.442494 -255.87521) (xy 127.438399 -255.824482) (xy 127.120142 -255.824482) (xy 127.119647 -255.849089)
			(xy 127.111752 -255.897666) (xy 127.096168 -255.944347) (xy 127.073297 -255.987924) (xy 127.043732 -256.027268)
			(xy 127.008239 -256.06136) (xy 126.967736 -256.089316) (xy 126.923274 -256.110414) (xy 126.876003 -256.124106)
			(xy 126.827148 -256.130038) (xy 126.777973 -256.128057) (xy 126.729754 -256.118213) (xy 126.683738 -256.100761)
			(xy 126.641117 -256.076154) (xy 126.602996 -256.045029) (xy 126.570361 -256.008192) (xy 126.544058 -255.966596)
			(xy 126.524767 -255.92132) (xy 126.51299 -255.873536) (xy 126.50903 -255.824482) (xy 125.240034 -255.824482)
			(xy 125.239539 -255.849089) (xy 125.231644 -255.897666) (xy 125.21606 -255.944347) (xy 125.193189 -255.987924)
			(xy 125.163624 -256.027268) (xy 125.128131 -256.06136) (xy 125.087628 -256.089316) (xy 125.043166 -256.110414)
			(xy 124.995895 -256.124106) (xy 124.94704 -256.130038) (xy 124.897865 -256.128057) (xy 124.849646 -256.118213)
			(xy 124.80363 -256.100761) (xy 124.761009 -256.076154) (xy 124.722888 -256.045029) (xy 124.690253 -256.008192)
			(xy 124.66395 -255.966596) (xy 124.644659 -255.92132) (xy 124.632882 -255.873536) (xy 124.628922 -255.824482)
			(xy 123.359926 -255.824482) (xy 123.359431 -255.849089) (xy 123.351536 -255.897666) (xy 123.335952 -255.944347)
			(xy 123.313081 -255.987924) (xy 123.283516 -256.027268) (xy 123.248023 -256.06136) (xy 123.20752 -256.089316)
			(xy 123.163058 -256.110414) (xy 123.115787 -256.124106) (xy 123.066932 -256.130038) (xy 123.017757 -256.128057)
			(xy 122.969538 -256.118213) (xy 122.923522 -256.100761) (xy 122.880901 -256.076154) (xy 122.84278 -256.045029)
			(xy 122.810145 -256.008192) (xy 122.783842 -255.966596) (xy 122.764551 -255.92132) (xy 122.752774 -255.873536)
			(xy 122.748814 -255.824482) (xy 121.480072 -255.824482) (xy 121.479577 -255.849089) (xy 121.471682 -255.897666)
			(xy 121.456098 -255.944347) (xy 121.433227 -255.987924) (xy 121.403662 -256.027268) (xy 121.368169 -256.06136)
			(xy 121.327666 -256.089316) (xy 121.283204 -256.110414) (xy 121.235933 -256.124106) (xy 121.187078 -256.130038)
			(xy 121.137903 -256.128057) (xy 121.089684 -256.118213) (xy 121.043668 -256.100761) (xy 121.001047 -256.076154)
			(xy 120.962926 -256.045029) (xy 120.930291 -256.008192) (xy 120.903988 -255.966596) (xy 120.884697 -255.92132)
			(xy 120.87292 -255.873536) (xy 120.86896 -255.824482) (xy 117.617604 -255.824482) (xy 117.581394 -255.844172)
			(xy 117.531841 -255.86197) (xy 117.480151 -255.871994) (xy 117.427537 -255.874011) (xy 117.375232 -255.867973)
			(xy 117.324461 -255.854021) (xy 117.276416 -255.832482) (xy 117.232221 -255.803862) (xy 117.192913 -255.768831)
			(xy 117.159413 -255.72821) (xy 117.132507 -255.682951) (xy 117.112824 -255.634116) (xy 117.100827 -255.582848)
			(xy 117.096797 -255.53035) (xy 107.38231 -255.53035) (xy 107.572302 -255.720342) (xy 107.577801 -255.725329)
			(xy 107.590968 -255.732173) (xy 107.59821 -255.733804) (xy 107.607862 -255.73482) (xy 109.859318 -255.73482)
			(xy 109.869386 -255.735247) (xy 109.887984 -255.742968) (xy 109.895386 -255.749806) (xy 110.081314 -255.935734)
			(xy 110.088165 -255.94313) (xy 110.0959 -255.961729) (xy 110.0963 -255.971802) (xy 110.0963 -256.058924)
			(xy 110.0963 -256.060448) (xy 110.097027 -256.069847) (xy 110.104353 -256.087197) (xy 110.117421 -256.100761)
			(xy 110.125764 -256.105152) (xy 110.126526 -256.105406) (xy 110.19536 -256.135886) (xy 110.21187 -256.142998)
			(xy 110.218638 -256.145703) (xy 110.233094 -256.147516) (xy 110.240318 -256.146554) (xy 110.24743 -256.145538)
			(xy 110.260638 -256.139188) (xy 110.26648 -256.133854) (xy 110.285558 -256.117074) (xy 110.327732 -256.088742)
			(xy 110.373619 -256.066933) (xy 110.422219 -256.052122) (xy 110.472471 -256.044633) (xy 110.497874 -256.044192)
			(xy 110.523576 -256.044646) (xy 110.574406 -256.052304) (xy 110.623527 -256.067453) (xy 110.669842 -256.089753)
			(xy 110.712315 -256.118708) (xy 110.749998 -256.15367) (xy 110.782049 -256.193858) (xy 110.807752 -256.238375)
			(xy 110.826533 -256.286225) (xy 110.837972 -256.33634) (xy 110.841814 -256.3876) (xy 111.103921 -256.3876)
			(xy 111.107951 -256.335102) (xy 111.119948 -256.283834) (xy 111.139631 -256.234999) (xy 111.166537 -256.18974)
			(xy 111.200037 -256.149119) (xy 111.239345 -256.114088) (xy 111.28354 -256.085468) (xy 111.331585 -256.063929)
			(xy 111.382356 -256.049977) (xy 111.434661 -256.043939) (xy 111.487275 -256.045956) (xy 111.538965 -256.05598)
			(xy 111.588518 -256.073778) (xy 111.634774 -256.098931) (xy 111.676648 -256.13085) (xy 111.71316 -256.168788)
			(xy 111.743452 -256.211854) (xy 111.766815 -256.259039) (xy 111.782701 -256.309238) (xy 111.790738 -256.361274)
			(xy 111.791242 -256.3876) (xy 112.053881 -256.3876) (xy 112.057911 -256.335102) (xy 112.069908 -256.283834)
			(xy 112.089591 -256.234999) (xy 112.116497 -256.18974) (xy 112.149997 -256.149119) (xy 112.189305 -256.114088)
			(xy 112.2335 -256.085468) (xy 112.281545 -256.063929) (xy 112.332316 -256.049977) (xy 112.384621 -256.043939)
			(xy 112.437235 -256.045956) (xy 112.488925 -256.05598) (xy 112.538478 -256.073778) (xy 112.584734 -256.098931)
			(xy 112.626608 -256.13085) (xy 112.66312 -256.168788) (xy 112.693412 -256.211854) (xy 112.716775 -256.259039)
			(xy 112.732661 -256.309238) (xy 112.740698 -256.361274) (xy 112.741202 -256.3876) (xy 113.004095 -256.3876)
			(xy 113.008125 -256.335102) (xy 113.020122 -256.283834) (xy 113.039805 -256.234999) (xy 113.066711 -256.18974)
			(xy 113.100211 -256.149119) (xy 113.139519 -256.114088) (xy 113.183714 -256.085468) (xy 113.231759 -256.063929)
			(xy 113.28253 -256.049977) (xy 113.334835 -256.043939) (xy 113.387449 -256.045956) (xy 113.439139 -256.05598)
			(xy 113.488692 -256.073778) (xy 113.534948 -256.098931) (xy 113.576822 -256.13085) (xy 113.613334 -256.168788)
			(xy 113.643626 -256.211854) (xy 113.666989 -256.259039) (xy 113.682875 -256.309238) (xy 113.690912 -256.361274)
			(xy 113.691416 -256.3876) (xy 113.954055 -256.3876) (xy 113.958085 -256.335102) (xy 113.970082 -256.283834)
			(xy 113.989765 -256.234999) (xy 114.016671 -256.18974) (xy 114.050171 -256.149119) (xy 114.089479 -256.114088)
			(xy 114.133674 -256.085468) (xy 114.181719 -256.063929) (xy 114.23249 -256.049977) (xy 114.284795 -256.043939)
			(xy 114.337409 -256.045956) (xy 114.389099 -256.05598) (xy 114.438652 -256.073778) (xy 114.484908 -256.098931)
			(xy 114.526782 -256.13085) (xy 114.563294 -256.168788) (xy 114.593586 -256.211854) (xy 114.616949 -256.259039)
			(xy 114.632835 -256.309238) (xy 114.640872 -256.361274) (xy 114.641376 -256.3876) (xy 114.904015 -256.3876)
			(xy 114.908045 -256.335102) (xy 114.920042 -256.283834) (xy 114.939725 -256.234999) (xy 114.966631 -256.18974)
			(xy 115.000131 -256.149119) (xy 115.039439 -256.114088) (xy 115.083634 -256.085468) (xy 115.131679 -256.063929)
			(xy 115.18245 -256.049977) (xy 115.234755 -256.043939) (xy 115.287369 -256.045956) (xy 115.339059 -256.05598)
			(xy 115.388612 -256.073778) (xy 115.434868 -256.098931) (xy 115.476742 -256.13085) (xy 115.513254 -256.168788)
			(xy 115.543546 -256.211854) (xy 115.566909 -256.259039) (xy 115.582795 -256.309238) (xy 115.590832 -256.361274)
			(xy 115.591336 -256.3876) (xy 115.853975 -256.3876) (xy 115.858005 -256.335102) (xy 115.870002 -256.283834)
			(xy 115.889685 -256.234999) (xy 115.916591 -256.18974) (xy 115.950091 -256.149119) (xy 115.989399 -256.114088)
			(xy 116.033594 -256.085468) (xy 116.081639 -256.063929) (xy 116.13241 -256.049977) (xy 116.184715 -256.043939)
			(xy 116.237329 -256.045956) (xy 116.289019 -256.05598) (xy 116.338572 -256.073778) (xy 116.384828 -256.098931)
			(xy 116.426702 -256.13085) (xy 116.463214 -256.168788) (xy 116.493506 -256.211854) (xy 116.516869 -256.259039)
			(xy 116.532755 -256.309238) (xy 116.540792 -256.361274) (xy 116.541296 -256.3876) (xy 116.540792 -256.413926)
			(xy 116.532755 -256.465962) (xy 116.528214 -256.48031) (xy 117.096797 -256.48031) (xy 117.100827 -256.427812)
			(xy 117.112824 -256.376544) (xy 117.132507 -256.327709) (xy 117.159413 -256.28245) (xy 117.192913 -256.241829)
			(xy 117.232221 -256.206798) (xy 117.276416 -256.178178) (xy 117.324461 -256.156639) (xy 117.375232 -256.142687)
			(xy 117.427537 -256.136649) (xy 117.480151 -256.138666) (xy 117.531841 -256.14869) (xy 117.581394 -256.166488)
			(xy 117.62765 -256.191641) (xy 117.669524 -256.22356) (xy 117.706036 -256.261498) (xy 117.736328 -256.304564)
			(xy 117.759691 -256.351749) (xy 117.775577 -256.401948) (xy 117.783614 -256.453984) (xy 117.784118 -256.48031)
			(xy 117.783614 -256.506636) (xy 117.775577 -256.558672) (xy 117.759691 -256.608871) (xy 117.747007 -256.634488)
			(xy 122.278914 -256.634488) (xy 122.282874 -256.585434) (xy 122.294651 -256.53765) (xy 122.313942 -256.492374)
			(xy 122.340245 -256.450778) (xy 122.37288 -256.413941) (xy 122.411001 -256.382816) (xy 122.453622 -256.358209)
			(xy 122.499638 -256.340757) (xy 122.547857 -256.330913) (xy 122.597032 -256.328932) (xy 122.645887 -256.334864)
			(xy 122.693158 -256.348556) (xy 122.73762 -256.369654) (xy 122.778123 -256.39761) (xy 122.813616 -256.431702)
			(xy 122.843181 -256.471046) (xy 122.866052 -256.514623) (xy 122.881636 -256.561304) (xy 122.889531 -256.609881)
			(xy 122.890026 -256.634488) (xy 124.159022 -256.634488) (xy 124.162982 -256.585434) (xy 124.174759 -256.53765)
			(xy 124.19405 -256.492374) (xy 124.220353 -256.450778) (xy 124.252988 -256.413941) (xy 124.291109 -256.382816)
			(xy 124.33373 -256.358209) (xy 124.379746 -256.340757) (xy 124.427965 -256.330913) (xy 124.47714 -256.328932)
			(xy 124.525995 -256.334864) (xy 124.573266 -256.348556) (xy 124.617728 -256.369654) (xy 124.658231 -256.39761)
			(xy 124.693724 -256.431702) (xy 124.723289 -256.471046) (xy 124.74616 -256.514623) (xy 124.761744 -256.561304)
			(xy 124.769639 -256.609881) (xy 124.770134 -256.634488) (xy 126.038876 -256.634488) (xy 126.042836 -256.585434)
			(xy 126.054613 -256.53765) (xy 126.073904 -256.492374) (xy 126.100207 -256.450778) (xy 126.132842 -256.413941)
			(xy 126.170963 -256.382816) (xy 126.213584 -256.358209) (xy 126.2596 -256.340757) (xy 126.307819 -256.330913)
			(xy 126.356994 -256.328932) (xy 126.405849 -256.334864) (xy 126.45312 -256.348556) (xy 126.497582 -256.369654)
			(xy 126.538085 -256.39761) (xy 126.573578 -256.431702) (xy 126.603143 -256.471046) (xy 126.626014 -256.514623)
			(xy 126.641598 -256.561304) (xy 126.649493 -256.609881) (xy 126.649988 -256.634488) (xy 127.918984 -256.634488)
			(xy 127.922944 -256.585434) (xy 127.934721 -256.53765) (xy 127.954012 -256.492374) (xy 127.980315 -256.450778)
			(xy 128.01295 -256.413941) (xy 128.051071 -256.382816) (xy 128.093692 -256.358209) (xy 128.139708 -256.340757)
			(xy 128.187927 -256.330913) (xy 128.237102 -256.328932) (xy 128.285957 -256.334864) (xy 128.333228 -256.348556)
			(xy 128.37769 -256.369654) (xy 128.418193 -256.39761) (xy 128.453686 -256.431702) (xy 128.483251 -256.471046)
			(xy 128.506122 -256.514623) (xy 128.521706 -256.561304) (xy 128.529601 -256.609881) (xy 128.530096 -256.634488)
			(xy 128.848607 -256.634488) (xy 128.852702 -256.58376) (xy 128.864881 -256.534346) (xy 128.884829 -256.487526)
			(xy 128.91203 -256.444512) (xy 128.945778 -256.406418) (xy 128.9852 -256.374231) (xy 129.029274 -256.348785)
			(xy 129.07686 -256.330738) (xy 129.126724 -256.320558) (xy 129.177576 -256.318509) (xy 129.228097 -256.324643)
			(xy 129.276981 -256.338803) (xy 129.32296 -256.36062) (xy 129.364844 -256.38953) (xy 129.401548 -256.424785)
			(xy 129.432121 -256.465471) (xy 129.455772 -256.510534) (xy 129.471888 -256.558808) (xy 129.480052 -256.609042)
			(xy 129.480564 -256.634488) (xy 130.738892 -256.634488) (xy 130.742852 -256.585434) (xy 130.754629 -256.53765)
			(xy 130.77392 -256.492374) (xy 130.800223 -256.450778) (xy 130.832858 -256.413941) (xy 130.870979 -256.382816)
			(xy 130.9136 -256.358209) (xy 130.959616 -256.340757) (xy 131.007835 -256.330913) (xy 131.05701 -256.328932)
			(xy 131.105865 -256.334864) (xy 131.153136 -256.348556) (xy 131.197598 -256.369654) (xy 131.238101 -256.39761)
			(xy 131.273594 -256.431702) (xy 131.303159 -256.471046) (xy 131.32603 -256.514623) (xy 131.341614 -256.561304)
			(xy 131.349509 -256.609881) (xy 131.350004 -256.634488) (xy 131.678946 -256.634488) (xy 131.682906 -256.585434)
			(xy 131.694683 -256.53765) (xy 131.713974 -256.492374) (xy 131.740277 -256.450778) (xy 131.772912 -256.413941)
			(xy 131.811033 -256.382816) (xy 131.853654 -256.358209) (xy 131.89967 -256.340757) (xy 131.947889 -256.330913)
			(xy 131.997064 -256.328932) (xy 132.045919 -256.334864) (xy 132.09319 -256.348556) (xy 132.137652 -256.369654)
			(xy 132.178155 -256.39761) (xy 132.213648 -256.431702) (xy 132.243213 -256.471046) (xy 132.266084 -256.514623)
			(xy 132.281668 -256.561304) (xy 132.289563 -256.609881) (xy 132.290058 -256.634488) (xy 132.608569 -256.634488)
			(xy 132.612664 -256.58376) (xy 132.624843 -256.534346) (xy 132.644791 -256.487526) (xy 132.671992 -256.444512)
			(xy 132.70574 -256.406418) (xy 132.745162 -256.374231) (xy 132.789236 -256.348785) (xy 132.836822 -256.330738)
			(xy 132.886686 -256.320558) (xy 132.937538 -256.318509) (xy 132.988059 -256.324643) (xy 133.036943 -256.338803)
			(xy 133.082922 -256.36062) (xy 133.124806 -256.38953) (xy 133.16151 -256.424785) (xy 133.192083 -256.465471)
			(xy 133.215734 -256.510534) (xy 133.23185 -256.558808) (xy 133.240014 -256.609042) (xy 133.240526 -256.634488)
			(xy 133.559054 -256.634488) (xy 133.563014 -256.585434) (xy 133.574791 -256.53765) (xy 133.594082 -256.492374)
			(xy 133.620385 -256.450778) (xy 133.65302 -256.413941) (xy 133.691141 -256.382816) (xy 133.733762 -256.358209)
			(xy 133.779778 -256.340757) (xy 133.827997 -256.330913) (xy 133.877172 -256.328932) (xy 133.926027 -256.334864)
			(xy 133.973298 -256.348556) (xy 134.01776 -256.369654) (xy 134.058263 -256.39761) (xy 134.093756 -256.431702)
			(xy 134.123321 -256.471046) (xy 134.146192 -256.514623) (xy 134.161776 -256.561304) (xy 134.169671 -256.609881)
			(xy 134.170166 -256.634488) (xy 134.498854 -256.634488) (xy 134.502814 -256.585434) (xy 134.514591 -256.53765)
			(xy 134.533882 -256.492374) (xy 134.560185 -256.450778) (xy 134.59282 -256.413941) (xy 134.630941 -256.382816)
			(xy 134.673562 -256.358209) (xy 134.719578 -256.340757) (xy 134.767797 -256.330913) (xy 134.816972 -256.328932)
			(xy 134.865827 -256.334864) (xy 134.913098 -256.348556) (xy 134.95756 -256.369654) (xy 134.998063 -256.39761)
			(xy 135.033556 -256.431702) (xy 135.063121 -256.471046) (xy 135.085992 -256.514623) (xy 135.101576 -256.561304)
			(xy 135.109471 -256.609881) (xy 135.109966 -256.634488) (xy 135.438908 -256.634488) (xy 135.442868 -256.585434)
			(xy 135.454645 -256.53765) (xy 135.473936 -256.492374) (xy 135.500239 -256.450778) (xy 135.532874 -256.413941)
			(xy 135.570995 -256.382816) (xy 135.613616 -256.358209) (xy 135.659632 -256.340757) (xy 135.707851 -256.330913)
			(xy 135.757026 -256.328932) (xy 135.805881 -256.334864) (xy 135.853152 -256.348556) (xy 135.897614 -256.369654)
			(xy 135.938117 -256.39761) (xy 135.97361 -256.431702) (xy 136.003175 -256.471046) (xy 136.026046 -256.514623)
			(xy 136.04163 -256.561304) (xy 136.049525 -256.609881) (xy 136.05002 -256.634488) (xy 137.319016 -256.634488)
			(xy 137.322976 -256.585434) (xy 137.334753 -256.53765) (xy 137.354044 -256.492374) (xy 137.380347 -256.450778)
			(xy 137.412982 -256.413941) (xy 137.451103 -256.382816) (xy 137.493724 -256.358209) (xy 137.53974 -256.340757)
			(xy 137.587959 -256.330913) (xy 137.637134 -256.328932) (xy 137.685989 -256.334864) (xy 137.73326 -256.348556)
			(xy 137.777722 -256.369654) (xy 137.818225 -256.39761) (xy 137.853718 -256.431702) (xy 137.883283 -256.471046)
			(xy 137.906154 -256.514623) (xy 137.921738 -256.561304) (xy 137.929633 -256.609881) (xy 137.930128 -256.634488)
			(xy 138.25907 -256.634488) (xy 138.26303 -256.585434) (xy 138.274807 -256.53765) (xy 138.294098 -256.492374)
			(xy 138.320401 -256.450778) (xy 138.353036 -256.413941) (xy 138.391157 -256.382816) (xy 138.433778 -256.358209)
			(xy 138.479794 -256.340757) (xy 138.528013 -256.330913) (xy 138.577188 -256.328932) (xy 138.626043 -256.334864)
			(xy 138.673314 -256.348556) (xy 138.717776 -256.369654) (xy 138.758279 -256.39761) (xy 138.793772 -256.431702)
			(xy 138.823337 -256.471046) (xy 138.846208 -256.514623) (xy 138.861792 -256.561304) (xy 138.869687 -256.609881)
			(xy 138.870182 -256.634488) (xy 139.19887 -256.634488) (xy 139.20283 -256.585434) (xy 139.214607 -256.53765)
			(xy 139.233898 -256.492374) (xy 139.260201 -256.450778) (xy 139.292836 -256.413941) (xy 139.330957 -256.382816)
			(xy 139.373578 -256.358209) (xy 139.419594 -256.340757) (xy 139.467813 -256.330913) (xy 139.516988 -256.328932)
			(xy 139.565843 -256.334864) (xy 139.613114 -256.348556) (xy 139.657576 -256.369654) (xy 139.698079 -256.39761)
			(xy 139.733572 -256.431702) (xy 139.763137 -256.471046) (xy 139.786008 -256.514623) (xy 139.801592 -256.561304)
			(xy 139.809487 -256.609881) (xy 139.809982 -256.634488) (xy 139.809487 -256.659095) (xy 139.801592 -256.707672)
			(xy 139.786008 -256.754353) (xy 139.763137 -256.79793) (xy 139.733572 -256.837274) (xy 139.698079 -256.871366)
			(xy 139.657576 -256.899322) (xy 139.613114 -256.92042) (xy 139.565843 -256.934112) (xy 139.516988 -256.940044)
			(xy 139.467813 -256.938063) (xy 139.419594 -256.928219) (xy 139.373578 -256.910767) (xy 139.330957 -256.88616)
			(xy 139.292836 -256.855035) (xy 139.260201 -256.818198) (xy 139.233898 -256.776602) (xy 139.214607 -256.731326)
			(xy 139.20283 -256.683542) (xy 139.19887 -256.634488) (xy 138.870182 -256.634488) (xy 138.869687 -256.659095)
			(xy 138.861792 -256.707672) (xy 138.846208 -256.754353) (xy 138.823337 -256.79793) (xy 138.793772 -256.837274)
			(xy 138.758279 -256.871366) (xy 138.717776 -256.899322) (xy 138.673314 -256.92042) (xy 138.626043 -256.934112)
			(xy 138.577188 -256.940044) (xy 138.528013 -256.938063) (xy 138.479794 -256.928219) (xy 138.433778 -256.910767)
			(xy 138.391157 -256.88616) (xy 138.353036 -256.855035) (xy 138.320401 -256.818198) (xy 138.294098 -256.776602)
			(xy 138.274807 -256.731326) (xy 138.26303 -256.683542) (xy 138.25907 -256.634488) (xy 137.930128 -256.634488)
			(xy 137.929633 -256.659095) (xy 137.921738 -256.707672) (xy 137.906154 -256.754353) (xy 137.883283 -256.79793)
			(xy 137.853718 -256.837274) (xy 137.818225 -256.871366) (xy 137.777722 -256.899322) (xy 137.73326 -256.92042)
			(xy 137.685989 -256.934112) (xy 137.637134 -256.940044) (xy 137.587959 -256.938063) (xy 137.53974 -256.928219)
			(xy 137.493724 -256.910767) (xy 137.451103 -256.88616) (xy 137.412982 -256.855035) (xy 137.380347 -256.818198)
			(xy 137.354044 -256.776602) (xy 137.334753 -256.731326) (xy 137.322976 -256.683542) (xy 137.319016 -256.634488)
			(xy 136.05002 -256.634488) (xy 136.049525 -256.659095) (xy 136.04163 -256.707672) (xy 136.026046 -256.754353)
			(xy 136.003175 -256.79793) (xy 135.97361 -256.837274) (xy 135.938117 -256.871366) (xy 135.897614 -256.899322)
			(xy 135.853152 -256.92042) (xy 135.805881 -256.934112) (xy 135.757026 -256.940044) (xy 135.707851 -256.938063)
			(xy 135.659632 -256.928219) (xy 135.613616 -256.910767) (xy 135.570995 -256.88616) (xy 135.532874 -256.855035)
			(xy 135.500239 -256.818198) (xy 135.473936 -256.776602) (xy 135.454645 -256.731326) (xy 135.442868 -256.683542)
			(xy 135.438908 -256.634488) (xy 135.109966 -256.634488) (xy 135.109471 -256.659095) (xy 135.101576 -256.707672)
			(xy 135.085992 -256.754353) (xy 135.063121 -256.79793) (xy 135.033556 -256.837274) (xy 134.998063 -256.871366)
			(xy 134.95756 -256.899322) (xy 134.913098 -256.92042) (xy 134.865827 -256.934112) (xy 134.816972 -256.940044)
			(xy 134.767797 -256.938063) (xy 134.719578 -256.928219) (xy 134.673562 -256.910767) (xy 134.630941 -256.88616)
			(xy 134.59282 -256.855035) (xy 134.560185 -256.818198) (xy 134.533882 -256.776602) (xy 134.514591 -256.731326)
			(xy 134.502814 -256.683542) (xy 134.498854 -256.634488) (xy 134.170166 -256.634488) (xy 134.169671 -256.659095)
			(xy 134.161776 -256.707672) (xy 134.146192 -256.754353) (xy 134.123321 -256.79793) (xy 134.093756 -256.837274)
			(xy 134.058263 -256.871366) (xy 134.01776 -256.899322) (xy 133.973298 -256.92042) (xy 133.926027 -256.934112)
			(xy 133.877172 -256.940044) (xy 133.827997 -256.938063) (xy 133.779778 -256.928219) (xy 133.733762 -256.910767)
			(xy 133.691141 -256.88616) (xy 133.65302 -256.855035) (xy 133.620385 -256.818198) (xy 133.594082 -256.776602)
			(xy 133.574791 -256.731326) (xy 133.563014 -256.683542) (xy 133.559054 -256.634488) (xy 133.240526 -256.634488)
			(xy 133.240014 -256.659934) (xy 133.23185 -256.710168) (xy 133.215734 -256.758442) (xy 133.192083 -256.803505)
			(xy 133.16151 -256.844191) (xy 133.124806 -256.879446) (xy 133.082922 -256.908356) (xy 133.036943 -256.930173)
			(xy 132.988059 -256.944333) (xy 132.937538 -256.950467) (xy 132.886686 -256.948418) (xy 132.836822 -256.938238)
			(xy 132.789236 -256.920191) (xy 132.745162 -256.894745) (xy 132.70574 -256.862558) (xy 132.671992 -256.824464)
			(xy 132.644791 -256.78145) (xy 132.624843 -256.73463) (xy 132.612664 -256.685216) (xy 132.608569 -256.634488)
			(xy 132.290058 -256.634488) (xy 132.289563 -256.659095) (xy 132.281668 -256.707672) (xy 132.266084 -256.754353)
			(xy 132.243213 -256.79793) (xy 132.213648 -256.837274) (xy 132.178155 -256.871366) (xy 132.137652 -256.899322)
			(xy 132.09319 -256.92042) (xy 132.045919 -256.934112) (xy 131.997064 -256.940044) (xy 131.947889 -256.938063)
			(xy 131.89967 -256.928219) (xy 131.853654 -256.910767) (xy 131.811033 -256.88616) (xy 131.772912 -256.855035)
			(xy 131.740277 -256.818198) (xy 131.713974 -256.776602) (xy 131.694683 -256.731326) (xy 131.682906 -256.683542)
			(xy 131.678946 -256.634488) (xy 131.350004 -256.634488) (xy 131.349509 -256.659095) (xy 131.341614 -256.707672)
			(xy 131.32603 -256.754353) (xy 131.303159 -256.79793) (xy 131.273594 -256.837274) (xy 131.238101 -256.871366)
			(xy 131.197598 -256.899322) (xy 131.153136 -256.92042) (xy 131.105865 -256.934112) (xy 131.05701 -256.940044)
			(xy 131.007835 -256.938063) (xy 130.959616 -256.928219) (xy 130.9136 -256.910767) (xy 130.870979 -256.88616)
			(xy 130.832858 -256.855035) (xy 130.800223 -256.818198) (xy 130.77392 -256.776602) (xy 130.754629 -256.731326)
			(xy 130.742852 -256.683542) (xy 130.738892 -256.634488) (xy 129.480564 -256.634488) (xy 129.480052 -256.659934)
			(xy 129.471888 -256.710168) (xy 129.455772 -256.758442) (xy 129.432121 -256.803505) (xy 129.401548 -256.844191)
			(xy 129.364844 -256.879446) (xy 129.32296 -256.908356) (xy 129.276981 -256.930173) (xy 129.228097 -256.944333)
			(xy 129.177576 -256.950467) (xy 129.126724 -256.948418) (xy 129.07686 -256.938238) (xy 129.029274 -256.920191)
			(xy 128.9852 -256.894745) (xy 128.945778 -256.862558) (xy 128.91203 -256.824464) (xy 128.884829 -256.78145)
			(xy 128.864881 -256.73463) (xy 128.852702 -256.685216) (xy 128.848607 -256.634488) (xy 128.530096 -256.634488)
			(xy 128.529601 -256.659095) (xy 128.521706 -256.707672) (xy 128.506122 -256.754353) (xy 128.483251 -256.79793)
			(xy 128.453686 -256.837274) (xy 128.418193 -256.871366) (xy 128.37769 -256.899322) (xy 128.333228 -256.92042)
			(xy 128.285957 -256.934112) (xy 128.237102 -256.940044) (xy 128.187927 -256.938063) (xy 128.139708 -256.928219)
			(xy 128.093692 -256.910767) (xy 128.051071 -256.88616) (xy 128.01295 -256.855035) (xy 127.980315 -256.818198)
			(xy 127.954012 -256.776602) (xy 127.934721 -256.731326) (xy 127.922944 -256.683542) (xy 127.918984 -256.634488)
			(xy 126.649988 -256.634488) (xy 126.649493 -256.659095) (xy 126.641598 -256.707672) (xy 126.626014 -256.754353)
			(xy 126.603143 -256.79793) (xy 126.573578 -256.837274) (xy 126.538085 -256.871366) (xy 126.497582 -256.899322)
			(xy 126.45312 -256.92042) (xy 126.405849 -256.934112) (xy 126.356994 -256.940044) (xy 126.307819 -256.938063)
			(xy 126.2596 -256.928219) (xy 126.213584 -256.910767) (xy 126.170963 -256.88616) (xy 126.132842 -256.855035)
			(xy 126.100207 -256.818198) (xy 126.073904 -256.776602) (xy 126.054613 -256.731326) (xy 126.042836 -256.683542)
			(xy 126.038876 -256.634488) (xy 124.770134 -256.634488) (xy 124.769639 -256.659095) (xy 124.761744 -256.707672)
			(xy 124.74616 -256.754353) (xy 124.723289 -256.79793) (xy 124.693724 -256.837274) (xy 124.658231 -256.871366)
			(xy 124.617728 -256.899322) (xy 124.573266 -256.92042) (xy 124.525995 -256.934112) (xy 124.47714 -256.940044)
			(xy 124.427965 -256.938063) (xy 124.379746 -256.928219) (xy 124.33373 -256.910767) (xy 124.291109 -256.88616)
			(xy 124.252988 -256.855035) (xy 124.220353 -256.818198) (xy 124.19405 -256.776602) (xy 124.174759 -256.731326)
			(xy 124.162982 -256.683542) (xy 124.159022 -256.634488) (xy 122.890026 -256.634488) (xy 122.889531 -256.659095)
			(xy 122.881636 -256.707672) (xy 122.866052 -256.754353) (xy 122.843181 -256.79793) (xy 122.813616 -256.837274)
			(xy 122.778123 -256.871366) (xy 122.73762 -256.899322) (xy 122.693158 -256.92042) (xy 122.645887 -256.934112)
			(xy 122.597032 -256.940044) (xy 122.547857 -256.938063) (xy 122.499638 -256.928219) (xy 122.453622 -256.910767)
			(xy 122.411001 -256.88616) (xy 122.37288 -256.855035) (xy 122.340245 -256.818198) (xy 122.313942 -256.776602)
			(xy 122.294651 -256.731326) (xy 122.282874 -256.683542) (xy 122.278914 -256.634488) (xy 117.747007 -256.634488)
			(xy 117.736328 -256.656056) (xy 117.706036 -256.699122) (xy 117.669524 -256.73706) (xy 117.62765 -256.768979)
			(xy 117.581394 -256.794132) (xy 117.531841 -256.81193) (xy 117.480151 -256.821954) (xy 117.427537 -256.823971)
			(xy 117.375232 -256.817933) (xy 117.324461 -256.803981) (xy 117.276416 -256.782442) (xy 117.232221 -256.753822)
			(xy 117.192913 -256.718791) (xy 117.159413 -256.67817) (xy 117.132507 -256.632911) (xy 117.112824 -256.584076)
			(xy 117.100827 -256.532808) (xy 117.096797 -256.48031) (xy 116.528214 -256.48031) (xy 116.516869 -256.516161)
			(xy 116.493506 -256.563346) (xy 116.463214 -256.606412) (xy 116.426702 -256.64435) (xy 116.384828 -256.676269)
			(xy 116.338572 -256.701422) (xy 116.289019 -256.71922) (xy 116.237329 -256.729244) (xy 116.184715 -256.731261)
			(xy 116.13241 -256.725223) (xy 116.081639 -256.711271) (xy 116.033594 -256.689732) (xy 115.989399 -256.661112)
			(xy 115.950091 -256.626081) (xy 115.916591 -256.58546) (xy 115.889685 -256.540201) (xy 115.870002 -256.491366)
			(xy 115.858005 -256.440098) (xy 115.853975 -256.3876) (xy 115.591336 -256.3876) (xy 115.590832 -256.413926)
			(xy 115.582795 -256.465962) (xy 115.566909 -256.516161) (xy 115.543546 -256.563346) (xy 115.513254 -256.606412)
			(xy 115.476742 -256.64435) (xy 115.434868 -256.676269) (xy 115.388612 -256.701422) (xy 115.339059 -256.71922)
			(xy 115.287369 -256.729244) (xy 115.234755 -256.731261) (xy 115.18245 -256.725223) (xy 115.131679 -256.711271)
			(xy 115.083634 -256.689732) (xy 115.039439 -256.661112) (xy 115.000131 -256.626081) (xy 114.966631 -256.58546)
			(xy 114.939725 -256.540201) (xy 114.920042 -256.491366) (xy 114.908045 -256.440098) (xy 114.904015 -256.3876)
			(xy 114.641376 -256.3876) (xy 114.640872 -256.413926) (xy 114.632835 -256.465962) (xy 114.616949 -256.516161)
			(xy 114.593586 -256.563346) (xy 114.563294 -256.606412) (xy 114.526782 -256.64435) (xy 114.484908 -256.676269)
			(xy 114.438652 -256.701422) (xy 114.389099 -256.71922) (xy 114.337409 -256.729244) (xy 114.284795 -256.731261)
			(xy 114.23249 -256.725223) (xy 114.181719 -256.711271) (xy 114.133674 -256.689732) (xy 114.089479 -256.661112)
			(xy 114.050171 -256.626081) (xy 114.016671 -256.58546) (xy 113.989765 -256.540201) (xy 113.970082 -256.491366)
			(xy 113.958085 -256.440098) (xy 113.954055 -256.3876) (xy 113.691416 -256.3876) (xy 113.690912 -256.413926)
			(xy 113.682875 -256.465962) (xy 113.666989 -256.516161) (xy 113.643626 -256.563346) (xy 113.613334 -256.606412)
			(xy 113.576822 -256.64435) (xy 113.534948 -256.676269) (xy 113.488692 -256.701422) (xy 113.439139 -256.71922)
			(xy 113.387449 -256.729244) (xy 113.334835 -256.731261) (xy 113.28253 -256.725223) (xy 113.231759 -256.711271)
			(xy 113.183714 -256.689732) (xy 113.139519 -256.661112) (xy 113.100211 -256.626081) (xy 113.066711 -256.58546)
			(xy 113.039805 -256.540201) (xy 113.020122 -256.491366) (xy 113.008125 -256.440098) (xy 113.004095 -256.3876)
			(xy 112.741202 -256.3876) (xy 112.740698 -256.413926) (xy 112.732661 -256.465962) (xy 112.716775 -256.516161)
			(xy 112.693412 -256.563346) (xy 112.66312 -256.606412) (xy 112.626608 -256.64435) (xy 112.584734 -256.676269)
			(xy 112.538478 -256.701422) (xy 112.488925 -256.71922) (xy 112.437235 -256.729244) (xy 112.384621 -256.731261)
			(xy 112.332316 -256.725223) (xy 112.281545 -256.711271) (xy 112.2335 -256.689732) (xy 112.189305 -256.661112)
			(xy 112.149997 -256.626081) (xy 112.116497 -256.58546) (xy 112.089591 -256.540201) (xy 112.069908 -256.491366)
			(xy 112.057911 -256.440098) (xy 112.053881 -256.3876) (xy 111.791242 -256.3876) (xy 111.790738 -256.413926)
			(xy 111.782701 -256.465962) (xy 111.766815 -256.516161) (xy 111.743452 -256.563346) (xy 111.71316 -256.606412)
			(xy 111.676648 -256.64435) (xy 111.634774 -256.676269) (xy 111.588518 -256.701422) (xy 111.538965 -256.71922)
			(xy 111.487275 -256.729244) (xy 111.434661 -256.731261) (xy 111.382356 -256.725223) (xy 111.331585 -256.711271)
			(xy 111.28354 -256.689732) (xy 111.239345 -256.661112) (xy 111.200037 -256.626081) (xy 111.166537 -256.58546)
			(xy 111.139631 -256.540201) (xy 111.119948 -256.491366) (xy 111.107951 -256.440098) (xy 111.103921 -256.3876)
			(xy 110.841814 -256.3876) (xy 110.837972 -256.43886) (xy 110.826533 -256.488975) (xy 110.807752 -256.536825)
			(xy 110.782049 -256.581342) (xy 110.749998 -256.62153) (xy 110.712315 -256.656492) (xy 110.669842 -256.685447)
			(xy 110.623527 -256.707747) (xy 110.574406 -256.722896) (xy 110.523576 -256.730554) (xy 110.497874 -256.731008)
			(xy 110.472472 -256.730548) (xy 110.422223 -256.723059) (xy 110.373626 -256.708249) (xy 110.327741 -256.686441)
			(xy 110.28557 -256.658111) (xy 110.26648 -256.641346) (xy 110.266226 -256.641092) (xy 110.260586 -256.63632)
			(xy 110.247303 -256.629868) (xy 110.240064 -256.628392) (xy 110.233206 -256.627376) (xy 110.218728 -256.629154)
			(xy 110.19536 -256.639314) (xy 110.126526 -256.669794) (xy 110.125764 -256.670048) (xy 110.117351 -256.67434)
			(xy 110.104238 -256.687917) (xy 110.096952 -256.705328) (xy 110.0963 -256.714752) (xy 110.0963 -257.74523)
			(xy 110.988351 -257.74523) (xy 110.992381 -257.692732) (xy 111.004378 -257.641464) (xy 111.024061 -257.592629)
			(xy 111.050967 -257.54737) (xy 111.084467 -257.506749) (xy 111.123775 -257.471718) (xy 111.16797 -257.443098)
			(xy 111.216015 -257.421559) (xy 111.266786 -257.407607) (xy 111.319091 -257.401569) (xy 111.371705 -257.403586)
			(xy 111.423395 -257.41361) (xy 111.472948 -257.431408) (xy 111.519204 -257.456561) (xy 111.561078 -257.48848)
			(xy 111.59759 -257.526418) (xy 111.627882 -257.569484) (xy 111.651245 -257.616669) (xy 111.667131 -257.666868)
			(xy 111.675168 -257.718904) (xy 111.675672 -257.74523) (xy 113.238283 -257.74523) (xy 113.242313 -257.692732)
			(xy 113.25431 -257.641464) (xy 113.273993 -257.592629) (xy 113.300899 -257.54737) (xy 113.334399 -257.506749)
			(xy 113.373707 -257.471718) (xy 113.417902 -257.443098) (xy 113.465947 -257.421559) (xy 113.516718 -257.407607)
			(xy 113.569023 -257.401569) (xy 113.621637 -257.403586) (xy 113.673327 -257.41361) (xy 113.72288 -257.431408)
			(xy 113.769136 -257.456561) (xy 113.81101 -257.48848) (xy 113.847522 -257.526418) (xy 113.877814 -257.569484)
			(xy 113.901177 -257.616669) (xy 113.917063 -257.666868) (xy 113.9251 -257.718904) (xy 113.925604 -257.74523)
			(xy 115.838227 -257.74523) (xy 115.842257 -257.692732) (xy 115.854254 -257.641464) (xy 115.873937 -257.592629)
			(xy 115.900843 -257.54737) (xy 115.934343 -257.506749) (xy 115.973651 -257.471718) (xy 116.017846 -257.443098)
			(xy 116.065891 -257.421559) (xy 116.116662 -257.407607) (xy 116.168967 -257.401569) (xy 116.221581 -257.403586)
			(xy 116.273271 -257.41361) (xy 116.319656 -257.43027) (xy 117.096797 -257.43027) (xy 117.100827 -257.377772)
			(xy 117.112824 -257.326504) (xy 117.132507 -257.277669) (xy 117.159413 -257.23241) (xy 117.192913 -257.191789)
			(xy 117.232221 -257.156758) (xy 117.276416 -257.128138) (xy 117.324461 -257.106599) (xy 117.375232 -257.092647)
			(xy 117.427537 -257.086609) (xy 117.480151 -257.088626) (xy 117.531841 -257.09865) (xy 117.581394 -257.116448)
			(xy 117.62765 -257.141601) (xy 117.669524 -257.17352) (xy 117.706036 -257.211458) (xy 117.736328 -257.254524)
			(xy 117.759691 -257.301709) (xy 117.775577 -257.351908) (xy 117.783614 -257.403944) (xy 117.784118 -257.43027)
			(xy 117.783614 -257.456596) (xy 117.775577 -257.508632) (xy 117.759691 -257.558831) (xy 117.736328 -257.606016)
			(xy 117.706036 -257.649082) (xy 117.669524 -257.68702) (xy 117.62765 -257.718939) (xy 117.581394 -257.744092)
			(xy 117.531841 -257.76189) (xy 117.480151 -257.771914) (xy 117.427537 -257.773931) (xy 117.375232 -257.767893)
			(xy 117.324461 -257.753941) (xy 117.276416 -257.732402) (xy 117.232221 -257.703782) (xy 117.192913 -257.668751)
			(xy 117.159413 -257.62813) (xy 117.132507 -257.582871) (xy 117.112824 -257.534036) (xy 117.100827 -257.482768)
			(xy 117.096797 -257.43027) (xy 116.319656 -257.43027) (xy 116.322824 -257.431408) (xy 116.36908 -257.456561)
			(xy 116.410954 -257.48848) (xy 116.447466 -257.526418) (xy 116.477758 -257.569484) (xy 116.501121 -257.616669)
			(xy 116.517007 -257.666868) (xy 116.525044 -257.718904) (xy 116.525548 -257.74523) (xy 116.525044 -257.771556)
			(xy 116.517007 -257.823592) (xy 116.501121 -257.873791) (xy 116.477758 -257.920976) (xy 116.471132 -257.930396)
			(xy 120.865649 -257.930396) (xy 120.869679 -257.877898) (xy 120.881676 -257.82663) (xy 120.901359 -257.777795)
			(xy 120.928265 -257.732536) (xy 120.961765 -257.691915) (xy 121.001073 -257.656884) (xy 121.045268 -257.628264)
			(xy 121.093313 -257.606725) (xy 121.144084 -257.592773) (xy 121.196389 -257.586735) (xy 121.249003 -257.588752)
			(xy 121.300693 -257.598776) (xy 121.350246 -257.616574) (xy 121.396502 -257.641727) (xy 121.438376 -257.673646)
			(xy 121.474888 -257.711584) (xy 121.50518 -257.75465) (xy 121.528543 -257.801835) (xy 121.544429 -257.852034)
			(xy 121.552466 -257.90407) (xy 121.55297 -257.930396) (xy 122.791223 -257.930396) (xy 122.795253 -257.877898)
			(xy 122.80725 -257.82663) (xy 122.826933 -257.777795) (xy 122.853839 -257.732536) (xy 122.887339 -257.691915)
			(xy 122.926647 -257.656884) (xy 122.970842 -257.628264) (xy 123.018887 -257.606725) (xy 123.069658 -257.592773)
			(xy 123.121963 -257.586735) (xy 123.174577 -257.588752) (xy 123.226267 -257.598776) (xy 123.27582 -257.616574)
			(xy 123.322076 -257.641727) (xy 123.36395 -257.673646) (xy 123.400462 -257.711584) (xy 123.430754 -257.75465)
			(xy 123.454117 -257.801835) (xy 123.470003 -257.852034) (xy 123.47804 -257.90407) (xy 123.478544 -257.930396)
			(xy 124.696223 -257.930396) (xy 124.700253 -257.877898) (xy 124.71225 -257.82663) (xy 124.731933 -257.777795)
			(xy 124.758839 -257.732536) (xy 124.792339 -257.691915) (xy 124.831647 -257.656884) (xy 124.875842 -257.628264)
			(xy 124.923887 -257.606725) (xy 124.974658 -257.592773) (xy 125.026963 -257.586735) (xy 125.079577 -257.588752)
			(xy 125.131267 -257.598776) (xy 125.18082 -257.616574) (xy 125.227076 -257.641727) (xy 125.26895 -257.673646)
			(xy 125.305462 -257.711584) (xy 125.335754 -257.75465) (xy 125.359117 -257.801835) (xy 125.375003 -257.852034)
			(xy 125.38304 -257.90407) (xy 125.383544 -257.930396) (xy 125.38304 -257.956722) (xy 125.375003 -258.008758)
			(xy 125.359117 -258.058957) (xy 125.335754 -258.106142) (xy 125.305462 -258.149208) (xy 125.26895 -258.187146)
			(xy 125.227076 -258.219065) (xy 125.18082 -258.244218) (xy 125.131267 -258.262016) (xy 125.079577 -258.27204)
			(xy 125.026963 -258.274057) (xy 124.974658 -258.268019) (xy 124.923887 -258.254067) (xy 124.875842 -258.232528)
			(xy 124.831647 -258.203908) (xy 124.792339 -258.168877) (xy 124.758839 -258.128256) (xy 124.731933 -258.082997)
			(xy 124.71225 -258.034162) (xy 124.700253 -257.982894) (xy 124.696223 -257.930396) (xy 123.478544 -257.930396)
			(xy 123.47804 -257.956722) (xy 123.470003 -258.008758) (xy 123.454117 -258.058957) (xy 123.430754 -258.106142)
			(xy 123.400462 -258.149208) (xy 123.36395 -258.187146) (xy 123.322076 -258.219065) (xy 123.27582 -258.244218)
			(xy 123.226267 -258.262016) (xy 123.174577 -258.27204) (xy 123.121963 -258.274057) (xy 123.069658 -258.268019)
			(xy 123.018887 -258.254067) (xy 122.970842 -258.232528) (xy 122.926647 -258.203908) (xy 122.887339 -258.168877)
			(xy 122.853839 -258.128256) (xy 122.826933 -258.082997) (xy 122.80725 -258.034162) (xy 122.795253 -257.982894)
			(xy 122.791223 -257.930396) (xy 121.55297 -257.930396) (xy 121.552466 -257.956722) (xy 121.544429 -258.008758)
			(xy 121.528543 -258.058957) (xy 121.50518 -258.106142) (xy 121.474888 -258.149208) (xy 121.438376 -258.187146)
			(xy 121.396502 -258.219065) (xy 121.350246 -258.244218) (xy 121.300693 -258.262016) (xy 121.249003 -258.27204)
			(xy 121.196389 -258.274057) (xy 121.144084 -258.268019) (xy 121.093313 -258.254067) (xy 121.045268 -258.232528)
			(xy 121.001073 -258.203908) (xy 120.961765 -258.168877) (xy 120.928265 -258.128256) (xy 120.901359 -258.082997)
			(xy 120.881676 -258.034162) (xy 120.869679 -257.982894) (xy 120.865649 -257.930396) (xy 116.471132 -257.930396)
			(xy 116.447466 -257.964042) (xy 116.410954 -258.00198) (xy 116.36908 -258.033899) (xy 116.322824 -258.059052)
			(xy 116.273271 -258.07685) (xy 116.221581 -258.086874) (xy 116.168967 -258.088891) (xy 116.116662 -258.082853)
			(xy 116.065891 -258.068901) (xy 116.017846 -258.047362) (xy 115.973651 -258.018742) (xy 115.934343 -257.983711)
			(xy 115.900843 -257.94309) (xy 115.873937 -257.897831) (xy 115.854254 -257.848996) (xy 115.842257 -257.797728)
			(xy 115.838227 -257.74523) (xy 113.925604 -257.74523) (xy 113.9251 -257.771556) (xy 113.917063 -257.823592)
			(xy 113.901177 -257.873791) (xy 113.877814 -257.920976) (xy 113.847522 -257.964042) (xy 113.81101 -258.00198)
			(xy 113.769136 -258.033899) (xy 113.72288 -258.059052) (xy 113.673327 -258.07685) (xy 113.621637 -258.086874)
			(xy 113.569023 -258.088891) (xy 113.516718 -258.082853) (xy 113.465947 -258.068901) (xy 113.417902 -258.047362)
			(xy 113.373707 -258.018742) (xy 113.334399 -257.983711) (xy 113.300899 -257.94309) (xy 113.273993 -257.897831)
			(xy 113.25431 -257.848996) (xy 113.242313 -257.797728) (xy 113.238283 -257.74523) (xy 111.675672 -257.74523)
			(xy 111.675168 -257.771556) (xy 111.667131 -257.823592) (xy 111.651245 -257.873791) (xy 111.627882 -257.920976)
			(xy 111.59759 -257.964042) (xy 111.561078 -258.00198) (xy 111.519204 -258.033899) (xy 111.472948 -258.059052)
			(xy 111.423395 -258.07685) (xy 111.371705 -258.086874) (xy 111.319091 -258.088891) (xy 111.266786 -258.082853)
			(xy 111.216015 -258.068901) (xy 111.16797 -258.047362) (xy 111.123775 -258.018742) (xy 111.084467 -257.983711)
			(xy 111.050967 -257.94309) (xy 111.024061 -257.897831) (xy 111.004378 -257.848996) (xy 110.992381 -257.797728)
			(xy 110.988351 -257.74523) (xy 110.0963 -257.74523) (xy 110.0963 -258.125722) (xy 110.097316 -258.135374)
			(xy 110.098946 -258.142617) (xy 110.10579 -258.155783) (xy 110.110778 -258.161282) (xy 110.168182 -258.218686)
			(xy 110.173678 -258.22368) (xy 110.186842 -258.230537) (xy 110.19409 -258.232148) (xy 110.203742 -258.233164)
			(xy 111.00689 -258.233164) (xy 111.016727 -258.233703) (xy 111.034886 -258.241291) (xy 111.042196 -258.247896)
			(xy 111.17453 -258.38023) (xy 117.096797 -258.38023) (xy 117.100827 -258.327732) (xy 117.112824 -258.276464)
			(xy 117.132507 -258.227629) (xy 117.159413 -258.18237) (xy 117.192913 -258.141749) (xy 117.232221 -258.106718)
			(xy 117.276416 -258.078098) (xy 117.324461 -258.056559) (xy 117.375232 -258.042607) (xy 117.427537 -258.036569)
			(xy 117.480151 -258.038586) (xy 117.531841 -258.04861) (xy 117.581394 -258.066408) (xy 117.62765 -258.091561)
			(xy 117.669524 -258.12348) (xy 117.706036 -258.161418) (xy 117.736328 -258.204484) (xy 117.759691 -258.251669)
			(xy 117.775577 -258.301868) (xy 117.783614 -258.353904) (xy 117.784118 -258.38023) (xy 117.783614 -258.406556)
			(xy 117.775577 -258.458592) (xy 117.759691 -258.508791) (xy 117.736328 -258.555976) (xy 117.706036 -258.599042)
			(xy 117.669524 -258.63698) (xy 117.62765 -258.668899) (xy 117.581394 -258.694052) (xy 117.531841 -258.71185)
			(xy 117.480151 -258.721874) (xy 117.427537 -258.723891) (xy 117.375232 -258.717853) (xy 117.324461 -258.703901)
			(xy 117.276416 -258.682362) (xy 117.232221 -258.653742) (xy 117.192913 -258.618711) (xy 117.159413 -258.57809)
			(xy 117.132507 -258.532831) (xy 117.112824 -258.483996) (xy 117.100827 -258.432728) (xy 117.096797 -258.38023)
			(xy 111.17453 -258.38023) (xy 111.235998 -258.441698) (xy 111.240348 -258.445872) (xy 111.25062 -258.452177)
			(xy 111.256318 -258.454144) (xy 111.267494 -258.4577) (xy 111.279432 -258.455922) (xy 111.292431 -258.454035)
			(xy 111.318622 -258.452001) (xy 111.331756 -258.451858) (xy 111.334042 -258.451858) (xy 111.36085 -258.452509)
			(xy 111.413777 -258.461111) (xy 111.464724 -258.477834) (xy 111.512453 -258.502272) (xy 111.555804 -258.53383)
			(xy 111.593724 -258.571742) (xy 111.625291 -258.615087) (xy 111.649738 -258.662811) (xy 111.666472 -258.713755)
			(xy 111.675085 -258.76668) (xy 111.675672 -258.793488) (xy 111.675672 -258.795774) (xy 111.67554 -258.808909)
			(xy 111.673503 -258.8351) (xy 111.671608 -258.848098) (xy 111.66983 -258.860036) (xy 111.673386 -258.871212)
			(xy 111.675429 -258.876875) (xy 111.681713 -258.887142) (xy 111.685832 -258.891532) (xy 111.851186 -259.056886)
			(xy 111.856682 -259.061879) (xy 111.869847 -259.068735) (xy 111.877094 -259.070348) (xy 111.886746 -259.071364)
			(xy 113.17478 -259.071364) (xy 113.187337 -259.070725) (xy 113.209475 -259.058871) (xy 113.216944 -259.048758)
			(xy 113.232946 -259.024628) (xy 113.262664 -258.979416) (xy 113.266044 -258.974116) (xy 113.270293 -258.962289)
			(xy 113.271046 -258.956048) (xy 113.272062 -258.943348) (xy 113.266982 -258.931664) (xy 113.266982 -258.93141)
			(xy 113.258106 -258.909864) (xy 113.245581 -258.864981) (xy 113.239219 -258.818818) (xy 113.238788 -258.79552)
			(xy 113.238788 -258.790694) (xy 113.239656 -258.763944) (xy 113.248661 -258.711188) (xy 113.26574 -258.660468)
			(xy 113.29048 -258.613011) (xy 113.322282 -258.569967) (xy 113.360377 -258.532376) (xy 113.403841 -258.50115)
			(xy 113.451623 -258.477043) (xy 113.502566 -258.460641) (xy 113.555437 -258.452339) (xy 113.608955 -258.452339)
			(xy 113.661826 -258.460641) (xy 113.712769 -258.477043) (xy 113.760551 -258.50115) (xy 113.804015 -258.532376)
			(xy 113.84211 -258.569967) (xy 113.873912 -258.613011) (xy 113.898652 -258.660468) (xy 113.915731 -258.711188)
			(xy 113.924736 -258.763944) (xy 113.925604 -258.790694) (xy 113.925604 -258.795266) (xy 113.925236 -258.818559)
			(xy 113.918976 -258.864721) (xy 113.906526 -258.909612) (xy 113.897664 -258.931156) (xy 113.893092 -258.941316)
			(xy 113.892584 -258.94284) (xy 113.8936 -258.955286) (xy 113.894346 -258.961501) (xy 113.898451 -258.973321)
			(xy 113.901728 -258.978654) (xy 113.94821 -259.049774) (xy 113.954811 -259.058328) (xy 113.973359 -259.069373)
			(xy 113.984024 -259.07111) (xy 113.989866 -259.071364) (xy 115.774724 -259.071364) (xy 115.787276 -259.070716)
			(xy 115.809397 -259.058851) (xy 115.816888 -259.048758) (xy 115.83289 -259.024628) (xy 115.862608 -258.979416)
			(xy 115.865991 -258.974117) (xy 115.870245 -258.96229) (xy 115.87099 -258.956048) (xy 115.872006 -258.943348)
			(xy 115.866926 -258.931664) (xy 115.866926 -258.93141) (xy 115.858049 -258.909864) (xy 115.845522 -258.864981)
			(xy 115.839159 -258.818819) (xy 115.838732 -258.79552) (xy 115.838732 -258.790694) (xy 115.8396 -258.763944)
			(xy 115.848605 -258.711188) (xy 115.865684 -258.660468) (xy 115.890424 -258.613011) (xy 115.922226 -258.569967)
			(xy 115.960321 -258.532376) (xy 116.003785 -258.50115) (xy 116.051567 -258.477043) (xy 116.10251 -258.460641)
			(xy 116.155381 -258.452339) (xy 116.208899 -258.452339) (xy 116.26177 -258.460641) (xy 116.312713 -258.477043)
			(xy 116.360495 -258.50115) (xy 116.403959 -258.532376) (xy 116.442054 -258.569967) (xy 116.473856 -258.613011)
			(xy 116.498596 -258.660468) (xy 116.515675 -258.711188) (xy 116.52468 -258.763944) (xy 116.525548 -258.790694)
			(xy 116.525548 -258.794758) (xy 116.525208 -258.818188) (xy 116.523561 -258.830318) (xy 120.865649 -258.830318)
			(xy 120.869679 -258.77782) (xy 120.881676 -258.726552) (xy 120.901359 -258.677717) (xy 120.928265 -258.632458)
			(xy 120.961765 -258.591837) (xy 121.001073 -258.556806) (xy 121.045268 -258.528186) (xy 121.093313 -258.506647)
			(xy 121.144084 -258.492695) (xy 121.196389 -258.486657) (xy 121.249003 -258.488674) (xy 121.300693 -258.498698)
			(xy 121.350246 -258.516496) (xy 121.396502 -258.541649) (xy 121.438376 -258.573568) (xy 121.474888 -258.611506)
			(xy 121.50518 -258.654572) (xy 121.528543 -258.701757) (xy 121.544429 -258.751956) (xy 121.552466 -258.803992)
			(xy 121.55297 -258.830318) (xy 122.791223 -258.830318) (xy 122.795253 -258.77782) (xy 122.80725 -258.726552)
			(xy 122.826933 -258.677717) (xy 122.853839 -258.632458) (xy 122.887339 -258.591837) (xy 122.926647 -258.556806)
			(xy 122.970842 -258.528186) (xy 123.018887 -258.506647) (xy 123.069658 -258.492695) (xy 123.121963 -258.486657)
			(xy 123.174577 -258.488674) (xy 123.226267 -258.498698) (xy 123.27582 -258.516496) (xy 123.322076 -258.541649)
			(xy 123.36395 -258.573568) (xy 123.400462 -258.611506) (xy 123.430754 -258.654572) (xy 123.454117 -258.701757)
			(xy 123.470003 -258.751956) (xy 123.47804 -258.803992) (xy 123.478544 -258.830318) (xy 124.696223 -258.830318)
			(xy 124.700253 -258.77782) (xy 124.71225 -258.726552) (xy 124.731933 -258.677717) (xy 124.758839 -258.632458)
			(xy 124.792339 -258.591837) (xy 124.831647 -258.556806) (xy 124.875842 -258.528186) (xy 124.923887 -258.506647)
			(xy 124.974658 -258.492695) (xy 125.026963 -258.486657) (xy 125.079577 -258.488674) (xy 125.131267 -258.498698)
			(xy 125.18082 -258.516496) (xy 125.227076 -258.541649) (xy 125.26895 -258.573568) (xy 125.305462 -258.611506)
			(xy 125.335754 -258.654572) (xy 125.359117 -258.701757) (xy 125.375003 -258.751956) (xy 125.38304 -258.803992)
			(xy 125.383544 -258.830318) (xy 125.38304 -258.856644) (xy 125.375003 -258.90868) (xy 125.359117 -258.958879)
			(xy 125.335754 -259.006064) (xy 125.305462 -259.04913) (xy 125.26895 -259.087068) (xy 125.227076 -259.118987)
			(xy 125.18082 -259.14414) (xy 125.131267 -259.161938) (xy 125.079577 -259.171962) (xy 125.026963 -259.173979)
			(xy 124.974658 -259.167941) (xy 124.923887 -259.153989) (xy 124.875842 -259.13245) (xy 124.831647 -259.10383)
			(xy 124.792339 -259.068799) (xy 124.758839 -259.028178) (xy 124.731933 -258.982919) (xy 124.71225 -258.934084)
			(xy 124.700253 -258.882816) (xy 124.696223 -258.830318) (xy 123.478544 -258.830318) (xy 123.47804 -258.856644)
			(xy 123.470003 -258.90868) (xy 123.454117 -258.958879) (xy 123.430754 -259.006064) (xy 123.400462 -259.04913)
			(xy 123.36395 -259.087068) (xy 123.322076 -259.118987) (xy 123.27582 -259.14414) (xy 123.226267 -259.161938)
			(xy 123.174577 -259.171962) (xy 123.121963 -259.173979) (xy 123.069658 -259.167941) (xy 123.018887 -259.153989)
			(xy 122.970842 -259.13245) (xy 122.926647 -259.10383) (xy 122.887339 -259.068799) (xy 122.853839 -259.028178)
			(xy 122.826933 -258.982919) (xy 122.80725 -258.934084) (xy 122.795253 -258.882816) (xy 122.791223 -258.830318)
			(xy 121.55297 -258.830318) (xy 121.552466 -258.856644) (xy 121.544429 -258.90868) (xy 121.528543 -258.958879)
			(xy 121.50518 -259.006064) (xy 121.474888 -259.04913) (xy 121.438376 -259.087068) (xy 121.396502 -259.118987)
			(xy 121.350246 -259.14414) (xy 121.300693 -259.161938) (xy 121.249003 -259.171962) (xy 121.196389 -259.173979)
			(xy 121.144084 -259.167941) (xy 121.093313 -259.153989) (xy 121.045268 -259.13245) (xy 121.001073 -259.10383)
			(xy 120.961765 -259.068799) (xy 120.928265 -259.028178) (xy 120.901359 -258.982919) (xy 120.881676 -258.934084)
			(xy 120.869679 -258.882816) (xy 120.865649 -258.830318) (xy 116.523561 -258.830318) (xy 116.518902 -258.864622)
			(xy 116.50632 -258.90976) (xy 116.497354 -258.93141) (xy 116.497354 -258.931664) (xy 116.495091 -258.937482)
			(xy 116.493174 -258.949815) (xy 116.493544 -258.956048) (xy 116.49456 -258.968494) (xy 116.50345 -258.981956)
			(xy 116.50345 -258.982464) (xy 116.53901 -259.036312) (xy 116.542834 -259.04252) (xy 116.547089 -259.056459)
			(xy 116.547392 -259.063744) (xy 116.547392 -259.330444) (xy 117.096797 -259.330444) (xy 117.100827 -259.277946)
			(xy 117.112824 -259.226678) (xy 117.132507 -259.177843) (xy 117.159413 -259.132584) (xy 117.192913 -259.091963)
			(xy 117.232221 -259.056932) (xy 117.276416 -259.028312) (xy 117.324461 -259.006773) (xy 117.375232 -258.992821)
			(xy 117.427537 -258.986783) (xy 117.480151 -258.9888) (xy 117.531841 -258.998824) (xy 117.581394 -259.016622)
			(xy 117.62765 -259.041775) (xy 117.669524 -259.073694) (xy 117.706036 -259.111632) (xy 117.736328 -259.154698)
			(xy 117.759691 -259.201883) (xy 117.775577 -259.252082) (xy 117.783614 -259.304118) (xy 117.784118 -259.330444)
			(xy 117.783614 -259.35677) (xy 117.775577 -259.408806) (xy 117.759691 -259.459005) (xy 117.736328 -259.50619)
			(xy 117.706036 -259.549256) (xy 117.669524 -259.587194) (xy 117.62765 -259.619113) (xy 117.581394 -259.644266)
			(xy 117.531841 -259.662064) (xy 117.480151 -259.672088) (xy 117.427537 -259.674105) (xy 117.375232 -259.668067)
			(xy 117.324461 -259.654115) (xy 117.276416 -259.632576) (xy 117.232221 -259.603956) (xy 117.192913 -259.568925)
			(xy 117.159413 -259.528304) (xy 117.132507 -259.483045) (xy 117.112824 -259.43421) (xy 117.100827 -259.382942)
			(xy 117.096797 -259.330444) (xy 116.547392 -259.330444) (xy 116.547392 -259.73024) (xy 120.865649 -259.73024)
			(xy 120.869679 -259.677742) (xy 120.881676 -259.626474) (xy 120.901359 -259.577639) (xy 120.928265 -259.53238)
			(xy 120.961765 -259.491759) (xy 121.001073 -259.456728) (xy 121.045268 -259.428108) (xy 121.093313 -259.406569)
			(xy 121.144084 -259.392617) (xy 121.196389 -259.386579) (xy 121.249003 -259.388596) (xy 121.300693 -259.39862)
			(xy 121.350246 -259.416418) (xy 121.396502 -259.441571) (xy 121.438376 -259.47349) (xy 121.474888 -259.511428)
			(xy 121.50518 -259.554494) (xy 121.528543 -259.601679) (xy 121.544429 -259.651878) (xy 121.552466 -259.703914)
			(xy 121.55297 -259.73024) (xy 122.791223 -259.73024) (xy 122.795253 -259.677742) (xy 122.80725 -259.626474)
			(xy 122.826933 -259.577639) (xy 122.853839 -259.53238) (xy 122.887339 -259.491759) (xy 122.926647 -259.456728)
			(xy 122.970842 -259.428108) (xy 123.018887 -259.406569) (xy 123.069658 -259.392617) (xy 123.121963 -259.386579)
			(xy 123.174577 -259.388596) (xy 123.226267 -259.39862) (xy 123.27582 -259.416418) (xy 123.322076 -259.441571)
			(xy 123.36395 -259.47349) (xy 123.400462 -259.511428) (xy 123.430754 -259.554494) (xy 123.454117 -259.601679)
			(xy 123.470003 -259.651878) (xy 123.47804 -259.703914) (xy 123.478544 -259.73024) (xy 124.696223 -259.73024)
			(xy 124.700253 -259.677742) (xy 124.71225 -259.626474) (xy 124.731933 -259.577639) (xy 124.758839 -259.53238)
			(xy 124.792339 -259.491759) (xy 124.831647 -259.456728) (xy 124.875842 -259.428108) (xy 124.923887 -259.406569)
			(xy 124.974658 -259.392617) (xy 125.026963 -259.386579) (xy 125.079577 -259.388596) (xy 125.131267 -259.39862)
			(xy 125.18082 -259.416418) (xy 125.227076 -259.441571) (xy 125.26895 -259.47349) (xy 125.305462 -259.511428)
			(xy 125.335754 -259.554494) (xy 125.359117 -259.601679) (xy 125.375003 -259.651878) (xy 125.38304 -259.703914)
			(xy 125.383544 -259.73024) (xy 125.38304 -259.756566) (xy 125.375003 -259.808602) (xy 125.359117 -259.858801)
			(xy 125.335754 -259.905986) (xy 125.305462 -259.949052) (xy 125.26895 -259.98699) (xy 125.227076 -260.018909)
			(xy 125.18082 -260.044062) (xy 125.131267 -260.06186) (xy 125.079577 -260.071884) (xy 125.026963 -260.073901)
			(xy 124.974658 -260.067863) (xy 124.923887 -260.053911) (xy 124.875842 -260.032372) (xy 124.831647 -260.003752)
			(xy 124.792339 -259.968721) (xy 124.758839 -259.9281) (xy 124.731933 -259.882841) (xy 124.71225 -259.834006)
			(xy 124.700253 -259.782738) (xy 124.696223 -259.73024) (xy 123.478544 -259.73024) (xy 123.47804 -259.756566)
			(xy 123.470003 -259.808602) (xy 123.454117 -259.858801) (xy 123.430754 -259.905986) (xy 123.400462 -259.949052)
			(xy 123.36395 -259.98699) (xy 123.322076 -260.018909) (xy 123.27582 -260.044062) (xy 123.226267 -260.06186)
			(xy 123.174577 -260.071884) (xy 123.121963 -260.073901) (xy 123.069658 -260.067863) (xy 123.018887 -260.053911)
			(xy 122.970842 -260.032372) (xy 122.926647 -260.003752) (xy 122.887339 -259.968721) (xy 122.853839 -259.9281)
			(xy 122.826933 -259.882841) (xy 122.80725 -259.834006) (xy 122.795253 -259.782738) (xy 122.791223 -259.73024)
			(xy 121.55297 -259.73024) (xy 121.552466 -259.756566) (xy 121.544429 -259.808602) (xy 121.528543 -259.858801)
			(xy 121.50518 -259.905986) (xy 121.474888 -259.949052) (xy 121.438376 -259.98699) (xy 121.396502 -260.018909)
			(xy 121.350246 -260.044062) (xy 121.300693 -260.06186) (xy 121.249003 -260.071884) (xy 121.196389 -260.073901)
			(xy 121.144084 -260.067863) (xy 121.093313 -260.053911) (xy 121.045268 -260.032372) (xy 121.001073 -260.003752)
			(xy 120.961765 -259.968721) (xy 120.928265 -259.9281) (xy 120.901359 -259.882841) (xy 120.881676 -259.834006)
			(xy 120.869679 -259.782738) (xy 120.865649 -259.73024) (xy 116.547392 -259.73024) (xy 116.547392 -260.280404)
			(xy 117.096797 -260.280404) (xy 117.100827 -260.227906) (xy 117.112824 -260.176638) (xy 117.132507 -260.127803)
			(xy 117.159413 -260.082544) (xy 117.192913 -260.041923) (xy 117.232221 -260.006892) (xy 117.276416 -259.978272)
			(xy 117.324461 -259.956733) (xy 117.375232 -259.942781) (xy 117.427537 -259.936743) (xy 117.480151 -259.93876)
			(xy 117.531841 -259.948784) (xy 117.581394 -259.966582) (xy 117.62765 -259.991735) (xy 117.669524 -260.023654)
			(xy 117.706036 -260.061592) (xy 117.736328 -260.104658) (xy 117.759691 -260.151843) (xy 117.775577 -260.202042)
			(xy 117.783614 -260.254078) (xy 117.784118 -260.280404) (xy 117.783614 -260.30673) (xy 117.775577 -260.358766)
			(xy 117.759691 -260.408965) (xy 117.736328 -260.45615) (xy 117.706036 -260.499216) (xy 117.669524 -260.537154)
			(xy 117.62765 -260.569073) (xy 117.581394 -260.594226) (xy 117.531841 -260.612024) (xy 117.480151 -260.622048)
			(xy 117.427537 -260.624065) (xy 117.375232 -260.618027) (xy 117.324461 -260.604075) (xy 117.276416 -260.582536)
			(xy 117.232221 -260.553916) (xy 117.192913 -260.518885) (xy 117.159413 -260.478264) (xy 117.132507 -260.433005)
			(xy 117.112824 -260.38417) (xy 117.100827 -260.332902) (xy 117.096797 -260.280404) (xy 116.547392 -260.280404)
			(xy 116.547392 -261.297928) (xy 116.548408 -261.30758) (xy 116.550038 -261.314823) (xy 116.556883 -261.327989)
			(xy 116.56187 -261.333488) (xy 116.802916 -261.574534) (xy 116.808416 -261.57952) (xy 116.821583 -261.586362)
			(xy 116.828824 -261.587996) (xy 116.838476 -261.589012) (xy 117.080284 -261.589012) (xy 117.084348 -261.588758)
			(xy 117.096752 -261.587129) (xy 117.11782 -261.573692) (xy 117.12448 -261.563104) (xy 117.153182 -261.506716)
			(xy 117.153182 -261.506208) (xy 117.16385 -261.485888) (xy 117.168103 -261.476769) (xy 117.169801 -261.456734)
			(xy 117.167152 -261.447026) (xy 117.161818 -261.431024) (xy 117.157754 -261.424928) (xy 117.143486 -261.403344)
			(xy 117.120902 -261.356795) (xy 117.105554 -261.307385) (xy 117.097787 -261.256233) (xy 117.097302 -261.230364)
			(xy 117.097782 -261.204665) (xy 117.105443 -261.153841) (xy 117.120592 -261.104727) (xy 117.142893 -261.058419)
			(xy 117.171846 -261.015952) (xy 117.206806 -260.978275) (xy 117.24699 -260.946229) (xy 117.291502 -260.92053)
			(xy 117.339347 -260.901753) (xy 117.389456 -260.890315) (xy 117.44071 -260.886475) (xy 117.491964 -260.890315)
			(xy 117.542073 -260.901753) (xy 117.589918 -260.92053) (xy 117.63443 -260.946229) (xy 117.674614 -260.978275)
			(xy 117.709574 -261.015952) (xy 117.738527 -261.058419) (xy 117.760828 -261.104727) (xy 117.767459 -261.126224)
			(xy 121.638834 -261.126224) (xy 121.642794 -261.07717) (xy 121.654571 -261.029386) (xy 121.673862 -260.98411)
			(xy 121.700165 -260.942514) (xy 121.7328 -260.905677) (xy 121.770921 -260.874552) (xy 121.813542 -260.849945)
			(xy 121.859558 -260.832493) (xy 121.907777 -260.822649) (xy 121.956952 -260.820668) (xy 122.005807 -260.8266)
			(xy 122.053078 -260.840292) (xy 122.09754 -260.86139) (xy 122.138043 -260.889346) (xy 122.173536 -260.923438)
			(xy 122.203101 -260.962782) (xy 122.225972 -261.006359) (xy 122.241556 -261.05304) (xy 122.249451 -261.101617)
			(xy 122.249946 -261.126224) (xy 123.518942 -261.126224) (xy 123.522902 -261.07717) (xy 123.534679 -261.029386)
			(xy 123.55397 -260.98411) (xy 123.580273 -260.942514) (xy 123.612908 -260.905677) (xy 123.651029 -260.874552)
			(xy 123.69365 -260.849945) (xy 123.739666 -260.832493) (xy 123.787885 -260.822649) (xy 123.83706 -260.820668)
			(xy 123.885915 -260.8266) (xy 123.933186 -260.840292) (xy 123.977648 -260.86139) (xy 124.018151 -260.889346)
			(xy 124.053644 -260.923438) (xy 124.083209 -260.962782) (xy 124.10608 -261.006359) (xy 124.121664 -261.05304)
			(xy 124.129559 -261.101617) (xy 124.130054 -261.126224) (xy 125.39905 -261.126224) (xy 125.40301 -261.07717)
			(xy 125.414787 -261.029386) (xy 125.434078 -260.98411) (xy 125.460381 -260.942514) (xy 125.493016 -260.905677)
			(xy 125.531137 -260.874552) (xy 125.573758 -260.849945) (xy 125.619774 -260.832493) (xy 125.667993 -260.822649)
			(xy 125.717168 -260.820668) (xy 125.766023 -260.8266) (xy 125.813294 -260.840292) (xy 125.857756 -260.86139)
			(xy 125.898259 -260.889346) (xy 125.933752 -260.923438) (xy 125.963317 -260.962782) (xy 125.986188 -261.006359)
			(xy 126.001772 -261.05304) (xy 126.009667 -261.101617) (xy 126.010162 -261.126224) (xy 127.278904 -261.126224)
			(xy 127.282864 -261.07717) (xy 127.294641 -261.029386) (xy 127.313932 -260.98411) (xy 127.340235 -260.942514)
			(xy 127.37287 -260.905677) (xy 127.410991 -260.874552) (xy 127.453612 -260.849945) (xy 127.499628 -260.832493)
			(xy 127.547847 -260.822649) (xy 127.597022 -260.820668) (xy 127.645877 -260.8266) (xy 127.693148 -260.840292)
			(xy 127.73761 -260.86139) (xy 127.778113 -260.889346) (xy 127.813606 -260.923438) (xy 127.843171 -260.962782)
			(xy 127.866042 -261.006359) (xy 127.881626 -261.05304) (xy 127.889521 -261.101617) (xy 127.890016 -261.126224)
			(xy 128.218958 -261.126224) (xy 128.222918 -261.07717) (xy 128.234695 -261.029386) (xy 128.253986 -260.98411)
			(xy 128.280289 -260.942514) (xy 128.312924 -260.905677) (xy 128.351045 -260.874552) (xy 128.393666 -260.849945)
			(xy 128.439682 -260.832493) (xy 128.487901 -260.822649) (xy 128.537076 -260.820668) (xy 128.585931 -260.8266)
			(xy 128.633202 -260.840292) (xy 128.677664 -260.86139) (xy 128.718167 -260.889346) (xy 128.75366 -260.923438)
			(xy 128.783225 -260.962782) (xy 128.806096 -261.006359) (xy 128.82168 -261.05304) (xy 128.829575 -261.101617)
			(xy 128.83007 -261.126224) (xy 129.159012 -261.126224) (xy 129.162972 -261.07717) (xy 129.174749 -261.029386)
			(xy 129.19404 -260.98411) (xy 129.220343 -260.942514) (xy 129.252978 -260.905677) (xy 129.291099 -260.874552)
			(xy 129.33372 -260.849945) (xy 129.379736 -260.832493) (xy 129.427955 -260.822649) (xy 129.47713 -260.820668)
			(xy 129.525985 -260.8266) (xy 129.573256 -260.840292) (xy 129.617718 -260.86139) (xy 129.658221 -260.889346)
			(xy 129.693714 -260.923438) (xy 129.723279 -260.962782) (xy 129.74615 -261.006359) (xy 129.761734 -261.05304)
			(xy 129.769629 -261.101617) (xy 129.770124 -261.126224) (xy 130.099066 -261.126224) (xy 130.103026 -261.07717)
			(xy 130.114803 -261.029386) (xy 130.134094 -260.98411) (xy 130.160397 -260.942514) (xy 130.193032 -260.905677)
			(xy 130.231153 -260.874552) (xy 130.273774 -260.849945) (xy 130.31979 -260.832493) (xy 130.368009 -260.822649)
			(xy 130.417184 -260.820668) (xy 130.466039 -260.8266) (xy 130.51331 -260.840292) (xy 130.557772 -260.86139)
			(xy 130.598275 -260.889346) (xy 130.633768 -260.923438) (xy 130.663333 -260.962782) (xy 130.686204 -261.006359)
			(xy 130.701788 -261.05304) (xy 130.709683 -261.101617) (xy 130.710178 -261.126224) (xy 131.038866 -261.126224)
			(xy 131.042826 -261.07717) (xy 131.054603 -261.029386) (xy 131.073894 -260.98411) (xy 131.100197 -260.942514)
			(xy 131.132832 -260.905677) (xy 131.170953 -260.874552) (xy 131.213574 -260.849945) (xy 131.25959 -260.832493)
			(xy 131.307809 -260.822649) (xy 131.356984 -260.820668) (xy 131.405839 -260.8266) (xy 131.45311 -260.840292)
			(xy 131.497572 -260.86139) (xy 131.538075 -260.889346) (xy 131.573568 -260.923438) (xy 131.603133 -260.962782)
			(xy 131.626004 -261.006359) (xy 131.641588 -261.05304) (xy 131.649483 -261.101617) (xy 131.649978 -261.126224)
			(xy 131.97892 -261.126224) (xy 131.98288 -261.07717) (xy 131.994657 -261.029386) (xy 132.013948 -260.98411)
			(xy 132.040251 -260.942514) (xy 132.072886 -260.905677) (xy 132.111007 -260.874552) (xy 132.153628 -260.849945)
			(xy 132.199644 -260.832493) (xy 132.247863 -260.822649) (xy 132.297038 -260.820668) (xy 132.345893 -260.8266)
			(xy 132.393164 -260.840292) (xy 132.437626 -260.86139) (xy 132.478129 -260.889346) (xy 132.513622 -260.923438)
			(xy 132.543187 -260.962782) (xy 132.566058 -261.006359) (xy 132.581642 -261.05304) (xy 132.589537 -261.101617)
			(xy 132.590032 -261.126224) (xy 132.918974 -261.126224) (xy 132.922934 -261.07717) (xy 132.934711 -261.029386)
			(xy 132.954002 -260.98411) (xy 132.980305 -260.942514) (xy 133.01294 -260.905677) (xy 133.051061 -260.874552)
			(xy 133.093682 -260.849945) (xy 133.139698 -260.832493) (xy 133.187917 -260.822649) (xy 133.237092 -260.820668)
			(xy 133.285947 -260.8266) (xy 133.333218 -260.840292) (xy 133.37768 -260.86139) (xy 133.418183 -260.889346)
			(xy 133.453676 -260.923438) (xy 133.483241 -260.962782) (xy 133.506112 -261.006359) (xy 133.521696 -261.05304)
			(xy 133.529591 -261.101617) (xy 133.530086 -261.126224) (xy 133.859028 -261.126224) (xy 133.862988 -261.07717)
			(xy 133.874765 -261.029386) (xy 133.894056 -260.98411) (xy 133.920359 -260.942514) (xy 133.952994 -260.905677)
			(xy 133.991115 -260.874552) (xy 134.033736 -260.849945) (xy 134.079752 -260.832493) (xy 134.127971 -260.822649)
			(xy 134.177146 -260.820668) (xy 134.226001 -260.8266) (xy 134.273272 -260.840292) (xy 134.317734 -260.86139)
			(xy 134.358237 -260.889346) (xy 134.39373 -260.923438) (xy 134.423295 -260.962782) (xy 134.446166 -261.006359)
			(xy 134.46175 -261.05304) (xy 134.469645 -261.101617) (xy 134.47014 -261.126224) (xy 134.798828 -261.126224)
			(xy 134.802788 -261.07717) (xy 134.814565 -261.029386) (xy 134.833856 -260.98411) (xy 134.860159 -260.942514)
			(xy 134.892794 -260.905677) (xy 134.930915 -260.874552) (xy 134.973536 -260.849945) (xy 135.019552 -260.832493)
			(xy 135.067771 -260.822649) (xy 135.116946 -260.820668) (xy 135.165801 -260.8266) (xy 135.213072 -260.840292)
			(xy 135.257534 -260.86139) (xy 135.298037 -260.889346) (xy 135.33353 -260.923438) (xy 135.363095 -260.962782)
			(xy 135.385966 -261.006359) (xy 135.40155 -261.05304) (xy 135.409445 -261.101617) (xy 135.40994 -261.126224)
			(xy 135.738882 -261.126224) (xy 135.742842 -261.07717) (xy 135.754619 -261.029386) (xy 135.77391 -260.98411)
			(xy 135.800213 -260.942514) (xy 135.832848 -260.905677) (xy 135.870969 -260.874552) (xy 135.91359 -260.849945)
			(xy 135.959606 -260.832493) (xy 136.007825 -260.822649) (xy 136.057 -260.820668) (xy 136.105855 -260.8266)
			(xy 136.153126 -260.840292) (xy 136.197588 -260.86139) (xy 136.238091 -260.889346) (xy 136.273584 -260.923438)
			(xy 136.303149 -260.962782) (xy 136.32602 -261.006359) (xy 136.341604 -261.05304) (xy 136.349499 -261.101617)
			(xy 136.349994 -261.126224) (xy 136.678936 -261.126224) (xy 136.682896 -261.07717) (xy 136.694673 -261.029386)
			(xy 136.713964 -260.98411) (xy 136.740267 -260.942514) (xy 136.772902 -260.905677) (xy 136.811023 -260.874552)
			(xy 136.853644 -260.849945) (xy 136.89966 -260.832493) (xy 136.947879 -260.822649) (xy 136.997054 -260.820668)
			(xy 137.045909 -260.8266) (xy 137.09318 -260.840292) (xy 137.137642 -260.86139) (xy 137.178145 -260.889346)
			(xy 137.213638 -260.923438) (xy 137.243203 -260.962782) (xy 137.266074 -261.006359) (xy 137.281658 -261.05304)
			(xy 137.289553 -261.101617) (xy 137.290048 -261.126224) (xy 137.61899 -261.126224) (xy 137.62295 -261.07717)
			(xy 137.634727 -261.029386) (xy 137.654018 -260.98411) (xy 137.680321 -260.942514) (xy 137.712956 -260.905677)
			(xy 137.751077 -260.874552) (xy 137.793698 -260.849945) (xy 137.839714 -260.832493) (xy 137.887933 -260.822649)
			(xy 137.937108 -260.820668) (xy 137.985963 -260.8266) (xy 138.033234 -260.840292) (xy 138.077696 -260.86139)
			(xy 138.118199 -260.889346) (xy 138.153692 -260.923438) (xy 138.183257 -260.962782) (xy 138.206128 -261.006359)
			(xy 138.221712 -261.05304) (xy 138.229607 -261.101617) (xy 138.230102 -261.126224) (xy 138.559044 -261.126224)
			(xy 138.563004 -261.07717) (xy 138.574781 -261.029386) (xy 138.594072 -260.98411) (xy 138.620375 -260.942514)
			(xy 138.65301 -260.905677) (xy 138.691131 -260.874552) (xy 138.733752 -260.849945) (xy 138.779768 -260.832493)
			(xy 138.827987 -260.822649) (xy 138.877162 -260.820668) (xy 138.926017 -260.8266) (xy 138.973288 -260.840292)
			(xy 139.01775 -260.86139) (xy 139.058253 -260.889346) (xy 139.093746 -260.923438) (xy 139.123311 -260.962782)
			(xy 139.146182 -261.006359) (xy 139.161766 -261.05304) (xy 139.169661 -261.101617) (xy 139.170156 -261.126224)
			(xy 139.498844 -261.126224) (xy 139.502804 -261.07717) (xy 139.514581 -261.029386) (xy 139.533872 -260.98411)
			(xy 139.560175 -260.942514) (xy 139.59281 -260.905677) (xy 139.630931 -260.874552) (xy 139.673552 -260.849945)
			(xy 139.719568 -260.832493) (xy 139.767787 -260.822649) (xy 139.816962 -260.820668) (xy 139.865817 -260.8266)
			(xy 139.913088 -260.840292) (xy 139.95755 -260.86139) (xy 139.998053 -260.889346) (xy 140.033546 -260.923438)
			(xy 140.063111 -260.962782) (xy 140.085982 -261.006359) (xy 140.101566 -261.05304) (xy 140.109461 -261.101617)
			(xy 140.109956 -261.126224) (xy 140.109461 -261.150831) (xy 140.101566 -261.199408) (xy 140.085982 -261.246089)
			(xy 140.063111 -261.289666) (xy 140.033546 -261.32901) (xy 139.998053 -261.363102) (xy 139.95755 -261.391058)
			(xy 139.913088 -261.412156) (xy 139.865817 -261.425848) (xy 139.816962 -261.43178) (xy 139.767787 -261.429799)
			(xy 139.719568 -261.419955) (xy 139.673552 -261.402503) (xy 139.630931 -261.377896) (xy 139.59281 -261.346771)
			(xy 139.560175 -261.309934) (xy 139.533872 -261.268338) (xy 139.514581 -261.223062) (xy 139.502804 -261.175278)
			(xy 139.498844 -261.126224) (xy 139.170156 -261.126224) (xy 139.169661 -261.150831) (xy 139.161766 -261.199408)
			(xy 139.146182 -261.246089) (xy 139.123311 -261.289666) (xy 139.093746 -261.32901) (xy 139.058253 -261.363102)
			(xy 139.01775 -261.391058) (xy 138.973288 -261.412156) (xy 138.926017 -261.425848) (xy 138.877162 -261.43178)
			(xy 138.827987 -261.429799) (xy 138.779768 -261.419955) (xy 138.733752 -261.402503) (xy 138.691131 -261.377896)
			(xy 138.65301 -261.346771) (xy 138.620375 -261.309934) (xy 138.594072 -261.268338) (xy 138.574781 -261.223062)
			(xy 138.563004 -261.175278) (xy 138.559044 -261.126224) (xy 138.230102 -261.126224) (xy 138.229607 -261.150831)
			(xy 138.221712 -261.199408) (xy 138.206128 -261.246089) (xy 138.183257 -261.289666) (xy 138.153692 -261.32901)
			(xy 138.118199 -261.363102) (xy 138.077696 -261.391058) (xy 138.033234 -261.412156) (xy 137.985963 -261.425848)
			(xy 137.937108 -261.43178) (xy 137.887933 -261.429799) (xy 137.839714 -261.419955) (xy 137.793698 -261.402503)
			(xy 137.751077 -261.377896) (xy 137.712956 -261.346771) (xy 137.680321 -261.309934) (xy 137.654018 -261.268338)
			(xy 137.634727 -261.223062) (xy 137.62295 -261.175278) (xy 137.61899 -261.126224) (xy 137.290048 -261.126224)
			(xy 137.289553 -261.150831) (xy 137.281658 -261.199408) (xy 137.266074 -261.246089) (xy 137.243203 -261.289666)
			(xy 137.213638 -261.32901) (xy 137.178145 -261.363102) (xy 137.137642 -261.391058) (xy 137.09318 -261.412156)
			(xy 137.045909 -261.425848) (xy 136.997054 -261.43178) (xy 136.947879 -261.429799) (xy 136.89966 -261.419955)
			(xy 136.853644 -261.402503) (xy 136.811023 -261.377896) (xy 136.772902 -261.346771) (xy 136.740267 -261.309934)
			(xy 136.713964 -261.268338) (xy 136.694673 -261.223062) (xy 136.682896 -261.175278) (xy 136.678936 -261.126224)
			(xy 136.349994 -261.126224) (xy 136.349499 -261.150831) (xy 136.341604 -261.199408) (xy 136.32602 -261.246089)
			(xy 136.303149 -261.289666) (xy 136.273584 -261.32901) (xy 136.238091 -261.363102) (xy 136.197588 -261.391058)
			(xy 136.153126 -261.412156) (xy 136.105855 -261.425848) (xy 136.057 -261.43178) (xy 136.007825 -261.429799)
			(xy 135.959606 -261.419955) (xy 135.91359 -261.402503) (xy 135.870969 -261.377896) (xy 135.832848 -261.346771)
			(xy 135.800213 -261.309934) (xy 135.77391 -261.268338) (xy 135.754619 -261.223062) (xy 135.742842 -261.175278)
			(xy 135.738882 -261.126224) (xy 135.40994 -261.126224) (xy 135.409445 -261.150831) (xy 135.40155 -261.199408)
			(xy 135.385966 -261.246089) (xy 135.363095 -261.289666) (xy 135.33353 -261.32901) (xy 135.298037 -261.363102)
			(xy 135.257534 -261.391058) (xy 135.213072 -261.412156) (xy 135.165801 -261.425848) (xy 135.116946 -261.43178)
			(xy 135.067771 -261.429799) (xy 135.019552 -261.419955) (xy 134.973536 -261.402503) (xy 134.930915 -261.377896)
			(xy 134.892794 -261.346771) (xy 134.860159 -261.309934) (xy 134.833856 -261.268338) (xy 134.814565 -261.223062)
			(xy 134.802788 -261.175278) (xy 134.798828 -261.126224) (xy 134.47014 -261.126224) (xy 134.469645 -261.150831)
			(xy 134.46175 -261.199408) (xy 134.446166 -261.246089) (xy 134.423295 -261.289666) (xy 134.39373 -261.32901)
			(xy 134.358237 -261.363102) (xy 134.317734 -261.391058) (xy 134.273272 -261.412156) (xy 134.226001 -261.425848)
			(xy 134.177146 -261.43178) (xy 134.127971 -261.429799) (xy 134.079752 -261.419955) (xy 134.033736 -261.402503)
			(xy 133.991115 -261.377896) (xy 133.952994 -261.346771) (xy 133.920359 -261.309934) (xy 133.894056 -261.268338)
			(xy 133.874765 -261.223062) (xy 133.862988 -261.175278) (xy 133.859028 -261.126224) (xy 133.530086 -261.126224)
			(xy 133.529591 -261.150831) (xy 133.521696 -261.199408) (xy 133.506112 -261.246089) (xy 133.483241 -261.289666)
			(xy 133.453676 -261.32901) (xy 133.418183 -261.363102) (xy 133.37768 -261.391058) (xy 133.333218 -261.412156)
			(xy 133.285947 -261.425848) (xy 133.237092 -261.43178) (xy 133.187917 -261.429799) (xy 133.139698 -261.419955)
			(xy 133.093682 -261.402503) (xy 133.051061 -261.377896) (xy 133.01294 -261.346771) (xy 132.980305 -261.309934)
			(xy 132.954002 -261.268338) (xy 132.934711 -261.223062) (xy 132.922934 -261.175278) (xy 132.918974 -261.126224)
			(xy 132.590032 -261.126224) (xy 132.589537 -261.150831) (xy 132.581642 -261.199408) (xy 132.566058 -261.246089)
			(xy 132.543187 -261.289666) (xy 132.513622 -261.32901) (xy 132.478129 -261.363102) (xy 132.437626 -261.391058)
			(xy 132.393164 -261.412156) (xy 132.345893 -261.425848) (xy 132.297038 -261.43178) (xy 132.247863 -261.429799)
			(xy 132.199644 -261.419955) (xy 132.153628 -261.402503) (xy 132.111007 -261.377896) (xy 132.072886 -261.346771)
			(xy 132.040251 -261.309934) (xy 132.013948 -261.268338) (xy 131.994657 -261.223062) (xy 131.98288 -261.175278)
			(xy 131.97892 -261.126224) (xy 131.649978 -261.126224) (xy 131.649483 -261.150831) (xy 131.641588 -261.199408)
			(xy 131.626004 -261.246089) (xy 131.603133 -261.289666) (xy 131.573568 -261.32901) (xy 131.538075 -261.363102)
			(xy 131.497572 -261.391058) (xy 131.45311 -261.412156) (xy 131.405839 -261.425848) (xy 131.356984 -261.43178)
			(xy 131.307809 -261.429799) (xy 131.25959 -261.419955) (xy 131.213574 -261.402503) (xy 131.170953 -261.377896)
			(xy 131.132832 -261.346771) (xy 131.100197 -261.309934) (xy 131.073894 -261.268338) (xy 131.054603 -261.223062)
			(xy 131.042826 -261.175278) (xy 131.038866 -261.126224) (xy 130.710178 -261.126224) (xy 130.709683 -261.150831)
			(xy 130.701788 -261.199408) (xy 130.686204 -261.246089) (xy 130.663333 -261.289666) (xy 130.633768 -261.32901)
			(xy 130.598275 -261.363102) (xy 130.557772 -261.391058) (xy 130.51331 -261.412156) (xy 130.466039 -261.425848)
			(xy 130.417184 -261.43178) (xy 130.368009 -261.429799) (xy 130.31979 -261.419955) (xy 130.273774 -261.402503)
			(xy 130.231153 -261.377896) (xy 130.193032 -261.346771) (xy 130.160397 -261.309934) (xy 130.134094 -261.268338)
			(xy 130.114803 -261.223062) (xy 130.103026 -261.175278) (xy 130.099066 -261.126224) (xy 129.770124 -261.126224)
			(xy 129.769629 -261.150831) (xy 129.761734 -261.199408) (xy 129.74615 -261.246089) (xy 129.723279 -261.289666)
			(xy 129.693714 -261.32901) (xy 129.658221 -261.363102) (xy 129.617718 -261.391058) (xy 129.573256 -261.412156)
			(xy 129.525985 -261.425848) (xy 129.47713 -261.43178) (xy 129.427955 -261.429799) (xy 129.379736 -261.419955)
			(xy 129.33372 -261.402503) (xy 129.291099 -261.377896) (xy 129.252978 -261.346771) (xy 129.220343 -261.309934)
			(xy 129.19404 -261.268338) (xy 129.174749 -261.223062) (xy 129.162972 -261.175278) (xy 129.159012 -261.126224)
			(xy 128.83007 -261.126224) (xy 128.829575 -261.150831) (xy 128.82168 -261.199408) (xy 128.806096 -261.246089)
			(xy 128.783225 -261.289666) (xy 128.75366 -261.32901) (xy 128.718167 -261.363102) (xy 128.677664 -261.391058)
			(xy 128.633202 -261.412156) (xy 128.585931 -261.425848) (xy 128.537076 -261.43178) (xy 128.487901 -261.429799)
			(xy 128.439682 -261.419955) (xy 128.393666 -261.402503) (xy 128.351045 -261.377896) (xy 128.312924 -261.346771)
			(xy 128.280289 -261.309934) (xy 128.253986 -261.268338) (xy 128.234695 -261.223062) (xy 128.222918 -261.175278)
			(xy 128.218958 -261.126224) (xy 127.890016 -261.126224) (xy 127.889521 -261.150831) (xy 127.881626 -261.199408)
			(xy 127.866042 -261.246089) (xy 127.843171 -261.289666) (xy 127.813606 -261.32901) (xy 127.778113 -261.363102)
			(xy 127.73761 -261.391058) (xy 127.693148 -261.412156) (xy 127.645877 -261.425848) (xy 127.597022 -261.43178)
			(xy 127.547847 -261.429799) (xy 127.499628 -261.419955) (xy 127.453612 -261.402503) (xy 127.410991 -261.377896)
			(xy 127.37287 -261.346771) (xy 127.340235 -261.309934) (xy 127.313932 -261.268338) (xy 127.294641 -261.223062)
			(xy 127.282864 -261.175278) (xy 127.278904 -261.126224) (xy 126.010162 -261.126224) (xy 126.009667 -261.150831)
			(xy 126.001772 -261.199408) (xy 125.986188 -261.246089) (xy 125.963317 -261.289666) (xy 125.933752 -261.32901)
			(xy 125.898259 -261.363102) (xy 125.857756 -261.391058) (xy 125.813294 -261.412156) (xy 125.766023 -261.425848)
			(xy 125.717168 -261.43178) (xy 125.667993 -261.429799) (xy 125.619774 -261.419955) (xy 125.573758 -261.402503)
			(xy 125.531137 -261.377896) (xy 125.493016 -261.346771) (xy 125.460381 -261.309934) (xy 125.434078 -261.268338)
			(xy 125.414787 -261.223062) (xy 125.40301 -261.175278) (xy 125.39905 -261.126224) (xy 124.130054 -261.126224)
			(xy 124.129559 -261.150831) (xy 124.121664 -261.199408) (xy 124.10608 -261.246089) (xy 124.083209 -261.289666)
			(xy 124.053644 -261.32901) (xy 124.018151 -261.363102) (xy 123.977648 -261.391058) (xy 123.933186 -261.412156)
			(xy 123.885915 -261.425848) (xy 123.83706 -261.43178) (xy 123.787885 -261.429799) (xy 123.739666 -261.419955)
			(xy 123.69365 -261.402503) (xy 123.651029 -261.377896) (xy 123.612908 -261.346771) (xy 123.580273 -261.309934)
			(xy 123.55397 -261.268338) (xy 123.534679 -261.223062) (xy 123.522902 -261.175278) (xy 123.518942 -261.126224)
			(xy 122.249946 -261.126224) (xy 122.249451 -261.150831) (xy 122.241556 -261.199408) (xy 122.225972 -261.246089)
			(xy 122.203101 -261.289666) (xy 122.173536 -261.32901) (xy 122.138043 -261.363102) (xy 122.09754 -261.391058)
			(xy 122.053078 -261.412156) (xy 122.005807 -261.425848) (xy 121.956952 -261.43178) (xy 121.907777 -261.429799)
			(xy 121.859558 -261.419955) (xy 121.813542 -261.402503) (xy 121.770921 -261.377896) (xy 121.7328 -261.346771)
			(xy 121.700165 -261.309934) (xy 121.673862 -261.268338) (xy 121.654571 -261.223062) (xy 121.642794 -261.175278)
			(xy 121.638834 -261.126224) (xy 117.767459 -261.126224) (xy 117.775977 -261.153841) (xy 117.783638 -261.204665)
			(xy 117.784118 -261.230364) (xy 117.783651 -261.256235) (xy 117.77589 -261.30739) (xy 117.760538 -261.356801)
			(xy 117.737943 -261.403348) (xy 117.723666 -261.424928) (xy 117.719602 -261.431024) (xy 117.714268 -261.447026)
			(xy 117.711604 -261.456732) (xy 117.713309 -261.47677) (xy 117.71757 -261.485888) (xy 117.728238 -261.506208)
			(xy 117.728238 -261.506716) (xy 117.75694 -261.563104) (xy 117.76362 -261.573682) (xy 117.784666 -261.587153)
			(xy 117.797072 -261.588758) (xy 117.801136 -261.589012) (xy 118.212362 -261.589012) (xy 118.222014 -261.587996)
			(xy 118.229261 -261.586374) (xy 118.24244 -261.579542) (xy 118.247922 -261.574534) (xy 118.254272 -261.568184)
			(xy 118.263162 -261.564374) (xy 118.267848 -261.562573) (xy 118.2777 -261.560649) (xy 118.28272 -261.560564)
			(xy 119.09171 -261.560564) (xy 119.101553 -261.561088) (xy 119.119733 -261.568656) (xy 119.127016 -261.575296)
			(xy 119.732806 -262.181086) (xy 119.738303 -262.186077) (xy 119.751469 -262.192928) (xy 119.758714 -262.194548)
			(xy 119.768366 -262.195564) (xy 122.036586 -262.195564) (xy 122.043698 -262.195056) (xy 122.052588 -262.193278)
			(xy 122.062405 -262.190878) (xy 122.079167 -262.179615) (xy 122.0851 -262.171434) (xy 122.120914 -262.117078)
			(xy 122.120914 -262.11657) (xy 122.12955 -262.103616) (xy 122.132775 -262.098273) (xy 122.136767 -262.086453)
			(xy 122.137424 -262.080248) (xy 122.138694 -262.067548) (xy 122.133868 -262.056118) (xy 122.126072 -262.036931)
			(xy 122.115152 -261.996982) (xy 122.109743 -261.955923) (xy 122.109484 -261.935214) (xy 122.109484 -261.928864)
			(xy 122.110573 -261.904007) (xy 122.119819 -261.855123) (xy 122.136867 -261.808383) (xy 122.161264 -261.765025)
			(xy 122.192368 -261.726195) (xy 122.229353 -261.69292) (xy 122.271244 -261.66608) (xy 122.31693 -261.646385)
			(xy 122.365206 -261.634355) (xy 122.414792 -261.63031) (xy 122.464378 -261.634355) (xy 122.512654 -261.646385)
			(xy 122.55834 -261.66608) (xy 122.600231 -261.69292) (xy 122.637216 -261.726195) (xy 122.66832 -261.765025)
			(xy 122.692717 -261.808383) (xy 122.709765 -261.855123) (xy 122.719011 -261.904007) (xy 122.7201 -261.928864)
			(xy 122.7201 -261.93496) (xy 122.720083 -261.93623) (xy 123.988842 -261.93623) (xy 123.992802 -261.887176)
			(xy 124.004579 -261.839392) (xy 124.02387 -261.794116) (xy 124.050173 -261.75252) (xy 124.082808 -261.715683)
			(xy 124.120929 -261.684558) (xy 124.16355 -261.659951) (xy 124.209566 -261.642499) (xy 124.257785 -261.632655)
			(xy 124.30696 -261.630674) (xy 124.355815 -261.636606) (xy 124.403086 -261.650298) (xy 124.447548 -261.671396)
			(xy 124.488051 -261.699352) (xy 124.523544 -261.733444) (xy 124.553109 -261.772788) (xy 124.57598 -261.816365)
			(xy 124.591564 -261.863046) (xy 124.599459 -261.911623) (xy 124.599954 -261.93623) (xy 125.86895 -261.93623)
			(xy 125.87291 -261.887176) (xy 125.884687 -261.839392) (xy 125.903978 -261.794116) (xy 125.930281 -261.75252)
			(xy 125.962916 -261.715683) (xy 126.001037 -261.684558) (xy 126.043658 -261.659951) (xy 126.089674 -261.642499)
			(xy 126.137893 -261.632655) (xy 126.187068 -261.630674) (xy 126.235923 -261.636606) (xy 126.283194 -261.650298)
			(xy 126.327656 -261.671396) (xy 126.368159 -261.699352) (xy 126.403652 -261.733444) (xy 126.433217 -261.772788)
			(xy 126.456088 -261.816365) (xy 126.471672 -261.863046) (xy 126.479567 -261.911623) (xy 126.480062 -261.93623)
			(xy 127.738627 -261.93623) (xy 127.742722 -261.885502) (xy 127.754901 -261.836088) (xy 127.774849 -261.789268)
			(xy 127.80205 -261.746254) (xy 127.835798 -261.70816) (xy 127.87522 -261.675973) (xy 127.919294 -261.650527)
			(xy 127.96688 -261.63248) (xy 128.016744 -261.6223) (xy 128.067596 -261.620251) (xy 128.118117 -261.626385)
			(xy 128.167001 -261.640545) (xy 128.21298 -261.662362) (xy 128.254864 -261.691272) (xy 128.291568 -261.726527)
			(xy 128.322141 -261.767213) (xy 128.345792 -261.812276) (xy 128.361908 -261.86055) (xy 128.370072 -261.910784)
			(xy 128.370584 -261.93623) (xy 128.688858 -261.93623) (xy 128.692818 -261.887176) (xy 128.704595 -261.839392)
			(xy 128.723886 -261.794116) (xy 128.750189 -261.75252) (xy 128.782824 -261.715683) (xy 128.820945 -261.684558)
			(xy 128.863566 -261.659951) (xy 128.909582 -261.642499) (xy 128.957801 -261.632655) (xy 129.006976 -261.630674)
			(xy 129.055831 -261.636606) (xy 129.103102 -261.650298) (xy 129.147564 -261.671396) (xy 129.188067 -261.699352)
			(xy 129.22356 -261.733444) (xy 129.253125 -261.772788) (xy 129.275996 -261.816365) (xy 129.29158 -261.863046)
			(xy 129.299475 -261.911623) (xy 129.29997 -261.93623) (xy 129.628912 -261.93623) (xy 129.632872 -261.887176)
			(xy 129.644649 -261.839392) (xy 129.66394 -261.794116) (xy 129.690243 -261.75252) (xy 129.722878 -261.715683)
			(xy 129.760999 -261.684558) (xy 129.80362 -261.659951) (xy 129.849636 -261.642499) (xy 129.897855 -261.632655)
			(xy 129.94703 -261.630674) (xy 129.995885 -261.636606) (xy 130.043156 -261.650298) (xy 130.087618 -261.671396)
			(xy 130.128121 -261.699352) (xy 130.163614 -261.733444) (xy 130.193179 -261.772788) (xy 130.21605 -261.816365)
			(xy 130.231634 -261.863046) (xy 130.239529 -261.911623) (xy 130.240024 -261.93623) (xy 130.568966 -261.93623)
			(xy 130.572926 -261.887176) (xy 130.584703 -261.839392) (xy 130.603994 -261.794116) (xy 130.630297 -261.75252)
			(xy 130.662932 -261.715683) (xy 130.701053 -261.684558) (xy 130.743674 -261.659951) (xy 130.78969 -261.642499)
			(xy 130.837909 -261.632655) (xy 130.887084 -261.630674) (xy 130.935939 -261.636606) (xy 130.98321 -261.650298)
			(xy 131.027672 -261.671396) (xy 131.068175 -261.699352) (xy 131.103668 -261.733444) (xy 131.133233 -261.772788)
			(xy 131.156104 -261.816365) (xy 131.171688 -261.863046) (xy 131.179583 -261.911623) (xy 131.180078 -261.93623)
			(xy 131.498589 -261.93623) (xy 131.502684 -261.885502) (xy 131.514863 -261.836088) (xy 131.534811 -261.789268)
			(xy 131.562012 -261.746254) (xy 131.59576 -261.70816) (xy 131.635182 -261.675973) (xy 131.679256 -261.650527)
			(xy 131.726842 -261.63248) (xy 131.776706 -261.6223) (xy 131.827558 -261.620251) (xy 131.878079 -261.626385)
			(xy 131.926963 -261.640545) (xy 131.972942 -261.662362) (xy 132.014826 -261.691272) (xy 132.05153 -261.726527)
			(xy 132.082103 -261.767213) (xy 132.105754 -261.812276) (xy 132.12187 -261.86055) (xy 132.130034 -261.910784)
			(xy 132.130546 -261.93623) (xy 132.44882 -261.93623) (xy 132.45278 -261.887176) (xy 132.464557 -261.839392)
			(xy 132.483848 -261.794116) (xy 132.510151 -261.75252) (xy 132.542786 -261.715683) (xy 132.580907 -261.684558)
			(xy 132.623528 -261.659951) (xy 132.669544 -261.642499) (xy 132.717763 -261.632655) (xy 132.766938 -261.630674)
			(xy 132.815793 -261.636606) (xy 132.863064 -261.650298) (xy 132.907526 -261.671396) (xy 132.948029 -261.699352)
			(xy 132.983522 -261.733444) (xy 133.013087 -261.772788) (xy 133.035958 -261.816365) (xy 133.051542 -261.863046)
			(xy 133.059437 -261.911623) (xy 133.059932 -261.93623) (xy 133.388874 -261.93623) (xy 133.392834 -261.887176)
			(xy 133.404611 -261.839392) (xy 133.423902 -261.794116) (xy 133.450205 -261.75252) (xy 133.48284 -261.715683)
			(xy 133.520961 -261.684558) (xy 133.563582 -261.659951) (xy 133.609598 -261.642499) (xy 133.657817 -261.632655)
			(xy 133.706992 -261.630674) (xy 133.755847 -261.636606) (xy 133.803118 -261.650298) (xy 133.84758 -261.671396)
			(xy 133.888083 -261.699352) (xy 133.923576 -261.733444) (xy 133.953141 -261.772788) (xy 133.976012 -261.816365)
			(xy 133.991596 -261.863046) (xy 133.999491 -261.911623) (xy 133.999986 -261.93623) (xy 134.328928 -261.93623)
			(xy 134.332888 -261.887176) (xy 134.344665 -261.839392) (xy 134.363956 -261.794116) (xy 134.390259 -261.75252)
			(xy 134.422894 -261.715683) (xy 134.461015 -261.684558) (xy 134.503636 -261.659951) (xy 134.549652 -261.642499)
			(xy 134.597871 -261.632655) (xy 134.647046 -261.630674) (xy 134.695901 -261.636606) (xy 134.743172 -261.650298)
			(xy 134.787634 -261.671396) (xy 134.828137 -261.699352) (xy 134.86363 -261.733444) (xy 134.893195 -261.772788)
			(xy 134.916066 -261.816365) (xy 134.93165 -261.863046) (xy 134.939545 -261.911623) (xy 134.94004 -261.93623)
			(xy 135.268982 -261.93623) (xy 135.272942 -261.887176) (xy 135.284719 -261.839392) (xy 135.30401 -261.794116)
			(xy 135.330313 -261.75252) (xy 135.362948 -261.715683) (xy 135.401069 -261.684558) (xy 135.44369 -261.659951)
			(xy 135.489706 -261.642499) (xy 135.537925 -261.632655) (xy 135.5871 -261.630674) (xy 135.635955 -261.636606)
			(xy 135.683226 -261.650298) (xy 135.727688 -261.671396) (xy 135.768191 -261.699352) (xy 135.803684 -261.733444)
			(xy 135.833249 -261.772788) (xy 135.85612 -261.816365) (xy 135.871704 -261.863046) (xy 135.879599 -261.911623)
			(xy 135.880094 -261.93623) (xy 136.209036 -261.93623) (xy 136.212996 -261.887176) (xy 136.224773 -261.839392)
			(xy 136.244064 -261.794116) (xy 136.270367 -261.75252) (xy 136.303002 -261.715683) (xy 136.341123 -261.684558)
			(xy 136.383744 -261.659951) (xy 136.42976 -261.642499) (xy 136.477979 -261.632655) (xy 136.527154 -261.630674)
			(xy 136.576009 -261.636606) (xy 136.62328 -261.650298) (xy 136.667742 -261.671396) (xy 136.708245 -261.699352)
			(xy 136.743738 -261.733444) (xy 136.773303 -261.772788) (xy 136.796174 -261.816365) (xy 136.811758 -261.863046)
			(xy 136.819653 -261.911623) (xy 136.820148 -261.93623) (xy 137.148836 -261.93623) (xy 137.152796 -261.887176)
			(xy 137.164573 -261.839392) (xy 137.183864 -261.794116) (xy 137.210167 -261.75252) (xy 137.242802 -261.715683)
			(xy 137.280923 -261.684558) (xy 137.323544 -261.659951) (xy 137.36956 -261.642499) (xy 137.417779 -261.632655)
			(xy 137.466954 -261.630674) (xy 137.515809 -261.636606) (xy 137.56308 -261.650298) (xy 137.607542 -261.671396)
			(xy 137.648045 -261.699352) (xy 137.683538 -261.733444) (xy 137.713103 -261.772788) (xy 137.735974 -261.816365)
			(xy 137.751558 -261.863046) (xy 137.759453 -261.911623) (xy 137.759948 -261.93623) (xy 138.08889 -261.93623)
			(xy 138.09285 -261.887176) (xy 138.104627 -261.839392) (xy 138.123918 -261.794116) (xy 138.150221 -261.75252)
			(xy 138.182856 -261.715683) (xy 138.220977 -261.684558) (xy 138.263598 -261.659951) (xy 138.309614 -261.642499)
			(xy 138.357833 -261.632655) (xy 138.407008 -261.630674) (xy 138.455863 -261.636606) (xy 138.503134 -261.650298)
			(xy 138.547596 -261.671396) (xy 138.588099 -261.699352) (xy 138.623592 -261.733444) (xy 138.653157 -261.772788)
			(xy 138.676028 -261.816365) (xy 138.691612 -261.863046) (xy 138.699507 -261.911623) (xy 138.700002 -261.93623)
			(xy 139.028944 -261.93623) (xy 139.032904 -261.887176) (xy 139.044681 -261.839392) (xy 139.063972 -261.794116)
			(xy 139.090275 -261.75252) (xy 139.12291 -261.715683) (xy 139.161031 -261.684558) (xy 139.203652 -261.659951)
			(xy 139.249668 -261.642499) (xy 139.297887 -261.632655) (xy 139.347062 -261.630674) (xy 139.395917 -261.636606)
			(xy 139.443188 -261.650298) (xy 139.48765 -261.671396) (xy 139.528153 -261.699352) (xy 139.563646 -261.733444)
			(xy 139.593211 -261.772788) (xy 139.616082 -261.816365) (xy 139.631666 -261.863046) (xy 139.639561 -261.911623)
			(xy 139.640056 -261.93623) (xy 139.639561 -261.960837) (xy 139.631666 -262.009414) (xy 139.616082 -262.056095)
			(xy 139.593211 -262.099672) (xy 139.563646 -262.139016) (xy 139.528153 -262.173108) (xy 139.48765 -262.201064)
			(xy 139.443188 -262.222162) (xy 139.395917 -262.235854) (xy 139.347062 -262.241786) (xy 139.297887 -262.239805)
			(xy 139.249668 -262.229961) (xy 139.203652 -262.212509) (xy 139.161031 -262.187902) (xy 139.12291 -262.156777)
			(xy 139.090275 -262.11994) (xy 139.063972 -262.078344) (xy 139.044681 -262.033068) (xy 139.032904 -261.985284)
			(xy 139.028944 -261.93623) (xy 138.700002 -261.93623) (xy 138.699507 -261.960837) (xy 138.691612 -262.009414)
			(xy 138.676028 -262.056095) (xy 138.653157 -262.099672) (xy 138.623592 -262.139016) (xy 138.588099 -262.173108)
			(xy 138.547596 -262.201064) (xy 138.503134 -262.222162) (xy 138.455863 -262.235854) (xy 138.407008 -262.241786)
			(xy 138.357833 -262.239805) (xy 138.309614 -262.229961) (xy 138.263598 -262.212509) (xy 138.220977 -262.187902)
			(xy 138.182856 -262.156777) (xy 138.150221 -262.11994) (xy 138.123918 -262.078344) (xy 138.104627 -262.033068)
			(xy 138.09285 -261.985284) (xy 138.08889 -261.93623) (xy 137.759948 -261.93623) (xy 137.759453 -261.960837)
			(xy 137.751558 -262.009414) (xy 137.735974 -262.056095) (xy 137.713103 -262.099672) (xy 137.683538 -262.139016)
			(xy 137.648045 -262.173108) (xy 137.607542 -262.201064) (xy 137.56308 -262.222162) (xy 137.515809 -262.235854)
			(xy 137.466954 -262.241786) (xy 137.417779 -262.239805) (xy 137.36956 -262.229961) (xy 137.323544 -262.212509)
			(xy 137.280923 -262.187902) (xy 137.242802 -262.156777) (xy 137.210167 -262.11994) (xy 137.183864 -262.078344)
			(xy 137.164573 -262.033068) (xy 137.152796 -261.985284) (xy 137.148836 -261.93623) (xy 136.820148 -261.93623)
			(xy 136.819653 -261.960837) (xy 136.811758 -262.009414) (xy 136.796174 -262.056095) (xy 136.773303 -262.099672)
			(xy 136.743738 -262.139016) (xy 136.708245 -262.173108) (xy 136.667742 -262.201064) (xy 136.62328 -262.222162)
			(xy 136.576009 -262.235854) (xy 136.527154 -262.241786) (xy 136.477979 -262.239805) (xy 136.42976 -262.229961)
			(xy 136.383744 -262.212509) (xy 136.341123 -262.187902) (xy 136.303002 -262.156777) (xy 136.270367 -262.11994)
			(xy 136.244064 -262.078344) (xy 136.224773 -262.033068) (xy 136.212996 -261.985284) (xy 136.209036 -261.93623)
			(xy 135.880094 -261.93623) (xy 135.879599 -261.960837) (xy 135.871704 -262.009414) (xy 135.85612 -262.056095)
			(xy 135.833249 -262.099672) (xy 135.803684 -262.139016) (xy 135.768191 -262.173108) (xy 135.727688 -262.201064)
			(xy 135.683226 -262.222162) (xy 135.635955 -262.235854) (xy 135.5871 -262.241786) (xy 135.537925 -262.239805)
			(xy 135.489706 -262.229961) (xy 135.44369 -262.212509) (xy 135.401069 -262.187902) (xy 135.362948 -262.156777)
			(xy 135.330313 -262.11994) (xy 135.30401 -262.078344) (xy 135.284719 -262.033068) (xy 135.272942 -261.985284)
			(xy 135.268982 -261.93623) (xy 134.94004 -261.93623) (xy 134.939545 -261.960837) (xy 134.93165 -262.009414)
			(xy 134.916066 -262.056095) (xy 134.893195 -262.099672) (xy 134.86363 -262.139016) (xy 134.828137 -262.173108)
			(xy 134.787634 -262.201064) (xy 134.743172 -262.222162) (xy 134.695901 -262.235854) (xy 134.647046 -262.241786)
			(xy 134.597871 -262.239805) (xy 134.549652 -262.229961) (xy 134.503636 -262.212509) (xy 134.461015 -262.187902)
			(xy 134.422894 -262.156777) (xy 134.390259 -262.11994) (xy 134.363956 -262.078344) (xy 134.344665 -262.033068)
			(xy 134.332888 -261.985284) (xy 134.328928 -261.93623) (xy 133.999986 -261.93623) (xy 133.999491 -261.960837)
			(xy 133.991596 -262.009414) (xy 133.976012 -262.056095) (xy 133.953141 -262.099672) (xy 133.923576 -262.139016)
			(xy 133.888083 -262.173108) (xy 133.84758 -262.201064) (xy 133.803118 -262.222162) (xy 133.755847 -262.235854)
			(xy 133.706992 -262.241786) (xy 133.657817 -262.239805) (xy 133.609598 -262.229961) (xy 133.563582 -262.212509)
			(xy 133.520961 -262.187902) (xy 133.48284 -262.156777) (xy 133.450205 -262.11994) (xy 133.423902 -262.078344)
			(xy 133.404611 -262.033068) (xy 133.392834 -261.985284) (xy 133.388874 -261.93623) (xy 133.059932 -261.93623)
			(xy 133.059437 -261.960837) (xy 133.051542 -262.009414) (xy 133.035958 -262.056095) (xy 133.013087 -262.099672)
			(xy 132.983522 -262.139016) (xy 132.948029 -262.173108) (xy 132.907526 -262.201064) (xy 132.863064 -262.222162)
			(xy 132.815793 -262.235854) (xy 132.766938 -262.241786) (xy 132.717763 -262.239805) (xy 132.669544 -262.229961)
			(xy 132.623528 -262.212509) (xy 132.580907 -262.187902) (xy 132.542786 -262.156777) (xy 132.510151 -262.11994)
			(xy 132.483848 -262.078344) (xy 132.464557 -262.033068) (xy 132.45278 -261.985284) (xy 132.44882 -261.93623)
			(xy 132.130546 -261.93623) (xy 132.130034 -261.961676) (xy 132.12187 -262.01191) (xy 132.105754 -262.060184)
			(xy 132.082103 -262.105247) (xy 132.05153 -262.145933) (xy 132.014826 -262.181188) (xy 131.972942 -262.210098)
			(xy 131.926963 -262.231915) (xy 131.878079 -262.246075) (xy 131.827558 -262.252209) (xy 131.776706 -262.25016)
			(xy 131.726842 -262.23998) (xy 131.679256 -262.221933) (xy 131.635182 -262.196487) (xy 131.59576 -262.1643)
			(xy 131.562012 -262.126206) (xy 131.534811 -262.083192) (xy 131.514863 -262.036372) (xy 131.502684 -261.986958)
			(xy 131.498589 -261.93623) (xy 131.180078 -261.93623) (xy 131.179583 -261.960837) (xy 131.171688 -262.009414)
			(xy 131.156104 -262.056095) (xy 131.133233 -262.099672) (xy 131.103668 -262.139016) (xy 131.068175 -262.173108)
			(xy 131.027672 -262.201064) (xy 130.98321 -262.222162) (xy 130.935939 -262.235854) (xy 130.887084 -262.241786)
			(xy 130.837909 -262.239805) (xy 130.78969 -262.229961) (xy 130.743674 -262.212509) (xy 130.701053 -262.187902)
			(xy 130.662932 -262.156777) (xy 130.630297 -262.11994) (xy 130.603994 -262.078344) (xy 130.584703 -262.033068)
			(xy 130.572926 -261.985284) (xy 130.568966 -261.93623) (xy 130.240024 -261.93623) (xy 130.239529 -261.960837)
			(xy 130.231634 -262.009414) (xy 130.21605 -262.056095) (xy 130.193179 -262.099672) (xy 130.163614 -262.139016)
			(xy 130.128121 -262.173108) (xy 130.087618 -262.201064) (xy 130.043156 -262.222162) (xy 129.995885 -262.235854)
			(xy 129.94703 -262.241786) (xy 129.897855 -262.239805) (xy 129.849636 -262.229961) (xy 129.80362 -262.212509)
			(xy 129.760999 -262.187902) (xy 129.722878 -262.156777) (xy 129.690243 -262.11994) (xy 129.66394 -262.078344)
			(xy 129.644649 -262.033068) (xy 129.632872 -261.985284) (xy 129.628912 -261.93623) (xy 129.29997 -261.93623)
			(xy 129.299475 -261.960837) (xy 129.29158 -262.009414) (xy 129.275996 -262.056095) (xy 129.253125 -262.099672)
			(xy 129.22356 -262.139016) (xy 129.188067 -262.173108) (xy 129.147564 -262.201064) (xy 129.103102 -262.222162)
			(xy 129.055831 -262.235854) (xy 129.006976 -262.241786) (xy 128.957801 -262.239805) (xy 128.909582 -262.229961)
			(xy 128.863566 -262.212509) (xy 128.820945 -262.187902) (xy 128.782824 -262.156777) (xy 128.750189 -262.11994)
			(xy 128.723886 -262.078344) (xy 128.704595 -262.033068) (xy 128.692818 -261.985284) (xy 128.688858 -261.93623)
			(xy 128.370584 -261.93623) (xy 128.370072 -261.961676) (xy 128.361908 -262.01191) (xy 128.345792 -262.060184)
			(xy 128.322141 -262.105247) (xy 128.291568 -262.145933) (xy 128.254864 -262.181188) (xy 128.21298 -262.210098)
			(xy 128.167001 -262.231915) (xy 128.118117 -262.246075) (xy 128.067596 -262.252209) (xy 128.016744 -262.25016)
			(xy 127.96688 -262.23998) (xy 127.919294 -262.221933) (xy 127.87522 -262.196487) (xy 127.835798 -262.1643)
			(xy 127.80205 -262.126206) (xy 127.774849 -262.083192) (xy 127.754901 -262.036372) (xy 127.742722 -261.986958)
			(xy 127.738627 -261.93623) (xy 126.480062 -261.93623) (xy 126.479567 -261.960837) (xy 126.471672 -262.009414)
			(xy 126.456088 -262.056095) (xy 126.433217 -262.099672) (xy 126.403652 -262.139016) (xy 126.368159 -262.173108)
			(xy 126.327656 -262.201064) (xy 126.283194 -262.222162) (xy 126.235923 -262.235854) (xy 126.187068 -262.241786)
			(xy 126.137893 -262.239805) (xy 126.089674 -262.229961) (xy 126.043658 -262.212509) (xy 126.001037 -262.187902)
			(xy 125.962916 -262.156777) (xy 125.930281 -262.11994) (xy 125.903978 -262.078344) (xy 125.884687 -262.033068)
			(xy 125.87291 -261.985284) (xy 125.86895 -261.93623) (xy 124.599954 -261.93623) (xy 124.599459 -261.960837)
			(xy 124.591564 -262.009414) (xy 124.57598 -262.056095) (xy 124.553109 -262.099672) (xy 124.523544 -262.139016)
			(xy 124.488051 -262.173108) (xy 124.447548 -262.201064) (xy 124.403086 -262.222162) (xy 124.355815 -262.235854)
			(xy 124.30696 -262.241786) (xy 124.257785 -262.239805) (xy 124.209566 -262.229961) (xy 124.16355 -262.212509)
			(xy 124.120929 -262.187902) (xy 124.082808 -262.156777) (xy 124.050173 -262.11994) (xy 124.02387 -262.078344)
			(xy 124.004579 -262.033068) (xy 123.992802 -261.985284) (xy 123.988842 -261.93623) (xy 122.720083 -261.93623)
			(xy 122.719823 -261.955625) (xy 122.714387 -261.996594) (xy 122.703485 -262.036459) (xy 122.695716 -262.05561)
			(xy 122.695716 -262.055864) (xy 122.692668 -262.06323) (xy 122.69089 -262.067548) (xy 122.691906 -262.07974)
			(xy 122.692589 -262.085941) (xy 122.696571 -262.097759) (xy 122.69978 -262.103108) (xy 122.71121 -262.120634)
			(xy 122.745246 -262.17245) (xy 122.750326 -262.179308) (xy 122.757636 -262.186544) (xy 122.776383 -262.194958)
			(xy 122.786648 -262.195564) (xy 123.40971 -262.195564) (xy 123.419553 -262.196088) (xy 123.437733 -262.203656)
			(xy 123.445016 -262.210296) (xy 123.678442 -262.443722) (xy 123.683584 -262.448486) (xy 123.695814 -262.455323)
			(xy 123.702572 -262.457184) (xy 123.709176 -262.458708) (xy 123.7234 -262.4582) (xy 123.730004 -262.455914)
			(xy 123.751955 -262.449204) (xy 123.797233 -262.441676) (xy 123.820174 -262.440928) (xy 123.828302 -262.440928)
			(xy 123.85193 -262.44165) (xy 123.898545 -262.449486) (xy 123.943395 -262.464413) (xy 123.985408 -262.486075)
			(xy 124.023581 -262.513953) (xy 124.057001 -262.547382) (xy 124.084869 -262.585562) (xy 124.106519 -262.627582)
			(xy 124.121434 -262.672436) (xy 124.129258 -262.719053) (xy 124.130054 -262.74268) (xy 124.130054 -262.746744)
			(xy 124.129566 -262.770709) (xy 124.12204 -262.818045) (xy 124.115068 -262.840978) (xy 124.112782 -262.847582)
			(xy 124.112274 -262.861806) (xy 124.113798 -262.86841) (xy 124.115621 -262.875184) (xy 124.122454 -262.88743)
			(xy 124.12726 -262.89254) (xy 124.304806 -263.070086) (xy 124.310303 -263.075077) (xy 124.323469 -263.081928)
			(xy 124.330714 -263.083548) (xy 124.340366 -263.084564) (xy 125.376178 -263.084564) (xy 125.37694 -263.084564)
			(xy 125.385858 -263.084093) (xy 125.402534 -263.077737) (xy 125.416025 -263.066053) (xy 125.420628 -263.058402)
			(xy 125.434598 -263.03097) (xy 125.434598 -263.030462) (xy 125.461522 -262.978392) (xy 125.464543 -262.971971)
			(xy 125.467245 -262.958046) (xy 125.466856 -262.95096) (xy 125.46584 -262.93826) (xy 125.458474 -262.92683)
			(xy 125.457458 -262.925306) (xy 125.443823 -262.90564) (xy 125.422184 -262.862959) (xy 125.407457 -262.81743)
			(xy 125.399999 -262.770162) (xy 125.399546 -262.746236) (xy 125.400068 -262.720981) (xy 125.408381 -262.671159)
			(xy 125.424782 -262.623385) (xy 125.448823 -262.578962) (xy 125.479847 -262.539102) (xy 125.517009 -262.504892)
			(xy 125.559295 -262.477266) (xy 125.605551 -262.456976) (xy 125.654516 -262.444576) (xy 125.704854 -262.440405)
			(xy 125.755192 -262.444576) (xy 125.804157 -262.456976) (xy 125.850413 -262.477266) (xy 125.892699 -262.504892)
			(xy 125.929861 -262.539102) (xy 125.960885 -262.578962) (xy 125.984926 -262.623385) (xy 126.001327 -262.671159)
			(xy 126.00964 -262.720981) (xy 126.010162 -262.746236) (xy 126.009696 -262.770161) (xy 126.002236 -262.817425)
			(xy 125.987506 -262.862951) (xy 125.965863 -262.905626) (xy 125.95225 -262.925306) (xy 125.951234 -262.92683)
			(xy 125.950726 -262.927592) (xy 125.947503 -262.932935) (xy 125.943515 -262.944756) (xy 125.942852 -262.95096)
			(xy 125.942491 -262.958042) (xy 125.945209 -262.971955) (xy 125.948186 -262.978392) (xy 125.97511 -263.030462)
			(xy 125.97511 -263.03097) (xy 125.98908 -263.058402) (xy 125.993703 -263.066041) (xy 126.00718 -263.077738)
			(xy 126.023851 -263.084101) (xy 126.032768 -263.084564) (xy 126.838964 -263.084564) (xy 126.843585 -263.084387)
			(xy 126.852658 -263.082604) (xy 126.856998 -263.081008) (xy 126.869698 -263.075674) (xy 126.874385 -263.073876)
			(xy 126.884237 -263.071959) (xy 126.889256 -263.071864) (xy 127.24765 -263.071864) (xy 127.25146 -263.07161)
			(xy 127.263906 -263.070097) (xy 127.285116 -263.056786) (xy 127.291846 -263.04621) (xy 127.294386 -263.041384)
			(xy 127.333502 -262.96747) (xy 127.336483 -262.96143) (xy 127.339448 -262.948296) (xy 127.339344 -262.941562)
			(xy 127.338582 -262.927592) (xy 127.330708 -262.915654) (xy 127.318576 -262.896748) (xy 127.299396 -262.856127)
			(xy 127.286378 -262.813134) (xy 127.279802 -262.768697) (xy 127.2794 -262.746236) (xy 127.2794 -262.739632)
			(xy 127.280431 -262.714734) (xy 127.289582 -262.665753) (xy 127.306564 -262.618908) (xy 127.330926 -262.575441)
			(xy 127.362021 -262.536505) (xy 127.399025 -262.503135) (xy 127.440955 -262.476214) (xy 127.4867 -262.456459)
			(xy 127.535045 -262.444391) (xy 127.584708 -262.440333) (xy 127.634371 -262.444391) (xy 127.682716 -262.456459)
			(xy 127.728461 -262.476214) (xy 127.770391 -262.503135) (xy 127.807395 -262.536505) (xy 127.83849 -262.575441)
			(xy 127.862852 -262.618908) (xy 127.879834 -262.665753) (xy 127.888985 -262.714734) (xy 127.890016 -262.739632)
			(xy 127.890016 -262.746236) (xy 127.889623 -262.768008) (xy 127.883431 -262.811109) (xy 127.871193 -262.852897)
			(xy 127.853154 -262.892528) (xy 127.841756 -262.911082) (xy 127.838454 -262.916162) (xy 127.83312 -262.93191)
			(xy 127.830981 -262.940801) (xy 127.832422 -262.959018) (xy 127.835914 -262.96747) (xy 127.860298 -263.013444)
			(xy 127.860298 -263.013952) (xy 127.877062 -263.04494) (xy 127.881698 -263.052854) (xy 127.895452 -263.064967)
			(xy 127.912602 -263.07143) (xy 127.921766 -263.071864) (xy 128.187704 -263.071864) (xy 128.191514 -263.07161)
			(xy 128.203953 -263.070087) (xy 128.225143 -263.056764) (xy 128.2319 -263.04621) (xy 128.23444 -263.041384)
			(xy 128.271524 -262.971788) (xy 128.274605 -262.965513) (xy 128.27756 -262.951853) (xy 128.277366 -262.944864)
			(xy 128.277112 -262.94207) (xy 128.261141 -262.921013) (xy 128.235719 -262.874683) (xy 128.218365 -262.824767)
			(xy 128.209562 -262.772659) (xy 128.20904 -262.746236) (xy 128.209527 -262.721426) (xy 128.217289 -262.672418)
			(xy 128.232622 -262.625228) (xy 128.255149 -262.581017) (xy 128.284314 -262.540874) (xy 128.3194 -262.505788)
			(xy 128.359543 -262.476623) (xy 128.403754 -262.454096) (xy 128.450944 -262.438763) (xy 128.499952 -262.431001)
			(xy 128.549572 -262.431001) (xy 128.59858 -262.438763) (xy 128.64577 -262.454096) (xy 128.689981 -262.476623)
			(xy 128.730124 -262.505788) (xy 128.76521 -262.540874) (xy 128.794375 -262.581017) (xy 128.816902 -262.625228)
			(xy 128.832235 -262.672418) (xy 128.839997 -262.721426) (xy 128.840484 -262.746236) (xy 128.84001 -262.770864)
			(xy 128.832359 -262.819522) (xy 128.817248 -262.866403) (xy 128.795044 -262.91037) (xy 128.781048 -262.93064)
			(xy 128.777011 -262.936605) (xy 128.772116 -262.950143) (xy 128.771396 -262.95731) (xy 128.771396 -262.959088)
			(xy 128.817116 -263.04494) (xy 128.82175 -263.052859) (xy 128.835501 -263.064985) (xy 128.852653 -263.071463)
			(xy 128.86182 -263.071864) (xy 129.127758 -263.071864) (xy 129.131568 -263.07161) (xy 129.144013 -263.070096)
			(xy 129.16522 -263.056782) (xy 129.171954 -263.04621) (xy 129.174494 -263.041384) (xy 129.211578 -262.971788)
			(xy 129.214661 -262.965513) (xy 129.217619 -262.951853) (xy 129.21742 -262.944864) (xy 129.217166 -262.94207)
			(xy 129.201276 -262.921085) (xy 129.175979 -262.874928) (xy 129.158696 -262.825211) (xy 129.149908 -262.773315)
			(xy 129.149348 -262.746998) (xy 129.149348 -262.746236) (xy 129.149834 -262.721446) (xy 129.15759 -262.672478)
			(xy 129.172911 -262.625325) (xy 129.19542 -262.58115) (xy 129.224562 -262.541039) (xy 129.259619 -262.505982)
			(xy 129.29973 -262.47684) (xy 129.343905 -262.454331) (xy 129.391058 -262.43901) (xy 129.440026 -262.431254)
			(xy 129.489606 -262.431254) (xy 129.538574 -262.43901) (xy 129.585727 -262.454331) (xy 129.629902 -262.47684)
			(xy 129.670013 -262.505982) (xy 129.70507 -262.541039) (xy 129.734212 -262.58115) (xy 129.756721 -262.625325)
			(xy 129.772042 -262.672478) (xy 129.779798 -262.721446) (xy 129.780284 -262.746236) (xy 129.780284 -262.746998)
			(xy 129.779808 -262.771524) (xy 129.772187 -262.819979) (xy 129.757144 -262.866667) (xy 129.735044 -262.910457)
			(xy 129.721102 -262.93064) (xy 129.717062 -262.936603) (xy 129.712161 -262.950142) (xy 129.71145 -262.95731)
			(xy 129.71145 -262.959088) (xy 129.75717 -263.04494) (xy 129.761802 -263.052864) (xy 129.775551 -263.065002)
			(xy 129.792704 -263.071495) (xy 129.801874 -263.071864) (xy 130.067812 -263.071864) (xy 130.071622 -263.07161)
			(xy 130.08406 -263.070085) (xy 130.105247 -263.056761) (xy 130.112008 -263.04621) (xy 130.114548 -263.041384)
			(xy 130.153664 -262.96747) (xy 130.156647 -262.961431) (xy 130.159614 -262.948297) (xy 130.159506 -262.941562)
			(xy 130.158744 -262.927592) (xy 130.15087 -262.915654) (xy 130.138739 -262.896747) (xy 130.119562 -262.856126)
			(xy 130.106545 -262.813133) (xy 130.09997 -262.768696) (xy 130.099562 -262.746236) (xy 130.099562 -262.739632)
			(xy 130.100593 -262.714734) (xy 130.109744 -262.665753) (xy 130.126726 -262.618908) (xy 130.151088 -262.575441)
			(xy 130.182183 -262.536505) (xy 130.219187 -262.503135) (xy 130.261117 -262.476214) (xy 130.306862 -262.456459)
			(xy 130.355207 -262.444391) (xy 130.40487 -262.440333) (xy 130.454533 -262.444391) (xy 130.502878 -262.456459)
			(xy 130.548623 -262.476214) (xy 130.590553 -262.503135) (xy 130.627557 -262.536505) (xy 130.658652 -262.575441)
			(xy 130.683014 -262.618908) (xy 130.699996 -262.665753) (xy 130.709147 -262.714734) (xy 130.710178 -262.739632)
			(xy 130.710178 -262.746236) (xy 130.709785 -262.768007) (xy 130.703593 -262.811108) (xy 130.691353 -262.852896)
			(xy 130.673312 -262.892526) (xy 130.661918 -262.911082) (xy 130.658616 -262.916162) (xy 130.653282 -262.93191)
			(xy 130.651142 -262.940801) (xy 130.652584 -262.959017) (xy 130.656076 -262.96747) (xy 130.68046 -263.013444)
			(xy 130.68046 -263.013952) (xy 130.697224 -263.04494) (xy 130.701858 -263.052858) (xy 130.71561 -263.064982)
			(xy 130.732761 -263.071457) (xy 130.741928 -263.071864) (xy 131.007612 -263.071864) (xy 131.011422 -263.07161)
			(xy 131.02386 -263.070085) (xy 131.045047 -263.056761) (xy 131.051808 -263.04621) (xy 131.054348 -263.041384)
			(xy 131.091432 -262.971788) (xy 131.094513 -262.965512) (xy 131.097467 -262.951853) (xy 131.097274 -262.944864)
			(xy 131.09702 -262.94207) (xy 131.081049 -262.921013) (xy 131.055626 -262.874683) (xy 131.038271 -262.824767)
			(xy 131.029468 -262.772659) (xy 131.028948 -262.746236) (xy 131.029435 -262.721426) (xy 131.037197 -262.672418)
			(xy 131.05253 -262.625228) (xy 131.075057 -262.581017) (xy 131.104222 -262.540874) (xy 131.139308 -262.505788)
			(xy 131.179451 -262.476623) (xy 131.223662 -262.454096) (xy 131.270852 -262.438763) (xy 131.31986 -262.431001)
			(xy 131.36948 -262.431001) (xy 131.418488 -262.438763) (xy 131.465678 -262.454096) (xy 131.509889 -262.476623)
			(xy 131.550032 -262.505788) (xy 131.585118 -262.540874) (xy 131.614283 -262.581017) (xy 131.63681 -262.625228)
			(xy 131.652143 -262.672418) (xy 131.659905 -262.721426) (xy 131.660392 -262.746236) (xy 131.97892 -262.746236)
			(xy 131.98288 -262.697182) (xy 131.994657 -262.649398) (xy 132.013948 -262.604122) (xy 132.040251 -262.562526)
			(xy 132.072886 -262.525689) (xy 132.111007 -262.494564) (xy 132.153628 -262.469957) (xy 132.199644 -262.452505)
			(xy 132.247863 -262.442661) (xy 132.297038 -262.44068) (xy 132.345893 -262.446612) (xy 132.393164 -262.460304)
			(xy 132.437626 -262.481402) (xy 132.478129 -262.509358) (xy 132.513622 -262.54345) (xy 132.543187 -262.582794)
			(xy 132.566058 -262.626371) (xy 132.581642 -262.673052) (xy 132.589537 -262.721629) (xy 132.590032 -262.746236)
			(xy 132.908543 -262.746236) (xy 132.912638 -262.695508) (xy 132.924817 -262.646094) (xy 132.944765 -262.599274)
			(xy 132.971966 -262.55626) (xy 133.005714 -262.518166) (xy 133.045136 -262.485979) (xy 133.08921 -262.460533)
			(xy 133.136796 -262.442486) (xy 133.18666 -262.432306) (xy 133.237512 -262.430257) (xy 133.288033 -262.436391)
			(xy 133.336917 -262.450551) (xy 133.382896 -262.472368) (xy 133.42478 -262.501278) (xy 133.461484 -262.536533)
			(xy 133.492057 -262.577219) (xy 133.515708 -262.622282) (xy 133.531824 -262.670556) (xy 133.539988 -262.72079)
			(xy 133.5405 -262.746236) (xy 133.859028 -262.746236) (xy 133.862988 -262.697182) (xy 133.874765 -262.649398)
			(xy 133.894056 -262.604122) (xy 133.920359 -262.562526) (xy 133.952994 -262.525689) (xy 133.991115 -262.494564)
			(xy 134.033736 -262.469957) (xy 134.079752 -262.452505) (xy 134.127971 -262.442661) (xy 134.177146 -262.44068)
			(xy 134.226001 -262.446612) (xy 134.273272 -262.460304) (xy 134.317734 -262.481402) (xy 134.358237 -262.509358)
			(xy 134.39373 -262.54345) (xy 134.423295 -262.582794) (xy 134.446166 -262.626371) (xy 134.46175 -262.673052)
			(xy 134.469645 -262.721629) (xy 134.47014 -262.746236) (xy 134.798828 -262.746236) (xy 134.802788 -262.697182)
			(xy 134.814565 -262.649398) (xy 134.833856 -262.604122) (xy 134.860159 -262.562526) (xy 134.892794 -262.525689)
			(xy 134.930915 -262.494564) (xy 134.973536 -262.469957) (xy 135.019552 -262.452505) (xy 135.067771 -262.442661)
			(xy 135.116946 -262.44068) (xy 135.165801 -262.446612) (xy 135.213072 -262.460304) (xy 135.257534 -262.481402)
			(xy 135.298037 -262.509358) (xy 135.33353 -262.54345) (xy 135.363095 -262.582794) (xy 135.385966 -262.626371)
			(xy 135.40155 -262.673052) (xy 135.409445 -262.721629) (xy 135.40994 -262.746236) (xy 135.738882 -262.746236)
			(xy 135.742842 -262.697182) (xy 135.754619 -262.649398) (xy 135.77391 -262.604122) (xy 135.800213 -262.562526)
			(xy 135.832848 -262.525689) (xy 135.870969 -262.494564) (xy 135.91359 -262.469957) (xy 135.959606 -262.452505)
			(xy 136.007825 -262.442661) (xy 136.057 -262.44068) (xy 136.105855 -262.446612) (xy 136.153126 -262.460304)
			(xy 136.197588 -262.481402) (xy 136.238091 -262.509358) (xy 136.273584 -262.54345) (xy 136.303149 -262.582794)
			(xy 136.32602 -262.626371) (xy 136.341604 -262.673052) (xy 136.349499 -262.721629) (xy 136.349994 -262.746236)
			(xy 136.678936 -262.746236) (xy 136.682896 -262.697182) (xy 136.694673 -262.649398) (xy 136.713964 -262.604122)
			(xy 136.740267 -262.562526) (xy 136.772902 -262.525689) (xy 136.811023 -262.494564) (xy 136.853644 -262.469957)
			(xy 136.89966 -262.452505) (xy 136.947879 -262.442661) (xy 136.997054 -262.44068) (xy 137.045909 -262.446612)
			(xy 137.09318 -262.460304) (xy 137.137642 -262.481402) (xy 137.178145 -262.509358) (xy 137.213638 -262.54345)
			(xy 137.243203 -262.582794) (xy 137.266074 -262.626371) (xy 137.281658 -262.673052) (xy 137.289553 -262.721629)
			(xy 137.290048 -262.746236) (xy 137.61899 -262.746236) (xy 137.62295 -262.697182) (xy 137.634727 -262.649398)
			(xy 137.654018 -262.604122) (xy 137.680321 -262.562526) (xy 137.712956 -262.525689) (xy 137.751077 -262.494564)
			(xy 137.793698 -262.469957) (xy 137.839714 -262.452505) (xy 137.887933 -262.442661) (xy 137.937108 -262.44068)
			(xy 137.985963 -262.446612) (xy 138.033234 -262.460304) (xy 138.077696 -262.481402) (xy 138.118199 -262.509358)
			(xy 138.153692 -262.54345) (xy 138.183257 -262.582794) (xy 138.206128 -262.626371) (xy 138.221712 -262.673052)
			(xy 138.229607 -262.721629) (xy 138.230102 -262.746236) (xy 138.559044 -262.746236) (xy 138.563004 -262.697182)
			(xy 138.574781 -262.649398) (xy 138.594072 -262.604122) (xy 138.620375 -262.562526) (xy 138.65301 -262.525689)
			(xy 138.691131 -262.494564) (xy 138.733752 -262.469957) (xy 138.779768 -262.452505) (xy 138.827987 -262.442661)
			(xy 138.877162 -262.44068) (xy 138.926017 -262.446612) (xy 138.973288 -262.460304) (xy 139.01775 -262.481402)
			(xy 139.058253 -262.509358) (xy 139.093746 -262.54345) (xy 139.123311 -262.582794) (xy 139.146182 -262.626371)
			(xy 139.161766 -262.673052) (xy 139.169661 -262.721629) (xy 139.170156 -262.746236) (xy 139.498844 -262.746236)
			(xy 139.502804 -262.697182) (xy 139.514581 -262.649398) (xy 139.533872 -262.604122) (xy 139.560175 -262.562526)
			(xy 139.59281 -262.525689) (xy 139.630931 -262.494564) (xy 139.673552 -262.469957) (xy 139.719568 -262.452505)
			(xy 139.767787 -262.442661) (xy 139.816962 -262.44068) (xy 139.865817 -262.446612) (xy 139.913088 -262.460304)
			(xy 139.95755 -262.481402) (xy 139.998053 -262.509358) (xy 140.033546 -262.54345) (xy 140.063111 -262.582794)
			(xy 140.085982 -262.626371) (xy 140.101566 -262.673052) (xy 140.109461 -262.721629) (xy 140.109956 -262.746236)
			(xy 140.109461 -262.770843) (xy 140.101566 -262.81942) (xy 140.085982 -262.866101) (xy 140.063111 -262.909678)
			(xy 140.033546 -262.949022) (xy 139.998053 -262.983114) (xy 139.95755 -263.01107) (xy 139.913088 -263.032168)
			(xy 139.865817 -263.04586) (xy 139.816962 -263.051792) (xy 139.767787 -263.049811) (xy 139.719568 -263.039967)
			(xy 139.673552 -263.022515) (xy 139.630931 -262.997908) (xy 139.59281 -262.966783) (xy 139.560175 -262.929946)
			(xy 139.533872 -262.88835) (xy 139.514581 -262.843074) (xy 139.502804 -262.79529) (xy 139.498844 -262.746236)
			(xy 139.170156 -262.746236) (xy 139.169661 -262.770843) (xy 139.161766 -262.81942) (xy 139.146182 -262.866101)
			(xy 139.123311 -262.909678) (xy 139.093746 -262.949022) (xy 139.058253 -262.983114) (xy 139.01775 -263.01107)
			(xy 138.973288 -263.032168) (xy 138.926017 -263.04586) (xy 138.877162 -263.051792) (xy 138.827987 -263.049811)
			(xy 138.779768 -263.039967) (xy 138.733752 -263.022515) (xy 138.691131 -262.997908) (xy 138.65301 -262.966783)
			(xy 138.620375 -262.929946) (xy 138.594072 -262.88835) (xy 138.574781 -262.843074) (xy 138.563004 -262.79529)
			(xy 138.559044 -262.746236) (xy 138.230102 -262.746236) (xy 138.229607 -262.770843) (xy 138.221712 -262.81942)
			(xy 138.206128 -262.866101) (xy 138.183257 -262.909678) (xy 138.153692 -262.949022) (xy 138.118199 -262.983114)
			(xy 138.077696 -263.01107) (xy 138.033234 -263.032168) (xy 137.985963 -263.04586) (xy 137.937108 -263.051792)
			(xy 137.887933 -263.049811) (xy 137.839714 -263.039967) (xy 137.793698 -263.022515) (xy 137.751077 -262.997908)
			(xy 137.712956 -262.966783) (xy 137.680321 -262.929946) (xy 137.654018 -262.88835) (xy 137.634727 -262.843074)
			(xy 137.62295 -262.79529) (xy 137.61899 -262.746236) (xy 137.290048 -262.746236) (xy 137.289553 -262.770843)
			(xy 137.281658 -262.81942) (xy 137.266074 -262.866101) (xy 137.243203 -262.909678) (xy 137.213638 -262.949022)
			(xy 137.178145 -262.983114) (xy 137.137642 -263.01107) (xy 137.09318 -263.032168) (xy 137.045909 -263.04586)
			(xy 136.997054 -263.051792) (xy 136.947879 -263.049811) (xy 136.89966 -263.039967) (xy 136.853644 -263.022515)
			(xy 136.811023 -262.997908) (xy 136.772902 -262.966783) (xy 136.740267 -262.929946) (xy 136.713964 -262.88835)
			(xy 136.694673 -262.843074) (xy 136.682896 -262.79529) (xy 136.678936 -262.746236) (xy 136.349994 -262.746236)
			(xy 136.349499 -262.770843) (xy 136.341604 -262.81942) (xy 136.32602 -262.866101) (xy 136.303149 -262.909678)
			(xy 136.273584 -262.949022) (xy 136.238091 -262.983114) (xy 136.197588 -263.01107) (xy 136.153126 -263.032168)
			(xy 136.105855 -263.04586) (xy 136.057 -263.051792) (xy 136.007825 -263.049811) (xy 135.959606 -263.039967)
			(xy 135.91359 -263.022515) (xy 135.870969 -262.997908) (xy 135.832848 -262.966783) (xy 135.800213 -262.929946)
			(xy 135.77391 -262.88835) (xy 135.754619 -262.843074) (xy 135.742842 -262.79529) (xy 135.738882 -262.746236)
			(xy 135.40994 -262.746236) (xy 135.409445 -262.770843) (xy 135.40155 -262.81942) (xy 135.385966 -262.866101)
			(xy 135.363095 -262.909678) (xy 135.33353 -262.949022) (xy 135.298037 -262.983114) (xy 135.257534 -263.01107)
			(xy 135.213072 -263.032168) (xy 135.165801 -263.04586) (xy 135.116946 -263.051792) (xy 135.067771 -263.049811)
			(xy 135.019552 -263.039967) (xy 134.973536 -263.022515) (xy 134.930915 -262.997908) (xy 134.892794 -262.966783)
			(xy 134.860159 -262.929946) (xy 134.833856 -262.88835) (xy 134.814565 -262.843074) (xy 134.802788 -262.79529)
			(xy 134.798828 -262.746236) (xy 134.47014 -262.746236) (xy 134.469645 -262.770843) (xy 134.46175 -262.81942)
			(xy 134.446166 -262.866101) (xy 134.423295 -262.909678) (xy 134.39373 -262.949022) (xy 134.358237 -262.983114)
			(xy 134.317734 -263.01107) (xy 134.273272 -263.032168) (xy 134.226001 -263.04586) (xy 134.177146 -263.051792)
			(xy 134.127971 -263.049811) (xy 134.079752 -263.039967) (xy 134.033736 -263.022515) (xy 133.991115 -262.997908)
			(xy 133.952994 -262.966783) (xy 133.920359 -262.929946) (xy 133.894056 -262.88835) (xy 133.874765 -262.843074)
			(xy 133.862988 -262.79529) (xy 133.859028 -262.746236) (xy 133.5405 -262.746236) (xy 133.539988 -262.771682)
			(xy 133.531824 -262.821916) (xy 133.515708 -262.87019) (xy 133.492057 -262.915253) (xy 133.461484 -262.955939)
			(xy 133.42478 -262.991194) (xy 133.382896 -263.020104) (xy 133.336917 -263.041921) (xy 133.288033 -263.056081)
			(xy 133.237512 -263.062215) (xy 133.18666 -263.060166) (xy 133.136796 -263.049986) (xy 133.08921 -263.031939)
			(xy 133.045136 -263.006493) (xy 133.005714 -262.974306) (xy 132.971966 -262.936212) (xy 132.944765 -262.893198)
			(xy 132.924817 -262.846378) (xy 132.912638 -262.796964) (xy 132.908543 -262.746236) (xy 132.590032 -262.746236)
			(xy 132.589537 -262.770843) (xy 132.581642 -262.81942) (xy 132.566058 -262.866101) (xy 132.543187 -262.909678)
			(xy 132.513622 -262.949022) (xy 132.478129 -262.983114) (xy 132.437626 -263.01107) (xy 132.393164 -263.032168)
			(xy 132.345893 -263.04586) (xy 132.297038 -263.051792) (xy 132.247863 -263.049811) (xy 132.199644 -263.039967)
			(xy 132.153628 -263.022515) (xy 132.111007 -262.997908) (xy 132.072886 -262.966783) (xy 132.040251 -262.929946)
			(xy 132.013948 -262.88835) (xy 131.994657 -262.843074) (xy 131.98288 -262.79529) (xy 131.97892 -262.746236)
			(xy 131.660392 -262.746236) (xy 131.65997 -262.769943) (xy 131.652885 -262.816824) (xy 131.638864 -262.862117)
			(xy 131.618223 -262.904802) (xy 131.591427 -262.943917) (xy 131.55908 -262.978582) (xy 131.540758 -262.993632)
			(xy 131.525264 -263.005824) (xy 131.52247 -263.011158) (xy 131.518914 -263.091422) (xy 131.519127 -263.101728)
			(xy 131.526723 -263.12087) (xy 131.533646 -263.128506) (xy 131.65836 -263.25322) (xy 131.663538 -263.258035)
			(xy 131.675911 -263.264864) (xy 131.682744 -263.266682) (xy 131.687062 -263.267698) (xy 131.707267 -263.259147)
			(xy 131.749446 -263.247068) (xy 131.792888 -263.240923) (xy 131.814824 -263.24052) (xy 131.839627 -263.240984)
			(xy 131.888622 -263.248751) (xy 131.935798 -263.264091) (xy 131.979992 -263.286624) (xy 132.020114 -263.315796)
			(xy 132.055177 -263.350889) (xy 132.084315 -263.391036) (xy 132.106811 -263.435248) (xy 132.122111 -263.482437)
			(xy 132.129837 -263.531438) (xy 132.130292 -263.556242) (xy 132.129741 -263.583871) (xy 132.120158 -263.63829)
			(xy 132.111242 -263.664446) (xy 132.108956 -263.670796) (xy 132.106651 -263.677801) (xy 132.105757 -263.692515)
			(xy 132.107178 -263.699752) (xy 132.107686 -263.702546) (xy 132.285486 -263.880346) (xy 132.290985 -263.885334)
			(xy 132.30415 -263.892182) (xy 132.311394 -263.893808) (xy 132.321046 -263.894824)
		)
		(stroke
			(width 0)
			(type solid)
		)
		(fill yes)
		(layer "In6.Cu")
		(net "PVDDCR_SOC_P1")
	)
	(gr_poly
		(pts
			(xy 164.34943 -339.166708) (xy 164.359587 -339.166262) (xy 164.378321 -339.158406) (xy 164.385752 -339.151468)
			(xy 170.40225 -333.00035) (xy 170.402758 -332.999842) (xy 174.551594 -328.851006) (xy 174.558992 -328.844158)
			(xy 174.57759 -328.83642) (xy 174.587662 -328.83602) (xy 195.841366 -328.83602) (xy 195.85143 -328.836456)
			(xy 195.870016 -328.844189) (xy 195.877434 -328.851006) (xy 197.823074 -330.796646) (xy 197.823582 -330.797154)
			(xy 197.830965 -330.803732) (xy 197.849264 -330.811172) (xy 197.859142 -330.811632) (xy 205.434692 -330.811632)
			(xy 205.444564 -330.81116) (xy 205.462846 -330.803701) (xy 205.470252 -330.797154) (xy 205.470506 -330.7969)
			(xy 206.263748 -330.003658) (xy 206.264256 -330.00315) (xy 206.270838 -329.995769) (xy 206.278289 -329.97747)
			(xy 206.278734 -329.96759) (xy 206.278734 -321.510914) (xy 206.278293 -321.500852) (xy 206.27055 -321.482277)
			(xy 206.263748 -321.474846) (xy 206.11084 -321.321938) (xy 206.103728 -321.314572) (xy 206.084932 -321.306952)
			(xy 165.74135 -321.306952) (xy 165.731285 -321.306518) (xy 165.712698 -321.298786) (xy 165.705282 -321.291966)
			(xy 164.65423 -320.240914) (xy 164.646828 -320.234077) (xy 164.62823 -320.226366) (xy 164.618162 -320.225928)
			(xy 162.14725 -320.225928) (xy 162.137183 -320.225497) (xy 162.118589 -320.217773) (xy 162.111182 -320.210942)
			(xy 145.879566 -303.979326) (xy 145.872724 -303.971927) (xy 145.865006 -303.953328) (xy 145.86458 -303.943258)
			(xy 145.86458 -302.984916) (xy 145.85696 -302.96612) (xy 145.849594 -302.959008) (xy 145.648172 -302.757332)
			(xy 144.90827 -302.017684) (xy 144.885544 -301.994321) (xy 144.844923 -301.943349) (xy 144.810267 -301.888147)
			(xy 144.782012 -301.829411) (xy 144.760513 -301.76788) (xy 144.74604 -301.704329) (xy 144.738777 -301.639556)
			(xy 144.738344 -301.606966) (xy 144.738344 -299.959522) (xy 144.73809 -299.959522) (xy 144.73809 -296.520616)
			(xy 144.738314 -296.500289) (xy 144.741236 -296.459739) (xy 144.743932 -296.43959) (xy 144.746466 -296.422341)
			(xy 144.753331 -296.388155) (xy 144.757648 -296.371264) (xy 144.758156 -296.36974) (xy 144.759934 -296.363136)
			(xy 144.759934 -296.192956) (xy 144.75333 -296.176446) (xy 144.750028 -296.168064) (xy 144.723612 -296.12971)
			(xy 144.710272 -296.109579) (xy 144.68942 -296.066021) (xy 144.67566 -296.019731) (xy 144.67205 -295.995852)
			(xy 144.671034 -295.987724) (xy 144.656302 -295.95699) (xy 144.649952 -295.95064) (xy 144.616514 -295.916932)
			(xy 144.554789 -295.844775) (xy 144.499338 -295.767693) (xy 144.45055 -295.68623) (xy 144.429226 -295.643808)
			(xy 144.405387 -295.593752) (xy 144.366455 -295.489933) (xy 144.351502 -295.436544) (xy 144.350486 -295.431972)
			(xy 144.345406 -295.421304) (xy 144.341088 -295.413938) (xy 144.32915 -295.396412) (xy 144.322292 -295.391332)
			(xy 144.305334 -295.378213) (xy 144.274904 -295.348012) (xy 144.248984 -295.313861) (xy 144.238218 -295.29532)
			(xy 144.224638 -295.269651) (xy 144.206346 -295.214543) (xy 144.201896 -295.185846) (xy 144.20088 -295.177718)
			(xy 144.191482 -295.15816) (xy 144.187418 -295.151048) (xy 144.180052 -295.140634) (xy 144.17675 -295.137332)
			(xy 144.141864 -295.101865) (xy 144.077771 -295.02577) (xy 144.020614 -294.944335) (xy 143.970837 -294.858191)
			(xy 143.928826 -294.768005) (xy 143.894905 -294.674475) (xy 143.881602 -294.626538) (xy 143.880586 -294.621966)
			(xy 143.875506 -294.611044) (xy 143.871188 -294.603678) (xy 143.858742 -294.585644) (xy 143.852138 -294.580818)
			(xy 143.83271 -294.565687) (xy 143.798495 -294.530276) (xy 143.770395 -294.489841) (xy 143.749137 -294.445426)
			(xy 143.735268 -294.398179) (xy 143.731742 -294.373808) (xy 143.730726 -294.365426) (xy 143.715994 -294.334946)
			(xy 143.709644 -294.32885) (xy 143.687294 -294.306477) (xy 143.644851 -294.259586) (xy 143.624808 -294.235124)
			(xy 143.606962 -294.212834) (xy 143.573291 -294.166711) (xy 143.557498 -294.142922) (xy 143.554704 -294.138604)
			(xy 143.268192 -293.852092) (xy 143.259672 -293.844513) (xy 143.238176 -293.836997) (xy 143.22679 -293.837614)
			(xy 143.226536 -293.837614) (xy 143.193952 -293.84119) (xy 143.128505 -293.845003) (xy 143.095726 -293.845234)
			(xy 143.093948 -293.845234) (xy 143.040662 -293.844616) (xy 142.934567 -293.834563) (xy 142.882112 -293.825168)
			(xy 142.871952 -293.823136) (xy 142.851221 -293.818858) (xy 142.810062 -293.808951) (xy 142.789656 -293.803324)
			(xy 142.787878 -293.802816) (xy 142.78356 -293.8018) (xy 142.778197 -293.800857) (xy 142.767311 -293.800994)
			(xy 142.76197 -293.802054) (xy 142.750286 -293.804594) (xy 142.746222 -293.806626) (xy 142.724986 -293.815312)
			(xy 142.6806 -293.826926) (xy 142.65783 -293.82974) (xy 142.62481 -293.831518) (xy 142.594254 -293.830781)
			(xy 142.534362 -293.818627) (xy 142.505938 -293.807388) (xy 142.503398 -293.806372) (xy 142.494508 -293.803578)
			(xy 142.47876 -293.799768) (xy 142.468346 -293.801546) (xy 142.465298 -293.802054) (xy 142.462504 -293.802816)
			(xy 142.424673 -293.813148) (xy 142.347895 -293.829166) (xy 142.309088 -293.83482) (xy 142.276981 -293.839043)
			(xy 142.212425 -293.844253) (xy 142.180056 -293.845234) (xy 142.168626 -293.845488) (xy 142.139162 -293.859966)
			(xy 142.133574 -293.865046) (xy 142.125358 -293.872333) (xy 142.115519 -293.891941) (xy 142.114695 -293.913864)
			(xy 142.118334 -293.924228) (xy 142.155926 -294.014906) (xy 142.177516 -294.031416) (xy 142.191486 -294.033194)
			(xy 142.215847 -294.036657) (xy 142.263103 -294.050355) (xy 142.30755 -294.071454) (xy 142.34804 -294.099407)
			(xy 142.383523 -294.133491) (xy 142.413081 -294.172823) (xy 142.43595 -294.216386) (xy 142.451538 -294.263053)
			(xy 142.459441 -294.311616) (xy 142.459964 -294.336216) (xy 142.788906 -294.336216) (xy 142.792866 -294.287162)
			(xy 142.804643 -294.239378) (xy 142.823934 -294.194102) (xy 142.850237 -294.152506) (xy 142.882872 -294.115669)
			(xy 142.920993 -294.084544) (xy 142.963614 -294.059937) (xy 143.00963 -294.042485) (xy 143.057849 -294.032641)
			(xy 143.107024 -294.03066) (xy 143.155879 -294.036592) (xy 143.20315 -294.050284) (xy 143.247612 -294.071382)
			(xy 143.288115 -294.099338) (xy 143.323608 -294.13343) (xy 143.353173 -294.172774) (xy 143.376044 -294.216351)
			(xy 143.391628 -294.263032) (xy 143.399523 -294.311609) (xy 143.400018 -294.336216) (xy 143.399523 -294.360823)
			(xy 143.391628 -294.4094) (xy 143.376044 -294.456081) (xy 143.353173 -294.499658) (xy 143.323608 -294.539002)
			(xy 143.288115 -294.573094) (xy 143.247612 -294.60105) (xy 143.20315 -294.622148) (xy 143.155879 -294.63584)
			(xy 143.107024 -294.641772) (xy 143.057849 -294.639791) (xy 143.00963 -294.629947) (xy 142.963614 -294.612495)
			(xy 142.920993 -294.587888) (xy 142.882872 -294.556763) (xy 142.850237 -294.519926) (xy 142.823934 -294.47833)
			(xy 142.804643 -294.433054) (xy 142.792866 -294.38527) (xy 142.788906 -294.336216) (xy 142.459964 -294.336216)
			(xy 142.459442 -294.361471) (xy 142.451129 -294.411293) (xy 142.434728 -294.459067) (xy 142.410687 -294.50349)
			(xy 142.379663 -294.54335) (xy 142.342501 -294.57756) (xy 142.300215 -294.605186) (xy 142.253959 -294.625476)
			(xy 142.204994 -294.637876) (xy 142.154656 -294.642047) (xy 142.104318 -294.637876) (xy 142.055353 -294.625476)
			(xy 142.009097 -294.605186) (xy 141.966811 -294.57756) (xy 141.929649 -294.54335) (xy 141.898625 -294.50349)
			(xy 141.874584 -294.459067) (xy 141.858183 -294.411293) (xy 141.84987 -294.361471) (xy 141.849348 -294.336216)
			(xy 141.849348 -294.335454) (xy 141.850082 -294.305995) (xy 141.861467 -294.248185) (xy 141.871954 -294.220646)
			(xy 141.874494 -294.21201) (xy 141.87551 -294.2082) (xy 141.877302 -294.197258) (xy 141.872438 -294.175649)
			(xy 141.866112 -294.166544) (xy 141.814042 -294.098726) (xy 141.809783 -294.093541) (xy 141.7991 -294.085429)
			(xy 141.79296 -294.082724) (xy 141.786577 -294.080345) (xy 141.773062 -294.078683) (xy 141.76629 -294.079422)
			(xy 141.746024 -294.082246) (xy 141.705216 -294.085297) (xy 141.684756 -294.085518) (xy 141.664359 -294.085301)
			(xy 141.623677 -294.08225) (xy 141.603476 -294.079422) (xy 141.58976 -294.07739) (xy 141.564106 -294.087804)
			(xy 141.49451 -294.178228) (xy 141.490954 -294.205152) (xy 141.496288 -294.217852) (xy 141.50739 -294.24611)
			(xy 141.519417 -294.305611) (xy 141.520164 -294.335962) (xy 141.520164 -294.33647) (xy 141.519673 -294.360446)
			(xy 141.512133 -294.407803) (xy 141.497281 -294.453398) (xy 141.475483 -294.49611) (xy 141.447274 -294.534888)
			(xy 141.413349 -294.568778) (xy 141.374542 -294.596947) (xy 141.331807 -294.618702) (xy 141.286197 -294.633507)
			(xy 141.238833 -294.640998) (xy 141.214856 -294.641524) (xy 141.190867 -294.64105) (xy 141.143479 -294.633539)
			(xy 141.09785 -294.618708) (xy 141.055102 -294.596922) (xy 141.016288 -294.568718) (xy 140.982364 -294.53479)
			(xy 140.954163 -294.495974) (xy 140.932382 -294.453224) (xy 140.917555 -294.407593) (xy 140.910048 -294.360205)
			(xy 140.909548 -294.336216) (xy 140.910016 -294.311612) (xy 140.917909 -294.263041) (xy 140.933493 -294.216366)
			(xy 140.956366 -294.172797) (xy 140.985932 -294.133462) (xy 141.021428 -294.099381) (xy 141.061932 -294.071438)
			(xy 141.106395 -294.050355) (xy 141.153664 -294.036681) (xy 141.178026 -294.033194) (xy 141.191996 -294.031416)
			(xy 141.213586 -294.014906) (xy 141.25702 -293.909496) (xy 141.25321 -293.882572) (xy 141.244828 -293.87165)
			(xy 141.232925 -293.856207) (xy 141.211059 -293.82392) (xy 141.20114 -293.807134) (xy 141.152372 -293.723568)
			(xy 141.145539 -293.713126) (xy 141.124371 -293.699961) (xy 141.111986 -293.698422) (xy 141.017498 -293.692072)
			(xy 140.994384 -293.70274) (xy 140.98651 -293.7129) (xy 140.971959 -293.731061) (xy 140.938284 -293.763179)
			(xy 140.900124 -293.789811) (xy 140.858362 -293.810342) (xy 140.813968 -293.824294) (xy 140.76797 -293.831344)
			(xy 140.744702 -293.831772) (xy 140.732002 -293.831518) (xy 140.719302 -293.830502) (xy 140.694187 -293.827882)
			(xy 140.645248 -293.815459) (xy 140.59902 -293.795151) (xy 140.556764 -293.767513) (xy 140.519633 -293.733298)
			(xy 140.488638 -293.693439) (xy 140.464624 -293.649024) (xy 140.448247 -293.601262) (xy 140.439953 -293.551456)
			(xy 140.439394 -293.52621) (xy 140.439874 -293.501876) (xy 140.447606 -293.453826) (xy 140.462861 -293.407611)
			(xy 140.485253 -293.364399) (xy 140.514214 -293.325286) (xy 140.549011 -293.291261) (xy 140.588765 -293.263185)
			(xy 140.632468 -293.241769) (xy 140.679014 -293.227555) (xy 140.703046 -293.223696) (xy 140.715324 -293.221319)
			(xy 140.735569 -293.206681) (xy 140.741654 -293.195756) (xy 140.777722 -293.122096) (xy 140.78259 -293.110539)
			(xy 140.78166 -293.085506) (xy 140.775944 -293.074344) (xy 140.73124 -292.997128) (xy 140.720695 -292.978593)
			(xy 140.702131 -292.940197) (xy 140.694156 -292.92042) (xy 140.689076 -292.907466) (xy 140.667232 -292.890448)
			(xy 140.554202 -292.875716) (xy 140.528802 -292.886638) (xy 140.52042 -292.89756) (xy 140.505923 -292.916438)
			(xy 140.472061 -292.949884) (xy 140.433415 -292.977666) (xy 140.390925 -292.99911) (xy 140.34562 -293.013697)
			(xy 140.2986 -293.021072) (xy 140.274802 -293.021512) (xy 140.249544 -293.021019) (xy 140.199716 -293.012705)
			(xy 140.151937 -292.996303) (xy 140.107509 -292.97226) (xy 140.067645 -292.941232) (xy 140.033431 -292.904066)
			(xy 140.005801 -292.861776) (xy 139.985509 -292.815514) (xy 139.973108 -292.766544) (xy 139.968936 -292.7162)
			(xy 139.973108 -292.665856) (xy 139.985509 -292.616886) (xy 140.005801 -292.570624) (xy 140.033431 -292.528334)
			(xy 140.067645 -292.491168) (xy 140.107509 -292.46014) (xy 140.151937 -292.436097) (xy 140.199716 -292.419695)
			(xy 140.249544 -292.411381) (xy 140.274802 -292.410896) (xy 140.298587 -292.411341) (xy 140.345586 -292.418697)
			(xy 140.390877 -292.433247) (xy 140.433366 -292.454639) (xy 140.472028 -292.482356) (xy 140.505928 -292.515729)
			(xy 140.52042 -292.534594) (xy 140.528802 -292.54577) (xy 140.554202 -292.556692) (xy 140.65377 -292.543484)
			(xy 140.662687 -292.541936) (xy 140.678676 -292.533484) (xy 140.690735 -292.520006) (xy 140.69441 -292.511734)
			(xy 140.704484 -292.487085) (xy 140.728658 -292.439635) (xy 140.74267 -292.416992) (xy 140.755271 -292.397456)
			(xy 140.78325 -292.360326) (xy 140.79855 -292.342824) (xy 140.8049 -292.335712) (xy 140.811504 -292.31844)
			(xy 140.811504 -292.28288) (xy 140.811026 -292.272542) (xy 140.802913 -292.253524) (xy 140.795756 -292.24605)
			(xy 140.781024 -292.23208) (xy 140.777537 -292.228901) (xy 140.769609 -292.223787) (xy 140.765276 -292.22192)
			(xy 140.74013 -292.21176) (xy 140.731494 -292.211252) (xy 140.706977 -292.209699) (xy 140.658873 -292.199744)
			(xy 140.612983 -292.182217) (xy 140.570492 -292.157568) (xy 140.532495 -292.126435) (xy 140.499972 -292.08962)
			(xy 140.473763 -292.048073) (xy 140.454544 -292.002865) (xy 140.442811 -291.955164) (xy 140.438866 -291.9062)
			(xy 140.442811 -291.857236) (xy 140.454544 -291.809534) (xy 140.473763 -291.764327) (xy 140.499972 -291.72278)
			(xy 140.532495 -291.685965) (xy 140.570492 -291.654832) (xy 140.612983 -291.630183) (xy 140.658873 -291.612656)
			(xy 140.706977 -291.602701) (xy 140.731494 -291.601144) (xy 140.74013 -291.600636) (xy 140.765276 -291.590476)
			(xy 140.769596 -291.588584) (xy 140.777525 -291.583478) (xy 140.781024 -291.580316) (xy 140.795756 -291.566346)
			(xy 140.802907 -291.558867) (xy 140.811022 -291.539854) (xy 140.811504 -291.529516) (xy 140.811504 -291.515038)
			(xy 140.73124 -291.377116) (xy 140.720695 -291.358581) (xy 140.702132 -291.320185) (xy 140.694156 -291.300408)
			(xy 140.689076 -291.287454) (xy 140.667232 -291.270436) (xy 140.554202 -291.255704) (xy 140.528802 -291.266626)
			(xy 140.52042 -291.277548) (xy 140.505921 -291.296422) (xy 140.472054 -291.329858) (xy 140.433407 -291.357632)
			(xy 140.390918 -291.37907) (xy 140.345615 -291.393653) (xy 140.298598 -291.401025) (xy 140.274802 -291.4015)
			(xy 140.249545 -291.401008) (xy 140.199719 -291.392693) (xy 140.151942 -291.376292) (xy 140.107516 -291.35225)
			(xy 140.067653 -291.321223) (xy 140.03344 -291.284059) (xy 140.005811 -291.24177) (xy 139.98552 -291.19551)
			(xy 139.973119 -291.146542) (xy 139.968948 -291.0962) (xy 139.973119 -291.045858) (xy 139.98552 -290.99689)
			(xy 140.005811 -290.95063) (xy 140.03344 -290.908341) (xy 140.067653 -290.871177) (xy 140.107516 -290.84015)
			(xy 140.151942 -290.816108) (xy 140.199719 -290.799707) (xy 140.249545 -290.791392) (xy 140.274802 -290.790884)
			(xy 140.298588 -290.791329) (xy 140.345586 -290.798685) (xy 140.390878 -290.813234) (xy 140.433368 -290.834626)
			(xy 140.47203 -290.862342) (xy 140.505931 -290.895714) (xy 140.52042 -290.914582) (xy 140.528802 -290.925758)
			(xy 140.554202 -290.93668) (xy 140.65377 -290.923472) (xy 140.662686 -290.921924) (xy 140.678674 -290.913471)
			(xy 140.69073 -290.899991) (xy 140.69441 -290.891722) (xy 140.70448 -290.867071) (xy 140.728648 -290.819618)
			(xy 140.74267 -290.79698) (xy 140.755271 -290.777445) (xy 140.783251 -290.740315) (xy 140.79855 -290.722812)
			(xy 140.8049 -290.7157) (xy 140.811504 -290.698428) (xy 140.811504 -290.662868) (xy 140.811024 -290.652531)
			(xy 140.802907 -290.633516) (xy 140.795756 -290.626038) (xy 140.781024 -290.612068) (xy 140.777537 -290.60889)
			(xy 140.769608 -290.603777) (xy 140.765276 -290.601908) (xy 140.74013 -290.591748) (xy 140.731494 -290.59124)
			(xy 140.706978 -290.589687) (xy 140.658876 -290.579733) (xy 140.612988 -290.562206) (xy 140.570498 -290.537558)
			(xy 140.532503 -290.506426) (xy 140.499981 -290.469612) (xy 140.473774 -290.428067) (xy 140.454555 -290.382861)
			(xy 140.442823 -290.335162) (xy 140.438878 -290.286199) (xy 140.442823 -290.237237) (xy 140.454556 -290.189538)
			(xy 140.473774 -290.144332) (xy 140.499982 -290.102787) (xy 140.532503 -290.065973) (xy 140.570499 -290.034841)
			(xy 140.612989 -290.010194) (xy 140.658877 -289.992667) (xy 140.706979 -289.982713) (xy 140.731494 -289.981132)
			(xy 140.74013 -289.980624) (xy 140.765276 -289.970464) (xy 140.769596 -289.968571) (xy 140.777524 -289.963465)
			(xy 140.781024 -289.960304) (xy 140.795756 -289.946334) (xy 140.802906 -289.938854) (xy 140.811016 -289.919841)
			(xy 140.811504 -289.909504) (xy 140.811504 -289.895026) (xy 140.73124 -289.757104) (xy 140.720695 -289.738569)
			(xy 140.702134 -289.700172) (xy 140.694156 -289.680396) (xy 140.689076 -289.667442) (xy 140.667232 -289.650424)
			(xy 140.554202 -289.635692) (xy 140.528802 -289.646614) (xy 140.52042 -289.657536) (xy 140.505921 -289.67641)
			(xy 140.472055 -289.709848) (xy 140.433408 -289.737623) (xy 140.390919 -289.759062) (xy 140.345616 -289.773645)
			(xy 140.298598 -289.781018) (xy 140.274802 -289.781488) (xy 140.249546 -289.780996) (xy 140.199722 -289.772682)
			(xy 140.151947 -289.756281) (xy 140.107522 -289.73224) (xy 140.067661 -289.701215) (xy 140.03345 -289.664051)
			(xy 140.005822 -289.621764) (xy 139.985531 -289.575506) (xy 139.973131 -289.52654) (xy 139.96896 -289.4762)
			(xy 139.973131 -289.42586) (xy 139.985531 -289.376894) (xy 140.005822 -289.330636) (xy 140.03345 -289.288349)
			(xy 140.067661 -289.251185) (xy 140.107522 -289.22016) (xy 140.151947 -289.196119) (xy 140.199722 -289.179718)
			(xy 140.249546 -289.171404) (xy 140.274802 -289.170872) (xy 140.298588 -289.171317) (xy 140.345587 -289.178673)
			(xy 140.390878 -289.193222) (xy 140.433369 -289.214612) (xy 140.472032 -289.242328) (xy 140.505934 -289.2757)
			(xy 140.52042 -289.29457) (xy 140.528802 -289.305746) (xy 140.554202 -289.316668) (xy 140.65377 -289.30346)
			(xy 140.662686 -289.301912) (xy 140.678672 -289.293458) (xy 140.690725 -289.279977) (xy 140.69441 -289.27171)
			(xy 140.704481 -289.247059) (xy 140.728649 -289.199606) (xy 140.74267 -289.176968) (xy 140.755269 -289.157431)
			(xy 140.783244 -289.120297) (xy 140.79855 -289.1028) (xy 140.8049 -289.095688) (xy 140.811504 -289.078416)
			(xy 140.811504 -289.042856) (xy 140.811022 -289.03252) (xy 140.802902 -289.013508) (xy 140.795756 -289.006026)
			(xy 140.781024 -288.992056) (xy 140.77754 -288.988873) (xy 140.769615 -288.983752) (xy 140.765276 -288.981896)
			(xy 140.74013 -288.971736) (xy 140.731494 -288.971228) (xy 140.706979 -288.969675) (xy 140.658879 -288.959721)
			(xy 140.612993 -288.942195) (xy 140.570505 -288.917548) (xy 140.532511 -288.886417) (xy 140.499991 -288.849605)
			(xy 140.473784 -288.808061) (xy 140.454567 -288.762857) (xy 140.442834 -288.715159) (xy 140.43889 -288.666199)
			(xy 140.442835 -288.617238) (xy 140.454567 -288.569541) (xy 140.473785 -288.524337) (xy 140.499992 -288.482794)
			(xy 140.532512 -288.445981) (xy 140.570506 -288.414851) (xy 140.612995 -288.390204) (xy 140.658881 -288.372678)
			(xy 140.706981 -288.362725) (xy 140.731494 -288.36112) (xy 140.74013 -288.360612) (xy 140.765276 -288.350452)
			(xy 140.769596 -288.348559) (xy 140.777523 -288.343451) (xy 140.781024 -288.340292) (xy 140.795756 -288.326322)
			(xy 140.802919 -288.318847) (xy 140.811063 -288.299835) (xy 140.811504 -288.289492) (xy 140.811504 -288.275268)
			(xy 140.73124 -288.137346) (xy 140.720694 -288.118811) (xy 140.70213 -288.080416) (xy 140.694156 -288.060638)
			(xy 140.689076 -288.047684) (xy 140.667232 -288.030666) (xy 140.554202 -288.015934) (xy 140.528802 -288.026856)
			(xy 140.52042 -288.037778) (xy 140.505923 -288.056655) (xy 140.472059 -288.090099) (xy 140.433414 -288.11788)
			(xy 140.390924 -288.139323) (xy 140.345619 -288.153909) (xy 140.298599 -288.161284) (xy 140.274802 -288.16173)
			(xy 140.249542 -288.161237) (xy 140.199712 -288.152923) (xy 140.15193 -288.136519) (xy 140.107499 -288.112475)
			(xy 140.067633 -288.081445) (xy 140.033417 -288.044277) (xy 140.005785 -288.001984) (xy 139.985492 -287.95572)
			(xy 139.97309 -287.906747) (xy 139.968918 -287.8564) (xy 139.97309 -287.806053) (xy 139.985492 -287.75708)
			(xy 140.005785 -287.710816) (xy 140.033417 -287.668523) (xy 140.067633 -287.631355) (xy 140.107499 -287.600325)
			(xy 140.15193 -287.576281) (xy 140.199712 -287.559877) (xy 140.249542 -287.551563) (xy 140.274802 -287.551114)
			(xy 140.298587 -287.551559) (xy 140.345585 -287.558916) (xy 140.390876 -287.573466) (xy 140.433364 -287.594859)
			(xy 140.472025 -287.622577) (xy 140.505923 -287.655951) (xy 140.52042 -287.674812) (xy 140.528802 -287.685988)
			(xy 140.554202 -287.69691) (xy 140.65377 -287.683702) (xy 140.662688 -287.682155) (xy 140.67868 -287.673705)
			(xy 140.690743 -287.660228) (xy 140.69441 -287.651952) (xy 140.704483 -287.627302) (xy 140.728656 -287.579852)
			(xy 140.74267 -287.55721) (xy 140.75527 -287.537674) (xy 140.783248 -287.500543) (xy 140.79855 -287.483042)
			(xy 140.8049 -287.47593) (xy 140.811504 -287.458658) (xy 140.811504 -287.422844) (xy 140.81102 -287.412509)
			(xy 140.802897 -287.393501) (xy 140.795756 -287.386014) (xy 140.781024 -287.372044) (xy 140.777539 -287.368862)
			(xy 140.769614 -287.363741) (xy 140.765276 -287.361884) (xy 140.74013 -287.351724) (xy 140.731494 -287.351216)
			(xy 140.70698 -287.349663) (xy 140.658881 -287.339709) (xy 140.612997 -287.322184) (xy 140.570511 -287.297538)
			(xy 140.532518 -287.266408) (xy 140.5 -287.229597) (xy 140.473794 -287.188055) (xy 140.454578 -287.142853)
			(xy 140.442846 -287.095157) (xy 140.438902 -287.046198) (xy 140.442847 -286.99724) (xy 140.454579 -286.949544)
			(xy 140.473796 -286.904342) (xy 140.500002 -286.8628) (xy 140.532521 -286.82599) (xy 140.570514 -286.79486)
			(xy 140.613 -286.770215) (xy 140.658885 -286.75269) (xy 140.706983 -286.742737) (xy 140.731494 -286.741108)
			(xy 140.74013 -286.7406) (xy 140.765276 -286.73044) (xy 140.769595 -286.728546) (xy 140.777522 -286.723438)
			(xy 140.781024 -286.72028) (xy 140.795756 -286.70631) (xy 140.802918 -286.698835) (xy 140.811056 -286.679822)
			(xy 140.811504 -286.66948) (xy 140.811504 -286.655256) (xy 140.73124 -286.517334) (xy 140.720695 -286.498799)
			(xy 140.702131 -286.460404) (xy 140.694156 -286.440626) (xy 140.689076 -286.427672) (xy 140.667232 -286.410654)
			(xy 140.554202 -286.395922) (xy 140.528802 -286.406844) (xy 140.52042 -286.417766) (xy 140.505923 -286.436644)
			(xy 140.47206 -286.470089) (xy 140.433415 -286.497871) (xy 140.390925 -286.519315) (xy 140.34562 -286.533901)
			(xy 140.2986 -286.541277) (xy 140.274802 -286.541718) (xy 140.249543 -286.541225) (xy 140.199715 -286.532911)
			(xy 140.151935 -286.516508) (xy 140.107506 -286.492465) (xy 140.067641 -286.461437) (xy 140.033426 -286.42427)
			(xy 140.005796 -286.381979) (xy 139.985503 -286.335716) (xy 139.973102 -286.286745) (xy 139.96893 -286.2364)
			(xy 139.973102 -286.186055) (xy 139.985503 -286.137084) (xy 140.005796 -286.090821) (xy 140.033426 -286.04853)
			(xy 140.067641 -286.011363) (xy 140.107506 -285.980335) (xy 140.151935 -285.956292) (xy 140.199715 -285.939889)
			(xy 140.249543 -285.931575) (xy 140.274802 -285.931102) (xy 140.298587 -285.931547) (xy 140.345586 -285.938904)
			(xy 140.390876 -285.953453) (xy 140.433366 -285.974845) (xy 140.472027 -286.002563) (xy 140.505926 -286.035936)
			(xy 140.52042 -286.0548) (xy 140.528802 -286.065976) (xy 140.554202 -286.076898) (xy 140.65377 -286.06369)
			(xy 140.662687 -286.062143) (xy 140.678677 -286.053691) (xy 140.690738 -286.040213) (xy 140.69441 -286.03194)
			(xy 140.704483 -286.007291) (xy 140.728657 -285.959841) (xy 140.74267 -285.937198) (xy 140.755271 -285.917662)
			(xy 140.783249 -285.880532) (xy 140.79855 -285.86303) (xy 140.8049 -285.855918) (xy 140.811504 -285.838646)
			(xy 140.811504 -285.803086) (xy 140.811027 -285.792747) (xy 140.802915 -285.773727) (xy 140.795756 -285.766256)
			(xy 140.781024 -285.752286) (xy 140.777537 -285.749107) (xy 140.76961 -285.743992) (xy 140.765276 -285.742126)
			(xy 140.74013 -285.731966) (xy 140.731494 -285.731458) (xy 140.706976 -285.729905) (xy 140.658871 -285.71995)
			(xy 140.612981 -285.702422) (xy 140.570489 -285.677773) (xy 140.532491 -285.64664) (xy 140.499967 -285.609824)
			(xy 140.473758 -285.568276) (xy 140.454539 -285.523068) (xy 140.442805 -285.475365) (xy 140.43886 -285.4264)
			(xy 140.442805 -285.377435) (xy 140.454539 -285.329733) (xy 140.473758 -285.284525) (xy 140.499967 -285.242977)
			(xy 140.53249 -285.206161) (xy 140.570488 -285.175027) (xy 140.612981 -285.150378) (xy 140.658871 -285.13285)
			(xy 140.706976 -285.122895) (xy 140.731494 -285.12135) (xy 140.74013 -285.120842) (xy 140.765276 -285.110682)
			(xy 140.769596 -285.10879) (xy 140.777525 -285.103684) (xy 140.781024 -285.100522) (xy 140.795756 -285.086552)
			(xy 140.802908 -285.079073) (xy 140.811025 -285.06006) (xy 140.811504 -285.049722) (xy 140.811504 -285.035244)
			(xy 140.73124 -284.897322) (xy 140.720695 -284.878787) (xy 140.702132 -284.840391) (xy 140.694156 -284.820614)
			(xy 140.689076 -284.80766) (xy 140.667232 -284.790642) (xy 140.554202 -284.77591) (xy 140.528802 -284.786832)
			(xy 140.52042 -284.797754) (xy 140.50592 -284.816627) (xy 140.472053 -284.850063) (xy 140.433407 -284.877837)
			(xy 140.390917 -284.899275) (xy 140.345615 -284.913856) (xy 140.298598 -284.921229) (xy 140.274802 -284.921706)
			(xy 140.249544 -284.921213) (xy 140.199718 -284.912899) (xy 140.15194 -284.896497) (xy 140.107513 -284.872455)
			(xy 140.067649 -284.841428) (xy 140.033436 -284.804263) (xy 140.005806 -284.761973) (xy 139.985514 -284.715712)
			(xy 139.973114 -284.666743) (xy 139.968942 -284.6164) (xy 139.973114 -284.566057) (xy 139.985514 -284.517088)
			(xy 140.005806 -284.470827) (xy 140.033436 -284.428537) (xy 140.067649 -284.391372) (xy 140.107513 -284.360345)
			(xy 140.15194 -284.336303) (xy 140.199718 -284.319901) (xy 140.249544 -284.311587) (xy 140.274802 -284.31109)
			(xy 140.298588 -284.311535) (xy 140.345586 -284.318891) (xy 140.390877 -284.333441) (xy 140.433367 -284.354832)
			(xy 140.472029 -284.382549) (xy 140.505929 -284.415922) (xy 140.52042 -284.434788) (xy 140.528802 -284.445964)
			(xy 140.554202 -284.456886) (xy 140.65377 -284.443678) (xy 140.662687 -284.44213) (xy 140.678675 -284.433678)
			(xy 140.690733 -284.420198) (xy 140.69441 -284.411928) (xy 140.704484 -284.387279) (xy 140.728659 -284.33983)
			(xy 140.74267 -284.317186) (xy 140.755271 -284.29765) (xy 140.78325 -284.260521) (xy 140.79855 -284.243018)
			(xy 140.8049 -284.235906) (xy 140.811504 -284.218634) (xy 140.811504 -284.183074) (xy 140.811025 -284.172736)
			(xy 140.80291 -284.15372) (xy 140.795756 -284.146244) (xy 140.781024 -284.132274) (xy 140.777537 -284.129096)
			(xy 140.769609 -284.123982) (xy 140.765276 -284.122114) (xy 140.74013 -284.111954) (xy 140.731494 -284.111446)
			(xy 140.706977 -284.109893) (xy 140.658874 -284.099939) (xy 140.612986 -284.082411) (xy 140.570495 -284.057763)
			(xy 140.532499 -284.026631) (xy 140.499977 -283.989816) (xy 140.473768 -283.94827) (xy 140.45455 -283.903063)
			(xy 140.442817 -283.855363) (xy 140.438872 -283.8064) (xy 140.442817 -283.757436) (xy 140.45455 -283.709736)
			(xy 140.473769 -283.66453) (xy 140.499977 -283.622983) (xy 140.532499 -283.586169) (xy 140.570496 -283.555036)
			(xy 140.612986 -283.530388) (xy 140.658875 -283.512861) (xy 140.706978 -283.502907) (xy 140.731494 -283.501338)
			(xy 140.74013 -283.50083) (xy 140.765276 -283.49067) (xy 140.769596 -283.488777) (xy 140.777524 -283.483671)
			(xy 140.781024 -283.48051) (xy 140.795756 -283.46654) (xy 140.802906 -283.459061) (xy 140.811019 -283.440048)
			(xy 140.811504 -283.42971) (xy 140.811504 -283.415232) (xy 140.73124 -283.27731) (xy 140.720695 -283.258775)
			(xy 140.702133 -283.220379) (xy 140.694156 -283.200602) (xy 140.689076 -283.187648) (xy 140.667232 -283.17063)
			(xy 140.554202 -283.155898) (xy 140.528802 -283.16682) (xy 140.52042 -283.177742) (xy 140.505921 -283.196616)
			(xy 140.472054 -283.230053) (xy 140.433408 -283.257828) (xy 140.390918 -283.279266) (xy 140.345615 -283.293849)
			(xy 140.298598 -283.301222) (xy 140.274802 -283.301694) (xy 140.249545 -283.301202) (xy 140.199721 -283.292888)
			(xy 140.151944 -283.276486) (xy 140.107519 -283.252445) (xy 140.067657 -283.221419) (xy 140.033445 -283.184255)
			(xy 140.005817 -283.141967) (xy 139.985526 -283.095708) (xy 139.973125 -283.046741) (xy 139.968954 -282.9964)
			(xy 139.973125 -282.946059) (xy 139.985526 -282.897092) (xy 140.005817 -282.850833) (xy 140.033445 -282.808545)
			(xy 140.067657 -282.771381) (xy 140.107519 -282.740355) (xy 140.151944 -282.716314) (xy 140.199721 -282.699912)
			(xy 140.249545 -282.691598) (xy 140.274802 -282.691078) (xy 140.298588 -282.691523) (xy 140.345586 -282.698879)
			(xy 140.390878 -282.713428) (xy 140.433368 -282.734819) (xy 140.472031 -282.762535) (xy 140.505933 -282.795907)
			(xy 140.52042 -282.814776) (xy 140.528802 -282.825952) (xy 140.554202 -282.836874) (xy 140.65377 -282.823666)
			(xy 140.662686 -282.822118) (xy 140.678673 -282.813664) (xy 140.690728 -282.800184) (xy 140.69441 -282.791916)
			(xy 140.70448 -282.767265) (xy 140.728649 -282.719812) (xy 140.74267 -282.697174) (xy 140.755271 -282.677639)
			(xy 140.783251 -282.640509) (xy 140.79855 -282.623006) (xy 140.8049 -282.615894) (xy 140.811504 -282.598622)
			(xy 140.811504 -282.563062) (xy 140.811023 -282.552725) (xy 140.802905 -282.533712) (xy 140.795756 -282.526232)
			(xy 140.781024 -282.512262) (xy 140.77754 -282.509079) (xy 140.769615 -282.503957) (xy 140.765276 -282.502102)
			(xy 140.74013 -282.491942) (xy 140.731494 -282.491434) (xy 140.706978 -282.489881) (xy 140.658877 -282.479927)
			(xy 140.61299 -282.4624) (xy 140.570501 -282.437753) (xy 140.532507 -282.406622) (xy 140.499986 -282.369808)
			(xy 140.473779 -282.328264) (xy 140.454561 -282.283059) (xy 140.442828 -282.235361) (xy 140.438884 -282.186399)
			(xy 140.442829 -282.137438) (xy 140.454562 -282.089739) (xy 140.47378 -282.044535) (xy 140.499987 -282.00299)
			(xy 140.532508 -281.966177) (xy 140.570503 -281.935046) (xy 140.612992 -281.910399) (xy 140.658879 -281.892873)
			(xy 140.70698 -281.882919) (xy 140.731494 -281.881326) (xy 140.74013 -281.880818) (xy 140.765276 -281.870658)
			(xy 140.769596 -281.868765) (xy 140.777523 -281.863658) (xy 140.781024 -281.860498) (xy 140.795756 -281.846528)
			(xy 140.802905 -281.839048) (xy 140.811013 -281.820035) (xy 140.811504 -281.809698) (xy 140.811504 -281.79522)
			(xy 140.73124 -281.657298) (xy 140.720696 -281.638763) (xy 140.702134 -281.600366) (xy 140.694156 -281.58059)
			(xy 140.689076 -281.567636) (xy 140.667232 -281.550618) (xy 140.554202 -281.535886) (xy 140.528802 -281.546808)
			(xy 140.52042 -281.55773) (xy 140.505921 -281.576605) (xy 140.472055 -281.610043) (xy 140.433409 -281.637819)
			(xy 140.390919 -281.659258) (xy 140.345616 -281.673841) (xy 140.298598 -281.681215) (xy 140.274802 -281.681682)
			(xy 140.249546 -281.68119) (xy 140.199724 -281.672876) (xy 140.151949 -281.656475) (xy 140.107526 -281.632435)
			(xy 140.067665 -281.60141) (xy 140.033455 -281.564248) (xy 140.005827 -281.521961) (xy 139.985537 -281.475705)
			(xy 139.973137 -281.426739) (xy 139.968966 -281.3764) (xy 139.973137 -281.326061) (xy 139.985537 -281.277095)
			(xy 140.005827 -281.230839) (xy 140.033455 -281.188552) (xy 140.067665 -281.15139) (xy 140.107526 -281.120365)
			(xy 140.151949 -281.096325) (xy 140.199724 -281.079924) (xy 140.249546 -281.07161) (xy 140.274802 -281.071066)
			(xy 140.298588 -281.071511) (xy 140.345587 -281.078867) (xy 140.390879 -281.093416) (xy 140.43337 -281.114806)
			(xy 140.472033 -281.142521) (xy 140.505936 -281.175893) (xy 140.52042 -281.194764) (xy 140.528802 -281.20594)
			(xy 140.554202 -281.216862) (xy 140.65377 -281.203654) (xy 140.662686 -281.202106) (xy 140.678671 -281.193651)
			(xy 140.690723 -281.18017) (xy 140.69441 -281.171904) (xy 140.704481 -281.147253) (xy 140.72865 -281.099801)
			(xy 140.74267 -281.077162) (xy 140.755269 -281.057625) (xy 140.783244 -281.020492) (xy 140.79855 -281.002994)
			(xy 140.8049 -280.995882) (xy 140.811504 -280.97861) (xy 140.811504 -280.94305) (xy 140.811021 -280.932714)
			(xy 140.802899 -280.913704) (xy 140.795756 -280.90622) (xy 140.781024 -280.89225) (xy 140.777539 -280.889068)
			(xy 140.769614 -280.883947) (xy 140.765276 -280.88209) (xy 140.74013 -280.87193) (xy 140.731494 -280.871422)
			(xy 140.706979 -280.869869) (xy 140.65888 -280.859915) (xy 140.612995 -280.842389) (xy 140.570508 -280.817743)
			(xy 140.532515 -280.786613) (xy 140.499995 -280.749801) (xy 140.473789 -280.708258) (xy 140.454572 -280.663055)
			(xy 140.44284 -280.615358) (xy 140.438896 -280.566399) (xy 140.442841 -280.517439) (xy 140.454573 -280.469743)
			(xy 140.473791 -280.42454) (xy 140.499997 -280.382997) (xy 140.532517 -280.346186) (xy 140.57051 -280.315055)
			(xy 140.612998 -280.29041) (xy 140.658883 -280.272884) (xy 140.706982 -280.262931) (xy 140.731494 -280.261314)
			(xy 140.74013 -280.260806) (xy 140.765276 -280.250646) (xy 140.769595 -280.248753) (xy 140.777522 -280.243645)
			(xy 140.781024 -280.240486) (xy 140.795756 -280.226516) (xy 140.802919 -280.219041) (xy 140.811059 -280.200028)
			(xy 140.811504 -280.189686) (xy 140.811504 -280.175208) (xy 140.73124 -280.037286) (xy 140.720696 -280.01875)
			(xy 140.702135 -279.980354) (xy 140.694156 -279.960578) (xy 140.689076 -279.947624) (xy 140.667232 -279.930606)
			(xy 140.554202 -279.915874) (xy 140.528802 -279.926796) (xy 140.52042 -279.937718) (xy 140.505922 -279.956593)
			(xy 140.472056 -279.990033) (xy 140.43341 -280.01781) (xy 140.39092 -280.03925) (xy 140.345617 -280.053834)
			(xy 140.298599 -280.061208) (xy 140.274802 -280.06167) (xy 140.249547 -280.061178) (xy 140.199727 -280.052864)
			(xy 140.151954 -280.036464) (xy 140.107532 -280.012425) (xy 140.067673 -279.981401) (xy 140.033464 -279.94424)
			(xy 140.005838 -279.901956) (xy 139.985548 -279.855701) (xy 139.973149 -279.806737) (xy 139.968978 -279.7564)
			(xy 139.973149 -279.706063) (xy 139.985548 -279.657099) (xy 140.005838 -279.610844) (xy 140.033464 -279.56856)
			(xy 140.067673 -279.531399) (xy 140.107532 -279.500375) (xy 140.151954 -279.476336) (xy 140.199727 -279.459936)
			(xy 140.249547 -279.451622) (xy 140.274802 -279.451054) (xy 140.298588 -279.451499) (xy 140.345587 -279.458855)
			(xy 140.39088 -279.473403) (xy 140.433371 -279.494793) (xy 140.472036 -279.522508) (xy 140.505939 -279.555878)
			(xy 140.52042 -279.574752) (xy 140.528802 -279.585928) (xy 140.554202 -279.59685) (xy 140.65377 -279.583642)
			(xy 140.662685 -279.582093) (xy 140.678668 -279.573638) (xy 140.690718 -279.560155) (xy 140.69441 -279.551892)
			(xy 140.704481 -279.527242) (xy 140.728651 -279.47979) (xy 140.74267 -279.45715) (xy 140.755269 -279.437613)
			(xy 140.783245 -279.40048) (xy 140.79855 -279.382982) (xy 140.8049 -279.37587) (xy 140.811504 -279.358598)
			(xy 140.811504 -279.323038) (xy 140.811018 -279.312703) (xy 140.802894 -279.293697) (xy 140.795756 -279.286208)
			(xy 140.781024 -279.272238) (xy 140.777539 -279.269056) (xy 140.769613 -279.263936) (xy 140.765276 -279.262078)
			(xy 140.74013 -279.251918) (xy 140.731494 -279.25141) (xy 140.70698 -279.249857) (xy 140.658883 -279.239904)
			(xy 140.613 -279.222378) (xy 140.570514 -279.197733) (xy 140.532522 -279.166604) (xy 140.500005 -279.129793)
			(xy 140.4738 -279.088252) (xy 140.454583 -279.04305) (xy 140.442852 -278.995356) (xy 140.438908 -278.946398)
			(xy 140.442853 -278.89744) (xy 140.454585 -278.849746) (xy 140.473801 -278.804545) (xy 140.500007 -278.763004)
			(xy 140.532525 -278.726194) (xy 140.570517 -278.695065) (xy 140.613003 -278.67042) (xy 140.658887 -278.652895)
			(xy 140.706984 -278.642943) (xy 140.731494 -278.641302) (xy 140.74013 -278.640794) (xy 140.765276 -278.630634)
			(xy 140.769595 -278.62874) (xy 140.777521 -278.623631) (xy 140.781024 -278.620474) (xy 140.795756 -278.606504)
			(xy 140.802917 -278.599028) (xy 140.811053 -278.580015) (xy 140.811504 -278.569674) (xy 140.811504 -278.555196)
			(xy 140.73124 -278.417274) (xy 140.720693 -278.39874) (xy 140.702127 -278.360345) (xy 140.694156 -278.340566)
			(xy 140.689076 -278.327612) (xy 140.667232 -278.310594) (xy 140.554202 -278.295862) (xy 140.528802 -278.306784)
			(xy 140.52042 -278.317706) (xy 140.505922 -278.336582) (xy 140.472057 -278.370023) (xy 140.433411 -278.397801)
			(xy 140.390921 -278.419242) (xy 140.345617 -278.433826) (xy 140.298599 -278.4412) (xy 140.274802 -278.441658)
			(xy 140.24954 -278.441165) (xy 140.199705 -278.43285) (xy 140.151919 -278.416445) (xy 140.107484 -278.392398)
			(xy 140.067614 -278.361366) (xy 140.033395 -278.324194) (xy 140.00576 -278.281898) (xy 139.985465 -278.235629)
			(xy 139.973062 -278.186651) (xy 139.96889 -278.1363) (xy 139.973062 -278.085949) (xy 139.985465 -278.036971)
			(xy 140.00576 -277.990702) (xy 140.033395 -277.948406) (xy 140.067614 -277.911234) (xy 140.107484 -277.880202)
			(xy 140.151919 -277.856155) (xy 140.199705 -277.83975) (xy 140.24954 -277.831435) (xy 140.274802 -277.831042)
			(xy 140.298587 -277.831488) (xy 140.345584 -277.838844) (xy 140.390874 -277.853395) (xy 140.433361 -277.874789)
			(xy 140.47202 -277.902509) (xy 140.505915 -277.935885) (xy 140.52042 -277.95474) (xy 140.528802 -277.965916)
			(xy 140.554202 -277.976838) (xy 140.65377 -277.96363) (xy 140.662689 -277.962084) (xy 140.678685 -277.953636)
			(xy 140.690755 -277.940161) (xy 140.69441 -277.93188) (xy 140.704482 -277.90723) (xy 140.728653 -277.859778)
			(xy 140.74267 -277.837138) (xy 140.75527 -277.817601) (xy 140.783246 -277.780469) (xy 140.79855 -277.76297)
			(xy 140.8049 -277.755858) (xy 140.811504 -277.738586) (xy 140.811504 -277.703026) (xy 140.811016 -277.692692)
			(xy 140.802889 -277.673689) (xy 140.795756 -277.666196) (xy 140.781024 -277.652226) (xy 140.777539 -277.649045)
			(xy 140.769613 -277.643926) (xy 140.765276 -277.642066) (xy 140.74013 -277.631906) (xy 140.731494 -277.631398)
			(xy 140.706973 -277.629845) (xy 140.658862 -277.619889) (xy 140.612965 -277.602359) (xy 140.570467 -277.577707)
			(xy 140.532464 -277.546569) (xy 140.499937 -277.509749) (xy 140.473723 -277.468196) (xy 140.454501 -277.422982)
			(xy 140.442766 -277.375274) (xy 140.43882 -277.326302) (xy 140.442765 -277.27733) (xy 140.4545 -277.229622)
			(xy 140.473722 -277.184408) (xy 140.499934 -277.142854) (xy 140.532461 -277.106033) (xy 140.570464 -277.074895)
			(xy 140.612962 -277.050243) (xy 140.658858 -277.032712) (xy 140.706969 -277.022756) (xy 140.731494 -277.02129)
			(xy 140.74013 -277.020782) (xy 140.765276 -277.010622) (xy 140.769595 -277.008728) (xy 140.77752 -277.003618)
			(xy 140.781024 -277.000462) (xy 140.795756 -276.986492) (xy 140.802915 -276.979016) (xy 140.811047 -276.960003)
			(xy 140.811504 -276.949662) (xy 140.811504 -276.935184) (xy 140.73124 -276.797262) (xy 140.720694 -276.778727)
			(xy 140.702128 -276.740333) (xy 140.694156 -276.720554) (xy 140.689076 -276.7076) (xy 140.667232 -276.690582)
			(xy 140.554202 -276.67585) (xy 140.528802 -276.686772) (xy 140.52042 -276.697694) (xy 140.505922 -276.716571)
			(xy 140.472058 -276.750013) (xy 140.433412 -276.777792) (xy 140.390922 -276.799234) (xy 140.345618 -276.813819)
			(xy 140.298599 -276.821193) (xy 140.274802 -276.821646) (xy 140.249541 -276.821153) (xy 140.199708 -276.812838)
			(xy 140.151924 -276.796434) (xy 140.107491 -276.772388) (xy 140.067622 -276.741357) (xy 140.033404 -276.704187)
			(xy 140.005771 -276.661892) (xy 139.985477 -276.615625) (xy 139.973074 -276.566649) (xy 139.968902 -276.5163)
			(xy 139.973074 -276.465951) (xy 139.985477 -276.416975) (xy 140.005771 -276.370708) (xy 140.033404 -276.328413)
			(xy 140.067622 -276.291243) (xy 140.107491 -276.260212) (xy 140.151924 -276.236166) (xy 140.199708 -276.219762)
			(xy 140.249541 -276.211447) (xy 140.274802 -276.21103) (xy 140.298587 -276.211476) (xy 140.345585 -276.218832)
			(xy 140.390874 -276.233383) (xy 140.433362 -276.254776) (xy 140.472022 -276.282495) (xy 140.505919 -276.31587)
			(xy 140.52042 -276.334728) (xy 140.528802 -276.345904) (xy 140.554202 -276.356826) (xy 140.65377 -276.343618)
			(xy 140.662689 -276.342072) (xy 140.678683 -276.333623) (xy 140.69075 -276.320147) (xy 140.69441 -276.311868)
			(xy 140.704482 -276.287218) (xy 140.728654 -276.239767) (xy 140.74267 -276.217126) (xy 140.75527 -276.19759)
			(xy 140.783247 -276.160458) (xy 140.79855 -276.142958) (xy 140.8049 -276.135846) (xy 140.811504 -276.118574)
			(xy 140.811504 -276.083014) (xy 140.811014 -276.072681) (xy 140.802884 -276.053681) (xy 140.795756 -276.046184)
			(xy 140.781024 -276.032214) (xy 140.777538 -276.029034) (xy 140.769612 -276.023916) (xy 140.765276 -276.022054)
			(xy 140.74013 -276.011894) (xy 140.731494 -276.011386) (xy 140.706974 -276.009833) (xy 140.658865 -275.999877)
			(xy 140.61297 -275.982348) (xy 140.570474 -275.957697) (xy 140.532472 -275.92656) (xy 140.499946 -275.889741)
			(xy 140.473734 -275.84819) (xy 140.454512 -275.802978) (xy 140.442778 -275.755271) (xy 140.438832 -275.706301)
			(xy 140.442777 -275.657332) (xy 140.454512 -275.609625) (xy 140.473733 -275.564413) (xy 140.499944 -275.522861)
			(xy 140.53247 -275.486041) (xy 140.570471 -275.454904) (xy 140.612967 -275.430253) (xy 140.658862 -275.412723)
			(xy 140.706971 -275.402768) (xy 140.731494 -275.401278) (xy 140.74013 -275.40077) (xy 140.765276 -275.39061)
			(xy 140.769595 -275.388715) (xy 140.777519 -275.383605) (xy 140.781024 -275.38045) (xy 140.795756 -275.36648)
			(xy 140.802913 -275.359003) (xy 140.81104 -275.33999) (xy 140.811504 -275.32965) (xy 140.811504 -275.315172)
			(xy 140.73124 -275.17725) (xy 140.720694 -275.158715) (xy 140.702129 -275.12032) (xy 140.694156 -275.100542)
			(xy 140.689076 -275.087588) (xy 140.667232 -275.07057) (xy 140.554202 -275.055838) (xy 140.528802 -275.06676)
			(xy 140.52042 -275.077682) (xy 140.505923 -275.096559) (xy 140.472059 -275.130003) (xy 140.433413 -275.157783)
			(xy 140.390923 -275.179226) (xy 140.345619 -275.193811) (xy 140.298599 -275.201186) (xy 140.274802 -275.201634)
			(xy 140.249542 -275.201141) (xy 140.199711 -275.192826) (xy 140.151928 -275.176423) (xy 140.107497 -275.152378)
			(xy 140.06763 -275.121348) (xy 140.033413 -275.08418) (xy 140.005782 -275.041886) (xy 139.985488 -274.995621)
			(xy 139.973086 -274.946647) (xy 139.968914 -274.8963) (xy 139.973086 -274.845953) (xy 139.985488 -274.796979)
			(xy 140.005782 -274.750714) (xy 140.033413 -274.70842) (xy 140.06763 -274.671252) (xy 140.107497 -274.640222)
			(xy 140.151928 -274.616177) (xy 140.199711 -274.599774) (xy 140.249542 -274.591459) (xy 140.274802 -274.591018)
			(xy 140.298587 -274.591464) (xy 140.345585 -274.59882) (xy 140.390875 -274.61337) (xy 140.433364 -274.634763)
			(xy 140.472024 -274.662481) (xy 140.505922 -274.695856) (xy 140.52042 -274.714716) (xy 140.528802 -274.725892)
			(xy 140.554202 -274.736814) (xy 140.65377 -274.723606) (xy 140.662688 -274.72206) (xy 140.678681 -274.713609)
			(xy 140.690745 -274.700132) (xy 140.69441 -274.691856) (xy 140.704483 -274.667206) (xy 140.728655 -274.619756)
			(xy 140.74267 -274.597114) (xy 140.75527 -274.577578) (xy 140.783248 -274.540447) (xy 140.79855 -274.522946)
			(xy 140.8049 -274.515834) (xy 140.811504 -274.498562) (xy 140.811504 -274.463002) (xy 140.811012 -274.452671)
			(xy 140.802878 -274.433674) (xy 140.795756 -274.426172) (xy 140.781024 -274.412202) (xy 140.777538 -274.409022)
			(xy 140.769611 -274.403906) (xy 140.765276 -274.402042) (xy 140.74013 -274.391882) (xy 140.731494 -274.391374)
			(xy 140.706975 -274.389821) (xy 140.658868 -274.379866) (xy 140.612975 -274.362337) (xy 140.57048 -274.337687)
			(xy 140.53248 -274.306551) (xy 140.499955 -274.269734) (xy 140.473744 -274.228184) (xy 140.454524 -274.182973)
			(xy 140.442789 -274.135269) (xy 140.438844 -274.086301) (xy 140.442789 -274.037333) (xy 140.454523 -273.989628)
			(xy 140.473743 -273.944418) (xy 140.499954 -273.902868) (xy 140.532479 -273.86605) (xy 140.570479 -273.834914)
			(xy 140.612973 -273.810264) (xy 140.658866 -273.792735) (xy 140.706973 -273.782779) (xy 140.731494 -273.781266)
			(xy 140.74013 -273.780758) (xy 140.765276 -273.770598) (xy 140.769594 -273.768703) (xy 140.777518 -273.763592)
			(xy 140.781024 -273.760438) (xy 140.795756 -273.746468) (xy 140.802911 -273.73899) (xy 140.811034 -273.719977)
			(xy 140.811504 -273.709638) (xy 140.811504 -273.69516) (xy 140.73124 -273.557238) (xy 140.720694 -273.538703)
			(xy 140.70213 -273.500308) (xy 140.694156 -273.48053) (xy 140.689076 -273.467576) (xy 140.667232 -273.450558)
			(xy 140.554202 -273.435826) (xy 140.528802 -273.446748) (xy 140.52042 -273.45767) (xy 140.505923 -273.476548)
			(xy 140.47206 -273.509993) (xy 140.433415 -273.537774) (xy 140.390924 -273.559218) (xy 140.34562 -273.573804)
			(xy 140.2986 -273.581179) (xy 140.274802 -273.581622) (xy 140.249543 -273.581129) (xy 140.199714 -273.572815)
			(xy 140.151933 -273.556412) (xy 140.107504 -273.532368) (xy 140.067638 -273.50134) (xy 140.033423 -273.464172)
			(xy 140.005792 -273.42188) (xy 139.985499 -273.375618) (xy 139.973098 -273.326645) (xy 139.968926 -273.2763)
			(xy 139.973098 -273.225955) (xy 139.985499 -273.176982) (xy 140.005792 -273.13072) (xy 140.033423 -273.088428)
			(xy 140.067638 -273.05126) (xy 140.107504 -273.020232) (xy 140.151933 -272.996188) (xy 140.199714 -272.979785)
			(xy 140.249543 -272.971471) (xy 140.274802 -272.971006) (xy 140.298587 -272.971451) (xy 140.345586 -272.978808)
			(xy 140.390876 -272.993358) (xy 140.433365 -273.01475) (xy 140.472026 -273.042468) (xy 140.505925 -273.075841)
			(xy 140.52042 -273.094704) (xy 140.528802 -273.10588) (xy 140.554202 -273.116802) (xy 140.65377 -273.103594)
			(xy 140.662688 -273.102047) (xy 140.678678 -273.093596) (xy 140.69074 -273.080118) (xy 140.69441 -273.071844)
			(xy 140.704483 -273.047195) (xy 140.728657 -272.999745) (xy 140.74267 -272.977102) (xy 140.75527 -272.957566)
			(xy 140.783249 -272.920436) (xy 140.79855 -272.902934) (xy 140.8049 -272.895822) (xy 140.811504 -272.87855)
			(xy 140.811504 -272.84299) (xy 140.811028 -272.832651) (xy 140.802917 -272.81363) (xy 140.795756 -272.80616)
			(xy 140.781024 -272.79219) (xy 140.777537 -272.789011) (xy 140.76961 -272.783896) (xy 140.765276 -272.78203)
			(xy 140.74013 -272.77187) (xy 140.731494 -272.771362) (xy 140.706976 -272.769809) (xy 140.658871 -272.759854)
			(xy 140.612979 -272.742326) (xy 140.570486 -272.717677) (xy 140.532488 -272.686542) (xy 140.499964 -272.649726)
			(xy 140.473755 -272.608178) (xy 140.454535 -272.562969) (xy 140.442801 -272.515266) (xy 140.438856 -272.4663)
			(xy 140.442801 -272.417334) (xy 140.454535 -272.369632) (xy 140.473754 -272.324423) (xy 140.499964 -272.282874)
			(xy 140.532488 -272.246058) (xy 140.570486 -272.214924) (xy 140.612979 -272.190274) (xy 140.65887 -272.172746)
			(xy 140.706975 -272.162791) (xy 140.731494 -272.161254) (xy 140.74013 -272.160746) (xy 140.765276 -272.150586)
			(xy 140.769596 -272.148694) (xy 140.777526 -272.143589) (xy 140.781024 -272.140426) (xy 140.795756 -272.126456)
			(xy 140.802909 -272.118978) (xy 140.811027 -272.099965) (xy 140.811504 -272.089626) (xy 140.811504 -272.075148)
			(xy 140.73124 -271.937226) (xy 140.720695 -271.918691) (xy 140.702132 -271.880295) (xy 140.694156 -271.860518)
			(xy 140.689076 -271.847564) (xy 140.667232 -271.830546) (xy 140.554202 -271.815814) (xy 140.528802 -271.826736)
			(xy 140.52042 -271.837658) (xy 140.50592 -271.856531) (xy 140.472053 -271.889967) (xy 140.433406 -271.91774)
			(xy 140.390917 -271.939177) (xy 140.345614 -271.953759) (xy 140.298598 -271.961131) (xy 140.274802 -271.96161)
			(xy 140.249544 -271.961117) (xy 140.199717 -271.952803) (xy 140.151938 -271.936401) (xy 140.10751 -271.912358)
			(xy 140.067646 -271.881331) (xy 140.033432 -271.844165) (xy 140.005803 -271.801875) (xy 139.985511 -271.755614)
			(xy 139.97311 -271.706643) (xy 139.968938 -271.6563) (xy 139.97311 -271.605957) (xy 139.985511 -271.556986)
			(xy 140.005803 -271.510725) (xy 140.033432 -271.468435) (xy 140.067646 -271.431269) (xy 140.10751 -271.400242)
			(xy 140.151938 -271.376199) (xy 140.199717 -271.359797) (xy 140.249544 -271.351483) (xy 140.274802 -271.350994)
			(xy 140.298587 -271.351439) (xy 140.345586 -271.358795) (xy 140.390877 -271.373345) (xy 140.433367 -271.394737)
			(xy 140.472028 -271.422454) (xy 140.505928 -271.455827) (xy 140.52042 -271.474692) (xy 140.528802 -271.485868)
			(xy 140.554202 -271.49679) (xy 140.65377 -271.483582) (xy 140.662687 -271.482034) (xy 140.678676 -271.473582)
			(xy 140.690734 -271.460103) (xy 140.69441 -271.451832) (xy 140.704484 -271.427183) (xy 140.728658 -271.379734)
			(xy 140.74267 -271.35709) (xy 140.755271 -271.337554) (xy 140.78325 -271.300424) (xy 140.79855 -271.282922)
			(xy 140.8049 -271.27581) (xy 140.811504 -271.258538) (xy 140.811504 -271.222978) (xy 140.811026 -271.21264)
			(xy 140.802912 -271.193622) (xy 140.795756 -271.186148) (xy 140.781024 -271.172178) (xy 140.777537 -271.168999)
			(xy 140.769609 -271.163885) (xy 140.765276 -271.162018) (xy 140.74013 -271.151858) (xy 140.731494 -271.15135)
			(xy 140.706977 -271.149797) (xy 140.658873 -271.139842) (xy 140.612984 -271.122315) (xy 140.570493 -271.097667)
			(xy 140.532496 -271.066534) (xy 140.499974 -271.029719) (xy 140.473765 -270.988172) (xy 140.454546 -270.942965)
			(xy 140.442813 -270.895264) (xy 140.438868 -270.8463) (xy 140.442813 -270.797336) (xy 140.454546 -270.749635)
			(xy 140.473765 -270.704428) (xy 140.499974 -270.662881) (xy 140.532496 -270.626066) (xy 140.570493 -270.594933)
			(xy 140.612984 -270.570285) (xy 140.658874 -270.552758) (xy 140.706977 -270.542803) (xy 140.731494 -270.541242)
			(xy 140.74013 -270.540734) (xy 140.765276 -270.530574) (xy 140.769596 -270.528681) (xy 140.777525 -270.523576)
			(xy 140.781024 -270.520414) (xy 140.795756 -270.506444) (xy 140.802907 -270.498965) (xy 140.811021 -270.479952)
			(xy 140.811504 -270.469614) (xy 140.811504 -270.455136) (xy 140.73124 -270.317214) (xy 140.720695 -270.298679)
			(xy 140.702133 -270.260283) (xy 140.694156 -270.240506) (xy 140.689076 -270.227552) (xy 140.667232 -270.210534)
			(xy 140.554202 -270.195802) (xy 140.528802 -270.206724) (xy 140.52042 -270.217646) (xy 140.505921 -270.23652)
			(xy 140.472054 -270.269957) (xy 140.433407 -270.297731) (xy 140.390918 -270.319169) (xy 140.345615 -270.333751)
			(xy 140.298598 -270.341124) (xy 140.274802 -270.341598) (xy 140.249545 -270.341106) (xy 140.19972 -270.332791)
			(xy 140.151943 -270.31639) (xy 140.107517 -270.292348) (xy 140.067654 -270.261322) (xy 140.033442 -270.224158)
			(xy 140.005813 -270.181869) (xy 139.985522 -270.13561) (xy 139.973121 -270.086641) (xy 139.96895 -270.0363)
			(xy 139.973121 -269.985959) (xy 139.985522 -269.93699) (xy 140.005813 -269.890731) (xy 140.033442 -269.848442)
			(xy 140.067654 -269.811278) (xy 140.107517 -269.780252) (xy 140.151943 -269.75621) (xy 140.19972 -269.739809)
			(xy 140.249545 -269.731494) (xy 140.274802 -269.730982) (xy 140.298588 -269.731427) (xy 140.345586 -269.738783)
			(xy 140.390878 -269.753332) (xy 140.433368 -269.774723) (xy 140.47203 -269.80244) (xy 140.505932 -269.835812)
			(xy 140.52042 -269.85468) (xy 140.528802 -269.865856) (xy 140.554202 -269.876778) (xy 140.65377 -269.86357)
			(xy 140.662686 -269.862022) (xy 140.678674 -269.853569) (xy 140.690729 -269.840089) (xy 140.69441 -269.83182)
			(xy 140.70448 -269.807169) (xy 140.728648 -269.759716) (xy 140.74267 -269.737078) (xy 140.755271 -269.717543)
			(xy 140.783251 -269.680413) (xy 140.79855 -269.66291) (xy 140.8049 -269.655798) (xy 140.811504 -269.638526)
			(xy 140.811504 -269.602966) (xy 140.811024 -269.592629) (xy 140.802907 -269.573615) (xy 140.795756 -269.566136)
			(xy 140.781024 -269.552166) (xy 140.777537 -269.548988) (xy 140.769608 -269.543875) (xy 140.765276 -269.542006)
			(xy 140.740384 -269.531846) (xy 140.731494 -269.531338) (xy 140.708029 -269.52989) (xy 140.661926 -269.520684)
			(xy 140.617779 -269.504522) (xy 140.57663 -269.481787) (xy 140.539451 -269.453015) (xy 140.507119 -269.418885)
			(xy 140.480399 -269.380204) (xy 140.459922 -269.337886) (xy 140.446171 -269.29293) (xy 140.442442 -269.269718)
			(xy 140.441426 -269.261844) (xy 140.440469 -269.252985) (xy 140.43945 -269.235194) (xy 140.439394 -269.226284)
			(xy 140.439944 -269.200444) (xy 140.448659 -269.149504) (xy 140.46582 -269.100756) (xy 140.490939 -269.055591)
			(xy 140.523299 -269.015296) (xy 140.561978 -268.98102) (xy 140.605872 -268.953741) (xy 140.653731 -268.934236)
			(xy 140.704188 -268.923061) (xy 140.72997 -268.92123) (xy 140.739622 -268.920722) (xy 140.75664 -268.913356)
			(xy 140.763498 -268.906498) (xy 140.770176 -268.899051) (xy 140.777753 -268.880561) (xy 140.777741 -268.860578)
			(xy 140.770142 -268.842098) (xy 140.763498 -268.834616) (xy 140.74648 -268.817598) (xy 140.739368 -268.810232)
			(xy 140.720572 -268.802612) (xy 130.503168 -268.802612) (xy 130.493327 -268.802083) (xy 130.475155 -268.794507)
			(xy 130.467862 -268.78788) (xy 130.302254 -268.622272) (xy 130.294888 -268.614652) (xy 130.275838 -268.607032)
			(xy 130.202178 -268.608556) (xy 130.192018 -268.609318) (xy 130.15849 -268.62405) (xy 130.151886 -268.630908)
			(xy 130.134567 -268.64778) (xy 130.095587 -268.676382) (xy 130.052585 -268.698482) (xy 130.006636 -268.713524)
			(xy 129.95889 -268.721134) (xy 129.934716 -268.721586) (xy 129.911066 -268.721137) (xy 129.864334 -268.713833)
			(xy 129.819286 -268.699415) (xy 129.776999 -268.678225) (xy 129.738483 -268.65077) (xy 129.704658 -268.617707)
			(xy 129.676334 -268.579826) (xy 129.654188 -268.538032) (xy 129.638747 -268.493323) (xy 129.630383 -268.44677)
			(xy 129.629408 -268.423136) (xy 129.629154 -268.41323) (xy 129.625344 -268.404086) (xy 129.623281 -268.399565)
			(xy 129.617647 -268.391379) (xy 129.614168 -268.38783) (xy 129.564638 -268.33957) (xy 129.557257 -268.332987)
			(xy 129.538958 -268.325536) (xy 129.529078 -268.325092) (xy 129.4003 -268.325092) (xy 129.390421 -268.325549)
			(xy 129.372118 -268.332987) (xy 129.36474 -268.33957) (xy 129.31521 -268.38783) (xy 129.311745 -268.39139)
			(xy 129.306115 -268.399575) (xy 129.304034 -268.404086) (xy 129.300224 -268.41323) (xy 129.29997 -268.423136)
			(xy 129.298919 -268.44802) (xy 129.289737 -268.496969) (xy 129.272733 -268.543779) (xy 129.248359 -268.58721)
			(xy 129.217262 -268.62611) (xy 129.180264 -268.659449) (xy 129.138347 -268.686342) (xy 129.092621 -268.706078)
			(xy 129.044299 -268.718133) (xy 128.994662 -268.722187) (xy 128.945025 -268.718133) (xy 128.896703 -268.706078)
			(xy 128.850977 -268.686342) (xy 128.80906 -268.659449) (xy 128.772062 -268.62611) (xy 128.740965 -268.58721)
			(xy 128.716591 -268.543779) (xy 128.699587 -268.496969) (xy 128.690405 -268.44802) (xy 128.689354 -268.423136)
			(xy 128.6891 -268.41323) (xy 128.68529 -268.404086) (xy 128.683225 -268.399566) (xy 128.677587 -268.391385)
			(xy 128.674114 -268.38783) (xy 128.624584 -268.33957) (xy 128.617206 -268.33298) (xy 128.598907 -268.325512)
			(xy 128.589024 -268.325092) (xy 128.4605 -268.325092) (xy 128.450621 -268.325549) (xy 128.432318 -268.332987)
			(xy 128.42494 -268.33957) (xy 128.37541 -268.38783) (xy 128.371945 -268.39139) (xy 128.366315 -268.399575)
			(xy 128.364234 -268.404086) (xy 128.360424 -268.41323) (xy 128.36017 -268.423136) (xy 128.359119 -268.44802)
			(xy 128.349937 -268.496969) (xy 128.332933 -268.543779) (xy 128.308559 -268.58721) (xy 128.277462 -268.62611)
			(xy 128.240464 -268.659449) (xy 128.198547 -268.686342) (xy 128.152821 -268.706078) (xy 128.104499 -268.718133)
			(xy 128.054862 -268.722187) (xy 128.005225 -268.718133) (xy 127.956903 -268.706078) (xy 127.911177 -268.686342)
			(xy 127.86926 -268.659449) (xy 127.832262 -268.62611) (xy 127.801165 -268.58721) (xy 127.776791 -268.543779)
			(xy 127.759787 -268.496969) (xy 127.750605 -268.44802) (xy 127.749554 -268.423136) (xy 127.7493 -268.41323)
			(xy 127.74549 -268.404086) (xy 127.743425 -268.399566) (xy 127.737787 -268.391385) (xy 127.734314 -268.38783)
			(xy 127.684784 -268.33957) (xy 127.677406 -268.33298) (xy 127.659107 -268.325512) (xy 127.649224 -268.325092)
			(xy 127.520446 -268.325092) (xy 127.510572 -268.325558) (xy 127.492282 -268.33301) (xy 127.484886 -268.33957)
			(xy 127.435356 -268.38783) (xy 127.431889 -268.391389) (xy 127.426254 -268.399571) (xy 127.42418 -268.404086)
			(xy 127.42037 -268.41323) (xy 127.420116 -268.423136) (xy 127.419142 -268.446773) (xy 127.4108 -268.493339)
			(xy 127.395375 -268.53806) (xy 127.373237 -268.579867) (xy 127.344915 -268.617758) (xy 127.311086 -268.650827)
			(xy 127.272562 -268.678282) (xy 127.230264 -268.699466) (xy 127.185204 -268.713872) (xy 127.138461 -268.721155)
			(xy 127.114808 -268.721586) (xy 127.090815 -268.72114) (xy 127.04342 -268.713635) (xy 126.997783 -268.698806)
			(xy 126.955027 -268.677021) (xy 126.916206 -268.648815) (xy 126.882276 -268.614883) (xy 126.854072 -268.576061)
			(xy 126.832288 -268.533304) (xy 126.817462 -268.487666) (xy 126.809959 -268.440271) (xy 126.8095 -268.416278)
			(xy 126.810007 -268.391474) (xy 126.818058 -268.342522) (xy 126.833899 -268.295509) (xy 126.857113 -268.251666)
			(xy 126.87173 -268.23162) (xy 126.876703 -268.224385) (xy 126.881911 -268.207632) (xy 126.88189 -268.198854)
			(xy 126.880874 -268.168882) (xy 126.880092 -268.159351) (xy 126.872385 -268.141865) (xy 126.865888 -268.134846)
			(xy 126.662942 -267.9319) (xy 126.656338 -267.925296) (xy 126.624842 -267.911072) (xy 126.61646 -267.91031)
			(xy 126.593082 -267.907703) (xy 126.547466 -267.89622) (xy 126.504151 -267.877877) (xy 126.464162 -267.853108)
			(xy 126.428445 -267.822498) (xy 126.397845 -267.786773) (xy 126.373086 -267.746777) (xy 126.354754 -267.703458)
			(xy 126.343284 -267.657839) (xy 126.340616 -267.634466) (xy 126.339854 -267.626084) (xy 126.32563 -267.594588)
			(xy 126.319026 -267.587984) (xy 126.02464 -267.293598) (xy 126.017528 -267.286232) (xy 125.998732 -267.278612)
			(xy 125.928882 -267.278612) (xy 125.918878 -267.279103) (xy 125.900394 -267.286766) (xy 125.88625 -267.300919)
			(xy 125.878597 -267.319407) (xy 125.878082 -267.329412) (xy 125.878082 -267.340842) (xy 125.887988 -267.36167)
			(xy 125.896878 -267.368782) (xy 125.914241 -267.383375) (xy 125.94488 -267.416817) (xy 125.970238 -267.454421)
			(xy 125.989757 -267.495361) (xy 126.00301 -267.538736) (xy 126.009705 -267.583594) (xy 126.010162 -267.606272)
			(xy 126.009718 -267.630265) (xy 126.002214 -267.677661) (xy 125.987388 -267.7233) (xy 125.965603 -267.766057)
			(xy 125.937397 -267.804878) (xy 125.903465 -267.838809) (xy 125.864641 -267.867012) (xy 125.821883 -267.888795)
			(xy 125.776244 -267.903619) (xy 125.728847 -267.911119) (xy 125.704854 -267.91158) (xy 125.681129 -267.911127)
			(xy 125.634252 -267.903781) (xy 125.589075 -267.889273) (xy 125.546686 -267.867951) (xy 125.508105 -267.84033)
			(xy 125.47426 -267.807074) (xy 125.445966 -267.768984) (xy 125.423904 -267.726975) (xy 125.408605 -267.68206)
			(xy 125.400437 -267.635319) (xy 125.399546 -267.611606) (xy 125.399546 -267.607796) (xy 125.399546 -267.606272)
			(xy 125.399968 -267.583541) (xy 125.406721 -267.538584) (xy 125.420073 -267.495128) (xy 125.439729 -267.454135)
			(xy 125.452124 -267.435076) (xy 125.459998 -267.423392) (xy 125.461522 -267.395452) (xy 125.414024 -267.30579)
			(xy 125.410214 -267.299694) (xy 125.403274 -267.29102) (xy 125.383903 -267.280201) (xy 125.372876 -267.278866)
			(xy 125.369066 -267.278612) (xy 125.100588 -267.278612) (xy 125.096778 -267.278866) (xy 125.085768 -267.28026)
			(xy 125.066406 -267.291056) (xy 125.05944 -267.299694) (xy 125.05563 -267.30579) (xy 125.008132 -267.395452)
			(xy 125.009656 -267.423392) (xy 125.01753 -267.435076) (xy 125.029936 -267.454127) (xy 125.049577 -267.495126)
			(xy 125.062919 -267.538584) (xy 125.069667 -267.583542) (xy 125.070108 -267.606272) (xy 125.070108 -267.611606)
			(xy 125.069174 -267.636572) (xy 125.060182 -267.685714) (xy 125.04331 -267.732737) (xy 125.01901 -267.776386)
			(xy 124.987928 -267.815498) (xy 124.950894 -267.849028) (xy 124.908896 -267.876083) (xy 124.863054 -267.89594)
			(xy 124.814591 -267.90807) (xy 124.7648 -267.91215) (xy 124.715009 -267.90807) (xy 124.666546 -267.89594)
			(xy 124.620704 -267.876083) (xy 124.578706 -267.849028) (xy 124.541672 -267.815498) (xy 124.51059 -267.776386)
			(xy 124.48629 -267.732737) (xy 124.469418 -267.685714) (xy 124.460426 -267.636572) (xy 124.459492 -267.611606)
			(xy 124.459492 -267.607796) (xy 124.459492 -267.606272) (xy 124.459914 -267.583541) (xy 124.466666 -267.538583)
			(xy 124.480016 -267.495126) (xy 124.499669 -267.454131) (xy 124.51207 -267.435076) (xy 124.519944 -267.423392)
			(xy 124.521468 -267.395452) (xy 124.47397 -267.30579) (xy 124.47016 -267.299694) (xy 124.463217 -267.291028)
			(xy 124.443843 -267.280229) (xy 124.432822 -267.278866) (xy 124.429012 -267.278612) (xy 124.170948 -267.278612)
			(xy 124.161109 -267.27808) (xy 124.142942 -267.270499) (xy 124.135642 -267.26388) (xy 123.785122 -266.91336)
			(xy 123.776217 -266.905415) (xy 123.753567 -266.897994) (xy 123.741688 -266.899136) (xy 123.650756 -266.913106)
			(xy 123.631198 -266.927076) (xy 123.625356 -266.937744) (xy 123.613943 -266.958584) (xy 123.585663 -266.996764)
			(xy 123.551811 -267.030103) (xy 123.513203 -267.057796) (xy 123.470771 -267.079174) (xy 123.425541 -267.093722)
			(xy 123.378602 -267.101089) (xy 123.354846 -267.101574) (xy 123.329067 -267.10104) (xy 123.278241 -267.092381)
			(xy 123.229594 -267.075302) (xy 123.18451 -267.050288) (xy 123.144272 -267.018051) (xy 123.110026 -266.97951)
			(xy 123.082746 -266.93576) (xy 123.063208 -266.888047) (xy 123.051968 -266.837729) (xy 123.050046 -266.812014)
			(xy 123.049538 -266.803378) (xy 123.049538 -266.796266) (xy 123.050118 -266.768574) (xy 123.060069 -266.714092)
			(xy 123.079693 -266.662301) (xy 123.09348 -266.638278) (xy 123.100592 -266.62634) (xy 123.1011 -266.599162)
			(xy 123.052078 -266.51204) (xy 123.047361 -266.504395) (xy 123.033695 -266.49275) (xy 123.016858 -266.486516)
			(xy 123.007882 -266.486132) (xy 122.761756 -266.486132) (xy 122.752771 -266.486482) (xy 122.73591 -266.492694)
			(xy 122.72225 -266.504369) (xy 122.71756 -266.51204) (xy 122.668538 -266.599162) (xy 122.669046 -266.62634)
			(xy 122.676158 -266.638278) (xy 122.68995 -266.662298) (xy 122.709555 -266.714095) (xy 122.719514 -266.768575)
			(xy 122.7201 -266.796266) (xy 122.7201 -266.803378) (xy 122.719592 -266.812014) (xy 122.717722 -266.837729)
			(xy 122.706445 -266.888036) (xy 122.686882 -266.935736) (xy 122.659587 -266.979473) (xy 122.625336 -267.018006)
			(xy 122.585101 -267.050241) (xy 122.540025 -267.075263) (xy 122.491387 -267.092361) (xy 122.440569 -267.10105)
			(xy 122.414792 -267.101574) (xy 122.39099 -267.101118) (xy 122.343961 -267.093729) (xy 122.29865 -267.079133)
			(xy 122.256152 -267.057681) (xy 122.217497 -267.029895) (xy 122.183623 -266.996447) (xy 122.155349 -266.958148)
			(xy 122.133361 -266.915925) (xy 122.118192 -266.870802) (xy 122.110208 -266.823871) (xy 122.109484 -266.800076)
			(xy 122.109484 -266.797028) (xy 122.109559 -266.786132) (xy 122.111083 -266.764394) (xy 122.112532 -266.753594)
			(xy 122.11431 -266.741148) (xy 122.106436 -266.718542) (xy 122.097546 -266.709906) (xy 122.090094 -266.703338)
			(xy 122.071675 -266.695953) (xy 122.051831 -266.69609) (xy 122.033515 -266.703727) (xy 122.026172 -266.710414)
			(xy 121.968006 -266.76858) (xy 121.961286 -266.775815) (xy 121.953677 -266.794021) (xy 121.953274 -266.803886)
			(xy 121.953274 -266.922758) (xy 121.95274 -266.932596) (xy 121.945153 -266.950758) (xy 121.938542 -266.958064)
			(xy 121.622566 -267.27404) (xy 121.615325 -267.280747) (xy 121.597121 -267.288328) (xy 121.58726 -267.288772)
			(xy 121.34723 -267.288772) (xy 121.338149 -267.289129) (xy 121.32113 -267.295464) (xy 121.307421 -267.307375)
			(xy 121.30278 -267.315188) (xy 121.25452 -267.40358) (xy 121.255282 -267.431266) (xy 121.262902 -267.44295)
			(xy 121.277688 -267.467599) (xy 121.298756 -267.521071) (xy 121.309472 -267.577536) (xy 121.310146 -267.606272)
			(xy 121.638834 -267.606272) (xy 121.642794 -267.557218) (xy 121.654571 -267.509434) (xy 121.673862 -267.464158)
			(xy 121.700165 -267.422562) (xy 121.7328 -267.385725) (xy 121.770921 -267.3546) (xy 121.813542 -267.329993)
			(xy 121.859558 -267.312541) (xy 121.907777 -267.302697) (xy 121.956952 -267.300716) (xy 122.005807 -267.306648)
			(xy 122.053078 -267.32034) (xy 122.09754 -267.341438) (xy 122.138043 -267.369394) (xy 122.173536 -267.403486)
			(xy 122.203101 -267.44283) (xy 122.225972 -267.486407) (xy 122.241556 -267.533088) (xy 122.249451 -267.581665)
			(xy 122.249946 -267.606272) (xy 122.578888 -267.606272) (xy 122.582848 -267.557218) (xy 122.594625 -267.509434)
			(xy 122.613916 -267.464158) (xy 122.640219 -267.422562) (xy 122.672854 -267.385725) (xy 122.710975 -267.3546)
			(xy 122.753596 -267.329993) (xy 122.799612 -267.312541) (xy 122.847831 -267.302697) (xy 122.897006 -267.300716)
			(xy 122.945861 -267.306648) (xy 122.993132 -267.32034) (xy 123.037594 -267.341438) (xy 123.078097 -267.369394)
			(xy 123.11359 -267.403486) (xy 123.143155 -267.44283) (xy 123.166026 -267.486407) (xy 123.18161 -267.533088)
			(xy 123.189505 -267.581665) (xy 123.19 -267.606272) (xy 123.518942 -267.606272) (xy 123.522902 -267.557218)
			(xy 123.534679 -267.509434) (xy 123.55397 -267.464158) (xy 123.580273 -267.422562) (xy 123.612908 -267.385725)
			(xy 123.651029 -267.3546) (xy 123.69365 -267.329993) (xy 123.739666 -267.312541) (xy 123.787885 -267.302697)
			(xy 123.83706 -267.300716) (xy 123.885915 -267.306648) (xy 123.933186 -267.32034) (xy 123.977648 -267.341438)
			(xy 124.018151 -267.369394) (xy 124.053644 -267.403486) (xy 124.083209 -267.44283) (xy 124.10608 -267.486407)
			(xy 124.121664 -267.533088) (xy 124.129559 -267.581665) (xy 124.130054 -267.606272) (xy 124.129559 -267.630879)
			(xy 124.121664 -267.679456) (xy 124.10608 -267.726137) (xy 124.083209 -267.769714) (xy 124.053644 -267.809058)
			(xy 124.018151 -267.84315) (xy 123.977648 -267.871106) (xy 123.933186 -267.892204) (xy 123.885915 -267.905896)
			(xy 123.83706 -267.911828) (xy 123.787885 -267.909847) (xy 123.739666 -267.900003) (xy 123.69365 -267.882551)
			(xy 123.651029 -267.857944) (xy 123.612908 -267.826819) (xy 123.580273 -267.789982) (xy 123.55397 -267.748386)
			(xy 123.534679 -267.70311) (xy 123.522902 -267.655326) (xy 123.518942 -267.606272) (xy 123.19 -267.606272)
			(xy 123.189505 -267.630879) (xy 123.18161 -267.679456) (xy 123.166026 -267.726137) (xy 123.143155 -267.769714)
			(xy 123.11359 -267.809058) (xy 123.078097 -267.84315) (xy 123.037594 -267.871106) (xy 122.993132 -267.892204)
			(xy 122.945861 -267.905896) (xy 122.897006 -267.911828) (xy 122.847831 -267.909847) (xy 122.799612 -267.900003)
			(xy 122.753596 -267.882551) (xy 122.710975 -267.857944) (xy 122.672854 -267.826819) (xy 122.640219 -267.789982)
			(xy 122.613916 -267.748386) (xy 122.594625 -267.70311) (xy 122.582848 -267.655326) (xy 122.578888 -267.606272)
			(xy 122.249946 -267.606272) (xy 122.249451 -267.630879) (xy 122.241556 -267.679456) (xy 122.225972 -267.726137)
			(xy 122.203101 -267.769714) (xy 122.173536 -267.809058) (xy 122.138043 -267.84315) (xy 122.09754 -267.871106)
			(xy 122.053078 -267.892204) (xy 122.005807 -267.905896) (xy 121.956952 -267.911828) (xy 121.907777 -267.909847)
			(xy 121.859558 -267.900003) (xy 121.813542 -267.882551) (xy 121.770921 -267.857944) (xy 121.7328 -267.826819)
			(xy 121.700165 -267.789982) (xy 121.673862 -267.748386) (xy 121.654571 -267.70311) (xy 121.642794 -267.655326)
			(xy 121.638834 -267.606272) (xy 121.310146 -267.606272) (xy 121.309624 -267.631527) (xy 121.301311 -267.681349)
			(xy 121.28491 -267.729123) (xy 121.260869 -267.773546) (xy 121.229845 -267.813406) (xy 121.192683 -267.847616)
			(xy 121.150397 -267.875242) (xy 121.104141 -267.895532) (xy 121.055176 -267.907932) (xy 121.004838 -267.912103)
			(xy 120.9545 -267.907932) (xy 120.905535 -267.895532) (xy 120.859279 -267.875242) (xy 120.816993 -267.847616)
			(xy 120.779831 -267.813406) (xy 120.748807 -267.773546) (xy 120.724766 -267.729123) (xy 120.708365 -267.681349)
			(xy 120.700052 -267.631527) (xy 120.69953 -267.606272) (xy 120.700157 -267.57753) (xy 120.710857 -267.521053)
			(xy 120.731948 -267.46758) (xy 120.746774 -267.44295) (xy 120.754394 -267.431266) (xy 120.755156 -267.40358)
			(xy 120.706896 -267.315188) (xy 120.702204 -267.30742) (xy 120.68849 -267.295555) (xy 120.671512 -267.289183)
			(xy 120.662446 -267.288772) (xy 120.381268 -267.288772) (xy 120.371428 -267.288242) (xy 120.35326 -267.280662)
			(xy 120.345962 -267.27404) (xy 120.010428 -266.938506) (xy 120.001852 -266.930897) (xy 119.980221 -266.923392)
			(xy 119.968772 -266.924028) (xy 119.879872 -266.934442) (xy 119.860568 -266.946634) (xy 119.854218 -266.956794)
			(xy 119.840154 -266.978536) (xy 119.805909 -267.017369) (xy 119.765599 -267.049863) (xy 119.72038 -267.075083)
			(xy 119.671553 -267.092306) (xy 119.620518 -267.101037) (xy 119.59463 -267.101574) (xy 119.568852 -267.101039)
			(xy 119.518028 -267.092378) (xy 119.469383 -267.075297) (xy 119.424301 -267.050282) (xy 119.384066 -267.018045)
			(xy 119.349822 -266.979504) (xy 119.322543 -266.935755) (xy 119.303007 -266.888044) (xy 119.291768 -266.837727)
			(xy 119.28983 -266.812014) (xy 119.289322 -266.803378) (xy 119.289322 -266.796266) (xy 119.289902 -266.768574)
			(xy 119.299853 -266.714092) (xy 119.319475 -266.662301) (xy 119.333264 -266.638278) (xy 119.340376 -266.62634)
			(xy 119.340884 -266.599162) (xy 119.291862 -266.51204) (xy 119.287144 -266.504396) (xy 119.273477 -266.492756)
			(xy 119.256641 -266.486527) (xy 119.247666 -266.486132) (xy 119.001794 -266.486132) (xy 118.992806 -266.486475)
			(xy 118.975935 -266.49268) (xy 118.962264 -266.504352) (xy 118.957598 -266.51204) (xy 118.908576 -266.599162)
			(xy 118.909084 -266.62634) (xy 118.916196 -266.638278) (xy 118.929986 -266.662298) (xy 118.949589 -266.714095)
			(xy 118.959546 -266.768575) (xy 118.960138 -266.796266) (xy 118.960138 -266.803378) (xy 118.95963 -266.812014)
			(xy 118.95776 -266.837731) (xy 118.946484 -266.88804) (xy 118.926921 -266.935742) (xy 118.899627 -266.979483)
			(xy 118.865377 -267.01802) (xy 118.825142 -267.05026) (xy 118.780066 -267.075286) (xy 118.731428 -267.09239)
			(xy 118.680609 -267.101084) (xy 118.65483 -267.101574) (xy 118.630836 -267.10113) (xy 118.583439 -267.093627)
			(xy 118.5378 -267.0788) (xy 118.495042 -267.057016) (xy 118.456219 -267.02881) (xy 118.422287 -266.994878)
			(xy 118.394082 -266.956055) (xy 118.372298 -266.913297) (xy 118.357472 -266.867657) (xy 118.34997 -266.82026)
			(xy 118.349522 -266.796266) (xy 118.350284 -266.77366) (xy 118.351046 -266.761976) (xy 118.343172 -266.741402)
			(xy 118.335044 -266.733528) (xy 118.327589 -266.726969) (xy 118.309171 -266.719597) (xy 118.289333 -266.719733)
			(xy 118.271018 -266.727358) (xy 118.26367 -266.734036) (xy 118.24716 -266.750546) (xy 118.239794 -266.757658)
			(xy 118.232174 -266.776454) (xy 118.232174 -266.869418) (xy 118.231647 -266.879259) (xy 118.22407 -266.897431)
			(xy 118.217442 -266.904724) (xy 117.843046 -267.27912) (xy 117.835805 -267.285825) (xy 117.8176 -267.293403)
			(xy 117.80774 -267.293852) (xy 117.590316 -267.293852) (xy 117.584474 -267.294106) (xy 117.57321 -267.296089)
			(xy 117.553946 -267.308357) (xy 117.54739 -267.317728) (xy 117.54612 -267.31976) (xy 117.503956 -267.394944)
			(xy 117.499773 -267.403034) (xy 117.496874 -267.421001) (xy 117.500476 -267.438839) (xy 117.504972 -267.44676)
			(xy 117.519053 -267.470962) (xy 117.539109 -267.523232) (xy 117.549318 -267.578279) (xy 117.54993 -267.606272)
			(xy 117.878872 -267.606272) (xy 117.882832 -267.557218) (xy 117.894609 -267.509434) (xy 117.9139 -267.464158)
			(xy 117.940203 -267.422562) (xy 117.972838 -267.385725) (xy 118.010959 -267.3546) (xy 118.05358 -267.329993)
			(xy 118.099596 -267.312541) (xy 118.147815 -267.302697) (xy 118.19699 -267.300716) (xy 118.245845 -267.306648)
			(xy 118.293116 -267.32034) (xy 118.337578 -267.341438) (xy 118.378081 -267.369394) (xy 118.413574 -267.403486)
			(xy 118.443139 -267.44283) (xy 118.46601 -267.486407) (xy 118.481594 -267.533088) (xy 118.489489 -267.581665)
			(xy 118.489984 -267.606272) (xy 118.818926 -267.606272) (xy 118.822886 -267.557218) (xy 118.834663 -267.509434)
			(xy 118.853954 -267.464158) (xy 118.880257 -267.422562) (xy 118.912892 -267.385725) (xy 118.951013 -267.3546)
			(xy 118.993634 -267.329993) (xy 119.03965 -267.312541) (xy 119.087869 -267.302697) (xy 119.137044 -267.300716)
			(xy 119.185899 -267.306648) (xy 119.23317 -267.32034) (xy 119.277632 -267.341438) (xy 119.318135 -267.369394)
			(xy 119.353628 -267.403486) (xy 119.383193 -267.44283) (xy 119.406064 -267.486407) (xy 119.421648 -267.533088)
			(xy 119.429543 -267.581665) (xy 119.430038 -267.606272) (xy 119.75898 -267.606272) (xy 119.76294 -267.557218)
			(xy 119.774717 -267.509434) (xy 119.794008 -267.464158) (xy 119.820311 -267.422562) (xy 119.852946 -267.385725)
			(xy 119.891067 -267.3546) (xy 119.933688 -267.329993) (xy 119.979704 -267.312541) (xy 120.027923 -267.302697)
			(xy 120.077098 -267.300716) (xy 120.125953 -267.306648) (xy 120.173224 -267.32034) (xy 120.217686 -267.341438)
			(xy 120.258189 -267.369394) (xy 120.293682 -267.403486) (xy 120.323247 -267.44283) (xy 120.346118 -267.486407)
			(xy 120.361702 -267.533088) (xy 120.369597 -267.581665) (xy 120.370092 -267.606272) (xy 120.369597 -267.630879)
			(xy 120.361702 -267.679456) (xy 120.346118 -267.726137) (xy 120.323247 -267.769714) (xy 120.293682 -267.809058)
			(xy 120.258189 -267.84315) (xy 120.217686 -267.871106) (xy 120.173224 -267.892204) (xy 120.125953 -267.905896)
			(xy 120.077098 -267.911828) (xy 120.027923 -267.909847) (xy 119.979704 -267.900003) (xy 119.933688 -267.882551)
			(xy 119.891067 -267.857944) (xy 119.852946 -267.826819) (xy 119.820311 -267.789982) (xy 119.794008 -267.748386)
			(xy 119.774717 -267.70311) (xy 119.76294 -267.655326) (xy 119.75898 -267.606272) (xy 119.430038 -267.606272)
			(xy 119.429543 -267.630879) (xy 119.421648 -267.679456) (xy 119.406064 -267.726137) (xy 119.383193 -267.769714)
			(xy 119.353628 -267.809058) (xy 119.318135 -267.84315) (xy 119.277632 -267.871106) (xy 119.23317 -267.892204)
			(xy 119.185899 -267.905896) (xy 119.137044 -267.911828) (xy 119.087869 -267.909847) (xy 119.03965 -267.900003)
			(xy 118.993634 -267.882551) (xy 118.951013 -267.857944) (xy 118.912892 -267.826819) (xy 118.880257 -267.789982)
			(xy 118.853954 -267.748386) (xy 118.834663 -267.70311) (xy 118.822886 -267.655326) (xy 118.818926 -267.606272)
			(xy 118.489984 -267.606272) (xy 118.489489 -267.630879) (xy 118.481594 -267.679456) (xy 118.46601 -267.726137)
			(xy 118.443139 -267.769714) (xy 118.413574 -267.809058) (xy 118.378081 -267.84315) (xy 118.337578 -267.871106)
			(xy 118.293116 -267.892204) (xy 118.245845 -267.905896) (xy 118.19699 -267.911828) (xy 118.147815 -267.909847)
			(xy 118.099596 -267.900003) (xy 118.05358 -267.882551) (xy 118.010959 -267.857944) (xy 117.972838 -267.826819)
			(xy 117.940203 -267.789982) (xy 117.9139 -267.748386) (xy 117.894609 -267.70311) (xy 117.882832 -267.655326)
			(xy 117.878872 -267.606272) (xy 117.54993 -267.606272) (xy 117.54993 -267.612622) (xy 117.548994 -267.636286)
			(xy 117.540714 -267.682914) (xy 117.525333 -267.727703) (xy 117.503221 -267.769581) (xy 117.474907 -267.807542)
			(xy 117.441072 -267.840675) (xy 117.402526 -267.868187) (xy 117.360194 -267.889416) (xy 117.315091 -267.903855)
			(xy 117.268301 -267.911155) (xy 117.244622 -267.91158) (xy 117.220937 -267.911127) (xy 117.174137 -267.903801)
			(xy 117.129029 -267.889336) (xy 117.086696 -267.868078) (xy 117.048154 -267.84054) (xy 117.014326 -267.807379)
			(xy 116.986024 -267.769393) (xy 116.963927 -267.727493) (xy 116.948565 -267.682683) (xy 116.940307 -267.636038)
			(xy 116.939314 -267.612368) (xy 116.939314 -267.606272) (xy 116.939936 -267.578278) (xy 116.950123 -267.523225)
			(xy 116.970168 -267.470949) (xy 116.984272 -267.44676) (xy 116.988718 -267.438826) (xy 116.992267 -267.421)
			(xy 116.989412 -267.403051) (xy 116.985288 -267.394944) (xy 116.943124 -267.31976) (xy 116.941854 -267.317728)
			(xy 116.935285 -267.30837) (xy 116.916028 -267.2961) (xy 116.90477 -267.294106) (xy 116.898928 -267.293852)
			(xy 116.596668 -267.293852) (xy 116.586826 -267.293324) (xy 116.568651 -267.285753) (xy 116.561362 -267.27912)
			(xy 116.238782 -266.95654) (xy 116.230654 -266.948412) (xy 116.209572 -266.940792) (xy 116.11102 -266.949936)
			(xy 116.09197 -266.961112) (xy 116.085366 -266.97051) (xy 116.070965 -266.990364) (xy 116.036888 -267.025636)
			(xy 115.997611 -267.055007) (xy 115.954144 -267.077721) (xy 115.907605 -267.093195) (xy 115.85919 -267.10103)
			(xy 115.834668 -267.101574) (xy 115.810677 -267.101125) (xy 115.763288 -267.093614) (xy 115.717657 -267.078783)
			(xy 115.674907 -267.056995) (xy 115.636093 -267.028788) (xy 115.602169 -266.994857) (xy 115.57397 -266.956036)
			(xy 115.552192 -266.913282) (xy 115.53737 -266.867648) (xy 115.529869 -266.820257) (xy 115.52936 -266.796266)
			(xy 115.529756 -266.77441) (xy 115.536026 -266.73115) (xy 115.548392 -266.689224) (xy 115.566601 -266.649485)
			(xy 115.578128 -266.630912) (xy 115.585748 -266.618974) (xy 115.586764 -266.591542) (xy 115.538504 -266.502642)
			(xy 115.533825 -266.494785) (xy 115.520049 -266.482778) (xy 115.502937 -266.476367) (xy 115.4938 -266.475972)
			(xy 115.235482 -266.475972) (xy 115.226344 -266.476356) (xy 115.209232 -266.482773) (xy 115.195458 -266.494784)
			(xy 115.190778 -266.502642) (xy 115.142518 -266.591542) (xy 115.143534 -266.618974) (xy 115.151154 -266.630912)
			(xy 115.162698 -266.649477) (xy 115.180927 -266.689211) (xy 115.193294 -266.731141) (xy 115.199544 -266.774408)
			(xy 115.199922 -266.796266) (xy 115.199478 -266.820261) (xy 115.191976 -266.867662) (xy 115.177151 -266.913305)
			(xy 115.155367 -266.956067) (xy 115.127162 -266.994894) (xy 115.093231 -267.028831) (xy 115.054408 -267.057042)
			(xy 115.011649 -267.078832) (xy 114.966008 -267.093665) (xy 114.918609 -267.101175) (xy 114.894614 -267.101574)
			(xy 114.870836 -267.101121) (xy 114.823854 -267.093751) (xy 114.778583 -267.079187) (xy 114.736116 -267.057781)
			(xy 114.697482 -267.030051) (xy 114.663613 -266.996666) (xy 114.635329 -266.958435) (xy 114.613313 -266.916282)
			(xy 114.598099 -266.871225) (xy 114.590053 -266.824354) (xy 114.589306 -266.800584) (xy 114.589306 -266.795758)
			(xy 114.589651 -266.775049) (xy 114.595259 -266.734013) (xy 114.600482 -266.71397) (xy 114.604292 -266.700508)
			(xy 114.59718 -266.674346) (xy 114.587528 -266.66444) (xy 114.580094 -266.657724) (xy 114.561594 -266.650088)
			(xy 114.54158 -266.650088) (xy 114.52308 -266.657724) (xy 114.515646 -266.66444) (xy 114.482626 -266.69746)
			(xy 114.475901 -266.704693) (xy 114.468282 -266.722899) (xy 114.467894 -266.732766) (xy 114.467894 -266.950698)
			(xy 114.467353 -266.960533) (xy 114.459758 -266.978686) (xy 114.453162 -266.986004) (xy 114.162586 -267.27658)
			(xy 114.155349 -267.283296) (xy 114.137144 -267.290894) (xy 114.12728 -267.291312) (xy 113.82883 -267.291312)
			(xy 113.828576 -267.291312) (xy 113.81964 -267.291705) (xy 113.802893 -267.297956) (xy 113.789338 -267.309609)
			(xy 113.784634 -267.31722) (xy 113.78438 -267.317474) (xy 113.735612 -267.405358) (xy 113.736374 -267.43279)
			(xy 113.74374 -267.444728) (xy 113.758233 -267.469153) (xy 113.778855 -267.522065) (xy 113.789341 -267.577877)
			(xy 113.789968 -267.606272) (xy 114.11891 -267.606272) (xy 114.12287 -267.557218) (xy 114.134647 -267.509434)
			(xy 114.153938 -267.464158) (xy 114.180241 -267.422562) (xy 114.212876 -267.385725) (xy 114.250997 -267.3546)
			(xy 114.293618 -267.329993) (xy 114.339634 -267.312541) (xy 114.387853 -267.302697) (xy 114.437028 -267.300716)
			(xy 114.485883 -267.306648) (xy 114.533154 -267.32034) (xy 114.577616 -267.341438) (xy 114.618119 -267.369394)
			(xy 114.653612 -267.403486) (xy 114.683177 -267.44283) (xy 114.706048 -267.486407) (xy 114.721632 -267.533088)
			(xy 114.729527 -267.581665) (xy 114.730022 -267.606272) (xy 115.058964 -267.606272) (xy 115.062924 -267.557218)
			(xy 115.074701 -267.509434) (xy 115.093992 -267.464158) (xy 115.120295 -267.422562) (xy 115.15293 -267.385725)
			(xy 115.191051 -267.3546) (xy 115.233672 -267.329993) (xy 115.279688 -267.312541) (xy 115.327907 -267.302697)
			(xy 115.377082 -267.300716) (xy 115.425937 -267.306648) (xy 115.473208 -267.32034) (xy 115.51767 -267.341438)
			(xy 115.558173 -267.369394) (xy 115.593666 -267.403486) (xy 115.623231 -267.44283) (xy 115.646102 -267.486407)
			(xy 115.661686 -267.533088) (xy 115.669581 -267.581665) (xy 115.670076 -267.606272) (xy 115.999018 -267.606272)
			(xy 116.002978 -267.557218) (xy 116.014755 -267.509434) (xy 116.034046 -267.464158) (xy 116.060349 -267.422562)
			(xy 116.092984 -267.385725) (xy 116.131105 -267.3546) (xy 116.173726 -267.329993) (xy 116.219742 -267.312541)
			(xy 116.267961 -267.302697) (xy 116.317136 -267.300716) (xy 116.365991 -267.306648) (xy 116.413262 -267.32034)
			(xy 116.457724 -267.341438) (xy 116.498227 -267.369394) (xy 116.53372 -267.403486) (xy 116.563285 -267.44283)
			(xy 116.586156 -267.486407) (xy 116.60174 -267.533088) (xy 116.609635 -267.581665) (xy 116.61013 -267.606272)
			(xy 116.609635 -267.630879) (xy 116.60174 -267.679456) (xy 116.586156 -267.726137) (xy 116.563285 -267.769714)
			(xy 116.53372 -267.809058) (xy 116.498227 -267.84315) (xy 116.457724 -267.871106) (xy 116.413262 -267.892204)
			(xy 116.365991 -267.905896) (xy 116.317136 -267.911828) (xy 116.267961 -267.909847) (xy 116.219742 -267.900003)
			(xy 116.173726 -267.882551) (xy 116.131105 -267.857944) (xy 116.092984 -267.826819) (xy 116.060349 -267.789982)
			(xy 116.034046 -267.748386) (xy 116.014755 -267.70311) (xy 116.002978 -267.655326) (xy 115.999018 -267.606272)
			(xy 115.670076 -267.606272) (xy 115.669581 -267.630879) (xy 115.661686 -267.679456) (xy 115.646102 -267.726137)
			(xy 115.623231 -267.769714) (xy 115.593666 -267.809058) (xy 115.558173 -267.84315) (xy 115.51767 -267.871106)
			(xy 115.473208 -267.892204) (xy 115.425937 -267.905896) (xy 115.377082 -267.911828) (xy 115.327907 -267.909847)
			(xy 115.279688 -267.900003) (xy 115.233672 -267.882551) (xy 115.191051 -267.857944) (xy 115.15293 -267.826819)
			(xy 115.120295 -267.789982) (xy 115.093992 -267.748386) (xy 115.074701 -267.70311) (xy 115.062924 -267.655326)
			(xy 115.058964 -267.606272) (xy 114.730022 -267.606272) (xy 114.729527 -267.630879) (xy 114.721632 -267.679456)
			(xy 114.706048 -267.726137) (xy 114.683177 -267.769714) (xy 114.653612 -267.809058) (xy 114.618119 -267.84315)
			(xy 114.577616 -267.871106) (xy 114.533154 -267.892204) (xy 114.485883 -267.905896) (xy 114.437028 -267.911828)
			(xy 114.387853 -267.909847) (xy 114.339634 -267.900003) (xy 114.293618 -267.882551) (xy 114.250997 -267.857944)
			(xy 114.212876 -267.826819) (xy 114.180241 -267.789982) (xy 114.153938 -267.748386) (xy 114.134647 -267.70311)
			(xy 114.12287 -267.655326) (xy 114.11891 -267.606272) (xy 113.789968 -267.606272) (xy 113.789446 -267.631527)
			(xy 113.781133 -267.681349) (xy 113.764732 -267.729123) (xy 113.740691 -267.773546) (xy 113.709667 -267.813406)
			(xy 113.672505 -267.847616) (xy 113.630219 -267.875242) (xy 113.583963 -267.895532) (xy 113.534998 -267.907932)
			(xy 113.48466 -267.912103) (xy 113.434322 -267.907932) (xy 113.385357 -267.895532) (xy 113.339101 -267.875242)
			(xy 113.296815 -267.847616) (xy 113.259653 -267.813406) (xy 113.228629 -267.773546) (xy 113.204588 -267.729123)
			(xy 113.188187 -267.681349) (xy 113.179874 -267.631527) (xy 113.179352 -267.606272) (xy 113.179739 -267.583973)
			(xy 113.186245 -267.539852) (xy 113.192306 -267.518388) (xy 113.19637 -267.504926) (xy 113.189512 -267.477748)
			(xy 113.179606 -267.467842) (xy 113.172172 -267.461126) (xy 113.153672 -267.45349) (xy 113.133658 -267.45349)
			(xy 113.115158 -267.461126) (xy 113.107724 -267.467842) (xy 113.060226 -267.51534) (xy 113.052989 -267.522056)
			(xy 113.034784 -267.529659) (xy 113.02492 -267.530072) (xy 111.760508 -267.530072) (xy 111.750673 -267.529531)
			(xy 111.73252 -267.521936) (xy 111.725202 -267.51534) (xy 111.51616 -267.306298) (xy 111.509048 -267.298932)
			(xy 111.490252 -267.291312) (xy 111.015272 -267.291312) (xy 111.015018 -267.291312) (xy 111.006078 -267.291698)
			(xy 110.98932 -267.29794) (xy 110.975754 -267.309591) (xy 110.971076 -267.31722) (xy 110.970822 -267.317474)
			(xy 110.922054 -267.405358) (xy 110.922816 -267.43279) (xy 110.930182 -267.444728) (xy 110.944673 -267.469154)
			(xy 110.965293 -267.522066) (xy 110.975776 -267.577878) (xy 110.97641 -267.606272) (xy 110.975888 -267.631527)
			(xy 110.967575 -267.681349) (xy 110.951174 -267.729123) (xy 110.927133 -267.773546) (xy 110.896109 -267.813406)
			(xy 110.858947 -267.847616) (xy 110.816661 -267.875242) (xy 110.770405 -267.895532) (xy 110.72144 -267.907932)
			(xy 110.671102 -267.912103) (xy 110.620764 -267.907932) (xy 110.571799 -267.895532) (xy 110.525543 -267.875242)
			(xy 110.483257 -267.847616) (xy 110.446095 -267.813406) (xy 110.415071 -267.773546) (xy 110.39103 -267.729123)
			(xy 110.374629 -267.681349) (xy 110.366316 -267.631527) (xy 110.365794 -267.606272) (xy 110.365932 -267.593509)
			(xy 110.368094 -267.568075) (xy 110.370112 -267.555472) (xy 110.369858 -267.555472) (xy 110.375586 -267.526181)
			(xy 110.396824 -267.470414) (xy 110.412022 -267.444728) (xy 110.419388 -267.43279) (xy 110.42015 -267.405358)
			(xy 110.371382 -267.317474) (xy 110.371128 -267.31722) (xy 110.366438 -267.309604) (xy 110.352857 -267.297983)
			(xy 110.33612 -267.291709) (xy 110.327186 -267.291312) (xy 110.226348 -267.291312) (xy 110.216509 -267.29078)
			(xy 110.198342 -267.283199) (xy 110.191042 -267.27658) (xy 109.728 -266.813538) (xy 109.719872 -266.806934)
			(xy 109.710274 -266.8013) (xy 109.688285 -266.79802) (xy 109.677454 -266.800584) (xy 109.59465 -266.824968)
			(xy 109.586025 -266.82786) (xy 109.57145 -266.838721) (xy 109.561613 -266.854006) (xy 109.559344 -266.862814)
			(xy 109.553177 -266.887877) (xy 109.53359 -266.935627) (xy 109.506258 -266.979407) (xy 109.47196 -267.017973)
			(xy 109.43167 -267.050228) (xy 109.386533 -267.075255) (xy 109.337832 -267.092343) (xy 109.286954 -267.101006)
			(xy 109.261148 -267.101574) (xy 109.237398 -267.101118) (xy 109.190473 -267.093756) (xy 109.145254 -267.079217)
			(xy 109.102832 -267.057851) (xy 109.064229 -267.030174) (xy 109.030377 -266.996855) (xy 109.002092 -266.958695)
			(xy 108.980057 -266.916617) (xy 108.964802 -266.871633) (xy 108.956697 -266.824831) (xy 108.95584 -266.801092)
			(xy 108.95584 -266.797028) (xy 108.956409 -266.768506) (xy 108.966857 -266.71243) (xy 108.987525 -266.659265)
			(xy 109.002068 -266.634722) (xy 109.002068 -266.634468) (xy 109.005401 -266.628635) (xy 109.009261 -266.615772)
			(xy 109.009688 -266.609068) (xy 109.010196 -266.595098) (xy 108.961428 -266.507214) (xy 108.956726 -266.499473)
			(xy 108.943001 -266.487673) (xy 108.926028 -266.481385) (xy 108.916978 -266.481052) (xy 108.665264 -266.481052)
			(xy 108.656221 -266.481421) (xy 108.639264 -266.487711) (xy 108.625544 -266.499497) (xy 108.620814 -266.507214)
			(xy 108.578904 -266.582906) (xy 108.575783 -266.588979) (xy 108.572554 -266.602241) (xy 108.572554 -266.609068)
			(xy 108.572808 -266.622784) (xy 108.580174 -266.634722) (xy 108.594723 -266.659262) (xy 108.615392 -266.712427)
			(xy 108.625831 -266.768505) (xy 108.626402 -266.797028) (xy 108.626402 -266.801092) (xy 108.625577 -266.824834)
			(xy 108.617482 -266.871643) (xy 108.602233 -266.916633) (xy 108.580199 -266.958717) (xy 108.551911 -266.99688)
			(xy 108.518052 -267.030199) (xy 108.47944 -267.057872) (xy 108.437008 -267.079228) (xy 108.391779 -267.093753)
			(xy 108.344846 -267.101096) (xy 108.321094 -267.101574) (xy 108.297426 -267.101129) (xy 108.250656 -267.093826)
			(xy 108.205572 -267.079396) (xy 108.163255 -267.058184) (xy 108.124715 -267.030698) (xy 108.090877 -266.997596)
			(xy 108.062551 -266.959671) (xy 108.040413 -266.91783) (xy 108.024995 -266.873075) (xy 108.020358 -266.84986)
			(xy 108.017818 -266.835636) (xy 107.999276 -266.814554) (xy 107.90174 -266.784074) (xy 107.892811 -266.781683)
			(xy 107.874373 -266.78275) (xy 107.857512 -266.790288) (xy 107.850686 -266.79652) (xy 107.368086 -267.27912)
			(xy 107.360847 -267.285832) (xy 107.342642 -267.293424) (xy 107.33278 -267.293852) (xy 107.256834 -267.293852)
			(xy 107.250992 -267.294106) (xy 107.239726 -267.296086) (xy 107.220456 -267.30835) (xy 107.213908 -267.317728)
			(xy 107.212638 -267.31976) (xy 107.170474 -267.394944) (xy 107.16629 -267.403034) (xy 107.16339 -267.421001)
			(xy 107.166993 -267.43884) (xy 107.17149 -267.44676) (xy 107.185571 -267.470962) (xy 107.205625 -267.523233)
			(xy 107.215834 -267.578279) (xy 107.216448 -267.606272) (xy 107.545136 -267.606272) (xy 107.549096 -267.557218)
			(xy 107.560873 -267.509434) (xy 107.580164 -267.464158) (xy 107.606467 -267.422562) (xy 107.639102 -267.385725)
			(xy 107.677223 -267.3546) (xy 107.719844 -267.329993) (xy 107.76586 -267.312541) (xy 107.814079 -267.302697)
			(xy 107.863254 -267.300716) (xy 107.912109 -267.306648) (xy 107.95938 -267.32034) (xy 108.003842 -267.341438)
			(xy 108.044345 -267.369394) (xy 108.079838 -267.403486) (xy 108.109403 -267.44283) (xy 108.132274 -267.486407)
			(xy 108.147858 -267.533088) (xy 108.155753 -267.581665) (xy 108.156248 -267.606272) (xy 108.48519 -267.606272)
			(xy 108.48915 -267.557218) (xy 108.500927 -267.509434) (xy 108.520218 -267.464158) (xy 108.546521 -267.422562)
			(xy 108.579156 -267.385725) (xy 108.617277 -267.3546) (xy 108.659898 -267.329993) (xy 108.705914 -267.312541)
			(xy 108.754133 -267.302697) (xy 108.803308 -267.300716) (xy 108.852163 -267.306648) (xy 108.899434 -267.32034)
			(xy 108.943896 -267.341438) (xy 108.984399 -267.369394) (xy 109.019892 -267.403486) (xy 109.049457 -267.44283)
			(xy 109.072328 -267.486407) (xy 109.087912 -267.533088) (xy 109.095807 -267.581665) (xy 109.096302 -267.606272)
			(xy 109.425244 -267.606272) (xy 109.429204 -267.557218) (xy 109.440981 -267.509434) (xy 109.460272 -267.464158)
			(xy 109.486575 -267.422562) (xy 109.51921 -267.385725) (xy 109.557331 -267.3546) (xy 109.599952 -267.329993)
			(xy 109.645968 -267.312541) (xy 109.694187 -267.302697) (xy 109.743362 -267.300716) (xy 109.792217 -267.306648)
			(xy 109.839488 -267.32034) (xy 109.88395 -267.341438) (xy 109.924453 -267.369394) (xy 109.959946 -267.403486)
			(xy 109.989511 -267.44283) (xy 110.012382 -267.486407) (xy 110.027966 -267.533088) (xy 110.035861 -267.581665)
			(xy 110.036356 -267.606272) (xy 110.035861 -267.630879) (xy 110.027966 -267.679456) (xy 110.012382 -267.726137)
			(xy 109.989511 -267.769714) (xy 109.959946 -267.809058) (xy 109.924453 -267.84315) (xy 109.88395 -267.871106)
			(xy 109.839488 -267.892204) (xy 109.792217 -267.905896) (xy 109.743362 -267.911828) (xy 109.694187 -267.909847)
			(xy 109.645968 -267.900003) (xy 109.599952 -267.882551) (xy 109.557331 -267.857944) (xy 109.51921 -267.826819)
			(xy 109.486575 -267.789982) (xy 109.460272 -267.748386) (xy 109.440981 -267.70311) (xy 109.429204 -267.655326)
			(xy 109.425244 -267.606272) (xy 109.096302 -267.606272) (xy 109.095807 -267.630879) (xy 109.087912 -267.679456)
			(xy 109.072328 -267.726137) (xy 109.049457 -267.769714) (xy 109.019892 -267.809058) (xy 108.984399 -267.84315)
			(xy 108.943896 -267.871106) (xy 108.899434 -267.892204) (xy 108.852163 -267.905896) (xy 108.803308 -267.911828)
			(xy 108.754133 -267.909847) (xy 108.705914 -267.900003) (xy 108.659898 -267.882551) (xy 108.617277 -267.857944)
			(xy 108.579156 -267.826819) (xy 108.546521 -267.789982) (xy 108.520218 -267.748386) (xy 108.500927 -267.70311)
			(xy 108.48915 -267.655326) (xy 108.48519 -267.606272) (xy 108.156248 -267.606272) (xy 108.155753 -267.630879)
			(xy 108.147858 -267.679456) (xy 108.132274 -267.726137) (xy 108.109403 -267.769714) (xy 108.079838 -267.809058)
			(xy 108.044345 -267.84315) (xy 108.003842 -267.871106) (xy 107.95938 -267.892204) (xy 107.912109 -267.905896)
			(xy 107.863254 -267.911828) (xy 107.814079 -267.909847) (xy 107.76586 -267.900003) (xy 107.719844 -267.882551)
			(xy 107.677223 -267.857944) (xy 107.639102 -267.826819) (xy 107.606467 -267.789982) (xy 107.580164 -267.748386)
			(xy 107.560873 -267.70311) (xy 107.549096 -267.655326) (xy 107.545136 -267.606272) (xy 107.216448 -267.606272)
			(xy 107.216448 -267.612622) (xy 107.215511 -267.636284) (xy 107.207231 -267.682906) (xy 107.191849 -267.727691)
			(xy 107.169736 -267.769562) (xy 107.141421 -267.807516) (xy 107.107584 -267.840642) (xy 107.069037 -267.868145)
			(xy 107.026705 -267.889364) (xy 106.981604 -267.903791) (xy 106.934816 -267.91108) (xy 106.91114 -267.91158)
			(xy 106.887454 -267.911129) (xy 106.840652 -267.903804) (xy 106.795542 -267.889341) (xy 106.753207 -267.868085)
			(xy 106.714662 -267.840546) (xy 106.680831 -267.807386) (xy 106.652527 -267.769399) (xy 106.630429 -267.727497)
			(xy 106.615066 -267.682686) (xy 106.606807 -267.636039) (xy 106.605832 -267.612368) (xy 106.605832 -267.606272)
			(xy 106.606454 -267.578278) (xy 106.616642 -267.523225) (xy 106.636688 -267.47095) (xy 106.65079 -267.44676)
			(xy 106.655242 -267.438827) (xy 106.658796 -267.421) (xy 106.655937 -267.403049) (xy 106.651806 -267.394944)
			(xy 106.609642 -267.31976) (xy 106.608372 -267.317728) (xy 106.601804 -267.308367) (xy 106.582548 -267.296091)
			(xy 106.571288 -267.294106) (xy 106.565446 -267.293852) (xy 106.459528 -267.293852) (xy 106.44969 -267.293317)
			(xy 106.431524 -267.285735) (xy 106.424222 -267.27912) (xy 105.966006 -266.820904) (xy 105.959368 -266.814785)
			(xy 105.94298 -266.80724) (xy 105.924994 -266.805819) (xy 105.916222 -266.80795) (xy 105.833164 -266.831318)
			(xy 105.824604 -266.834062) (xy 105.810036 -266.844573) (xy 105.800033 -266.859494) (xy 105.797604 -266.868148)
			(xy 105.797604 -266.868402) (xy 105.791103 -266.893004) (xy 105.771057 -266.939773) (xy 105.743536 -266.982572)
			(xy 105.709301 -267.020216) (xy 105.669299 -267.051665) (xy 105.624638 -267.076047) (xy 105.576552 -267.092688)
			(xy 105.526374 -267.101129) (xy 105.500932 -267.101574) (xy 105.475154 -267.101039) (xy 105.424329 -267.092378)
			(xy 105.375684 -267.075297) (xy 105.330602 -267.050283) (xy 105.290367 -267.018046) (xy 105.256122 -266.979505)
			(xy 105.228844 -266.935756) (xy 105.209307 -266.888044) (xy 105.198068 -266.837727) (xy 105.196132 -266.812014)
			(xy 105.195624 -266.803378) (xy 105.195624 -266.796266) (xy 105.196204 -266.768574) (xy 105.206155 -266.714092)
			(xy 105.225777 -266.662301) (xy 105.239566 -266.638278) (xy 105.246678 -266.62634) (xy 105.247186 -266.599162)
			(xy 105.198164 -266.51204) (xy 105.193446 -266.504396) (xy 105.179779 -266.492756) (xy 105.162943 -266.486526)
			(xy 105.153968 -266.486132) (xy 104.908096 -266.486132) (xy 104.899107 -266.486475) (xy 104.882236 -266.492679)
			(xy 104.868565 -266.504351) (xy 104.8639 -266.51204) (xy 104.814878 -266.599162) (xy 104.815386 -266.62634)
			(xy 104.822498 -266.638278) (xy 104.836288 -266.662298) (xy 104.85589 -266.714095) (xy 104.865848 -266.768575)
			(xy 104.86644 -266.796266) (xy 104.86644 -266.803378) (xy 104.865932 -266.812014) (xy 104.864062 -266.837727)
			(xy 104.852784 -266.88803) (xy 104.83322 -266.935725) (xy 104.805924 -266.979457) (xy 104.771672 -267.017985)
			(xy 104.731436 -267.050213) (xy 104.68636 -267.075227) (xy 104.637723 -267.092316) (xy 104.586908 -267.100995)
			(xy 104.561132 -267.101574) (xy 104.53551 -267.101054) (xy 104.484983 -267.092505) (xy 104.436592 -267.075643)
			(xy 104.391695 -267.05094) (xy 104.351551 -267.01909) (xy 104.317286 -266.980985) (xy 104.289863 -266.937696)
			(xy 104.27005 -266.890436) (xy 104.263698 -266.865608) (xy 104.263698 -266.865354) (xy 104.262174 -266.859258)
			(xy 104.25938 -266.85367) (xy 104.252014 -266.843002) (xy 104.235758 -266.824968) (xy 104.23099 -266.820029)
			(xy 104.219404 -266.812677) (xy 104.212898 -266.81049) (xy 104.142286 -266.7889) (xy 104.133372 -266.786609)
			(xy 104.115018 -266.787806) (xy 104.098249 -266.79536) (xy 104.091486 -266.8016) (xy 103.613966 -267.27912)
			(xy 103.606726 -267.285829) (xy 103.588521 -267.293414) (xy 103.57866 -267.293852) (xy 103.496872 -267.293852)
			(xy 103.49103 -267.294106) (xy 103.479772 -267.296098) (xy 103.460522 -267.308374) (xy 103.453946 -267.317728)
			(xy 103.452676 -267.31976) (xy 103.410512 -267.394944) (xy 103.406332 -267.403035) (xy 103.403436 -267.421001)
			(xy 103.407035 -267.438839) (xy 103.411528 -267.44676) (xy 103.425607 -267.470962) (xy 103.445658 -267.523233)
			(xy 103.455866 -267.57828) (xy 103.456486 -267.606272) (xy 103.785174 -267.606272) (xy 103.789134 -267.557218)
			(xy 103.800911 -267.509434) (xy 103.820202 -267.464158) (xy 103.846505 -267.422562) (xy 103.87914 -267.385725)
			(xy 103.917261 -267.3546) (xy 103.959882 -267.329993) (xy 104.005898 -267.312541) (xy 104.054117 -267.302697)
			(xy 104.103292 -267.300716) (xy 104.152147 -267.306648) (xy 104.199418 -267.32034) (xy 104.24388 -267.341438)
			(xy 104.284383 -267.369394) (xy 104.319876 -267.403486) (xy 104.349441 -267.44283) (xy 104.372312 -267.486407)
			(xy 104.387896 -267.533088) (xy 104.395791 -267.581665) (xy 104.396286 -267.606272) (xy 104.725228 -267.606272)
			(xy 104.729188 -267.557218) (xy 104.740965 -267.509434) (xy 104.760256 -267.464158) (xy 104.786559 -267.422562)
			(xy 104.819194 -267.385725) (xy 104.857315 -267.3546) (xy 104.899936 -267.329993) (xy 104.945952 -267.312541)
			(xy 104.994171 -267.302697) (xy 105.043346 -267.300716) (xy 105.092201 -267.306648) (xy 105.139472 -267.32034)
			(xy 105.183934 -267.341438) (xy 105.224437 -267.369394) (xy 105.25993 -267.403486) (xy 105.289495 -267.44283)
			(xy 105.312366 -267.486407) (xy 105.32795 -267.533088) (xy 105.335845 -267.581665) (xy 105.33634 -267.606272)
			(xy 105.665282 -267.606272) (xy 105.669242 -267.557218) (xy 105.681019 -267.509434) (xy 105.70031 -267.464158)
			(xy 105.726613 -267.422562) (xy 105.759248 -267.385725) (xy 105.797369 -267.3546) (xy 105.83999 -267.329993)
			(xy 105.886006 -267.312541) (xy 105.934225 -267.302697) (xy 105.9834 -267.300716) (xy 106.032255 -267.306648)
			(xy 106.079526 -267.32034) (xy 106.123988 -267.341438) (xy 106.164491 -267.369394) (xy 106.199984 -267.403486)
			(xy 106.229549 -267.44283) (xy 106.25242 -267.486407) (xy 106.268004 -267.533088) (xy 106.275899 -267.581665)
			(xy 106.276394 -267.606272) (xy 106.275899 -267.630879) (xy 106.268004 -267.679456) (xy 106.25242 -267.726137)
			(xy 106.229549 -267.769714) (xy 106.199984 -267.809058) (xy 106.164491 -267.84315) (xy 106.123988 -267.871106)
			(xy 106.079526 -267.892204) (xy 106.032255 -267.905896) (xy 105.9834 -267.911828) (xy 105.934225 -267.909847)
			(xy 105.886006 -267.900003) (xy 105.83999 -267.882551) (xy 105.797369 -267.857944) (xy 105.759248 -267.826819)
			(xy 105.726613 -267.789982) (xy 105.70031 -267.748386) (xy 105.681019 -267.70311) (xy 105.669242 -267.655326)
			(xy 105.665282 -267.606272) (xy 105.33634 -267.606272) (xy 105.335845 -267.630879) (xy 105.32795 -267.679456)
			(xy 105.312366 -267.726137) (xy 105.289495 -267.769714) (xy 105.25993 -267.809058) (xy 105.224437 -267.84315)
			(xy 105.183934 -267.871106) (xy 105.139472 -267.892204) (xy 105.092201 -267.905896) (xy 105.043346 -267.911828)
			(xy 104.994171 -267.909847) (xy 104.945952 -267.900003) (xy 104.899936 -267.882551) (xy 104.857315 -267.857944)
			(xy 104.819194 -267.826819) (xy 104.786559 -267.789982) (xy 104.760256 -267.748386) (xy 104.740965 -267.70311)
			(xy 104.729188 -267.655326) (xy 104.725228 -267.606272) (xy 104.396286 -267.606272) (xy 104.395791 -267.630879)
			(xy 104.387896 -267.679456) (xy 104.372312 -267.726137) (xy 104.349441 -267.769714) (xy 104.319876 -267.809058)
			(xy 104.284383 -267.84315) (xy 104.24388 -267.871106) (xy 104.199418 -267.892204) (xy 104.152147 -267.905896)
			(xy 104.103292 -267.911828) (xy 104.054117 -267.909847) (xy 104.005898 -267.900003) (xy 103.959882 -267.882551)
			(xy 103.917261 -267.857944) (xy 103.87914 -267.826819) (xy 103.846505 -267.789982) (xy 103.820202 -267.748386)
			(xy 103.800911 -267.70311) (xy 103.789134 -267.655326) (xy 103.785174 -267.606272) (xy 103.456486 -267.606272)
			(xy 103.456486 -267.612622) (xy 103.455549 -267.636285) (xy 103.447269 -267.68291) (xy 103.431888 -267.727697)
			(xy 103.409775 -267.769571) (xy 103.381461 -267.807528) (xy 103.347625 -267.840658) (xy 103.309078 -267.868164)
			(xy 103.266746 -267.889388) (xy 103.221645 -267.903821) (xy 103.174855 -267.911115) (xy 103.151178 -267.91158)
			(xy 103.12749 -267.911132) (xy 103.080683 -267.903812) (xy 103.035569 -267.889352) (xy 102.993228 -267.868098)
			(xy 102.954678 -267.84056) (xy 102.920843 -267.807399) (xy 102.892535 -267.769411) (xy 102.870433 -267.727506)
			(xy 102.855067 -267.682692) (xy 102.846807 -267.636042) (xy 102.84587 -267.612368) (xy 102.84587 -267.606272)
			(xy 102.846493 -267.578278) (xy 102.856681 -267.523226) (xy 102.876729 -267.470952) (xy 102.890828 -267.44676)
			(xy 102.895277 -267.438827) (xy 102.898829 -267.421) (xy 102.895971 -267.40305) (xy 102.891844 -267.394944)
			(xy 102.84968 -267.31976) (xy 102.84841 -267.317728) (xy 102.841845 -267.308362) (xy 102.822591 -267.296072)
			(xy 102.811326 -267.294106) (xy 102.805484 -267.293852) (xy 102.556818 -267.293852) (xy 102.550976 -267.294106)
			(xy 102.539712 -267.296089) (xy 102.520447 -267.308356) (xy 102.513892 -267.317728) (xy 102.512622 -267.31976)
			(xy 102.470458 -267.394944) (xy 102.466274 -267.403034) (xy 102.463376 -267.421001) (xy 102.466978 -267.438839)
			(xy 102.471474 -267.44676) (xy 102.485555 -267.470962) (xy 102.50561 -267.523232) (xy 102.51582 -267.578279)
			(xy 102.516432 -267.606272) (xy 102.516432 -267.612368) (xy 102.515514 -267.636045) (xy 102.507265 -267.682703)
			(xy 102.491906 -267.727527) (xy 102.469807 -267.769439) (xy 102.441498 -267.807434) (xy 102.407658 -267.840599)
			(xy 102.369101 -267.868138) (xy 102.326753 -267.889389) (xy 102.28163 -267.903842) (xy 102.234815 -267.911151)
			(xy 102.211124 -267.91158) (xy 102.18713 -267.911136) (xy 102.139734 -267.903632) (xy 102.094095 -267.888805)
			(xy 102.051337 -267.86702) (xy 102.012515 -267.838815) (xy 101.978583 -267.804882) (xy 101.950378 -267.766059)
			(xy 101.928594 -267.723302) (xy 101.913767 -267.677662) (xy 101.906264 -267.630266) (xy 101.905816 -267.606272)
			(xy 101.906416 -267.578679) (xy 101.91633 -267.52439) (xy 101.935815 -267.472758) (xy 101.949504 -267.448792)
			(xy 101.956616 -267.436854) (xy 101.957124 -267.409676) (xy 101.908356 -267.322554) (xy 101.903681 -267.314849)
			(xy 101.890037 -267.303092) (xy 101.873164 -267.296794) (xy 101.86416 -267.296392) (xy 101.597968 -267.296392)
			(xy 101.588128 -267.295863) (xy 101.569957 -267.288284) (xy 101.562662 -267.28166) (xy 101.312726 -267.031724)
			(xy 101.306003 -267.02449) (xy 101.29839 -267.006284) (xy 101.297994 -266.996418) (xy 101.297994 -266.735814)
			(xy 101.297555 -266.725751) (xy 101.289818 -266.70717) (xy 101.283008 -266.699746) (xy 100.991924 -266.408662)
			(xy 100.984812 -266.401296) (xy 100.966016 -266.393676) (xy 100.856288 -266.393676) (xy 100.84628 -266.394166)
			(xy 100.827788 -266.401826) (xy 100.813633 -266.415978) (xy 100.805968 -266.434468) (xy 100.805488 -266.444476)
			(xy 100.805488 -266.463272) (xy 100.829872 -266.49172) (xy 100.848414 -266.494768) (xy 100.872079 -266.498908)
			(xy 100.9178 -266.513648) (xy 100.960646 -266.535375) (xy 100.999555 -266.563551) (xy 101.033565 -266.597479)
			(xy 101.061836 -266.636319) (xy 101.083667 -266.679111) (xy 101.098519 -266.724797) (xy 101.106025 -266.772246)
			(xy 101.106478 -266.796266) (xy 101.105956 -266.821521) (xy 101.097643 -266.871343) (xy 101.081242 -266.919117)
			(xy 101.057201 -266.96354) (xy 101.026177 -267.0034) (xy 100.989015 -267.03761) (xy 100.946729 -267.065236)
			(xy 100.900473 -267.085526) (xy 100.851508 -267.097926) (xy 100.80117 -267.102097) (xy 100.750832 -267.097926)
			(xy 100.701867 -267.085526) (xy 100.655611 -267.065236) (xy 100.613325 -267.03761) (xy 100.576163 -267.0034)
			(xy 100.545139 -266.96354) (xy 100.521098 -266.919117) (xy 100.504697 -266.871343) (xy 100.496384 -266.821521)
			(xy 100.495862 -266.796266) (xy 100.496313 -266.772248) (xy 100.503842 -266.724806) (xy 100.518709 -266.679129)
			(xy 100.540547 -266.636345) (xy 100.568816 -266.597509) (xy 100.60282 -266.56358) (xy 100.641718 -266.535396)
			(xy 100.684551 -266.513652) (xy 100.73026 -266.498886) (xy 100.753926 -266.494768) (xy 100.772468 -266.49172)
			(xy 100.796852 -266.463272) (xy 100.796852 -266.444476) (xy 100.796428 -266.434461) (xy 100.788752 -266.415961)
			(xy 100.774579 -266.401808) (xy 100.756067 -266.394158) (xy 100.746052 -266.393676) (xy 100.583492 -266.393676)
			(xy 100.573649 -266.3942) (xy 100.55547 -266.401769) (xy 100.548186 -266.408408) (xy 100.477828 -266.47902)
			(xy 100.470592 -266.485739) (xy 100.452387 -266.493346) (xy 100.442522 -266.493752) (xy 100.212906 -266.493752)
			(xy 100.204017 -266.494092) (xy 100.187315 -266.500182) (xy 100.173711 -266.511628) (xy 100.168964 -266.519152)
			(xy 100.118926 -266.605258) (xy 100.118926 -266.632182) (xy 100.125784 -266.64412) (xy 100.138535 -266.667431)
			(xy 100.156655 -266.717374) (xy 100.165848 -266.769702) (xy 100.166424 -266.796266) (xy 100.165902 -266.821521)
			(xy 100.157589 -266.871343) (xy 100.141188 -266.919117) (xy 100.117147 -266.96354) (xy 100.086123 -267.0034)
			(xy 100.048961 -267.03761) (xy 100.006675 -267.065236) (xy 99.960419 -267.085526) (xy 99.911454 -267.097926)
			(xy 99.861116 -267.102097) (xy 99.810778 -267.097926) (xy 99.761813 -267.085526) (xy 99.715557 -267.065236)
			(xy 99.673271 -267.03761) (xy 99.636109 -267.0034) (xy 99.605085 -266.96354) (xy 99.581044 -266.919117)
			(xy 99.564643 -266.871343) (xy 99.55633 -266.821521) (xy 99.555808 -266.796266) (xy 99.556384 -266.769702)
			(xy 99.565586 -266.717377) (xy 99.583706 -266.667435) (xy 99.596448 -266.64412) (xy 99.603306 -266.632182)
			(xy 99.603306 -266.605258) (xy 99.553522 -266.519152) (xy 99.550601 -266.514398) (xy 99.543032 -266.506202)
			(xy 99.538536 -266.502896) (xy 99.531932 -266.498324) (xy 99.5172 -266.493752) (xy 98.537268 -266.493752)
			(xy 98.527515 -266.494262) (xy 98.509478 -266.501701) (xy 98.502216 -266.50823) (xy 98.298 -266.712446)
			(xy 98.293967 -266.71665) (xy 98.287803 -266.726531) (xy 98.285808 -266.732004) (xy 98.281998 -266.743434)
			(xy 98.283522 -266.755372) (xy 98.284818 -266.765546) (xy 98.286215 -266.78601) (xy 98.286316 -266.796266)
			(xy 98.285872 -266.820261) (xy 98.27837 -266.867661) (xy 98.263544 -266.913304) (xy 98.241761 -266.956065)
			(xy 98.213556 -266.994892) (xy 98.179624 -267.028829) (xy 98.140801 -267.057039) (xy 98.098043 -267.078828)
			(xy 98.052402 -267.09366) (xy 98.005003 -267.101169) (xy 97.981008 -267.101574) (xy 97.970752 -267.101483)
			(xy 97.950287 -267.100085) (xy 97.940114 -267.09878) (xy 97.934278 -267.098184) (xy 97.922606 -267.099339)
			(xy 97.917 -267.101066) (xy 97.916746 -267.101066) (xy 97.911304 -267.103125) (xy 97.901433 -267.109279)
			(xy 97.897188 -267.113258) (xy 97.744788 -267.265658) (xy 97.742248 -267.268452) (xy 97.741994 -267.268706)
			(xy 97.73665 -267.27549) (xy 97.73043 -267.291588) (xy 97.729802 -267.300202) (xy 97.727262 -267.378942)
			(xy 97.733866 -267.39723) (xy 97.740216 -267.404596) (xy 97.75799 -267.425671) (xy 97.786407 -267.472908)
			(xy 97.805882 -267.524479) (xy 97.815783 -267.578709) (xy 97.816416 -267.606272) (xy 98.145358 -267.606272)
			(xy 98.149318 -267.557218) (xy 98.161095 -267.509434) (xy 98.180386 -267.464158) (xy 98.206689 -267.422562)
			(xy 98.239324 -267.385725) (xy 98.277445 -267.3546) (xy 98.320066 -267.329993) (xy 98.366082 -267.312541)
			(xy 98.414301 -267.302697) (xy 98.463476 -267.300716) (xy 98.512331 -267.306648) (xy 98.559602 -267.32034)
			(xy 98.604064 -267.341438) (xy 98.644567 -267.369394) (xy 98.68006 -267.403486) (xy 98.709625 -267.44283)
			(xy 98.732496 -267.486407) (xy 98.74808 -267.533088) (xy 98.755975 -267.581665) (xy 98.75647 -267.606272)
			(xy 100.025212 -267.606272) (xy 100.029172 -267.557218) (xy 100.040949 -267.509434) (xy 100.06024 -267.464158)
			(xy 100.086543 -267.422562) (xy 100.119178 -267.385725) (xy 100.157299 -267.3546) (xy 100.19992 -267.329993)
			(xy 100.245936 -267.312541) (xy 100.294155 -267.302697) (xy 100.34333 -267.300716) (xy 100.392185 -267.306648)
			(xy 100.439456 -267.32034) (xy 100.483918 -267.341438) (xy 100.524421 -267.369394) (xy 100.559914 -267.403486)
			(xy 100.589479 -267.44283) (xy 100.61235 -267.486407) (xy 100.627934 -267.533088) (xy 100.635829 -267.581665)
			(xy 100.636324 -267.606272) (xy 100.965266 -267.606272) (xy 100.969226 -267.557218) (xy 100.981003 -267.509434)
			(xy 101.000294 -267.464158) (xy 101.026597 -267.422562) (xy 101.059232 -267.385725) (xy 101.097353 -267.3546)
			(xy 101.139974 -267.329993) (xy 101.18599 -267.312541) (xy 101.234209 -267.302697) (xy 101.283384 -267.300716)
			(xy 101.332239 -267.306648) (xy 101.37951 -267.32034) (xy 101.423972 -267.341438) (xy 101.464475 -267.369394)
			(xy 101.499968 -267.403486) (xy 101.529533 -267.44283) (xy 101.552404 -267.486407) (xy 101.567988 -267.533088)
			(xy 101.575883 -267.581665) (xy 101.576378 -267.606272) (xy 101.575883 -267.630879) (xy 101.567988 -267.679456)
			(xy 101.552404 -267.726137) (xy 101.529533 -267.769714) (xy 101.499968 -267.809058) (xy 101.464475 -267.84315)
			(xy 101.423972 -267.871106) (xy 101.37951 -267.892204) (xy 101.332239 -267.905896) (xy 101.283384 -267.911828)
			(xy 101.234209 -267.909847) (xy 101.18599 -267.900003) (xy 101.139974 -267.882551) (xy 101.097353 -267.857944)
			(xy 101.059232 -267.826819) (xy 101.026597 -267.789982) (xy 101.000294 -267.748386) (xy 100.981003 -267.70311)
			(xy 100.969226 -267.655326) (xy 100.965266 -267.606272) (xy 100.636324 -267.606272) (xy 100.635829 -267.630879)
			(xy 100.627934 -267.679456) (xy 100.61235 -267.726137) (xy 100.589479 -267.769714) (xy 100.559914 -267.809058)
			(xy 100.524421 -267.84315) (xy 100.483918 -267.871106) (xy 100.439456 -267.892204) (xy 100.392185 -267.905896)
			(xy 100.34333 -267.911828) (xy 100.294155 -267.909847) (xy 100.245936 -267.900003) (xy 100.19992 -267.882551)
			(xy 100.157299 -267.857944) (xy 100.119178 -267.826819) (xy 100.086543 -267.789982) (xy 100.06024 -267.748386)
			(xy 100.040949 -267.70311) (xy 100.029172 -267.655326) (xy 100.025212 -267.606272) (xy 98.75647 -267.606272)
			(xy 98.755975 -267.630879) (xy 98.74808 -267.679456) (xy 98.732496 -267.726137) (xy 98.709625 -267.769714)
			(xy 98.68006 -267.809058) (xy 98.644567 -267.84315) (xy 98.604064 -267.871106) (xy 98.559602 -267.892204)
			(xy 98.512331 -267.905896) (xy 98.463476 -267.911828) (xy 98.414301 -267.909847) (xy 98.366082 -267.900003)
			(xy 98.320066 -267.882551) (xy 98.277445 -267.857944) (xy 98.239324 -267.826819) (xy 98.206689 -267.789982)
			(xy 98.180386 -267.748386) (xy 98.161095 -267.70311) (xy 98.149318 -267.655326) (xy 98.145358 -267.606272)
			(xy 97.816416 -267.606272) (xy 97.815972 -267.630267) (xy 97.808469 -267.677666) (xy 97.793643 -267.723308)
			(xy 97.771859 -267.766069) (xy 97.743654 -267.804895) (xy 97.709722 -267.838831) (xy 97.670899 -267.86704)
			(xy 97.628141 -267.888829) (xy 97.582501 -267.90366) (xy 97.535103 -267.911169) (xy 97.511108 -267.91158)
			(xy 97.493582 -267.911072) (xy 97.483168 -267.910564) (xy 97.463356 -267.917676) (xy 97.402142 -267.975588)
			(xy 97.394914 -267.983036) (xy 97.38665 -268.002052) (xy 97.386465 -268.005814) (xy 111.710473 -268.005814)
			(xy 111.714503 -267.953316) (xy 111.7265 -267.902048) (xy 111.746183 -267.853213) (xy 111.773089 -267.807954)
			(xy 111.806589 -267.767333) (xy 111.845897 -267.732302) (xy 111.890092 -267.703682) (xy 111.938137 -267.682143)
			(xy 111.988908 -267.668191) (xy 112.041213 -267.662153) (xy 112.093827 -267.66417) (xy 112.145517 -267.674194)
			(xy 112.19507 -267.691992) (xy 112.241326 -267.717145) (xy 112.2832 -267.749064) (xy 112.319712 -267.787002)
			(xy 112.350004 -267.830068) (xy 112.373367 -267.877253) (xy 112.389253 -267.927452) (xy 112.39729 -267.979488)
			(xy 112.397794 -268.005814) (xy 112.39729 -268.03214) (xy 112.389253 -268.084176) (xy 112.373367 -268.134375)
			(xy 112.350004 -268.18156) (xy 112.319712 -268.224626) (xy 112.2832 -268.262564) (xy 112.241326 -268.294483)
			(xy 112.19507 -268.319636) (xy 112.145517 -268.337434) (xy 112.093827 -268.347458) (xy 112.041213 -268.349475)
			(xy 111.988908 -268.343437) (xy 111.938137 -268.329485) (xy 111.890092 -268.307946) (xy 111.845897 -268.279326)
			(xy 111.806589 -268.244295) (xy 111.773089 -268.203674) (xy 111.746183 -268.158415) (xy 111.7265 -268.10958)
			(xy 111.714503 -268.058312) (xy 111.710473 -268.005814) (xy 97.386465 -268.005814) (xy 97.38614 -268.012418)
			(xy 97.38614 -268.416278) (xy 97.675204 -268.416278) (xy 97.679164 -268.367224) (xy 97.690941 -268.31944)
			(xy 97.710232 -268.274164) (xy 97.736535 -268.232568) (xy 97.76917 -268.195731) (xy 97.807291 -268.164606)
			(xy 97.849912 -268.139999) (xy 97.895928 -268.122547) (xy 97.944147 -268.112703) (xy 97.993322 -268.110722)
			(xy 98.042177 -268.116654) (xy 98.089448 -268.130346) (xy 98.13391 -268.151444) (xy 98.174413 -268.1794)
			(xy 98.209906 -268.213492) (xy 98.239471 -268.252836) (xy 98.262342 -268.296413) (xy 98.277926 -268.343094)
			(xy 98.285821 -268.391671) (xy 98.286316 -268.416278) (xy 98.615258 -268.416278) (xy 98.619218 -268.367224)
			(xy 98.630995 -268.31944) (xy 98.650286 -268.274164) (xy 98.676589 -268.232568) (xy 98.709224 -268.195731)
			(xy 98.747345 -268.164606) (xy 98.789966 -268.139999) (xy 98.835982 -268.122547) (xy 98.884201 -268.112703)
			(xy 98.933376 -268.110722) (xy 98.982231 -268.116654) (xy 99.029502 -268.130346) (xy 99.073964 -268.151444)
			(xy 99.114467 -268.1794) (xy 99.14996 -268.213492) (xy 99.179525 -268.252836) (xy 99.202396 -268.296413)
			(xy 99.21798 -268.343094) (xy 99.225875 -268.391671) (xy 99.22637 -268.416278) (xy 99.555312 -268.416278)
			(xy 99.559272 -268.367224) (xy 99.571049 -268.31944) (xy 99.59034 -268.274164) (xy 99.616643 -268.232568)
			(xy 99.649278 -268.195731) (xy 99.687399 -268.164606) (xy 99.73002 -268.139999) (xy 99.776036 -268.122547)
			(xy 99.824255 -268.112703) (xy 99.87343 -268.110722) (xy 99.922285 -268.116654) (xy 99.969556 -268.130346)
			(xy 100.014018 -268.151444) (xy 100.054521 -268.1794) (xy 100.090014 -268.213492) (xy 100.119579 -268.252836)
			(xy 100.14245 -268.296413) (xy 100.158034 -268.343094) (xy 100.165929 -268.391671) (xy 100.166424 -268.416278)
			(xy 100.495366 -268.416278) (xy 100.499326 -268.367224) (xy 100.511103 -268.31944) (xy 100.530394 -268.274164)
			(xy 100.556697 -268.232568) (xy 100.589332 -268.195731) (xy 100.627453 -268.164606) (xy 100.670074 -268.139999)
			(xy 100.71609 -268.122547) (xy 100.764309 -268.112703) (xy 100.813484 -268.110722) (xy 100.862339 -268.116654)
			(xy 100.90961 -268.130346) (xy 100.954072 -268.151444) (xy 100.994575 -268.1794) (xy 101.030068 -268.213492)
			(xy 101.059633 -268.252836) (xy 101.082504 -268.296413) (xy 101.098088 -268.343094) (xy 101.105983 -268.391671)
			(xy 101.106478 -268.416278) (xy 101.435166 -268.416278) (xy 101.439126 -268.367224) (xy 101.450903 -268.31944)
			(xy 101.470194 -268.274164) (xy 101.496497 -268.232568) (xy 101.529132 -268.195731) (xy 101.567253 -268.164606)
			(xy 101.609874 -268.139999) (xy 101.65589 -268.122547) (xy 101.704109 -268.112703) (xy 101.753284 -268.110722)
			(xy 101.802139 -268.116654) (xy 101.84941 -268.130346) (xy 101.893872 -268.151444) (xy 101.934375 -268.1794)
			(xy 101.969868 -268.213492) (xy 101.999433 -268.252836) (xy 102.022304 -268.296413) (xy 102.037888 -268.343094)
			(xy 102.045783 -268.391671) (xy 102.046278 -268.416278) (xy 102.37522 -268.416278) (xy 102.37918 -268.367224)
			(xy 102.390957 -268.31944) (xy 102.410248 -268.274164) (xy 102.436551 -268.232568) (xy 102.469186 -268.195731)
			(xy 102.507307 -268.164606) (xy 102.549928 -268.139999) (xy 102.595944 -268.122547) (xy 102.644163 -268.112703)
			(xy 102.693338 -268.110722) (xy 102.742193 -268.116654) (xy 102.789464 -268.130346) (xy 102.833926 -268.151444)
			(xy 102.874429 -268.1794) (xy 102.909922 -268.213492) (xy 102.939487 -268.252836) (xy 102.962358 -268.296413)
			(xy 102.977942 -268.343094) (xy 102.985837 -268.391671) (xy 102.986332 -268.416278) (xy 103.315274 -268.416278)
			(xy 103.319234 -268.367224) (xy 103.331011 -268.31944) (xy 103.350302 -268.274164) (xy 103.376605 -268.232568)
			(xy 103.40924 -268.195731) (xy 103.447361 -268.164606) (xy 103.489982 -268.139999) (xy 103.535998 -268.122547)
			(xy 103.584217 -268.112703) (xy 103.633392 -268.110722) (xy 103.682247 -268.116654) (xy 103.729518 -268.130346)
			(xy 103.77398 -268.151444) (xy 103.814483 -268.1794) (xy 103.849976 -268.213492) (xy 103.879541 -268.252836)
			(xy 103.902412 -268.296413) (xy 103.917996 -268.343094) (xy 103.925891 -268.391671) (xy 103.926386 -268.416278)
			(xy 104.255328 -268.416278) (xy 104.259288 -268.367224) (xy 104.271065 -268.31944) (xy 104.290356 -268.274164)
			(xy 104.316659 -268.232568) (xy 104.349294 -268.195731) (xy 104.387415 -268.164606) (xy 104.430036 -268.139999)
			(xy 104.476052 -268.122547) (xy 104.524271 -268.112703) (xy 104.573446 -268.110722) (xy 104.622301 -268.116654)
			(xy 104.669572 -268.130346) (xy 104.714034 -268.151444) (xy 104.754537 -268.1794) (xy 104.79003 -268.213492)
			(xy 104.819595 -268.252836) (xy 104.842466 -268.296413) (xy 104.85805 -268.343094) (xy 104.865945 -268.391671)
			(xy 104.86644 -268.416278) (xy 105.195128 -268.416278) (xy 105.199088 -268.367224) (xy 105.210865 -268.31944)
			(xy 105.230156 -268.274164) (xy 105.256459 -268.232568) (xy 105.289094 -268.195731) (xy 105.327215 -268.164606)
			(xy 105.369836 -268.139999) (xy 105.415852 -268.122547) (xy 105.464071 -268.112703) (xy 105.513246 -268.110722)
			(xy 105.562101 -268.116654) (xy 105.609372 -268.130346) (xy 105.653834 -268.151444) (xy 105.694337 -268.1794)
			(xy 105.72983 -268.213492) (xy 105.759395 -268.252836) (xy 105.782266 -268.296413) (xy 105.79785 -268.343094)
			(xy 105.805745 -268.391671) (xy 105.80624 -268.416278) (xy 106.135182 -268.416278) (xy 106.139142 -268.367224)
			(xy 106.150919 -268.31944) (xy 106.17021 -268.274164) (xy 106.196513 -268.232568) (xy 106.229148 -268.195731)
			(xy 106.267269 -268.164606) (xy 106.30989 -268.139999) (xy 106.355906 -268.122547) (xy 106.404125 -268.112703)
			(xy 106.4533 -268.110722) (xy 106.502155 -268.116654) (xy 106.549426 -268.130346) (xy 106.593888 -268.151444)
			(xy 106.634391 -268.1794) (xy 106.669884 -268.213492) (xy 106.699449 -268.252836) (xy 106.72232 -268.296413)
			(xy 106.737904 -268.343094) (xy 106.745799 -268.391671) (xy 106.746294 -268.416278) (xy 107.075236 -268.416278)
			(xy 107.079196 -268.367224) (xy 107.090973 -268.31944) (xy 107.110264 -268.274164) (xy 107.136567 -268.232568)
			(xy 107.169202 -268.195731) (xy 107.207323 -268.164606) (xy 107.249944 -268.139999) (xy 107.29596 -268.122547)
			(xy 107.344179 -268.112703) (xy 107.393354 -268.110722) (xy 107.442209 -268.116654) (xy 107.48948 -268.130346)
			(xy 107.533942 -268.151444) (xy 107.574445 -268.1794) (xy 107.609938 -268.213492) (xy 107.639503 -268.252836)
			(xy 107.662374 -268.296413) (xy 107.677958 -268.343094) (xy 107.685853 -268.391671) (xy 107.686348 -268.416278)
			(xy 108.01529 -268.416278) (xy 108.01925 -268.367224) (xy 108.031027 -268.31944) (xy 108.050318 -268.274164)
			(xy 108.076621 -268.232568) (xy 108.109256 -268.195731) (xy 108.147377 -268.164606) (xy 108.189998 -268.139999)
			(xy 108.236014 -268.122547) (xy 108.284233 -268.112703) (xy 108.333408 -268.110722) (xy 108.382263 -268.116654)
			(xy 108.429534 -268.130346) (xy 108.473996 -268.151444) (xy 108.514499 -268.1794) (xy 108.549992 -268.213492)
			(xy 108.579557 -268.252836) (xy 108.602428 -268.296413) (xy 108.618012 -268.343094) (xy 108.625907 -268.391671)
			(xy 108.626402 -268.416278) (xy 108.955344 -268.416278) (xy 108.959304 -268.367224) (xy 108.971081 -268.31944)
			(xy 108.990372 -268.274164) (xy 109.016675 -268.232568) (xy 109.04931 -268.195731) (xy 109.087431 -268.164606)
			(xy 109.130052 -268.139999) (xy 109.176068 -268.122547) (xy 109.224287 -268.112703) (xy 109.273462 -268.110722)
			(xy 109.322317 -268.116654) (xy 109.369588 -268.130346) (xy 109.41405 -268.151444) (xy 109.454553 -268.1794)
			(xy 109.490046 -268.213492) (xy 109.519611 -268.252836) (xy 109.542482 -268.296413) (xy 109.558066 -268.343094)
			(xy 109.565961 -268.391671) (xy 109.566456 -268.416278) (xy 109.895144 -268.416278) (xy 109.899104 -268.367224)
			(xy 109.910881 -268.31944) (xy 109.930172 -268.274164) (xy 109.956475 -268.232568) (xy 109.98911 -268.195731)
			(xy 110.027231 -268.164606) (xy 110.069852 -268.139999) (xy 110.115868 -268.122547) (xy 110.164087 -268.112703)
			(xy 110.213262 -268.110722) (xy 110.262117 -268.116654) (xy 110.309388 -268.130346) (xy 110.35385 -268.151444)
			(xy 110.394353 -268.1794) (xy 110.429846 -268.213492) (xy 110.459411 -268.252836) (xy 110.482282 -268.296413)
			(xy 110.497866 -268.343094) (xy 110.505761 -268.391671) (xy 110.506256 -268.416278) (xy 113.64901 -268.416278)
			(xy 113.65297 -268.367224) (xy 113.664747 -268.31944) (xy 113.684038 -268.274164) (xy 113.710341 -268.232568)
			(xy 113.742976 -268.195731) (xy 113.781097 -268.164606) (xy 113.823718 -268.139999) (xy 113.869734 -268.122547)
			(xy 113.917953 -268.112703) (xy 113.967128 -268.110722) (xy 114.015983 -268.116654) (xy 114.063254 -268.130346)
			(xy 114.107716 -268.151444) (xy 114.148219 -268.1794) (xy 114.183712 -268.213492) (xy 114.213277 -268.252836)
			(xy 114.236148 -268.296413) (xy 114.251732 -268.343094) (xy 114.259627 -268.391671) (xy 114.260122 -268.416278)
			(xy 114.58881 -268.416278) (xy 114.59277 -268.367224) (xy 114.604547 -268.31944) (xy 114.623838 -268.274164)
			(xy 114.650141 -268.232568) (xy 114.682776 -268.195731) (xy 114.720897 -268.164606) (xy 114.763518 -268.139999)
			(xy 114.809534 -268.122547) (xy 114.857753 -268.112703) (xy 114.906928 -268.110722) (xy 114.955783 -268.116654)
			(xy 115.003054 -268.130346) (xy 115.047516 -268.151444) (xy 115.088019 -268.1794) (xy 115.123512 -268.213492)
			(xy 115.153077 -268.252836) (xy 115.175948 -268.296413) (xy 115.191532 -268.343094) (xy 115.199427 -268.391671)
			(xy 115.199922 -268.416278) (xy 115.528864 -268.416278) (xy 115.532824 -268.367224) (xy 115.544601 -268.31944)
			(xy 115.563892 -268.274164) (xy 115.590195 -268.232568) (xy 115.62283 -268.195731) (xy 115.660951 -268.164606)
			(xy 115.703572 -268.139999) (xy 115.749588 -268.122547) (xy 115.797807 -268.112703) (xy 115.846982 -268.110722)
			(xy 115.895837 -268.116654) (xy 115.943108 -268.130346) (xy 115.98757 -268.151444) (xy 116.028073 -268.1794)
			(xy 116.063566 -268.213492) (xy 116.093131 -268.252836) (xy 116.116002 -268.296413) (xy 116.131586 -268.343094)
			(xy 116.139481 -268.391671) (xy 116.139976 -268.416278) (xy 116.468918 -268.416278) (xy 116.472878 -268.367224)
			(xy 116.484655 -268.31944) (xy 116.503946 -268.274164) (xy 116.530249 -268.232568) (xy 116.562884 -268.195731)
			(xy 116.601005 -268.164606) (xy 116.643626 -268.139999) (xy 116.689642 -268.122547) (xy 116.737861 -268.112703)
			(xy 116.787036 -268.110722) (xy 116.835891 -268.116654) (xy 116.883162 -268.130346) (xy 116.927624 -268.151444)
			(xy 116.968127 -268.1794) (xy 117.00362 -268.213492) (xy 117.033185 -268.252836) (xy 117.056056 -268.296413)
			(xy 117.07164 -268.343094) (xy 117.079535 -268.391671) (xy 117.08003 -268.416278) (xy 117.408972 -268.416278)
			(xy 117.412932 -268.367224) (xy 117.424709 -268.31944) (xy 117.444 -268.274164) (xy 117.470303 -268.232568)
			(xy 117.502938 -268.195731) (xy 117.541059 -268.164606) (xy 117.58368 -268.139999) (xy 117.629696 -268.122547)
			(xy 117.677915 -268.112703) (xy 117.72709 -268.110722) (xy 117.775945 -268.116654) (xy 117.823216 -268.130346)
			(xy 117.867678 -268.151444) (xy 117.908181 -268.1794) (xy 117.943674 -268.213492) (xy 117.973239 -268.252836)
			(xy 117.99611 -268.296413) (xy 118.011694 -268.343094) (xy 118.019589 -268.391671) (xy 118.020084 -268.416278)
			(xy 118.349026 -268.416278) (xy 118.352986 -268.367224) (xy 118.364763 -268.31944) (xy 118.384054 -268.274164)
			(xy 118.410357 -268.232568) (xy 118.442992 -268.195731) (xy 118.481113 -268.164606) (xy 118.523734 -268.139999)
			(xy 118.56975 -268.122547) (xy 118.617969 -268.112703) (xy 118.667144 -268.110722) (xy 118.715999 -268.116654)
			(xy 118.76327 -268.130346) (xy 118.807732 -268.151444) (xy 118.848235 -268.1794) (xy 118.883728 -268.213492)
			(xy 118.913293 -268.252836) (xy 118.936164 -268.296413) (xy 118.951748 -268.343094) (xy 118.959643 -268.391671)
			(xy 118.960138 -268.416278) (xy 119.288826 -268.416278) (xy 119.292786 -268.367224) (xy 119.304563 -268.31944)
			(xy 119.323854 -268.274164) (xy 119.350157 -268.232568) (xy 119.382792 -268.195731) (xy 119.420913 -268.164606)
			(xy 119.463534 -268.139999) (xy 119.50955 -268.122547) (xy 119.557769 -268.112703) (xy 119.606944 -268.110722)
			(xy 119.655799 -268.116654) (xy 119.70307 -268.130346) (xy 119.747532 -268.151444) (xy 119.788035 -268.1794)
			(xy 119.823528 -268.213492) (xy 119.853093 -268.252836) (xy 119.875964 -268.296413) (xy 119.891548 -268.343094)
			(xy 119.899443 -268.391671) (xy 119.899938 -268.416278) (xy 120.22888 -268.416278) (xy 120.23284 -268.367224)
			(xy 120.244617 -268.31944) (xy 120.263908 -268.274164) (xy 120.290211 -268.232568) (xy 120.322846 -268.195731)
			(xy 120.360967 -268.164606) (xy 120.403588 -268.139999) (xy 120.449604 -268.122547) (xy 120.497823 -268.112703)
			(xy 120.546998 -268.110722) (xy 120.595853 -268.116654) (xy 120.643124 -268.130346) (xy 120.687586 -268.151444)
			(xy 120.728089 -268.1794) (xy 120.763582 -268.213492) (xy 120.793147 -268.252836) (xy 120.816018 -268.296413)
			(xy 120.831602 -268.343094) (xy 120.839497 -268.391671) (xy 120.839992 -268.416278) (xy 121.168934 -268.416278)
			(xy 121.172894 -268.367224) (xy 121.184671 -268.31944) (xy 121.203962 -268.274164) (xy 121.230265 -268.232568)
			(xy 121.2629 -268.195731) (xy 121.301021 -268.164606) (xy 121.343642 -268.139999) (xy 121.389658 -268.122547)
			(xy 121.437877 -268.112703) (xy 121.487052 -268.110722) (xy 121.535907 -268.116654) (xy 121.583178 -268.130346)
			(xy 121.62764 -268.151444) (xy 121.668143 -268.1794) (xy 121.703636 -268.213492) (xy 121.733201 -268.252836)
			(xy 121.756072 -268.296413) (xy 121.771656 -268.343094) (xy 121.779551 -268.391671) (xy 121.780046 -268.416278)
			(xy 122.108988 -268.416278) (xy 122.112948 -268.367224) (xy 122.124725 -268.31944) (xy 122.144016 -268.274164)
			(xy 122.170319 -268.232568) (xy 122.202954 -268.195731) (xy 122.241075 -268.164606) (xy 122.283696 -268.139999)
			(xy 122.329712 -268.122547) (xy 122.377931 -268.112703) (xy 122.427106 -268.110722) (xy 122.475961 -268.116654)
			(xy 122.523232 -268.130346) (xy 122.567694 -268.151444) (xy 122.608197 -268.1794) (xy 122.64369 -268.213492)
			(xy 122.673255 -268.252836) (xy 122.696126 -268.296413) (xy 122.71171 -268.343094) (xy 122.719605 -268.391671)
			(xy 122.7201 -268.416278) (xy 123.049042 -268.416278) (xy 123.053002 -268.367224) (xy 123.064779 -268.31944)
			(xy 123.08407 -268.274164) (xy 123.110373 -268.232568) (xy 123.143008 -268.195731) (xy 123.181129 -268.164606)
			(xy 123.22375 -268.139999) (xy 123.269766 -268.122547) (xy 123.317985 -268.112703) (xy 123.36716 -268.110722)
			(xy 123.416015 -268.116654) (xy 123.463286 -268.130346) (xy 123.507748 -268.151444) (xy 123.548251 -268.1794)
			(xy 123.583744 -268.213492) (xy 123.613309 -268.252836) (xy 123.63618 -268.296413) (xy 123.651764 -268.343094)
			(xy 123.659659 -268.391671) (xy 123.660154 -268.416278) (xy 123.988842 -268.416278) (xy 123.992802 -268.367224)
			(xy 124.004579 -268.31944) (xy 124.02387 -268.274164) (xy 124.050173 -268.232568) (xy 124.082808 -268.195731)
			(xy 124.120929 -268.164606) (xy 124.16355 -268.139999) (xy 124.209566 -268.122547) (xy 124.257785 -268.112703)
			(xy 124.30696 -268.110722) (xy 124.355815 -268.116654) (xy 124.403086 -268.130346) (xy 124.447548 -268.151444)
			(xy 124.488051 -268.1794) (xy 124.523544 -268.213492) (xy 124.553109 -268.252836) (xy 124.57598 -268.296413)
			(xy 124.591564 -268.343094) (xy 124.599459 -268.391671) (xy 124.599954 -268.416278) (xy 124.928896 -268.416278)
			(xy 124.932856 -268.367224) (xy 124.944633 -268.31944) (xy 124.963924 -268.274164) (xy 124.990227 -268.232568)
			(xy 125.022862 -268.195731) (xy 125.060983 -268.164606) (xy 125.103604 -268.139999) (xy 125.14962 -268.122547)
			(xy 125.197839 -268.112703) (xy 125.247014 -268.110722) (xy 125.295869 -268.116654) (xy 125.34314 -268.130346)
			(xy 125.387602 -268.151444) (xy 125.428105 -268.1794) (xy 125.463598 -268.213492) (xy 125.493163 -268.252836)
			(xy 125.516034 -268.296413) (xy 125.531618 -268.343094) (xy 125.539513 -268.391671) (xy 125.540008 -268.416278)
			(xy 125.86895 -268.416278) (xy 125.87291 -268.367224) (xy 125.884687 -268.31944) (xy 125.903978 -268.274164)
			(xy 125.930281 -268.232568) (xy 125.962916 -268.195731) (xy 126.001037 -268.164606) (xy 126.043658 -268.139999)
			(xy 126.089674 -268.122547) (xy 126.137893 -268.112703) (xy 126.187068 -268.110722) (xy 126.235923 -268.116654)
			(xy 126.283194 -268.130346) (xy 126.327656 -268.151444) (xy 126.368159 -268.1794) (xy 126.403652 -268.213492)
			(xy 126.433217 -268.252836) (xy 126.456088 -268.296413) (xy 126.471672 -268.343094) (xy 126.479567 -268.391671)
			(xy 126.480062 -268.416278) (xy 126.479567 -268.440885) (xy 126.471672 -268.489462) (xy 126.456088 -268.536143)
			(xy 126.433217 -268.57972) (xy 126.403652 -268.619064) (xy 126.368159 -268.653156) (xy 126.327656 -268.681112)
			(xy 126.283194 -268.70221) (xy 126.235923 -268.715902) (xy 126.187068 -268.721834) (xy 126.137893 -268.719853)
			(xy 126.089674 -268.710009) (xy 126.043658 -268.692557) (xy 126.001037 -268.66795) (xy 125.962916 -268.636825)
			(xy 125.930281 -268.599988) (xy 125.903978 -268.558392) (xy 125.884687 -268.513116) (xy 125.87291 -268.465332)
			(xy 125.86895 -268.416278) (xy 125.540008 -268.416278) (xy 125.539513 -268.440885) (xy 125.531618 -268.489462)
			(xy 125.516034 -268.536143) (xy 125.493163 -268.57972) (xy 125.463598 -268.619064) (xy 125.428105 -268.653156)
			(xy 125.387602 -268.681112) (xy 125.34314 -268.70221) (xy 125.295869 -268.715902) (xy 125.247014 -268.721834)
			(xy 125.197839 -268.719853) (xy 125.14962 -268.710009) (xy 125.103604 -268.692557) (xy 125.060983 -268.66795)
			(xy 125.022862 -268.636825) (xy 124.990227 -268.599988) (xy 124.963924 -268.558392) (xy 124.944633 -268.513116)
			(xy 124.932856 -268.465332) (xy 124.928896 -268.416278) (xy 124.599954 -268.416278) (xy 124.599459 -268.440885)
			(xy 124.591564 -268.489462) (xy 124.57598 -268.536143) (xy 124.553109 -268.57972) (xy 124.523544 -268.619064)
			(xy 124.488051 -268.653156) (xy 124.447548 -268.681112) (xy 124.403086 -268.70221) (xy 124.355815 -268.715902)
			(xy 124.30696 -268.721834) (xy 124.257785 -268.719853) (xy 124.209566 -268.710009) (xy 124.16355 -268.692557)
			(xy 124.120929 -268.66795) (xy 124.082808 -268.636825) (xy 124.050173 -268.599988) (xy 124.02387 -268.558392)
			(xy 124.004579 -268.513116) (xy 123.992802 -268.465332) (xy 123.988842 -268.416278) (xy 123.660154 -268.416278)
			(xy 123.659659 -268.440885) (xy 123.651764 -268.489462) (xy 123.63618 -268.536143) (xy 123.613309 -268.57972)
			(xy 123.583744 -268.619064) (xy 123.548251 -268.653156) (xy 123.507748 -268.681112) (xy 123.463286 -268.70221)
			(xy 123.416015 -268.715902) (xy 123.36716 -268.721834) (xy 123.317985 -268.719853) (xy 123.269766 -268.710009)
			(xy 123.22375 -268.692557) (xy 123.181129 -268.66795) (xy 123.143008 -268.636825) (xy 123.110373 -268.599988)
			(xy 123.08407 -268.558392) (xy 123.064779 -268.513116) (xy 123.053002 -268.465332) (xy 123.049042 -268.416278)
			(xy 122.7201 -268.416278) (xy 122.719605 -268.440885) (xy 122.71171 -268.489462) (xy 122.696126 -268.536143)
			(xy 122.673255 -268.57972) (xy 122.64369 -268.619064) (xy 122.608197 -268.653156) (xy 122.567694 -268.681112)
			(xy 122.523232 -268.70221) (xy 122.475961 -268.715902) (xy 122.427106 -268.721834) (xy 122.377931 -268.719853)
			(xy 122.329712 -268.710009) (xy 122.283696 -268.692557) (xy 122.241075 -268.66795) (xy 122.202954 -268.636825)
			(xy 122.170319 -268.599988) (xy 122.144016 -268.558392) (xy 122.124725 -268.513116) (xy 122.112948 -268.465332)
			(xy 122.108988 -268.416278) (xy 121.780046 -268.416278) (xy 121.779551 -268.440885) (xy 121.771656 -268.489462)
			(xy 121.756072 -268.536143) (xy 121.733201 -268.57972) (xy 121.703636 -268.619064) (xy 121.668143 -268.653156)
			(xy 121.62764 -268.681112) (xy 121.583178 -268.70221) (xy 121.535907 -268.715902) (xy 121.487052 -268.721834)
			(xy 121.437877 -268.719853) (xy 121.389658 -268.710009) (xy 121.343642 -268.692557) (xy 121.301021 -268.66795)
			(xy 121.2629 -268.636825) (xy 121.230265 -268.599988) (xy 121.203962 -268.558392) (xy 121.184671 -268.513116)
			(xy 121.172894 -268.465332) (xy 121.168934 -268.416278) (xy 120.839992 -268.416278) (xy 120.839497 -268.440885)
			(xy 120.831602 -268.489462) (xy 120.816018 -268.536143) (xy 120.793147 -268.57972) (xy 120.763582 -268.619064)
			(xy 120.728089 -268.653156) (xy 120.687586 -268.681112) (xy 120.643124 -268.70221) (xy 120.595853 -268.715902)
			(xy 120.546998 -268.721834) (xy 120.497823 -268.719853) (xy 120.449604 -268.710009) (xy 120.403588 -268.692557)
			(xy 120.360967 -268.66795) (xy 120.322846 -268.636825) (xy 120.290211 -268.599988) (xy 120.263908 -268.558392)
			(xy 120.244617 -268.513116) (xy 120.23284 -268.465332) (xy 120.22888 -268.416278) (xy 119.899938 -268.416278)
			(xy 119.899443 -268.440885) (xy 119.891548 -268.489462) (xy 119.875964 -268.536143) (xy 119.853093 -268.57972)
			(xy 119.823528 -268.619064) (xy 119.788035 -268.653156) (xy 119.747532 -268.681112) (xy 119.70307 -268.70221)
			(xy 119.655799 -268.715902) (xy 119.606944 -268.721834) (xy 119.557769 -268.719853) (xy 119.50955 -268.710009)
			(xy 119.463534 -268.692557) (xy 119.420913 -268.66795) (xy 119.382792 -268.636825) (xy 119.350157 -268.599988)
			(xy 119.323854 -268.558392) (xy 119.304563 -268.513116) (xy 119.292786 -268.465332) (xy 119.288826 -268.416278)
			(xy 118.960138 -268.416278) (xy 118.959643 -268.440885) (xy 118.951748 -268.489462) (xy 118.936164 -268.536143)
			(xy 118.913293 -268.57972) (xy 118.883728 -268.619064) (xy 118.848235 -268.653156) (xy 118.807732 -268.681112)
			(xy 118.76327 -268.70221) (xy 118.715999 -268.715902) (xy 118.667144 -268.721834) (xy 118.617969 -268.719853)
			(xy 118.56975 -268.710009) (xy 118.523734 -268.692557) (xy 118.481113 -268.66795) (xy 118.442992 -268.636825)
			(xy 118.410357 -268.599988) (xy 118.384054 -268.558392) (xy 118.364763 -268.513116) (xy 118.352986 -268.465332)
			(xy 118.349026 -268.416278) (xy 118.020084 -268.416278) (xy 118.019589 -268.440885) (xy 118.011694 -268.489462)
			(xy 117.99611 -268.536143) (xy 117.973239 -268.57972) (xy 117.943674 -268.619064) (xy 117.908181 -268.653156)
			(xy 117.867678 -268.681112) (xy 117.823216 -268.70221) (xy 117.775945 -268.715902) (xy 117.72709 -268.721834)
			(xy 117.677915 -268.719853) (xy 117.629696 -268.710009) (xy 117.58368 -268.692557) (xy 117.541059 -268.66795)
			(xy 117.502938 -268.636825) (xy 117.470303 -268.599988) (xy 117.444 -268.558392) (xy 117.424709 -268.513116)
			(xy 117.412932 -268.465332) (xy 117.408972 -268.416278) (xy 117.08003 -268.416278) (xy 117.079535 -268.440885)
			(xy 117.07164 -268.489462) (xy 117.056056 -268.536143) (xy 117.033185 -268.57972) (xy 117.00362 -268.619064)
			(xy 116.968127 -268.653156) (xy 116.927624 -268.681112) (xy 116.883162 -268.70221) (xy 116.835891 -268.715902)
			(xy 116.787036 -268.721834) (xy 116.737861 -268.719853) (xy 116.689642 -268.710009) (xy 116.643626 -268.692557)
			(xy 116.601005 -268.66795) (xy 116.562884 -268.636825) (xy 116.530249 -268.599988) (xy 116.503946 -268.558392)
			(xy 116.484655 -268.513116) (xy 116.472878 -268.465332) (xy 116.468918 -268.416278) (xy 116.139976 -268.416278)
			(xy 116.139481 -268.440885) (xy 116.131586 -268.489462) (xy 116.116002 -268.536143) (xy 116.093131 -268.57972)
			(xy 116.063566 -268.619064) (xy 116.028073 -268.653156) (xy 115.98757 -268.681112) (xy 115.943108 -268.70221)
			(xy 115.895837 -268.715902) (xy 115.846982 -268.721834) (xy 115.797807 -268.719853) (xy 115.749588 -268.710009)
			(xy 115.703572 -268.692557) (xy 115.660951 -268.66795) (xy 115.62283 -268.636825) (xy 115.590195 -268.599988)
			(xy 115.563892 -268.558392) (xy 115.544601 -268.513116) (xy 115.532824 -268.465332) (xy 115.528864 -268.416278)
			(xy 115.199922 -268.416278) (xy 115.199427 -268.440885) (xy 115.191532 -268.489462) (xy 115.175948 -268.536143)
			(xy 115.153077 -268.57972) (xy 115.123512 -268.619064) (xy 115.088019 -268.653156) (xy 115.047516 -268.681112)
			(xy 115.003054 -268.70221) (xy 114.955783 -268.715902) (xy 114.906928 -268.721834) (xy 114.857753 -268.719853)
			(xy 114.809534 -268.710009) (xy 114.763518 -268.692557) (xy 114.720897 -268.66795) (xy 114.682776 -268.636825)
			(xy 114.650141 -268.599988) (xy 114.623838 -268.558392) (xy 114.604547 -268.513116) (xy 114.59277 -268.465332)
			(xy 114.58881 -268.416278) (xy 114.260122 -268.416278) (xy 114.259627 -268.440885) (xy 114.251732 -268.489462)
			(xy 114.236148 -268.536143) (xy 114.213277 -268.57972) (xy 114.183712 -268.619064) (xy 114.148219 -268.653156)
			(xy 114.107716 -268.681112) (xy 114.063254 -268.70221) (xy 114.015983 -268.715902) (xy 113.967128 -268.721834)
			(xy 113.917953 -268.719853) (xy 113.869734 -268.710009) (xy 113.823718 -268.692557) (xy 113.781097 -268.66795)
			(xy 113.742976 -268.636825) (xy 113.710341 -268.599988) (xy 113.684038 -268.558392) (xy 113.664747 -268.513116)
			(xy 113.65297 -268.465332) (xy 113.64901 -268.416278) (xy 110.506256 -268.416278) (xy 110.505761 -268.440885)
			(xy 110.497866 -268.489462) (xy 110.482282 -268.536143) (xy 110.459411 -268.57972) (xy 110.429846 -268.619064)
			(xy 110.394353 -268.653156) (xy 110.35385 -268.681112) (xy 110.309388 -268.70221) (xy 110.262117 -268.715902)
			(xy 110.213262 -268.721834) (xy 110.164087 -268.719853) (xy 110.115868 -268.710009) (xy 110.069852 -268.692557)
			(xy 110.027231 -268.66795) (xy 109.98911 -268.636825) (xy 109.956475 -268.599988) (xy 109.930172 -268.558392)
			(xy 109.910881 -268.513116) (xy 109.899104 -268.465332) (xy 109.895144 -268.416278) (xy 109.566456 -268.416278)
			(xy 109.565961 -268.440885) (xy 109.558066 -268.489462) (xy 109.542482 -268.536143) (xy 109.519611 -268.57972)
			(xy 109.490046 -268.619064) (xy 109.454553 -268.653156) (xy 109.41405 -268.681112) (xy 109.369588 -268.70221)
			(xy 109.322317 -268.715902) (xy 109.273462 -268.721834) (xy 109.224287 -268.719853) (xy 109.176068 -268.710009)
			(xy 109.130052 -268.692557) (xy 109.087431 -268.66795) (xy 109.04931 -268.636825) (xy 109.016675 -268.599988)
			(xy 108.990372 -268.558392) (xy 108.971081 -268.513116) (xy 108.959304 -268.465332) (xy 108.955344 -268.416278)
			(xy 108.626402 -268.416278) (xy 108.625907 -268.440885) (xy 108.618012 -268.489462) (xy 108.602428 -268.536143)
			(xy 108.579557 -268.57972) (xy 108.549992 -268.619064) (xy 108.514499 -268.653156) (xy 108.473996 -268.681112)
			(xy 108.429534 -268.70221) (xy 108.382263 -268.715902) (xy 108.333408 -268.721834) (xy 108.284233 -268.719853)
			(xy 108.236014 -268.710009) (xy 108.189998 -268.692557) (xy 108.147377 -268.66795) (xy 108.109256 -268.636825)
			(xy 108.076621 -268.599988) (xy 108.050318 -268.558392) (xy 108.031027 -268.513116) (xy 108.01925 -268.465332)
			(xy 108.01529 -268.416278) (xy 107.686348 -268.416278) (xy 107.685853 -268.440885) (xy 107.677958 -268.489462)
			(xy 107.662374 -268.536143) (xy 107.639503 -268.57972) (xy 107.609938 -268.619064) (xy 107.574445 -268.653156)
			(xy 107.533942 -268.681112) (xy 107.48948 -268.70221) (xy 107.442209 -268.715902) (xy 107.393354 -268.721834)
			(xy 107.344179 -268.719853) (xy 107.29596 -268.710009) (xy 107.249944 -268.692557) (xy 107.207323 -268.66795)
			(xy 107.169202 -268.636825) (xy 107.136567 -268.599988) (xy 107.110264 -268.558392) (xy 107.090973 -268.513116)
			(xy 107.079196 -268.465332) (xy 107.075236 -268.416278) (xy 106.746294 -268.416278) (xy 106.745799 -268.440885)
			(xy 106.737904 -268.489462) (xy 106.72232 -268.536143) (xy 106.699449 -268.57972) (xy 106.669884 -268.619064)
			(xy 106.634391 -268.653156) (xy 106.593888 -268.681112) (xy 106.549426 -268.70221) (xy 106.502155 -268.715902)
			(xy 106.4533 -268.721834) (xy 106.404125 -268.719853) (xy 106.355906 -268.710009) (xy 106.30989 -268.692557)
			(xy 106.267269 -268.66795) (xy 106.229148 -268.636825) (xy 106.196513 -268.599988) (xy 106.17021 -268.558392)
			(xy 106.150919 -268.513116) (xy 106.139142 -268.465332) (xy 106.135182 -268.416278) (xy 105.80624 -268.416278)
			(xy 105.805745 -268.440885) (xy 105.79785 -268.489462) (xy 105.782266 -268.536143) (xy 105.759395 -268.57972)
			(xy 105.72983 -268.619064) (xy 105.694337 -268.653156) (xy 105.653834 -268.681112) (xy 105.609372 -268.70221)
			(xy 105.562101 -268.715902) (xy 105.513246 -268.721834) (xy 105.464071 -268.719853) (xy 105.415852 -268.710009)
			(xy 105.369836 -268.692557) (xy 105.327215 -268.66795) (xy 105.289094 -268.636825) (xy 105.256459 -268.599988)
			(xy 105.230156 -268.558392) (xy 105.210865 -268.513116) (xy 105.199088 -268.465332) (xy 105.195128 -268.416278)
			(xy 104.86644 -268.416278) (xy 104.865945 -268.440885) (xy 104.85805 -268.489462) (xy 104.842466 -268.536143)
			(xy 104.819595 -268.57972) (xy 104.79003 -268.619064) (xy 104.754537 -268.653156) (xy 104.714034 -268.681112)
			(xy 104.669572 -268.70221) (xy 104.622301 -268.715902) (xy 104.573446 -268.721834) (xy 104.524271 -268.719853)
			(xy 104.476052 -268.710009) (xy 104.430036 -268.692557) (xy 104.387415 -268.66795) (xy 104.349294 -268.636825)
			(xy 104.316659 -268.599988) (xy 104.290356 -268.558392) (xy 104.271065 -268.513116) (xy 104.259288 -268.465332)
			(xy 104.255328 -268.416278) (xy 103.926386 -268.416278) (xy 103.925891 -268.440885) (xy 103.917996 -268.489462)
			(xy 103.902412 -268.536143) (xy 103.879541 -268.57972) (xy 103.849976 -268.619064) (xy 103.814483 -268.653156)
			(xy 103.77398 -268.681112) (xy 103.729518 -268.70221) (xy 103.682247 -268.715902) (xy 103.633392 -268.721834)
			(xy 103.584217 -268.719853) (xy 103.535998 -268.710009) (xy 103.489982 -268.692557) (xy 103.447361 -268.66795)
			(xy 103.40924 -268.636825) (xy 103.376605 -268.599988) (xy 103.350302 -268.558392) (xy 103.331011 -268.513116)
			(xy 103.319234 -268.465332) (xy 103.315274 -268.416278) (xy 102.986332 -268.416278) (xy 102.985837 -268.440885)
			(xy 102.977942 -268.489462) (xy 102.962358 -268.536143) (xy 102.939487 -268.57972) (xy 102.909922 -268.619064)
			(xy 102.874429 -268.653156) (xy 102.833926 -268.681112) (xy 102.789464 -268.70221) (xy 102.742193 -268.715902)
			(xy 102.693338 -268.721834) (xy 102.644163 -268.719853) (xy 102.595944 -268.710009) (xy 102.549928 -268.692557)
			(xy 102.507307 -268.66795) (xy 102.469186 -268.636825) (xy 102.436551 -268.599988) (xy 102.410248 -268.558392)
			(xy 102.390957 -268.513116) (xy 102.37918 -268.465332) (xy 102.37522 -268.416278) (xy 102.046278 -268.416278)
			(xy 102.045783 -268.440885) (xy 102.037888 -268.489462) (xy 102.022304 -268.536143) (xy 101.999433 -268.57972)
			(xy 101.969868 -268.619064) (xy 101.934375 -268.653156) (xy 101.893872 -268.681112) (xy 101.84941 -268.70221)
			(xy 101.802139 -268.715902) (xy 101.753284 -268.721834) (xy 101.704109 -268.719853) (xy 101.65589 -268.710009)
			(xy 101.609874 -268.692557) (xy 101.567253 -268.66795) (xy 101.529132 -268.636825) (xy 101.496497 -268.599988)
			(xy 101.470194 -268.558392) (xy 101.450903 -268.513116) (xy 101.439126 -268.465332) (xy 101.435166 -268.416278)
			(xy 101.106478 -268.416278) (xy 101.105983 -268.440885) (xy 101.098088 -268.489462) (xy 101.082504 -268.536143)
			(xy 101.059633 -268.57972) (xy 101.030068 -268.619064) (xy 100.994575 -268.653156) (xy 100.954072 -268.681112)
			(xy 100.90961 -268.70221) (xy 100.862339 -268.715902) (xy 100.813484 -268.721834) (xy 100.764309 -268.719853)
			(xy 100.71609 -268.710009) (xy 100.670074 -268.692557) (xy 100.627453 -268.66795) (xy 100.589332 -268.636825)
			(xy 100.556697 -268.599988) (xy 100.530394 -268.558392) (xy 100.511103 -268.513116) (xy 100.499326 -268.465332)
			(xy 100.495366 -268.416278) (xy 100.166424 -268.416278) (xy 100.165929 -268.440885) (xy 100.158034 -268.489462)
			(xy 100.14245 -268.536143) (xy 100.119579 -268.57972) (xy 100.090014 -268.619064) (xy 100.054521 -268.653156)
			(xy 100.014018 -268.681112) (xy 99.969556 -268.70221) (xy 99.922285 -268.715902) (xy 99.87343 -268.721834)
			(xy 99.824255 -268.719853) (xy 99.776036 -268.710009) (xy 99.73002 -268.692557) (xy 99.687399 -268.66795)
			(xy 99.649278 -268.636825) (xy 99.616643 -268.599988) (xy 99.59034 -268.558392) (xy 99.571049 -268.513116)
			(xy 99.559272 -268.465332) (xy 99.555312 -268.416278) (xy 99.22637 -268.416278) (xy 99.225875 -268.440885)
			(xy 99.21798 -268.489462) (xy 99.202396 -268.536143) (xy 99.179525 -268.57972) (xy 99.14996 -268.619064)
			(xy 99.114467 -268.653156) (xy 99.073964 -268.681112) (xy 99.029502 -268.70221) (xy 98.982231 -268.715902)
			(xy 98.933376 -268.721834) (xy 98.884201 -268.719853) (xy 98.835982 -268.710009) (xy 98.789966 -268.692557)
			(xy 98.747345 -268.66795) (xy 98.709224 -268.636825) (xy 98.676589 -268.599988) (xy 98.650286 -268.558392)
			(xy 98.630995 -268.513116) (xy 98.619218 -268.465332) (xy 98.615258 -268.416278) (xy 98.286316 -268.416278)
			(xy 98.285821 -268.440885) (xy 98.277926 -268.489462) (xy 98.262342 -268.536143) (xy 98.239471 -268.57972)
			(xy 98.209906 -268.619064) (xy 98.174413 -268.653156) (xy 98.13391 -268.681112) (xy 98.089448 -268.70221)
			(xy 98.042177 -268.715902) (xy 97.993322 -268.721834) (xy 97.944147 -268.719853) (xy 97.895928 -268.710009)
			(xy 97.849912 -268.692557) (xy 97.807291 -268.66795) (xy 97.76917 -268.636825) (xy 97.736535 -268.599988)
			(xy 97.710232 -268.558392) (xy 97.690941 -268.513116) (xy 97.679164 -268.465332) (xy 97.675204 -268.416278)
			(xy 97.38614 -268.416278) (xy 97.38614 -268.819884) (xy 97.386647 -268.830307) (xy 97.394907 -268.849448)
			(xy 97.402142 -268.856968) (xy 97.463356 -268.91488) (xy 97.483168 -268.921992) (xy 97.493582 -268.921484)
			(xy 97.511108 -268.920976) (xy 97.536364 -268.921498) (xy 97.586188 -268.929813) (xy 97.633963 -268.946216)
			(xy 97.678387 -268.970258) (xy 97.718248 -269.001284) (xy 97.752458 -269.038448) (xy 97.780086 -269.080735)
			(xy 97.800376 -269.126993) (xy 97.812776 -269.17596) (xy 97.816946 -269.226284) (xy 98.145358 -269.226284)
			(xy 98.149318 -269.17723) (xy 98.161095 -269.129446) (xy 98.180386 -269.08417) (xy 98.206689 -269.042574)
			(xy 98.239324 -269.005737) (xy 98.277445 -268.974612) (xy 98.320066 -268.950005) (xy 98.366082 -268.932553)
			(xy 98.414301 -268.922709) (xy 98.463476 -268.920728) (xy 98.512331 -268.92666) (xy 98.559602 -268.940352)
			(xy 98.604064 -268.96145) (xy 98.644567 -268.989406) (xy 98.68006 -269.023498) (xy 98.709625 -269.062842)
			(xy 98.732496 -269.106419) (xy 98.74808 -269.1531) (xy 98.755975 -269.201677) (xy 98.75647 -269.226284)
			(xy 99.085158 -269.226284) (xy 99.089118 -269.17723) (xy 99.100895 -269.129446) (xy 99.120186 -269.08417)
			(xy 99.146489 -269.042574) (xy 99.179124 -269.005737) (xy 99.217245 -268.974612) (xy 99.259866 -268.950005)
			(xy 99.305882 -268.932553) (xy 99.354101 -268.922709) (xy 99.403276 -268.920728) (xy 99.452131 -268.92666)
			(xy 99.499402 -268.940352) (xy 99.543864 -268.96145) (xy 99.584367 -268.989406) (xy 99.61986 -269.023498)
			(xy 99.649425 -269.062842) (xy 99.672296 -269.106419) (xy 99.68788 -269.1531) (xy 99.695775 -269.201677)
			(xy 99.69627 -269.226284) (xy 100.025212 -269.226284) (xy 100.029172 -269.17723) (xy 100.040949 -269.129446)
			(xy 100.06024 -269.08417) (xy 100.086543 -269.042574) (xy 100.119178 -269.005737) (xy 100.157299 -268.974612)
			(xy 100.19992 -268.950005) (xy 100.245936 -268.932553) (xy 100.294155 -268.922709) (xy 100.34333 -268.920728)
			(xy 100.392185 -268.92666) (xy 100.439456 -268.940352) (xy 100.483918 -268.96145) (xy 100.524421 -268.989406)
			(xy 100.559914 -269.023498) (xy 100.589479 -269.062842) (xy 100.61235 -269.106419) (xy 100.627934 -269.1531)
			(xy 100.635829 -269.201677) (xy 100.636324 -269.226284) (xy 100.965266 -269.226284) (xy 100.969226 -269.17723)
			(xy 100.981003 -269.129446) (xy 101.000294 -269.08417) (xy 101.026597 -269.042574) (xy 101.059232 -269.005737)
			(xy 101.097353 -268.974612) (xy 101.139974 -268.950005) (xy 101.18599 -268.932553) (xy 101.234209 -268.922709)
			(xy 101.283384 -268.920728) (xy 101.332239 -268.92666) (xy 101.37951 -268.940352) (xy 101.423972 -268.96145)
			(xy 101.464475 -268.989406) (xy 101.499968 -269.023498) (xy 101.529533 -269.062842) (xy 101.552404 -269.106419)
			(xy 101.567988 -269.1531) (xy 101.575883 -269.201677) (xy 101.576378 -269.226284) (xy 101.90532 -269.226284)
			(xy 101.90928 -269.17723) (xy 101.921057 -269.129446) (xy 101.940348 -269.08417) (xy 101.966651 -269.042574)
			(xy 101.999286 -269.005737) (xy 102.037407 -268.974612) (xy 102.080028 -268.950005) (xy 102.126044 -268.932553)
			(xy 102.174263 -268.922709) (xy 102.223438 -268.920728) (xy 102.272293 -268.92666) (xy 102.319564 -268.940352)
			(xy 102.364026 -268.96145) (xy 102.404529 -268.989406) (xy 102.440022 -269.023498) (xy 102.469587 -269.062842)
			(xy 102.492458 -269.106419) (xy 102.508042 -269.1531) (xy 102.515937 -269.201677) (xy 102.516432 -269.226284)
			(xy 102.845374 -269.226284) (xy 102.849334 -269.17723) (xy 102.861111 -269.129446) (xy 102.880402 -269.08417)
			(xy 102.906705 -269.042574) (xy 102.93934 -269.005737) (xy 102.977461 -268.974612) (xy 103.020082 -268.950005)
			(xy 103.066098 -268.932553) (xy 103.114317 -268.922709) (xy 103.163492 -268.920728) (xy 103.212347 -268.92666)
			(xy 103.259618 -268.940352) (xy 103.30408 -268.96145) (xy 103.344583 -268.989406) (xy 103.380076 -269.023498)
			(xy 103.409641 -269.062842) (xy 103.432512 -269.106419) (xy 103.448096 -269.1531) (xy 103.455991 -269.201677)
			(xy 103.456486 -269.226284) (xy 103.785174 -269.226284) (xy 103.789134 -269.17723) (xy 103.800911 -269.129446)
			(xy 103.820202 -269.08417) (xy 103.846505 -269.042574) (xy 103.87914 -269.005737) (xy 103.917261 -268.974612)
			(xy 103.959882 -268.950005) (xy 104.005898 -268.932553) (xy 104.054117 -268.922709) (xy 104.103292 -268.920728)
			(xy 104.152147 -268.92666) (xy 104.199418 -268.940352) (xy 104.24388 -268.96145) (xy 104.284383 -268.989406)
			(xy 104.319876 -269.023498) (xy 104.349441 -269.062842) (xy 104.372312 -269.106419) (xy 104.387896 -269.1531)
			(xy 104.395791 -269.201677) (xy 104.396286 -269.226284) (xy 104.725228 -269.226284) (xy 104.729188 -269.17723)
			(xy 104.740965 -269.129446) (xy 104.760256 -269.08417) (xy 104.786559 -269.042574) (xy 104.819194 -269.005737)
			(xy 104.857315 -268.974612) (xy 104.899936 -268.950005) (xy 104.945952 -268.932553) (xy 104.994171 -268.922709)
			(xy 105.043346 -268.920728) (xy 105.092201 -268.92666) (xy 105.139472 -268.940352) (xy 105.183934 -268.96145)
			(xy 105.224437 -268.989406) (xy 105.25993 -269.023498) (xy 105.289495 -269.062842) (xy 105.312366 -269.106419)
			(xy 105.32795 -269.1531) (xy 105.335845 -269.201677) (xy 105.33634 -269.226284) (xy 105.665282 -269.226284)
			(xy 105.669242 -269.17723) (xy 105.681019 -269.129446) (xy 105.70031 -269.08417) (xy 105.726613 -269.042574)
			(xy 105.759248 -269.005737) (xy 105.797369 -268.974612) (xy 105.83999 -268.950005) (xy 105.886006 -268.932553)
			(xy 105.934225 -268.922709) (xy 105.9834 -268.920728) (xy 106.032255 -268.92666) (xy 106.079526 -268.940352)
			(xy 106.123988 -268.96145) (xy 106.164491 -268.989406) (xy 106.199984 -269.023498) (xy 106.229549 -269.062842)
			(xy 106.25242 -269.106419) (xy 106.268004 -269.1531) (xy 106.275899 -269.201677) (xy 106.276394 -269.226284)
			(xy 106.605336 -269.226284) (xy 106.609296 -269.17723) (xy 106.621073 -269.129446) (xy 106.640364 -269.08417)
			(xy 106.666667 -269.042574) (xy 106.699302 -269.005737) (xy 106.737423 -268.974612) (xy 106.780044 -268.950005)
			(xy 106.82606 -268.932553) (xy 106.874279 -268.922709) (xy 106.923454 -268.920728) (xy 106.972309 -268.92666)
			(xy 107.01958 -268.940352) (xy 107.064042 -268.96145) (xy 107.104545 -268.989406) (xy 107.140038 -269.023498)
			(xy 107.169603 -269.062842) (xy 107.192474 -269.106419) (xy 107.208058 -269.1531) (xy 107.215953 -269.201677)
			(xy 107.216448 -269.226284) (xy 107.545136 -269.226284) (xy 107.549096 -269.17723) (xy 107.560873 -269.129446)
			(xy 107.580164 -269.08417) (xy 107.606467 -269.042574) (xy 107.639102 -269.005737) (xy 107.677223 -268.974612)
			(xy 107.719844 -268.950005) (xy 107.76586 -268.932553) (xy 107.814079 -268.922709) (xy 107.863254 -268.920728)
			(xy 107.912109 -268.92666) (xy 107.95938 -268.940352) (xy 108.003842 -268.96145) (xy 108.044345 -268.989406)
			(xy 108.079838 -269.023498) (xy 108.109403 -269.062842) (xy 108.132274 -269.106419) (xy 108.147858 -269.1531)
			(xy 108.155753 -269.201677) (xy 108.156248 -269.226284) (xy 108.48519 -269.226284) (xy 108.48915 -269.17723)
			(xy 108.500927 -269.129446) (xy 108.520218 -269.08417) (xy 108.546521 -269.042574) (xy 108.579156 -269.005737)
			(xy 108.617277 -268.974612) (xy 108.659898 -268.950005) (xy 108.705914 -268.932553) (xy 108.754133 -268.922709)
			(xy 108.803308 -268.920728) (xy 108.852163 -268.92666) (xy 108.899434 -268.940352) (xy 108.943896 -268.96145)
			(xy 108.984399 -268.989406) (xy 109.019892 -269.023498) (xy 109.049457 -269.062842) (xy 109.072328 -269.106419)
			(xy 109.087912 -269.1531) (xy 109.095807 -269.201677) (xy 109.096302 -269.226284) (xy 109.425244 -269.226284)
			(xy 109.429204 -269.17723) (xy 109.440981 -269.129446) (xy 109.460272 -269.08417) (xy 109.486575 -269.042574)
			(xy 109.51921 -269.005737) (xy 109.557331 -268.974612) (xy 109.599952 -268.950005) (xy 109.645968 -268.932553)
			(xy 109.694187 -268.922709) (xy 109.743362 -268.920728) (xy 109.792217 -268.92666) (xy 109.839488 -268.940352)
			(xy 109.88395 -268.96145) (xy 109.924453 -268.989406) (xy 109.959946 -269.023498) (xy 109.989511 -269.062842)
			(xy 110.012382 -269.106419) (xy 110.027966 -269.1531) (xy 110.035861 -269.201677) (xy 110.036356 -269.226284)
			(xy 110.365298 -269.226284) (xy 110.369258 -269.17723) (xy 110.381035 -269.129446) (xy 110.400326 -269.08417)
			(xy 110.426629 -269.042574) (xy 110.459264 -269.005737) (xy 110.497385 -268.974612) (xy 110.540006 -268.950005)
			(xy 110.586022 -268.932553) (xy 110.634241 -268.922709) (xy 110.683416 -268.920728) (xy 110.732271 -268.92666)
			(xy 110.779542 -268.940352) (xy 110.824004 -268.96145) (xy 110.864507 -268.989406) (xy 110.9 -269.023498)
			(xy 110.929565 -269.062842) (xy 110.952436 -269.106419) (xy 110.96802 -269.1531) (xy 110.975915 -269.201677)
			(xy 110.97641 -269.226284) (xy 113.178856 -269.226284) (xy 113.182816 -269.17723) (xy 113.194593 -269.129446)
			(xy 113.213884 -269.08417) (xy 113.240187 -269.042574) (xy 113.272822 -269.005737) (xy 113.310943 -268.974612)
			(xy 113.353564 -268.950005) (xy 113.39958 -268.932553) (xy 113.447799 -268.922709) (xy 113.496974 -268.920728)
			(xy 113.545829 -268.92666) (xy 113.5931 -268.940352) (xy 113.637562 -268.96145) (xy 113.678065 -268.989406)
			(xy 113.713558 -269.023498) (xy 113.743123 -269.062842) (xy 113.765994 -269.106419) (xy 113.781578 -269.1531)
			(xy 113.789473 -269.201677) (xy 113.789968 -269.226284) (xy 114.11891 -269.226284) (xy 114.12287 -269.17723)
			(xy 114.134647 -269.129446) (xy 114.153938 -269.08417) (xy 114.180241 -269.042574) (xy 114.212876 -269.005737)
			(xy 114.250997 -268.974612) (xy 114.293618 -268.950005) (xy 114.339634 -268.932553) (xy 114.387853 -268.922709)
			(xy 114.437028 -268.920728) (xy 114.485883 -268.92666) (xy 114.533154 -268.940352) (xy 114.577616 -268.96145)
			(xy 114.618119 -268.989406) (xy 114.653612 -269.023498) (xy 114.683177 -269.062842) (xy 114.706048 -269.106419)
			(xy 114.721632 -269.1531) (xy 114.729527 -269.201677) (xy 114.730022 -269.226284) (xy 115.058964 -269.226284)
			(xy 115.062924 -269.17723) (xy 115.074701 -269.129446) (xy 115.093992 -269.08417) (xy 115.120295 -269.042574)
			(xy 115.15293 -269.005737) (xy 115.191051 -268.974612) (xy 115.233672 -268.950005) (xy 115.279688 -268.932553)
			(xy 115.327907 -268.922709) (xy 115.377082 -268.920728) (xy 115.425937 -268.92666) (xy 115.473208 -268.940352)
			(xy 115.51767 -268.96145) (xy 115.558173 -268.989406) (xy 115.593666 -269.023498) (xy 115.623231 -269.062842)
			(xy 115.646102 -269.106419) (xy 115.661686 -269.1531) (xy 115.669581 -269.201677) (xy 115.670076 -269.226284)
			(xy 115.999018 -269.226284) (xy 116.002978 -269.17723) (xy 116.014755 -269.129446) (xy 116.034046 -269.08417)
			(xy 116.060349 -269.042574) (xy 116.092984 -269.005737) (xy 116.131105 -268.974612) (xy 116.173726 -268.950005)
			(xy 116.219742 -268.932553) (xy 116.267961 -268.922709) (xy 116.317136 -268.920728) (xy 116.365991 -268.92666)
			(xy 116.413262 -268.940352) (xy 116.457724 -268.96145) (xy 116.498227 -268.989406) (xy 116.53372 -269.023498)
			(xy 116.563285 -269.062842) (xy 116.586156 -269.106419) (xy 116.60174 -269.1531) (xy 116.609635 -269.201677)
			(xy 116.61013 -269.226284) (xy 116.938818 -269.226284) (xy 116.942778 -269.17723) (xy 116.954555 -269.129446)
			(xy 116.973846 -269.08417) (xy 117.000149 -269.042574) (xy 117.032784 -269.005737) (xy 117.070905 -268.974612)
			(xy 117.113526 -268.950005) (xy 117.159542 -268.932553) (xy 117.207761 -268.922709) (xy 117.256936 -268.920728)
			(xy 117.305791 -268.92666) (xy 117.353062 -268.940352) (xy 117.397524 -268.96145) (xy 117.438027 -268.989406)
			(xy 117.47352 -269.023498) (xy 117.503085 -269.062842) (xy 117.525956 -269.106419) (xy 117.54154 -269.1531)
			(xy 117.549435 -269.201677) (xy 117.54993 -269.226284) (xy 117.878872 -269.226284) (xy 117.882832 -269.17723)
			(xy 117.894609 -269.129446) (xy 117.9139 -269.08417) (xy 117.940203 -269.042574) (xy 117.972838 -269.005737)
			(xy 118.010959 -268.974612) (xy 118.05358 -268.950005) (xy 118.099596 -268.932553) (xy 118.147815 -268.922709)
			(xy 118.19699 -268.920728) (xy 118.245845 -268.92666) (xy 118.293116 -268.940352) (xy 118.337578 -268.96145)
			(xy 118.378081 -268.989406) (xy 118.413574 -269.023498) (xy 118.443139 -269.062842) (xy 118.46601 -269.106419)
			(xy 118.481594 -269.1531) (xy 118.489489 -269.201677) (xy 118.489984 -269.226284) (xy 118.818926 -269.226284)
			(xy 118.822886 -269.17723) (xy 118.834663 -269.129446) (xy 118.853954 -269.08417) (xy 118.880257 -269.042574)
			(xy 118.912892 -269.005737) (xy 118.951013 -268.974612) (xy 118.993634 -268.950005) (xy 119.03965 -268.932553)
			(xy 119.087869 -268.922709) (xy 119.137044 -268.920728) (xy 119.185899 -268.92666) (xy 119.23317 -268.940352)
			(xy 119.277632 -268.96145) (xy 119.318135 -268.989406) (xy 119.353628 -269.023498) (xy 119.383193 -269.062842)
			(xy 119.406064 -269.106419) (xy 119.421648 -269.1531) (xy 119.429543 -269.201677) (xy 119.430038 -269.226284)
			(xy 119.75898 -269.226284) (xy 119.76294 -269.17723) (xy 119.774717 -269.129446) (xy 119.794008 -269.08417)
			(xy 119.820311 -269.042574) (xy 119.852946 -269.005737) (xy 119.891067 -268.974612) (xy 119.933688 -268.950005)
			(xy 119.979704 -268.932553) (xy 120.027923 -268.922709) (xy 120.077098 -268.920728) (xy 120.125953 -268.92666)
			(xy 120.173224 -268.940352) (xy 120.217686 -268.96145) (xy 120.258189 -268.989406) (xy 120.293682 -269.023498)
			(xy 120.323247 -269.062842) (xy 120.346118 -269.106419) (xy 120.361702 -269.1531) (xy 120.369597 -269.201677)
			(xy 120.370092 -269.226284) (xy 120.699034 -269.226284) (xy 120.702994 -269.17723) (xy 120.714771 -269.129446)
			(xy 120.734062 -269.08417) (xy 120.760365 -269.042574) (xy 120.793 -269.005737) (xy 120.831121 -268.974612)
			(xy 120.873742 -268.950005) (xy 120.919758 -268.932553) (xy 120.967977 -268.922709) (xy 121.017152 -268.920728)
			(xy 121.066007 -268.92666) (xy 121.113278 -268.940352) (xy 121.15774 -268.96145) (xy 121.198243 -268.989406)
			(xy 121.233736 -269.023498) (xy 121.263301 -269.062842) (xy 121.286172 -269.106419) (xy 121.301756 -269.1531)
			(xy 121.309651 -269.201677) (xy 121.310146 -269.226284) (xy 121.638834 -269.226284) (xy 121.642794 -269.17723)
			(xy 121.654571 -269.129446) (xy 121.673862 -269.08417) (xy 121.700165 -269.042574) (xy 121.7328 -269.005737)
			(xy 121.770921 -268.974612) (xy 121.813542 -268.950005) (xy 121.859558 -268.932553) (xy 121.907777 -268.922709)
			(xy 121.956952 -268.920728) (xy 122.005807 -268.92666) (xy 122.053078 -268.940352) (xy 122.09754 -268.96145)
			(xy 122.138043 -268.989406) (xy 122.173536 -269.023498) (xy 122.203101 -269.062842) (xy 122.225972 -269.106419)
			(xy 122.241556 -269.1531) (xy 122.249451 -269.201677) (xy 122.249946 -269.226284) (xy 122.578888 -269.226284)
			(xy 122.582848 -269.17723) (xy 122.594625 -269.129446) (xy 122.613916 -269.08417) (xy 122.640219 -269.042574)
			(xy 122.672854 -269.005737) (xy 122.710975 -268.974612) (xy 122.753596 -268.950005) (xy 122.799612 -268.932553)
			(xy 122.847831 -268.922709) (xy 122.897006 -268.920728) (xy 122.945861 -268.92666) (xy 122.993132 -268.940352)
			(xy 123.037594 -268.96145) (xy 123.078097 -268.989406) (xy 123.11359 -269.023498) (xy 123.143155 -269.062842)
			(xy 123.166026 -269.106419) (xy 123.18161 -269.1531) (xy 123.189505 -269.201677) (xy 123.19 -269.226284)
			(xy 123.518942 -269.226284) (xy 123.522902 -269.17723) (xy 123.534679 -269.129446) (xy 123.55397 -269.08417)
			(xy 123.580273 -269.042574) (xy 123.612908 -269.005737) (xy 123.651029 -268.974612) (xy 123.69365 -268.950005)
			(xy 123.739666 -268.932553) (xy 123.787885 -268.922709) (xy 123.83706 -268.920728) (xy 123.885915 -268.92666)
			(xy 123.933186 -268.940352) (xy 123.977648 -268.96145) (xy 124.018151 -268.989406) (xy 124.053644 -269.023498)
			(xy 124.083209 -269.062842) (xy 124.10608 -269.106419) (xy 124.121664 -269.1531) (xy 124.129559 -269.201677)
			(xy 124.130054 -269.226284) (xy 124.458996 -269.226284) (xy 124.462956 -269.17723) (xy 124.474733 -269.129446)
			(xy 124.494024 -269.08417) (xy 124.520327 -269.042574) (xy 124.552962 -269.005737) (xy 124.591083 -268.974612)
			(xy 124.633704 -268.950005) (xy 124.67972 -268.932553) (xy 124.727939 -268.922709) (xy 124.777114 -268.920728)
			(xy 124.825969 -268.92666) (xy 124.87324 -268.940352) (xy 124.917702 -268.96145) (xy 124.958205 -268.989406)
			(xy 124.993698 -269.023498) (xy 125.023263 -269.062842) (xy 125.046134 -269.106419) (xy 125.061718 -269.1531)
			(xy 125.069613 -269.201677) (xy 125.070108 -269.226284) (xy 125.39905 -269.226284) (xy 125.40301 -269.17723)
			(xy 125.414787 -269.129446) (xy 125.434078 -269.08417) (xy 125.460381 -269.042574) (xy 125.493016 -269.005737)
			(xy 125.531137 -268.974612) (xy 125.573758 -268.950005) (xy 125.619774 -268.932553) (xy 125.667993 -268.922709)
			(xy 125.717168 -268.920728) (xy 125.766023 -268.92666) (xy 125.813294 -268.940352) (xy 125.857756 -268.96145)
			(xy 125.898259 -268.989406) (xy 125.933752 -269.023498) (xy 125.963317 -269.062842) (xy 125.986188 -269.106419)
			(xy 126.001772 -269.1531) (xy 126.009667 -269.201677) (xy 126.010162 -269.226284) (xy 126.33885 -269.226284)
			(xy 126.34281 -269.17723) (xy 126.354587 -269.129446) (xy 126.373878 -269.08417) (xy 126.400181 -269.042574)
			(xy 126.432816 -269.005737) (xy 126.470937 -268.974612) (xy 126.513558 -268.950005) (xy 126.559574 -268.932553)
			(xy 126.607793 -268.922709) (xy 126.656968 -268.920728) (xy 126.705823 -268.92666) (xy 126.753094 -268.940352)
			(xy 126.797556 -268.96145) (xy 126.838059 -268.989406) (xy 126.873552 -269.023498) (xy 126.903117 -269.062842)
			(xy 126.925988 -269.106419) (xy 126.941572 -269.1531) (xy 126.949467 -269.201677) (xy 126.949962 -269.226284)
			(xy 127.278904 -269.226284) (xy 127.282864 -269.17723) (xy 127.294641 -269.129446) (xy 127.313932 -269.08417)
			(xy 127.340235 -269.042574) (xy 127.37287 -269.005737) (xy 127.410991 -268.974612) (xy 127.453612 -268.950005)
			(xy 127.499628 -268.932553) (xy 127.547847 -268.922709) (xy 127.597022 -268.920728) (xy 127.645877 -268.92666)
			(xy 127.693148 -268.940352) (xy 127.73761 -268.96145) (xy 127.778113 -268.989406) (xy 127.813606 -269.023498)
			(xy 127.843171 -269.062842) (xy 127.866042 -269.106419) (xy 127.881626 -269.1531) (xy 127.889521 -269.201677)
			(xy 127.890016 -269.226284) (xy 128.218958 -269.226284) (xy 128.222918 -269.17723) (xy 128.234695 -269.129446)
			(xy 128.253986 -269.08417) (xy 128.280289 -269.042574) (xy 128.312924 -269.005737) (xy 128.351045 -268.974612)
			(xy 128.393666 -268.950005) (xy 128.439682 -268.932553) (xy 128.487901 -268.922709) (xy 128.537076 -268.920728)
			(xy 128.585931 -268.92666) (xy 128.633202 -268.940352) (xy 128.677664 -268.96145) (xy 128.718167 -268.989406)
			(xy 128.75366 -269.023498) (xy 128.783225 -269.062842) (xy 128.806096 -269.106419) (xy 128.82168 -269.1531)
			(xy 128.829575 -269.201677) (xy 128.83007 -269.226284) (xy 129.148581 -269.226284) (xy 129.152676 -269.175556)
			(xy 129.164855 -269.126142) (xy 129.184803 -269.079322) (xy 129.212004 -269.036308) (xy 129.245752 -268.998214)
			(xy 129.285174 -268.966027) (xy 129.329248 -268.940581) (xy 129.376834 -268.922534) (xy 129.426698 -268.912354)
			(xy 129.47755 -268.910305) (xy 129.528071 -268.916439) (xy 129.576955 -268.930599) (xy 129.622934 -268.952416)
			(xy 129.664818 -268.981326) (xy 129.701522 -269.016581) (xy 129.732095 -269.057267) (xy 129.755746 -269.10233)
			(xy 129.771862 -269.150604) (xy 129.780026 -269.200838) (xy 129.780538 -269.226284) (xy 130.099066 -269.226284)
			(xy 130.103026 -269.17723) (xy 130.114803 -269.129446) (xy 130.134094 -269.08417) (xy 130.160397 -269.042574)
			(xy 130.193032 -269.005737) (xy 130.231153 -268.974612) (xy 130.273774 -268.950005) (xy 130.31979 -268.932553)
			(xy 130.368009 -268.922709) (xy 130.417184 -268.920728) (xy 130.466039 -268.92666) (xy 130.51331 -268.940352)
			(xy 130.557772 -268.96145) (xy 130.598275 -268.989406) (xy 130.633768 -269.023498) (xy 130.663333 -269.062842)
			(xy 130.686204 -269.106419) (xy 130.701788 -269.1531) (xy 130.709683 -269.201677) (xy 130.710178 -269.226284)
			(xy 131.038866 -269.226284) (xy 131.042826 -269.17723) (xy 131.054603 -269.129446) (xy 131.073894 -269.08417)
			(xy 131.100197 -269.042574) (xy 131.132832 -269.005737) (xy 131.170953 -268.974612) (xy 131.213574 -268.950005)
			(xy 131.25959 -268.932553) (xy 131.307809 -268.922709) (xy 131.356984 -268.920728) (xy 131.405839 -268.92666)
			(xy 131.45311 -268.940352) (xy 131.497572 -268.96145) (xy 131.538075 -268.989406) (xy 131.573568 -269.023498)
			(xy 131.603133 -269.062842) (xy 131.626004 -269.106419) (xy 131.641588 -269.1531) (xy 131.649483 -269.201677)
			(xy 131.649978 -269.226284) (xy 131.97892 -269.226284) (xy 131.98288 -269.17723) (xy 131.994657 -269.129446)
			(xy 132.013948 -269.08417) (xy 132.040251 -269.042574) (xy 132.072886 -269.005737) (xy 132.111007 -268.974612)
			(xy 132.153628 -268.950005) (xy 132.199644 -268.932553) (xy 132.247863 -268.922709) (xy 132.297038 -268.920728)
			(xy 132.345893 -268.92666) (xy 132.393164 -268.940352) (xy 132.437626 -268.96145) (xy 132.478129 -268.989406)
			(xy 132.513622 -269.023498) (xy 132.543187 -269.062842) (xy 132.566058 -269.106419) (xy 132.581642 -269.1531)
			(xy 132.589537 -269.201677) (xy 132.590032 -269.226284) (xy 132.908543 -269.226284) (xy 132.912638 -269.175556)
			(xy 132.924817 -269.126142) (xy 132.944765 -269.079322) (xy 132.971966 -269.036308) (xy 133.005714 -268.998214)
			(xy 133.045136 -268.966027) (xy 133.08921 -268.940581) (xy 133.136796 -268.922534) (xy 133.18666 -268.912354)
			(xy 133.237512 -268.910305) (xy 133.288033 -268.916439) (xy 133.336917 -268.930599) (xy 133.382896 -268.952416)
			(xy 133.42478 -268.981326) (xy 133.461484 -269.016581) (xy 133.492057 -269.057267) (xy 133.515708 -269.10233)
			(xy 133.531824 -269.150604) (xy 133.539988 -269.200838) (xy 133.5405 -269.226284) (xy 133.859028 -269.226284)
			(xy 133.862988 -269.17723) (xy 133.874765 -269.129446) (xy 133.894056 -269.08417) (xy 133.920359 -269.042574)
			(xy 133.952994 -269.005737) (xy 133.991115 -268.974612) (xy 134.033736 -268.950005) (xy 134.079752 -268.932553)
			(xy 134.127971 -268.922709) (xy 134.177146 -268.920728) (xy 134.226001 -268.92666) (xy 134.273272 -268.940352)
			(xy 134.317734 -268.96145) (xy 134.358237 -268.989406) (xy 134.39373 -269.023498) (xy 134.423295 -269.062842)
			(xy 134.446166 -269.106419) (xy 134.46175 -269.1531) (xy 134.469645 -269.201677) (xy 134.47014 -269.226284)
			(xy 134.798828 -269.226284) (xy 134.802788 -269.17723) (xy 134.814565 -269.129446) (xy 134.833856 -269.08417)
			(xy 134.860159 -269.042574) (xy 134.892794 -269.005737) (xy 134.930915 -268.974612) (xy 134.973536 -268.950005)
			(xy 135.019552 -268.932553) (xy 135.067771 -268.922709) (xy 135.116946 -268.920728) (xy 135.165801 -268.92666)
			(xy 135.213072 -268.940352) (xy 135.257534 -268.96145) (xy 135.298037 -268.989406) (xy 135.33353 -269.023498)
			(xy 135.363095 -269.062842) (xy 135.385966 -269.106419) (xy 135.40155 -269.1531) (xy 135.409445 -269.201677)
			(xy 135.40994 -269.226284) (xy 135.738882 -269.226284) (xy 135.742842 -269.17723) (xy 135.754619 -269.129446)
			(xy 135.77391 -269.08417) (xy 135.800213 -269.042574) (xy 135.832848 -269.005737) (xy 135.870969 -268.974612)
			(xy 135.91359 -268.950005) (xy 135.959606 -268.932553) (xy 136.007825 -268.922709) (xy 136.057 -268.920728)
			(xy 136.105855 -268.92666) (xy 136.153126 -268.940352) (xy 136.197588 -268.96145) (xy 136.238091 -268.989406)
			(xy 136.273584 -269.023498) (xy 136.303149 -269.062842) (xy 136.32602 -269.106419) (xy 136.341604 -269.1531)
			(xy 136.349499 -269.201677) (xy 136.349994 -269.226284) (xy 136.678936 -269.226284) (xy 136.682896 -269.17723)
			(xy 136.694673 -269.129446) (xy 136.713964 -269.08417) (xy 136.740267 -269.042574) (xy 136.772902 -269.005737)
			(xy 136.811023 -268.974612) (xy 136.853644 -268.950005) (xy 136.89966 -268.932553) (xy 136.947879 -268.922709)
			(xy 136.997054 -268.920728) (xy 137.045909 -268.92666) (xy 137.09318 -268.940352) (xy 137.137642 -268.96145)
			(xy 137.178145 -268.989406) (xy 137.213638 -269.023498) (xy 137.243203 -269.062842) (xy 137.266074 -269.106419)
			(xy 137.281658 -269.1531) (xy 137.289553 -269.201677) (xy 137.290048 -269.226284) (xy 137.61899 -269.226284)
			(xy 137.62295 -269.17723) (xy 137.634727 -269.129446) (xy 137.654018 -269.08417) (xy 137.680321 -269.042574)
			(xy 137.712956 -269.005737) (xy 137.751077 -268.974612) (xy 137.793698 -268.950005) (xy 137.839714 -268.932553)
			(xy 137.887933 -268.922709) (xy 137.937108 -268.920728) (xy 137.985963 -268.92666) (xy 138.033234 -268.940352)
			(xy 138.077696 -268.96145) (xy 138.118199 -268.989406) (xy 138.153692 -269.023498) (xy 138.183257 -269.062842)
			(xy 138.206128 -269.106419) (xy 138.221712 -269.1531) (xy 138.229607 -269.201677) (xy 138.230102 -269.226284)
			(xy 138.559044 -269.226284) (xy 138.563004 -269.17723) (xy 138.574781 -269.129446) (xy 138.594072 -269.08417)
			(xy 138.620375 -269.042574) (xy 138.65301 -269.005737) (xy 138.691131 -268.974612) (xy 138.733752 -268.950005)
			(xy 138.779768 -268.932553) (xy 138.827987 -268.922709) (xy 138.877162 -268.920728) (xy 138.926017 -268.92666)
			(xy 138.973288 -268.940352) (xy 139.01775 -268.96145) (xy 139.058253 -268.989406) (xy 139.093746 -269.023498)
			(xy 139.123311 -269.062842) (xy 139.146182 -269.106419) (xy 139.161766 -269.1531) (xy 139.169661 -269.201677)
			(xy 139.170156 -269.226284) (xy 139.498844 -269.226284) (xy 139.502804 -269.17723) (xy 139.514581 -269.129446)
			(xy 139.533872 -269.08417) (xy 139.560175 -269.042574) (xy 139.59281 -269.005737) (xy 139.630931 -268.974612)
			(xy 139.673552 -268.950005) (xy 139.719568 -268.932553) (xy 139.767787 -268.922709) (xy 139.816962 -268.920728)
			(xy 139.865817 -268.92666) (xy 139.913088 -268.940352) (xy 139.95755 -268.96145) (xy 139.998053 -268.989406)
			(xy 140.033546 -269.023498) (xy 140.063111 -269.062842) (xy 140.085982 -269.106419) (xy 140.101566 -269.1531)
			(xy 140.109461 -269.201677) (xy 140.109956 -269.226284) (xy 140.109461 -269.250891) (xy 140.101566 -269.299468)
			(xy 140.085982 -269.346149) (xy 140.063111 -269.389726) (xy 140.033546 -269.42907) (xy 139.998053 -269.463162)
			(xy 139.95755 -269.491118) (xy 139.913088 -269.512216) (xy 139.865817 -269.525908) (xy 139.816962 -269.53184)
			(xy 139.767787 -269.529859) (xy 139.719568 -269.520015) (xy 139.673552 -269.502563) (xy 139.630931 -269.477956)
			(xy 139.59281 -269.446831) (xy 139.560175 -269.409994) (xy 139.533872 -269.368398) (xy 139.514581 -269.323122)
			(xy 139.502804 -269.275338) (xy 139.498844 -269.226284) (xy 139.170156 -269.226284) (xy 139.169661 -269.250891)
			(xy 139.161766 -269.299468) (xy 139.146182 -269.346149) (xy 139.123311 -269.389726) (xy 139.093746 -269.42907)
			(xy 139.058253 -269.463162) (xy 139.01775 -269.491118) (xy 138.973288 -269.512216) (xy 138.926017 -269.525908)
			(xy 138.877162 -269.53184) (xy 138.827987 -269.529859) (xy 138.779768 -269.520015) (xy 138.733752 -269.502563)
			(xy 138.691131 -269.477956) (xy 138.65301 -269.446831) (xy 138.620375 -269.409994) (xy 138.594072 -269.368398)
			(xy 138.574781 -269.323122) (xy 138.563004 -269.275338) (xy 138.559044 -269.226284) (xy 138.230102 -269.226284)
			(xy 138.229607 -269.250891) (xy 138.221712 -269.299468) (xy 138.206128 -269.346149) (xy 138.183257 -269.389726)
			(xy 138.153692 -269.42907) (xy 138.118199 -269.463162) (xy 138.077696 -269.491118) (xy 138.033234 -269.512216)
			(xy 137.985963 -269.525908) (xy 137.937108 -269.53184) (xy 137.887933 -269.529859) (xy 137.839714 -269.520015)
			(xy 137.793698 -269.502563) (xy 137.751077 -269.477956) (xy 137.712956 -269.446831) (xy 137.680321 -269.409994)
			(xy 137.654018 -269.368398) (xy 137.634727 -269.323122) (xy 137.62295 -269.275338) (xy 137.61899 -269.226284)
			(xy 137.290048 -269.226284) (xy 137.289553 -269.250891) (xy 137.281658 -269.299468) (xy 137.266074 -269.346149)
			(xy 137.243203 -269.389726) (xy 137.213638 -269.42907) (xy 137.178145 -269.463162) (xy 137.137642 -269.491118)
			(xy 137.09318 -269.512216) (xy 137.045909 -269.525908) (xy 136.997054 -269.53184) (xy 136.947879 -269.529859)
			(xy 136.89966 -269.520015) (xy 136.853644 -269.502563) (xy 136.811023 -269.477956) (xy 136.772902 -269.446831)
			(xy 136.740267 -269.409994) (xy 136.713964 -269.368398) (xy 136.694673 -269.323122) (xy 136.682896 -269.275338)
			(xy 136.678936 -269.226284) (xy 136.349994 -269.226284) (xy 136.349499 -269.250891) (xy 136.341604 -269.299468)
			(xy 136.32602 -269.346149) (xy 136.303149 -269.389726) (xy 136.273584 -269.42907) (xy 136.238091 -269.463162)
			(xy 136.197588 -269.491118) (xy 136.153126 -269.512216) (xy 136.105855 -269.525908) (xy 136.057 -269.53184)
			(xy 136.007825 -269.529859) (xy 135.959606 -269.520015) (xy 135.91359 -269.502563) (xy 135.870969 -269.477956)
			(xy 135.832848 -269.446831) (xy 135.800213 -269.409994) (xy 135.77391 -269.368398) (xy 135.754619 -269.323122)
			(xy 135.742842 -269.275338) (xy 135.738882 -269.226284) (xy 135.40994 -269.226284) (xy 135.409445 -269.250891)
			(xy 135.40155 -269.299468) (xy 135.385966 -269.346149) (xy 135.363095 -269.389726) (xy 135.33353 -269.42907)
			(xy 135.298037 -269.463162) (xy 135.257534 -269.491118) (xy 135.213072 -269.512216) (xy 135.165801 -269.525908)
			(xy 135.116946 -269.53184) (xy 135.067771 -269.529859) (xy 135.019552 -269.520015) (xy 134.973536 -269.502563)
			(xy 134.930915 -269.477956) (xy 134.892794 -269.446831) (xy 134.860159 -269.409994) (xy 134.833856 -269.368398)
			(xy 134.814565 -269.323122) (xy 134.802788 -269.275338) (xy 134.798828 -269.226284) (xy 134.47014 -269.226284)
			(xy 134.469645 -269.250891) (xy 134.46175 -269.299468) (xy 134.446166 -269.346149) (xy 134.423295 -269.389726)
			(xy 134.39373 -269.42907) (xy 134.358237 -269.463162) (xy 134.317734 -269.491118) (xy 134.273272 -269.512216)
			(xy 134.226001 -269.525908) (xy 134.177146 -269.53184) (xy 134.127971 -269.529859) (xy 134.079752 -269.520015)
			(xy 134.033736 -269.502563) (xy 133.991115 -269.477956) (xy 133.952994 -269.446831) (xy 133.920359 -269.409994)
			(xy 133.894056 -269.368398) (xy 133.874765 -269.323122) (xy 133.862988 -269.275338) (xy 133.859028 -269.226284)
			(xy 133.5405 -269.226284) (xy 133.539988 -269.25173) (xy 133.531824 -269.301964) (xy 133.515708 -269.350238)
			(xy 133.492057 -269.395301) (xy 133.461484 -269.435987) (xy 133.42478 -269.471242) (xy 133.382896 -269.500152)
			(xy 133.336917 -269.521969) (xy 133.288033 -269.536129) (xy 133.237512 -269.542263) (xy 133.18666 -269.540214)
			(xy 133.136796 -269.530034) (xy 133.08921 -269.511987) (xy 133.045136 -269.486541) (xy 133.005714 -269.454354)
			(xy 132.971966 -269.41626) (xy 132.944765 -269.373246) (xy 132.924817 -269.326426) (xy 132.912638 -269.277012)
			(xy 132.908543 -269.226284) (xy 132.590032 -269.226284) (xy 132.589537 -269.250891) (xy 132.581642 -269.299468)
			(xy 132.566058 -269.346149) (xy 132.543187 -269.389726) (xy 132.513622 -269.42907) (xy 132.478129 -269.463162)
			(xy 132.437626 -269.491118) (xy 132.393164 -269.512216) (xy 132.345893 -269.525908) (xy 132.297038 -269.53184)
			(xy 132.247863 -269.529859) (xy 132.199644 -269.520015) (xy 132.153628 -269.502563) (xy 132.111007 -269.477956)
			(xy 132.072886 -269.446831) (xy 132.040251 -269.409994) (xy 132.013948 -269.368398) (xy 131.994657 -269.323122)
			(xy 131.98288 -269.275338) (xy 131.97892 -269.226284) (xy 131.649978 -269.226284) (xy 131.649483 -269.250891)
			(xy 131.641588 -269.299468) (xy 131.626004 -269.346149) (xy 131.603133 -269.389726) (xy 131.573568 -269.42907)
			(xy 131.538075 -269.463162) (xy 131.497572 -269.491118) (xy 131.45311 -269.512216) (xy 131.405839 -269.525908)
			(xy 131.356984 -269.53184) (xy 131.307809 -269.529859) (xy 131.25959 -269.520015) (xy 131.213574 -269.502563)
			(xy 131.170953 -269.477956) (xy 131.132832 -269.446831) (xy 131.100197 -269.409994) (xy 131.073894 -269.368398)
			(xy 131.054603 -269.323122) (xy 131.042826 -269.275338) (xy 131.038866 -269.226284) (xy 130.710178 -269.226284)
			(xy 130.709683 -269.250891) (xy 130.701788 -269.299468) (xy 130.686204 -269.346149) (xy 130.663333 -269.389726)
			(xy 130.633768 -269.42907) (xy 130.598275 -269.463162) (xy 130.557772 -269.491118) (xy 130.51331 -269.512216)
			(xy 130.466039 -269.525908) (xy 130.417184 -269.53184) (xy 130.368009 -269.529859) (xy 130.31979 -269.520015)
			(xy 130.273774 -269.502563) (xy 130.231153 -269.477956) (xy 130.193032 -269.446831) (xy 130.160397 -269.409994)
			(xy 130.134094 -269.368398) (xy 130.114803 -269.323122) (xy 130.103026 -269.275338) (xy 130.099066 -269.226284)
			(xy 129.780538 -269.226284) (xy 129.780026 -269.25173) (xy 129.771862 -269.301964) (xy 129.755746 -269.350238)
			(xy 129.732095 -269.395301) (xy 129.701522 -269.435987) (xy 129.664818 -269.471242) (xy 129.622934 -269.500152)
			(xy 129.576955 -269.521969) (xy 129.528071 -269.536129) (xy 129.47755 -269.542263) (xy 129.426698 -269.540214)
			(xy 129.376834 -269.530034) (xy 129.329248 -269.511987) (xy 129.285174 -269.486541) (xy 129.245752 -269.454354)
			(xy 129.212004 -269.41626) (xy 129.184803 -269.373246) (xy 129.164855 -269.326426) (xy 129.152676 -269.277012)
			(xy 129.148581 -269.226284) (xy 128.83007 -269.226284) (xy 128.829575 -269.250891) (xy 128.82168 -269.299468)
			(xy 128.806096 -269.346149) (xy 128.783225 -269.389726) (xy 128.75366 -269.42907) (xy 128.718167 -269.463162)
			(xy 128.677664 -269.491118) (xy 128.633202 -269.512216) (xy 128.585931 -269.525908) (xy 128.537076 -269.53184)
			(xy 128.487901 -269.529859) (xy 128.439682 -269.520015) (xy 128.393666 -269.502563) (xy 128.351045 -269.477956)
			(xy 128.312924 -269.446831) (xy 128.280289 -269.409994) (xy 128.253986 -269.368398) (xy 128.234695 -269.323122)
			(xy 128.222918 -269.275338) (xy 128.218958 -269.226284) (xy 127.890016 -269.226284) (xy 127.889521 -269.250891)
			(xy 127.881626 -269.299468) (xy 127.866042 -269.346149) (xy 127.843171 -269.389726) (xy 127.813606 -269.42907)
			(xy 127.778113 -269.463162) (xy 127.73761 -269.491118) (xy 127.693148 -269.512216) (xy 127.645877 -269.525908)
			(xy 127.597022 -269.53184) (xy 127.547847 -269.529859) (xy 127.499628 -269.520015) (xy 127.453612 -269.502563)
			(xy 127.410991 -269.477956) (xy 127.37287 -269.446831) (xy 127.340235 -269.409994) (xy 127.313932 -269.368398)
			(xy 127.294641 -269.323122) (xy 127.282864 -269.275338) (xy 127.278904 -269.226284) (xy 126.949962 -269.226284)
			(xy 126.949467 -269.250891) (xy 126.941572 -269.299468) (xy 126.925988 -269.346149) (xy 126.903117 -269.389726)
			(xy 126.873552 -269.42907) (xy 126.838059 -269.463162) (xy 126.797556 -269.491118) (xy 126.753094 -269.512216)
			(xy 126.705823 -269.525908) (xy 126.656968 -269.53184) (xy 126.607793 -269.529859) (xy 126.559574 -269.520015)
			(xy 126.513558 -269.502563) (xy 126.470937 -269.477956) (xy 126.432816 -269.446831) (xy 126.400181 -269.409994)
			(xy 126.373878 -269.368398) (xy 126.354587 -269.323122) (xy 126.34281 -269.275338) (xy 126.33885 -269.226284)
			(xy 126.010162 -269.226284) (xy 126.009667 -269.250891) (xy 126.001772 -269.299468) (xy 125.986188 -269.346149)
			(xy 125.963317 -269.389726) (xy 125.933752 -269.42907) (xy 125.898259 -269.463162) (xy 125.857756 -269.491118)
			(xy 125.813294 -269.512216) (xy 125.766023 -269.525908) (xy 125.717168 -269.53184) (xy 125.667993 -269.529859)
			(xy 125.619774 -269.520015) (xy 125.573758 -269.502563) (xy 125.531137 -269.477956) (xy 125.493016 -269.446831)
			(xy 125.460381 -269.409994) (xy 125.434078 -269.368398) (xy 125.414787 -269.323122) (xy 125.40301 -269.275338)
			(xy 125.39905 -269.226284) (xy 125.070108 -269.226284) (xy 125.069613 -269.250891) (xy 125.061718 -269.299468)
			(xy 125.046134 -269.346149) (xy 125.023263 -269.389726) (xy 124.993698 -269.42907) (xy 124.958205 -269.463162)
			(xy 124.917702 -269.491118) (xy 124.87324 -269.512216) (xy 124.825969 -269.525908) (xy 124.777114 -269.53184)
			(xy 124.727939 -269.529859) (xy 124.67972 -269.520015) (xy 124.633704 -269.502563) (xy 124.591083 -269.477956)
			(xy 124.552962 -269.446831) (xy 124.520327 -269.409994) (xy 124.494024 -269.368398) (xy 124.474733 -269.323122)
			(xy 124.462956 -269.275338) (xy 124.458996 -269.226284) (xy 124.130054 -269.226284) (xy 124.129559 -269.250891)
			(xy 124.121664 -269.299468) (xy 124.10608 -269.346149) (xy 124.083209 -269.389726) (xy 124.053644 -269.42907)
			(xy 124.018151 -269.463162) (xy 123.977648 -269.491118) (xy 123.933186 -269.512216) (xy 123.885915 -269.525908)
			(xy 123.83706 -269.53184) (xy 123.787885 -269.529859) (xy 123.739666 -269.520015) (xy 123.69365 -269.502563)
			(xy 123.651029 -269.477956) (xy 123.612908 -269.446831) (xy 123.580273 -269.409994) (xy 123.55397 -269.368398)
			(xy 123.534679 -269.323122) (xy 123.522902 -269.275338) (xy 123.518942 -269.226284) (xy 123.19 -269.226284)
			(xy 123.189505 -269.250891) (xy 123.18161 -269.299468) (xy 123.166026 -269.346149) (xy 123.143155 -269.389726)
			(xy 123.11359 -269.42907) (xy 123.078097 -269.463162) (xy 123.037594 -269.491118) (xy 122.993132 -269.512216)
			(xy 122.945861 -269.525908) (xy 122.897006 -269.53184) (xy 122.847831 -269.529859) (xy 122.799612 -269.520015)
			(xy 122.753596 -269.502563) (xy 122.710975 -269.477956) (xy 122.672854 -269.446831) (xy 122.640219 -269.409994)
			(xy 122.613916 -269.368398) (xy 122.594625 -269.323122) (xy 122.582848 -269.275338) (xy 122.578888 -269.226284)
			(xy 122.249946 -269.226284) (xy 122.249451 -269.250891) (xy 122.241556 -269.299468) (xy 122.225972 -269.346149)
			(xy 122.203101 -269.389726) (xy 122.173536 -269.42907) (xy 122.138043 -269.463162) (xy 122.09754 -269.491118)
			(xy 122.053078 -269.512216) (xy 122.005807 -269.525908) (xy 121.956952 -269.53184) (xy 121.907777 -269.529859)
			(xy 121.859558 -269.520015) (xy 121.813542 -269.502563) (xy 121.770921 -269.477956) (xy 121.7328 -269.446831)
			(xy 121.700165 -269.409994) (xy 121.673862 -269.368398) (xy 121.654571 -269.323122) (xy 121.642794 -269.275338)
			(xy 121.638834 -269.226284) (xy 121.310146 -269.226284) (xy 121.309651 -269.250891) (xy 121.301756 -269.299468)
			(xy 121.286172 -269.346149) (xy 121.263301 -269.389726) (xy 121.233736 -269.42907) (xy 121.198243 -269.463162)
			(xy 121.15774 -269.491118) (xy 121.113278 -269.512216) (xy 121.066007 -269.525908) (xy 121.017152 -269.53184)
			(xy 120.967977 -269.529859) (xy 120.919758 -269.520015) (xy 120.873742 -269.502563) (xy 120.831121 -269.477956)
			(xy 120.793 -269.446831) (xy 120.760365 -269.409994) (xy 120.734062 -269.368398) (xy 120.714771 -269.323122)
			(xy 120.702994 -269.275338) (xy 120.699034 -269.226284) (xy 120.370092 -269.226284) (xy 120.369597 -269.250891)
			(xy 120.361702 -269.299468) (xy 120.346118 -269.346149) (xy 120.323247 -269.389726) (xy 120.293682 -269.42907)
			(xy 120.258189 -269.463162) (xy 120.217686 -269.491118) (xy 120.173224 -269.512216) (xy 120.125953 -269.525908)
			(xy 120.077098 -269.53184) (xy 120.027923 -269.529859) (xy 119.979704 -269.520015) (xy 119.933688 -269.502563)
			(xy 119.891067 -269.477956) (xy 119.852946 -269.446831) (xy 119.820311 -269.409994) (xy 119.794008 -269.368398)
			(xy 119.774717 -269.323122) (xy 119.76294 -269.275338) (xy 119.75898 -269.226284) (xy 119.430038 -269.226284)
			(xy 119.429543 -269.250891) (xy 119.421648 -269.299468) (xy 119.406064 -269.346149) (xy 119.383193 -269.389726)
			(xy 119.353628 -269.42907) (xy 119.318135 -269.463162) (xy 119.277632 -269.491118) (xy 119.23317 -269.512216)
			(xy 119.185899 -269.525908) (xy 119.137044 -269.53184) (xy 119.087869 -269.529859) (xy 119.03965 -269.520015)
			(xy 118.993634 -269.502563) (xy 118.951013 -269.477956) (xy 118.912892 -269.446831) (xy 118.880257 -269.409994)
			(xy 118.853954 -269.368398) (xy 118.834663 -269.323122) (xy 118.822886 -269.275338) (xy 118.818926 -269.226284)
			(xy 118.489984 -269.226284) (xy 118.489489 -269.250891) (xy 118.481594 -269.299468) (xy 118.46601 -269.346149)
			(xy 118.443139 -269.389726) (xy 118.413574 -269.42907) (xy 118.378081 -269.463162) (xy 118.337578 -269.491118)
			(xy 118.293116 -269.512216) (xy 118.245845 -269.525908) (xy 118.19699 -269.53184) (xy 118.147815 -269.529859)
			(xy 118.099596 -269.520015) (xy 118.05358 -269.502563) (xy 118.010959 -269.477956) (xy 117.972838 -269.446831)
			(xy 117.940203 -269.409994) (xy 117.9139 -269.368398) (xy 117.894609 -269.323122) (xy 117.882832 -269.275338)
			(xy 117.878872 -269.226284) (xy 117.54993 -269.226284) (xy 117.549435 -269.250891) (xy 117.54154 -269.299468)
			(xy 117.525956 -269.346149) (xy 117.503085 -269.389726) (xy 117.47352 -269.42907) (xy 117.438027 -269.463162)
			(xy 117.397524 -269.491118) (xy 117.353062 -269.512216) (xy 117.305791 -269.525908) (xy 117.256936 -269.53184)
			(xy 117.207761 -269.529859) (xy 117.159542 -269.520015) (xy 117.113526 -269.502563) (xy 117.070905 -269.477956)
			(xy 117.032784 -269.446831) (xy 117.000149 -269.409994) (xy 116.973846 -269.368398) (xy 116.954555 -269.323122)
			(xy 116.942778 -269.275338) (xy 116.938818 -269.226284) (xy 116.61013 -269.226284) (xy 116.609635 -269.250891)
			(xy 116.60174 -269.299468) (xy 116.586156 -269.346149) (xy 116.563285 -269.389726) (xy 116.53372 -269.42907)
			(xy 116.498227 -269.463162) (xy 116.457724 -269.491118) (xy 116.413262 -269.512216) (xy 116.365991 -269.525908)
			(xy 116.317136 -269.53184) (xy 116.267961 -269.529859) (xy 116.219742 -269.520015) (xy 116.173726 -269.502563)
			(xy 116.131105 -269.477956) (xy 116.092984 -269.446831) (xy 116.060349 -269.409994) (xy 116.034046 -269.368398)
			(xy 116.014755 -269.323122) (xy 116.002978 -269.275338) (xy 115.999018 -269.226284) (xy 115.670076 -269.226284)
			(xy 115.669581 -269.250891) (xy 115.661686 -269.299468) (xy 115.646102 -269.346149) (xy 115.623231 -269.389726)
			(xy 115.593666 -269.42907) (xy 115.558173 -269.463162) (xy 115.51767 -269.491118) (xy 115.473208 -269.512216)
			(xy 115.425937 -269.525908) (xy 115.377082 -269.53184) (xy 115.327907 -269.529859) (xy 115.279688 -269.520015)
			(xy 115.233672 -269.502563) (xy 115.191051 -269.477956) (xy 115.15293 -269.446831) (xy 115.120295 -269.409994)
			(xy 115.093992 -269.368398) (xy 115.074701 -269.323122) (xy 115.062924 -269.275338) (xy 115.058964 -269.226284)
			(xy 114.730022 -269.226284) (xy 114.729527 -269.250891) (xy 114.721632 -269.299468) (xy 114.706048 -269.346149)
			(xy 114.683177 -269.389726) (xy 114.653612 -269.42907) (xy 114.618119 -269.463162) (xy 114.577616 -269.491118)
			(xy 114.533154 -269.512216) (xy 114.485883 -269.525908) (xy 114.437028 -269.53184) (xy 114.387853 -269.529859)
			(xy 114.339634 -269.520015) (xy 114.293618 -269.502563) (xy 114.250997 -269.477956) (xy 114.212876 -269.446831)
			(xy 114.180241 -269.409994) (xy 114.153938 -269.368398) (xy 114.134647 -269.323122) (xy 114.12287 -269.275338)
			(xy 114.11891 -269.226284) (xy 113.789968 -269.226284) (xy 113.789473 -269.250891) (xy 113.781578 -269.299468)
			(xy 113.765994 -269.346149) (xy 113.743123 -269.389726) (xy 113.713558 -269.42907) (xy 113.678065 -269.463162)
			(xy 113.637562 -269.491118) (xy 113.5931 -269.512216) (xy 113.545829 -269.525908) (xy 113.496974 -269.53184)
			(xy 113.447799 -269.529859) (xy 113.39958 -269.520015) (xy 113.353564 -269.502563) (xy 113.310943 -269.477956)
			(xy 113.272822 -269.446831) (xy 113.240187 -269.409994) (xy 113.213884 -269.368398) (xy 113.194593 -269.323122)
			(xy 113.182816 -269.275338) (xy 113.178856 -269.226284) (xy 110.97641 -269.226284) (xy 110.975915 -269.250891)
			(xy 110.96802 -269.299468) (xy 110.952436 -269.346149) (xy 110.929565 -269.389726) (xy 110.9 -269.42907)
			(xy 110.864507 -269.463162) (xy 110.824004 -269.491118) (xy 110.779542 -269.512216) (xy 110.732271 -269.525908)
			(xy 110.683416 -269.53184) (xy 110.634241 -269.529859) (xy 110.586022 -269.520015) (xy 110.540006 -269.502563)
			(xy 110.497385 -269.477956) (xy 110.459264 -269.446831) (xy 110.426629 -269.409994) (xy 110.400326 -269.368398)
			(xy 110.381035 -269.323122) (xy 110.369258 -269.275338) (xy 110.365298 -269.226284) (xy 110.036356 -269.226284)
			(xy 110.035861 -269.250891) (xy 110.027966 -269.299468) (xy 110.012382 -269.346149) (xy 109.989511 -269.389726)
			(xy 109.959946 -269.42907) (xy 109.924453 -269.463162) (xy 109.88395 -269.491118) (xy 109.839488 -269.512216)
			(xy 109.792217 -269.525908) (xy 109.743362 -269.53184) (xy 109.694187 -269.529859) (xy 109.645968 -269.520015)
			(xy 109.599952 -269.502563) (xy 109.557331 -269.477956) (xy 109.51921 -269.446831) (xy 109.486575 -269.409994)
			(xy 109.460272 -269.368398) (xy 109.440981 -269.323122) (xy 109.429204 -269.275338) (xy 109.425244 -269.226284)
			(xy 109.096302 -269.226284) (xy 109.095807 -269.250891) (xy 109.087912 -269.299468) (xy 109.072328 -269.346149)
			(xy 109.049457 -269.389726) (xy 109.019892 -269.42907) (xy 108.984399 -269.463162) (xy 108.943896 -269.491118)
			(xy 108.899434 -269.512216) (xy 108.852163 -269.525908) (xy 108.803308 -269.53184) (xy 108.754133 -269.529859)
			(xy 108.705914 -269.520015) (xy 108.659898 -269.502563) (xy 108.617277 -269.477956) (xy 108.579156 -269.446831)
			(xy 108.546521 -269.409994) (xy 108.520218 -269.368398) (xy 108.500927 -269.323122) (xy 108.48915 -269.275338)
			(xy 108.48519 -269.226284) (xy 108.156248 -269.226284) (xy 108.155753 -269.250891) (xy 108.147858 -269.299468)
			(xy 108.132274 -269.346149) (xy 108.109403 -269.389726) (xy 108.079838 -269.42907) (xy 108.044345 -269.463162)
			(xy 108.003842 -269.491118) (xy 107.95938 -269.512216) (xy 107.912109 -269.525908) (xy 107.863254 -269.53184)
			(xy 107.814079 -269.529859) (xy 107.76586 -269.520015) (xy 107.719844 -269.502563) (xy 107.677223 -269.477956)
			(xy 107.639102 -269.446831) (xy 107.606467 -269.409994) (xy 107.580164 -269.368398) (xy 107.560873 -269.323122)
			(xy 107.549096 -269.275338) (xy 107.545136 -269.226284) (xy 107.216448 -269.226284) (xy 107.215953 -269.250891)
			(xy 107.208058 -269.299468) (xy 107.192474 -269.346149) (xy 107.169603 -269.389726) (xy 107.140038 -269.42907)
			(xy 107.104545 -269.463162) (xy 107.064042 -269.491118) (xy 107.01958 -269.512216) (xy 106.972309 -269.525908)
			(xy 106.923454 -269.53184) (xy 106.874279 -269.529859) (xy 106.82606 -269.520015) (xy 106.780044 -269.502563)
			(xy 106.737423 -269.477956) (xy 106.699302 -269.446831) (xy 106.666667 -269.409994) (xy 106.640364 -269.368398)
			(xy 106.621073 -269.323122) (xy 106.609296 -269.275338) (xy 106.605336 -269.226284) (xy 106.276394 -269.226284)
			(xy 106.275899 -269.250891) (xy 106.268004 -269.299468) (xy 106.25242 -269.346149) (xy 106.229549 -269.389726)
			(xy 106.199984 -269.42907) (xy 106.164491 -269.463162) (xy 106.123988 -269.491118) (xy 106.079526 -269.512216)
			(xy 106.032255 -269.525908) (xy 105.9834 -269.53184) (xy 105.934225 -269.529859) (xy 105.886006 -269.520015)
			(xy 105.83999 -269.502563) (xy 105.797369 -269.477956) (xy 105.759248 -269.446831) (xy 105.726613 -269.409994)
			(xy 105.70031 -269.368398) (xy 105.681019 -269.323122) (xy 105.669242 -269.275338) (xy 105.665282 -269.226284)
			(xy 105.33634 -269.226284) (xy 105.335845 -269.250891) (xy 105.32795 -269.299468) (xy 105.312366 -269.346149)
			(xy 105.289495 -269.389726) (xy 105.25993 -269.42907) (xy 105.224437 -269.463162) (xy 105.183934 -269.491118)
			(xy 105.139472 -269.512216) (xy 105.092201 -269.525908) (xy 105.043346 -269.53184) (xy 104.994171 -269.529859)
			(xy 104.945952 -269.520015) (xy 104.899936 -269.502563) (xy 104.857315 -269.477956) (xy 104.819194 -269.446831)
			(xy 104.786559 -269.409994) (xy 104.760256 -269.368398) (xy 104.740965 -269.323122) (xy 104.729188 -269.275338)
			(xy 104.725228 -269.226284) (xy 104.396286 -269.226284) (xy 104.395791 -269.250891) (xy 104.387896 -269.299468)
			(xy 104.372312 -269.346149) (xy 104.349441 -269.389726) (xy 104.319876 -269.42907) (xy 104.284383 -269.463162)
			(xy 104.24388 -269.491118) (xy 104.199418 -269.512216) (xy 104.152147 -269.525908) (xy 104.103292 -269.53184)
			(xy 104.054117 -269.529859) (xy 104.005898 -269.520015) (xy 103.959882 -269.502563) (xy 103.917261 -269.477956)
			(xy 103.87914 -269.446831) (xy 103.846505 -269.409994) (xy 103.820202 -269.368398) (xy 103.800911 -269.323122)
			(xy 103.789134 -269.275338) (xy 103.785174 -269.226284) (xy 103.456486 -269.226284) (xy 103.455991 -269.250891)
			(xy 103.448096 -269.299468) (xy 103.432512 -269.346149) (xy 103.409641 -269.389726) (xy 103.380076 -269.42907)
			(xy 103.344583 -269.463162) (xy 103.30408 -269.491118) (xy 103.259618 -269.512216) (xy 103.212347 -269.525908)
			(xy 103.163492 -269.53184) (xy 103.114317 -269.529859) (xy 103.066098 -269.520015) (xy 103.020082 -269.502563)
			(xy 102.977461 -269.477956) (xy 102.93934 -269.446831) (xy 102.906705 -269.409994) (xy 102.880402 -269.368398)
			(xy 102.861111 -269.323122) (xy 102.849334 -269.275338) (xy 102.845374 -269.226284) (xy 102.516432 -269.226284)
			(xy 102.515937 -269.250891) (xy 102.508042 -269.299468) (xy 102.492458 -269.346149) (xy 102.469587 -269.389726)
			(xy 102.440022 -269.42907) (xy 102.404529 -269.463162) (xy 102.364026 -269.491118) (xy 102.319564 -269.512216)
			(xy 102.272293 -269.525908) (xy 102.223438 -269.53184) (xy 102.174263 -269.529859) (xy 102.126044 -269.520015)
			(xy 102.080028 -269.502563) (xy 102.037407 -269.477956) (xy 101.999286 -269.446831) (xy 101.966651 -269.409994)
			(xy 101.940348 -269.368398) (xy 101.921057 -269.323122) (xy 101.90928 -269.275338) (xy 101.90532 -269.226284)
			(xy 101.576378 -269.226284) (xy 101.575883 -269.250891) (xy 101.567988 -269.299468) (xy 101.552404 -269.346149)
			(xy 101.529533 -269.389726) (xy 101.499968 -269.42907) (xy 101.464475 -269.463162) (xy 101.423972 -269.491118)
			(xy 101.37951 -269.512216) (xy 101.332239 -269.525908) (xy 101.283384 -269.53184) (xy 101.234209 -269.529859)
			(xy 101.18599 -269.520015) (xy 101.139974 -269.502563) (xy 101.097353 -269.477956) (xy 101.059232 -269.446831)
			(xy 101.026597 -269.409994) (xy 101.000294 -269.368398) (xy 100.981003 -269.323122) (xy 100.969226 -269.275338)
			(xy 100.965266 -269.226284) (xy 100.636324 -269.226284) (xy 100.635829 -269.250891) (xy 100.627934 -269.299468)
			(xy 100.61235 -269.346149) (xy 100.589479 -269.389726) (xy 100.559914 -269.42907) (xy 100.524421 -269.463162)
			(xy 100.483918 -269.491118) (xy 100.439456 -269.512216) (xy 100.392185 -269.525908) (xy 100.34333 -269.53184)
			(xy 100.294155 -269.529859) (xy 100.245936 -269.520015) (xy 100.19992 -269.502563) (xy 100.157299 -269.477956)
			(xy 100.119178 -269.446831) (xy 100.086543 -269.409994) (xy 100.06024 -269.368398) (xy 100.040949 -269.323122)
			(xy 100.029172 -269.275338) (xy 100.025212 -269.226284) (xy 99.69627 -269.226284) (xy 99.695775 -269.250891)
			(xy 99.68788 -269.299468) (xy 99.672296 -269.346149) (xy 99.649425 -269.389726) (xy 99.61986 -269.42907)
			(xy 99.584367 -269.463162) (xy 99.543864 -269.491118) (xy 99.499402 -269.512216) (xy 99.452131 -269.525908)
			(xy 99.403276 -269.53184) (xy 99.354101 -269.529859) (xy 99.305882 -269.520015) (xy 99.259866 -269.502563)
			(xy 99.217245 -269.477956) (xy 99.179124 -269.446831) (xy 99.146489 -269.409994) (xy 99.120186 -269.368398)
			(xy 99.100895 -269.323122) (xy 99.089118 -269.275338) (xy 99.085158 -269.226284) (xy 98.75647 -269.226284)
			(xy 98.755975 -269.250891) (xy 98.74808 -269.299468) (xy 98.732496 -269.346149) (xy 98.709625 -269.389726)
			(xy 98.68006 -269.42907) (xy 98.644567 -269.463162) (xy 98.604064 -269.491118) (xy 98.559602 -269.512216)
			(xy 98.512331 -269.525908) (xy 98.463476 -269.53184) (xy 98.414301 -269.529859) (xy 98.366082 -269.520015)
			(xy 98.320066 -269.502563) (xy 98.277445 -269.477956) (xy 98.239324 -269.446831) (xy 98.206689 -269.409994)
			(xy 98.180386 -269.368398) (xy 98.161095 -269.323122) (xy 98.149318 -269.275338) (xy 98.145358 -269.226284)
			(xy 97.816946 -269.226284) (xy 97.816947 -269.2263) (xy 97.812776 -269.27664) (xy 97.800376 -269.325607)
			(xy 97.780086 -269.371865) (xy 97.752458 -269.414152) (xy 97.718248 -269.451316) (xy 97.678387 -269.482342)
			(xy 97.633963 -269.506384) (xy 97.586188 -269.522787) (xy 97.536364 -269.531102) (xy 97.511108 -269.531592)
			(xy 97.493582 -269.531084) (xy 97.483168 -269.530576) (xy 97.463356 -269.537688) (xy 97.402142 -269.5956)
			(xy 97.394916 -269.603049) (xy 97.386656 -269.622065) (xy 97.38614 -269.63243) (xy 97.38614 -270.03629)
			(xy 97.675204 -270.03629) (xy 97.679164 -269.987236) (xy 97.690941 -269.939452) (xy 97.710232 -269.894176)
			(xy 97.736535 -269.85258) (xy 97.76917 -269.815743) (xy 97.807291 -269.784618) (xy 97.849912 -269.760011)
			(xy 97.895928 -269.742559) (xy 97.944147 -269.732715) (xy 97.993322 -269.730734) (xy 98.042177 -269.736666)
			(xy 98.089448 -269.750358) (xy 98.13391 -269.771456) (xy 98.174413 -269.799412) (xy 98.209906 -269.833504)
			(xy 98.239471 -269.872848) (xy 98.262342 -269.916425) (xy 98.277926 -269.963106) (xy 98.285821 -270.011683)
			(xy 98.286316 -270.03629) (xy 98.615258 -270.03629) (xy 98.619218 -269.987236) (xy 98.630995 -269.939452)
			(xy 98.650286 -269.894176) (xy 98.676589 -269.85258) (xy 98.709224 -269.815743) (xy 98.747345 -269.784618)
			(xy 98.789966 -269.760011) (xy 98.835982 -269.742559) (xy 98.884201 -269.732715) (xy 98.933376 -269.730734)
			(xy 98.982231 -269.736666) (xy 99.029502 -269.750358) (xy 99.073964 -269.771456) (xy 99.114467 -269.799412)
			(xy 99.14996 -269.833504) (xy 99.179525 -269.872848) (xy 99.202396 -269.916425) (xy 99.21798 -269.963106)
			(xy 99.225875 -270.011683) (xy 99.22637 -270.03629) (xy 99.555312 -270.03629) (xy 99.559272 -269.987236)
			(xy 99.571049 -269.939452) (xy 99.59034 -269.894176) (xy 99.616643 -269.85258) (xy 99.649278 -269.815743)
			(xy 99.687399 -269.784618) (xy 99.73002 -269.760011) (xy 99.776036 -269.742559) (xy 99.824255 -269.732715)
			(xy 99.87343 -269.730734) (xy 99.922285 -269.736666) (xy 99.969556 -269.750358) (xy 100.014018 -269.771456)
			(xy 100.054521 -269.799412) (xy 100.090014 -269.833504) (xy 100.119579 -269.872848) (xy 100.14245 -269.916425)
			(xy 100.158034 -269.963106) (xy 100.165929 -270.011683) (xy 100.166424 -270.03629) (xy 100.495366 -270.03629)
			(xy 100.499326 -269.987236) (xy 100.511103 -269.939452) (xy 100.530394 -269.894176) (xy 100.556697 -269.85258)
			(xy 100.589332 -269.815743) (xy 100.627453 -269.784618) (xy 100.670074 -269.760011) (xy 100.71609 -269.742559)
			(xy 100.764309 -269.732715) (xy 100.813484 -269.730734) (xy 100.862339 -269.736666) (xy 100.90961 -269.750358)
			(xy 100.954072 -269.771456) (xy 100.994575 -269.799412) (xy 101.030068 -269.833504) (xy 101.059633 -269.872848)
			(xy 101.082504 -269.916425) (xy 101.098088 -269.963106) (xy 101.105983 -270.011683) (xy 101.106478 -270.03629)
			(xy 101.435166 -270.03629) (xy 101.439126 -269.987236) (xy 101.450903 -269.939452) (xy 101.470194 -269.894176)
			(xy 101.496497 -269.85258) (xy 101.529132 -269.815743) (xy 101.567253 -269.784618) (xy 101.609874 -269.760011)
			(xy 101.65589 -269.742559) (xy 101.704109 -269.732715) (xy 101.753284 -269.730734) (xy 101.802139 -269.736666)
			(xy 101.84941 -269.750358) (xy 101.893872 -269.771456) (xy 101.934375 -269.799412) (xy 101.969868 -269.833504)
			(xy 101.999433 -269.872848) (xy 102.022304 -269.916425) (xy 102.037888 -269.963106) (xy 102.045783 -270.011683)
			(xy 102.046278 -270.03629) (xy 102.37522 -270.03629) (xy 102.37918 -269.987236) (xy 102.390957 -269.939452)
			(xy 102.410248 -269.894176) (xy 102.436551 -269.85258) (xy 102.469186 -269.815743) (xy 102.507307 -269.784618)
			(xy 102.549928 -269.760011) (xy 102.595944 -269.742559) (xy 102.644163 -269.732715) (xy 102.693338 -269.730734)
			(xy 102.742193 -269.736666) (xy 102.789464 -269.750358) (xy 102.833926 -269.771456) (xy 102.874429 -269.799412)
			(xy 102.909922 -269.833504) (xy 102.939487 -269.872848) (xy 102.962358 -269.916425) (xy 102.977942 -269.963106)
			(xy 102.985837 -270.011683) (xy 102.986332 -270.03629) (xy 103.315274 -270.03629) (xy 103.319234 -269.987236)
			(xy 103.331011 -269.939452) (xy 103.350302 -269.894176) (xy 103.376605 -269.85258) (xy 103.40924 -269.815743)
			(xy 103.447361 -269.784618) (xy 103.489982 -269.760011) (xy 103.535998 -269.742559) (xy 103.584217 -269.732715)
			(xy 103.633392 -269.730734) (xy 103.682247 -269.736666) (xy 103.729518 -269.750358) (xy 103.77398 -269.771456)
			(xy 103.814483 -269.799412) (xy 103.849976 -269.833504) (xy 103.879541 -269.872848) (xy 103.902412 -269.916425)
			(xy 103.917996 -269.963106) (xy 103.925891 -270.011683) (xy 103.926386 -270.03629) (xy 104.255328 -270.03629)
			(xy 104.259288 -269.987236) (xy 104.271065 -269.939452) (xy 104.290356 -269.894176) (xy 104.316659 -269.85258)
			(xy 104.349294 -269.815743) (xy 104.387415 -269.784618) (xy 104.430036 -269.760011) (xy 104.476052 -269.742559)
			(xy 104.524271 -269.732715) (xy 104.573446 -269.730734) (xy 104.622301 -269.736666) (xy 104.669572 -269.750358)
			(xy 104.714034 -269.771456) (xy 104.754537 -269.799412) (xy 104.79003 -269.833504) (xy 104.819595 -269.872848)
			(xy 104.842466 -269.916425) (xy 104.85805 -269.963106) (xy 104.865945 -270.011683) (xy 104.86644 -270.03629)
			(xy 105.195128 -270.03629) (xy 105.199088 -269.987236) (xy 105.210865 -269.939452) (xy 105.230156 -269.894176)
			(xy 105.256459 -269.85258) (xy 105.289094 -269.815743) (xy 105.327215 -269.784618) (xy 105.369836 -269.760011)
			(xy 105.415852 -269.742559) (xy 105.464071 -269.732715) (xy 105.513246 -269.730734) (xy 105.562101 -269.736666)
			(xy 105.609372 -269.750358) (xy 105.653834 -269.771456) (xy 105.694337 -269.799412) (xy 105.72983 -269.833504)
			(xy 105.759395 -269.872848) (xy 105.782266 -269.916425) (xy 105.79785 -269.963106) (xy 105.805745 -270.011683)
			(xy 105.80624 -270.03629) (xy 106.135182 -270.03629) (xy 106.139142 -269.987236) (xy 106.150919 -269.939452)
			(xy 106.17021 -269.894176) (xy 106.196513 -269.85258) (xy 106.229148 -269.815743) (xy 106.267269 -269.784618)
			(xy 106.30989 -269.760011) (xy 106.355906 -269.742559) (xy 106.404125 -269.732715) (xy 106.4533 -269.730734)
			(xy 106.502155 -269.736666) (xy 106.549426 -269.750358) (xy 106.593888 -269.771456) (xy 106.634391 -269.799412)
			(xy 106.669884 -269.833504) (xy 106.699449 -269.872848) (xy 106.72232 -269.916425) (xy 106.737904 -269.963106)
			(xy 106.745799 -270.011683) (xy 106.746294 -270.03629) (xy 107.075236 -270.03629) (xy 107.079196 -269.987236)
			(xy 107.090973 -269.939452) (xy 107.110264 -269.894176) (xy 107.136567 -269.85258) (xy 107.169202 -269.815743)
			(xy 107.207323 -269.784618) (xy 107.249944 -269.760011) (xy 107.29596 -269.742559) (xy 107.344179 -269.732715)
			(xy 107.393354 -269.730734) (xy 107.442209 -269.736666) (xy 107.48948 -269.750358) (xy 107.533942 -269.771456)
			(xy 107.574445 -269.799412) (xy 107.609938 -269.833504) (xy 107.639503 -269.872848) (xy 107.662374 -269.916425)
			(xy 107.677958 -269.963106) (xy 107.685853 -270.011683) (xy 107.686348 -270.03629) (xy 108.01529 -270.03629)
			(xy 108.01925 -269.987236) (xy 108.031027 -269.939452) (xy 108.050318 -269.894176) (xy 108.076621 -269.85258)
			(xy 108.109256 -269.815743) (xy 108.147377 -269.784618) (xy 108.189998 -269.760011) (xy 108.236014 -269.742559)
			(xy 108.284233 -269.732715) (xy 108.333408 -269.730734) (xy 108.382263 -269.736666) (xy 108.429534 -269.750358)
			(xy 108.473996 -269.771456) (xy 108.514499 -269.799412) (xy 108.549992 -269.833504) (xy 108.579557 -269.872848)
			(xy 108.602428 -269.916425) (xy 108.618012 -269.963106) (xy 108.625907 -270.011683) (xy 108.626402 -270.03629)
			(xy 108.955344 -270.03629) (xy 108.959304 -269.987236) (xy 108.971081 -269.939452) (xy 108.990372 -269.894176)
			(xy 109.016675 -269.85258) (xy 109.04931 -269.815743) (xy 109.087431 -269.784618) (xy 109.130052 -269.760011)
			(xy 109.176068 -269.742559) (xy 109.224287 -269.732715) (xy 109.273462 -269.730734) (xy 109.322317 -269.736666)
			(xy 109.369588 -269.750358) (xy 109.41405 -269.771456) (xy 109.454553 -269.799412) (xy 109.490046 -269.833504)
			(xy 109.519611 -269.872848) (xy 109.542482 -269.916425) (xy 109.558066 -269.963106) (xy 109.565961 -270.011683)
			(xy 109.566456 -270.03629) (xy 109.895144 -270.03629) (xy 109.899104 -269.987236) (xy 109.910881 -269.939452)
			(xy 109.930172 -269.894176) (xy 109.956475 -269.85258) (xy 109.98911 -269.815743) (xy 110.027231 -269.784618)
			(xy 110.069852 -269.760011) (xy 110.115868 -269.742559) (xy 110.164087 -269.732715) (xy 110.213262 -269.730734)
			(xy 110.262117 -269.736666) (xy 110.309388 -269.750358) (xy 110.35385 -269.771456) (xy 110.394353 -269.799412)
			(xy 110.429846 -269.833504) (xy 110.459411 -269.872848) (xy 110.482282 -269.916425) (xy 110.497866 -269.963106)
			(xy 110.505761 -270.011683) (xy 110.506256 -270.03629) (xy 113.64901 -270.03629) (xy 113.65297 -269.987236)
			(xy 113.664747 -269.939452) (xy 113.684038 -269.894176) (xy 113.710341 -269.85258) (xy 113.742976 -269.815743)
			(xy 113.781097 -269.784618) (xy 113.823718 -269.760011) (xy 113.869734 -269.742559) (xy 113.917953 -269.732715)
			(xy 113.967128 -269.730734) (xy 114.015983 -269.736666) (xy 114.063254 -269.750358) (xy 114.107716 -269.771456)
			(xy 114.148219 -269.799412) (xy 114.183712 -269.833504) (xy 114.213277 -269.872848) (xy 114.236148 -269.916425)
			(xy 114.251732 -269.963106) (xy 114.259627 -270.011683) (xy 114.260122 -270.03629) (xy 114.58881 -270.03629)
			(xy 114.59277 -269.987236) (xy 114.604547 -269.939452) (xy 114.623838 -269.894176) (xy 114.650141 -269.85258)
			(xy 114.682776 -269.815743) (xy 114.720897 -269.784618) (xy 114.763518 -269.760011) (xy 114.809534 -269.742559)
			(xy 114.857753 -269.732715) (xy 114.906928 -269.730734) (xy 114.955783 -269.736666) (xy 115.003054 -269.750358)
			(xy 115.047516 -269.771456) (xy 115.088019 -269.799412) (xy 115.123512 -269.833504) (xy 115.153077 -269.872848)
			(xy 115.175948 -269.916425) (xy 115.191532 -269.963106) (xy 115.199427 -270.011683) (xy 115.199922 -270.03629)
			(xy 115.528864 -270.03629) (xy 115.532824 -269.987236) (xy 115.544601 -269.939452) (xy 115.563892 -269.894176)
			(xy 115.590195 -269.85258) (xy 115.62283 -269.815743) (xy 115.660951 -269.784618) (xy 115.703572 -269.760011)
			(xy 115.749588 -269.742559) (xy 115.797807 -269.732715) (xy 115.846982 -269.730734) (xy 115.895837 -269.736666)
			(xy 115.943108 -269.750358) (xy 115.98757 -269.771456) (xy 116.028073 -269.799412) (xy 116.063566 -269.833504)
			(xy 116.093131 -269.872848) (xy 116.116002 -269.916425) (xy 116.131586 -269.963106) (xy 116.139481 -270.011683)
			(xy 116.139976 -270.03629) (xy 116.468918 -270.03629) (xy 116.472878 -269.987236) (xy 116.484655 -269.939452)
			(xy 116.503946 -269.894176) (xy 116.530249 -269.85258) (xy 116.562884 -269.815743) (xy 116.601005 -269.784618)
			(xy 116.643626 -269.760011) (xy 116.689642 -269.742559) (xy 116.737861 -269.732715) (xy 116.787036 -269.730734)
			(xy 116.835891 -269.736666) (xy 116.883162 -269.750358) (xy 116.927624 -269.771456) (xy 116.968127 -269.799412)
			(xy 117.00362 -269.833504) (xy 117.033185 -269.872848) (xy 117.056056 -269.916425) (xy 117.07164 -269.963106)
			(xy 117.079535 -270.011683) (xy 117.08003 -270.03629) (xy 117.408972 -270.03629) (xy 117.412932 -269.987236)
			(xy 117.424709 -269.939452) (xy 117.444 -269.894176) (xy 117.470303 -269.85258) (xy 117.502938 -269.815743)
			(xy 117.541059 -269.784618) (xy 117.58368 -269.760011) (xy 117.629696 -269.742559) (xy 117.677915 -269.732715)
			(xy 117.72709 -269.730734) (xy 117.775945 -269.736666) (xy 117.823216 -269.750358) (xy 117.867678 -269.771456)
			(xy 117.908181 -269.799412) (xy 117.943674 -269.833504) (xy 117.973239 -269.872848) (xy 117.99611 -269.916425)
			(xy 118.011694 -269.963106) (xy 118.019589 -270.011683) (xy 118.020084 -270.03629) (xy 118.349026 -270.03629)
			(xy 118.352986 -269.987236) (xy 118.364763 -269.939452) (xy 118.384054 -269.894176) (xy 118.410357 -269.85258)
			(xy 118.442992 -269.815743) (xy 118.481113 -269.784618) (xy 118.523734 -269.760011) (xy 118.56975 -269.742559)
			(xy 118.617969 -269.732715) (xy 118.667144 -269.730734) (xy 118.715999 -269.736666) (xy 118.76327 -269.750358)
			(xy 118.807732 -269.771456) (xy 118.848235 -269.799412) (xy 118.883728 -269.833504) (xy 118.913293 -269.872848)
			(xy 118.936164 -269.916425) (xy 118.951748 -269.963106) (xy 118.959643 -270.011683) (xy 118.960138 -270.03629)
			(xy 119.288826 -270.03629) (xy 119.292786 -269.987236) (xy 119.304563 -269.939452) (xy 119.323854 -269.894176)
			(xy 119.350157 -269.85258) (xy 119.382792 -269.815743) (xy 119.420913 -269.784618) (xy 119.463534 -269.760011)
			(xy 119.50955 -269.742559) (xy 119.557769 -269.732715) (xy 119.606944 -269.730734) (xy 119.655799 -269.736666)
			(xy 119.70307 -269.750358) (xy 119.747532 -269.771456) (xy 119.788035 -269.799412) (xy 119.823528 -269.833504)
			(xy 119.853093 -269.872848) (xy 119.875964 -269.916425) (xy 119.891548 -269.963106) (xy 119.899443 -270.011683)
			(xy 119.899938 -270.03629) (xy 120.22888 -270.03629) (xy 120.23284 -269.987236) (xy 120.244617 -269.939452)
			(xy 120.263908 -269.894176) (xy 120.290211 -269.85258) (xy 120.322846 -269.815743) (xy 120.360967 -269.784618)
			(xy 120.403588 -269.760011) (xy 120.449604 -269.742559) (xy 120.497823 -269.732715) (xy 120.546998 -269.730734)
			(xy 120.595853 -269.736666) (xy 120.643124 -269.750358) (xy 120.687586 -269.771456) (xy 120.728089 -269.799412)
			(xy 120.763582 -269.833504) (xy 120.793147 -269.872848) (xy 120.816018 -269.916425) (xy 120.831602 -269.963106)
			(xy 120.839497 -270.011683) (xy 120.839992 -270.03629) (xy 121.168934 -270.03629) (xy 121.172894 -269.987236)
			(xy 121.184671 -269.939452) (xy 121.203962 -269.894176) (xy 121.230265 -269.85258) (xy 121.2629 -269.815743)
			(xy 121.301021 -269.784618) (xy 121.343642 -269.760011) (xy 121.389658 -269.742559) (xy 121.437877 -269.732715)
			(xy 121.487052 -269.730734) (xy 121.535907 -269.736666) (xy 121.583178 -269.750358) (xy 121.62764 -269.771456)
			(xy 121.668143 -269.799412) (xy 121.703636 -269.833504) (xy 121.733201 -269.872848) (xy 121.756072 -269.916425)
			(xy 121.771656 -269.963106) (xy 121.779551 -270.011683) (xy 121.780046 -270.03629) (xy 122.108988 -270.03629)
			(xy 122.112948 -269.987236) (xy 122.124725 -269.939452) (xy 122.144016 -269.894176) (xy 122.170319 -269.85258)
			(xy 122.202954 -269.815743) (xy 122.241075 -269.784618) (xy 122.283696 -269.760011) (xy 122.329712 -269.742559)
			(xy 122.377931 -269.732715) (xy 122.427106 -269.730734) (xy 122.475961 -269.736666) (xy 122.523232 -269.750358)
			(xy 122.567694 -269.771456) (xy 122.608197 -269.799412) (xy 122.64369 -269.833504) (xy 122.673255 -269.872848)
			(xy 122.696126 -269.916425) (xy 122.71171 -269.963106) (xy 122.719605 -270.011683) (xy 122.7201 -270.03629)
			(xy 123.049042 -270.03629) (xy 123.053002 -269.987236) (xy 123.064779 -269.939452) (xy 123.08407 -269.894176)
			(xy 123.110373 -269.85258) (xy 123.143008 -269.815743) (xy 123.181129 -269.784618) (xy 123.22375 -269.760011)
			(xy 123.269766 -269.742559) (xy 123.317985 -269.732715) (xy 123.36716 -269.730734) (xy 123.416015 -269.736666)
			(xy 123.463286 -269.750358) (xy 123.507748 -269.771456) (xy 123.548251 -269.799412) (xy 123.583744 -269.833504)
			(xy 123.613309 -269.872848) (xy 123.63618 -269.916425) (xy 123.651764 -269.963106) (xy 123.659659 -270.011683)
			(xy 123.660154 -270.03629) (xy 123.988842 -270.03629) (xy 123.992802 -269.987236) (xy 124.004579 -269.939452)
			(xy 124.02387 -269.894176) (xy 124.050173 -269.85258) (xy 124.082808 -269.815743) (xy 124.120929 -269.784618)
			(xy 124.16355 -269.760011) (xy 124.209566 -269.742559) (xy 124.257785 -269.732715) (xy 124.30696 -269.730734)
			(xy 124.355815 -269.736666) (xy 124.403086 -269.750358) (xy 124.447548 -269.771456) (xy 124.488051 -269.799412)
			(xy 124.523544 -269.833504) (xy 124.553109 -269.872848) (xy 124.57598 -269.916425) (xy 124.591564 -269.963106)
			(xy 124.599459 -270.011683) (xy 124.599954 -270.03629) (xy 124.928896 -270.03629) (xy 124.932856 -269.987236)
			(xy 124.944633 -269.939452) (xy 124.963924 -269.894176) (xy 124.990227 -269.85258) (xy 125.022862 -269.815743)
			(xy 125.060983 -269.784618) (xy 125.103604 -269.760011) (xy 125.14962 -269.742559) (xy 125.197839 -269.732715)
			(xy 125.247014 -269.730734) (xy 125.295869 -269.736666) (xy 125.34314 -269.750358) (xy 125.387602 -269.771456)
			(xy 125.428105 -269.799412) (xy 125.463598 -269.833504) (xy 125.493163 -269.872848) (xy 125.516034 -269.916425)
			(xy 125.531618 -269.963106) (xy 125.539513 -270.011683) (xy 125.540008 -270.03629) (xy 125.86895 -270.03629)
			(xy 125.87291 -269.987236) (xy 125.884687 -269.939452) (xy 125.903978 -269.894176) (xy 125.930281 -269.85258)
			(xy 125.962916 -269.815743) (xy 126.001037 -269.784618) (xy 126.043658 -269.760011) (xy 126.089674 -269.742559)
			(xy 126.137893 -269.732715) (xy 126.187068 -269.730734) (xy 126.235923 -269.736666) (xy 126.283194 -269.750358)
			(xy 126.327656 -269.771456) (xy 126.368159 -269.799412) (xy 126.403652 -269.833504) (xy 126.433217 -269.872848)
			(xy 126.456088 -269.916425) (xy 126.471672 -269.963106) (xy 126.479567 -270.011683) (xy 126.480062 -270.03629)
			(xy 126.809004 -270.03629) (xy 126.812964 -269.987236) (xy 126.824741 -269.939452) (xy 126.844032 -269.894176)
			(xy 126.870335 -269.85258) (xy 126.90297 -269.815743) (xy 126.941091 -269.784618) (xy 126.983712 -269.760011)
			(xy 127.029728 -269.742559) (xy 127.077947 -269.732715) (xy 127.127122 -269.730734) (xy 127.175977 -269.736666)
			(xy 127.223248 -269.750358) (xy 127.26771 -269.771456) (xy 127.308213 -269.799412) (xy 127.343706 -269.833504)
			(xy 127.373271 -269.872848) (xy 127.396142 -269.916425) (xy 127.411726 -269.963106) (xy 127.419621 -270.011683)
			(xy 127.420116 -270.03629) (xy 127.738627 -270.03629) (xy 127.742722 -269.985562) (xy 127.754901 -269.936148)
			(xy 127.774849 -269.889328) (xy 127.80205 -269.846314) (xy 127.835798 -269.80822) (xy 127.87522 -269.776033)
			(xy 127.919294 -269.750587) (xy 127.96688 -269.73254) (xy 128.016744 -269.72236) (xy 128.067596 -269.720311)
			(xy 128.118117 -269.726445) (xy 128.167001 -269.740605) (xy 128.21298 -269.762422) (xy 128.254864 -269.791332)
			(xy 128.291568 -269.826587) (xy 128.322141 -269.867273) (xy 128.345792 -269.912336) (xy 128.361908 -269.96061)
			(xy 128.370072 -270.010844) (xy 128.370584 -270.03629) (xy 128.688858 -270.03629) (xy 128.692818 -269.987236)
			(xy 128.704595 -269.939452) (xy 128.723886 -269.894176) (xy 128.750189 -269.85258) (xy 128.782824 -269.815743)
			(xy 128.820945 -269.784618) (xy 128.863566 -269.760011) (xy 128.909582 -269.742559) (xy 128.957801 -269.732715)
			(xy 129.006976 -269.730734) (xy 129.055831 -269.736666) (xy 129.103102 -269.750358) (xy 129.147564 -269.771456)
			(xy 129.188067 -269.799412) (xy 129.22356 -269.833504) (xy 129.253125 -269.872848) (xy 129.275996 -269.916425)
			(xy 129.29158 -269.963106) (xy 129.299475 -270.011683) (xy 129.29997 -270.03629) (xy 129.618481 -270.03629)
			(xy 129.622576 -269.985562) (xy 129.634755 -269.936148) (xy 129.654703 -269.889328) (xy 129.681904 -269.846314)
			(xy 129.715652 -269.80822) (xy 129.755074 -269.776033) (xy 129.799148 -269.750587) (xy 129.846734 -269.73254)
			(xy 129.896598 -269.72236) (xy 129.94745 -269.720311) (xy 129.997971 -269.726445) (xy 130.046855 -269.740605)
			(xy 130.092834 -269.762422) (xy 130.134718 -269.791332) (xy 130.171422 -269.826587) (xy 130.201995 -269.867273)
			(xy 130.225646 -269.912336) (xy 130.241762 -269.96061) (xy 130.249926 -270.010844) (xy 130.250438 -270.03629)
			(xy 130.568966 -270.03629) (xy 130.572926 -269.987236) (xy 130.584703 -269.939452) (xy 130.603994 -269.894176)
			(xy 130.630297 -269.85258) (xy 130.662932 -269.815743) (xy 130.701053 -269.784618) (xy 130.743674 -269.760011)
			(xy 130.78969 -269.742559) (xy 130.837909 -269.732715) (xy 130.887084 -269.730734) (xy 130.935939 -269.736666)
			(xy 130.98321 -269.750358) (xy 131.027672 -269.771456) (xy 131.068175 -269.799412) (xy 131.103668 -269.833504)
			(xy 131.133233 -269.872848) (xy 131.156104 -269.916425) (xy 131.171688 -269.963106) (xy 131.179583 -270.011683)
			(xy 131.180078 -270.03629) (xy 131.498589 -270.03629) (xy 131.502684 -269.985562) (xy 131.514863 -269.936148)
			(xy 131.534811 -269.889328) (xy 131.562012 -269.846314) (xy 131.59576 -269.80822) (xy 131.635182 -269.776033)
			(xy 131.679256 -269.750587) (xy 131.726842 -269.73254) (xy 131.776706 -269.72236) (xy 131.827558 -269.720311)
			(xy 131.878079 -269.726445) (xy 131.926963 -269.740605) (xy 131.972942 -269.762422) (xy 132.014826 -269.791332)
			(xy 132.05153 -269.826587) (xy 132.082103 -269.867273) (xy 132.105754 -269.912336) (xy 132.12187 -269.96061)
			(xy 132.130034 -270.010844) (xy 132.130546 -270.03629) (xy 132.438643 -270.03629) (xy 132.442738 -269.985562)
			(xy 132.454917 -269.936148) (xy 132.474865 -269.889328) (xy 132.502066 -269.846314) (xy 132.535814 -269.80822)
			(xy 132.575236 -269.776033) (xy 132.61931 -269.750587) (xy 132.666896 -269.73254) (xy 132.71676 -269.72236)
			(xy 132.767612 -269.720311) (xy 132.818133 -269.726445) (xy 132.867017 -269.740605) (xy 132.912996 -269.762422)
			(xy 132.95488 -269.791332) (xy 132.991584 -269.826587) (xy 133.022157 -269.867273) (xy 133.045808 -269.912336)
			(xy 133.061924 -269.96061) (xy 133.070088 -270.010844) (xy 133.0706 -270.03629) (xy 133.388874 -270.03629)
			(xy 133.392834 -269.987236) (xy 133.404611 -269.939452) (xy 133.423902 -269.894176) (xy 133.450205 -269.85258)
			(xy 133.48284 -269.815743) (xy 133.520961 -269.784618) (xy 133.563582 -269.760011) (xy 133.609598 -269.742559)
			(xy 133.657817 -269.732715) (xy 133.706992 -269.730734) (xy 133.755847 -269.736666) (xy 133.803118 -269.750358)
			(xy 133.84758 -269.771456) (xy 133.888083 -269.799412) (xy 133.923576 -269.833504) (xy 133.953141 -269.872848)
			(xy 133.976012 -269.916425) (xy 133.991596 -269.963106) (xy 133.999491 -270.011683) (xy 133.999986 -270.03629)
			(xy 134.328928 -270.03629) (xy 134.332888 -269.987236) (xy 134.344665 -269.939452) (xy 134.363956 -269.894176)
			(xy 134.390259 -269.85258) (xy 134.422894 -269.815743) (xy 134.461015 -269.784618) (xy 134.503636 -269.760011)
			(xy 134.549652 -269.742559) (xy 134.597871 -269.732715) (xy 134.647046 -269.730734) (xy 134.695901 -269.736666)
			(xy 134.743172 -269.750358) (xy 134.787634 -269.771456) (xy 134.828137 -269.799412) (xy 134.86363 -269.833504)
			(xy 134.893195 -269.872848) (xy 134.916066 -269.916425) (xy 134.93165 -269.963106) (xy 134.939545 -270.011683)
			(xy 134.94004 -270.03629) (xy 135.268982 -270.03629) (xy 135.272942 -269.987236) (xy 135.284719 -269.939452)
			(xy 135.30401 -269.894176) (xy 135.330313 -269.85258) (xy 135.362948 -269.815743) (xy 135.401069 -269.784618)
			(xy 135.44369 -269.760011) (xy 135.489706 -269.742559) (xy 135.537925 -269.732715) (xy 135.5871 -269.730734)
			(xy 135.635955 -269.736666) (xy 135.683226 -269.750358) (xy 135.727688 -269.771456) (xy 135.768191 -269.799412)
			(xy 135.803684 -269.833504) (xy 135.833249 -269.872848) (xy 135.85612 -269.916425) (xy 135.871704 -269.963106)
			(xy 135.879599 -270.011683) (xy 135.880094 -270.03629) (xy 136.209036 -270.03629) (xy 136.212996 -269.987236)
			(xy 136.224773 -269.939452) (xy 136.244064 -269.894176) (xy 136.270367 -269.85258) (xy 136.303002 -269.815743)
			(xy 136.341123 -269.784618) (xy 136.383744 -269.760011) (xy 136.42976 -269.742559) (xy 136.477979 -269.732715)
			(xy 136.527154 -269.730734) (xy 136.576009 -269.736666) (xy 136.62328 -269.750358) (xy 136.667742 -269.771456)
			(xy 136.708245 -269.799412) (xy 136.743738 -269.833504) (xy 136.773303 -269.872848) (xy 136.796174 -269.916425)
			(xy 136.811758 -269.963106) (xy 136.819653 -270.011683) (xy 136.820148 -270.03629) (xy 137.148836 -270.03629)
			(xy 137.152796 -269.987236) (xy 137.164573 -269.939452) (xy 137.183864 -269.894176) (xy 137.210167 -269.85258)
			(xy 137.242802 -269.815743) (xy 137.280923 -269.784618) (xy 137.323544 -269.760011) (xy 137.36956 -269.742559)
			(xy 137.417779 -269.732715) (xy 137.466954 -269.730734) (xy 137.515809 -269.736666) (xy 137.56308 -269.750358)
			(xy 137.607542 -269.771456) (xy 137.648045 -269.799412) (xy 137.683538 -269.833504) (xy 137.713103 -269.872848)
			(xy 137.735974 -269.916425) (xy 137.751558 -269.963106) (xy 137.759453 -270.011683) (xy 137.759948 -270.03629)
			(xy 138.08889 -270.03629) (xy 138.09285 -269.987236) (xy 138.104627 -269.939452) (xy 138.123918 -269.894176)
			(xy 138.150221 -269.85258) (xy 138.182856 -269.815743) (xy 138.220977 -269.784618) (xy 138.263598 -269.760011)
			(xy 138.309614 -269.742559) (xy 138.357833 -269.732715) (xy 138.407008 -269.730734) (xy 138.455863 -269.736666)
			(xy 138.503134 -269.750358) (xy 138.547596 -269.771456) (xy 138.588099 -269.799412) (xy 138.623592 -269.833504)
			(xy 138.653157 -269.872848) (xy 138.676028 -269.916425) (xy 138.691612 -269.963106) (xy 138.699507 -270.011683)
			(xy 138.700002 -270.03629) (xy 139.028944 -270.03629) (xy 139.032904 -269.987236) (xy 139.044681 -269.939452)
			(xy 139.063972 -269.894176) (xy 139.090275 -269.85258) (xy 139.12291 -269.815743) (xy 139.161031 -269.784618)
			(xy 139.203652 -269.760011) (xy 139.249668 -269.742559) (xy 139.297887 -269.732715) (xy 139.347062 -269.730734)
			(xy 139.395917 -269.736666) (xy 139.443188 -269.750358) (xy 139.48765 -269.771456) (xy 139.528153 -269.799412)
			(xy 139.563646 -269.833504) (xy 139.593211 -269.872848) (xy 139.616082 -269.916425) (xy 139.631666 -269.963106)
			(xy 139.639561 -270.011683) (xy 139.640056 -270.03629) (xy 139.639561 -270.060897) (xy 139.631666 -270.109474)
			(xy 139.616082 -270.156155) (xy 139.593211 -270.199732) (xy 139.563646 -270.239076) (xy 139.528153 -270.273168)
			(xy 139.48765 -270.301124) (xy 139.443188 -270.322222) (xy 139.395917 -270.335914) (xy 139.347062 -270.341846)
			(xy 139.297887 -270.339865) (xy 139.249668 -270.330021) (xy 139.203652 -270.312569) (xy 139.161031 -270.287962)
			(xy 139.12291 -270.256837) (xy 139.090275 -270.22) (xy 139.063972 -270.178404) (xy 139.044681 -270.133128)
			(xy 139.032904 -270.085344) (xy 139.028944 -270.03629) (xy 138.700002 -270.03629) (xy 138.699507 -270.060897)
			(xy 138.691612 -270.109474) (xy 138.676028 -270.156155) (xy 138.653157 -270.199732) (xy 138.623592 -270.239076)
			(xy 138.588099 -270.273168) (xy 138.547596 -270.301124) (xy 138.503134 -270.322222) (xy 138.455863 -270.335914)
			(xy 138.407008 -270.341846) (xy 138.357833 -270.339865) (xy 138.309614 -270.330021) (xy 138.263598 -270.312569)
			(xy 138.220977 -270.287962) (xy 138.182856 -270.256837) (xy 138.150221 -270.22) (xy 138.123918 -270.178404)
			(xy 138.104627 -270.133128) (xy 138.09285 -270.085344) (xy 138.08889 -270.03629) (xy 137.759948 -270.03629)
			(xy 137.759453 -270.060897) (xy 137.751558 -270.109474) (xy 137.735974 -270.156155) (xy 137.713103 -270.199732)
			(xy 137.683538 -270.239076) (xy 137.648045 -270.273168) (xy 137.607542 -270.301124) (xy 137.56308 -270.322222)
			(xy 137.515809 -270.335914) (xy 137.466954 -270.341846) (xy 137.417779 -270.339865) (xy 137.36956 -270.330021)
			(xy 137.323544 -270.312569) (xy 137.280923 -270.287962) (xy 137.242802 -270.256837) (xy 137.210167 -270.22)
			(xy 137.183864 -270.178404) (xy 137.164573 -270.133128) (xy 137.152796 -270.085344) (xy 137.148836 -270.03629)
			(xy 136.820148 -270.03629) (xy 136.819653 -270.060897) (xy 136.811758 -270.109474) (xy 136.796174 -270.156155)
			(xy 136.773303 -270.199732) (xy 136.743738 -270.239076) (xy 136.708245 -270.273168) (xy 136.667742 -270.301124)
			(xy 136.62328 -270.322222) (xy 136.576009 -270.335914) (xy 136.527154 -270.341846) (xy 136.477979 -270.339865)
			(xy 136.42976 -270.330021) (xy 136.383744 -270.312569) (xy 136.341123 -270.287962) (xy 136.303002 -270.256837)
			(xy 136.270367 -270.22) (xy 136.244064 -270.178404) (xy 136.224773 -270.133128) (xy 136.212996 -270.085344)
			(xy 136.209036 -270.03629) (xy 135.880094 -270.03629) (xy 135.879599 -270.060897) (xy 135.871704 -270.109474)
			(xy 135.85612 -270.156155) (xy 135.833249 -270.199732) (xy 135.803684 -270.239076) (xy 135.768191 -270.273168)
			(xy 135.727688 -270.301124) (xy 135.683226 -270.322222) (xy 135.635955 -270.335914) (xy 135.5871 -270.341846)
			(xy 135.537925 -270.339865) (xy 135.489706 -270.330021) (xy 135.44369 -270.312569) (xy 135.401069 -270.287962)
			(xy 135.362948 -270.256837) (xy 135.330313 -270.22) (xy 135.30401 -270.178404) (xy 135.284719 -270.133128)
			(xy 135.272942 -270.085344) (xy 135.268982 -270.03629) (xy 134.94004 -270.03629) (xy 134.939545 -270.060897)
			(xy 134.93165 -270.109474) (xy 134.916066 -270.156155) (xy 134.893195 -270.199732) (xy 134.86363 -270.239076)
			(xy 134.828137 -270.273168) (xy 134.787634 -270.301124) (xy 134.743172 -270.322222) (xy 134.695901 -270.335914)
			(xy 134.647046 -270.341846) (xy 134.597871 -270.339865) (xy 134.549652 -270.330021) (xy 134.503636 -270.312569)
			(xy 134.461015 -270.287962) (xy 134.422894 -270.256837) (xy 134.390259 -270.22) (xy 134.363956 -270.178404)
			(xy 134.344665 -270.133128) (xy 134.332888 -270.085344) (xy 134.328928 -270.03629) (xy 133.999986 -270.03629)
			(xy 133.999491 -270.060897) (xy 133.991596 -270.109474) (xy 133.976012 -270.156155) (xy 133.953141 -270.199732)
			(xy 133.923576 -270.239076) (xy 133.888083 -270.273168) (xy 133.84758 -270.301124) (xy 133.803118 -270.322222)
			(xy 133.755847 -270.335914) (xy 133.706992 -270.341846) (xy 133.657817 -270.339865) (xy 133.609598 -270.330021)
			(xy 133.563582 -270.312569) (xy 133.520961 -270.287962) (xy 133.48284 -270.256837) (xy 133.450205 -270.22)
			(xy 133.423902 -270.178404) (xy 133.404611 -270.133128) (xy 133.392834 -270.085344) (xy 133.388874 -270.03629)
			(xy 133.0706 -270.03629) (xy 133.070088 -270.061736) (xy 133.061924 -270.11197) (xy 133.045808 -270.160244)
			(xy 133.022157 -270.205307) (xy 132.991584 -270.245993) (xy 132.95488 -270.281248) (xy 132.912996 -270.310158)
			(xy 132.867017 -270.331975) (xy 132.818133 -270.346135) (xy 132.767612 -270.352269) (xy 132.71676 -270.35022)
			(xy 132.666896 -270.34004) (xy 132.61931 -270.321993) (xy 132.575236 -270.296547) (xy 132.535814 -270.26436)
			(xy 132.502066 -270.226266) (xy 132.474865 -270.183252) (xy 132.454917 -270.136432) (xy 132.442738 -270.087018)
			(xy 132.438643 -270.03629) (xy 132.130546 -270.03629) (xy 132.130034 -270.061736) (xy 132.12187 -270.11197)
			(xy 132.105754 -270.160244) (xy 132.082103 -270.205307) (xy 132.05153 -270.245993) (xy 132.014826 -270.281248)
			(xy 131.972942 -270.310158) (xy 131.926963 -270.331975) (xy 131.878079 -270.346135) (xy 131.827558 -270.352269)
			(xy 131.776706 -270.35022) (xy 131.726842 -270.34004) (xy 131.679256 -270.321993) (xy 131.635182 -270.296547)
			(xy 131.59576 -270.26436) (xy 131.562012 -270.226266) (xy 131.534811 -270.183252) (xy 131.514863 -270.136432)
			(xy 131.502684 -270.087018) (xy 131.498589 -270.03629) (xy 131.180078 -270.03629) (xy 131.179583 -270.060897)
			(xy 131.171688 -270.109474) (xy 131.156104 -270.156155) (xy 131.133233 -270.199732) (xy 131.103668 -270.239076)
			(xy 131.068175 -270.273168) (xy 131.027672 -270.301124) (xy 130.98321 -270.322222) (xy 130.935939 -270.335914)
			(xy 130.887084 -270.341846) (xy 130.837909 -270.339865) (xy 130.78969 -270.330021) (xy 130.743674 -270.312569)
			(xy 130.701053 -270.287962) (xy 130.662932 -270.256837) (xy 130.630297 -270.22) (xy 130.603994 -270.178404)
			(xy 130.584703 -270.133128) (xy 130.572926 -270.085344) (xy 130.568966 -270.03629) (xy 130.250438 -270.03629)
			(xy 130.249926 -270.061736) (xy 130.241762 -270.11197) (xy 130.225646 -270.160244) (xy 130.201995 -270.205307)
			(xy 130.171422 -270.245993) (xy 130.134718 -270.281248) (xy 130.092834 -270.310158) (xy 130.046855 -270.331975)
			(xy 129.997971 -270.346135) (xy 129.94745 -270.352269) (xy 129.896598 -270.35022) (xy 129.846734 -270.34004)
			(xy 129.799148 -270.321993) (xy 129.755074 -270.296547) (xy 129.715652 -270.26436) (xy 129.681904 -270.226266)
			(xy 129.654703 -270.183252) (xy 129.634755 -270.136432) (xy 129.622576 -270.087018) (xy 129.618481 -270.03629)
			(xy 129.29997 -270.03629) (xy 129.299475 -270.060897) (xy 129.29158 -270.109474) (xy 129.275996 -270.156155)
			(xy 129.253125 -270.199732) (xy 129.22356 -270.239076) (xy 129.188067 -270.273168) (xy 129.147564 -270.301124)
			(xy 129.103102 -270.322222) (xy 129.055831 -270.335914) (xy 129.006976 -270.341846) (xy 128.957801 -270.339865)
			(xy 128.909582 -270.330021) (xy 128.863566 -270.312569) (xy 128.820945 -270.287962) (xy 128.782824 -270.256837)
			(xy 128.750189 -270.22) (xy 128.723886 -270.178404) (xy 128.704595 -270.133128) (xy 128.692818 -270.085344)
			(xy 128.688858 -270.03629) (xy 128.370584 -270.03629) (xy 128.370072 -270.061736) (xy 128.361908 -270.11197)
			(xy 128.345792 -270.160244) (xy 128.322141 -270.205307) (xy 128.291568 -270.245993) (xy 128.254864 -270.281248)
			(xy 128.21298 -270.310158) (xy 128.167001 -270.331975) (xy 128.118117 -270.346135) (xy 128.067596 -270.352269)
			(xy 128.016744 -270.35022) (xy 127.96688 -270.34004) (xy 127.919294 -270.321993) (xy 127.87522 -270.296547)
			(xy 127.835798 -270.26436) (xy 127.80205 -270.226266) (xy 127.774849 -270.183252) (xy 127.754901 -270.136432)
			(xy 127.742722 -270.087018) (xy 127.738627 -270.03629) (xy 127.420116 -270.03629) (xy 127.419621 -270.060897)
			(xy 127.411726 -270.109474) (xy 127.396142 -270.156155) (xy 127.373271 -270.199732) (xy 127.343706 -270.239076)
			(xy 127.308213 -270.273168) (xy 127.26771 -270.301124) (xy 127.223248 -270.322222) (xy 127.175977 -270.335914)
			(xy 127.127122 -270.341846) (xy 127.077947 -270.339865) (xy 127.029728 -270.330021) (xy 126.983712 -270.312569)
			(xy 126.941091 -270.287962) (xy 126.90297 -270.256837) (xy 126.870335 -270.22) (xy 126.844032 -270.178404)
			(xy 126.824741 -270.133128) (xy 126.812964 -270.085344) (xy 126.809004 -270.03629) (xy 126.480062 -270.03629)
			(xy 126.479567 -270.060897) (xy 126.471672 -270.109474) (xy 126.456088 -270.156155) (xy 126.433217 -270.199732)
			(xy 126.403652 -270.239076) (xy 126.368159 -270.273168) (xy 126.327656 -270.301124) (xy 126.283194 -270.322222)
			(xy 126.235923 -270.335914) (xy 126.187068 -270.341846) (xy 126.137893 -270.339865) (xy 126.089674 -270.330021)
			(xy 126.043658 -270.312569) (xy 126.001037 -270.287962) (xy 125.962916 -270.256837) (xy 125.930281 -270.22)
			(xy 125.903978 -270.178404) (xy 125.884687 -270.133128) (xy 125.87291 -270.085344) (xy 125.86895 -270.03629)
			(xy 125.540008 -270.03629) (xy 125.539513 -270.060897) (xy 125.531618 -270.109474) (xy 125.516034 -270.156155)
			(xy 125.493163 -270.199732) (xy 125.463598 -270.239076) (xy 125.428105 -270.273168) (xy 125.387602 -270.301124)
			(xy 125.34314 -270.322222) (xy 125.295869 -270.335914) (xy 125.247014 -270.341846) (xy 125.197839 -270.339865)
			(xy 125.14962 -270.330021) (xy 125.103604 -270.312569) (xy 125.060983 -270.287962) (xy 125.022862 -270.256837)
			(xy 124.990227 -270.22) (xy 124.963924 -270.178404) (xy 124.944633 -270.133128) (xy 124.932856 -270.085344)
			(xy 124.928896 -270.03629) (xy 124.599954 -270.03629) (xy 124.599459 -270.060897) (xy 124.591564 -270.109474)
			(xy 124.57598 -270.156155) (xy 124.553109 -270.199732) (xy 124.523544 -270.239076) (xy 124.488051 -270.273168)
			(xy 124.447548 -270.301124) (xy 124.403086 -270.322222) (xy 124.355815 -270.335914) (xy 124.30696 -270.341846)
			(xy 124.257785 -270.339865) (xy 124.209566 -270.330021) (xy 124.16355 -270.312569) (xy 124.120929 -270.287962)
			(xy 124.082808 -270.256837) (xy 124.050173 -270.22) (xy 124.02387 -270.178404) (xy 124.004579 -270.133128)
			(xy 123.992802 -270.085344) (xy 123.988842 -270.03629) (xy 123.660154 -270.03629) (xy 123.659659 -270.060897)
			(xy 123.651764 -270.109474) (xy 123.63618 -270.156155) (xy 123.613309 -270.199732) (xy 123.583744 -270.239076)
			(xy 123.548251 -270.273168) (xy 123.507748 -270.301124) (xy 123.463286 -270.322222) (xy 123.416015 -270.335914)
			(xy 123.36716 -270.341846) (xy 123.317985 -270.339865) (xy 123.269766 -270.330021) (xy 123.22375 -270.312569)
			(xy 123.181129 -270.287962) (xy 123.143008 -270.256837) (xy 123.110373 -270.22) (xy 123.08407 -270.178404)
			(xy 123.064779 -270.133128) (xy 123.053002 -270.085344) (xy 123.049042 -270.03629) (xy 122.7201 -270.03629)
			(xy 122.719605 -270.060897) (xy 122.71171 -270.109474) (xy 122.696126 -270.156155) (xy 122.673255 -270.199732)
			(xy 122.64369 -270.239076) (xy 122.608197 -270.273168) (xy 122.567694 -270.301124) (xy 122.523232 -270.322222)
			(xy 122.475961 -270.335914) (xy 122.427106 -270.341846) (xy 122.377931 -270.339865) (xy 122.329712 -270.330021)
			(xy 122.283696 -270.312569) (xy 122.241075 -270.287962) (xy 122.202954 -270.256837) (xy 122.170319 -270.22)
			(xy 122.144016 -270.178404) (xy 122.124725 -270.133128) (xy 122.112948 -270.085344) (xy 122.108988 -270.03629)
			(xy 121.780046 -270.03629) (xy 121.779551 -270.060897) (xy 121.771656 -270.109474) (xy 121.756072 -270.156155)
			(xy 121.733201 -270.199732) (xy 121.703636 -270.239076) (xy 121.668143 -270.273168) (xy 121.62764 -270.301124)
			(xy 121.583178 -270.322222) (xy 121.535907 -270.335914) (xy 121.487052 -270.341846) (xy 121.437877 -270.339865)
			(xy 121.389658 -270.330021) (xy 121.343642 -270.312569) (xy 121.301021 -270.287962) (xy 121.2629 -270.256837)
			(xy 121.230265 -270.22) (xy 121.203962 -270.178404) (xy 121.184671 -270.133128) (xy 121.172894 -270.085344)
			(xy 121.168934 -270.03629) (xy 120.839992 -270.03629) (xy 120.839497 -270.060897) (xy 120.831602 -270.109474)
			(xy 120.816018 -270.156155) (xy 120.793147 -270.199732) (xy 120.763582 -270.239076) (xy 120.728089 -270.273168)
			(xy 120.687586 -270.301124) (xy 120.643124 -270.322222) (xy 120.595853 -270.335914) (xy 120.546998 -270.341846)
			(xy 120.497823 -270.339865) (xy 120.449604 -270.330021) (xy 120.403588 -270.312569) (xy 120.360967 -270.287962)
			(xy 120.322846 -270.256837) (xy 120.290211 -270.22) (xy 120.263908 -270.178404) (xy 120.244617 -270.133128)
			(xy 120.23284 -270.085344) (xy 120.22888 -270.03629) (xy 119.899938 -270.03629) (xy 119.899443 -270.060897)
			(xy 119.891548 -270.109474) (xy 119.875964 -270.156155) (xy 119.853093 -270.199732) (xy 119.823528 -270.239076)
			(xy 119.788035 -270.273168) (xy 119.747532 -270.301124) (xy 119.70307 -270.322222) (xy 119.655799 -270.335914)
			(xy 119.606944 -270.341846) (xy 119.557769 -270.339865) (xy 119.50955 -270.330021) (xy 119.463534 -270.312569)
			(xy 119.420913 -270.287962) (xy 119.382792 -270.256837) (xy 119.350157 -270.22) (xy 119.323854 -270.178404)
			(xy 119.304563 -270.133128) (xy 119.292786 -270.085344) (xy 119.288826 -270.03629) (xy 118.960138 -270.03629)
			(xy 118.959643 -270.060897) (xy 118.951748 -270.109474) (xy 118.936164 -270.156155) (xy 118.913293 -270.199732)
			(xy 118.883728 -270.239076) (xy 118.848235 -270.273168) (xy 118.807732 -270.301124) (xy 118.76327 -270.322222)
			(xy 118.715999 -270.335914) (xy 118.667144 -270.341846) (xy 118.617969 -270.339865) (xy 118.56975 -270.330021)
			(xy 118.523734 -270.312569) (xy 118.481113 -270.287962) (xy 118.442992 -270.256837) (xy 118.410357 -270.22)
			(xy 118.384054 -270.178404) (xy 118.364763 -270.133128) (xy 118.352986 -270.085344) (xy 118.349026 -270.03629)
			(xy 118.020084 -270.03629) (xy 118.019589 -270.060897) (xy 118.011694 -270.109474) (xy 117.99611 -270.156155)
			(xy 117.973239 -270.199732) (xy 117.943674 -270.239076) (xy 117.908181 -270.273168) (xy 117.867678 -270.301124)
			(xy 117.823216 -270.322222) (xy 117.775945 -270.335914) (xy 117.72709 -270.341846) (xy 117.677915 -270.339865)
			(xy 117.629696 -270.330021) (xy 117.58368 -270.312569) (xy 117.541059 -270.287962) (xy 117.502938 -270.256837)
			(xy 117.470303 -270.22) (xy 117.444 -270.178404) (xy 117.424709 -270.133128) (xy 117.412932 -270.085344)
			(xy 117.408972 -270.03629) (xy 117.08003 -270.03629) (xy 117.079535 -270.060897) (xy 117.07164 -270.109474)
			(xy 117.056056 -270.156155) (xy 117.033185 -270.199732) (xy 117.00362 -270.239076) (xy 116.968127 -270.273168)
			(xy 116.927624 -270.301124) (xy 116.883162 -270.322222) (xy 116.835891 -270.335914) (xy 116.787036 -270.341846)
			(xy 116.737861 -270.339865) (xy 116.689642 -270.330021) (xy 116.643626 -270.312569) (xy 116.601005 -270.287962)
			(xy 116.562884 -270.256837) (xy 116.530249 -270.22) (xy 116.503946 -270.178404) (xy 116.484655 -270.133128)
			(xy 116.472878 -270.085344) (xy 116.468918 -270.03629) (xy 116.139976 -270.03629) (xy 116.139481 -270.060897)
			(xy 116.131586 -270.109474) (xy 116.116002 -270.156155) (xy 116.093131 -270.199732) (xy 116.063566 -270.239076)
			(xy 116.028073 -270.273168) (xy 115.98757 -270.301124) (xy 115.943108 -270.322222) (xy 115.895837 -270.335914)
			(xy 115.846982 -270.341846) (xy 115.797807 -270.339865) (xy 115.749588 -270.330021) (xy 115.703572 -270.312569)
			(xy 115.660951 -270.287962) (xy 115.62283 -270.256837) (xy 115.590195 -270.22) (xy 115.563892 -270.178404)
			(xy 115.544601 -270.133128) (xy 115.532824 -270.085344) (xy 115.528864 -270.03629) (xy 115.199922 -270.03629)
			(xy 115.199427 -270.060897) (xy 115.191532 -270.109474) (xy 115.175948 -270.156155) (xy 115.153077 -270.199732)
			(xy 115.123512 -270.239076) (xy 115.088019 -270.273168) (xy 115.047516 -270.301124) (xy 115.003054 -270.322222)
			(xy 114.955783 -270.335914) (xy 114.906928 -270.341846) (xy 114.857753 -270.339865) (xy 114.809534 -270.330021)
			(xy 114.763518 -270.312569) (xy 114.720897 -270.287962) (xy 114.682776 -270.256837) (xy 114.650141 -270.22)
			(xy 114.623838 -270.178404) (xy 114.604547 -270.133128) (xy 114.59277 -270.085344) (xy 114.58881 -270.03629)
			(xy 114.260122 -270.03629) (xy 114.259627 -270.060897) (xy 114.251732 -270.109474) (xy 114.236148 -270.156155)
			(xy 114.213277 -270.199732) (xy 114.183712 -270.239076) (xy 114.148219 -270.273168) (xy 114.107716 -270.301124)
			(xy 114.063254 -270.322222) (xy 114.015983 -270.335914) (xy 113.967128 -270.341846) (xy 113.917953 -270.339865)
			(xy 113.869734 -270.330021) (xy 113.823718 -270.312569) (xy 113.781097 -270.287962) (xy 113.742976 -270.256837)
			(xy 113.710341 -270.22) (xy 113.684038 -270.178404) (xy 113.664747 -270.133128) (xy 113.65297 -270.085344)
			(xy 113.64901 -270.03629) (xy 110.506256 -270.03629) (xy 110.505761 -270.060897) (xy 110.497866 -270.109474)
			(xy 110.482282 -270.156155) (xy 110.459411 -270.199732) (xy 110.429846 -270.239076) (xy 110.394353 -270.273168)
			(xy 110.35385 -270.301124) (xy 110.309388 -270.322222) (xy 110.262117 -270.335914) (xy 110.213262 -270.341846)
			(xy 110.164087 -270.339865) (xy 110.115868 -270.330021) (xy 110.069852 -270.312569) (xy 110.027231 -270.287962)
			(xy 109.98911 -270.256837) (xy 109.956475 -270.22) (xy 109.930172 -270.178404) (xy 109.910881 -270.133128)
			(xy 109.899104 -270.085344) (xy 109.895144 -270.03629) (xy 109.566456 -270.03629) (xy 109.565961 -270.060897)
			(xy 109.558066 -270.109474) (xy 109.542482 -270.156155) (xy 109.519611 -270.199732) (xy 109.490046 -270.239076)
			(xy 109.454553 -270.273168) (xy 109.41405 -270.301124) (xy 109.369588 -270.322222) (xy 109.322317 -270.335914)
			(xy 109.273462 -270.341846) (xy 109.224287 -270.339865) (xy 109.176068 -270.330021) (xy 109.130052 -270.312569)
			(xy 109.087431 -270.287962) (xy 109.04931 -270.256837) (xy 109.016675 -270.22) (xy 108.990372 -270.178404)
			(xy 108.971081 -270.133128) (xy 108.959304 -270.085344) (xy 108.955344 -270.03629) (xy 108.626402 -270.03629)
			(xy 108.625907 -270.060897) (xy 108.618012 -270.109474) (xy 108.602428 -270.156155) (xy 108.579557 -270.199732)
			(xy 108.549992 -270.239076) (xy 108.514499 -270.273168) (xy 108.473996 -270.301124) (xy 108.429534 -270.322222)
			(xy 108.382263 -270.335914) (xy 108.333408 -270.341846) (xy 108.284233 -270.339865) (xy 108.236014 -270.330021)
			(xy 108.189998 -270.312569) (xy 108.147377 -270.287962) (xy 108.109256 -270.256837) (xy 108.076621 -270.22)
			(xy 108.050318 -270.178404) (xy 108.031027 -270.133128) (xy 108.01925 -270.085344) (xy 108.01529 -270.03629)
			(xy 107.686348 -270.03629) (xy 107.685853 -270.060897) (xy 107.677958 -270.109474) (xy 107.662374 -270.156155)
			(xy 107.639503 -270.199732) (xy 107.609938 -270.239076) (xy 107.574445 -270.273168) (xy 107.533942 -270.301124)
			(xy 107.48948 -270.322222) (xy 107.442209 -270.335914) (xy 107.393354 -270.341846) (xy 107.344179 -270.339865)
			(xy 107.29596 -270.330021) (xy 107.249944 -270.312569) (xy 107.207323 -270.287962) (xy 107.169202 -270.256837)
			(xy 107.136567 -270.22) (xy 107.110264 -270.178404) (xy 107.090973 -270.133128) (xy 107.079196 -270.085344)
			(xy 107.075236 -270.03629) (xy 106.746294 -270.03629) (xy 106.745799 -270.060897) (xy 106.737904 -270.109474)
			(xy 106.72232 -270.156155) (xy 106.699449 -270.199732) (xy 106.669884 -270.239076) (xy 106.634391 -270.273168)
			(xy 106.593888 -270.301124) (xy 106.549426 -270.322222) (xy 106.502155 -270.335914) (xy 106.4533 -270.341846)
			(xy 106.404125 -270.339865) (xy 106.355906 -270.330021) (xy 106.30989 -270.312569) (xy 106.267269 -270.287962)
			(xy 106.229148 -270.256837) (xy 106.196513 -270.22) (xy 106.17021 -270.178404) (xy 106.150919 -270.133128)
			(xy 106.139142 -270.085344) (xy 106.135182 -270.03629) (xy 105.80624 -270.03629) (xy 105.805745 -270.060897)
			(xy 105.79785 -270.109474) (xy 105.782266 -270.156155) (xy 105.759395 -270.199732) (xy 105.72983 -270.239076)
			(xy 105.694337 -270.273168) (xy 105.653834 -270.301124) (xy 105.609372 -270.322222) (xy 105.562101 -270.335914)
			(xy 105.513246 -270.341846) (xy 105.464071 -270.339865) (xy 105.415852 -270.330021) (xy 105.369836 -270.312569)
			(xy 105.327215 -270.287962) (xy 105.289094 -270.256837) (xy 105.256459 -270.22) (xy 105.230156 -270.178404)
			(xy 105.210865 -270.133128) (xy 105.199088 -270.085344) (xy 105.195128 -270.03629) (xy 104.86644 -270.03629)
			(xy 104.865945 -270.060897) (xy 104.85805 -270.109474) (xy 104.842466 -270.156155) (xy 104.819595 -270.199732)
			(xy 104.79003 -270.239076) (xy 104.754537 -270.273168) (xy 104.714034 -270.301124) (xy 104.669572 -270.322222)
			(xy 104.622301 -270.335914) (xy 104.573446 -270.341846) (xy 104.524271 -270.339865) (xy 104.476052 -270.330021)
			(xy 104.430036 -270.312569) (xy 104.387415 -270.287962) (xy 104.349294 -270.256837) (xy 104.316659 -270.22)
			(xy 104.290356 -270.178404) (xy 104.271065 -270.133128) (xy 104.259288 -270.085344) (xy 104.255328 -270.03629)
			(xy 103.926386 -270.03629) (xy 103.925891 -270.060897) (xy 103.917996 -270.109474) (xy 103.902412 -270.156155)
			(xy 103.879541 -270.199732) (xy 103.849976 -270.239076) (xy 103.814483 -270.273168) (xy 103.77398 -270.301124)
			(xy 103.729518 -270.322222) (xy 103.682247 -270.335914) (xy 103.633392 -270.341846) (xy 103.584217 -270.339865)
			(xy 103.535998 -270.330021) (xy 103.489982 -270.312569) (xy 103.447361 -270.287962) (xy 103.40924 -270.256837)
			(xy 103.376605 -270.22) (xy 103.350302 -270.178404) (xy 103.331011 -270.133128) (xy 103.319234 -270.085344)
			(xy 103.315274 -270.03629) (xy 102.986332 -270.03629) (xy 102.985837 -270.060897) (xy 102.977942 -270.109474)
			(xy 102.962358 -270.156155) (xy 102.939487 -270.199732) (xy 102.909922 -270.239076) (xy 102.874429 -270.273168)
			(xy 102.833926 -270.301124) (xy 102.789464 -270.322222) (xy 102.742193 -270.335914) (xy 102.693338 -270.341846)
			(xy 102.644163 -270.339865) (xy 102.595944 -270.330021) (xy 102.549928 -270.312569) (xy 102.507307 -270.287962)
			(xy 102.469186 -270.256837) (xy 102.436551 -270.22) (xy 102.410248 -270.178404) (xy 102.390957 -270.133128)
			(xy 102.37918 -270.085344) (xy 102.37522 -270.03629) (xy 102.046278 -270.03629) (xy 102.045783 -270.060897)
			(xy 102.037888 -270.109474) (xy 102.022304 -270.156155) (xy 101.999433 -270.199732) (xy 101.969868 -270.239076)
			(xy 101.934375 -270.273168) (xy 101.893872 -270.301124) (xy 101.84941 -270.322222) (xy 101.802139 -270.335914)
			(xy 101.753284 -270.341846) (xy 101.704109 -270.339865) (xy 101.65589 -270.330021) (xy 101.609874 -270.312569)
			(xy 101.567253 -270.287962) (xy 101.529132 -270.256837) (xy 101.496497 -270.22) (xy 101.470194 -270.178404)
			(xy 101.450903 -270.133128) (xy 101.439126 -270.085344) (xy 101.435166 -270.03629) (xy 101.106478 -270.03629)
			(xy 101.105983 -270.060897) (xy 101.098088 -270.109474) (xy 101.082504 -270.156155) (xy 101.059633 -270.199732)
			(xy 101.030068 -270.239076) (xy 100.994575 -270.273168) (xy 100.954072 -270.301124) (xy 100.90961 -270.322222)
			(xy 100.862339 -270.335914) (xy 100.813484 -270.341846) (xy 100.764309 -270.339865) (xy 100.71609 -270.330021)
			(xy 100.670074 -270.312569) (xy 100.627453 -270.287962) (xy 100.589332 -270.256837) (xy 100.556697 -270.22)
			(xy 100.530394 -270.178404) (xy 100.511103 -270.133128) (xy 100.499326 -270.085344) (xy 100.495366 -270.03629)
			(xy 100.166424 -270.03629) (xy 100.165929 -270.060897) (xy 100.158034 -270.109474) (xy 100.14245 -270.156155)
			(xy 100.119579 -270.199732) (xy 100.090014 -270.239076) (xy 100.054521 -270.273168) (xy 100.014018 -270.301124)
			(xy 99.969556 -270.322222) (xy 99.922285 -270.335914) (xy 99.87343 -270.341846) (xy 99.824255 -270.339865)
			(xy 99.776036 -270.330021) (xy 99.73002 -270.312569) (xy 99.687399 -270.287962) (xy 99.649278 -270.256837)
			(xy 99.616643 -270.22) (xy 99.59034 -270.178404) (xy 99.571049 -270.133128) (xy 99.559272 -270.085344)
			(xy 99.555312 -270.03629) (xy 99.22637 -270.03629) (xy 99.225875 -270.060897) (xy 99.21798 -270.109474)
			(xy 99.202396 -270.156155) (xy 99.179525 -270.199732) (xy 99.14996 -270.239076) (xy 99.114467 -270.273168)
			(xy 99.073964 -270.301124) (xy 99.029502 -270.322222) (xy 98.982231 -270.335914) (xy 98.933376 -270.341846)
			(xy 98.884201 -270.339865) (xy 98.835982 -270.330021) (xy 98.789966 -270.312569) (xy 98.747345 -270.287962)
			(xy 98.709224 -270.256837) (xy 98.676589 -270.22) (xy 98.650286 -270.178404) (xy 98.630995 -270.133128)
			(xy 98.619218 -270.085344) (xy 98.615258 -270.03629) (xy 98.286316 -270.03629) (xy 98.285821 -270.060897)
			(xy 98.277926 -270.109474) (xy 98.262342 -270.156155) (xy 98.239471 -270.199732) (xy 98.209906 -270.239076)
			(xy 98.174413 -270.273168) (xy 98.13391 -270.301124) (xy 98.089448 -270.322222) (xy 98.042177 -270.335914)
			(xy 97.993322 -270.341846) (xy 97.944147 -270.339865) (xy 97.895928 -270.330021) (xy 97.849912 -270.312569)
			(xy 97.807291 -270.287962) (xy 97.76917 -270.256837) (xy 97.736535 -270.22) (xy 97.710232 -270.178404)
			(xy 97.690941 -270.133128) (xy 97.679164 -270.085344) (xy 97.675204 -270.03629) (xy 97.38614 -270.03629)
			(xy 97.38614 -270.439896) (xy 97.386649 -270.450318) (xy 97.394912 -270.469456) (xy 97.402142 -270.47698)
			(xy 97.463356 -270.534892) (xy 97.483168 -270.542004) (xy 97.493582 -270.541496) (xy 97.511108 -270.540988)
			(xy 97.536363 -270.54151) (xy 97.586185 -270.549825) (xy 97.633958 -270.566227) (xy 97.67838 -270.590268)
			(xy 97.71824 -270.621293) (xy 97.752449 -270.658455) (xy 97.780075 -270.700741) (xy 97.800365 -270.746997)
			(xy 97.812764 -270.795962) (xy 97.816935 -270.846296) (xy 98.145358 -270.846296) (xy 98.149318 -270.797242)
			(xy 98.161095 -270.749458) (xy 98.180386 -270.704182) (xy 98.206689 -270.662586) (xy 98.239324 -270.625749)
			(xy 98.277445 -270.594624) (xy 98.320066 -270.570017) (xy 98.366082 -270.552565) (xy 98.414301 -270.542721)
			(xy 98.463476 -270.54074) (xy 98.512331 -270.546672) (xy 98.559602 -270.560364) (xy 98.604064 -270.581462)
			(xy 98.644567 -270.609418) (xy 98.68006 -270.64351) (xy 98.709625 -270.682854) (xy 98.732496 -270.726431)
			(xy 98.74808 -270.773112) (xy 98.755975 -270.821689) (xy 98.75647 -270.846296) (xy 99.085158 -270.846296)
			(xy 99.089118 -270.797242) (xy 99.100895 -270.749458) (xy 99.120186 -270.704182) (xy 99.146489 -270.662586)
			(xy 99.179124 -270.625749) (xy 99.217245 -270.594624) (xy 99.259866 -270.570017) (xy 99.305882 -270.552565)
			(xy 99.354101 -270.542721) (xy 99.403276 -270.54074) (xy 99.452131 -270.546672) (xy 99.499402 -270.560364)
			(xy 99.543864 -270.581462) (xy 99.584367 -270.609418) (xy 99.61986 -270.64351) (xy 99.649425 -270.682854)
			(xy 99.672296 -270.726431) (xy 99.68788 -270.773112) (xy 99.695775 -270.821689) (xy 99.69627 -270.846296)
			(xy 100.025212 -270.846296) (xy 100.029172 -270.797242) (xy 100.040949 -270.749458) (xy 100.06024 -270.704182)
			(xy 100.086543 -270.662586) (xy 100.119178 -270.625749) (xy 100.157299 -270.594624) (xy 100.19992 -270.570017)
			(xy 100.245936 -270.552565) (xy 100.294155 -270.542721) (xy 100.34333 -270.54074) (xy 100.392185 -270.546672)
			(xy 100.439456 -270.560364) (xy 100.483918 -270.581462) (xy 100.524421 -270.609418) (xy 100.559914 -270.64351)
			(xy 100.589479 -270.682854) (xy 100.61235 -270.726431) (xy 100.627934 -270.773112) (xy 100.635829 -270.821689)
			(xy 100.636324 -270.846296) (xy 100.965266 -270.846296) (xy 100.969226 -270.797242) (xy 100.981003 -270.749458)
			(xy 101.000294 -270.704182) (xy 101.026597 -270.662586) (xy 101.059232 -270.625749) (xy 101.097353 -270.594624)
			(xy 101.139974 -270.570017) (xy 101.18599 -270.552565) (xy 101.234209 -270.542721) (xy 101.283384 -270.54074)
			(xy 101.332239 -270.546672) (xy 101.37951 -270.560364) (xy 101.423972 -270.581462) (xy 101.464475 -270.609418)
			(xy 101.499968 -270.64351) (xy 101.529533 -270.682854) (xy 101.552404 -270.726431) (xy 101.567988 -270.773112)
			(xy 101.575883 -270.821689) (xy 101.576378 -270.846296) (xy 101.90532 -270.846296) (xy 101.90928 -270.797242)
			(xy 101.921057 -270.749458) (xy 101.940348 -270.704182) (xy 101.966651 -270.662586) (xy 101.999286 -270.625749)
			(xy 102.037407 -270.594624) (xy 102.080028 -270.570017) (xy 102.126044 -270.552565) (xy 102.174263 -270.542721)
			(xy 102.223438 -270.54074) (xy 102.272293 -270.546672) (xy 102.319564 -270.560364) (xy 102.364026 -270.581462)
			(xy 102.404529 -270.609418) (xy 102.440022 -270.64351) (xy 102.469587 -270.682854) (xy 102.492458 -270.726431)
			(xy 102.508042 -270.773112) (xy 102.515937 -270.821689) (xy 102.516432 -270.846296) (xy 102.845374 -270.846296)
			(xy 102.849334 -270.797242) (xy 102.861111 -270.749458) (xy 102.880402 -270.704182) (xy 102.906705 -270.662586)
			(xy 102.93934 -270.625749) (xy 102.977461 -270.594624) (xy 103.020082 -270.570017) (xy 103.066098 -270.552565)
			(xy 103.114317 -270.542721) (xy 103.163492 -270.54074) (xy 103.212347 -270.546672) (xy 103.259618 -270.560364)
			(xy 103.30408 -270.581462) (xy 103.344583 -270.609418) (xy 103.380076 -270.64351) (xy 103.409641 -270.682854)
			(xy 103.432512 -270.726431) (xy 103.448096 -270.773112) (xy 103.455991 -270.821689) (xy 103.456486 -270.846296)
			(xy 103.785174 -270.846296) (xy 103.789134 -270.797242) (xy 103.800911 -270.749458) (xy 103.820202 -270.704182)
			(xy 103.846505 -270.662586) (xy 103.87914 -270.625749) (xy 103.917261 -270.594624) (xy 103.959882 -270.570017)
			(xy 104.005898 -270.552565) (xy 104.054117 -270.542721) (xy 104.103292 -270.54074) (xy 104.152147 -270.546672)
			(xy 104.199418 -270.560364) (xy 104.24388 -270.581462) (xy 104.284383 -270.609418) (xy 104.319876 -270.64351)
			(xy 104.349441 -270.682854) (xy 104.372312 -270.726431) (xy 104.387896 -270.773112) (xy 104.395791 -270.821689)
			(xy 104.396286 -270.846296) (xy 104.725228 -270.846296) (xy 104.729188 -270.797242) (xy 104.740965 -270.749458)
			(xy 104.760256 -270.704182) (xy 104.786559 -270.662586) (xy 104.819194 -270.625749) (xy 104.857315 -270.594624)
			(xy 104.899936 -270.570017) (xy 104.945952 -270.552565) (xy 104.994171 -270.542721) (xy 105.043346 -270.54074)
			(xy 105.092201 -270.546672) (xy 105.139472 -270.560364) (xy 105.183934 -270.581462) (xy 105.224437 -270.609418)
			(xy 105.25993 -270.64351) (xy 105.289495 -270.682854) (xy 105.312366 -270.726431) (xy 105.32795 -270.773112)
			(xy 105.335845 -270.821689) (xy 105.33634 -270.846296) (xy 105.665282 -270.846296) (xy 105.669242 -270.797242)
			(xy 105.681019 -270.749458) (xy 105.70031 -270.704182) (xy 105.726613 -270.662586) (xy 105.759248 -270.625749)
			(xy 105.797369 -270.594624) (xy 105.83999 -270.570017) (xy 105.886006 -270.552565) (xy 105.934225 -270.542721)
			(xy 105.9834 -270.54074) (xy 106.032255 -270.546672) (xy 106.079526 -270.560364) (xy 106.123988 -270.581462)
			(xy 106.164491 -270.609418) (xy 106.199984 -270.64351) (xy 106.229549 -270.682854) (xy 106.25242 -270.726431)
			(xy 106.268004 -270.773112) (xy 106.275899 -270.821689) (xy 106.276394 -270.846296) (xy 106.605336 -270.846296)
			(xy 106.609296 -270.797242) (xy 106.621073 -270.749458) (xy 106.640364 -270.704182) (xy 106.666667 -270.662586)
			(xy 106.699302 -270.625749) (xy 106.737423 -270.594624) (xy 106.780044 -270.570017) (xy 106.82606 -270.552565)
			(xy 106.874279 -270.542721) (xy 106.923454 -270.54074) (xy 106.972309 -270.546672) (xy 107.01958 -270.560364)
			(xy 107.064042 -270.581462) (xy 107.104545 -270.609418) (xy 107.140038 -270.64351) (xy 107.169603 -270.682854)
			(xy 107.192474 -270.726431) (xy 107.208058 -270.773112) (xy 107.215953 -270.821689) (xy 107.216448 -270.846296)
			(xy 107.545136 -270.846296) (xy 107.549096 -270.797242) (xy 107.560873 -270.749458) (xy 107.580164 -270.704182)
			(xy 107.606467 -270.662586) (xy 107.639102 -270.625749) (xy 107.677223 -270.594624) (xy 107.719844 -270.570017)
			(xy 107.76586 -270.552565) (xy 107.814079 -270.542721) (xy 107.863254 -270.54074) (xy 107.912109 -270.546672)
			(xy 107.95938 -270.560364) (xy 108.003842 -270.581462) (xy 108.044345 -270.609418) (xy 108.079838 -270.64351)
			(xy 108.109403 -270.682854) (xy 108.132274 -270.726431) (xy 108.147858 -270.773112) (xy 108.155753 -270.821689)
			(xy 108.156248 -270.846296) (xy 108.48519 -270.846296) (xy 108.48915 -270.797242) (xy 108.500927 -270.749458)
			(xy 108.520218 -270.704182) (xy 108.546521 -270.662586) (xy 108.579156 -270.625749) (xy 108.617277 -270.594624)
			(xy 108.659898 -270.570017) (xy 108.705914 -270.552565) (xy 108.754133 -270.542721) (xy 108.803308 -270.54074)
			(xy 108.852163 -270.546672) (xy 108.899434 -270.560364) (xy 108.943896 -270.581462) (xy 108.984399 -270.609418)
			(xy 109.019892 -270.64351) (xy 109.049457 -270.682854) (xy 109.072328 -270.726431) (xy 109.087912 -270.773112)
			(xy 109.095807 -270.821689) (xy 109.096302 -270.846296) (xy 109.425244 -270.846296) (xy 109.429204 -270.797242)
			(xy 109.440981 -270.749458) (xy 109.460272 -270.704182) (xy 109.486575 -270.662586) (xy 109.51921 -270.625749)
			(xy 109.557331 -270.594624) (xy 109.599952 -270.570017) (xy 109.645968 -270.552565) (xy 109.694187 -270.542721)
			(xy 109.743362 -270.54074) (xy 109.792217 -270.546672) (xy 109.839488 -270.560364) (xy 109.88395 -270.581462)
			(xy 109.924453 -270.609418) (xy 109.959946 -270.64351) (xy 109.989511 -270.682854) (xy 110.012382 -270.726431)
			(xy 110.027966 -270.773112) (xy 110.035861 -270.821689) (xy 110.036356 -270.846296) (xy 110.365298 -270.846296)
			(xy 110.369258 -270.797242) (xy 110.381035 -270.749458) (xy 110.400326 -270.704182) (xy 110.426629 -270.662586)
			(xy 110.459264 -270.625749) (xy 110.497385 -270.594624) (xy 110.540006 -270.570017) (xy 110.586022 -270.552565)
			(xy 110.634241 -270.542721) (xy 110.683416 -270.54074) (xy 110.732271 -270.546672) (xy 110.779542 -270.560364)
			(xy 110.824004 -270.581462) (xy 110.864507 -270.609418) (xy 110.9 -270.64351) (xy 110.929565 -270.682854)
			(xy 110.952436 -270.726431) (xy 110.96802 -270.773112) (xy 110.975915 -270.821689) (xy 110.97641 -270.846296)
			(xy 113.178856 -270.846296) (xy 113.182816 -270.797242) (xy 113.194593 -270.749458) (xy 113.213884 -270.704182)
			(xy 113.240187 -270.662586) (xy 113.272822 -270.625749) (xy 113.310943 -270.594624) (xy 113.353564 -270.570017)
			(xy 113.39958 -270.552565) (xy 113.447799 -270.542721) (xy 113.496974 -270.54074) (xy 113.545829 -270.546672)
			(xy 113.5931 -270.560364) (xy 113.637562 -270.581462) (xy 113.678065 -270.609418) (xy 113.713558 -270.64351)
			(xy 113.743123 -270.682854) (xy 113.765994 -270.726431) (xy 113.781578 -270.773112) (xy 113.789473 -270.821689)
			(xy 113.789968 -270.846296) (xy 114.11891 -270.846296) (xy 114.12287 -270.797242) (xy 114.134647 -270.749458)
			(xy 114.153938 -270.704182) (xy 114.180241 -270.662586) (xy 114.212876 -270.625749) (xy 114.250997 -270.594624)
			(xy 114.293618 -270.570017) (xy 114.339634 -270.552565) (xy 114.387853 -270.542721) (xy 114.437028 -270.54074)
			(xy 114.485883 -270.546672) (xy 114.533154 -270.560364) (xy 114.577616 -270.581462) (xy 114.618119 -270.609418)
			(xy 114.653612 -270.64351) (xy 114.683177 -270.682854) (xy 114.706048 -270.726431) (xy 114.721632 -270.773112)
			(xy 114.729527 -270.821689) (xy 114.730022 -270.846296) (xy 115.058964 -270.846296) (xy 115.062924 -270.797242)
			(xy 115.074701 -270.749458) (xy 115.093992 -270.704182) (xy 115.120295 -270.662586) (xy 115.15293 -270.625749)
			(xy 115.191051 -270.594624) (xy 115.233672 -270.570017) (xy 115.279688 -270.552565) (xy 115.327907 -270.542721)
			(xy 115.377082 -270.54074) (xy 115.425937 -270.546672) (xy 115.473208 -270.560364) (xy 115.51767 -270.581462)
			(xy 115.558173 -270.609418) (xy 115.593666 -270.64351) (xy 115.623231 -270.682854) (xy 115.646102 -270.726431)
			(xy 115.661686 -270.773112) (xy 115.669581 -270.821689) (xy 115.670076 -270.846296) (xy 115.999018 -270.846296)
			(xy 116.002978 -270.797242) (xy 116.014755 -270.749458) (xy 116.034046 -270.704182) (xy 116.060349 -270.662586)
			(xy 116.092984 -270.625749) (xy 116.131105 -270.594624) (xy 116.173726 -270.570017) (xy 116.219742 -270.552565)
			(xy 116.267961 -270.542721) (xy 116.317136 -270.54074) (xy 116.365991 -270.546672) (xy 116.413262 -270.560364)
			(xy 116.457724 -270.581462) (xy 116.498227 -270.609418) (xy 116.53372 -270.64351) (xy 116.563285 -270.682854)
			(xy 116.586156 -270.726431) (xy 116.60174 -270.773112) (xy 116.609635 -270.821689) (xy 116.61013 -270.846296)
			(xy 116.938818 -270.846296) (xy 116.942778 -270.797242) (xy 116.954555 -270.749458) (xy 116.973846 -270.704182)
			(xy 117.000149 -270.662586) (xy 117.032784 -270.625749) (xy 117.070905 -270.594624) (xy 117.113526 -270.570017)
			(xy 117.159542 -270.552565) (xy 117.207761 -270.542721) (xy 117.256936 -270.54074) (xy 117.305791 -270.546672)
			(xy 117.353062 -270.560364) (xy 117.397524 -270.581462) (xy 117.438027 -270.609418) (xy 117.47352 -270.64351)
			(xy 117.503085 -270.682854) (xy 117.525956 -270.726431) (xy 117.54154 -270.773112) (xy 117.549435 -270.821689)
			(xy 117.54993 -270.846296) (xy 117.878872 -270.846296) (xy 117.882832 -270.797242) (xy 117.894609 -270.749458)
			(xy 117.9139 -270.704182) (xy 117.940203 -270.662586) (xy 117.972838 -270.625749) (xy 118.010959 -270.594624)
			(xy 118.05358 -270.570017) (xy 118.099596 -270.552565) (xy 118.147815 -270.542721) (xy 118.19699 -270.54074)
			(xy 118.245845 -270.546672) (xy 118.293116 -270.560364) (xy 118.337578 -270.581462) (xy 118.378081 -270.609418)
			(xy 118.413574 -270.64351) (xy 118.443139 -270.682854) (xy 118.46601 -270.726431) (xy 118.481594 -270.773112)
			(xy 118.489489 -270.821689) (xy 118.489984 -270.846296) (xy 118.818926 -270.846296) (xy 118.822886 -270.797242)
			(xy 118.834663 -270.749458) (xy 118.853954 -270.704182) (xy 118.880257 -270.662586) (xy 118.912892 -270.625749)
			(xy 118.951013 -270.594624) (xy 118.993634 -270.570017) (xy 119.03965 -270.552565) (xy 119.087869 -270.542721)
			(xy 119.137044 -270.54074) (xy 119.185899 -270.546672) (xy 119.23317 -270.560364) (xy 119.277632 -270.581462)
			(xy 119.318135 -270.609418) (xy 119.353628 -270.64351) (xy 119.383193 -270.682854) (xy 119.406064 -270.726431)
			(xy 119.421648 -270.773112) (xy 119.429543 -270.821689) (xy 119.430038 -270.846296) (xy 119.75898 -270.846296)
			(xy 119.76294 -270.797242) (xy 119.774717 -270.749458) (xy 119.794008 -270.704182) (xy 119.820311 -270.662586)
			(xy 119.852946 -270.625749) (xy 119.891067 -270.594624) (xy 119.933688 -270.570017) (xy 119.979704 -270.552565)
			(xy 120.027923 -270.542721) (xy 120.077098 -270.54074) (xy 120.125953 -270.546672) (xy 120.173224 -270.560364)
			(xy 120.217686 -270.581462) (xy 120.258189 -270.609418) (xy 120.293682 -270.64351) (xy 120.323247 -270.682854)
			(xy 120.346118 -270.726431) (xy 120.361702 -270.773112) (xy 120.369597 -270.821689) (xy 120.370092 -270.846296)
			(xy 120.699034 -270.846296) (xy 120.702994 -270.797242) (xy 120.714771 -270.749458) (xy 120.734062 -270.704182)
			(xy 120.760365 -270.662586) (xy 120.793 -270.625749) (xy 120.831121 -270.594624) (xy 120.873742 -270.570017)
			(xy 120.919758 -270.552565) (xy 120.967977 -270.542721) (xy 121.017152 -270.54074) (xy 121.066007 -270.546672)
			(xy 121.113278 -270.560364) (xy 121.15774 -270.581462) (xy 121.198243 -270.609418) (xy 121.233736 -270.64351)
			(xy 121.263301 -270.682854) (xy 121.286172 -270.726431) (xy 121.301756 -270.773112) (xy 121.309651 -270.821689)
			(xy 121.310146 -270.846296) (xy 121.638834 -270.846296) (xy 121.642794 -270.797242) (xy 121.654571 -270.749458)
			(xy 121.673862 -270.704182) (xy 121.700165 -270.662586) (xy 121.7328 -270.625749) (xy 121.770921 -270.594624)
			(xy 121.813542 -270.570017) (xy 121.859558 -270.552565) (xy 121.907777 -270.542721) (xy 121.956952 -270.54074)
			(xy 122.005807 -270.546672) (xy 122.053078 -270.560364) (xy 122.09754 -270.581462) (xy 122.138043 -270.609418)
			(xy 122.173536 -270.64351) (xy 122.203101 -270.682854) (xy 122.225972 -270.726431) (xy 122.241556 -270.773112)
			(xy 122.249451 -270.821689) (xy 122.249946 -270.846296) (xy 122.578888 -270.846296) (xy 122.582848 -270.797242)
			(xy 122.594625 -270.749458) (xy 122.613916 -270.704182) (xy 122.640219 -270.662586) (xy 122.672854 -270.625749)
			(xy 122.710975 -270.594624) (xy 122.753596 -270.570017) (xy 122.799612 -270.552565) (xy 122.847831 -270.542721)
			(xy 122.897006 -270.54074) (xy 122.945861 -270.546672) (xy 122.993132 -270.560364) (xy 123.037594 -270.581462)
			(xy 123.078097 -270.609418) (xy 123.11359 -270.64351) (xy 123.143155 -270.682854) (xy 123.166026 -270.726431)
			(xy 123.18161 -270.773112) (xy 123.189505 -270.821689) (xy 123.19 -270.846296) (xy 123.518942 -270.846296)
			(xy 123.522902 -270.797242) (xy 123.534679 -270.749458) (xy 123.55397 -270.704182) (xy 123.580273 -270.662586)
			(xy 123.612908 -270.625749) (xy 123.651029 -270.594624) (xy 123.69365 -270.570017) (xy 123.739666 -270.552565)
			(xy 123.787885 -270.542721) (xy 123.83706 -270.54074) (xy 123.885915 -270.546672) (xy 123.933186 -270.560364)
			(xy 123.977648 -270.581462) (xy 124.018151 -270.609418) (xy 124.053644 -270.64351) (xy 124.083209 -270.682854)
			(xy 124.10608 -270.726431) (xy 124.121664 -270.773112) (xy 124.129559 -270.821689) (xy 124.130054 -270.846296)
			(xy 124.458996 -270.846296) (xy 124.462956 -270.797242) (xy 124.474733 -270.749458) (xy 124.494024 -270.704182)
			(xy 124.520327 -270.662586) (xy 124.552962 -270.625749) (xy 124.591083 -270.594624) (xy 124.633704 -270.570017)
			(xy 124.67972 -270.552565) (xy 124.727939 -270.542721) (xy 124.777114 -270.54074) (xy 124.825969 -270.546672)
			(xy 124.87324 -270.560364) (xy 124.917702 -270.581462) (xy 124.958205 -270.609418) (xy 124.993698 -270.64351)
			(xy 125.023263 -270.682854) (xy 125.046134 -270.726431) (xy 125.061718 -270.773112) (xy 125.069613 -270.821689)
			(xy 125.070108 -270.846296) (xy 125.39905 -270.846296) (xy 125.40301 -270.797242) (xy 125.414787 -270.749458)
			(xy 125.434078 -270.704182) (xy 125.460381 -270.662586) (xy 125.493016 -270.625749) (xy 125.531137 -270.594624)
			(xy 125.573758 -270.570017) (xy 125.619774 -270.552565) (xy 125.667993 -270.542721) (xy 125.717168 -270.54074)
			(xy 125.766023 -270.546672) (xy 125.813294 -270.560364) (xy 125.857756 -270.581462) (xy 125.898259 -270.609418)
			(xy 125.933752 -270.64351) (xy 125.963317 -270.682854) (xy 125.986188 -270.726431) (xy 126.001772 -270.773112)
			(xy 126.009667 -270.821689) (xy 126.010162 -270.846296) (xy 126.33885 -270.846296) (xy 126.34281 -270.797242)
			(xy 126.354587 -270.749458) (xy 126.373878 -270.704182) (xy 126.400181 -270.662586) (xy 126.432816 -270.625749)
			(xy 126.470937 -270.594624) (xy 126.513558 -270.570017) (xy 126.559574 -270.552565) (xy 126.607793 -270.542721)
			(xy 126.656968 -270.54074) (xy 126.705823 -270.546672) (xy 126.753094 -270.560364) (xy 126.797556 -270.581462)
			(xy 126.838059 -270.609418) (xy 126.873552 -270.64351) (xy 126.903117 -270.682854) (xy 126.925988 -270.726431)
			(xy 126.941572 -270.773112) (xy 126.949467 -270.821689) (xy 126.949962 -270.846296) (xy 127.278904 -270.846296)
			(xy 127.282864 -270.797242) (xy 127.294641 -270.749458) (xy 127.313932 -270.704182) (xy 127.340235 -270.662586)
			(xy 127.37287 -270.625749) (xy 127.410991 -270.594624) (xy 127.453612 -270.570017) (xy 127.499628 -270.552565)
			(xy 127.547847 -270.542721) (xy 127.597022 -270.54074) (xy 127.645877 -270.546672) (xy 127.693148 -270.560364)
			(xy 127.73761 -270.581462) (xy 127.778113 -270.609418) (xy 127.813606 -270.64351) (xy 127.843171 -270.682854)
			(xy 127.866042 -270.726431) (xy 127.881626 -270.773112) (xy 127.889521 -270.821689) (xy 127.890016 -270.846296)
			(xy 128.208527 -270.846296) (xy 128.212622 -270.795568) (xy 128.224801 -270.746154) (xy 128.244749 -270.699334)
			(xy 128.27195 -270.65632) (xy 128.305698 -270.618226) (xy 128.34512 -270.586039) (xy 128.389194 -270.560593)
			(xy 128.43678 -270.542546) (xy 128.486644 -270.532366) (xy 128.537496 -270.530317) (xy 128.588017 -270.536451)
			(xy 128.636901 -270.550611) (xy 128.68288 -270.572428) (xy 128.724764 -270.601338) (xy 128.761468 -270.636593)
			(xy 128.792041 -270.677279) (xy 128.815692 -270.722342) (xy 128.831808 -270.770616) (xy 128.839972 -270.82085)
			(xy 128.840484 -270.846296) (xy 129.148581 -270.846296) (xy 129.152676 -270.795568) (xy 129.164855 -270.746154)
			(xy 129.184803 -270.699334) (xy 129.212004 -270.65632) (xy 129.245752 -270.618226) (xy 129.285174 -270.586039)
			(xy 129.329248 -270.560593) (xy 129.376834 -270.542546) (xy 129.426698 -270.532366) (xy 129.47755 -270.530317)
			(xy 129.528071 -270.536451) (xy 129.576955 -270.550611) (xy 129.622934 -270.572428) (xy 129.664818 -270.601338)
			(xy 129.701522 -270.636593) (xy 129.732095 -270.677279) (xy 129.755746 -270.722342) (xy 129.771862 -270.770616)
			(xy 129.780026 -270.82085) (xy 129.780538 -270.846296) (xy 130.099066 -270.846296) (xy 130.103026 -270.797242)
			(xy 130.114803 -270.749458) (xy 130.134094 -270.704182) (xy 130.160397 -270.662586) (xy 130.193032 -270.625749)
			(xy 130.231153 -270.594624) (xy 130.273774 -270.570017) (xy 130.31979 -270.552565) (xy 130.368009 -270.542721)
			(xy 130.417184 -270.54074) (xy 130.466039 -270.546672) (xy 130.51331 -270.560364) (xy 130.557772 -270.581462)
			(xy 130.598275 -270.609418) (xy 130.633768 -270.64351) (xy 130.663333 -270.682854) (xy 130.686204 -270.726431)
			(xy 130.701788 -270.773112) (xy 130.709683 -270.821689) (xy 130.710178 -270.846296) (xy 131.028435 -270.846296)
			(xy 131.03253 -270.795568) (xy 131.044709 -270.746154) (xy 131.064657 -270.699334) (xy 131.091858 -270.65632)
			(xy 131.125606 -270.618226) (xy 131.165028 -270.586039) (xy 131.209102 -270.560593) (xy 131.256688 -270.542546)
			(xy 131.306552 -270.532366) (xy 131.357404 -270.530317) (xy 131.407925 -270.536451) (xy 131.456809 -270.550611)
			(xy 131.502788 -270.572428) (xy 131.544672 -270.601338) (xy 131.581376 -270.636593) (xy 131.611949 -270.677279)
			(xy 131.6356 -270.722342) (xy 131.651716 -270.770616) (xy 131.65988 -270.82085) (xy 131.660392 -270.846296)
			(xy 131.97892 -270.846296) (xy 131.98288 -270.797242) (xy 131.994657 -270.749458) (xy 132.013948 -270.704182)
			(xy 132.040251 -270.662586) (xy 132.072886 -270.625749) (xy 132.111007 -270.594624) (xy 132.153628 -270.570017)
			(xy 132.199644 -270.552565) (xy 132.247863 -270.542721) (xy 132.297038 -270.54074) (xy 132.345893 -270.546672)
			(xy 132.393164 -270.560364) (xy 132.437626 -270.581462) (xy 132.478129 -270.609418) (xy 132.513622 -270.64351)
			(xy 132.543187 -270.682854) (xy 132.566058 -270.726431) (xy 132.581642 -270.773112) (xy 132.589537 -270.821689)
			(xy 132.590032 -270.846296) (xy 132.908543 -270.846296) (xy 132.912638 -270.795568) (xy 132.924817 -270.746154)
			(xy 132.944765 -270.699334) (xy 132.971966 -270.65632) (xy 133.005714 -270.618226) (xy 133.045136 -270.586039)
			(xy 133.08921 -270.560593) (xy 133.136796 -270.542546) (xy 133.18666 -270.532366) (xy 133.237512 -270.530317)
			(xy 133.288033 -270.536451) (xy 133.336917 -270.550611) (xy 133.382896 -270.572428) (xy 133.42478 -270.601338)
			(xy 133.461484 -270.636593) (xy 133.492057 -270.677279) (xy 133.515708 -270.722342) (xy 133.531824 -270.770616)
			(xy 133.539988 -270.82085) (xy 133.5405 -270.846296) (xy 133.859028 -270.846296) (xy 133.862988 -270.797242)
			(xy 133.874765 -270.749458) (xy 133.894056 -270.704182) (xy 133.920359 -270.662586) (xy 133.952994 -270.625749)
			(xy 133.991115 -270.594624) (xy 134.033736 -270.570017) (xy 134.079752 -270.552565) (xy 134.127971 -270.542721)
			(xy 134.177146 -270.54074) (xy 134.226001 -270.546672) (xy 134.273272 -270.560364) (xy 134.317734 -270.581462)
			(xy 134.358237 -270.609418) (xy 134.39373 -270.64351) (xy 134.423295 -270.682854) (xy 134.446166 -270.726431)
			(xy 134.46175 -270.773112) (xy 134.469645 -270.821689) (xy 134.47014 -270.846296) (xy 134.798828 -270.846296)
			(xy 134.802788 -270.797242) (xy 134.814565 -270.749458) (xy 134.833856 -270.704182) (xy 134.860159 -270.662586)
			(xy 134.892794 -270.625749) (xy 134.930915 -270.594624) (xy 134.973536 -270.570017) (xy 135.019552 -270.552565)
			(xy 135.067771 -270.542721) (xy 135.116946 -270.54074) (xy 135.165801 -270.546672) (xy 135.213072 -270.560364)
			(xy 135.257534 -270.581462) (xy 135.298037 -270.609418) (xy 135.33353 -270.64351) (xy 135.363095 -270.682854)
			(xy 135.385966 -270.726431) (xy 135.40155 -270.773112) (xy 135.409445 -270.821689) (xy 135.40994 -270.846296)
			(xy 135.738882 -270.846296) (xy 135.742842 -270.797242) (xy 135.754619 -270.749458) (xy 135.77391 -270.704182)
			(xy 135.800213 -270.662586) (xy 135.832848 -270.625749) (xy 135.870969 -270.594624) (xy 135.91359 -270.570017)
			(xy 135.959606 -270.552565) (xy 136.007825 -270.542721) (xy 136.057 -270.54074) (xy 136.105855 -270.546672)
			(xy 136.153126 -270.560364) (xy 136.197588 -270.581462) (xy 136.238091 -270.609418) (xy 136.273584 -270.64351)
			(xy 136.303149 -270.682854) (xy 136.32602 -270.726431) (xy 136.341604 -270.773112) (xy 136.349499 -270.821689)
			(xy 136.349994 -270.846296) (xy 136.678936 -270.846296) (xy 136.682896 -270.797242) (xy 136.694673 -270.749458)
			(xy 136.713964 -270.704182) (xy 136.740267 -270.662586) (xy 136.772902 -270.625749) (xy 136.811023 -270.594624)
			(xy 136.853644 -270.570017) (xy 136.89966 -270.552565) (xy 136.947879 -270.542721) (xy 136.997054 -270.54074)
			(xy 137.045909 -270.546672) (xy 137.09318 -270.560364) (xy 137.137642 -270.581462) (xy 137.178145 -270.609418)
			(xy 137.213638 -270.64351) (xy 137.243203 -270.682854) (xy 137.266074 -270.726431) (xy 137.281658 -270.773112)
			(xy 137.289553 -270.821689) (xy 137.290048 -270.846296) (xy 137.61899 -270.846296) (xy 137.62295 -270.797242)
			(xy 137.634727 -270.749458) (xy 137.654018 -270.704182) (xy 137.680321 -270.662586) (xy 137.712956 -270.625749)
			(xy 137.751077 -270.594624) (xy 137.793698 -270.570017) (xy 137.839714 -270.552565) (xy 137.887933 -270.542721)
			(xy 137.937108 -270.54074) (xy 137.985963 -270.546672) (xy 138.033234 -270.560364) (xy 138.077696 -270.581462)
			(xy 138.118199 -270.609418) (xy 138.153692 -270.64351) (xy 138.183257 -270.682854) (xy 138.206128 -270.726431)
			(xy 138.221712 -270.773112) (xy 138.229607 -270.821689) (xy 138.230102 -270.846296) (xy 138.559044 -270.846296)
			(xy 138.563004 -270.797242) (xy 138.574781 -270.749458) (xy 138.594072 -270.704182) (xy 138.620375 -270.662586)
			(xy 138.65301 -270.625749) (xy 138.691131 -270.594624) (xy 138.733752 -270.570017) (xy 138.779768 -270.552565)
			(xy 138.827987 -270.542721) (xy 138.877162 -270.54074) (xy 138.926017 -270.546672) (xy 138.973288 -270.560364)
			(xy 139.01775 -270.581462) (xy 139.058253 -270.609418) (xy 139.093746 -270.64351) (xy 139.123311 -270.682854)
			(xy 139.146182 -270.726431) (xy 139.161766 -270.773112) (xy 139.169661 -270.821689) (xy 139.170156 -270.846296)
			(xy 139.498844 -270.846296) (xy 139.502804 -270.797242) (xy 139.514581 -270.749458) (xy 139.533872 -270.704182)
			(xy 139.560175 -270.662586) (xy 139.59281 -270.625749) (xy 139.630931 -270.594624) (xy 139.673552 -270.570017)
			(xy 139.719568 -270.552565) (xy 139.767787 -270.542721) (xy 139.816962 -270.54074) (xy 139.865817 -270.546672)
			(xy 139.913088 -270.560364) (xy 139.95755 -270.581462) (xy 139.998053 -270.609418) (xy 140.033546 -270.64351)
			(xy 140.063111 -270.682854) (xy 140.085982 -270.726431) (xy 140.101566 -270.773112) (xy 140.109461 -270.821689)
			(xy 140.109956 -270.846296) (xy 140.109461 -270.870903) (xy 140.101566 -270.91948) (xy 140.085982 -270.966161)
			(xy 140.063111 -271.009738) (xy 140.033546 -271.049082) (xy 139.998053 -271.083174) (xy 139.95755 -271.11113)
			(xy 139.913088 -271.132228) (xy 139.865817 -271.14592) (xy 139.816962 -271.151852) (xy 139.767787 -271.149871)
			(xy 139.719568 -271.140027) (xy 139.673552 -271.122575) (xy 139.630931 -271.097968) (xy 139.59281 -271.066843)
			(xy 139.560175 -271.030006) (xy 139.533872 -270.98841) (xy 139.514581 -270.943134) (xy 139.502804 -270.89535)
			(xy 139.498844 -270.846296) (xy 139.170156 -270.846296) (xy 139.169661 -270.870903) (xy 139.161766 -270.91948)
			(xy 139.146182 -270.966161) (xy 139.123311 -271.009738) (xy 139.093746 -271.049082) (xy 139.058253 -271.083174)
			(xy 139.01775 -271.11113) (xy 138.973288 -271.132228) (xy 138.926017 -271.14592) (xy 138.877162 -271.151852)
			(xy 138.827987 -271.149871) (xy 138.779768 -271.140027) (xy 138.733752 -271.122575) (xy 138.691131 -271.097968)
			(xy 138.65301 -271.066843) (xy 138.620375 -271.030006) (xy 138.594072 -270.98841) (xy 138.574781 -270.943134)
			(xy 138.563004 -270.89535) (xy 138.559044 -270.846296) (xy 138.230102 -270.846296) (xy 138.229607 -270.870903)
			(xy 138.221712 -270.91948) (xy 138.206128 -270.966161) (xy 138.183257 -271.009738) (xy 138.153692 -271.049082)
			(xy 138.118199 -271.083174) (xy 138.077696 -271.11113) (xy 138.033234 -271.132228) (xy 137.985963 -271.14592)
			(xy 137.937108 -271.151852) (xy 137.887933 -271.149871) (xy 137.839714 -271.140027) (xy 137.793698 -271.122575)
			(xy 137.751077 -271.097968) (xy 137.712956 -271.066843) (xy 137.680321 -271.030006) (xy 137.654018 -270.98841)
			(xy 137.634727 -270.943134) (xy 137.62295 -270.89535) (xy 137.61899 -270.846296) (xy 137.290048 -270.846296)
			(xy 137.289553 -270.870903) (xy 137.281658 -270.91948) (xy 137.266074 -270.966161) (xy 137.243203 -271.009738)
			(xy 137.213638 -271.049082) (xy 137.178145 -271.083174) (xy 137.137642 -271.11113) (xy 137.09318 -271.132228)
			(xy 137.045909 -271.14592) (xy 136.997054 -271.151852) (xy 136.947879 -271.149871) (xy 136.89966 -271.140027)
			(xy 136.853644 -271.122575) (xy 136.811023 -271.097968) (xy 136.772902 -271.066843) (xy 136.740267 -271.030006)
			(xy 136.713964 -270.98841) (xy 136.694673 -270.943134) (xy 136.682896 -270.89535) (xy 136.678936 -270.846296)
			(xy 136.349994 -270.846296) (xy 136.349499 -270.870903) (xy 136.341604 -270.91948) (xy 136.32602 -270.966161)
			(xy 136.303149 -271.009738) (xy 136.273584 -271.049082) (xy 136.238091 -271.083174) (xy 136.197588 -271.11113)
			(xy 136.153126 -271.132228) (xy 136.105855 -271.14592) (xy 136.057 -271.151852) (xy 136.007825 -271.149871)
			(xy 135.959606 -271.140027) (xy 135.91359 -271.122575) (xy 135.870969 -271.097968) (xy 135.832848 -271.066843)
			(xy 135.800213 -271.030006) (xy 135.77391 -270.98841) (xy 135.754619 -270.943134) (xy 135.742842 -270.89535)
			(xy 135.738882 -270.846296) (xy 135.40994 -270.846296) (xy 135.409445 -270.870903) (xy 135.40155 -270.91948)
			(xy 135.385966 -270.966161) (xy 135.363095 -271.009738) (xy 135.33353 -271.049082) (xy 135.298037 -271.083174)
			(xy 135.257534 -271.11113) (xy 135.213072 -271.132228) (xy 135.165801 -271.14592) (xy 135.116946 -271.151852)
			(xy 135.067771 -271.149871) (xy 135.019552 -271.140027) (xy 134.973536 -271.122575) (xy 134.930915 -271.097968)
			(xy 134.892794 -271.066843) (xy 134.860159 -271.030006) (xy 134.833856 -270.98841) (xy 134.814565 -270.943134)
			(xy 134.802788 -270.89535) (xy 134.798828 -270.846296) (xy 134.47014 -270.846296) (xy 134.469645 -270.870903)
			(xy 134.46175 -270.91948) (xy 134.446166 -270.966161) (xy 134.423295 -271.009738) (xy 134.39373 -271.049082)
			(xy 134.358237 -271.083174) (xy 134.317734 -271.11113) (xy 134.273272 -271.132228) (xy 134.226001 -271.14592)
			(xy 134.177146 -271.151852) (xy 134.127971 -271.149871) (xy 134.079752 -271.140027) (xy 134.033736 -271.122575)
			(xy 133.991115 -271.097968) (xy 133.952994 -271.066843) (xy 133.920359 -271.030006) (xy 133.894056 -270.98841)
			(xy 133.874765 -270.943134) (xy 133.862988 -270.89535) (xy 133.859028 -270.846296) (xy 133.5405 -270.846296)
			(xy 133.539988 -270.871742) (xy 133.531824 -270.921976) (xy 133.515708 -270.97025) (xy 133.492057 -271.015313)
			(xy 133.461484 -271.055999) (xy 133.42478 -271.091254) (xy 133.382896 -271.120164) (xy 133.336917 -271.141981)
			(xy 133.288033 -271.156141) (xy 133.237512 -271.162275) (xy 133.18666 -271.160226) (xy 133.136796 -271.150046)
			(xy 133.08921 -271.131999) (xy 133.045136 -271.106553) (xy 133.005714 -271.074366) (xy 132.971966 -271.036272)
			(xy 132.944765 -270.993258) (xy 132.924817 -270.946438) (xy 132.912638 -270.897024) (xy 132.908543 -270.846296)
			(xy 132.590032 -270.846296) (xy 132.589537 -270.870903) (xy 132.581642 -270.91948) (xy 132.566058 -270.966161)
			(xy 132.543187 -271.009738) (xy 132.513622 -271.049082) (xy 132.478129 -271.083174) (xy 132.437626 -271.11113)
			(xy 132.393164 -271.132228) (xy 132.345893 -271.14592) (xy 132.297038 -271.151852) (xy 132.247863 -271.149871)
			(xy 132.199644 -271.140027) (xy 132.153628 -271.122575) (xy 132.111007 -271.097968) (xy 132.072886 -271.066843)
			(xy 132.040251 -271.030006) (xy 132.013948 -270.98841) (xy 131.994657 -270.943134) (xy 131.98288 -270.89535)
			(xy 131.97892 -270.846296) (xy 131.660392 -270.846296) (xy 131.65988 -270.871742) (xy 131.651716 -270.921976)
			(xy 131.6356 -270.97025) (xy 131.611949 -271.015313) (xy 131.581376 -271.055999) (xy 131.544672 -271.091254)
			(xy 131.502788 -271.120164) (xy 131.456809 -271.141981) (xy 131.407925 -271.156141) (xy 131.357404 -271.162275)
			(xy 131.306552 -271.160226) (xy 131.256688 -271.150046) (xy 131.209102 -271.131999) (xy 131.165028 -271.106553)
			(xy 131.125606 -271.074366) (xy 131.091858 -271.036272) (xy 131.064657 -270.993258) (xy 131.044709 -270.946438)
			(xy 131.03253 -270.897024) (xy 131.028435 -270.846296) (xy 130.710178 -270.846296) (xy 130.709683 -270.870903)
			(xy 130.701788 -270.91948) (xy 130.686204 -270.966161) (xy 130.663333 -271.009738) (xy 130.633768 -271.049082)
			(xy 130.598275 -271.083174) (xy 130.557772 -271.11113) (xy 130.51331 -271.132228) (xy 130.466039 -271.14592)
			(xy 130.417184 -271.151852) (xy 130.368009 -271.149871) (xy 130.31979 -271.140027) (xy 130.273774 -271.122575)
			(xy 130.231153 -271.097968) (xy 130.193032 -271.066843) (xy 130.160397 -271.030006) (xy 130.134094 -270.98841)
			(xy 130.114803 -270.943134) (xy 130.103026 -270.89535) (xy 130.099066 -270.846296) (xy 129.780538 -270.846296)
			(xy 129.780026 -270.871742) (xy 129.771862 -270.921976) (xy 129.755746 -270.97025) (xy 129.732095 -271.015313)
			(xy 129.701522 -271.055999) (xy 129.664818 -271.091254) (xy 129.622934 -271.120164) (xy 129.576955 -271.141981)
			(xy 129.528071 -271.156141) (xy 129.47755 -271.162275) (xy 129.426698 -271.160226) (xy 129.376834 -271.150046)
			(xy 129.329248 -271.131999) (xy 129.285174 -271.106553) (xy 129.245752 -271.074366) (xy 129.212004 -271.036272)
			(xy 129.184803 -270.993258) (xy 129.164855 -270.946438) (xy 129.152676 -270.897024) (xy 129.148581 -270.846296)
			(xy 128.840484 -270.846296) (xy 128.839972 -270.871742) (xy 128.831808 -270.921976) (xy 128.815692 -270.97025)
			(xy 128.792041 -271.015313) (xy 128.761468 -271.055999) (xy 128.724764 -271.091254) (xy 128.68288 -271.120164)
			(xy 128.636901 -271.141981) (xy 128.588017 -271.156141) (xy 128.537496 -271.162275) (xy 128.486644 -271.160226)
			(xy 128.43678 -271.150046) (xy 128.389194 -271.131999) (xy 128.34512 -271.106553) (xy 128.305698 -271.074366)
			(xy 128.27195 -271.036272) (xy 128.244749 -270.993258) (xy 128.224801 -270.946438) (xy 128.212622 -270.897024)
			(xy 128.208527 -270.846296) (xy 127.890016 -270.846296) (xy 127.889521 -270.870903) (xy 127.881626 -270.91948)
			(xy 127.866042 -270.966161) (xy 127.843171 -271.009738) (xy 127.813606 -271.049082) (xy 127.778113 -271.083174)
			(xy 127.73761 -271.11113) (xy 127.693148 -271.132228) (xy 127.645877 -271.14592) (xy 127.597022 -271.151852)
			(xy 127.547847 -271.149871) (xy 127.499628 -271.140027) (xy 127.453612 -271.122575) (xy 127.410991 -271.097968)
			(xy 127.37287 -271.066843) (xy 127.340235 -271.030006) (xy 127.313932 -270.98841) (xy 127.294641 -270.943134)
			(xy 127.282864 -270.89535) (xy 127.278904 -270.846296) (xy 126.949962 -270.846296) (xy 126.949467 -270.870903)
			(xy 126.941572 -270.91948) (xy 126.925988 -270.966161) (xy 126.903117 -271.009738) (xy 126.873552 -271.049082)
			(xy 126.838059 -271.083174) (xy 126.797556 -271.11113) (xy 126.753094 -271.132228) (xy 126.705823 -271.14592)
			(xy 126.656968 -271.151852) (xy 126.607793 -271.149871) (xy 126.559574 -271.140027) (xy 126.513558 -271.122575)
			(xy 126.470937 -271.097968) (xy 126.432816 -271.066843) (xy 126.400181 -271.030006) (xy 126.373878 -270.98841)
			(xy 126.354587 -270.943134) (xy 126.34281 -270.89535) (xy 126.33885 -270.846296) (xy 126.010162 -270.846296)
			(xy 126.009667 -270.870903) (xy 126.001772 -270.91948) (xy 125.986188 -270.966161) (xy 125.963317 -271.009738)
			(xy 125.933752 -271.049082) (xy 125.898259 -271.083174) (xy 125.857756 -271.11113) (xy 125.813294 -271.132228)
			(xy 125.766023 -271.14592) (xy 125.717168 -271.151852) (xy 125.667993 -271.149871) (xy 125.619774 -271.140027)
			(xy 125.573758 -271.122575) (xy 125.531137 -271.097968) (xy 125.493016 -271.066843) (xy 125.460381 -271.030006)
			(xy 125.434078 -270.98841) (xy 125.414787 -270.943134) (xy 125.40301 -270.89535) (xy 125.39905 -270.846296)
			(xy 125.070108 -270.846296) (xy 125.069613 -270.870903) (xy 125.061718 -270.91948) (xy 125.046134 -270.966161)
			(xy 125.023263 -271.009738) (xy 124.993698 -271.049082) (xy 124.958205 -271.083174) (xy 124.917702 -271.11113)
			(xy 124.87324 -271.132228) (xy 124.825969 -271.14592) (xy 124.777114 -271.151852) (xy 124.727939 -271.149871)
			(xy 124.67972 -271.140027) (xy 124.633704 -271.122575) (xy 124.591083 -271.097968) (xy 124.552962 -271.066843)
			(xy 124.520327 -271.030006) (xy 124.494024 -270.98841) (xy 124.474733 -270.943134) (xy 124.462956 -270.89535)
			(xy 124.458996 -270.846296) (xy 124.130054 -270.846296) (xy 124.129559 -270.870903) (xy 124.121664 -270.91948)
			(xy 124.10608 -270.966161) (xy 124.083209 -271.009738) (xy 124.053644 -271.049082) (xy 124.018151 -271.083174)
			(xy 123.977648 -271.11113) (xy 123.933186 -271.132228) (xy 123.885915 -271.14592) (xy 123.83706 -271.151852)
			(xy 123.787885 -271.149871) (xy 123.739666 -271.140027) (xy 123.69365 -271.122575) (xy 123.651029 -271.097968)
			(xy 123.612908 -271.066843) (xy 123.580273 -271.030006) (xy 123.55397 -270.98841) (xy 123.534679 -270.943134)
			(xy 123.522902 -270.89535) (xy 123.518942 -270.846296) (xy 123.19 -270.846296) (xy 123.189505 -270.870903)
			(xy 123.18161 -270.91948) (xy 123.166026 -270.966161) (xy 123.143155 -271.009738) (xy 123.11359 -271.049082)
			(xy 123.078097 -271.083174) (xy 123.037594 -271.11113) (xy 122.993132 -271.132228) (xy 122.945861 -271.14592)
			(xy 122.897006 -271.151852) (xy 122.847831 -271.149871) (xy 122.799612 -271.140027) (xy 122.753596 -271.122575)
			(xy 122.710975 -271.097968) (xy 122.672854 -271.066843) (xy 122.640219 -271.030006) (xy 122.613916 -270.98841)
			(xy 122.594625 -270.943134) (xy 122.582848 -270.89535) (xy 122.578888 -270.846296) (xy 122.249946 -270.846296)
			(xy 122.249451 -270.870903) (xy 122.241556 -270.91948) (xy 122.225972 -270.966161) (xy 122.203101 -271.009738)
			(xy 122.173536 -271.049082) (xy 122.138043 -271.083174) (xy 122.09754 -271.11113) (xy 122.053078 -271.132228)
			(xy 122.005807 -271.14592) (xy 121.956952 -271.151852) (xy 121.907777 -271.149871) (xy 121.859558 -271.140027)
			(xy 121.813542 -271.122575) (xy 121.770921 -271.097968) (xy 121.7328 -271.066843) (xy 121.700165 -271.030006)
			(xy 121.673862 -270.98841) (xy 121.654571 -270.943134) (xy 121.642794 -270.89535) (xy 121.638834 -270.846296)
			(xy 121.310146 -270.846296) (xy 121.309651 -270.870903) (xy 121.301756 -270.91948) (xy 121.286172 -270.966161)
			(xy 121.263301 -271.009738) (xy 121.233736 -271.049082) (xy 121.198243 -271.083174) (xy 121.15774 -271.11113)
			(xy 121.113278 -271.132228) (xy 121.066007 -271.14592) (xy 121.017152 -271.151852) (xy 120.967977 -271.149871)
			(xy 120.919758 -271.140027) (xy 120.873742 -271.122575) (xy 120.831121 -271.097968) (xy 120.793 -271.066843)
			(xy 120.760365 -271.030006) (xy 120.734062 -270.98841) (xy 120.714771 -270.943134) (xy 120.702994 -270.89535)
			(xy 120.699034 -270.846296) (xy 120.370092 -270.846296) (xy 120.369597 -270.870903) (xy 120.361702 -270.91948)
			(xy 120.346118 -270.966161) (xy 120.323247 -271.009738) (xy 120.293682 -271.049082) (xy 120.258189 -271.083174)
			(xy 120.217686 -271.11113) (xy 120.173224 -271.132228) (xy 120.125953 -271.14592) (xy 120.077098 -271.151852)
			(xy 120.027923 -271.149871) (xy 119.979704 -271.140027) (xy 119.933688 -271.122575) (xy 119.891067 -271.097968)
			(xy 119.852946 -271.066843) (xy 119.820311 -271.030006) (xy 119.794008 -270.98841) (xy 119.774717 -270.943134)
			(xy 119.76294 -270.89535) (xy 119.75898 -270.846296) (xy 119.430038 -270.846296) (xy 119.429543 -270.870903)
			(xy 119.421648 -270.91948) (xy 119.406064 -270.966161) (xy 119.383193 -271.009738) (xy 119.353628 -271.049082)
			(xy 119.318135 -271.083174) (xy 119.277632 -271.11113) (xy 119.23317 -271.132228) (xy 119.185899 -271.14592)
			(xy 119.137044 -271.151852) (xy 119.087869 -271.149871) (xy 119.03965 -271.140027) (xy 118.993634 -271.122575)
			(xy 118.951013 -271.097968) (xy 118.912892 -271.066843) (xy 118.880257 -271.030006) (xy 118.853954 -270.98841)
			(xy 118.834663 -270.943134) (xy 118.822886 -270.89535) (xy 118.818926 -270.846296) (xy 118.489984 -270.846296)
			(xy 118.489489 -270.870903) (xy 118.481594 -270.91948) (xy 118.46601 -270.966161) (xy 118.443139 -271.009738)
			(xy 118.413574 -271.049082) (xy 118.378081 -271.083174) (xy 118.337578 -271.11113) (xy 118.293116 -271.132228)
			(xy 118.245845 -271.14592) (xy 118.19699 -271.151852) (xy 118.147815 -271.149871) (xy 118.099596 -271.140027)
			(xy 118.05358 -271.122575) (xy 118.010959 -271.097968) (xy 117.972838 -271.066843) (xy 117.940203 -271.030006)
			(xy 117.9139 -270.98841) (xy 117.894609 -270.943134) (xy 117.882832 -270.89535) (xy 117.878872 -270.846296)
			(xy 117.54993 -270.846296) (xy 117.549435 -270.870903) (xy 117.54154 -270.91948) (xy 117.525956 -270.966161)
			(xy 117.503085 -271.009738) (xy 117.47352 -271.049082) (xy 117.438027 -271.083174) (xy 117.397524 -271.11113)
			(xy 117.353062 -271.132228) (xy 117.305791 -271.14592) (xy 117.256936 -271.151852) (xy 117.207761 -271.149871)
			(xy 117.159542 -271.140027) (xy 117.113526 -271.122575) (xy 117.070905 -271.097968) (xy 117.032784 -271.066843)
			(xy 117.000149 -271.030006) (xy 116.973846 -270.98841) (xy 116.954555 -270.943134) (xy 116.942778 -270.89535)
			(xy 116.938818 -270.846296) (xy 116.61013 -270.846296) (xy 116.609635 -270.870903) (xy 116.60174 -270.91948)
			(xy 116.586156 -270.966161) (xy 116.563285 -271.009738) (xy 116.53372 -271.049082) (xy 116.498227 -271.083174)
			(xy 116.457724 -271.11113) (xy 116.413262 -271.132228) (xy 116.365991 -271.14592) (xy 116.317136 -271.151852)
			(xy 116.267961 -271.149871) (xy 116.219742 -271.140027) (xy 116.173726 -271.122575) (xy 116.131105 -271.097968)
			(xy 116.092984 -271.066843) (xy 116.060349 -271.030006) (xy 116.034046 -270.98841) (xy 116.014755 -270.943134)
			(xy 116.002978 -270.89535) (xy 115.999018 -270.846296) (xy 115.670076 -270.846296) (xy 115.669581 -270.870903)
			(xy 115.661686 -270.91948) (xy 115.646102 -270.966161) (xy 115.623231 -271.009738) (xy 115.593666 -271.049082)
			(xy 115.558173 -271.083174) (xy 115.51767 -271.11113) (xy 115.473208 -271.132228) (xy 115.425937 -271.14592)
			(xy 115.377082 -271.151852) (xy 115.327907 -271.149871) (xy 115.279688 -271.140027) (xy 115.233672 -271.122575)
			(xy 115.191051 -271.097968) (xy 115.15293 -271.066843) (xy 115.120295 -271.030006) (xy 115.093992 -270.98841)
			(xy 115.074701 -270.943134) (xy 115.062924 -270.89535) (xy 115.058964 -270.846296) (xy 114.730022 -270.846296)
			(xy 114.729527 -270.870903) (xy 114.721632 -270.91948) (xy 114.706048 -270.966161) (xy 114.683177 -271.009738)
			(xy 114.653612 -271.049082) (xy 114.618119 -271.083174) (xy 114.577616 -271.11113) (xy 114.533154 -271.132228)
			(xy 114.485883 -271.14592) (xy 114.437028 -271.151852) (xy 114.387853 -271.149871) (xy 114.339634 -271.140027)
			(xy 114.293618 -271.122575) (xy 114.250997 -271.097968) (xy 114.212876 -271.066843) (xy 114.180241 -271.030006)
			(xy 114.153938 -270.98841) (xy 114.134647 -270.943134) (xy 114.12287 -270.89535) (xy 114.11891 -270.846296)
			(xy 113.789968 -270.846296) (xy 113.789473 -270.870903) (xy 113.781578 -270.91948) (xy 113.765994 -270.966161)
			(xy 113.743123 -271.009738) (xy 113.713558 -271.049082) (xy 113.678065 -271.083174) (xy 113.637562 -271.11113)
			(xy 113.5931 -271.132228) (xy 113.545829 -271.14592) (xy 113.496974 -271.151852) (xy 113.447799 -271.149871)
			(xy 113.39958 -271.140027) (xy 113.353564 -271.122575) (xy 113.310943 -271.097968) (xy 113.272822 -271.066843)
			(xy 113.240187 -271.030006) (xy 113.213884 -270.98841) (xy 113.194593 -270.943134) (xy 113.182816 -270.89535)
			(xy 113.178856 -270.846296) (xy 110.97641 -270.846296) (xy 110.975915 -270.870903) (xy 110.96802 -270.91948)
			(xy 110.952436 -270.966161) (xy 110.929565 -271.009738) (xy 110.9 -271.049082) (xy 110.864507 -271.083174)
			(xy 110.824004 -271.11113) (xy 110.779542 -271.132228) (xy 110.732271 -271.14592) (xy 110.683416 -271.151852)
			(xy 110.634241 -271.149871) (xy 110.586022 -271.140027) (xy 110.540006 -271.122575) (xy 110.497385 -271.097968)
			(xy 110.459264 -271.066843) (xy 110.426629 -271.030006) (xy 110.400326 -270.98841) (xy 110.381035 -270.943134)
			(xy 110.369258 -270.89535) (xy 110.365298 -270.846296) (xy 110.036356 -270.846296) (xy 110.035861 -270.870903)
			(xy 110.027966 -270.91948) (xy 110.012382 -270.966161) (xy 109.989511 -271.009738) (xy 109.959946 -271.049082)
			(xy 109.924453 -271.083174) (xy 109.88395 -271.11113) (xy 109.839488 -271.132228) (xy 109.792217 -271.14592)
			(xy 109.743362 -271.151852) (xy 109.694187 -271.149871) (xy 109.645968 -271.140027) (xy 109.599952 -271.122575)
			(xy 109.557331 -271.097968) (xy 109.51921 -271.066843) (xy 109.486575 -271.030006) (xy 109.460272 -270.98841)
			(xy 109.440981 -270.943134) (xy 109.429204 -270.89535) (xy 109.425244 -270.846296) (xy 109.096302 -270.846296)
			(xy 109.095807 -270.870903) (xy 109.087912 -270.91948) (xy 109.072328 -270.966161) (xy 109.049457 -271.009738)
			(xy 109.019892 -271.049082) (xy 108.984399 -271.083174) (xy 108.943896 -271.11113) (xy 108.899434 -271.132228)
			(xy 108.852163 -271.14592) (xy 108.803308 -271.151852) (xy 108.754133 -271.149871) (xy 108.705914 -271.140027)
			(xy 108.659898 -271.122575) (xy 108.617277 -271.097968) (xy 108.579156 -271.066843) (xy 108.546521 -271.030006)
			(xy 108.520218 -270.98841) (xy 108.500927 -270.943134) (xy 108.48915 -270.89535) (xy 108.48519 -270.846296)
			(xy 108.156248 -270.846296) (xy 108.155753 -270.870903) (xy 108.147858 -270.91948) (xy 108.132274 -270.966161)
			(xy 108.109403 -271.009738) (xy 108.079838 -271.049082) (xy 108.044345 -271.083174) (xy 108.003842 -271.11113)
			(xy 107.95938 -271.132228) (xy 107.912109 -271.14592) (xy 107.863254 -271.151852) (xy 107.814079 -271.149871)
			(xy 107.76586 -271.140027) (xy 107.719844 -271.122575) (xy 107.677223 -271.097968) (xy 107.639102 -271.066843)
			(xy 107.606467 -271.030006) (xy 107.580164 -270.98841) (xy 107.560873 -270.943134) (xy 107.549096 -270.89535)
			(xy 107.545136 -270.846296) (xy 107.216448 -270.846296) (xy 107.215953 -270.870903) (xy 107.208058 -270.91948)
			(xy 107.192474 -270.966161) (xy 107.169603 -271.009738) (xy 107.140038 -271.049082) (xy 107.104545 -271.083174)
			(xy 107.064042 -271.11113) (xy 107.01958 -271.132228) (xy 106.972309 -271.14592) (xy 106.923454 -271.151852)
			(xy 106.874279 -271.149871) (xy 106.82606 -271.140027) (xy 106.780044 -271.122575) (xy 106.737423 -271.097968)
			(xy 106.699302 -271.066843) (xy 106.666667 -271.030006) (xy 106.640364 -270.98841) (xy 106.621073 -270.943134)
			(xy 106.609296 -270.89535) (xy 106.605336 -270.846296) (xy 106.276394 -270.846296) (xy 106.275899 -270.870903)
			(xy 106.268004 -270.91948) (xy 106.25242 -270.966161) (xy 106.229549 -271.009738) (xy 106.199984 -271.049082)
			(xy 106.164491 -271.083174) (xy 106.123988 -271.11113) (xy 106.079526 -271.132228) (xy 106.032255 -271.14592)
			(xy 105.9834 -271.151852) (xy 105.934225 -271.149871) (xy 105.886006 -271.140027) (xy 105.83999 -271.122575)
			(xy 105.797369 -271.097968) (xy 105.759248 -271.066843) (xy 105.726613 -271.030006) (xy 105.70031 -270.98841)
			(xy 105.681019 -270.943134) (xy 105.669242 -270.89535) (xy 105.665282 -270.846296) (xy 105.33634 -270.846296)
			(xy 105.335845 -270.870903) (xy 105.32795 -270.91948) (xy 105.312366 -270.966161) (xy 105.289495 -271.009738)
			(xy 105.25993 -271.049082) (xy 105.224437 -271.083174) (xy 105.183934 -271.11113) (xy 105.139472 -271.132228)
			(xy 105.092201 -271.14592) (xy 105.043346 -271.151852) (xy 104.994171 -271.149871) (xy 104.945952 -271.140027)
			(xy 104.899936 -271.122575) (xy 104.857315 -271.097968) (xy 104.819194 -271.066843) (xy 104.786559 -271.030006)
			(xy 104.760256 -270.98841) (xy 104.740965 -270.943134) (xy 104.729188 -270.89535) (xy 104.725228 -270.846296)
			(xy 104.396286 -270.846296) (xy 104.395791 -270.870903) (xy 104.387896 -270.91948) (xy 104.372312 -270.966161)
			(xy 104.349441 -271.009738) (xy 104.319876 -271.049082) (xy 104.284383 -271.083174) (xy 104.24388 -271.11113)
			(xy 104.199418 -271.132228) (xy 104.152147 -271.14592) (xy 104.103292 -271.151852) (xy 104.054117 -271.149871)
			(xy 104.005898 -271.140027) (xy 103.959882 -271.122575) (xy 103.917261 -271.097968) (xy 103.87914 -271.066843)
			(xy 103.846505 -271.030006) (xy 103.820202 -270.98841) (xy 103.800911 -270.943134) (xy 103.789134 -270.89535)
			(xy 103.785174 -270.846296) (xy 103.456486 -270.846296) (xy 103.455991 -270.870903) (xy 103.448096 -270.91948)
			(xy 103.432512 -270.966161) (xy 103.409641 -271.009738) (xy 103.380076 -271.049082) (xy 103.344583 -271.083174)
			(xy 103.30408 -271.11113) (xy 103.259618 -271.132228) (xy 103.212347 -271.14592) (xy 103.163492 -271.151852)
			(xy 103.114317 -271.149871) (xy 103.066098 -271.140027) (xy 103.020082 -271.122575) (xy 102.977461 -271.097968)
			(xy 102.93934 -271.066843) (xy 102.906705 -271.030006) (xy 102.880402 -270.98841) (xy 102.861111 -270.943134)
			(xy 102.849334 -270.89535) (xy 102.845374 -270.846296) (xy 102.516432 -270.846296) (xy 102.515937 -270.870903)
			(xy 102.508042 -270.91948) (xy 102.492458 -270.966161) (xy 102.469587 -271.009738) (xy 102.440022 -271.049082)
			(xy 102.404529 -271.083174) (xy 102.364026 -271.11113) (xy 102.319564 -271.132228) (xy 102.272293 -271.14592)
			(xy 102.223438 -271.151852) (xy 102.174263 -271.149871) (xy 102.126044 -271.140027) (xy 102.080028 -271.122575)
			(xy 102.037407 -271.097968) (xy 101.999286 -271.066843) (xy 101.966651 -271.030006) (xy 101.940348 -270.98841)
			(xy 101.921057 -270.943134) (xy 101.90928 -270.89535) (xy 101.90532 -270.846296) (xy 101.576378 -270.846296)
			(xy 101.575883 -270.870903) (xy 101.567988 -270.91948) (xy 101.552404 -270.966161) (xy 101.529533 -271.009738)
			(xy 101.499968 -271.049082) (xy 101.464475 -271.083174) (xy 101.423972 -271.11113) (xy 101.37951 -271.132228)
			(xy 101.332239 -271.14592) (xy 101.283384 -271.151852) (xy 101.234209 -271.149871) (xy 101.18599 -271.140027)
			(xy 101.139974 -271.122575) (xy 101.097353 -271.097968) (xy 101.059232 -271.066843) (xy 101.026597 -271.030006)
			(xy 101.000294 -270.98841) (xy 100.981003 -270.943134) (xy 100.969226 -270.89535) (xy 100.965266 -270.846296)
			(xy 100.636324 -270.846296) (xy 100.635829 -270.870903) (xy 100.627934 -270.91948) (xy 100.61235 -270.966161)
			(xy 100.589479 -271.009738) (xy 100.559914 -271.049082) (xy 100.524421 -271.083174) (xy 100.483918 -271.11113)
			(xy 100.439456 -271.132228) (xy 100.392185 -271.14592) (xy 100.34333 -271.151852) (xy 100.294155 -271.149871)
			(xy 100.245936 -271.140027) (xy 100.19992 -271.122575) (xy 100.157299 -271.097968) (xy 100.119178 -271.066843)
			(xy 100.086543 -271.030006) (xy 100.06024 -270.98841) (xy 100.040949 -270.943134) (xy 100.029172 -270.89535)
			(xy 100.025212 -270.846296) (xy 99.69627 -270.846296) (xy 99.695775 -270.870903) (xy 99.68788 -270.91948)
			(xy 99.672296 -270.966161) (xy 99.649425 -271.009738) (xy 99.61986 -271.049082) (xy 99.584367 -271.083174)
			(xy 99.543864 -271.11113) (xy 99.499402 -271.132228) (xy 99.452131 -271.14592) (xy 99.403276 -271.151852)
			(xy 99.354101 -271.149871) (xy 99.305882 -271.140027) (xy 99.259866 -271.122575) (xy 99.217245 -271.097968)
			(xy 99.179124 -271.066843) (xy 99.146489 -271.030006) (xy 99.120186 -270.98841) (xy 99.100895 -270.943134)
			(xy 99.089118 -270.89535) (xy 99.085158 -270.846296) (xy 98.75647 -270.846296) (xy 98.755975 -270.870903)
			(xy 98.74808 -270.91948) (xy 98.732496 -270.966161) (xy 98.709625 -271.009738) (xy 98.68006 -271.049082)
			(xy 98.644567 -271.083174) (xy 98.604064 -271.11113) (xy 98.559602 -271.132228) (xy 98.512331 -271.14592)
			(xy 98.463476 -271.151852) (xy 98.414301 -271.149871) (xy 98.366082 -271.140027) (xy 98.320066 -271.122575)
			(xy 98.277445 -271.097968) (xy 98.239324 -271.066843) (xy 98.206689 -271.030006) (xy 98.180386 -270.98841)
			(xy 98.161095 -270.943134) (xy 98.149318 -270.89535) (xy 98.145358 -270.846296) (xy 97.816935 -270.846296)
			(xy 97.816935 -270.8463) (xy 97.812764 -270.896638) (xy 97.800365 -270.945603) (xy 97.780075 -270.991859)
			(xy 97.752449 -271.034145) (xy 97.71824 -271.071307) (xy 97.67838 -271.102332) (xy 97.633958 -271.126373)
			(xy 97.586185 -271.142775) (xy 97.536363 -271.15109) (xy 97.511108 -271.151604) (xy 97.493582 -271.151096)
			(xy 97.483168 -271.150588) (xy 97.463356 -271.1577) (xy 97.402142 -271.215612) (xy 97.394918 -271.223062)
			(xy 97.386663 -271.242077) (xy 97.38614 -271.252442) (xy 97.38614 -271.656302) (xy 97.675204 -271.656302)
			(xy 97.679164 -271.607248) (xy 97.690941 -271.559464) (xy 97.710232 -271.514188) (xy 97.736535 -271.472592)
			(xy 97.76917 -271.435755) (xy 97.807291 -271.40463) (xy 97.849912 -271.380023) (xy 97.895928 -271.362571)
			(xy 97.944147 -271.352727) (xy 97.993322 -271.350746) (xy 98.042177 -271.356678) (xy 98.089448 -271.37037)
			(xy 98.13391 -271.391468) (xy 98.174413 -271.419424) (xy 98.209906 -271.453516) (xy 98.239471 -271.49286)
			(xy 98.262342 -271.536437) (xy 98.277926 -271.583118) (xy 98.285821 -271.631695) (xy 98.286316 -271.656302)
			(xy 98.615258 -271.656302) (xy 98.619218 -271.607248) (xy 98.630995 -271.559464) (xy 98.650286 -271.514188)
			(xy 98.676589 -271.472592) (xy 98.709224 -271.435755) (xy 98.747345 -271.40463) (xy 98.789966 -271.380023)
			(xy 98.835982 -271.362571) (xy 98.884201 -271.352727) (xy 98.933376 -271.350746) (xy 98.982231 -271.356678)
			(xy 99.029502 -271.37037) (xy 99.073964 -271.391468) (xy 99.114467 -271.419424) (xy 99.14996 -271.453516)
			(xy 99.179525 -271.49286) (xy 99.202396 -271.536437) (xy 99.21798 -271.583118) (xy 99.225875 -271.631695)
			(xy 99.22637 -271.656302) (xy 99.555312 -271.656302) (xy 99.559272 -271.607248) (xy 99.571049 -271.559464)
			(xy 99.59034 -271.514188) (xy 99.616643 -271.472592) (xy 99.649278 -271.435755) (xy 99.687399 -271.40463)
			(xy 99.73002 -271.380023) (xy 99.776036 -271.362571) (xy 99.824255 -271.352727) (xy 99.87343 -271.350746)
			(xy 99.922285 -271.356678) (xy 99.969556 -271.37037) (xy 100.014018 -271.391468) (xy 100.054521 -271.419424)
			(xy 100.090014 -271.453516) (xy 100.119579 -271.49286) (xy 100.14245 -271.536437) (xy 100.158034 -271.583118)
			(xy 100.165929 -271.631695) (xy 100.166424 -271.656302) (xy 100.495366 -271.656302) (xy 100.499326 -271.607248)
			(xy 100.511103 -271.559464) (xy 100.530394 -271.514188) (xy 100.556697 -271.472592) (xy 100.589332 -271.435755)
			(xy 100.627453 -271.40463) (xy 100.670074 -271.380023) (xy 100.71609 -271.362571) (xy 100.764309 -271.352727)
			(xy 100.813484 -271.350746) (xy 100.862339 -271.356678) (xy 100.90961 -271.37037) (xy 100.954072 -271.391468)
			(xy 100.994575 -271.419424) (xy 101.030068 -271.453516) (xy 101.059633 -271.49286) (xy 101.082504 -271.536437)
			(xy 101.098088 -271.583118) (xy 101.105983 -271.631695) (xy 101.106478 -271.656302) (xy 101.435166 -271.656302)
			(xy 101.439126 -271.607248) (xy 101.450903 -271.559464) (xy 101.470194 -271.514188) (xy 101.496497 -271.472592)
			(xy 101.529132 -271.435755) (xy 101.567253 -271.40463) (xy 101.609874 -271.380023) (xy 101.65589 -271.362571)
			(xy 101.704109 -271.352727) (xy 101.753284 -271.350746) (xy 101.802139 -271.356678) (xy 101.84941 -271.37037)
			(xy 101.893872 -271.391468) (xy 101.934375 -271.419424) (xy 101.969868 -271.453516) (xy 101.999433 -271.49286)
			(xy 102.022304 -271.536437) (xy 102.037888 -271.583118) (xy 102.045783 -271.631695) (xy 102.046278 -271.656302)
			(xy 102.37522 -271.656302) (xy 102.37918 -271.607248) (xy 102.390957 -271.559464) (xy 102.410248 -271.514188)
			(xy 102.436551 -271.472592) (xy 102.469186 -271.435755) (xy 102.507307 -271.40463) (xy 102.549928 -271.380023)
			(xy 102.595944 -271.362571) (xy 102.644163 -271.352727) (xy 102.693338 -271.350746) (xy 102.742193 -271.356678)
			(xy 102.789464 -271.37037) (xy 102.833926 -271.391468) (xy 102.874429 -271.419424) (xy 102.909922 -271.453516)
			(xy 102.939487 -271.49286) (xy 102.962358 -271.536437) (xy 102.977942 -271.583118) (xy 102.985837 -271.631695)
			(xy 102.986332 -271.656302) (xy 103.315274 -271.656302) (xy 103.319234 -271.607248) (xy 103.331011 -271.559464)
			(xy 103.350302 -271.514188) (xy 103.376605 -271.472592) (xy 103.40924 -271.435755) (xy 103.447361 -271.40463)
			(xy 103.489982 -271.380023) (xy 103.535998 -271.362571) (xy 103.584217 -271.352727) (xy 103.633392 -271.350746)
			(xy 103.682247 -271.356678) (xy 103.729518 -271.37037) (xy 103.77398 -271.391468) (xy 103.814483 -271.419424)
			(xy 103.849976 -271.453516) (xy 103.879541 -271.49286) (xy 103.902412 -271.536437) (xy 103.917996 -271.583118)
			(xy 103.925891 -271.631695) (xy 103.926386 -271.656302) (xy 104.255328 -271.656302) (xy 104.259288 -271.607248)
			(xy 104.271065 -271.559464) (xy 104.290356 -271.514188) (xy 104.316659 -271.472592) (xy 104.349294 -271.435755)
			(xy 104.387415 -271.40463) (xy 104.430036 -271.380023) (xy 104.476052 -271.362571) (xy 104.524271 -271.352727)
			(xy 104.573446 -271.350746) (xy 104.622301 -271.356678) (xy 104.669572 -271.37037) (xy 104.714034 -271.391468)
			(xy 104.754537 -271.419424) (xy 104.79003 -271.453516) (xy 104.819595 -271.49286) (xy 104.842466 -271.536437)
			(xy 104.85805 -271.583118) (xy 104.865945 -271.631695) (xy 104.86644 -271.656302) (xy 105.195128 -271.656302)
			(xy 105.199088 -271.607248) (xy 105.210865 -271.559464) (xy 105.230156 -271.514188) (xy 105.256459 -271.472592)
			(xy 105.289094 -271.435755) (xy 105.327215 -271.40463) (xy 105.369836 -271.380023) (xy 105.415852 -271.362571)
			(xy 105.464071 -271.352727) (xy 105.513246 -271.350746) (xy 105.562101 -271.356678) (xy 105.609372 -271.37037)
			(xy 105.653834 -271.391468) (xy 105.694337 -271.419424) (xy 105.72983 -271.453516) (xy 105.759395 -271.49286)
			(xy 105.782266 -271.536437) (xy 105.79785 -271.583118) (xy 105.805745 -271.631695) (xy 105.80624 -271.656302)
			(xy 106.135182 -271.656302) (xy 106.139142 -271.607248) (xy 106.150919 -271.559464) (xy 106.17021 -271.514188)
			(xy 106.196513 -271.472592) (xy 106.229148 -271.435755) (xy 106.267269 -271.40463) (xy 106.30989 -271.380023)
			(xy 106.355906 -271.362571) (xy 106.404125 -271.352727) (xy 106.4533 -271.350746) (xy 106.502155 -271.356678)
			(xy 106.549426 -271.37037) (xy 106.593888 -271.391468) (xy 106.634391 -271.419424) (xy 106.669884 -271.453516)
			(xy 106.699449 -271.49286) (xy 106.72232 -271.536437) (xy 106.737904 -271.583118) (xy 106.745799 -271.631695)
			(xy 106.746294 -271.656302) (xy 107.075236 -271.656302) (xy 107.079196 -271.607248) (xy 107.090973 -271.559464)
			(xy 107.110264 -271.514188) (xy 107.136567 -271.472592) (xy 107.169202 -271.435755) (xy 107.207323 -271.40463)
			(xy 107.249944 -271.380023) (xy 107.29596 -271.362571) (xy 107.344179 -271.352727) (xy 107.393354 -271.350746)
			(xy 107.442209 -271.356678) (xy 107.48948 -271.37037) (xy 107.533942 -271.391468) (xy 107.574445 -271.419424)
			(xy 107.609938 -271.453516) (xy 107.639503 -271.49286) (xy 107.662374 -271.536437) (xy 107.677958 -271.583118)
			(xy 107.685853 -271.631695) (xy 107.686348 -271.656302) (xy 108.01529 -271.656302) (xy 108.01925 -271.607248)
			(xy 108.031027 -271.559464) (xy 108.050318 -271.514188) (xy 108.076621 -271.472592) (xy 108.109256 -271.435755)
			(xy 108.147377 -271.40463) (xy 108.189998 -271.380023) (xy 108.236014 -271.362571) (xy 108.284233 -271.352727)
			(xy 108.333408 -271.350746) (xy 108.382263 -271.356678) (xy 108.429534 -271.37037) (xy 108.473996 -271.391468)
			(xy 108.514499 -271.419424) (xy 108.549992 -271.453516) (xy 108.579557 -271.49286) (xy 108.602428 -271.536437)
			(xy 108.618012 -271.583118) (xy 108.625907 -271.631695) (xy 108.626402 -271.656302) (xy 108.955344 -271.656302)
			(xy 108.959304 -271.607248) (xy 108.971081 -271.559464) (xy 108.990372 -271.514188) (xy 109.016675 -271.472592)
			(xy 109.04931 -271.435755) (xy 109.087431 -271.40463) (xy 109.130052 -271.380023) (xy 109.176068 -271.362571)
			(xy 109.224287 -271.352727) (xy 109.273462 -271.350746) (xy 109.322317 -271.356678) (xy 109.369588 -271.37037)
			(xy 109.41405 -271.391468) (xy 109.454553 -271.419424) (xy 109.490046 -271.453516) (xy 109.519611 -271.49286)
			(xy 109.542482 -271.536437) (xy 109.558066 -271.583118) (xy 109.565961 -271.631695) (xy 109.566456 -271.656302)
			(xy 109.895144 -271.656302) (xy 109.899104 -271.607248) (xy 109.910881 -271.559464) (xy 109.930172 -271.514188)
			(xy 109.956475 -271.472592) (xy 109.98911 -271.435755) (xy 110.027231 -271.40463) (xy 110.069852 -271.380023)
			(xy 110.115868 -271.362571) (xy 110.164087 -271.352727) (xy 110.213262 -271.350746) (xy 110.262117 -271.356678)
			(xy 110.309388 -271.37037) (xy 110.35385 -271.391468) (xy 110.394353 -271.419424) (xy 110.429846 -271.453516)
			(xy 110.459411 -271.49286) (xy 110.482282 -271.536437) (xy 110.497866 -271.583118) (xy 110.505761 -271.631695)
			(xy 110.506256 -271.656302) (xy 113.64901 -271.656302) (xy 113.65297 -271.607248) (xy 113.664747 -271.559464)
			(xy 113.684038 -271.514188) (xy 113.710341 -271.472592) (xy 113.742976 -271.435755) (xy 113.781097 -271.40463)
			(xy 113.823718 -271.380023) (xy 113.869734 -271.362571) (xy 113.917953 -271.352727) (xy 113.967128 -271.350746)
			(xy 114.015983 -271.356678) (xy 114.063254 -271.37037) (xy 114.107716 -271.391468) (xy 114.148219 -271.419424)
			(xy 114.183712 -271.453516) (xy 114.213277 -271.49286) (xy 114.236148 -271.536437) (xy 114.251732 -271.583118)
			(xy 114.259627 -271.631695) (xy 114.260122 -271.656302) (xy 114.58881 -271.656302) (xy 114.59277 -271.607248)
			(xy 114.604547 -271.559464) (xy 114.623838 -271.514188) (xy 114.650141 -271.472592) (xy 114.682776 -271.435755)
			(xy 114.720897 -271.40463) (xy 114.763518 -271.380023) (xy 114.809534 -271.362571) (xy 114.857753 -271.352727)
			(xy 114.906928 -271.350746) (xy 114.955783 -271.356678) (xy 115.003054 -271.37037) (xy 115.047516 -271.391468)
			(xy 115.088019 -271.419424) (xy 115.123512 -271.453516) (xy 115.153077 -271.49286) (xy 115.175948 -271.536437)
			(xy 115.191532 -271.583118) (xy 115.199427 -271.631695) (xy 115.199922 -271.656302) (xy 115.528864 -271.656302)
			(xy 115.532824 -271.607248) (xy 115.544601 -271.559464) (xy 115.563892 -271.514188) (xy 115.590195 -271.472592)
			(xy 115.62283 -271.435755) (xy 115.660951 -271.40463) (xy 115.703572 -271.380023) (xy 115.749588 -271.362571)
			(xy 115.797807 -271.352727) (xy 115.846982 -271.350746) (xy 115.895837 -271.356678) (xy 115.943108 -271.37037)
			(xy 115.98757 -271.391468) (xy 116.028073 -271.419424) (xy 116.063566 -271.453516) (xy 116.093131 -271.49286)
			(xy 116.116002 -271.536437) (xy 116.131586 -271.583118) (xy 116.139481 -271.631695) (xy 116.139976 -271.656302)
			(xy 116.468918 -271.656302) (xy 116.472878 -271.607248) (xy 116.484655 -271.559464) (xy 116.503946 -271.514188)
			(xy 116.530249 -271.472592) (xy 116.562884 -271.435755) (xy 116.601005 -271.40463) (xy 116.643626 -271.380023)
			(xy 116.689642 -271.362571) (xy 116.737861 -271.352727) (xy 116.787036 -271.350746) (xy 116.835891 -271.356678)
			(xy 116.883162 -271.37037) (xy 116.927624 -271.391468) (xy 116.968127 -271.419424) (xy 117.00362 -271.453516)
			(xy 117.033185 -271.49286) (xy 117.056056 -271.536437) (xy 117.07164 -271.583118) (xy 117.079535 -271.631695)
			(xy 117.08003 -271.656302) (xy 117.408972 -271.656302) (xy 117.412932 -271.607248) (xy 117.424709 -271.559464)
			(xy 117.444 -271.514188) (xy 117.470303 -271.472592) (xy 117.502938 -271.435755) (xy 117.541059 -271.40463)
			(xy 117.58368 -271.380023) (xy 117.629696 -271.362571) (xy 117.677915 -271.352727) (xy 117.72709 -271.350746)
			(xy 117.775945 -271.356678) (xy 117.823216 -271.37037) (xy 117.867678 -271.391468) (xy 117.908181 -271.419424)
			(xy 117.943674 -271.453516) (xy 117.973239 -271.49286) (xy 117.99611 -271.536437) (xy 118.011694 -271.583118)
			(xy 118.019589 -271.631695) (xy 118.020084 -271.656302) (xy 118.349026 -271.656302) (xy 118.352986 -271.607248)
			(xy 118.364763 -271.559464) (xy 118.384054 -271.514188) (xy 118.410357 -271.472592) (xy 118.442992 -271.435755)
			(xy 118.481113 -271.40463) (xy 118.523734 -271.380023) (xy 118.56975 -271.362571) (xy 118.617969 -271.352727)
			(xy 118.667144 -271.350746) (xy 118.715999 -271.356678) (xy 118.76327 -271.37037) (xy 118.807732 -271.391468)
			(xy 118.848235 -271.419424) (xy 118.883728 -271.453516) (xy 118.913293 -271.49286) (xy 118.936164 -271.536437)
			(xy 118.951748 -271.583118) (xy 118.959643 -271.631695) (xy 118.960138 -271.656302) (xy 119.288826 -271.656302)
			(xy 119.292786 -271.607248) (xy 119.304563 -271.559464) (xy 119.323854 -271.514188) (xy 119.350157 -271.472592)
			(xy 119.382792 -271.435755) (xy 119.420913 -271.40463) (xy 119.463534 -271.380023) (xy 119.50955 -271.362571)
			(xy 119.557769 -271.352727) (xy 119.606944 -271.350746) (xy 119.655799 -271.356678) (xy 119.70307 -271.37037)
			(xy 119.747532 -271.391468) (xy 119.788035 -271.419424) (xy 119.823528 -271.453516) (xy 119.853093 -271.49286)
			(xy 119.875964 -271.536437) (xy 119.891548 -271.583118) (xy 119.899443 -271.631695) (xy 119.899938 -271.656302)
			(xy 120.22888 -271.656302) (xy 120.23284 -271.607248) (xy 120.244617 -271.559464) (xy 120.263908 -271.514188)
			(xy 120.290211 -271.472592) (xy 120.322846 -271.435755) (xy 120.360967 -271.40463) (xy 120.403588 -271.380023)
			(xy 120.449604 -271.362571) (xy 120.497823 -271.352727) (xy 120.546998 -271.350746) (xy 120.595853 -271.356678)
			(xy 120.643124 -271.37037) (xy 120.687586 -271.391468) (xy 120.728089 -271.419424) (xy 120.763582 -271.453516)
			(xy 120.793147 -271.49286) (xy 120.816018 -271.536437) (xy 120.831602 -271.583118) (xy 120.839497 -271.631695)
			(xy 120.839992 -271.656302) (xy 121.168934 -271.656302) (xy 121.172894 -271.607248) (xy 121.184671 -271.559464)
			(xy 121.203962 -271.514188) (xy 121.230265 -271.472592) (xy 121.2629 -271.435755) (xy 121.301021 -271.40463)
			(xy 121.343642 -271.380023) (xy 121.389658 -271.362571) (xy 121.437877 -271.352727) (xy 121.487052 -271.350746)
			(xy 121.535907 -271.356678) (xy 121.583178 -271.37037) (xy 121.62764 -271.391468) (xy 121.668143 -271.419424)
			(xy 121.703636 -271.453516) (xy 121.733201 -271.49286) (xy 121.756072 -271.536437) (xy 121.771656 -271.583118)
			(xy 121.779551 -271.631695) (xy 121.780046 -271.656302) (xy 122.108988 -271.656302) (xy 122.112948 -271.607248)
			(xy 122.124725 -271.559464) (xy 122.144016 -271.514188) (xy 122.170319 -271.472592) (xy 122.202954 -271.435755)
			(xy 122.241075 -271.40463) (xy 122.283696 -271.380023) (xy 122.329712 -271.362571) (xy 122.377931 -271.352727)
			(xy 122.427106 -271.350746) (xy 122.475961 -271.356678) (xy 122.523232 -271.37037) (xy 122.567694 -271.391468)
			(xy 122.608197 -271.419424) (xy 122.64369 -271.453516) (xy 122.673255 -271.49286) (xy 122.696126 -271.536437)
			(xy 122.71171 -271.583118) (xy 122.719605 -271.631695) (xy 122.7201 -271.656302) (xy 123.049042 -271.656302)
			(xy 123.053002 -271.607248) (xy 123.064779 -271.559464) (xy 123.08407 -271.514188) (xy 123.110373 -271.472592)
			(xy 123.143008 -271.435755) (xy 123.181129 -271.40463) (xy 123.22375 -271.380023) (xy 123.269766 -271.362571)
			(xy 123.317985 -271.352727) (xy 123.36716 -271.350746) (xy 123.416015 -271.356678) (xy 123.463286 -271.37037)
			(xy 123.507748 -271.391468) (xy 123.548251 -271.419424) (xy 123.583744 -271.453516) (xy 123.613309 -271.49286)
			(xy 123.63618 -271.536437) (xy 123.651764 -271.583118) (xy 123.659659 -271.631695) (xy 123.660154 -271.656302)
			(xy 123.988842 -271.656302) (xy 123.992802 -271.607248) (xy 124.004579 -271.559464) (xy 124.02387 -271.514188)
			(xy 124.050173 -271.472592) (xy 124.082808 -271.435755) (xy 124.120929 -271.40463) (xy 124.16355 -271.380023)
			(xy 124.209566 -271.362571) (xy 124.257785 -271.352727) (xy 124.30696 -271.350746) (xy 124.355815 -271.356678)
			(xy 124.403086 -271.37037) (xy 124.447548 -271.391468) (xy 124.488051 -271.419424) (xy 124.523544 -271.453516)
			(xy 124.553109 -271.49286) (xy 124.57598 -271.536437) (xy 124.591564 -271.583118) (xy 124.599459 -271.631695)
			(xy 124.599954 -271.656302) (xy 124.928896 -271.656302) (xy 124.932856 -271.607248) (xy 124.944633 -271.559464)
			(xy 124.963924 -271.514188) (xy 124.990227 -271.472592) (xy 125.022862 -271.435755) (xy 125.060983 -271.40463)
			(xy 125.103604 -271.380023) (xy 125.14962 -271.362571) (xy 125.197839 -271.352727) (xy 125.247014 -271.350746)
			(xy 125.295869 -271.356678) (xy 125.34314 -271.37037) (xy 125.387602 -271.391468) (xy 125.428105 -271.419424)
			(xy 125.463598 -271.453516) (xy 125.493163 -271.49286) (xy 125.516034 -271.536437) (xy 125.531618 -271.583118)
			(xy 125.539513 -271.631695) (xy 125.540008 -271.656302) (xy 125.86895 -271.656302) (xy 125.87291 -271.607248)
			(xy 125.884687 -271.559464) (xy 125.903978 -271.514188) (xy 125.930281 -271.472592) (xy 125.962916 -271.435755)
			(xy 126.001037 -271.40463) (xy 126.043658 -271.380023) (xy 126.089674 -271.362571) (xy 126.137893 -271.352727)
			(xy 126.187068 -271.350746) (xy 126.235923 -271.356678) (xy 126.283194 -271.37037) (xy 126.327656 -271.391468)
			(xy 126.368159 -271.419424) (xy 126.403652 -271.453516) (xy 126.433217 -271.49286) (xy 126.456088 -271.536437)
			(xy 126.471672 -271.583118) (xy 126.479567 -271.631695) (xy 126.480062 -271.656302) (xy 126.809004 -271.656302)
			(xy 126.812964 -271.607248) (xy 126.824741 -271.559464) (xy 126.844032 -271.514188) (xy 126.870335 -271.472592)
			(xy 126.90297 -271.435755) (xy 126.941091 -271.40463) (xy 126.983712 -271.380023) (xy 127.029728 -271.362571)
			(xy 127.077947 -271.352727) (xy 127.127122 -271.350746) (xy 127.175977 -271.356678) (xy 127.223248 -271.37037)
			(xy 127.26771 -271.391468) (xy 127.308213 -271.419424) (xy 127.343706 -271.453516) (xy 127.373271 -271.49286)
			(xy 127.396142 -271.536437) (xy 127.411726 -271.583118) (xy 127.419621 -271.631695) (xy 127.420116 -271.656302)
			(xy 127.738627 -271.656302) (xy 127.742722 -271.605574) (xy 127.754901 -271.55616) (xy 127.774849 -271.50934)
			(xy 127.80205 -271.466326) (xy 127.835798 -271.428232) (xy 127.87522 -271.396045) (xy 127.919294 -271.370599)
			(xy 127.96688 -271.352552) (xy 128.016744 -271.342372) (xy 128.067596 -271.340323) (xy 128.118117 -271.346457)
			(xy 128.167001 -271.360617) (xy 128.21298 -271.382434) (xy 128.254864 -271.411344) (xy 128.291568 -271.446599)
			(xy 128.322141 -271.487285) (xy 128.345792 -271.532348) (xy 128.361908 -271.580622) (xy 128.370072 -271.630856)
			(xy 128.370584 -271.656302) (xy 128.688858 -271.656302) (xy 128.692818 -271.607248) (xy 128.704595 -271.559464)
			(xy 128.723886 -271.514188) (xy 128.750189 -271.472592) (xy 128.782824 -271.435755) (xy 128.820945 -271.40463)
			(xy 128.863566 -271.380023) (xy 128.909582 -271.362571) (xy 128.957801 -271.352727) (xy 129.006976 -271.350746)
			(xy 129.055831 -271.356678) (xy 129.103102 -271.37037) (xy 129.147564 -271.391468) (xy 129.188067 -271.419424)
			(xy 129.22356 -271.453516) (xy 129.253125 -271.49286) (xy 129.275996 -271.536437) (xy 129.29158 -271.583118)
			(xy 129.299475 -271.631695) (xy 129.29997 -271.656302) (xy 129.618481 -271.656302) (xy 129.622576 -271.605574)
			(xy 129.634755 -271.55616) (xy 129.654703 -271.50934) (xy 129.681904 -271.466326) (xy 129.715652 -271.428232)
			(xy 129.755074 -271.396045) (xy 129.799148 -271.370599) (xy 129.846734 -271.352552) (xy 129.896598 -271.342372)
			(xy 129.94745 -271.340323) (xy 129.997971 -271.346457) (xy 130.046855 -271.360617) (xy 130.092834 -271.382434)
			(xy 130.134718 -271.411344) (xy 130.171422 -271.446599) (xy 130.201995 -271.487285) (xy 130.225646 -271.532348)
			(xy 130.241762 -271.580622) (xy 130.249926 -271.630856) (xy 130.250438 -271.656302) (xy 130.568966 -271.656302)
			(xy 130.572926 -271.607248) (xy 130.584703 -271.559464) (xy 130.603994 -271.514188) (xy 130.630297 -271.472592)
			(xy 130.662932 -271.435755) (xy 130.701053 -271.40463) (xy 130.743674 -271.380023) (xy 130.78969 -271.362571)
			(xy 130.837909 -271.352727) (xy 130.887084 -271.350746) (xy 130.935939 -271.356678) (xy 130.98321 -271.37037)
			(xy 131.027672 -271.391468) (xy 131.068175 -271.419424) (xy 131.103668 -271.453516) (xy 131.133233 -271.49286)
			(xy 131.156104 -271.536437) (xy 131.171688 -271.583118) (xy 131.179583 -271.631695) (xy 131.180078 -271.656302)
			(xy 131.498589 -271.656302) (xy 131.502684 -271.605574) (xy 131.514863 -271.55616) (xy 131.534811 -271.50934)
			(xy 131.562012 -271.466326) (xy 131.59576 -271.428232) (xy 131.635182 -271.396045) (xy 131.679256 -271.370599)
			(xy 131.726842 -271.352552) (xy 131.776706 -271.342372) (xy 131.827558 -271.340323) (xy 131.878079 -271.346457)
			(xy 131.926963 -271.360617) (xy 131.972942 -271.382434) (xy 132.014826 -271.411344) (xy 132.05153 -271.446599)
			(xy 132.082103 -271.487285) (xy 132.105754 -271.532348) (xy 132.12187 -271.580622) (xy 132.130034 -271.630856)
			(xy 132.130546 -271.656302) (xy 132.438643 -271.656302) (xy 132.442738 -271.605574) (xy 132.454917 -271.55616)
			(xy 132.474865 -271.50934) (xy 132.502066 -271.466326) (xy 132.535814 -271.428232) (xy 132.575236 -271.396045)
			(xy 132.61931 -271.370599) (xy 132.666896 -271.352552) (xy 132.71676 -271.342372) (xy 132.767612 -271.340323)
			(xy 132.818133 -271.346457) (xy 132.867017 -271.360617) (xy 132.912996 -271.382434) (xy 132.95488 -271.411344)
			(xy 132.991584 -271.446599) (xy 133.022157 -271.487285) (xy 133.045808 -271.532348) (xy 133.061924 -271.580622)
			(xy 133.070088 -271.630856) (xy 133.0706 -271.656302) (xy 133.388874 -271.656302) (xy 133.392834 -271.607248)
			(xy 133.404611 -271.559464) (xy 133.423902 -271.514188) (xy 133.450205 -271.472592) (xy 133.48284 -271.435755)
			(xy 133.520961 -271.40463) (xy 133.563582 -271.380023) (xy 133.609598 -271.362571) (xy 133.657817 -271.352727)
			(xy 133.706992 -271.350746) (xy 133.755847 -271.356678) (xy 133.803118 -271.37037) (xy 133.84758 -271.391468)
			(xy 133.888083 -271.419424) (xy 133.923576 -271.453516) (xy 133.953141 -271.49286) (xy 133.976012 -271.536437)
			(xy 133.991596 -271.583118) (xy 133.999491 -271.631695) (xy 133.999986 -271.656302) (xy 134.328928 -271.656302)
			(xy 134.332888 -271.607248) (xy 134.344665 -271.559464) (xy 134.363956 -271.514188) (xy 134.390259 -271.472592)
			(xy 134.422894 -271.435755) (xy 134.461015 -271.40463) (xy 134.503636 -271.380023) (xy 134.549652 -271.362571)
			(xy 134.597871 -271.352727) (xy 134.647046 -271.350746) (xy 134.695901 -271.356678) (xy 134.743172 -271.37037)
			(xy 134.787634 -271.391468) (xy 134.828137 -271.419424) (xy 134.86363 -271.453516) (xy 134.893195 -271.49286)
			(xy 134.916066 -271.536437) (xy 134.93165 -271.583118) (xy 134.939545 -271.631695) (xy 134.94004 -271.656302)
			(xy 135.268982 -271.656302) (xy 135.272942 -271.607248) (xy 135.284719 -271.559464) (xy 135.30401 -271.514188)
			(xy 135.330313 -271.472592) (xy 135.362948 -271.435755) (xy 135.401069 -271.40463) (xy 135.44369 -271.380023)
			(xy 135.489706 -271.362571) (xy 135.537925 -271.352727) (xy 135.5871 -271.350746) (xy 135.635955 -271.356678)
			(xy 135.683226 -271.37037) (xy 135.727688 -271.391468) (xy 135.768191 -271.419424) (xy 135.803684 -271.453516)
			(xy 135.833249 -271.49286) (xy 135.85612 -271.536437) (xy 135.871704 -271.583118) (xy 135.879599 -271.631695)
			(xy 135.880094 -271.656302) (xy 136.209036 -271.656302) (xy 136.212996 -271.607248) (xy 136.224773 -271.559464)
			(xy 136.244064 -271.514188) (xy 136.270367 -271.472592) (xy 136.303002 -271.435755) (xy 136.341123 -271.40463)
			(xy 136.383744 -271.380023) (xy 136.42976 -271.362571) (xy 136.477979 -271.352727) (xy 136.527154 -271.350746)
			(xy 136.576009 -271.356678) (xy 136.62328 -271.37037) (xy 136.667742 -271.391468) (xy 136.708245 -271.419424)
			(xy 136.743738 -271.453516) (xy 136.773303 -271.49286) (xy 136.796174 -271.536437) (xy 136.811758 -271.583118)
			(xy 136.819653 -271.631695) (xy 136.820148 -271.656302) (xy 137.148836 -271.656302) (xy 137.152796 -271.607248)
			(xy 137.164573 -271.559464) (xy 137.183864 -271.514188) (xy 137.210167 -271.472592) (xy 137.242802 -271.435755)
			(xy 137.280923 -271.40463) (xy 137.323544 -271.380023) (xy 137.36956 -271.362571) (xy 137.417779 -271.352727)
			(xy 137.466954 -271.350746) (xy 137.515809 -271.356678) (xy 137.56308 -271.37037) (xy 137.607542 -271.391468)
			(xy 137.648045 -271.419424) (xy 137.683538 -271.453516) (xy 137.713103 -271.49286) (xy 137.735974 -271.536437)
			(xy 137.751558 -271.583118) (xy 137.759453 -271.631695) (xy 137.759948 -271.656302) (xy 138.08889 -271.656302)
			(xy 138.09285 -271.607248) (xy 138.104627 -271.559464) (xy 138.123918 -271.514188) (xy 138.150221 -271.472592)
			(xy 138.182856 -271.435755) (xy 138.220977 -271.40463) (xy 138.263598 -271.380023) (xy 138.309614 -271.362571)
			(xy 138.357833 -271.352727) (xy 138.407008 -271.350746) (xy 138.455863 -271.356678) (xy 138.503134 -271.37037)
			(xy 138.547596 -271.391468) (xy 138.588099 -271.419424) (xy 138.623592 -271.453516) (xy 138.653157 -271.49286)
			(xy 138.676028 -271.536437) (xy 138.691612 -271.583118) (xy 138.699507 -271.631695) (xy 138.700002 -271.656302)
			(xy 139.028944 -271.656302) (xy 139.032904 -271.607248) (xy 139.044681 -271.559464) (xy 139.063972 -271.514188)
			(xy 139.090275 -271.472592) (xy 139.12291 -271.435755) (xy 139.161031 -271.40463) (xy 139.203652 -271.380023)
			(xy 139.249668 -271.362571) (xy 139.297887 -271.352727) (xy 139.347062 -271.350746) (xy 139.395917 -271.356678)
			(xy 139.443188 -271.37037) (xy 139.48765 -271.391468) (xy 139.528153 -271.419424) (xy 139.563646 -271.453516)
			(xy 139.593211 -271.49286) (xy 139.616082 -271.536437) (xy 139.631666 -271.583118) (xy 139.639561 -271.631695)
			(xy 139.640056 -271.656302) (xy 139.639561 -271.680909) (xy 139.631666 -271.729486) (xy 139.616082 -271.776167)
			(xy 139.593211 -271.819744) (xy 139.563646 -271.859088) (xy 139.528153 -271.89318) (xy 139.48765 -271.921136)
			(xy 139.443188 -271.942234) (xy 139.395917 -271.955926) (xy 139.347062 -271.961858) (xy 139.297887 -271.959877)
			(xy 139.249668 -271.950033) (xy 139.203652 -271.932581) (xy 139.161031 -271.907974) (xy 139.12291 -271.876849)
			(xy 139.090275 -271.840012) (xy 139.063972 -271.798416) (xy 139.044681 -271.75314) (xy 139.032904 -271.705356)
			(xy 139.028944 -271.656302) (xy 138.700002 -271.656302) (xy 138.699507 -271.680909) (xy 138.691612 -271.729486)
			(xy 138.676028 -271.776167) (xy 138.653157 -271.819744) (xy 138.623592 -271.859088) (xy 138.588099 -271.89318)
			(xy 138.547596 -271.921136) (xy 138.503134 -271.942234) (xy 138.455863 -271.955926) (xy 138.407008 -271.961858)
			(xy 138.357833 -271.959877) (xy 138.309614 -271.950033) (xy 138.263598 -271.932581) (xy 138.220977 -271.907974)
			(xy 138.182856 -271.876849) (xy 138.150221 -271.840012) (xy 138.123918 -271.798416) (xy 138.104627 -271.75314)
			(xy 138.09285 -271.705356) (xy 138.08889 -271.656302) (xy 137.759948 -271.656302) (xy 137.759453 -271.680909)
			(xy 137.751558 -271.729486) (xy 137.735974 -271.776167) (xy 137.713103 -271.819744) (xy 137.683538 -271.859088)
			(xy 137.648045 -271.89318) (xy 137.607542 -271.921136) (xy 137.56308 -271.942234) (xy 137.515809 -271.955926)
			(xy 137.466954 -271.961858) (xy 137.417779 -271.959877) (xy 137.36956 -271.950033) (xy 137.323544 -271.932581)
			(xy 137.280923 -271.907974) (xy 137.242802 -271.876849) (xy 137.210167 -271.840012) (xy 137.183864 -271.798416)
			(xy 137.164573 -271.75314) (xy 137.152796 -271.705356) (xy 137.148836 -271.656302) (xy 136.820148 -271.656302)
			(xy 136.819653 -271.680909) (xy 136.811758 -271.729486) (xy 136.796174 -271.776167) (xy 136.773303 -271.819744)
			(xy 136.743738 -271.859088) (xy 136.708245 -271.89318) (xy 136.667742 -271.921136) (xy 136.62328 -271.942234)
			(xy 136.576009 -271.955926) (xy 136.527154 -271.961858) (xy 136.477979 -271.959877) (xy 136.42976 -271.950033)
			(xy 136.383744 -271.932581) (xy 136.341123 -271.907974) (xy 136.303002 -271.876849) (xy 136.270367 -271.840012)
			(xy 136.244064 -271.798416) (xy 136.224773 -271.75314) (xy 136.212996 -271.705356) (xy 136.209036 -271.656302)
			(xy 135.880094 -271.656302) (xy 135.879599 -271.680909) (xy 135.871704 -271.729486) (xy 135.85612 -271.776167)
			(xy 135.833249 -271.819744) (xy 135.803684 -271.859088) (xy 135.768191 -271.89318) (xy 135.727688 -271.921136)
			(xy 135.683226 -271.942234) (xy 135.635955 -271.955926) (xy 135.5871 -271.961858) (xy 135.537925 -271.959877)
			(xy 135.489706 -271.950033) (xy 135.44369 -271.932581) (xy 135.401069 -271.907974) (xy 135.362948 -271.876849)
			(xy 135.330313 -271.840012) (xy 135.30401 -271.798416) (xy 135.284719 -271.75314) (xy 135.272942 -271.705356)
			(xy 135.268982 -271.656302) (xy 134.94004 -271.656302) (xy 134.939545 -271.680909) (xy 134.93165 -271.729486)
			(xy 134.916066 -271.776167) (xy 134.893195 -271.819744) (xy 134.86363 -271.859088) (xy 134.828137 -271.89318)
			(xy 134.787634 -271.921136) (xy 134.743172 -271.942234) (xy 134.695901 -271.955926) (xy 134.647046 -271.961858)
			(xy 134.597871 -271.959877) (xy 134.549652 -271.950033) (xy 134.503636 -271.932581) (xy 134.461015 -271.907974)
			(xy 134.422894 -271.876849) (xy 134.390259 -271.840012) (xy 134.363956 -271.798416) (xy 134.344665 -271.75314)
			(xy 134.332888 -271.705356) (xy 134.328928 -271.656302) (xy 133.999986 -271.656302) (xy 133.999491 -271.680909)
			(xy 133.991596 -271.729486) (xy 133.976012 -271.776167) (xy 133.953141 -271.819744) (xy 133.923576 -271.859088)
			(xy 133.888083 -271.89318) (xy 133.84758 -271.921136) (xy 133.803118 -271.942234) (xy 133.755847 -271.955926)
			(xy 133.706992 -271.961858) (xy 133.657817 -271.959877) (xy 133.609598 -271.950033) (xy 133.563582 -271.932581)
			(xy 133.520961 -271.907974) (xy 133.48284 -271.876849) (xy 133.450205 -271.840012) (xy 133.423902 -271.798416)
			(xy 133.404611 -271.75314) (xy 133.392834 -271.705356) (xy 133.388874 -271.656302) (xy 133.0706 -271.656302)
			(xy 133.070088 -271.681748) (xy 133.061924 -271.731982) (xy 133.045808 -271.780256) (xy 133.022157 -271.825319)
			(xy 132.991584 -271.866005) (xy 132.95488 -271.90126) (xy 132.912996 -271.93017) (xy 132.867017 -271.951987)
			(xy 132.818133 -271.966147) (xy 132.767612 -271.972281) (xy 132.71676 -271.970232) (xy 132.666896 -271.960052)
			(xy 132.61931 -271.942005) (xy 132.575236 -271.916559) (xy 132.535814 -271.884372) (xy 132.502066 -271.846278)
			(xy 132.474865 -271.803264) (xy 132.454917 -271.756444) (xy 132.442738 -271.70703) (xy 132.438643 -271.656302)
			(xy 132.130546 -271.656302) (xy 132.130034 -271.681748) (xy 132.12187 -271.731982) (xy 132.105754 -271.780256)
			(xy 132.082103 -271.825319) (xy 132.05153 -271.866005) (xy 132.014826 -271.90126) (xy 131.972942 -271.93017)
			(xy 131.926963 -271.951987) (xy 131.878079 -271.966147) (xy 131.827558 -271.972281) (xy 131.776706 -271.970232)
			(xy 131.726842 -271.960052) (xy 131.679256 -271.942005) (xy 131.635182 -271.916559) (xy 131.59576 -271.884372)
			(xy 131.562012 -271.846278) (xy 131.534811 -271.803264) (xy 131.514863 -271.756444) (xy 131.502684 -271.70703)
			(xy 131.498589 -271.656302) (xy 131.180078 -271.656302) (xy 131.179583 -271.680909) (xy 131.171688 -271.729486)
			(xy 131.156104 -271.776167) (xy 131.133233 -271.819744) (xy 131.103668 -271.859088) (xy 131.068175 -271.89318)
			(xy 131.027672 -271.921136) (xy 130.98321 -271.942234) (xy 130.935939 -271.955926) (xy 130.887084 -271.961858)
			(xy 130.837909 -271.959877) (xy 130.78969 -271.950033) (xy 130.743674 -271.932581) (xy 130.701053 -271.907974)
			(xy 130.662932 -271.876849) (xy 130.630297 -271.840012) (xy 130.603994 -271.798416) (xy 130.584703 -271.75314)
			(xy 130.572926 -271.705356) (xy 130.568966 -271.656302) (xy 130.250438 -271.656302) (xy 130.249926 -271.681748)
			(xy 130.241762 -271.731982) (xy 130.225646 -271.780256) (xy 130.201995 -271.825319) (xy 130.171422 -271.866005)
			(xy 130.134718 -271.90126) (xy 130.092834 -271.93017) (xy 130.046855 -271.951987) (xy 129.997971 -271.966147)
			(xy 129.94745 -271.972281) (xy 129.896598 -271.970232) (xy 129.846734 -271.960052) (xy 129.799148 -271.942005)
			(xy 129.755074 -271.916559) (xy 129.715652 -271.884372) (xy 129.681904 -271.846278) (xy 129.654703 -271.803264)
			(xy 129.634755 -271.756444) (xy 129.622576 -271.70703) (xy 129.618481 -271.656302) (xy 129.29997 -271.656302)
			(xy 129.299475 -271.680909) (xy 129.29158 -271.729486) (xy 129.275996 -271.776167) (xy 129.253125 -271.819744)
			(xy 129.22356 -271.859088) (xy 129.188067 -271.89318) (xy 129.147564 -271.921136) (xy 129.103102 -271.942234)
			(xy 129.055831 -271.955926) (xy 129.006976 -271.961858) (xy 128.957801 -271.959877) (xy 128.909582 -271.950033)
			(xy 128.863566 -271.932581) (xy 128.820945 -271.907974) (xy 128.782824 -271.876849) (xy 128.750189 -271.840012)
			(xy 128.723886 -271.798416) (xy 128.704595 -271.75314) (xy 128.692818 -271.705356) (xy 128.688858 -271.656302)
			(xy 128.370584 -271.656302) (xy 128.370072 -271.681748) (xy 128.361908 -271.731982) (xy 128.345792 -271.780256)
			(xy 128.322141 -271.825319) (xy 128.291568 -271.866005) (xy 128.254864 -271.90126) (xy 128.21298 -271.93017)
			(xy 128.167001 -271.951987) (xy 128.118117 -271.966147) (xy 128.067596 -271.972281) (xy 128.016744 -271.970232)
			(xy 127.96688 -271.960052) (xy 127.919294 -271.942005) (xy 127.87522 -271.916559) (xy 127.835798 -271.884372)
			(xy 127.80205 -271.846278) (xy 127.774849 -271.803264) (xy 127.754901 -271.756444) (xy 127.742722 -271.70703)
			(xy 127.738627 -271.656302) (xy 127.420116 -271.656302) (xy 127.419621 -271.680909) (xy 127.411726 -271.729486)
			(xy 127.396142 -271.776167) (xy 127.373271 -271.819744) (xy 127.343706 -271.859088) (xy 127.308213 -271.89318)
			(xy 127.26771 -271.921136) (xy 127.223248 -271.942234) (xy 127.175977 -271.955926) (xy 127.127122 -271.961858)
			(xy 127.077947 -271.959877) (xy 127.029728 -271.950033) (xy 126.983712 -271.932581) (xy 126.941091 -271.907974)
			(xy 126.90297 -271.876849) (xy 126.870335 -271.840012) (xy 126.844032 -271.798416) (xy 126.824741 -271.75314)
			(xy 126.812964 -271.705356) (xy 126.809004 -271.656302) (xy 126.480062 -271.656302) (xy 126.479567 -271.680909)
			(xy 126.471672 -271.729486) (xy 126.456088 -271.776167) (xy 126.433217 -271.819744) (xy 126.403652 -271.859088)
			(xy 126.368159 -271.89318) (xy 126.327656 -271.921136) (xy 126.283194 -271.942234) (xy 126.235923 -271.955926)
			(xy 126.187068 -271.961858) (xy 126.137893 -271.959877) (xy 126.089674 -271.950033) (xy 126.043658 -271.932581)
			(xy 126.001037 -271.907974) (xy 125.962916 -271.876849) (xy 125.930281 -271.840012) (xy 125.903978 -271.798416)
			(xy 125.884687 -271.75314) (xy 125.87291 -271.705356) (xy 125.86895 -271.656302) (xy 125.540008 -271.656302)
			(xy 125.539513 -271.680909) (xy 125.531618 -271.729486) (xy 125.516034 -271.776167) (xy 125.493163 -271.819744)
			(xy 125.463598 -271.859088) (xy 125.428105 -271.89318) (xy 125.387602 -271.921136) (xy 125.34314 -271.942234)
			(xy 125.295869 -271.955926) (xy 125.247014 -271.961858) (xy 125.197839 -271.959877) (xy 125.14962 -271.950033)
			(xy 125.103604 -271.932581) (xy 125.060983 -271.907974) (xy 125.022862 -271.876849) (xy 124.990227 -271.840012)
			(xy 124.963924 -271.798416) (xy 124.944633 -271.75314) (xy 124.932856 -271.705356) (xy 124.928896 -271.656302)
			(xy 124.599954 -271.656302) (xy 124.599459 -271.680909) (xy 124.591564 -271.729486) (xy 124.57598 -271.776167)
			(xy 124.553109 -271.819744) (xy 124.523544 -271.859088) (xy 124.488051 -271.89318) (xy 124.447548 -271.921136)
			(xy 124.403086 -271.942234) (xy 124.355815 -271.955926) (xy 124.30696 -271.961858) (xy 124.257785 -271.959877)
			(xy 124.209566 -271.950033) (xy 124.16355 -271.932581) (xy 124.120929 -271.907974) (xy 124.082808 -271.876849)
			(xy 124.050173 -271.840012) (xy 124.02387 -271.798416) (xy 124.004579 -271.75314) (xy 123.992802 -271.705356)
			(xy 123.988842 -271.656302) (xy 123.660154 -271.656302) (xy 123.659659 -271.680909) (xy 123.651764 -271.729486)
			(xy 123.63618 -271.776167) (xy 123.613309 -271.819744) (xy 123.583744 -271.859088) (xy 123.548251 -271.89318)
			(xy 123.507748 -271.921136) (xy 123.463286 -271.942234) (xy 123.416015 -271.955926) (xy 123.36716 -271.961858)
			(xy 123.317985 -271.959877) (xy 123.269766 -271.950033) (xy 123.22375 -271.932581) (xy 123.181129 -271.907974)
			(xy 123.143008 -271.876849) (xy 123.110373 -271.840012) (xy 123.08407 -271.798416) (xy 123.064779 -271.75314)
			(xy 123.053002 -271.705356) (xy 123.049042 -271.656302) (xy 122.7201 -271.656302) (xy 122.719605 -271.680909)
			(xy 122.71171 -271.729486) (xy 122.696126 -271.776167) (xy 122.673255 -271.819744) (xy 122.64369 -271.859088)
			(xy 122.608197 -271.89318) (xy 122.567694 -271.921136) (xy 122.523232 -271.942234) (xy 122.475961 -271.955926)
			(xy 122.427106 -271.961858) (xy 122.377931 -271.959877) (xy 122.329712 -271.950033) (xy 122.283696 -271.932581)
			(xy 122.241075 -271.907974) (xy 122.202954 -271.876849) (xy 122.170319 -271.840012) (xy 122.144016 -271.798416)
			(xy 122.124725 -271.75314) (xy 122.112948 -271.705356) (xy 122.108988 -271.656302) (xy 121.780046 -271.656302)
			(xy 121.779551 -271.680909) (xy 121.771656 -271.729486) (xy 121.756072 -271.776167) (xy 121.733201 -271.819744)
			(xy 121.703636 -271.859088) (xy 121.668143 -271.89318) (xy 121.62764 -271.921136) (xy 121.583178 -271.942234)
			(xy 121.535907 -271.955926) (xy 121.487052 -271.961858) (xy 121.437877 -271.959877) (xy 121.389658 -271.950033)
			(xy 121.343642 -271.932581) (xy 121.301021 -271.907974) (xy 121.2629 -271.876849) (xy 121.230265 -271.840012)
			(xy 121.203962 -271.798416) (xy 121.184671 -271.75314) (xy 121.172894 -271.705356) (xy 121.168934 -271.656302)
			(xy 120.839992 -271.656302) (xy 120.839497 -271.680909) (xy 120.831602 -271.729486) (xy 120.816018 -271.776167)
			(xy 120.793147 -271.819744) (xy 120.763582 -271.859088) (xy 120.728089 -271.89318) (xy 120.687586 -271.921136)
			(xy 120.643124 -271.942234) (xy 120.595853 -271.955926) (xy 120.546998 -271.961858) (xy 120.497823 -271.959877)
			(xy 120.449604 -271.950033) (xy 120.403588 -271.932581) (xy 120.360967 -271.907974) (xy 120.322846 -271.876849)
			(xy 120.290211 -271.840012) (xy 120.263908 -271.798416) (xy 120.244617 -271.75314) (xy 120.23284 -271.705356)
			(xy 120.22888 -271.656302) (xy 119.899938 -271.656302) (xy 119.899443 -271.680909) (xy 119.891548 -271.729486)
			(xy 119.875964 -271.776167) (xy 119.853093 -271.819744) (xy 119.823528 -271.859088) (xy 119.788035 -271.89318)
			(xy 119.747532 -271.921136) (xy 119.70307 -271.942234) (xy 119.655799 -271.955926) (xy 119.606944 -271.961858)
			(xy 119.557769 -271.959877) (xy 119.50955 -271.950033) (xy 119.463534 -271.932581) (xy 119.420913 -271.907974)
			(xy 119.382792 -271.876849) (xy 119.350157 -271.840012) (xy 119.323854 -271.798416) (xy 119.304563 -271.75314)
			(xy 119.292786 -271.705356) (xy 119.288826 -271.656302) (xy 118.960138 -271.656302) (xy 118.959643 -271.680909)
			(xy 118.951748 -271.729486) (xy 118.936164 -271.776167) (xy 118.913293 -271.819744) (xy 118.883728 -271.859088)
			(xy 118.848235 -271.89318) (xy 118.807732 -271.921136) (xy 118.76327 -271.942234) (xy 118.715999 -271.955926)
			(xy 118.667144 -271.961858) (xy 118.617969 -271.959877) (xy 118.56975 -271.950033) (xy 118.523734 -271.932581)
			(xy 118.481113 -271.907974) (xy 118.442992 -271.876849) (xy 118.410357 -271.840012) (xy 118.384054 -271.798416)
			(xy 118.364763 -271.75314) (xy 118.352986 -271.705356) (xy 118.349026 -271.656302) (xy 118.020084 -271.656302)
			(xy 118.019589 -271.680909) (xy 118.011694 -271.729486) (xy 117.99611 -271.776167) (xy 117.973239 -271.819744)
			(xy 117.943674 -271.859088) (xy 117.908181 -271.89318) (xy 117.867678 -271.921136) (xy 117.823216 -271.942234)
			(xy 117.775945 -271.955926) (xy 117.72709 -271.961858) (xy 117.677915 -271.959877) (xy 117.629696 -271.950033)
			(xy 117.58368 -271.932581) (xy 117.541059 -271.907974) (xy 117.502938 -271.876849) (xy 117.470303 -271.840012)
			(xy 117.444 -271.798416) (xy 117.424709 -271.75314) (xy 117.412932 -271.705356) (xy 117.408972 -271.656302)
			(xy 117.08003 -271.656302) (xy 117.079535 -271.680909) (xy 117.07164 -271.729486) (xy 117.056056 -271.776167)
			(xy 117.033185 -271.819744) (xy 117.00362 -271.859088) (xy 116.968127 -271.89318) (xy 116.927624 -271.921136)
			(xy 116.883162 -271.942234) (xy 116.835891 -271.955926) (xy 116.787036 -271.961858) (xy 116.737861 -271.959877)
			(xy 116.689642 -271.950033) (xy 116.643626 -271.932581) (xy 116.601005 -271.907974) (xy 116.562884 -271.876849)
			(xy 116.530249 -271.840012) (xy 116.503946 -271.798416) (xy 116.484655 -271.75314) (xy 116.472878 -271.705356)
			(xy 116.468918 -271.656302) (xy 116.139976 -271.656302) (xy 116.139481 -271.680909) (xy 116.131586 -271.729486)
			(xy 116.116002 -271.776167) (xy 116.093131 -271.819744) (xy 116.063566 -271.859088) (xy 116.028073 -271.89318)
			(xy 115.98757 -271.921136) (xy 115.943108 -271.942234) (xy 115.895837 -271.955926) (xy 115.846982 -271.961858)
			(xy 115.797807 -271.959877) (xy 115.749588 -271.950033) (xy 115.703572 -271.932581) (xy 115.660951 -271.907974)
			(xy 115.62283 -271.876849) (xy 115.590195 -271.840012) (xy 115.563892 -271.798416) (xy 115.544601 -271.75314)
			(xy 115.532824 -271.705356) (xy 115.528864 -271.656302) (xy 115.199922 -271.656302) (xy 115.199427 -271.680909)
			(xy 115.191532 -271.729486) (xy 115.175948 -271.776167) (xy 115.153077 -271.819744) (xy 115.123512 -271.859088)
			(xy 115.088019 -271.89318) (xy 115.047516 -271.921136) (xy 115.003054 -271.942234) (xy 114.955783 -271.955926)
			(xy 114.906928 -271.961858) (xy 114.857753 -271.959877) (xy 114.809534 -271.950033) (xy 114.763518 -271.932581)
			(xy 114.720897 -271.907974) (xy 114.682776 -271.876849) (xy 114.650141 -271.840012) (xy 114.623838 -271.798416)
			(xy 114.604547 -271.75314) (xy 114.59277 -271.705356) (xy 114.58881 -271.656302) (xy 114.260122 -271.656302)
			(xy 114.259627 -271.680909) (xy 114.251732 -271.729486) (xy 114.236148 -271.776167) (xy 114.213277 -271.819744)
			(xy 114.183712 -271.859088) (xy 114.148219 -271.89318) (xy 114.107716 -271.921136) (xy 114.063254 -271.942234)
			(xy 114.015983 -271.955926) (xy 113.967128 -271.961858) (xy 113.917953 -271.959877) (xy 113.869734 -271.950033)
			(xy 113.823718 -271.932581) (xy 113.781097 -271.907974) (xy 113.742976 -271.876849) (xy 113.710341 -271.840012)
			(xy 113.684038 -271.798416) (xy 113.664747 -271.75314) (xy 113.65297 -271.705356) (xy 113.64901 -271.656302)
			(xy 110.506256 -271.656302) (xy 110.505761 -271.680909) (xy 110.497866 -271.729486) (xy 110.482282 -271.776167)
			(xy 110.459411 -271.819744) (xy 110.429846 -271.859088) (xy 110.394353 -271.89318) (xy 110.35385 -271.921136)
			(xy 110.309388 -271.942234) (xy 110.262117 -271.955926) (xy 110.213262 -271.961858) (xy 110.164087 -271.959877)
			(xy 110.115868 -271.950033) (xy 110.069852 -271.932581) (xy 110.027231 -271.907974) (xy 109.98911 -271.876849)
			(xy 109.956475 -271.840012) (xy 109.930172 -271.798416) (xy 109.910881 -271.75314) (xy 109.899104 -271.705356)
			(xy 109.895144 -271.656302) (xy 109.566456 -271.656302) (xy 109.565961 -271.680909) (xy 109.558066 -271.729486)
			(xy 109.542482 -271.776167) (xy 109.519611 -271.819744) (xy 109.490046 -271.859088) (xy 109.454553 -271.89318)
			(xy 109.41405 -271.921136) (xy 109.369588 -271.942234) (xy 109.322317 -271.955926) (xy 109.273462 -271.961858)
			(xy 109.224287 -271.959877) (xy 109.176068 -271.950033) (xy 109.130052 -271.932581) (xy 109.087431 -271.907974)
			(xy 109.04931 -271.876849) (xy 109.016675 -271.840012) (xy 108.990372 -271.798416) (xy 108.971081 -271.75314)
			(xy 108.959304 -271.705356) (xy 108.955344 -271.656302) (xy 108.626402 -271.656302) (xy 108.625907 -271.680909)
			(xy 108.618012 -271.729486) (xy 108.602428 -271.776167) (xy 108.579557 -271.819744) (xy 108.549992 -271.859088)
			(xy 108.514499 -271.89318) (xy 108.473996 -271.921136) (xy 108.429534 -271.942234) (xy 108.382263 -271.955926)
			(xy 108.333408 -271.961858) (xy 108.284233 -271.959877) (xy 108.236014 -271.950033) (xy 108.189998 -271.932581)
			(xy 108.147377 -271.907974) (xy 108.109256 -271.876849) (xy 108.076621 -271.840012) (xy 108.050318 -271.798416)
			(xy 108.031027 -271.75314) (xy 108.01925 -271.705356) (xy 108.01529 -271.656302) (xy 107.686348 -271.656302)
			(xy 107.685853 -271.680909) (xy 107.677958 -271.729486) (xy 107.662374 -271.776167) (xy 107.639503 -271.819744)
			(xy 107.609938 -271.859088) (xy 107.574445 -271.89318) (xy 107.533942 -271.921136) (xy 107.48948 -271.942234)
			(xy 107.442209 -271.955926) (xy 107.393354 -271.961858) (xy 107.344179 -271.959877) (xy 107.29596 -271.950033)
			(xy 107.249944 -271.932581) (xy 107.207323 -271.907974) (xy 107.169202 -271.876849) (xy 107.136567 -271.840012)
			(xy 107.110264 -271.798416) (xy 107.090973 -271.75314) (xy 107.079196 -271.705356) (xy 107.075236 -271.656302)
			(xy 106.746294 -271.656302) (xy 106.745799 -271.680909) (xy 106.737904 -271.729486) (xy 106.72232 -271.776167)
			(xy 106.699449 -271.819744) (xy 106.669884 -271.859088) (xy 106.634391 -271.89318) (xy 106.593888 -271.921136)
			(xy 106.549426 -271.942234) (xy 106.502155 -271.955926) (xy 106.4533 -271.961858) (xy 106.404125 -271.959877)
			(xy 106.355906 -271.950033) (xy 106.30989 -271.932581) (xy 106.267269 -271.907974) (xy 106.229148 -271.876849)
			(xy 106.196513 -271.840012) (xy 106.17021 -271.798416) (xy 106.150919 -271.75314) (xy 106.139142 -271.705356)
			(xy 106.135182 -271.656302) (xy 105.80624 -271.656302) (xy 105.805745 -271.680909) (xy 105.79785 -271.729486)
			(xy 105.782266 -271.776167) (xy 105.759395 -271.819744) (xy 105.72983 -271.859088) (xy 105.694337 -271.89318)
			(xy 105.653834 -271.921136) (xy 105.609372 -271.942234) (xy 105.562101 -271.955926) (xy 105.513246 -271.961858)
			(xy 105.464071 -271.959877) (xy 105.415852 -271.950033) (xy 105.369836 -271.932581) (xy 105.327215 -271.907974)
			(xy 105.289094 -271.876849) (xy 105.256459 -271.840012) (xy 105.230156 -271.798416) (xy 105.210865 -271.75314)
			(xy 105.199088 -271.705356) (xy 105.195128 -271.656302) (xy 104.86644 -271.656302) (xy 104.865945 -271.680909)
			(xy 104.85805 -271.729486) (xy 104.842466 -271.776167) (xy 104.819595 -271.819744) (xy 104.79003 -271.859088)
			(xy 104.754537 -271.89318) (xy 104.714034 -271.921136) (xy 104.669572 -271.942234) (xy 104.622301 -271.955926)
			(xy 104.573446 -271.961858) (xy 104.524271 -271.959877) (xy 104.476052 -271.950033) (xy 104.430036 -271.932581)
			(xy 104.387415 -271.907974) (xy 104.349294 -271.876849) (xy 104.316659 -271.840012) (xy 104.290356 -271.798416)
			(xy 104.271065 -271.75314) (xy 104.259288 -271.705356) (xy 104.255328 -271.656302) (xy 103.926386 -271.656302)
			(xy 103.925891 -271.680909) (xy 103.917996 -271.729486) (xy 103.902412 -271.776167) (xy 103.879541 -271.819744)
			(xy 103.849976 -271.859088) (xy 103.814483 -271.89318) (xy 103.77398 -271.921136) (xy 103.729518 -271.942234)
			(xy 103.682247 -271.955926) (xy 103.633392 -271.961858) (xy 103.584217 -271.959877) (xy 103.535998 -271.950033)
			(xy 103.489982 -271.932581) (xy 103.447361 -271.907974) (xy 103.40924 -271.876849) (xy 103.376605 -271.840012)
			(xy 103.350302 -271.798416) (xy 103.331011 -271.75314) (xy 103.319234 -271.705356) (xy 103.315274 -271.656302)
			(xy 102.986332 -271.656302) (xy 102.985837 -271.680909) (xy 102.977942 -271.729486) (xy 102.962358 -271.776167)
			(xy 102.939487 -271.819744) (xy 102.909922 -271.859088) (xy 102.874429 -271.89318) (xy 102.833926 -271.921136)
			(xy 102.789464 -271.942234) (xy 102.742193 -271.955926) (xy 102.693338 -271.961858) (xy 102.644163 -271.959877)
			(xy 102.595944 -271.950033) (xy 102.549928 -271.932581) (xy 102.507307 -271.907974) (xy 102.469186 -271.876849)
			(xy 102.436551 -271.840012) (xy 102.410248 -271.798416) (xy 102.390957 -271.75314) (xy 102.37918 -271.705356)
			(xy 102.37522 -271.656302) (xy 102.046278 -271.656302) (xy 102.045783 -271.680909) (xy 102.037888 -271.729486)
			(xy 102.022304 -271.776167) (xy 101.999433 -271.819744) (xy 101.969868 -271.859088) (xy 101.934375 -271.89318)
			(xy 101.893872 -271.921136) (xy 101.84941 -271.942234) (xy 101.802139 -271.955926) (xy 101.753284 -271.961858)
			(xy 101.704109 -271.959877) (xy 101.65589 -271.950033) (xy 101.609874 -271.932581) (xy 101.567253 -271.907974)
			(xy 101.529132 -271.876849) (xy 101.496497 -271.840012) (xy 101.470194 -271.798416) (xy 101.450903 -271.75314)
			(xy 101.439126 -271.705356) (xy 101.435166 -271.656302) (xy 101.106478 -271.656302) (xy 101.105983 -271.680909)
			(xy 101.098088 -271.729486) (xy 101.082504 -271.776167) (xy 101.059633 -271.819744) (xy 101.030068 -271.859088)
			(xy 100.994575 -271.89318) (xy 100.954072 -271.921136) (xy 100.90961 -271.942234) (xy 100.862339 -271.955926)
			(xy 100.813484 -271.961858) (xy 100.764309 -271.959877) (xy 100.71609 -271.950033) (xy 100.670074 -271.932581)
			(xy 100.627453 -271.907974) (xy 100.589332 -271.876849) (xy 100.556697 -271.840012) (xy 100.530394 -271.798416)
			(xy 100.511103 -271.75314) (xy 100.499326 -271.705356) (xy 100.495366 -271.656302) (xy 100.166424 -271.656302)
			(xy 100.165929 -271.680909) (xy 100.158034 -271.729486) (xy 100.14245 -271.776167) (xy 100.119579 -271.819744)
			(xy 100.090014 -271.859088) (xy 100.054521 -271.89318) (xy 100.014018 -271.921136) (xy 99.969556 -271.942234)
			(xy 99.922285 -271.955926) (xy 99.87343 -271.961858) (xy 99.824255 -271.959877) (xy 99.776036 -271.950033)
			(xy 99.73002 -271.932581) (xy 99.687399 -271.907974) (xy 99.649278 -271.876849) (xy 99.616643 -271.840012)
			(xy 99.59034 -271.798416) (xy 99.571049 -271.75314) (xy 99.559272 -271.705356) (xy 99.555312 -271.656302)
			(xy 99.22637 -271.656302) (xy 99.225875 -271.680909) (xy 99.21798 -271.729486) (xy 99.202396 -271.776167)
			(xy 99.179525 -271.819744) (xy 99.14996 -271.859088) (xy 99.114467 -271.89318) (xy 99.073964 -271.921136)
			(xy 99.029502 -271.942234) (xy 98.982231 -271.955926) (xy 98.933376 -271.961858) (xy 98.884201 -271.959877)
			(xy 98.835982 -271.950033) (xy 98.789966 -271.932581) (xy 98.747345 -271.907974) (xy 98.709224 -271.876849)
			(xy 98.676589 -271.840012) (xy 98.650286 -271.798416) (xy 98.630995 -271.75314) (xy 98.619218 -271.705356)
			(xy 98.615258 -271.656302) (xy 98.286316 -271.656302) (xy 98.285821 -271.680909) (xy 98.277926 -271.729486)
			(xy 98.262342 -271.776167) (xy 98.239471 -271.819744) (xy 98.209906 -271.859088) (xy 98.174413 -271.89318)
			(xy 98.13391 -271.921136) (xy 98.089448 -271.942234) (xy 98.042177 -271.955926) (xy 97.993322 -271.961858)
			(xy 97.944147 -271.959877) (xy 97.895928 -271.950033) (xy 97.849912 -271.932581) (xy 97.807291 -271.907974)
			(xy 97.76917 -271.876849) (xy 97.736535 -271.840012) (xy 97.710232 -271.798416) (xy 97.690941 -271.75314)
			(xy 97.679164 -271.705356) (xy 97.675204 -271.656302) (xy 97.38614 -271.656302) (xy 97.38614 -272.059908)
			(xy 97.386651 -272.070329) (xy 97.394918 -272.089463) (xy 97.402142 -272.096992) (xy 97.463356 -272.154904)
			(xy 97.483168 -272.162016) (xy 97.493582 -272.161508) (xy 97.511108 -272.161) (xy 97.535099 -272.161471)
			(xy 97.582489 -272.168978) (xy 97.628121 -272.183807) (xy 97.670872 -272.205591) (xy 97.709689 -272.233794)
			(xy 97.743616 -272.267723) (xy 97.771818 -272.306541) (xy 97.7936 -272.349294) (xy 97.808425 -272.394927)
			(xy 97.81593 -272.442317) (xy 97.816416 -272.466308) (xy 98.145358 -272.466308) (xy 98.149318 -272.417254)
			(xy 98.161095 -272.36947) (xy 98.180386 -272.324194) (xy 98.206689 -272.282598) (xy 98.239324 -272.245761)
			(xy 98.277445 -272.214636) (xy 98.320066 -272.190029) (xy 98.366082 -272.172577) (xy 98.414301 -272.162733)
			(xy 98.463476 -272.160752) (xy 98.512331 -272.166684) (xy 98.559602 -272.180376) (xy 98.604064 -272.201474)
			(xy 98.644567 -272.22943) (xy 98.68006 -272.263522) (xy 98.709625 -272.302866) (xy 98.732496 -272.346443)
			(xy 98.74808 -272.393124) (xy 98.755975 -272.441701) (xy 98.75647 -272.466308) (xy 99.085158 -272.466308)
			(xy 99.089118 -272.417254) (xy 99.100895 -272.36947) (xy 99.120186 -272.324194) (xy 99.146489 -272.282598)
			(xy 99.179124 -272.245761) (xy 99.217245 -272.214636) (xy 99.259866 -272.190029) (xy 99.305882 -272.172577)
			(xy 99.354101 -272.162733) (xy 99.403276 -272.160752) (xy 99.452131 -272.166684) (xy 99.499402 -272.180376)
			(xy 99.543864 -272.201474) (xy 99.584367 -272.22943) (xy 99.61986 -272.263522) (xy 99.649425 -272.302866)
			(xy 99.672296 -272.346443) (xy 99.68788 -272.393124) (xy 99.695775 -272.441701) (xy 99.69627 -272.466308)
			(xy 100.025212 -272.466308) (xy 100.029172 -272.417254) (xy 100.040949 -272.36947) (xy 100.06024 -272.324194)
			(xy 100.086543 -272.282598) (xy 100.119178 -272.245761) (xy 100.157299 -272.214636) (xy 100.19992 -272.190029)
			(xy 100.245936 -272.172577) (xy 100.294155 -272.162733) (xy 100.34333 -272.160752) (xy 100.392185 -272.166684)
			(xy 100.439456 -272.180376) (xy 100.483918 -272.201474) (xy 100.524421 -272.22943) (xy 100.559914 -272.263522)
			(xy 100.589479 -272.302866) (xy 100.61235 -272.346443) (xy 100.627934 -272.393124) (xy 100.635829 -272.441701)
			(xy 100.636324 -272.466308) (xy 100.965266 -272.466308) (xy 100.969226 -272.417254) (xy 100.981003 -272.36947)
			(xy 101.000294 -272.324194) (xy 101.026597 -272.282598) (xy 101.059232 -272.245761) (xy 101.097353 -272.214636)
			(xy 101.139974 -272.190029) (xy 101.18599 -272.172577) (xy 101.234209 -272.162733) (xy 101.283384 -272.160752)
			(xy 101.332239 -272.166684) (xy 101.37951 -272.180376) (xy 101.423972 -272.201474) (xy 101.464475 -272.22943)
			(xy 101.499968 -272.263522) (xy 101.529533 -272.302866) (xy 101.552404 -272.346443) (xy 101.567988 -272.393124)
			(xy 101.575883 -272.441701) (xy 101.576378 -272.466308) (xy 101.90532 -272.466308) (xy 101.90928 -272.417254)
			(xy 101.921057 -272.36947) (xy 101.940348 -272.324194) (xy 101.966651 -272.282598) (xy 101.999286 -272.245761)
			(xy 102.037407 -272.214636) (xy 102.080028 -272.190029) (xy 102.126044 -272.172577) (xy 102.174263 -272.162733)
			(xy 102.223438 -272.160752) (xy 102.272293 -272.166684) (xy 102.319564 -272.180376) (xy 102.364026 -272.201474)
			(xy 102.404529 -272.22943) (xy 102.440022 -272.263522) (xy 102.469587 -272.302866) (xy 102.492458 -272.346443)
			(xy 102.508042 -272.393124) (xy 102.515937 -272.441701) (xy 102.516432 -272.466308) (xy 102.845374 -272.466308)
			(xy 102.849334 -272.417254) (xy 102.861111 -272.36947) (xy 102.880402 -272.324194) (xy 102.906705 -272.282598)
			(xy 102.93934 -272.245761) (xy 102.977461 -272.214636) (xy 103.020082 -272.190029) (xy 103.066098 -272.172577)
			(xy 103.114317 -272.162733) (xy 103.163492 -272.160752) (xy 103.212347 -272.166684) (xy 103.259618 -272.180376)
			(xy 103.30408 -272.201474) (xy 103.344583 -272.22943) (xy 103.380076 -272.263522) (xy 103.409641 -272.302866)
			(xy 103.432512 -272.346443) (xy 103.448096 -272.393124) (xy 103.455991 -272.441701) (xy 103.456486 -272.466308)
			(xy 103.785174 -272.466308) (xy 103.789134 -272.417254) (xy 103.800911 -272.36947) (xy 103.820202 -272.324194)
			(xy 103.846505 -272.282598) (xy 103.87914 -272.245761) (xy 103.917261 -272.214636) (xy 103.959882 -272.190029)
			(xy 104.005898 -272.172577) (xy 104.054117 -272.162733) (xy 104.103292 -272.160752) (xy 104.152147 -272.166684)
			(xy 104.199418 -272.180376) (xy 104.24388 -272.201474) (xy 104.284383 -272.22943) (xy 104.319876 -272.263522)
			(xy 104.349441 -272.302866) (xy 104.372312 -272.346443) (xy 104.387896 -272.393124) (xy 104.395791 -272.441701)
			(xy 104.396286 -272.466308) (xy 104.725228 -272.466308) (xy 104.729188 -272.417254) (xy 104.740965 -272.36947)
			(xy 104.760256 -272.324194) (xy 104.786559 -272.282598) (xy 104.819194 -272.245761) (xy 104.857315 -272.214636)
			(xy 104.899936 -272.190029) (xy 104.945952 -272.172577) (xy 104.994171 -272.162733) (xy 105.043346 -272.160752)
			(xy 105.092201 -272.166684) (xy 105.139472 -272.180376) (xy 105.183934 -272.201474) (xy 105.224437 -272.22943)
			(xy 105.25993 -272.263522) (xy 105.289495 -272.302866) (xy 105.312366 -272.346443) (xy 105.32795 -272.393124)
			(xy 105.335845 -272.441701) (xy 105.33634 -272.466308) (xy 105.665282 -272.466308) (xy 105.669242 -272.417254)
			(xy 105.681019 -272.36947) (xy 105.70031 -272.324194) (xy 105.726613 -272.282598) (xy 105.759248 -272.245761)
			(xy 105.797369 -272.214636) (xy 105.83999 -272.190029) (xy 105.886006 -272.172577) (xy 105.934225 -272.162733)
			(xy 105.9834 -272.160752) (xy 106.032255 -272.166684) (xy 106.079526 -272.180376) (xy 106.123988 -272.201474)
			(xy 106.164491 -272.22943) (xy 106.199984 -272.263522) (xy 106.229549 -272.302866) (xy 106.25242 -272.346443)
			(xy 106.268004 -272.393124) (xy 106.275899 -272.441701) (xy 106.276394 -272.466308) (xy 106.605336 -272.466308)
			(xy 106.609296 -272.417254) (xy 106.621073 -272.36947) (xy 106.640364 -272.324194) (xy 106.666667 -272.282598)
			(xy 106.699302 -272.245761) (xy 106.737423 -272.214636) (xy 106.780044 -272.190029) (xy 106.82606 -272.172577)
			(xy 106.874279 -272.162733) (xy 106.923454 -272.160752) (xy 106.972309 -272.166684) (xy 107.01958 -272.180376)
			(xy 107.064042 -272.201474) (xy 107.104545 -272.22943) (xy 107.140038 -272.263522) (xy 107.169603 -272.302866)
			(xy 107.192474 -272.346443) (xy 107.208058 -272.393124) (xy 107.215953 -272.441701) (xy 107.216448 -272.466308)
			(xy 107.545136 -272.466308) (xy 107.549096 -272.417254) (xy 107.560873 -272.36947) (xy 107.580164 -272.324194)
			(xy 107.606467 -272.282598) (xy 107.639102 -272.245761) (xy 107.677223 -272.214636) (xy 107.719844 -272.190029)
			(xy 107.76586 -272.172577) (xy 107.814079 -272.162733) (xy 107.863254 -272.160752) (xy 107.912109 -272.166684)
			(xy 107.95938 -272.180376) (xy 108.003842 -272.201474) (xy 108.044345 -272.22943) (xy 108.079838 -272.263522)
			(xy 108.109403 -272.302866) (xy 108.132274 -272.346443) (xy 108.147858 -272.393124) (xy 108.155753 -272.441701)
			(xy 108.156248 -272.466308) (xy 108.48519 -272.466308) (xy 108.48915 -272.417254) (xy 108.500927 -272.36947)
			(xy 108.520218 -272.324194) (xy 108.546521 -272.282598) (xy 108.579156 -272.245761) (xy 108.617277 -272.214636)
			(xy 108.659898 -272.190029) (xy 108.705914 -272.172577) (xy 108.754133 -272.162733) (xy 108.803308 -272.160752)
			(xy 108.852163 -272.166684) (xy 108.899434 -272.180376) (xy 108.943896 -272.201474) (xy 108.984399 -272.22943)
			(xy 109.019892 -272.263522) (xy 109.049457 -272.302866) (xy 109.072328 -272.346443) (xy 109.087912 -272.393124)
			(xy 109.095807 -272.441701) (xy 109.096302 -272.466308) (xy 109.425244 -272.466308) (xy 109.429204 -272.417254)
			(xy 109.440981 -272.36947) (xy 109.460272 -272.324194) (xy 109.486575 -272.282598) (xy 109.51921 -272.245761)
			(xy 109.557331 -272.214636) (xy 109.599952 -272.190029) (xy 109.645968 -272.172577) (xy 109.694187 -272.162733)
			(xy 109.743362 -272.160752) (xy 109.792217 -272.166684) (xy 109.839488 -272.180376) (xy 109.88395 -272.201474)
			(xy 109.924453 -272.22943) (xy 109.959946 -272.263522) (xy 109.989511 -272.302866) (xy 110.012382 -272.346443)
			(xy 110.027966 -272.393124) (xy 110.035861 -272.441701) (xy 110.036356 -272.466308) (xy 110.365298 -272.466308)
			(xy 110.369258 -272.417254) (xy 110.381035 -272.36947) (xy 110.400326 -272.324194) (xy 110.426629 -272.282598)
			(xy 110.459264 -272.245761) (xy 110.497385 -272.214636) (xy 110.540006 -272.190029) (xy 110.586022 -272.172577)
			(xy 110.634241 -272.162733) (xy 110.683416 -272.160752) (xy 110.732271 -272.166684) (xy 110.779542 -272.180376)
			(xy 110.824004 -272.201474) (xy 110.864507 -272.22943) (xy 110.9 -272.263522) (xy 110.929565 -272.302866)
			(xy 110.952436 -272.346443) (xy 110.96802 -272.393124) (xy 110.975915 -272.441701) (xy 110.97641 -272.466308)
			(xy 113.178856 -272.466308) (xy 113.182816 -272.417254) (xy 113.194593 -272.36947) (xy 113.213884 -272.324194)
			(xy 113.240187 -272.282598) (xy 113.272822 -272.245761) (xy 113.310943 -272.214636) (xy 113.353564 -272.190029)
			(xy 113.39958 -272.172577) (xy 113.447799 -272.162733) (xy 113.496974 -272.160752) (xy 113.545829 -272.166684)
			(xy 113.5931 -272.180376) (xy 113.637562 -272.201474) (xy 113.678065 -272.22943) (xy 113.713558 -272.263522)
			(xy 113.743123 -272.302866) (xy 113.765994 -272.346443) (xy 113.781578 -272.393124) (xy 113.789473 -272.441701)
			(xy 113.789968 -272.466308) (xy 114.11891 -272.466308) (xy 114.12287 -272.417254) (xy 114.134647 -272.36947)
			(xy 114.153938 -272.324194) (xy 114.180241 -272.282598) (xy 114.212876 -272.245761) (xy 114.250997 -272.214636)
			(xy 114.293618 -272.190029) (xy 114.339634 -272.172577) (xy 114.387853 -272.162733) (xy 114.437028 -272.160752)
			(xy 114.485883 -272.166684) (xy 114.533154 -272.180376) (xy 114.577616 -272.201474) (xy 114.618119 -272.22943)
			(xy 114.653612 -272.263522) (xy 114.683177 -272.302866) (xy 114.706048 -272.346443) (xy 114.721632 -272.393124)
			(xy 114.729527 -272.441701) (xy 114.730022 -272.466308) (xy 115.058964 -272.466308) (xy 115.062924 -272.417254)
			(xy 115.074701 -272.36947) (xy 115.093992 -272.324194) (xy 115.120295 -272.282598) (xy 115.15293 -272.245761)
			(xy 115.191051 -272.214636) (xy 115.233672 -272.190029) (xy 115.279688 -272.172577) (xy 115.327907 -272.162733)
			(xy 115.377082 -272.160752) (xy 115.425937 -272.166684) (xy 115.473208 -272.180376) (xy 115.51767 -272.201474)
			(xy 115.558173 -272.22943) (xy 115.593666 -272.263522) (xy 115.623231 -272.302866) (xy 115.646102 -272.346443)
			(xy 115.661686 -272.393124) (xy 115.669581 -272.441701) (xy 115.670076 -272.466308) (xy 115.999018 -272.466308)
			(xy 116.002978 -272.417254) (xy 116.014755 -272.36947) (xy 116.034046 -272.324194) (xy 116.060349 -272.282598)
			(xy 116.092984 -272.245761) (xy 116.131105 -272.214636) (xy 116.173726 -272.190029) (xy 116.219742 -272.172577)
			(xy 116.267961 -272.162733) (xy 116.317136 -272.160752) (xy 116.365991 -272.166684) (xy 116.413262 -272.180376)
			(xy 116.457724 -272.201474) (xy 116.498227 -272.22943) (xy 116.53372 -272.263522) (xy 116.563285 -272.302866)
			(xy 116.586156 -272.346443) (xy 116.60174 -272.393124) (xy 116.609635 -272.441701) (xy 116.61013 -272.466308)
			(xy 116.938818 -272.466308) (xy 116.942778 -272.417254) (xy 116.954555 -272.36947) (xy 116.973846 -272.324194)
			(xy 117.000149 -272.282598) (xy 117.032784 -272.245761) (xy 117.070905 -272.214636) (xy 117.113526 -272.190029)
			(xy 117.159542 -272.172577) (xy 117.207761 -272.162733) (xy 117.256936 -272.160752) (xy 117.305791 -272.166684)
			(xy 117.353062 -272.180376) (xy 117.397524 -272.201474) (xy 117.438027 -272.22943) (xy 117.47352 -272.263522)
			(xy 117.503085 -272.302866) (xy 117.525956 -272.346443) (xy 117.54154 -272.393124) (xy 117.549435 -272.441701)
			(xy 117.54993 -272.466308) (xy 117.878872 -272.466308) (xy 117.882832 -272.417254) (xy 117.894609 -272.36947)
			(xy 117.9139 -272.324194) (xy 117.940203 -272.282598) (xy 117.972838 -272.245761) (xy 118.010959 -272.214636)
			(xy 118.05358 -272.190029) (xy 118.099596 -272.172577) (xy 118.147815 -272.162733) (xy 118.19699 -272.160752)
			(xy 118.245845 -272.166684) (xy 118.293116 -272.180376) (xy 118.337578 -272.201474) (xy 118.378081 -272.22943)
			(xy 118.413574 -272.263522) (xy 118.443139 -272.302866) (xy 118.46601 -272.346443) (xy 118.481594 -272.393124)
			(xy 118.489489 -272.441701) (xy 118.489984 -272.466308) (xy 118.818926 -272.466308) (xy 118.822886 -272.417254)
			(xy 118.834663 -272.36947) (xy 118.853954 -272.324194) (xy 118.880257 -272.282598) (xy 118.912892 -272.245761)
			(xy 118.951013 -272.214636) (xy 118.993634 -272.190029) (xy 119.03965 -272.172577) (xy 119.087869 -272.162733)
			(xy 119.137044 -272.160752) (xy 119.185899 -272.166684) (xy 119.23317 -272.180376) (xy 119.277632 -272.201474)
			(xy 119.318135 -272.22943) (xy 119.353628 -272.263522) (xy 119.383193 -272.302866) (xy 119.406064 -272.346443)
			(xy 119.421648 -272.393124) (xy 119.429543 -272.441701) (xy 119.430038 -272.466308) (xy 119.75898 -272.466308)
			(xy 119.76294 -272.417254) (xy 119.774717 -272.36947) (xy 119.794008 -272.324194) (xy 119.820311 -272.282598)
			(xy 119.852946 -272.245761) (xy 119.891067 -272.214636) (xy 119.933688 -272.190029) (xy 119.979704 -272.172577)
			(xy 120.027923 -272.162733) (xy 120.077098 -272.160752) (xy 120.125953 -272.166684) (xy 120.173224 -272.180376)
			(xy 120.217686 -272.201474) (xy 120.258189 -272.22943) (xy 120.293682 -272.263522) (xy 120.323247 -272.302866)
			(xy 120.346118 -272.346443) (xy 120.361702 -272.393124) (xy 120.369597 -272.441701) (xy 120.370092 -272.466308)
			(xy 120.699034 -272.466308) (xy 120.702994 -272.417254) (xy 120.714771 -272.36947) (xy 120.734062 -272.324194)
			(xy 120.760365 -272.282598) (xy 120.793 -272.245761) (xy 120.831121 -272.214636) (xy 120.873742 -272.190029)
			(xy 120.919758 -272.172577) (xy 120.967977 -272.162733) (xy 121.017152 -272.160752) (xy 121.066007 -272.166684)
			(xy 121.113278 -272.180376) (xy 121.15774 -272.201474) (xy 121.198243 -272.22943) (xy 121.233736 -272.263522)
			(xy 121.263301 -272.302866) (xy 121.286172 -272.346443) (xy 121.301756 -272.393124) (xy 121.309651 -272.441701)
			(xy 121.310146 -272.466308) (xy 121.638834 -272.466308) (xy 121.642794 -272.417254) (xy 121.654571 -272.36947)
			(xy 121.673862 -272.324194) (xy 121.700165 -272.282598) (xy 121.7328 -272.245761) (xy 121.770921 -272.214636)
			(xy 121.813542 -272.190029) (xy 121.859558 -272.172577) (xy 121.907777 -272.162733) (xy 121.956952 -272.160752)
			(xy 122.005807 -272.166684) (xy 122.053078 -272.180376) (xy 122.09754 -272.201474) (xy 122.138043 -272.22943)
			(xy 122.173536 -272.263522) (xy 122.203101 -272.302866) (xy 122.225972 -272.346443) (xy 122.241556 -272.393124)
			(xy 122.249451 -272.441701) (xy 122.249946 -272.466308) (xy 122.578888 -272.466308) (xy 122.582848 -272.417254)
			(xy 122.594625 -272.36947) (xy 122.613916 -272.324194) (xy 122.640219 -272.282598) (xy 122.672854 -272.245761)
			(xy 122.710975 -272.214636) (xy 122.753596 -272.190029) (xy 122.799612 -272.172577) (xy 122.847831 -272.162733)
			(xy 122.897006 -272.160752) (xy 122.945861 -272.166684) (xy 122.993132 -272.180376) (xy 123.037594 -272.201474)
			(xy 123.078097 -272.22943) (xy 123.11359 -272.263522) (xy 123.143155 -272.302866) (xy 123.166026 -272.346443)
			(xy 123.18161 -272.393124) (xy 123.189505 -272.441701) (xy 123.19 -272.466308) (xy 123.518942 -272.466308)
			(xy 123.522902 -272.417254) (xy 123.534679 -272.36947) (xy 123.55397 -272.324194) (xy 123.580273 -272.282598)
			(xy 123.612908 -272.245761) (xy 123.651029 -272.214636) (xy 123.69365 -272.190029) (xy 123.739666 -272.172577)
			(xy 123.787885 -272.162733) (xy 123.83706 -272.160752) (xy 123.885915 -272.166684) (xy 123.933186 -272.180376)
			(xy 123.977648 -272.201474) (xy 124.018151 -272.22943) (xy 124.053644 -272.263522) (xy 124.083209 -272.302866)
			(xy 124.10608 -272.346443) (xy 124.121664 -272.393124) (xy 124.129559 -272.441701) (xy 124.130054 -272.466308)
			(xy 124.458996 -272.466308) (xy 124.462956 -272.417254) (xy 124.474733 -272.36947) (xy 124.494024 -272.324194)
			(xy 124.520327 -272.282598) (xy 124.552962 -272.245761) (xy 124.591083 -272.214636) (xy 124.633704 -272.190029)
			(xy 124.67972 -272.172577) (xy 124.727939 -272.162733) (xy 124.777114 -272.160752) (xy 124.825969 -272.166684)
			(xy 124.87324 -272.180376) (xy 124.917702 -272.201474) (xy 124.958205 -272.22943) (xy 124.993698 -272.263522)
			(xy 125.023263 -272.302866) (xy 125.046134 -272.346443) (xy 125.061718 -272.393124) (xy 125.069613 -272.441701)
			(xy 125.070108 -272.466308) (xy 125.39905 -272.466308) (xy 125.40301 -272.417254) (xy 125.414787 -272.36947)
			(xy 125.434078 -272.324194) (xy 125.460381 -272.282598) (xy 125.493016 -272.245761) (xy 125.531137 -272.214636)
			(xy 125.573758 -272.190029) (xy 125.619774 -272.172577) (xy 125.667993 -272.162733) (xy 125.717168 -272.160752)
			(xy 125.766023 -272.166684) (xy 125.813294 -272.180376) (xy 125.857756 -272.201474) (xy 125.898259 -272.22943)
			(xy 125.933752 -272.263522) (xy 125.963317 -272.302866) (xy 125.986188 -272.346443) (xy 126.001772 -272.393124)
			(xy 126.009667 -272.441701) (xy 126.010162 -272.466308) (xy 126.33885 -272.466308) (xy 126.34281 -272.417254)
			(xy 126.354587 -272.36947) (xy 126.373878 -272.324194) (xy 126.400181 -272.282598) (xy 126.432816 -272.245761)
			(xy 126.470937 -272.214636) (xy 126.513558 -272.190029) (xy 126.559574 -272.172577) (xy 126.607793 -272.162733)
			(xy 126.656968 -272.160752) (xy 126.705823 -272.166684) (xy 126.753094 -272.180376) (xy 126.797556 -272.201474)
			(xy 126.838059 -272.22943) (xy 126.873552 -272.263522) (xy 126.903117 -272.302866) (xy 126.925988 -272.346443)
			(xy 126.941572 -272.393124) (xy 126.949467 -272.441701) (xy 126.949962 -272.466308) (xy 127.278904 -272.466308)
			(xy 127.282864 -272.417254) (xy 127.294641 -272.36947) (xy 127.313932 -272.324194) (xy 127.340235 -272.282598)
			(xy 127.37287 -272.245761) (xy 127.410991 -272.214636) (xy 127.453612 -272.190029) (xy 127.499628 -272.172577)
			(xy 127.547847 -272.162733) (xy 127.597022 -272.160752) (xy 127.645877 -272.166684) (xy 127.693148 -272.180376)
			(xy 127.73761 -272.201474) (xy 127.778113 -272.22943) (xy 127.813606 -272.263522) (xy 127.843171 -272.302866)
			(xy 127.866042 -272.346443) (xy 127.881626 -272.393124) (xy 127.889521 -272.441701) (xy 127.890016 -272.466308)
			(xy 128.208527 -272.466308) (xy 128.212622 -272.41558) (xy 128.224801 -272.366166) (xy 128.244749 -272.319346)
			(xy 128.27195 -272.276332) (xy 128.305698 -272.238238) (xy 128.34512 -272.206051) (xy 128.389194 -272.180605)
			(xy 128.43678 -272.162558) (xy 128.486644 -272.152378) (xy 128.537496 -272.150329) (xy 128.588017 -272.156463)
			(xy 128.636901 -272.170623) (xy 128.68288 -272.19244) (xy 128.724764 -272.22135) (xy 128.761468 -272.256605)
			(xy 128.792041 -272.297291) (xy 128.815692 -272.342354) (xy 128.831808 -272.390628) (xy 128.839972 -272.440862)
			(xy 128.840484 -272.466308) (xy 129.148581 -272.466308) (xy 129.152676 -272.41558) (xy 129.164855 -272.366166)
			(xy 129.184803 -272.319346) (xy 129.212004 -272.276332) (xy 129.245752 -272.238238) (xy 129.285174 -272.206051)
			(xy 129.329248 -272.180605) (xy 129.376834 -272.162558) (xy 129.426698 -272.152378) (xy 129.47755 -272.150329)
			(xy 129.528071 -272.156463) (xy 129.576955 -272.170623) (xy 129.622934 -272.19244) (xy 129.664818 -272.22135)
			(xy 129.701522 -272.256605) (xy 129.732095 -272.297291) (xy 129.755746 -272.342354) (xy 129.771862 -272.390628)
			(xy 129.780026 -272.440862) (xy 129.780538 -272.466308) (xy 130.099066 -272.466308) (xy 130.103026 -272.417254)
			(xy 130.114803 -272.36947) (xy 130.134094 -272.324194) (xy 130.160397 -272.282598) (xy 130.193032 -272.245761)
			(xy 130.231153 -272.214636) (xy 130.273774 -272.190029) (xy 130.31979 -272.172577) (xy 130.368009 -272.162733)
			(xy 130.417184 -272.160752) (xy 130.466039 -272.166684) (xy 130.51331 -272.180376) (xy 130.557772 -272.201474)
			(xy 130.598275 -272.22943) (xy 130.633768 -272.263522) (xy 130.663333 -272.302866) (xy 130.686204 -272.346443)
			(xy 130.701788 -272.393124) (xy 130.709683 -272.441701) (xy 130.710178 -272.466308) (xy 131.028435 -272.466308)
			(xy 131.03253 -272.41558) (xy 131.044709 -272.366166) (xy 131.064657 -272.319346) (xy 131.091858 -272.276332)
			(xy 131.125606 -272.238238) (xy 131.165028 -272.206051) (xy 131.209102 -272.180605) (xy 131.256688 -272.162558)
			(xy 131.306552 -272.152378) (xy 131.357404 -272.150329) (xy 131.407925 -272.156463) (xy 131.456809 -272.170623)
			(xy 131.502788 -272.19244) (xy 131.544672 -272.22135) (xy 131.581376 -272.256605) (xy 131.611949 -272.297291)
			(xy 131.6356 -272.342354) (xy 131.651716 -272.390628) (xy 131.65988 -272.440862) (xy 131.660392 -272.466308)
			(xy 131.97892 -272.466308) (xy 131.98288 -272.417254) (xy 131.994657 -272.36947) (xy 132.013948 -272.324194)
			(xy 132.040251 -272.282598) (xy 132.072886 -272.245761) (xy 132.111007 -272.214636) (xy 132.153628 -272.190029)
			(xy 132.199644 -272.172577) (xy 132.247863 -272.162733) (xy 132.297038 -272.160752) (xy 132.345893 -272.166684)
			(xy 132.393164 -272.180376) (xy 132.437626 -272.201474) (xy 132.478129 -272.22943) (xy 132.513622 -272.263522)
			(xy 132.543187 -272.302866) (xy 132.566058 -272.346443) (xy 132.581642 -272.393124) (xy 132.589537 -272.441701)
			(xy 132.590032 -272.466308) (xy 132.908543 -272.466308) (xy 132.912638 -272.41558) (xy 132.924817 -272.366166)
			(xy 132.944765 -272.319346) (xy 132.971966 -272.276332) (xy 133.005714 -272.238238) (xy 133.045136 -272.206051)
			(xy 133.08921 -272.180605) (xy 133.136796 -272.162558) (xy 133.18666 -272.152378) (xy 133.237512 -272.150329)
			(xy 133.288033 -272.156463) (xy 133.336917 -272.170623) (xy 133.382896 -272.19244) (xy 133.42478 -272.22135)
			(xy 133.461484 -272.256605) (xy 133.492057 -272.297291) (xy 133.515708 -272.342354) (xy 133.531824 -272.390628)
			(xy 133.539988 -272.440862) (xy 133.5405 -272.466308) (xy 133.859028 -272.466308) (xy 133.862988 -272.417254)
			(xy 133.874765 -272.36947) (xy 133.894056 -272.324194) (xy 133.920359 -272.282598) (xy 133.952994 -272.245761)
			(xy 133.991115 -272.214636) (xy 134.033736 -272.190029) (xy 134.079752 -272.172577) (xy 134.127971 -272.162733)
			(xy 134.177146 -272.160752) (xy 134.226001 -272.166684) (xy 134.273272 -272.180376) (xy 134.317734 -272.201474)
			(xy 134.358237 -272.22943) (xy 134.39373 -272.263522) (xy 134.423295 -272.302866) (xy 134.446166 -272.346443)
			(xy 134.46175 -272.393124) (xy 134.469645 -272.441701) (xy 134.47014 -272.466308) (xy 134.798828 -272.466308)
			(xy 134.802788 -272.417254) (xy 134.814565 -272.36947) (xy 134.833856 -272.324194) (xy 134.860159 -272.282598)
			(xy 134.892794 -272.245761) (xy 134.930915 -272.214636) (xy 134.973536 -272.190029) (xy 135.019552 -272.172577)
			(xy 135.067771 -272.162733) (xy 135.116946 -272.160752) (xy 135.165801 -272.166684) (xy 135.213072 -272.180376)
			(xy 135.257534 -272.201474) (xy 135.298037 -272.22943) (xy 135.33353 -272.263522) (xy 135.363095 -272.302866)
			(xy 135.385966 -272.346443) (xy 135.40155 -272.393124) (xy 135.409445 -272.441701) (xy 135.40994 -272.466308)
			(xy 135.738882 -272.466308) (xy 135.742842 -272.417254) (xy 135.754619 -272.36947) (xy 135.77391 -272.324194)
			(xy 135.800213 -272.282598) (xy 135.832848 -272.245761) (xy 135.870969 -272.214636) (xy 135.91359 -272.190029)
			(xy 135.959606 -272.172577) (xy 136.007825 -272.162733) (xy 136.057 -272.160752) (xy 136.105855 -272.166684)
			(xy 136.153126 -272.180376) (xy 136.197588 -272.201474) (xy 136.238091 -272.22943) (xy 136.273584 -272.263522)
			(xy 136.303149 -272.302866) (xy 136.32602 -272.346443) (xy 136.341604 -272.393124) (xy 136.349499 -272.441701)
			(xy 136.349994 -272.466308) (xy 136.678936 -272.466308) (xy 136.682896 -272.417254) (xy 136.694673 -272.36947)
			(xy 136.713964 -272.324194) (xy 136.740267 -272.282598) (xy 136.772902 -272.245761) (xy 136.811023 -272.214636)
			(xy 136.853644 -272.190029) (xy 136.89966 -272.172577) (xy 136.947879 -272.162733) (xy 136.997054 -272.160752)
			(xy 137.045909 -272.166684) (xy 137.09318 -272.180376) (xy 137.137642 -272.201474) (xy 137.178145 -272.22943)
			(xy 137.213638 -272.263522) (xy 137.243203 -272.302866) (xy 137.266074 -272.346443) (xy 137.281658 -272.393124)
			(xy 137.289553 -272.441701) (xy 137.290048 -272.466308) (xy 137.61899 -272.466308) (xy 137.62295 -272.417254)
			(xy 137.634727 -272.36947) (xy 137.654018 -272.324194) (xy 137.680321 -272.282598) (xy 137.712956 -272.245761)
			(xy 137.751077 -272.214636) (xy 137.793698 -272.190029) (xy 137.839714 -272.172577) (xy 137.887933 -272.162733)
			(xy 137.937108 -272.160752) (xy 137.985963 -272.166684) (xy 138.033234 -272.180376) (xy 138.077696 -272.201474)
			(xy 138.118199 -272.22943) (xy 138.153692 -272.263522) (xy 138.183257 -272.302866) (xy 138.206128 -272.346443)
			(xy 138.221712 -272.393124) (xy 138.229607 -272.441701) (xy 138.230102 -272.466308) (xy 138.559044 -272.466308)
			(xy 138.563004 -272.417254) (xy 138.574781 -272.36947) (xy 138.594072 -272.324194) (xy 138.620375 -272.282598)
			(xy 138.65301 -272.245761) (xy 138.691131 -272.214636) (xy 138.733752 -272.190029) (xy 138.779768 -272.172577)
			(xy 138.827987 -272.162733) (xy 138.877162 -272.160752) (xy 138.926017 -272.166684) (xy 138.973288 -272.180376)
			(xy 139.01775 -272.201474) (xy 139.058253 -272.22943) (xy 139.093746 -272.263522) (xy 139.123311 -272.302866)
			(xy 139.146182 -272.346443) (xy 139.161766 -272.393124) (xy 139.169661 -272.441701) (xy 139.170156 -272.466308)
			(xy 139.498844 -272.466308) (xy 139.502804 -272.417254) (xy 139.514581 -272.36947) (xy 139.533872 -272.324194)
			(xy 139.560175 -272.282598) (xy 139.59281 -272.245761) (xy 139.630931 -272.214636) (xy 139.673552 -272.190029)
			(xy 139.719568 -272.172577) (xy 139.767787 -272.162733) (xy 139.816962 -272.160752) (xy 139.865817 -272.166684)
			(xy 139.913088 -272.180376) (xy 139.95755 -272.201474) (xy 139.998053 -272.22943) (xy 140.033546 -272.263522)
			(xy 140.063111 -272.302866) (xy 140.085982 -272.346443) (xy 140.101566 -272.393124) (xy 140.109461 -272.441701)
			(xy 140.109956 -272.466308) (xy 140.109461 -272.490915) (xy 140.101566 -272.539492) (xy 140.085982 -272.586173)
			(xy 140.063111 -272.62975) (xy 140.033546 -272.669094) (xy 139.998053 -272.703186) (xy 139.95755 -272.731142)
			(xy 139.913088 -272.75224) (xy 139.865817 -272.765932) (xy 139.816962 -272.771864) (xy 139.767787 -272.769883)
			(xy 139.719568 -272.760039) (xy 139.673552 -272.742587) (xy 139.630931 -272.71798) (xy 139.59281 -272.686855)
			(xy 139.560175 -272.650018) (xy 139.533872 -272.608422) (xy 139.514581 -272.563146) (xy 139.502804 -272.515362)
			(xy 139.498844 -272.466308) (xy 139.170156 -272.466308) (xy 139.169661 -272.490915) (xy 139.161766 -272.539492)
			(xy 139.146182 -272.586173) (xy 139.123311 -272.62975) (xy 139.093746 -272.669094) (xy 139.058253 -272.703186)
			(xy 139.01775 -272.731142) (xy 138.973288 -272.75224) (xy 138.926017 -272.765932) (xy 138.877162 -272.771864)
			(xy 138.827987 -272.769883) (xy 138.779768 -272.760039) (xy 138.733752 -272.742587) (xy 138.691131 -272.71798)
			(xy 138.65301 -272.686855) (xy 138.620375 -272.650018) (xy 138.594072 -272.608422) (xy 138.574781 -272.563146)
			(xy 138.563004 -272.515362) (xy 138.559044 -272.466308) (xy 138.230102 -272.466308) (xy 138.229607 -272.490915)
			(xy 138.221712 -272.539492) (xy 138.206128 -272.586173) (xy 138.183257 -272.62975) (xy 138.153692 -272.669094)
			(xy 138.118199 -272.703186) (xy 138.077696 -272.731142) (xy 138.033234 -272.75224) (xy 137.985963 -272.765932)
			(xy 137.937108 -272.771864) (xy 137.887933 -272.769883) (xy 137.839714 -272.760039) (xy 137.793698 -272.742587)
			(xy 137.751077 -272.71798) (xy 137.712956 -272.686855) (xy 137.680321 -272.650018) (xy 137.654018 -272.608422)
			(xy 137.634727 -272.563146) (xy 137.62295 -272.515362) (xy 137.61899 -272.466308) (xy 137.290048 -272.466308)
			(xy 137.289553 -272.490915) (xy 137.281658 -272.539492) (xy 137.266074 -272.586173) (xy 137.243203 -272.62975)
			(xy 137.213638 -272.669094) (xy 137.178145 -272.703186) (xy 137.137642 -272.731142) (xy 137.09318 -272.75224)
			(xy 137.045909 -272.765932) (xy 136.997054 -272.771864) (xy 136.947879 -272.769883) (xy 136.89966 -272.760039)
			(xy 136.853644 -272.742587) (xy 136.811023 -272.71798) (xy 136.772902 -272.686855) (xy 136.740267 -272.650018)
			(xy 136.713964 -272.608422) (xy 136.694673 -272.563146) (xy 136.682896 -272.515362) (xy 136.678936 -272.466308)
			(xy 136.349994 -272.466308) (xy 136.349499 -272.490915) (xy 136.341604 -272.539492) (xy 136.32602 -272.586173)
			(xy 136.303149 -272.62975) (xy 136.273584 -272.669094) (xy 136.238091 -272.703186) (xy 136.197588 -272.731142)
			(xy 136.153126 -272.75224) (xy 136.105855 -272.765932) (xy 136.057 -272.771864) (xy 136.007825 -272.769883)
			(xy 135.959606 -272.760039) (xy 135.91359 -272.742587) (xy 135.870969 -272.71798) (xy 135.832848 -272.686855)
			(xy 135.800213 -272.650018) (xy 135.77391 -272.608422) (xy 135.754619 -272.563146) (xy 135.742842 -272.515362)
			(xy 135.738882 -272.466308) (xy 135.40994 -272.466308) (xy 135.409445 -272.490915) (xy 135.40155 -272.539492)
			(xy 135.385966 -272.586173) (xy 135.363095 -272.62975) (xy 135.33353 -272.669094) (xy 135.298037 -272.703186)
			(xy 135.257534 -272.731142) (xy 135.213072 -272.75224) (xy 135.165801 -272.765932) (xy 135.116946 -272.771864)
			(xy 135.067771 -272.769883) (xy 135.019552 -272.760039) (xy 134.973536 -272.742587) (xy 134.930915 -272.71798)
			(xy 134.892794 -272.686855) (xy 134.860159 -272.650018) (xy 134.833856 -272.608422) (xy 134.814565 -272.563146)
			(xy 134.802788 -272.515362) (xy 134.798828 -272.466308) (xy 134.47014 -272.466308) (xy 134.469645 -272.490915)
			(xy 134.46175 -272.539492) (xy 134.446166 -272.586173) (xy 134.423295 -272.62975) (xy 134.39373 -272.669094)
			(xy 134.358237 -272.703186) (xy 134.317734 -272.731142) (xy 134.273272 -272.75224) (xy 134.226001 -272.765932)
			(xy 134.177146 -272.771864) (xy 134.127971 -272.769883) (xy 134.079752 -272.760039) (xy 134.033736 -272.742587)
			(xy 133.991115 -272.71798) (xy 133.952994 -272.686855) (xy 133.920359 -272.650018) (xy 133.894056 -272.608422)
			(xy 133.874765 -272.563146) (xy 133.862988 -272.515362) (xy 133.859028 -272.466308) (xy 133.5405 -272.466308)
			(xy 133.539988 -272.491754) (xy 133.531824 -272.541988) (xy 133.515708 -272.590262) (xy 133.492057 -272.635325)
			(xy 133.461484 -272.676011) (xy 133.42478 -272.711266) (xy 133.382896 -272.740176) (xy 133.336917 -272.761993)
			(xy 133.288033 -272.776153) (xy 133.237512 -272.782287) (xy 133.18666 -272.780238) (xy 133.136796 -272.770058)
			(xy 133.08921 -272.752011) (xy 133.045136 -272.726565) (xy 133.005714 -272.694378) (xy 132.971966 -272.656284)
			(xy 132.944765 -272.61327) (xy 132.924817 -272.56645) (xy 132.912638 -272.517036) (xy 132.908543 -272.466308)
			(xy 132.590032 -272.466308) (xy 132.589537 -272.490915) (xy 132.581642 -272.539492) (xy 132.566058 -272.586173)
			(xy 132.543187 -272.62975) (xy 132.513622 -272.669094) (xy 132.478129 -272.703186) (xy 132.437626 -272.731142)
			(xy 132.393164 -272.75224) (xy 132.345893 -272.765932) (xy 132.297038 -272.771864) (xy 132.247863 -272.769883)
			(xy 132.199644 -272.760039) (xy 132.153628 -272.742587) (xy 132.111007 -272.71798) (xy 132.072886 -272.686855)
			(xy 132.040251 -272.650018) (xy 132.013948 -272.608422) (xy 131.994657 -272.563146) (xy 131.98288 -272.515362)
			(xy 131.97892 -272.466308) (xy 131.660392 -272.466308) (xy 131.65988 -272.491754) (xy 131.651716 -272.541988)
			(xy 131.6356 -272.590262) (xy 131.611949 -272.635325) (xy 131.581376 -272.676011) (xy 131.544672 -272.711266)
			(xy 131.502788 -272.740176) (xy 131.456809 -272.761993) (xy 131.407925 -272.776153) (xy 131.357404 -272.782287)
			(xy 131.306552 -272.780238) (xy 131.256688 -272.770058) (xy 131.209102 -272.752011) (xy 131.165028 -272.726565)
			(xy 131.125606 -272.694378) (xy 131.091858 -272.656284) (xy 131.064657 -272.61327) (xy 131.044709 -272.56645)
			(xy 131.03253 -272.517036) (xy 131.028435 -272.466308) (xy 130.710178 -272.466308) (xy 130.709683 -272.490915)
			(xy 130.701788 -272.539492) (xy 130.686204 -272.586173) (xy 130.663333 -272.62975) (xy 130.633768 -272.669094)
			(xy 130.598275 -272.703186) (xy 130.557772 -272.731142) (xy 130.51331 -272.75224) (xy 130.466039 -272.765932)
			(xy 130.417184 -272.771864) (xy 130.368009 -272.769883) (xy 130.31979 -272.760039) (xy 130.273774 -272.742587)
			(xy 130.231153 -272.71798) (xy 130.193032 -272.686855) (xy 130.160397 -272.650018) (xy 130.134094 -272.608422)
			(xy 130.114803 -272.563146) (xy 130.103026 -272.515362) (xy 130.099066 -272.466308) (xy 129.780538 -272.466308)
			(xy 129.780026 -272.491754) (xy 129.771862 -272.541988) (xy 129.755746 -272.590262) (xy 129.732095 -272.635325)
			(xy 129.701522 -272.676011) (xy 129.664818 -272.711266) (xy 129.622934 -272.740176) (xy 129.576955 -272.761993)
			(xy 129.528071 -272.776153) (xy 129.47755 -272.782287) (xy 129.426698 -272.780238) (xy 129.376834 -272.770058)
			(xy 129.329248 -272.752011) (xy 129.285174 -272.726565) (xy 129.245752 -272.694378) (xy 129.212004 -272.656284)
			(xy 129.184803 -272.61327) (xy 129.164855 -272.56645) (xy 129.152676 -272.517036) (xy 129.148581 -272.466308)
			(xy 128.840484 -272.466308) (xy 128.839972 -272.491754) (xy 128.831808 -272.541988) (xy 128.815692 -272.590262)
			(xy 128.792041 -272.635325) (xy 128.761468 -272.676011) (xy 128.724764 -272.711266) (xy 128.68288 -272.740176)
			(xy 128.636901 -272.761993) (xy 128.588017 -272.776153) (xy 128.537496 -272.782287) (xy 128.486644 -272.780238)
			(xy 128.43678 -272.770058) (xy 128.389194 -272.752011) (xy 128.34512 -272.726565) (xy 128.305698 -272.694378)
			(xy 128.27195 -272.656284) (xy 128.244749 -272.61327) (xy 128.224801 -272.56645) (xy 128.212622 -272.517036)
			(xy 128.208527 -272.466308) (xy 127.890016 -272.466308) (xy 127.889521 -272.490915) (xy 127.881626 -272.539492)
			(xy 127.866042 -272.586173) (xy 127.843171 -272.62975) (xy 127.813606 -272.669094) (xy 127.778113 -272.703186)
			(xy 127.73761 -272.731142) (xy 127.693148 -272.75224) (xy 127.645877 -272.765932) (xy 127.597022 -272.771864)
			(xy 127.547847 -272.769883) (xy 127.499628 -272.760039) (xy 127.453612 -272.742587) (xy 127.410991 -272.71798)
			(xy 127.37287 -272.686855) (xy 127.340235 -272.650018) (xy 127.313932 -272.608422) (xy 127.294641 -272.563146)
			(xy 127.282864 -272.515362) (xy 127.278904 -272.466308) (xy 126.949962 -272.466308) (xy 126.949467 -272.490915)
			(xy 126.941572 -272.539492) (xy 126.925988 -272.586173) (xy 126.903117 -272.62975) (xy 126.873552 -272.669094)
			(xy 126.838059 -272.703186) (xy 126.797556 -272.731142) (xy 126.753094 -272.75224) (xy 126.705823 -272.765932)
			(xy 126.656968 -272.771864) (xy 126.607793 -272.769883) (xy 126.559574 -272.760039) (xy 126.513558 -272.742587)
			(xy 126.470937 -272.71798) (xy 126.432816 -272.686855) (xy 126.400181 -272.650018) (xy 126.373878 -272.608422)
			(xy 126.354587 -272.563146) (xy 126.34281 -272.515362) (xy 126.33885 -272.466308) (xy 126.010162 -272.466308)
			(xy 126.009667 -272.490915) (xy 126.001772 -272.539492) (xy 125.986188 -272.586173) (xy 125.963317 -272.62975)
			(xy 125.933752 -272.669094) (xy 125.898259 -272.703186) (xy 125.857756 -272.731142) (xy 125.813294 -272.75224)
			(xy 125.766023 -272.765932) (xy 125.717168 -272.771864) (xy 125.667993 -272.769883) (xy 125.619774 -272.760039)
			(xy 125.573758 -272.742587) (xy 125.531137 -272.71798) (xy 125.493016 -272.686855) (xy 125.460381 -272.650018)
			(xy 125.434078 -272.608422) (xy 125.414787 -272.563146) (xy 125.40301 -272.515362) (xy 125.39905 -272.466308)
			(xy 125.070108 -272.466308) (xy 125.069613 -272.490915) (xy 125.061718 -272.539492) (xy 125.046134 -272.586173)
			(xy 125.023263 -272.62975) (xy 124.993698 -272.669094) (xy 124.958205 -272.703186) (xy 124.917702 -272.731142)
			(xy 124.87324 -272.75224) (xy 124.825969 -272.765932) (xy 124.777114 -272.771864) (xy 124.727939 -272.769883)
			(xy 124.67972 -272.760039) (xy 124.633704 -272.742587) (xy 124.591083 -272.71798) (xy 124.552962 -272.686855)
			(xy 124.520327 -272.650018) (xy 124.494024 -272.608422) (xy 124.474733 -272.563146) (xy 124.462956 -272.515362)
			(xy 124.458996 -272.466308) (xy 124.130054 -272.466308) (xy 124.129559 -272.490915) (xy 124.121664 -272.539492)
			(xy 124.10608 -272.586173) (xy 124.083209 -272.62975) (xy 124.053644 -272.669094) (xy 124.018151 -272.703186)
			(xy 123.977648 -272.731142) (xy 123.933186 -272.75224) (xy 123.885915 -272.765932) (xy 123.83706 -272.771864)
			(xy 123.787885 -272.769883) (xy 123.739666 -272.760039) (xy 123.69365 -272.742587) (xy 123.651029 -272.71798)
			(xy 123.612908 -272.686855) (xy 123.580273 -272.650018) (xy 123.55397 -272.608422) (xy 123.534679 -272.563146)
			(xy 123.522902 -272.515362) (xy 123.518942 -272.466308) (xy 123.19 -272.466308) (xy 123.189505 -272.490915)
			(xy 123.18161 -272.539492) (xy 123.166026 -272.586173) (xy 123.143155 -272.62975) (xy 123.11359 -272.669094)
			(xy 123.078097 -272.703186) (xy 123.037594 -272.731142) (xy 122.993132 -272.75224) (xy 122.945861 -272.765932)
			(xy 122.897006 -272.771864) (xy 122.847831 -272.769883) (xy 122.799612 -272.760039) (xy 122.753596 -272.742587)
			(xy 122.710975 -272.71798) (xy 122.672854 -272.686855) (xy 122.640219 -272.650018) (xy 122.613916 -272.608422)
			(xy 122.594625 -272.563146) (xy 122.582848 -272.515362) (xy 122.578888 -272.466308) (xy 122.249946 -272.466308)
			(xy 122.249451 -272.490915) (xy 122.241556 -272.539492) (xy 122.225972 -272.586173) (xy 122.203101 -272.62975)
			(xy 122.173536 -272.669094) (xy 122.138043 -272.703186) (xy 122.09754 -272.731142) (xy 122.053078 -272.75224)
			(xy 122.005807 -272.765932) (xy 121.956952 -272.771864) (xy 121.907777 -272.769883) (xy 121.859558 -272.760039)
			(xy 121.813542 -272.742587) (xy 121.770921 -272.71798) (xy 121.7328 -272.686855) (xy 121.700165 -272.650018)
			(xy 121.673862 -272.608422) (xy 121.654571 -272.563146) (xy 121.642794 -272.515362) (xy 121.638834 -272.466308)
			(xy 121.310146 -272.466308) (xy 121.309651 -272.490915) (xy 121.301756 -272.539492) (xy 121.286172 -272.586173)
			(xy 121.263301 -272.62975) (xy 121.233736 -272.669094) (xy 121.198243 -272.703186) (xy 121.15774 -272.731142)
			(xy 121.113278 -272.75224) (xy 121.066007 -272.765932) (xy 121.017152 -272.771864) (xy 120.967977 -272.769883)
			(xy 120.919758 -272.760039) (xy 120.873742 -272.742587) (xy 120.831121 -272.71798) (xy 120.793 -272.686855)
			(xy 120.760365 -272.650018) (xy 120.734062 -272.608422) (xy 120.714771 -272.563146) (xy 120.702994 -272.515362)
			(xy 120.699034 -272.466308) (xy 120.370092 -272.466308) (xy 120.369597 -272.490915) (xy 120.361702 -272.539492)
			(xy 120.346118 -272.586173) (xy 120.323247 -272.62975) (xy 120.293682 -272.669094) (xy 120.258189 -272.703186)
			(xy 120.217686 -272.731142) (xy 120.173224 -272.75224) (xy 120.125953 -272.765932) (xy 120.077098 -272.771864)
			(xy 120.027923 -272.769883) (xy 119.979704 -272.760039) (xy 119.933688 -272.742587) (xy 119.891067 -272.71798)
			(xy 119.852946 -272.686855) (xy 119.820311 -272.650018) (xy 119.794008 -272.608422) (xy 119.774717 -272.563146)
			(xy 119.76294 -272.515362) (xy 119.75898 -272.466308) (xy 119.430038 -272.466308) (xy 119.429543 -272.490915)
			(xy 119.421648 -272.539492) (xy 119.406064 -272.586173) (xy 119.383193 -272.62975) (xy 119.353628 -272.669094)
			(xy 119.318135 -272.703186) (xy 119.277632 -272.731142) (xy 119.23317 -272.75224) (xy 119.185899 -272.765932)
			(xy 119.137044 -272.771864) (xy 119.087869 -272.769883) (xy 119.03965 -272.760039) (xy 118.993634 -272.742587)
			(xy 118.951013 -272.71798) (xy 118.912892 -272.686855) (xy 118.880257 -272.650018) (xy 118.853954 -272.608422)
			(xy 118.834663 -272.563146) (xy 118.822886 -272.515362) (xy 118.818926 -272.466308) (xy 118.489984 -272.466308)
			(xy 118.489489 -272.490915) (xy 118.481594 -272.539492) (xy 118.46601 -272.586173) (xy 118.443139 -272.62975)
			(xy 118.413574 -272.669094) (xy 118.378081 -272.703186) (xy 118.337578 -272.731142) (xy 118.293116 -272.75224)
			(xy 118.245845 -272.765932) (xy 118.19699 -272.771864) (xy 118.147815 -272.769883) (xy 118.099596 -272.760039)
			(xy 118.05358 -272.742587) (xy 118.010959 -272.71798) (xy 117.972838 -272.686855) (xy 117.940203 -272.650018)
			(xy 117.9139 -272.608422) (xy 117.894609 -272.563146) (xy 117.882832 -272.515362) (xy 117.878872 -272.466308)
			(xy 117.54993 -272.466308) (xy 117.549435 -272.490915) (xy 117.54154 -272.539492) (xy 117.525956 -272.586173)
			(xy 117.503085 -272.62975) (xy 117.47352 -272.669094) (xy 117.438027 -272.703186) (xy 117.397524 -272.731142)
			(xy 117.353062 -272.75224) (xy 117.305791 -272.765932) (xy 117.256936 -272.771864) (xy 117.207761 -272.769883)
			(xy 117.159542 -272.760039) (xy 117.113526 -272.742587) (xy 117.070905 -272.71798) (xy 117.032784 -272.686855)
			(xy 117.000149 -272.650018) (xy 116.973846 -272.608422) (xy 116.954555 -272.563146) (xy 116.942778 -272.515362)
			(xy 116.938818 -272.466308) (xy 116.61013 -272.466308) (xy 116.609635 -272.490915) (xy 116.60174 -272.539492)
			(xy 116.586156 -272.586173) (xy 116.563285 -272.62975) (xy 116.53372 -272.669094) (xy 116.498227 -272.703186)
			(xy 116.457724 -272.731142) (xy 116.413262 -272.75224) (xy 116.365991 -272.765932) (xy 116.317136 -272.771864)
			(xy 116.267961 -272.769883) (xy 116.219742 -272.760039) (xy 116.173726 -272.742587) (xy 116.131105 -272.71798)
			(xy 116.092984 -272.686855) (xy 116.060349 -272.650018) (xy 116.034046 -272.608422) (xy 116.014755 -272.563146)
			(xy 116.002978 -272.515362) (xy 115.999018 -272.466308) (xy 115.670076 -272.466308) (xy 115.669581 -272.490915)
			(xy 115.661686 -272.539492) (xy 115.646102 -272.586173) (xy 115.623231 -272.62975) (xy 115.593666 -272.669094)
			(xy 115.558173 -272.703186) (xy 115.51767 -272.731142) (xy 115.473208 -272.75224) (xy 115.425937 -272.765932)
			(xy 115.377082 -272.771864) (xy 115.327907 -272.769883) (xy 115.279688 -272.760039) (xy 115.233672 -272.742587)
			(xy 115.191051 -272.71798) (xy 115.15293 -272.686855) (xy 115.120295 -272.650018) (xy 115.093992 -272.608422)
			(xy 115.074701 -272.563146) (xy 115.062924 -272.515362) (xy 115.058964 -272.466308) (xy 114.730022 -272.466308)
			(xy 114.729527 -272.490915) (xy 114.721632 -272.539492) (xy 114.706048 -272.586173) (xy 114.683177 -272.62975)
			(xy 114.653612 -272.669094) (xy 114.618119 -272.703186) (xy 114.577616 -272.731142) (xy 114.533154 -272.75224)
			(xy 114.485883 -272.765932) (xy 114.437028 -272.771864) (xy 114.387853 -272.769883) (xy 114.339634 -272.760039)
			(xy 114.293618 -272.742587) (xy 114.250997 -272.71798) (xy 114.212876 -272.686855) (xy 114.180241 -272.650018)
			(xy 114.153938 -272.608422) (xy 114.134647 -272.563146) (xy 114.12287 -272.515362) (xy 114.11891 -272.466308)
			(xy 113.789968 -272.466308) (xy 113.789473 -272.490915) (xy 113.781578 -272.539492) (xy 113.765994 -272.586173)
			(xy 113.743123 -272.62975) (xy 113.713558 -272.669094) (xy 113.678065 -272.703186) (xy 113.637562 -272.731142)
			(xy 113.5931 -272.75224) (xy 113.545829 -272.765932) (xy 113.496974 -272.771864) (xy 113.447799 -272.769883)
			(xy 113.39958 -272.760039) (xy 113.353564 -272.742587) (xy 113.310943 -272.71798) (xy 113.272822 -272.686855)
			(xy 113.240187 -272.650018) (xy 113.213884 -272.608422) (xy 113.194593 -272.563146) (xy 113.182816 -272.515362)
			(xy 113.178856 -272.466308) (xy 110.97641 -272.466308) (xy 110.975915 -272.490915) (xy 110.96802 -272.539492)
			(xy 110.952436 -272.586173) (xy 110.929565 -272.62975) (xy 110.9 -272.669094) (xy 110.864507 -272.703186)
			(xy 110.824004 -272.731142) (xy 110.779542 -272.75224) (xy 110.732271 -272.765932) (xy 110.683416 -272.771864)
			(xy 110.634241 -272.769883) (xy 110.586022 -272.760039) (xy 110.540006 -272.742587) (xy 110.497385 -272.71798)
			(xy 110.459264 -272.686855) (xy 110.426629 -272.650018) (xy 110.400326 -272.608422) (xy 110.381035 -272.563146)
			(xy 110.369258 -272.515362) (xy 110.365298 -272.466308) (xy 110.036356 -272.466308) (xy 110.035861 -272.490915)
			(xy 110.027966 -272.539492) (xy 110.012382 -272.586173) (xy 109.989511 -272.62975) (xy 109.959946 -272.669094)
			(xy 109.924453 -272.703186) (xy 109.88395 -272.731142) (xy 109.839488 -272.75224) (xy 109.792217 -272.765932)
			(xy 109.743362 -272.771864) (xy 109.694187 -272.769883) (xy 109.645968 -272.760039) (xy 109.599952 -272.742587)
			(xy 109.557331 -272.71798) (xy 109.51921 -272.686855) (xy 109.486575 -272.650018) (xy 109.460272 -272.608422)
			(xy 109.440981 -272.563146) (xy 109.429204 -272.515362) (xy 109.425244 -272.466308) (xy 109.096302 -272.466308)
			(xy 109.095807 -272.490915) (xy 109.087912 -272.539492) (xy 109.072328 -272.586173) (xy 109.049457 -272.62975)
			(xy 109.019892 -272.669094) (xy 108.984399 -272.703186) (xy 108.943896 -272.731142) (xy 108.899434 -272.75224)
			(xy 108.852163 -272.765932) (xy 108.803308 -272.771864) (xy 108.754133 -272.769883) (xy 108.705914 -272.760039)
			(xy 108.659898 -272.742587) (xy 108.617277 -272.71798) (xy 108.579156 -272.686855) (xy 108.546521 -272.650018)
			(xy 108.520218 -272.608422) (xy 108.500927 -272.563146) (xy 108.48915 -272.515362) (xy 108.48519 -272.466308)
			(xy 108.156248 -272.466308) (xy 108.155753 -272.490915) (xy 108.147858 -272.539492) (xy 108.132274 -272.586173)
			(xy 108.109403 -272.62975) (xy 108.079838 -272.669094) (xy 108.044345 -272.703186) (xy 108.003842 -272.731142)
			(xy 107.95938 -272.75224) (xy 107.912109 -272.765932) (xy 107.863254 -272.771864) (xy 107.814079 -272.769883)
			(xy 107.76586 -272.760039) (xy 107.719844 -272.742587) (xy 107.677223 -272.71798) (xy 107.639102 -272.686855)
			(xy 107.606467 -272.650018) (xy 107.580164 -272.608422) (xy 107.560873 -272.563146) (xy 107.549096 -272.515362)
			(xy 107.545136 -272.466308) (xy 107.216448 -272.466308) (xy 107.215953 -272.490915) (xy 107.208058 -272.539492)
			(xy 107.192474 -272.586173) (xy 107.169603 -272.62975) (xy 107.140038 -272.669094) (xy 107.104545 -272.703186)
			(xy 107.064042 -272.731142) (xy 107.01958 -272.75224) (xy 106.972309 -272.765932) (xy 106.923454 -272.771864)
			(xy 106.874279 -272.769883) (xy 106.82606 -272.760039) (xy 106.780044 -272.742587) (xy 106.737423 -272.71798)
			(xy 106.699302 -272.686855) (xy 106.666667 -272.650018) (xy 106.640364 -272.608422) (xy 106.621073 -272.563146)
			(xy 106.609296 -272.515362) (xy 106.605336 -272.466308) (xy 106.276394 -272.466308) (xy 106.275899 -272.490915)
			(xy 106.268004 -272.539492) (xy 106.25242 -272.586173) (xy 106.229549 -272.62975) (xy 106.199984 -272.669094)
			(xy 106.164491 -272.703186) (xy 106.123988 -272.731142) (xy 106.079526 -272.75224) (xy 106.032255 -272.765932)
			(xy 105.9834 -272.771864) (xy 105.934225 -272.769883) (xy 105.886006 -272.760039) (xy 105.83999 -272.742587)
			(xy 105.797369 -272.71798) (xy 105.759248 -272.686855) (xy 105.726613 -272.650018) (xy 105.70031 -272.608422)
			(xy 105.681019 -272.563146) (xy 105.669242 -272.515362) (xy 105.665282 -272.466308) (xy 105.33634 -272.466308)
			(xy 105.335845 -272.490915) (xy 105.32795 -272.539492) (xy 105.312366 -272.586173) (xy 105.289495 -272.62975)
			(xy 105.25993 -272.669094) (xy 105.224437 -272.703186) (xy 105.183934 -272.731142) (xy 105.139472 -272.75224)
			(xy 105.092201 -272.765932) (xy 105.043346 -272.771864) (xy 104.994171 -272.769883) (xy 104.945952 -272.760039)
			(xy 104.899936 -272.742587) (xy 104.857315 -272.71798) (xy 104.819194 -272.686855) (xy 104.786559 -272.650018)
			(xy 104.760256 -272.608422) (xy 104.740965 -272.563146) (xy 104.729188 -272.515362) (xy 104.725228 -272.466308)
			(xy 104.396286 -272.466308) (xy 104.395791 -272.490915) (xy 104.387896 -272.539492) (xy 104.372312 -272.586173)
			(xy 104.349441 -272.62975) (xy 104.319876 -272.669094) (xy 104.284383 -272.703186) (xy 104.24388 -272.731142)
			(xy 104.199418 -272.75224) (xy 104.152147 -272.765932) (xy 104.103292 -272.771864) (xy 104.054117 -272.769883)
			(xy 104.005898 -272.760039) (xy 103.959882 -272.742587) (xy 103.917261 -272.71798) (xy 103.87914 -272.686855)
			(xy 103.846505 -272.650018) (xy 103.820202 -272.608422) (xy 103.800911 -272.563146) (xy 103.789134 -272.515362)
			(xy 103.785174 -272.466308) (xy 103.456486 -272.466308) (xy 103.455991 -272.490915) (xy 103.448096 -272.539492)
			(xy 103.432512 -272.586173) (xy 103.409641 -272.62975) (xy 103.380076 -272.669094) (xy 103.344583 -272.703186)
			(xy 103.30408 -272.731142) (xy 103.259618 -272.75224) (xy 103.212347 -272.765932) (xy 103.163492 -272.771864)
			(xy 103.114317 -272.769883) (xy 103.066098 -272.760039) (xy 103.020082 -272.742587) (xy 102.977461 -272.71798)
			(xy 102.93934 -272.686855) (xy 102.906705 -272.650018) (xy 102.880402 -272.608422) (xy 102.861111 -272.563146)
			(xy 102.849334 -272.515362) (xy 102.845374 -272.466308) (xy 102.516432 -272.466308) (xy 102.515937 -272.490915)
			(xy 102.508042 -272.539492) (xy 102.492458 -272.586173) (xy 102.469587 -272.62975) (xy 102.440022 -272.669094)
			(xy 102.404529 -272.703186) (xy 102.364026 -272.731142) (xy 102.319564 -272.75224) (xy 102.272293 -272.765932)
			(xy 102.223438 -272.771864) (xy 102.174263 -272.769883) (xy 102.126044 -272.760039) (xy 102.080028 -272.742587)
			(xy 102.037407 -272.71798) (xy 101.999286 -272.686855) (xy 101.966651 -272.650018) (xy 101.940348 -272.608422)
			(xy 101.921057 -272.563146) (xy 101.90928 -272.515362) (xy 101.90532 -272.466308) (xy 101.576378 -272.466308)
			(xy 101.575883 -272.490915) (xy 101.567988 -272.539492) (xy 101.552404 -272.586173) (xy 101.529533 -272.62975)
			(xy 101.499968 -272.669094) (xy 101.464475 -272.703186) (xy 101.423972 -272.731142) (xy 101.37951 -272.75224)
			(xy 101.332239 -272.765932) (xy 101.283384 -272.771864) (xy 101.234209 -272.769883) (xy 101.18599 -272.760039)
			(xy 101.139974 -272.742587) (xy 101.097353 -272.71798) (xy 101.059232 -272.686855) (xy 101.026597 -272.650018)
			(xy 101.000294 -272.608422) (xy 100.981003 -272.563146) (xy 100.969226 -272.515362) (xy 100.965266 -272.466308)
			(xy 100.636324 -272.466308) (xy 100.635829 -272.490915) (xy 100.627934 -272.539492) (xy 100.61235 -272.586173)
			(xy 100.589479 -272.62975) (xy 100.559914 -272.669094) (xy 100.524421 -272.703186) (xy 100.483918 -272.731142)
			(xy 100.439456 -272.75224) (xy 100.392185 -272.765932) (xy 100.34333 -272.771864) (xy 100.294155 -272.769883)
			(xy 100.245936 -272.760039) (xy 100.19992 -272.742587) (xy 100.157299 -272.71798) (xy 100.119178 -272.686855)
			(xy 100.086543 -272.650018) (xy 100.06024 -272.608422) (xy 100.040949 -272.563146) (xy 100.029172 -272.515362)
			(xy 100.025212 -272.466308) (xy 99.69627 -272.466308) (xy 99.695775 -272.490915) (xy 99.68788 -272.539492)
			(xy 99.672296 -272.586173) (xy 99.649425 -272.62975) (xy 99.61986 -272.669094) (xy 99.584367 -272.703186)
			(xy 99.543864 -272.731142) (xy 99.499402 -272.75224) (xy 99.452131 -272.765932) (xy 99.403276 -272.771864)
			(xy 99.354101 -272.769883) (xy 99.305882 -272.760039) (xy 99.259866 -272.742587) (xy 99.217245 -272.71798)
			(xy 99.179124 -272.686855) (xy 99.146489 -272.650018) (xy 99.120186 -272.608422) (xy 99.100895 -272.563146)
			(xy 99.089118 -272.515362) (xy 99.085158 -272.466308) (xy 98.75647 -272.466308) (xy 98.755975 -272.490915)
			(xy 98.74808 -272.539492) (xy 98.732496 -272.586173) (xy 98.709625 -272.62975) (xy 98.68006 -272.669094)
			(xy 98.644567 -272.703186) (xy 98.604064 -272.731142) (xy 98.559602 -272.75224) (xy 98.512331 -272.765932)
			(xy 98.463476 -272.771864) (xy 98.414301 -272.769883) (xy 98.366082 -272.760039) (xy 98.320066 -272.742587)
			(xy 98.277445 -272.71798) (xy 98.239324 -272.686855) (xy 98.206689 -272.650018) (xy 98.180386 -272.608422)
			(xy 98.161095 -272.563146) (xy 98.149318 -272.515362) (xy 98.145358 -272.466308) (xy 97.816416 -272.466308)
			(xy 97.816279 -272.479071) (xy 97.814119 -272.504505) (xy 97.812098 -272.517108) (xy 97.812352 -272.517108)
			(xy 97.80794 -272.540528) (xy 97.792819 -272.585722) (xy 97.770866 -272.62802) (xy 97.742613 -272.666398)
			(xy 97.708745 -272.699925) (xy 97.68967 -272.714212) (xy 97.680272 -272.720816) (xy 97.66935 -272.74012)
			(xy 97.662238 -272.828258) (xy 97.661222 -272.839688) (xy 97.668842 -272.860262) (xy 97.683574 -272.874994)
			(xy 97.684082 -272.875502) (xy 97.691462 -272.882085) (xy 97.709762 -272.889533) (xy 97.719642 -272.88998)
			(xy 125.852174 -272.88998) (xy 125.862239 -272.890416) (xy 125.880826 -272.898147) (xy 125.888242 -272.904966)
			(xy 125.939042 -272.955766) (xy 125.946441 -272.962609) (xy 125.96504 -272.970334) (xy 125.97511 -272.970752)
			(xy 126.174754 -272.970752) (xy 126.198769 -272.971195) (xy 126.246209 -272.978702) (xy 126.29189 -272.993539)
			(xy 126.334687 -273.015341) (xy 126.373546 -273.043569) (xy 126.40751 -273.07753) (xy 126.435743 -273.116386)
			(xy 126.457548 -273.159181) (xy 126.47239 -273.20486) (xy 126.479902 -273.252299) (xy 126.480316 -273.276314)
			(xy 126.809004 -273.276314) (xy 126.812964 -273.22726) (xy 126.824741 -273.179476) (xy 126.844032 -273.1342)
			(xy 126.870335 -273.092604) (xy 126.90297 -273.055767) (xy 126.941091 -273.024642) (xy 126.983712 -273.000035)
			(xy 127.029728 -272.982583) (xy 127.077947 -272.972739) (xy 127.127122 -272.970758) (xy 127.175977 -272.97669)
			(xy 127.223248 -272.990382) (xy 127.26771 -273.01148) (xy 127.308213 -273.039436) (xy 127.343706 -273.073528)
			(xy 127.373271 -273.112872) (xy 127.396142 -273.156449) (xy 127.411726 -273.20313) (xy 127.419621 -273.251707)
			(xy 127.420116 -273.276314) (xy 127.738627 -273.276314) (xy 127.742722 -273.225586) (xy 127.754901 -273.176172)
			(xy 127.774849 -273.129352) (xy 127.80205 -273.086338) (xy 127.835798 -273.048244) (xy 127.87522 -273.016057)
			(xy 127.919294 -272.990611) (xy 127.96688 -272.972564) (xy 128.016744 -272.962384) (xy 128.067596 -272.960335)
			(xy 128.118117 -272.966469) (xy 128.167001 -272.980629) (xy 128.21298 -273.002446) (xy 128.254864 -273.031356)
			(xy 128.291568 -273.066611) (xy 128.322141 -273.107297) (xy 128.345792 -273.15236) (xy 128.361908 -273.200634)
			(xy 128.370072 -273.250868) (xy 128.370584 -273.276314) (xy 128.688858 -273.276314) (xy 128.692818 -273.22726)
			(xy 128.704595 -273.179476) (xy 128.723886 -273.1342) (xy 128.750189 -273.092604) (xy 128.782824 -273.055767)
			(xy 128.820945 -273.024642) (xy 128.863566 -273.000035) (xy 128.909582 -272.982583) (xy 128.957801 -272.972739)
			(xy 129.006976 -272.970758) (xy 129.055831 -272.97669) (xy 129.103102 -272.990382) (xy 129.147564 -273.01148)
			(xy 129.188067 -273.039436) (xy 129.22356 -273.073528) (xy 129.253125 -273.112872) (xy 129.275996 -273.156449)
			(xy 129.29158 -273.20313) (xy 129.299475 -273.251707) (xy 129.29997 -273.276314) (xy 129.618481 -273.276314)
			(xy 129.622576 -273.225586) (xy 129.634755 -273.176172) (xy 129.654703 -273.129352) (xy 129.681904 -273.086338)
			(xy 129.715652 -273.048244) (xy 129.755074 -273.016057) (xy 129.799148 -272.990611) (xy 129.846734 -272.972564)
			(xy 129.896598 -272.962384) (xy 129.94745 -272.960335) (xy 129.997971 -272.966469) (xy 130.046855 -272.980629)
			(xy 130.092834 -273.002446) (xy 130.134718 -273.031356) (xy 130.171422 -273.066611) (xy 130.201995 -273.107297)
			(xy 130.225646 -273.15236) (xy 130.241762 -273.200634) (xy 130.249926 -273.250868) (xy 130.250438 -273.276314)
			(xy 130.568966 -273.276314) (xy 130.572926 -273.22726) (xy 130.584703 -273.179476) (xy 130.603994 -273.1342)
			(xy 130.630297 -273.092604) (xy 130.662932 -273.055767) (xy 130.701053 -273.024642) (xy 130.743674 -273.000035)
			(xy 130.78969 -272.982583) (xy 130.837909 -272.972739) (xy 130.887084 -272.970758) (xy 130.935939 -272.97669)
			(xy 130.98321 -272.990382) (xy 131.027672 -273.01148) (xy 131.068175 -273.039436) (xy 131.103668 -273.073528)
			(xy 131.133233 -273.112872) (xy 131.156104 -273.156449) (xy 131.171688 -273.20313) (xy 131.179583 -273.251707)
			(xy 131.180078 -273.276314) (xy 131.498589 -273.276314) (xy 131.502684 -273.225586) (xy 131.514863 -273.176172)
			(xy 131.534811 -273.129352) (xy 131.562012 -273.086338) (xy 131.59576 -273.048244) (xy 131.635182 -273.016057)
			(xy 131.679256 -272.990611) (xy 131.726842 -272.972564) (xy 131.776706 -272.962384) (xy 131.827558 -272.960335)
			(xy 131.878079 -272.966469) (xy 131.926963 -272.980629) (xy 131.972942 -273.002446) (xy 132.014826 -273.031356)
			(xy 132.05153 -273.066611) (xy 132.082103 -273.107297) (xy 132.105754 -273.15236) (xy 132.12187 -273.200634)
			(xy 132.130034 -273.250868) (xy 132.130546 -273.276314) (xy 132.438643 -273.276314) (xy 132.442738 -273.225586)
			(xy 132.454917 -273.176172) (xy 132.474865 -273.129352) (xy 132.502066 -273.086338) (xy 132.535814 -273.048244)
			(xy 132.575236 -273.016057) (xy 132.61931 -272.990611) (xy 132.666896 -272.972564) (xy 132.71676 -272.962384)
			(xy 132.767612 -272.960335) (xy 132.818133 -272.966469) (xy 132.867017 -272.980629) (xy 132.912996 -273.002446)
			(xy 132.95488 -273.031356) (xy 132.991584 -273.066611) (xy 133.022157 -273.107297) (xy 133.045808 -273.15236)
			(xy 133.061924 -273.200634) (xy 133.070088 -273.250868) (xy 133.0706 -273.276314) (xy 133.388874 -273.276314)
			(xy 133.392834 -273.22726) (xy 133.404611 -273.179476) (xy 133.423902 -273.1342) (xy 133.450205 -273.092604)
			(xy 133.48284 -273.055767) (xy 133.520961 -273.024642) (xy 133.563582 -273.000035) (xy 133.609598 -272.982583)
			(xy 133.657817 -272.972739) (xy 133.706992 -272.970758) (xy 133.755847 -272.97669) (xy 133.803118 -272.990382)
			(xy 133.84758 -273.01148) (xy 133.888083 -273.039436) (xy 133.923576 -273.073528) (xy 133.953141 -273.112872)
			(xy 133.976012 -273.156449) (xy 133.991596 -273.20313) (xy 133.999491 -273.251707) (xy 133.999986 -273.276314)
			(xy 134.328928 -273.276314) (xy 134.332888 -273.22726) (xy 134.344665 -273.179476) (xy 134.363956 -273.1342)
			(xy 134.390259 -273.092604) (xy 134.422894 -273.055767) (xy 134.461015 -273.024642) (xy 134.503636 -273.000035)
			(xy 134.549652 -272.982583) (xy 134.597871 -272.972739) (xy 134.647046 -272.970758) (xy 134.695901 -272.97669)
			(xy 134.743172 -272.990382) (xy 134.787634 -273.01148) (xy 134.828137 -273.039436) (xy 134.86363 -273.073528)
			(xy 134.893195 -273.112872) (xy 134.916066 -273.156449) (xy 134.93165 -273.20313) (xy 134.939545 -273.251707)
			(xy 134.94004 -273.276314) (xy 135.268982 -273.276314) (xy 135.272942 -273.22726) (xy 135.284719 -273.179476)
			(xy 135.30401 -273.1342) (xy 135.330313 -273.092604) (xy 135.362948 -273.055767) (xy 135.401069 -273.024642)
			(xy 135.44369 -273.000035) (xy 135.489706 -272.982583) (xy 135.537925 -272.972739) (xy 135.5871 -272.970758)
			(xy 135.635955 -272.97669) (xy 135.683226 -272.990382) (xy 135.727688 -273.01148) (xy 135.768191 -273.039436)
			(xy 135.803684 -273.073528) (xy 135.833249 -273.112872) (xy 135.85612 -273.156449) (xy 135.871704 -273.20313)
			(xy 135.879599 -273.251707) (xy 135.880094 -273.276314) (xy 136.209036 -273.276314) (xy 136.212996 -273.22726)
			(xy 136.224773 -273.179476) (xy 136.244064 -273.1342) (xy 136.270367 -273.092604) (xy 136.303002 -273.055767)
			(xy 136.341123 -273.024642) (xy 136.383744 -273.000035) (xy 136.42976 -272.982583) (xy 136.477979 -272.972739)
			(xy 136.527154 -272.970758) (xy 136.576009 -272.97669) (xy 136.62328 -272.990382) (xy 136.667742 -273.01148)
			(xy 136.708245 -273.039436) (xy 136.743738 -273.073528) (xy 136.773303 -273.112872) (xy 136.796174 -273.156449)
			(xy 136.811758 -273.20313) (xy 136.819653 -273.251707) (xy 136.820148 -273.276314) (xy 137.148836 -273.276314)
			(xy 137.152796 -273.22726) (xy 137.164573 -273.179476) (xy 137.183864 -273.1342) (xy 137.210167 -273.092604)
			(xy 137.242802 -273.055767) (xy 137.280923 -273.024642) (xy 137.323544 -273.000035) (xy 137.36956 -272.982583)
			(xy 137.417779 -272.972739) (xy 137.466954 -272.970758) (xy 137.515809 -272.97669) (xy 137.56308 -272.990382)
			(xy 137.607542 -273.01148) (xy 137.648045 -273.039436) (xy 137.683538 -273.073528) (xy 137.713103 -273.112872)
			(xy 137.735974 -273.156449) (xy 137.751558 -273.20313) (xy 137.759453 -273.251707) (xy 137.759948 -273.276314)
			(xy 138.08889 -273.276314) (xy 138.09285 -273.22726) (xy 138.104627 -273.179476) (xy 138.123918 -273.1342)
			(xy 138.150221 -273.092604) (xy 138.182856 -273.055767) (xy 138.220977 -273.024642) (xy 138.263598 -273.000035)
			(xy 138.309614 -272.982583) (xy 138.357833 -272.972739) (xy 138.407008 -272.970758) (xy 138.455863 -272.97669)
			(xy 138.503134 -272.990382) (xy 138.547596 -273.01148) (xy 138.588099 -273.039436) (xy 138.623592 -273.073528)
			(xy 138.653157 -273.112872) (xy 138.676028 -273.156449) (xy 138.691612 -273.20313) (xy 138.699507 -273.251707)
			(xy 138.700002 -273.276314) (xy 139.028944 -273.276314) (xy 139.032904 -273.22726) (xy 139.044681 -273.179476)
			(xy 139.063972 -273.1342) (xy 139.090275 -273.092604) (xy 139.12291 -273.055767) (xy 139.161031 -273.024642)
			(xy 139.203652 -273.000035) (xy 139.249668 -272.982583) (xy 139.297887 -272.972739) (xy 139.347062 -272.970758)
			(xy 139.395917 -272.97669) (xy 139.443188 -272.990382) (xy 139.48765 -273.01148) (xy 139.528153 -273.039436)
			(xy 139.563646 -273.073528) (xy 139.593211 -273.112872) (xy 139.616082 -273.156449) (xy 139.631666 -273.20313)
			(xy 139.639561 -273.251707) (xy 139.640056 -273.276314) (xy 139.639561 -273.300921) (xy 139.631666 -273.349498)
			(xy 139.616082 -273.396179) (xy 139.593211 -273.439756) (xy 139.563646 -273.4791) (xy 139.528153 -273.513192)
			(xy 139.48765 -273.541148) (xy 139.443188 -273.562246) (xy 139.395917 -273.575938) (xy 139.347062 -273.58187)
			(xy 139.297887 -273.579889) (xy 139.249668 -273.570045) (xy 139.203652 -273.552593) (xy 139.161031 -273.527986)
			(xy 139.12291 -273.496861) (xy 139.090275 -273.460024) (xy 139.063972 -273.418428) (xy 139.044681 -273.373152)
			(xy 139.032904 -273.325368) (xy 139.028944 -273.276314) (xy 138.700002 -273.276314) (xy 138.699507 -273.300921)
			(xy 138.691612 -273.349498) (xy 138.676028 -273.396179) (xy 138.653157 -273.439756) (xy 138.623592 -273.4791)
			(xy 138.588099 -273.513192) (xy 138.547596 -273.541148) (xy 138.503134 -273.562246) (xy 138.455863 -273.575938)
			(xy 138.407008 -273.58187) (xy 138.357833 -273.579889) (xy 138.309614 -273.570045) (xy 138.263598 -273.552593)
			(xy 138.220977 -273.527986) (xy 138.182856 -273.496861) (xy 138.150221 -273.460024) (xy 138.123918 -273.418428)
			(xy 138.104627 -273.373152) (xy 138.09285 -273.325368) (xy 138.08889 -273.276314) (xy 137.759948 -273.276314)
			(xy 137.759453 -273.300921) (xy 137.751558 -273.349498) (xy 137.735974 -273.396179) (xy 137.713103 -273.439756)
			(xy 137.683538 -273.4791) (xy 137.648045 -273.513192) (xy 137.607542 -273.541148) (xy 137.56308 -273.562246)
			(xy 137.515809 -273.575938) (xy 137.466954 -273.58187) (xy 137.417779 -273.579889) (xy 137.36956 -273.570045)
			(xy 137.323544 -273.552593) (xy 137.280923 -273.527986) (xy 137.242802 -273.496861) (xy 137.210167 -273.460024)
			(xy 137.183864 -273.418428) (xy 137.164573 -273.373152) (xy 137.152796 -273.325368) (xy 137.148836 -273.276314)
			(xy 136.820148 -273.276314) (xy 136.819653 -273.300921) (xy 136.811758 -273.349498) (xy 136.796174 -273.396179)
			(xy 136.773303 -273.439756) (xy 136.743738 -273.4791) (xy 136.708245 -273.513192) (xy 136.667742 -273.541148)
			(xy 136.62328 -273.562246) (xy 136.576009 -273.575938) (xy 136.527154 -273.58187) (xy 136.477979 -273.579889)
			(xy 136.42976 -273.570045) (xy 136.383744 -273.552593) (xy 136.341123 -273.527986) (xy 136.303002 -273.496861)
			(xy 136.270367 -273.460024) (xy 136.244064 -273.418428) (xy 136.224773 -273.373152) (xy 136.212996 -273.325368)
			(xy 136.209036 -273.276314) (xy 135.880094 -273.276314) (xy 135.879599 -273.300921) (xy 135.871704 -273.349498)
			(xy 135.85612 -273.396179) (xy 135.833249 -273.439756) (xy 135.803684 -273.4791) (xy 135.768191 -273.513192)
			(xy 135.727688 -273.541148) (xy 135.683226 -273.562246) (xy 135.635955 -273.575938) (xy 135.5871 -273.58187)
			(xy 135.537925 -273.579889) (xy 135.489706 -273.570045) (xy 135.44369 -273.552593) (xy 135.401069 -273.527986)
			(xy 135.362948 -273.496861) (xy 135.330313 -273.460024) (xy 135.30401 -273.418428) (xy 135.284719 -273.373152)
			(xy 135.272942 -273.325368) (xy 135.268982 -273.276314) (xy 134.94004 -273.276314) (xy 134.939545 -273.300921)
			(xy 134.93165 -273.349498) (xy 134.916066 -273.396179) (xy 134.893195 -273.439756) (xy 134.86363 -273.4791)
			(xy 134.828137 -273.513192) (xy 134.787634 -273.541148) (xy 134.743172 -273.562246) (xy 134.695901 -273.575938)
			(xy 134.647046 -273.58187) (xy 134.597871 -273.579889) (xy 134.549652 -273.570045) (xy 134.503636 -273.552593)
			(xy 134.461015 -273.527986) (xy 134.422894 -273.496861) (xy 134.390259 -273.460024) (xy 134.363956 -273.418428)
			(xy 134.344665 -273.373152) (xy 134.332888 -273.325368) (xy 134.328928 -273.276314) (xy 133.999986 -273.276314)
			(xy 133.999491 -273.300921) (xy 133.991596 -273.349498) (xy 133.976012 -273.396179) (xy 133.953141 -273.439756)
			(xy 133.923576 -273.4791) (xy 133.888083 -273.513192) (xy 133.84758 -273.541148) (xy 133.803118 -273.562246)
			(xy 133.755847 -273.575938) (xy 133.706992 -273.58187) (xy 133.657817 -273.579889) (xy 133.609598 -273.570045)
			(xy 133.563582 -273.552593) (xy 133.520961 -273.527986) (xy 133.48284 -273.496861) (xy 133.450205 -273.460024)
			(xy 133.423902 -273.418428) (xy 133.404611 -273.373152) (xy 133.392834 -273.325368) (xy 133.388874 -273.276314)
			(xy 133.0706 -273.276314) (xy 133.070088 -273.30176) (xy 133.061924 -273.351994) (xy 133.045808 -273.400268)
			(xy 133.022157 -273.445331) (xy 132.991584 -273.486017) (xy 132.95488 -273.521272) (xy 132.912996 -273.550182)
			(xy 132.867017 -273.571999) (xy 132.818133 -273.586159) (xy 132.767612 -273.592293) (xy 132.71676 -273.590244)
			(xy 132.666896 -273.580064) (xy 132.61931 -273.562017) (xy 132.575236 -273.536571) (xy 132.535814 -273.504384)
			(xy 132.502066 -273.46629) (xy 132.474865 -273.423276) (xy 132.454917 -273.376456) (xy 132.442738 -273.327042)
			(xy 132.438643 -273.276314) (xy 132.130546 -273.276314) (xy 132.130034 -273.30176) (xy 132.12187 -273.351994)
			(xy 132.105754 -273.400268) (xy 132.082103 -273.445331) (xy 132.05153 -273.486017) (xy 132.014826 -273.521272)
			(xy 131.972942 -273.550182) (xy 131.926963 -273.571999) (xy 131.878079 -273.586159) (xy 131.827558 -273.592293)
			(xy 131.776706 -273.590244) (xy 131.726842 -273.580064) (xy 131.679256 -273.562017) (xy 131.635182 -273.536571)
			(xy 131.59576 -273.504384) (xy 131.562012 -273.46629) (xy 131.534811 -273.423276) (xy 131.514863 -273.376456)
			(xy 131.502684 -273.327042) (xy 131.498589 -273.276314) (xy 131.180078 -273.276314) (xy 131.179583 -273.300921)
			(xy 131.171688 -273.349498) (xy 131.156104 -273.396179) (xy 131.133233 -273.439756) (xy 131.103668 -273.4791)
			(xy 131.068175 -273.513192) (xy 131.027672 -273.541148) (xy 130.98321 -273.562246) (xy 130.935939 -273.575938)
			(xy 130.887084 -273.58187) (xy 130.837909 -273.579889) (xy 130.78969 -273.570045) (xy 130.743674 -273.552593)
			(xy 130.701053 -273.527986) (xy 130.662932 -273.496861) (xy 130.630297 -273.460024) (xy 130.603994 -273.418428)
			(xy 130.584703 -273.373152) (xy 130.572926 -273.325368) (xy 130.568966 -273.276314) (xy 130.250438 -273.276314)
			(xy 130.249926 -273.30176) (xy 130.241762 -273.351994) (xy 130.225646 -273.400268) (xy 130.201995 -273.445331)
			(xy 130.171422 -273.486017) (xy 130.134718 -273.521272) (xy 130.092834 -273.550182) (xy 130.046855 -273.571999)
			(xy 129.997971 -273.586159) (xy 129.94745 -273.592293) (xy 129.896598 -273.590244) (xy 129.846734 -273.580064)
			(xy 129.799148 -273.562017) (xy 129.755074 -273.536571) (xy 129.715652 -273.504384) (xy 129.681904 -273.46629)
			(xy 129.654703 -273.423276) (xy 129.634755 -273.376456) (xy 129.622576 -273.327042) (xy 129.618481 -273.276314)
			(xy 129.29997 -273.276314) (xy 129.299475 -273.300921) (xy 129.29158 -273.349498) (xy 129.275996 -273.396179)
			(xy 129.253125 -273.439756) (xy 129.22356 -273.4791) (xy 129.188067 -273.513192) (xy 129.147564 -273.541148)
			(xy 129.103102 -273.562246) (xy 129.055831 -273.575938) (xy 129.006976 -273.58187) (xy 128.957801 -273.579889)
			(xy 128.909582 -273.570045) (xy 128.863566 -273.552593) (xy 128.820945 -273.527986) (xy 128.782824 -273.496861)
			(xy 128.750189 -273.460024) (xy 128.723886 -273.418428) (xy 128.704595 -273.373152) (xy 128.692818 -273.325368)
			(xy 128.688858 -273.276314) (xy 128.370584 -273.276314) (xy 128.370072 -273.30176) (xy 128.361908 -273.351994)
			(xy 128.345792 -273.400268) (xy 128.322141 -273.445331) (xy 128.291568 -273.486017) (xy 128.254864 -273.521272)
			(xy 128.21298 -273.550182) (xy 128.167001 -273.571999) (xy 128.118117 -273.586159) (xy 128.067596 -273.592293)
			(xy 128.016744 -273.590244) (xy 127.96688 -273.580064) (xy 127.919294 -273.562017) (xy 127.87522 -273.536571)
			(xy 127.835798 -273.504384) (xy 127.80205 -273.46629) (xy 127.774849 -273.423276) (xy 127.754901 -273.376456)
			(xy 127.742722 -273.327042) (xy 127.738627 -273.276314) (xy 127.420116 -273.276314) (xy 127.419621 -273.300921)
			(xy 127.411726 -273.349498) (xy 127.396142 -273.396179) (xy 127.373271 -273.439756) (xy 127.343706 -273.4791)
			(xy 127.308213 -273.513192) (xy 127.26771 -273.541148) (xy 127.223248 -273.562246) (xy 127.175977 -273.575938)
			(xy 127.127122 -273.58187) (xy 127.077947 -273.579889) (xy 127.029728 -273.570045) (xy 126.983712 -273.552593)
			(xy 126.941091 -273.527986) (xy 126.90297 -273.496861) (xy 126.870335 -273.460024) (xy 126.844032 -273.418428)
			(xy 126.824741 -273.373152) (xy 126.812964 -273.325368) (xy 126.809004 -273.276314) (xy 126.480316 -273.276314)
			(xy 126.479853 -273.300223) (xy 126.472405 -273.347457) (xy 126.457695 -273.392956) (xy 126.447296 -273.41449)
			(xy 126.43993 -273.429222) (xy 126.44501 -273.461734) (xy 126.818644 -273.835368) (xy 126.8222 -273.837908)
			(xy 126.841616 -273.852349) (xy 126.876053 -273.886337) (xy 126.904695 -273.925335) (xy 126.926824 -273.968363)
			(xy 126.941885 -274.014345) (xy 126.949502 -274.062127) (xy 126.949962 -274.08632) (xy 127.278904 -274.08632)
			(xy 127.282864 -274.037266) (xy 127.294641 -273.989482) (xy 127.313932 -273.944206) (xy 127.340235 -273.90261)
			(xy 127.37287 -273.865773) (xy 127.410991 -273.834648) (xy 127.453612 -273.810041) (xy 127.499628 -273.792589)
			(xy 127.547847 -273.782745) (xy 127.597022 -273.780764) (xy 127.645877 -273.786696) (xy 127.693148 -273.800388)
			(xy 127.73761 -273.821486) (xy 127.778113 -273.849442) (xy 127.813606 -273.883534) (xy 127.843171 -273.922878)
			(xy 127.866042 -273.966455) (xy 127.881626 -274.013136) (xy 127.889521 -274.061713) (xy 127.890016 -274.08632)
			(xy 128.208527 -274.08632) (xy 128.212622 -274.035592) (xy 128.224801 -273.986178) (xy 128.244749 -273.939358)
			(xy 128.27195 -273.896344) (xy 128.305698 -273.85825) (xy 128.34512 -273.826063) (xy 128.389194 -273.800617)
			(xy 128.43678 -273.78257) (xy 128.486644 -273.77239) (xy 128.537496 -273.770341) (xy 128.588017 -273.776475)
			(xy 128.636901 -273.790635) (xy 128.68288 -273.812452) (xy 128.724764 -273.841362) (xy 128.761468 -273.876617)
			(xy 128.792041 -273.917303) (xy 128.815692 -273.962366) (xy 128.831808 -274.01064) (xy 128.839972 -274.060874)
			(xy 128.840484 -274.08632) (xy 129.148581 -274.08632) (xy 129.152676 -274.035592) (xy 129.164855 -273.986178)
			(xy 129.184803 -273.939358) (xy 129.212004 -273.896344) (xy 129.245752 -273.85825) (xy 129.285174 -273.826063)
			(xy 129.329248 -273.800617) (xy 129.376834 -273.78257) (xy 129.426698 -273.77239) (xy 129.47755 -273.770341)
			(xy 129.528071 -273.776475) (xy 129.576955 -273.790635) (xy 129.622934 -273.812452) (xy 129.664818 -273.841362)
			(xy 129.701522 -273.876617) (xy 129.732095 -273.917303) (xy 129.755746 -273.962366) (xy 129.771862 -274.01064)
			(xy 129.780026 -274.060874) (xy 129.780538 -274.08632) (xy 130.099066 -274.08632) (xy 130.103026 -274.037266)
			(xy 130.114803 -273.989482) (xy 130.134094 -273.944206) (xy 130.160397 -273.90261) (xy 130.193032 -273.865773)
			(xy 130.231153 -273.834648) (xy 130.273774 -273.810041) (xy 130.31979 -273.792589) (xy 130.368009 -273.782745)
			(xy 130.417184 -273.780764) (xy 130.466039 -273.786696) (xy 130.51331 -273.800388) (xy 130.557772 -273.821486)
			(xy 130.598275 -273.849442) (xy 130.633768 -273.883534) (xy 130.663333 -273.922878) (xy 130.686204 -273.966455)
			(xy 130.701788 -274.013136) (xy 130.709683 -274.061713) (xy 130.710178 -274.08632) (xy 131.028435 -274.08632)
			(xy 131.03253 -274.035592) (xy 131.044709 -273.986178) (xy 131.064657 -273.939358) (xy 131.091858 -273.896344)
			(xy 131.125606 -273.85825) (xy 131.165028 -273.826063) (xy 131.209102 -273.800617) (xy 131.256688 -273.78257)
			(xy 131.306552 -273.77239) (xy 131.357404 -273.770341) (xy 131.407925 -273.776475) (xy 131.456809 -273.790635)
			(xy 131.502788 -273.812452) (xy 131.544672 -273.841362) (xy 131.581376 -273.876617) (xy 131.611949 -273.917303)
			(xy 131.6356 -273.962366) (xy 131.651716 -274.01064) (xy 131.65988 -274.060874) (xy 131.660392 -274.08632)
			(xy 131.97892 -274.08632) (xy 131.98288 -274.037266) (xy 131.994657 -273.989482) (xy 132.013948 -273.944206)
			(xy 132.040251 -273.90261) (xy 132.072886 -273.865773) (xy 132.111007 -273.834648) (xy 132.153628 -273.810041)
			(xy 132.199644 -273.792589) (xy 132.247863 -273.782745) (xy 132.297038 -273.780764) (xy 132.345893 -273.786696)
			(xy 132.393164 -273.800388) (xy 132.437626 -273.821486) (xy 132.478129 -273.849442) (xy 132.513622 -273.883534)
			(xy 132.543187 -273.922878) (xy 132.566058 -273.966455) (xy 132.581642 -274.013136) (xy 132.589537 -274.061713)
			(xy 132.590032 -274.08632) (xy 132.908543 -274.08632) (xy 132.912638 -274.035592) (xy 132.924817 -273.986178)
			(xy 132.944765 -273.939358) (xy 132.971966 -273.896344) (xy 133.005714 -273.85825) (xy 133.045136 -273.826063)
			(xy 133.08921 -273.800617) (xy 133.136796 -273.78257) (xy 133.18666 -273.77239) (xy 133.237512 -273.770341)
			(xy 133.288033 -273.776475) (xy 133.336917 -273.790635) (xy 133.382896 -273.812452) (xy 133.42478 -273.841362)
			(xy 133.461484 -273.876617) (xy 133.492057 -273.917303) (xy 133.515708 -273.962366) (xy 133.531824 -274.01064)
			(xy 133.539988 -274.060874) (xy 133.5405 -274.08632) (xy 133.859028 -274.08632) (xy 133.862988 -274.037266)
			(xy 133.874765 -273.989482) (xy 133.894056 -273.944206) (xy 133.920359 -273.90261) (xy 133.952994 -273.865773)
			(xy 133.991115 -273.834648) (xy 134.033736 -273.810041) (xy 134.079752 -273.792589) (xy 134.127971 -273.782745)
			(xy 134.177146 -273.780764) (xy 134.226001 -273.786696) (xy 134.273272 -273.800388) (xy 134.317734 -273.821486)
			(xy 134.358237 -273.849442) (xy 134.39373 -273.883534) (xy 134.423295 -273.922878) (xy 134.446166 -273.966455)
			(xy 134.46175 -274.013136) (xy 134.469645 -274.061713) (xy 134.47014 -274.08632) (xy 134.798828 -274.08632)
			(xy 134.802788 -274.037266) (xy 134.814565 -273.989482) (xy 134.833856 -273.944206) (xy 134.860159 -273.90261)
			(xy 134.892794 -273.865773) (xy 134.930915 -273.834648) (xy 134.973536 -273.810041) (xy 135.019552 -273.792589)
			(xy 135.067771 -273.782745) (xy 135.116946 -273.780764) (xy 135.165801 -273.786696) (xy 135.213072 -273.800388)
			(xy 135.257534 -273.821486) (xy 135.298037 -273.849442) (xy 135.33353 -273.883534) (xy 135.363095 -273.922878)
			(xy 135.385966 -273.966455) (xy 135.40155 -274.013136) (xy 135.409445 -274.061713) (xy 135.40994 -274.08632)
			(xy 135.738882 -274.08632) (xy 135.742842 -274.037266) (xy 135.754619 -273.989482) (xy 135.77391 -273.944206)
			(xy 135.800213 -273.90261) (xy 135.832848 -273.865773) (xy 135.870969 -273.834648) (xy 135.91359 -273.810041)
			(xy 135.959606 -273.792589) (xy 136.007825 -273.782745) (xy 136.057 -273.780764) (xy 136.105855 -273.786696)
			(xy 136.153126 -273.800388) (xy 136.197588 -273.821486) (xy 136.238091 -273.849442) (xy 136.273584 -273.883534)
			(xy 136.303149 -273.922878) (xy 136.32602 -273.966455) (xy 136.341604 -274.013136) (xy 136.349499 -274.061713)
			(xy 136.349994 -274.08632) (xy 136.678936 -274.08632) (xy 136.682896 -274.037266) (xy 136.694673 -273.989482)
			(xy 136.713964 -273.944206) (xy 136.740267 -273.90261) (xy 136.772902 -273.865773) (xy 136.811023 -273.834648)
			(xy 136.853644 -273.810041) (xy 136.89966 -273.792589) (xy 136.947879 -273.782745) (xy 136.997054 -273.780764)
			(xy 137.045909 -273.786696) (xy 137.09318 -273.800388) (xy 137.137642 -273.821486) (xy 137.178145 -273.849442)
			(xy 137.213638 -273.883534) (xy 137.243203 -273.922878) (xy 137.266074 -273.966455) (xy 137.281658 -274.013136)
			(xy 137.289553 -274.061713) (xy 137.290048 -274.08632) (xy 137.61899 -274.08632) (xy 137.62295 -274.037266)
			(xy 137.634727 -273.989482) (xy 137.654018 -273.944206) (xy 137.680321 -273.90261) (xy 137.712956 -273.865773)
			(xy 137.751077 -273.834648) (xy 137.793698 -273.810041) (xy 137.839714 -273.792589) (xy 137.887933 -273.782745)
			(xy 137.937108 -273.780764) (xy 137.985963 -273.786696) (xy 138.033234 -273.800388) (xy 138.077696 -273.821486)
			(xy 138.118199 -273.849442) (xy 138.153692 -273.883534) (xy 138.183257 -273.922878) (xy 138.206128 -273.966455)
			(xy 138.221712 -274.013136) (xy 138.229607 -274.061713) (xy 138.230102 -274.08632) (xy 138.559044 -274.08632)
			(xy 138.563004 -274.037266) (xy 138.574781 -273.989482) (xy 138.594072 -273.944206) (xy 138.620375 -273.90261)
			(xy 138.65301 -273.865773) (xy 138.691131 -273.834648) (xy 138.733752 -273.810041) (xy 138.779768 -273.792589)
			(xy 138.827987 -273.782745) (xy 138.877162 -273.780764) (xy 138.926017 -273.786696) (xy 138.973288 -273.800388)
			(xy 139.01775 -273.821486) (xy 139.058253 -273.849442) (xy 139.093746 -273.883534) (xy 139.123311 -273.922878)
			(xy 139.146182 -273.966455) (xy 139.161766 -274.013136) (xy 139.169661 -274.061713) (xy 139.170156 -274.08632)
			(xy 139.498844 -274.08632) (xy 139.502804 -274.037266) (xy 139.514581 -273.989482) (xy 139.533872 -273.944206)
			(xy 139.560175 -273.90261) (xy 139.59281 -273.865773) (xy 139.630931 -273.834648) (xy 139.673552 -273.810041)
			(xy 139.719568 -273.792589) (xy 139.767787 -273.782745) (xy 139.816962 -273.780764) (xy 139.865817 -273.786696)
			(xy 139.913088 -273.800388) (xy 139.95755 -273.821486) (xy 139.998053 -273.849442) (xy 140.033546 -273.883534)
			(xy 140.063111 -273.922878) (xy 140.085982 -273.966455) (xy 140.101566 -274.013136) (xy 140.109461 -274.061713)
			(xy 140.109956 -274.08632) (xy 140.109461 -274.110927) (xy 140.101566 -274.159504) (xy 140.085982 -274.206185)
			(xy 140.063111 -274.249762) (xy 140.033546 -274.289106) (xy 139.998053 -274.323198) (xy 139.95755 -274.351154)
			(xy 139.913088 -274.372252) (xy 139.865817 -274.385944) (xy 139.816962 -274.391876) (xy 139.767787 -274.389895)
			(xy 139.719568 -274.380051) (xy 139.673552 -274.362599) (xy 139.630931 -274.337992) (xy 139.59281 -274.306867)
			(xy 139.560175 -274.27003) (xy 139.533872 -274.228434) (xy 139.514581 -274.183158) (xy 139.502804 -274.135374)
			(xy 139.498844 -274.08632) (xy 139.170156 -274.08632) (xy 139.169661 -274.110927) (xy 139.161766 -274.159504)
			(xy 139.146182 -274.206185) (xy 139.123311 -274.249762) (xy 139.093746 -274.289106) (xy 139.058253 -274.323198)
			(xy 139.01775 -274.351154) (xy 138.973288 -274.372252) (xy 138.926017 -274.385944) (xy 138.877162 -274.391876)
			(xy 138.827987 -274.389895) (xy 138.779768 -274.380051) (xy 138.733752 -274.362599) (xy 138.691131 -274.337992)
			(xy 138.65301 -274.306867) (xy 138.620375 -274.27003) (xy 138.594072 -274.228434) (xy 138.574781 -274.183158)
			(xy 138.563004 -274.135374) (xy 138.559044 -274.08632) (xy 138.230102 -274.08632) (xy 138.229607 -274.110927)
			(xy 138.221712 -274.159504) (xy 138.206128 -274.206185) (xy 138.183257 -274.249762) (xy 138.153692 -274.289106)
			(xy 138.118199 -274.323198) (xy 138.077696 -274.351154) (xy 138.033234 -274.372252) (xy 137.985963 -274.385944)
			(xy 137.937108 -274.391876) (xy 137.887933 -274.389895) (xy 137.839714 -274.380051) (xy 137.793698 -274.362599)
			(xy 137.751077 -274.337992) (xy 137.712956 -274.306867) (xy 137.680321 -274.27003) (xy 137.654018 -274.228434)
			(xy 137.634727 -274.183158) (xy 137.62295 -274.135374) (xy 137.61899 -274.08632) (xy 137.290048 -274.08632)
			(xy 137.289553 -274.110927) (xy 137.281658 -274.159504) (xy 137.266074 -274.206185) (xy 137.243203 -274.249762)
			(xy 137.213638 -274.289106) (xy 137.178145 -274.323198) (xy 137.137642 -274.351154) (xy 137.09318 -274.372252)
			(xy 137.045909 -274.385944) (xy 136.997054 -274.391876) (xy 136.947879 -274.389895) (xy 136.89966 -274.380051)
			(xy 136.853644 -274.362599) (xy 136.811023 -274.337992) (xy 136.772902 -274.306867) (xy 136.740267 -274.27003)
			(xy 136.713964 -274.228434) (xy 136.694673 -274.183158) (xy 136.682896 -274.135374) (xy 136.678936 -274.08632)
			(xy 136.349994 -274.08632) (xy 136.349499 -274.110927) (xy 136.341604 -274.159504) (xy 136.32602 -274.206185)
			(xy 136.303149 -274.249762) (xy 136.273584 -274.289106) (xy 136.238091 -274.323198) (xy 136.197588 -274.351154)
			(xy 136.153126 -274.372252) (xy 136.105855 -274.385944) (xy 136.057 -274.391876) (xy 136.007825 -274.389895)
			(xy 135.959606 -274.380051) (xy 135.91359 -274.362599) (xy 135.870969 -274.337992) (xy 135.832848 -274.306867)
			(xy 135.800213 -274.27003) (xy 135.77391 -274.228434) (xy 135.754619 -274.183158) (xy 135.742842 -274.135374)
			(xy 135.738882 -274.08632) (xy 135.40994 -274.08632) (xy 135.409445 -274.110927) (xy 135.40155 -274.159504)
			(xy 135.385966 -274.206185) (xy 135.363095 -274.249762) (xy 135.33353 -274.289106) (xy 135.298037 -274.323198)
			(xy 135.257534 -274.351154) (xy 135.213072 -274.372252) (xy 135.165801 -274.385944) (xy 135.116946 -274.391876)
			(xy 135.067771 -274.389895) (xy 135.019552 -274.380051) (xy 134.973536 -274.362599) (xy 134.930915 -274.337992)
			(xy 134.892794 -274.306867) (xy 134.860159 -274.27003) (xy 134.833856 -274.228434) (xy 134.814565 -274.183158)
			(xy 134.802788 -274.135374) (xy 134.798828 -274.08632) (xy 134.47014 -274.08632) (xy 134.469645 -274.110927)
			(xy 134.46175 -274.159504) (xy 134.446166 -274.206185) (xy 134.423295 -274.249762) (xy 134.39373 -274.289106)
			(xy 134.358237 -274.323198) (xy 134.317734 -274.351154) (xy 134.273272 -274.372252) (xy 134.226001 -274.385944)
			(xy 134.177146 -274.391876) (xy 134.127971 -274.389895) (xy 134.079752 -274.380051) (xy 134.033736 -274.362599)
			(xy 133.991115 -274.337992) (xy 133.952994 -274.306867) (xy 133.920359 -274.27003) (xy 133.894056 -274.228434)
			(xy 133.874765 -274.183158) (xy 133.862988 -274.135374) (xy 133.859028 -274.08632) (xy 133.5405 -274.08632)
			(xy 133.539988 -274.111766) (xy 133.531824 -274.162) (xy 133.515708 -274.210274) (xy 133.492057 -274.255337)
			(xy 133.461484 -274.296023) (xy 133.42478 -274.331278) (xy 133.382896 -274.360188) (xy 133.336917 -274.382005)
			(xy 133.288033 -274.396165) (xy 133.237512 -274.402299) (xy 133.18666 -274.40025) (xy 133.136796 -274.39007)
			(xy 133.08921 -274.372023) (xy 133.045136 -274.346577) (xy 133.005714 -274.31439) (xy 132.971966 -274.276296)
			(xy 132.944765 -274.233282) (xy 132.924817 -274.186462) (xy 132.912638 -274.137048) (xy 132.908543 -274.08632)
			(xy 132.590032 -274.08632) (xy 132.589537 -274.110927) (xy 132.581642 -274.159504) (xy 132.566058 -274.206185)
			(xy 132.543187 -274.249762) (xy 132.513622 -274.289106) (xy 132.478129 -274.323198) (xy 132.437626 -274.351154)
			(xy 132.393164 -274.372252) (xy 132.345893 -274.385944) (xy 132.297038 -274.391876) (xy 132.247863 -274.389895)
			(xy 132.199644 -274.380051) (xy 132.153628 -274.362599) (xy 132.111007 -274.337992) (xy 132.072886 -274.306867)
			(xy 132.040251 -274.27003) (xy 132.013948 -274.228434) (xy 131.994657 -274.183158) (xy 131.98288 -274.135374)
			(xy 131.97892 -274.08632) (xy 131.660392 -274.08632) (xy 131.65988 -274.111766) (xy 131.651716 -274.162)
			(xy 131.6356 -274.210274) (xy 131.611949 -274.255337) (xy 131.581376 -274.296023) (xy 131.544672 -274.331278)
			(xy 131.502788 -274.360188) (xy 131.456809 -274.382005) (xy 131.407925 -274.396165) (xy 131.357404 -274.402299)
			(xy 131.306552 -274.40025) (xy 131.256688 -274.39007) (xy 131.209102 -274.372023) (xy 131.165028 -274.346577)
			(xy 131.125606 -274.31439) (xy 131.091858 -274.276296) (xy 131.064657 -274.233282) (xy 131.044709 -274.186462)
			(xy 131.03253 -274.137048) (xy 131.028435 -274.08632) (xy 130.710178 -274.08632) (xy 130.709683 -274.110927)
			(xy 130.701788 -274.159504) (xy 130.686204 -274.206185) (xy 130.663333 -274.249762) (xy 130.633768 -274.289106)
			(xy 130.598275 -274.323198) (xy 130.557772 -274.351154) (xy 130.51331 -274.372252) (xy 130.466039 -274.385944)
			(xy 130.417184 -274.391876) (xy 130.368009 -274.389895) (xy 130.31979 -274.380051) (xy 130.273774 -274.362599)
			(xy 130.231153 -274.337992) (xy 130.193032 -274.306867) (xy 130.160397 -274.27003) (xy 130.134094 -274.228434)
			(xy 130.114803 -274.183158) (xy 130.103026 -274.135374) (xy 130.099066 -274.08632) (xy 129.780538 -274.08632)
			(xy 129.780026 -274.111766) (xy 129.771862 -274.162) (xy 129.755746 -274.210274) (xy 129.732095 -274.255337)
			(xy 129.701522 -274.296023) (xy 129.664818 -274.331278) (xy 129.622934 -274.360188) (xy 129.576955 -274.382005)
			(xy 129.528071 -274.396165) (xy 129.47755 -274.402299) (xy 129.426698 -274.40025) (xy 129.376834 -274.39007)
			(xy 129.329248 -274.372023) (xy 129.285174 -274.346577) (xy 129.245752 -274.31439) (xy 129.212004 -274.276296)
			(xy 129.184803 -274.233282) (xy 129.164855 -274.186462) (xy 129.152676 -274.137048) (xy 129.148581 -274.08632)
			(xy 128.840484 -274.08632) (xy 128.839972 -274.111766) (xy 128.831808 -274.162) (xy 128.815692 -274.210274)
			(xy 128.792041 -274.255337) (xy 128.761468 -274.296023) (xy 128.724764 -274.331278) (xy 128.68288 -274.360188)
			(xy 128.636901 -274.382005) (xy 128.588017 -274.396165) (xy 128.537496 -274.402299) (xy 128.486644 -274.40025)
			(xy 128.43678 -274.39007) (xy 128.389194 -274.372023) (xy 128.34512 -274.346577) (xy 128.305698 -274.31439)
			(xy 128.27195 -274.276296) (xy 128.244749 -274.233282) (xy 128.224801 -274.186462) (xy 128.212622 -274.137048)
			(xy 128.208527 -274.08632) (xy 127.890016 -274.08632) (xy 127.889521 -274.110927) (xy 127.881626 -274.159504)
			(xy 127.866042 -274.206185) (xy 127.843171 -274.249762) (xy 127.813606 -274.289106) (xy 127.778113 -274.323198)
			(xy 127.73761 -274.351154) (xy 127.693148 -274.372252) (xy 127.645877 -274.385944) (xy 127.597022 -274.391876)
			(xy 127.547847 -274.389895) (xy 127.499628 -274.380051) (xy 127.453612 -274.362599) (xy 127.410991 -274.337992)
			(xy 127.37287 -274.306867) (xy 127.340235 -274.27003) (xy 127.313932 -274.228434) (xy 127.294641 -274.183158)
			(xy 127.282864 -274.135374) (xy 127.278904 -274.08632) (xy 126.949962 -274.08632) (xy 126.949962 -274.087082)
			(xy 126.949835 -274.099459) (xy 126.947804 -274.124128) (xy 126.945898 -274.136358) (xy 126.941436 -274.160334)
			(xy 126.925905 -274.206562) (xy 126.903222 -274.249732) (xy 126.873962 -274.288746) (xy 126.838872 -274.32261)
			(xy 126.798843 -274.350464) (xy 126.754894 -274.371599) (xy 126.708143 -274.385477) (xy 126.684024 -274.389088)
			(xy 126.677928 -274.38985) (xy 126.665228 -274.39493) (xy 126.655842 -274.39906) (xy 126.641153 -274.413342)
			(xy 126.63678 -274.422616) (xy 126.604014 -274.50034) (xy 126.601569 -274.506641) (xy 126.599768 -274.520032)
			(xy 126.600458 -274.526756) (xy 126.60249 -274.541996) (xy 126.62027 -274.563332) (xy 126.642261 -274.593827)
			(xy 126.678712 -274.659584) (xy 126.692914 -274.694396) (xy 126.696568 -274.702748) (xy 126.708702 -274.716337)
			(xy 126.724827 -274.724814) (xy 126.733808 -274.7264) (xy 126.776734 -274.731988) (xy 126.83363 -274.739608)
			(xy 126.859284 -274.728686) (xy 126.867666 -274.717256) (xy 126.882113 -274.698059) (xy 126.916032 -274.664034)
			(xy 126.954866 -274.635746) (xy 126.997653 -274.613895) (xy 127.043336 -274.599021) (xy 127.090786 -274.591491)
			(xy 127.114808 -274.591018) (xy 127.1388 -274.591465) (xy 127.186193 -274.598973) (xy 127.231828 -274.613802)
			(xy 127.274581 -274.635588) (xy 127.3134 -274.663795) (xy 127.347327 -274.697726) (xy 127.375529 -274.736548)
			(xy 127.397311 -274.779304) (xy 127.412135 -274.82494) (xy 127.419638 -274.872334) (xy 127.420116 -274.896326)
			(xy 127.738627 -274.896326) (xy 127.742722 -274.845598) (xy 127.754901 -274.796184) (xy 127.774849 -274.749364)
			(xy 127.80205 -274.70635) (xy 127.835798 -274.668256) (xy 127.87522 -274.636069) (xy 127.919294 -274.610623)
			(xy 127.96688 -274.592576) (xy 128.016744 -274.582396) (xy 128.067596 -274.580347) (xy 128.118117 -274.586481)
			(xy 128.167001 -274.600641) (xy 128.21298 -274.622458) (xy 128.254864 -274.651368) (xy 128.291568 -274.686623)
			(xy 128.322141 -274.727309) (xy 128.345792 -274.772372) (xy 128.361908 -274.820646) (xy 128.370072 -274.87088)
			(xy 128.370584 -274.896326) (xy 128.688858 -274.896326) (xy 128.692818 -274.847272) (xy 128.704595 -274.799488)
			(xy 128.723886 -274.754212) (xy 128.750189 -274.712616) (xy 128.782824 -274.675779) (xy 128.820945 -274.644654)
			(xy 128.863566 -274.620047) (xy 128.909582 -274.602595) (xy 128.957801 -274.592751) (xy 129.006976 -274.59077)
			(xy 129.055831 -274.596702) (xy 129.103102 -274.610394) (xy 129.147564 -274.631492) (xy 129.188067 -274.659448)
			(xy 129.22356 -274.69354) (xy 129.253125 -274.732884) (xy 129.275996 -274.776461) (xy 129.29158 -274.823142)
			(xy 129.299475 -274.871719) (xy 129.29997 -274.896326) (xy 129.618481 -274.896326) (xy 129.622576 -274.845598)
			(xy 129.634755 -274.796184) (xy 129.654703 -274.749364) (xy 129.681904 -274.70635) (xy 129.715652 -274.668256)
			(xy 129.755074 -274.636069) (xy 129.799148 -274.610623) (xy 129.846734 -274.592576) (xy 129.896598 -274.582396)
			(xy 129.94745 -274.580347) (xy 129.997971 -274.586481) (xy 130.046855 -274.600641) (xy 130.092834 -274.622458)
			(xy 130.134718 -274.651368) (xy 130.171422 -274.686623) (xy 130.201995 -274.727309) (xy 130.225646 -274.772372)
			(xy 130.241762 -274.820646) (xy 130.249926 -274.87088) (xy 130.250438 -274.896326) (xy 130.568966 -274.896326)
			(xy 130.572926 -274.847272) (xy 130.584703 -274.799488) (xy 130.603994 -274.754212) (xy 130.630297 -274.712616)
			(xy 130.662932 -274.675779) (xy 130.701053 -274.644654) (xy 130.743674 -274.620047) (xy 130.78969 -274.602595)
			(xy 130.837909 -274.592751) (xy 130.887084 -274.59077) (xy 130.935939 -274.596702) (xy 130.98321 -274.610394)
			(xy 131.027672 -274.631492) (xy 131.068175 -274.659448) (xy 131.103668 -274.69354) (xy 131.133233 -274.732884)
			(xy 131.156104 -274.776461) (xy 131.171688 -274.823142) (xy 131.179583 -274.871719) (xy 131.180078 -274.896326)
			(xy 131.498589 -274.896326) (xy 131.502684 -274.845598) (xy 131.514863 -274.796184) (xy 131.534811 -274.749364)
			(xy 131.562012 -274.70635) (xy 131.59576 -274.668256) (xy 131.635182 -274.636069) (xy 131.679256 -274.610623)
			(xy 131.726842 -274.592576) (xy 131.776706 -274.582396) (xy 131.827558 -274.580347) (xy 131.878079 -274.586481)
			(xy 131.926963 -274.600641) (xy 131.972942 -274.622458) (xy 132.014826 -274.651368) (xy 132.05153 -274.686623)
			(xy 132.082103 -274.727309) (xy 132.105754 -274.772372) (xy 132.12187 -274.820646) (xy 132.130034 -274.87088)
			(xy 132.130546 -274.896326) (xy 132.438643 -274.896326) (xy 132.442738 -274.845598) (xy 132.454917 -274.796184)
			(xy 132.474865 -274.749364) (xy 132.502066 -274.70635) (xy 132.535814 -274.668256) (xy 132.575236 -274.636069)
			(xy 132.61931 -274.610623) (xy 132.666896 -274.592576) (xy 132.71676 -274.582396) (xy 132.767612 -274.580347)
			(xy 132.818133 -274.586481) (xy 132.867017 -274.600641) (xy 132.912996 -274.622458) (xy 132.95488 -274.651368)
			(xy 132.991584 -274.686623) (xy 133.022157 -274.727309) (xy 133.045808 -274.772372) (xy 133.061924 -274.820646)
			(xy 133.070088 -274.87088) (xy 133.0706 -274.896326) (xy 133.388874 -274.896326) (xy 133.392834 -274.847272)
			(xy 133.404611 -274.799488) (xy 133.423902 -274.754212) (xy 133.450205 -274.712616) (xy 133.48284 -274.675779)
			(xy 133.520961 -274.644654) (xy 133.563582 -274.620047) (xy 133.609598 -274.602595) (xy 133.657817 -274.592751)
			(xy 133.706992 -274.59077) (xy 133.755847 -274.596702) (xy 133.803118 -274.610394) (xy 133.84758 -274.631492)
			(xy 133.888083 -274.659448) (xy 133.923576 -274.69354) (xy 133.953141 -274.732884) (xy 133.976012 -274.776461)
			(xy 133.991596 -274.823142) (xy 133.999491 -274.871719) (xy 133.999986 -274.896326) (xy 134.328928 -274.896326)
			(xy 134.332888 -274.847272) (xy 134.344665 -274.799488) (xy 134.363956 -274.754212) (xy 134.390259 -274.712616)
			(xy 134.422894 -274.675779) (xy 134.461015 -274.644654) (xy 134.503636 -274.620047) (xy 134.549652 -274.602595)
			(xy 134.597871 -274.592751) (xy 134.647046 -274.59077) (xy 134.695901 -274.596702) (xy 134.743172 -274.610394)
			(xy 134.787634 -274.631492) (xy 134.828137 -274.659448) (xy 134.86363 -274.69354) (xy 134.893195 -274.732884)
			(xy 134.916066 -274.776461) (xy 134.93165 -274.823142) (xy 134.939545 -274.871719) (xy 134.94004 -274.896326)
			(xy 135.268982 -274.896326) (xy 135.272942 -274.847272) (xy 135.284719 -274.799488) (xy 135.30401 -274.754212)
			(xy 135.330313 -274.712616) (xy 135.362948 -274.675779) (xy 135.401069 -274.644654) (xy 135.44369 -274.620047)
			(xy 135.489706 -274.602595) (xy 135.537925 -274.592751) (xy 135.5871 -274.59077) (xy 135.635955 -274.596702)
			(xy 135.683226 -274.610394) (xy 135.727688 -274.631492) (xy 135.768191 -274.659448) (xy 135.803684 -274.69354)
			(xy 135.833249 -274.732884) (xy 135.85612 -274.776461) (xy 135.871704 -274.823142) (xy 135.879599 -274.871719)
			(xy 135.880094 -274.896326) (xy 136.209036 -274.896326) (xy 136.212996 -274.847272) (xy 136.224773 -274.799488)
			(xy 136.244064 -274.754212) (xy 136.270367 -274.712616) (xy 136.303002 -274.675779) (xy 136.341123 -274.644654)
			(xy 136.383744 -274.620047) (xy 136.42976 -274.602595) (xy 136.477979 -274.592751) (xy 136.527154 -274.59077)
			(xy 136.576009 -274.596702) (xy 136.62328 -274.610394) (xy 136.667742 -274.631492) (xy 136.708245 -274.659448)
			(xy 136.743738 -274.69354) (xy 136.773303 -274.732884) (xy 136.796174 -274.776461) (xy 136.811758 -274.823142)
			(xy 136.819653 -274.871719) (xy 136.820148 -274.896326) (xy 137.148836 -274.896326) (xy 137.152796 -274.847272)
			(xy 137.164573 -274.799488) (xy 137.183864 -274.754212) (xy 137.210167 -274.712616) (xy 137.242802 -274.675779)
			(xy 137.280923 -274.644654) (xy 137.323544 -274.620047) (xy 137.36956 -274.602595) (xy 137.417779 -274.592751)
			(xy 137.466954 -274.59077) (xy 137.515809 -274.596702) (xy 137.56308 -274.610394) (xy 137.607542 -274.631492)
			(xy 137.648045 -274.659448) (xy 137.683538 -274.69354) (xy 137.713103 -274.732884) (xy 137.735974 -274.776461)
			(xy 137.751558 -274.823142) (xy 137.759453 -274.871719) (xy 137.759948 -274.896326) (xy 138.08889 -274.896326)
			(xy 138.09285 -274.847272) (xy 138.104627 -274.799488) (xy 138.123918 -274.754212) (xy 138.150221 -274.712616)
			(xy 138.182856 -274.675779) (xy 138.220977 -274.644654) (xy 138.263598 -274.620047) (xy 138.309614 -274.602595)
			(xy 138.357833 -274.592751) (xy 138.407008 -274.59077) (xy 138.455863 -274.596702) (xy 138.503134 -274.610394)
			(xy 138.547596 -274.631492) (xy 138.588099 -274.659448) (xy 138.623592 -274.69354) (xy 138.653157 -274.732884)
			(xy 138.676028 -274.776461) (xy 138.691612 -274.823142) (xy 138.699507 -274.871719) (xy 138.700002 -274.896326)
			(xy 139.028944 -274.896326) (xy 139.032904 -274.847272) (xy 139.044681 -274.799488) (xy 139.063972 -274.754212)
			(xy 139.090275 -274.712616) (xy 139.12291 -274.675779) (xy 139.161031 -274.644654) (xy 139.203652 -274.620047)
			(xy 139.249668 -274.602595) (xy 139.297887 -274.592751) (xy 139.347062 -274.59077) (xy 139.395917 -274.596702)
			(xy 139.443188 -274.610394) (xy 139.48765 -274.631492) (xy 139.528153 -274.659448) (xy 139.563646 -274.69354)
			(xy 139.593211 -274.732884) (xy 139.616082 -274.776461) (xy 139.631666 -274.823142) (xy 139.639561 -274.871719)
			(xy 139.640056 -274.896326) (xy 139.639561 -274.920933) (xy 139.631666 -274.96951) (xy 139.616082 -275.016191)
			(xy 139.593211 -275.059768) (xy 139.563646 -275.099112) (xy 139.528153 -275.133204) (xy 139.48765 -275.16116)
			(xy 139.443188 -275.182258) (xy 139.395917 -275.19595) (xy 139.347062 -275.201882) (xy 139.297887 -275.199901)
			(xy 139.249668 -275.190057) (xy 139.203652 -275.172605) (xy 139.161031 -275.147998) (xy 139.12291 -275.116873)
			(xy 139.090275 -275.080036) (xy 139.063972 -275.03844) (xy 139.044681 -274.993164) (xy 139.032904 -274.94538)
			(xy 139.028944 -274.896326) (xy 138.700002 -274.896326) (xy 138.699507 -274.920933) (xy 138.691612 -274.96951)
			(xy 138.676028 -275.016191) (xy 138.653157 -275.059768) (xy 138.623592 -275.099112) (xy 138.588099 -275.133204)
			(xy 138.547596 -275.16116) (xy 138.503134 -275.182258) (xy 138.455863 -275.19595) (xy 138.407008 -275.201882)
			(xy 138.357833 -275.199901) (xy 138.309614 -275.190057) (xy 138.263598 -275.172605) (xy 138.220977 -275.147998)
			(xy 138.182856 -275.116873) (xy 138.150221 -275.080036) (xy 138.123918 -275.03844) (xy 138.104627 -274.993164)
			(xy 138.09285 -274.94538) (xy 138.08889 -274.896326) (xy 137.759948 -274.896326) (xy 137.759453 -274.920933)
			(xy 137.751558 -274.96951) (xy 137.735974 -275.016191) (xy 137.713103 -275.059768) (xy 137.683538 -275.099112)
			(xy 137.648045 -275.133204) (xy 137.607542 -275.16116) (xy 137.56308 -275.182258) (xy 137.515809 -275.19595)
			(xy 137.466954 -275.201882) (xy 137.417779 -275.199901) (xy 137.36956 -275.190057) (xy 137.323544 -275.172605)
			(xy 137.280923 -275.147998) (xy 137.242802 -275.116873) (xy 137.210167 -275.080036) (xy 137.183864 -275.03844)
			(xy 137.164573 -274.993164) (xy 137.152796 -274.94538) (xy 137.148836 -274.896326) (xy 136.820148 -274.896326)
			(xy 136.819653 -274.920933) (xy 136.811758 -274.96951) (xy 136.796174 -275.016191) (xy 136.773303 -275.059768)
			(xy 136.743738 -275.099112) (xy 136.708245 -275.133204) (xy 136.667742 -275.16116) (xy 136.62328 -275.182258)
			(xy 136.576009 -275.19595) (xy 136.527154 -275.201882) (xy 136.477979 -275.199901) (xy 136.42976 -275.190057)
			(xy 136.383744 -275.172605) (xy 136.341123 -275.147998) (xy 136.303002 -275.116873) (xy 136.270367 -275.080036)
			(xy 136.244064 -275.03844) (xy 136.224773 -274.993164) (xy 136.212996 -274.94538) (xy 136.209036 -274.896326)
			(xy 135.880094 -274.896326) (xy 135.879599 -274.920933) (xy 135.871704 -274.96951) (xy 135.85612 -275.016191)
			(xy 135.833249 -275.059768) (xy 135.803684 -275.099112) (xy 135.768191 -275.133204) (xy 135.727688 -275.16116)
			(xy 135.683226 -275.182258) (xy 135.635955 -275.19595) (xy 135.5871 -275.201882) (xy 135.537925 -275.199901)
			(xy 135.489706 -275.190057) (xy 135.44369 -275.172605) (xy 135.401069 -275.147998) (xy 135.362948 -275.116873)
			(xy 135.330313 -275.080036) (xy 135.30401 -275.03844) (xy 135.284719 -274.993164) (xy 135.272942 -274.94538)
			(xy 135.268982 -274.896326) (xy 134.94004 -274.896326) (xy 134.939545 -274.920933) (xy 134.93165 -274.96951)
			(xy 134.916066 -275.016191) (xy 134.893195 -275.059768) (xy 134.86363 -275.099112) (xy 134.828137 -275.133204)
			(xy 134.787634 -275.16116) (xy 134.743172 -275.182258) (xy 134.695901 -275.19595) (xy 134.647046 -275.201882)
			(xy 134.597871 -275.199901) (xy 134.549652 -275.190057) (xy 134.503636 -275.172605) (xy 134.461015 -275.147998)
			(xy 134.422894 -275.116873) (xy 134.390259 -275.080036) (xy 134.363956 -275.03844) (xy 134.344665 -274.993164)
			(xy 134.332888 -274.94538) (xy 134.328928 -274.896326) (xy 133.999986 -274.896326) (xy 133.999491 -274.920933)
			(xy 133.991596 -274.96951) (xy 133.976012 -275.016191) (xy 133.953141 -275.059768) (xy 133.923576 -275.099112)
			(xy 133.888083 -275.133204) (xy 133.84758 -275.16116) (xy 133.803118 -275.182258) (xy 133.755847 -275.19595)
			(xy 133.706992 -275.201882) (xy 133.657817 -275.199901) (xy 133.609598 -275.190057) (xy 133.563582 -275.172605)
			(xy 133.520961 -275.147998) (xy 133.48284 -275.116873) (xy 133.450205 -275.080036) (xy 133.423902 -275.03844)
			(xy 133.404611 -274.993164) (xy 133.392834 -274.94538) (xy 133.388874 -274.896326) (xy 133.0706 -274.896326)
			(xy 133.070088 -274.921772) (xy 133.061924 -274.972006) (xy 133.045808 -275.02028) (xy 133.022157 -275.065343)
			(xy 132.991584 -275.106029) (xy 132.95488 -275.141284) (xy 132.912996 -275.170194) (xy 132.867017 -275.192011)
			(xy 132.818133 -275.206171) (xy 132.767612 -275.212305) (xy 132.71676 -275.210256) (xy 132.666896 -275.200076)
			(xy 132.61931 -275.182029) (xy 132.575236 -275.156583) (xy 132.535814 -275.124396) (xy 132.502066 -275.086302)
			(xy 132.474865 -275.043288) (xy 132.454917 -274.996468) (xy 132.442738 -274.947054) (xy 132.438643 -274.896326)
			(xy 132.130546 -274.896326) (xy 132.130034 -274.921772) (xy 132.12187 -274.972006) (xy 132.105754 -275.02028)
			(xy 132.082103 -275.065343) (xy 132.05153 -275.106029) (xy 132.014826 -275.141284) (xy 131.972942 -275.170194)
			(xy 131.926963 -275.192011) (xy 131.878079 -275.206171) (xy 131.827558 -275.212305) (xy 131.776706 -275.210256)
			(xy 131.726842 -275.200076) (xy 131.679256 -275.182029) (xy 131.635182 -275.156583) (xy 131.59576 -275.124396)
			(xy 131.562012 -275.086302) (xy 131.534811 -275.043288) (xy 131.514863 -274.996468) (xy 131.502684 -274.947054)
			(xy 131.498589 -274.896326) (xy 131.180078 -274.896326) (xy 131.179583 -274.920933) (xy 131.171688 -274.96951)
			(xy 131.156104 -275.016191) (xy 131.133233 -275.059768) (xy 131.103668 -275.099112) (xy 131.068175 -275.133204)
			(xy 131.027672 -275.16116) (xy 130.98321 -275.182258) (xy 130.935939 -275.19595) (xy 130.887084 -275.201882)
			(xy 130.837909 -275.199901) (xy 130.78969 -275.190057) (xy 130.743674 -275.172605) (xy 130.701053 -275.147998)
			(xy 130.662932 -275.116873) (xy 130.630297 -275.080036) (xy 130.603994 -275.03844) (xy 130.584703 -274.993164)
			(xy 130.572926 -274.94538) (xy 130.568966 -274.896326) (xy 130.250438 -274.896326) (xy 130.249926 -274.921772)
			(xy 130.241762 -274.972006) (xy 130.225646 -275.02028) (xy 130.201995 -275.065343) (xy 130.171422 -275.106029)
			(xy 130.134718 -275.141284) (xy 130.092834 -275.170194) (xy 130.046855 -275.192011) (xy 129.997971 -275.206171)
			(xy 129.94745 -275.212305) (xy 129.896598 -275.210256) (xy 129.846734 -275.200076) (xy 129.799148 -275.182029)
			(xy 129.755074 -275.156583) (xy 129.715652 -275.124396) (xy 129.681904 -275.086302) (xy 129.654703 -275.043288)
			(xy 129.634755 -274.996468) (xy 129.622576 -274.947054) (xy 129.618481 -274.896326) (xy 129.29997 -274.896326)
			(xy 129.299475 -274.920933) (xy 129.29158 -274.96951) (xy 129.275996 -275.016191) (xy 129.253125 -275.059768)
			(xy 129.22356 -275.099112) (xy 129.188067 -275.133204) (xy 129.147564 -275.16116) (xy 129.103102 -275.182258)
			(xy 129.055831 -275.19595) (xy 129.006976 -275.201882) (xy 128.957801 -275.199901) (xy 128.909582 -275.190057)
			(xy 128.863566 -275.172605) (xy 128.820945 -275.147998) (xy 128.782824 -275.116873) (xy 128.750189 -275.080036)
			(xy 128.723886 -275.03844) (xy 128.704595 -274.993164) (xy 128.692818 -274.94538) (xy 128.688858 -274.896326)
			(xy 128.370584 -274.896326) (xy 128.370072 -274.921772) (xy 128.361908 -274.972006) (xy 128.345792 -275.02028)
			(xy 128.322141 -275.065343) (xy 128.291568 -275.106029) (xy 128.254864 -275.141284) (xy 128.21298 -275.170194)
			(xy 128.167001 -275.192011) (xy 128.118117 -275.206171) (xy 128.067596 -275.212305) (xy 128.016744 -275.210256)
			(xy 127.96688 -275.200076) (xy 127.919294 -275.182029) (xy 127.87522 -275.156583) (xy 127.835798 -275.124396)
			(xy 127.80205 -275.086302) (xy 127.774849 -275.043288) (xy 127.754901 -274.996468) (xy 127.742722 -274.947054)
			(xy 127.738627 -274.896326) (xy 127.420116 -274.896326) (xy 127.419685 -274.91979) (xy 127.412502 -274.966166)
			(xy 127.39831 -275.010898) (xy 127.377443 -275.052932) (xy 127.350392 -275.091279) (xy 127.317793 -275.125037)
			(xy 127.280414 -275.153412) (xy 127.239134 -275.175734) (xy 127.194926 -275.19148) (xy 127.171958 -275.1963)
			(xy 127.171196 -275.1963) (xy 127.162332 -275.198492) (xy 127.146879 -275.208194) (xy 127.135847 -275.222727)
			(xy 127.132842 -275.231352) (xy 127.106934 -275.314918) (xy 127.104595 -275.323867) (xy 127.105762 -275.342314)
			(xy 127.113383 -275.359152) (xy 127.119634 -275.365972) (xy 127.235458 -275.481796) (xy 127.246634 -275.490178)
			(xy 127.252223 -275.493157) (xy 127.264437 -275.496492) (xy 127.270764 -275.496782) (xy 127.339598 -275.497798)
			(xy 127.344605 -275.49775) (xy 127.354455 -275.495966) (xy 127.359156 -275.494242) (xy 127.3683 -275.490686)
			(xy 127.375412 -275.484082) (xy 127.392501 -275.468574) (xy 127.430476 -275.442356) (xy 127.471962 -275.422149)
			(xy 127.516016 -275.408412) (xy 127.561635 -275.401457) (xy 127.584708 -275.401024) (xy 127.6087 -275.401471)
			(xy 127.656092 -275.408979) (xy 127.701727 -275.423808) (xy 127.74448 -275.445595) (xy 127.783298 -275.473801)
			(xy 127.817225 -275.507733) (xy 127.845426 -275.546554) (xy 127.867207 -275.58931) (xy 127.882031 -275.634946)
			(xy 127.889532 -275.68234) (xy 127.890016 -275.706332) (xy 128.208527 -275.706332) (xy 128.212622 -275.655604)
			(xy 128.224801 -275.60619) (xy 128.244749 -275.55937) (xy 128.27195 -275.516356) (xy 128.305698 -275.478262)
			(xy 128.34512 -275.446075) (xy 128.389194 -275.420629) (xy 128.43678 -275.402582) (xy 128.486644 -275.392402)
			(xy 128.537496 -275.390353) (xy 128.588017 -275.396487) (xy 128.636901 -275.410647) (xy 128.68288 -275.432464)
			(xy 128.724764 -275.461374) (xy 128.761468 -275.496629) (xy 128.792041 -275.537315) (xy 128.815692 -275.582378)
			(xy 128.831808 -275.630652) (xy 128.839972 -275.680886) (xy 128.840484 -275.706332) (xy 129.148581 -275.706332)
			(xy 129.152676 -275.655604) (xy 129.164855 -275.60619) (xy 129.184803 -275.55937) (xy 129.212004 -275.516356)
			(xy 129.245752 -275.478262) (xy 129.285174 -275.446075) (xy 129.329248 -275.420629) (xy 129.376834 -275.402582)
			(xy 129.426698 -275.392402) (xy 129.47755 -275.390353) (xy 129.528071 -275.396487) (xy 129.576955 -275.410647)
			(xy 129.622934 -275.432464) (xy 129.664818 -275.461374) (xy 129.701522 -275.496629) (xy 129.732095 -275.537315)
			(xy 129.755746 -275.582378) (xy 129.771862 -275.630652) (xy 129.780026 -275.680886) (xy 129.780538 -275.706332)
			(xy 130.099066 -275.706332) (xy 130.103026 -275.657278) (xy 130.114803 -275.609494) (xy 130.134094 -275.564218)
			(xy 130.160397 -275.522622) (xy 130.193032 -275.485785) (xy 130.231153 -275.45466) (xy 130.273774 -275.430053)
			(xy 130.31979 -275.412601) (xy 130.368009 -275.402757) (xy 130.417184 -275.400776) (xy 130.466039 -275.406708)
			(xy 130.51331 -275.4204) (xy 130.557772 -275.441498) (xy 130.598275 -275.469454) (xy 130.633768 -275.503546)
			(xy 130.663333 -275.54289) (xy 130.686204 -275.586467) (xy 130.701788 -275.633148) (xy 130.709683 -275.681725)
			(xy 130.710178 -275.706332) (xy 131.028435 -275.706332) (xy 131.03253 -275.655604) (xy 131.044709 -275.60619)
			(xy 131.064657 -275.55937) (xy 131.091858 -275.516356) (xy 131.125606 -275.478262) (xy 131.165028 -275.446075)
			(xy 131.209102 -275.420629) (xy 131.256688 -275.402582) (xy 131.306552 -275.392402) (xy 131.357404 -275.390353)
			(xy 131.407925 -275.396487) (xy 131.456809 -275.410647) (xy 131.502788 -275.432464) (xy 131.544672 -275.461374)
			(xy 131.581376 -275.496629) (xy 131.611949 -275.537315) (xy 131.6356 -275.582378) (xy 131.651716 -275.630652)
			(xy 131.65988 -275.680886) (xy 131.660392 -275.706332) (xy 131.97892 -275.706332) (xy 131.98288 -275.657278)
			(xy 131.994657 -275.609494) (xy 132.013948 -275.564218) (xy 132.040251 -275.522622) (xy 132.072886 -275.485785)
			(xy 132.111007 -275.45466) (xy 132.153628 -275.430053) (xy 132.199644 -275.412601) (xy 132.247863 -275.402757)
			(xy 132.297038 -275.400776) (xy 132.345893 -275.406708) (xy 132.393164 -275.4204) (xy 132.437626 -275.441498)
			(xy 132.478129 -275.469454) (xy 132.513622 -275.503546) (xy 132.543187 -275.54289) (xy 132.566058 -275.586467)
			(xy 132.581642 -275.633148) (xy 132.589537 -275.681725) (xy 132.590032 -275.706332) (xy 132.908543 -275.706332)
			(xy 132.912638 -275.655604) (xy 132.924817 -275.60619) (xy 132.944765 -275.55937) (xy 132.971966 -275.516356)
			(xy 133.005714 -275.478262) (xy 133.045136 -275.446075) (xy 133.08921 -275.420629) (xy 133.136796 -275.402582)
			(xy 133.18666 -275.392402) (xy 133.237512 -275.390353) (xy 133.288033 -275.396487) (xy 133.336917 -275.410647)
			(xy 133.382896 -275.432464) (xy 133.42478 -275.461374) (xy 133.461484 -275.496629) (xy 133.492057 -275.537315)
			(xy 133.515708 -275.582378) (xy 133.531824 -275.630652) (xy 133.539988 -275.680886) (xy 133.5405 -275.706332)
			(xy 133.859028 -275.706332) (xy 133.862988 -275.657278) (xy 133.874765 -275.609494) (xy 133.894056 -275.564218)
			(xy 133.920359 -275.522622) (xy 133.952994 -275.485785) (xy 133.991115 -275.45466) (xy 134.033736 -275.430053)
			(xy 134.079752 -275.412601) (xy 134.127971 -275.402757) (xy 134.177146 -275.400776) (xy 134.226001 -275.406708)
			(xy 134.273272 -275.4204) (xy 134.317734 -275.441498) (xy 134.358237 -275.469454) (xy 134.39373 -275.503546)
			(xy 134.423295 -275.54289) (xy 134.446166 -275.586467) (xy 134.46175 -275.633148) (xy 134.469645 -275.681725)
			(xy 134.47014 -275.706332) (xy 134.798828 -275.706332) (xy 134.802788 -275.657278) (xy 134.814565 -275.609494)
			(xy 134.833856 -275.564218) (xy 134.860159 -275.522622) (xy 134.892794 -275.485785) (xy 134.930915 -275.45466)
			(xy 134.973536 -275.430053) (xy 135.019552 -275.412601) (xy 135.067771 -275.402757) (xy 135.116946 -275.400776)
			(xy 135.165801 -275.406708) (xy 135.213072 -275.4204) (xy 135.257534 -275.441498) (xy 135.298037 -275.469454)
			(xy 135.33353 -275.503546) (xy 135.363095 -275.54289) (xy 135.385966 -275.586467) (xy 135.40155 -275.633148)
			(xy 135.409445 -275.681725) (xy 135.40994 -275.706332) (xy 135.738882 -275.706332) (xy 135.742842 -275.657278)
			(xy 135.754619 -275.609494) (xy 135.77391 -275.564218) (xy 135.800213 -275.522622) (xy 135.832848 -275.485785)
			(xy 135.870969 -275.45466) (xy 135.91359 -275.430053) (xy 135.959606 -275.412601) (xy 136.007825 -275.402757)
			(xy 136.057 -275.400776) (xy 136.105855 -275.406708) (xy 136.153126 -275.4204) (xy 136.197588 -275.441498)
			(xy 136.238091 -275.469454) (xy 136.273584 -275.503546) (xy 136.303149 -275.54289) (xy 136.32602 -275.586467)
			(xy 136.341604 -275.633148) (xy 136.349499 -275.681725) (xy 136.349994 -275.706332) (xy 136.678936 -275.706332)
			(xy 136.682896 -275.657278) (xy 136.694673 -275.609494) (xy 136.713964 -275.564218) (xy 136.740267 -275.522622)
			(xy 136.772902 -275.485785) (xy 136.811023 -275.45466) (xy 136.853644 -275.430053) (xy 136.89966 -275.412601)
			(xy 136.947879 -275.402757) (xy 136.997054 -275.400776) (xy 137.045909 -275.406708) (xy 137.09318 -275.4204)
			(xy 137.137642 -275.441498) (xy 137.178145 -275.469454) (xy 137.213638 -275.503546) (xy 137.243203 -275.54289)
			(xy 137.266074 -275.586467) (xy 137.281658 -275.633148) (xy 137.289553 -275.681725) (xy 137.290048 -275.706332)
			(xy 137.61899 -275.706332) (xy 137.62295 -275.657278) (xy 137.634727 -275.609494) (xy 137.654018 -275.564218)
			(xy 137.680321 -275.522622) (xy 137.712956 -275.485785) (xy 137.751077 -275.45466) (xy 137.793698 -275.430053)
			(xy 137.839714 -275.412601) (xy 137.887933 -275.402757) (xy 137.937108 -275.400776) (xy 137.985963 -275.406708)
			(xy 138.033234 -275.4204) (xy 138.077696 -275.441498) (xy 138.118199 -275.469454) (xy 138.153692 -275.503546)
			(xy 138.183257 -275.54289) (xy 138.206128 -275.586467) (xy 138.221712 -275.633148) (xy 138.229607 -275.681725)
			(xy 138.230102 -275.706332) (xy 138.559044 -275.706332) (xy 138.563004 -275.657278) (xy 138.574781 -275.609494)
			(xy 138.594072 -275.564218) (xy 138.620375 -275.522622) (xy 138.65301 -275.485785) (xy 138.691131 -275.45466)
			(xy 138.733752 -275.430053) (xy 138.779768 -275.412601) (xy 138.827987 -275.402757) (xy 138.877162 -275.400776)
			(xy 138.926017 -275.406708) (xy 138.973288 -275.4204) (xy 139.01775 -275.441498) (xy 139.058253 -275.469454)
			(xy 139.093746 -275.503546) (xy 139.123311 -275.54289) (xy 139.146182 -275.586467) (xy 139.161766 -275.633148)
			(xy 139.169661 -275.681725) (xy 139.170156 -275.706332) (xy 139.498844 -275.706332) (xy 139.502804 -275.657278)
			(xy 139.514581 -275.609494) (xy 139.533872 -275.564218) (xy 139.560175 -275.522622) (xy 139.59281 -275.485785)
			(xy 139.630931 -275.45466) (xy 139.673552 -275.430053) (xy 139.719568 -275.412601) (xy 139.767787 -275.402757)
			(xy 139.816962 -275.400776) (xy 139.865817 -275.406708) (xy 139.913088 -275.4204) (xy 139.95755 -275.441498)
			(xy 139.998053 -275.469454) (xy 140.033546 -275.503546) (xy 140.063111 -275.54289) (xy 140.085982 -275.586467)
			(xy 140.101566 -275.633148) (xy 140.109461 -275.681725) (xy 140.109956 -275.706332) (xy 140.109461 -275.730939)
			(xy 140.101566 -275.779516) (xy 140.085982 -275.826197) (xy 140.063111 -275.869774) (xy 140.033546 -275.909118)
			(xy 139.998053 -275.94321) (xy 139.95755 -275.971166) (xy 139.913088 -275.992264) (xy 139.865817 -276.005956)
			(xy 139.816962 -276.011888) (xy 139.767787 -276.009907) (xy 139.719568 -276.000063) (xy 139.673552 -275.982611)
			(xy 139.630931 -275.958004) (xy 139.59281 -275.926879) (xy 139.560175 -275.890042) (xy 139.533872 -275.848446)
			(xy 139.514581 -275.80317) (xy 139.502804 -275.755386) (xy 139.498844 -275.706332) (xy 139.170156 -275.706332)
			(xy 139.169661 -275.730939) (xy 139.161766 -275.779516) (xy 139.146182 -275.826197) (xy 139.123311 -275.869774)
			(xy 139.093746 -275.909118) (xy 139.058253 -275.94321) (xy 139.01775 -275.971166) (xy 138.973288 -275.992264)
			(xy 138.926017 -276.005956) (xy 138.877162 -276.011888) (xy 138.827987 -276.009907) (xy 138.779768 -276.000063)
			(xy 138.733752 -275.982611) (xy 138.691131 -275.958004) (xy 138.65301 -275.926879) (xy 138.620375 -275.890042)
			(xy 138.594072 -275.848446) (xy 138.574781 -275.80317) (xy 138.563004 -275.755386) (xy 138.559044 -275.706332)
			(xy 138.230102 -275.706332) (xy 138.229607 -275.730939) (xy 138.221712 -275.779516) (xy 138.206128 -275.826197)
			(xy 138.183257 -275.869774) (xy 138.153692 -275.909118) (xy 138.118199 -275.94321) (xy 138.077696 -275.971166)
			(xy 138.033234 -275.992264) (xy 137.985963 -276.005956) (xy 137.937108 -276.011888) (xy 137.887933 -276.009907)
			(xy 137.839714 -276.000063) (xy 137.793698 -275.982611) (xy 137.751077 -275.958004) (xy 137.712956 -275.926879)
			(xy 137.680321 -275.890042) (xy 137.654018 -275.848446) (xy 137.634727 -275.80317) (xy 137.62295 -275.755386)
			(xy 137.61899 -275.706332) (xy 137.290048 -275.706332) (xy 137.289553 -275.730939) (xy 137.281658 -275.779516)
			(xy 137.266074 -275.826197) (xy 137.243203 -275.869774) (xy 137.213638 -275.909118) (xy 137.178145 -275.94321)
			(xy 137.137642 -275.971166) (xy 137.09318 -275.992264) (xy 137.045909 -276.005956) (xy 136.997054 -276.011888)
			(xy 136.947879 -276.009907) (xy 136.89966 -276.000063) (xy 136.853644 -275.982611) (xy 136.811023 -275.958004)
			(xy 136.772902 -275.926879) (xy 136.740267 -275.890042) (xy 136.713964 -275.848446) (xy 136.694673 -275.80317)
			(xy 136.682896 -275.755386) (xy 136.678936 -275.706332) (xy 136.349994 -275.706332) (xy 136.349499 -275.730939)
			(xy 136.341604 -275.779516) (xy 136.32602 -275.826197) (xy 136.303149 -275.869774) (xy 136.273584 -275.909118)
			(xy 136.238091 -275.94321) (xy 136.197588 -275.971166) (xy 136.153126 -275.992264) (xy 136.105855 -276.005956)
			(xy 136.057 -276.011888) (xy 136.007825 -276.009907) (xy 135.959606 -276.000063) (xy 135.91359 -275.982611)
			(xy 135.870969 -275.958004) (xy 135.832848 -275.926879) (xy 135.800213 -275.890042) (xy 135.77391 -275.848446)
			(xy 135.754619 -275.80317) (xy 135.742842 -275.755386) (xy 135.738882 -275.706332) (xy 135.40994 -275.706332)
			(xy 135.409445 -275.730939) (xy 135.40155 -275.779516) (xy 135.385966 -275.826197) (xy 135.363095 -275.869774)
			(xy 135.33353 -275.909118) (xy 135.298037 -275.94321) (xy 135.257534 -275.971166) (xy 135.213072 -275.992264)
			(xy 135.165801 -276.005956) (xy 135.116946 -276.011888) (xy 135.067771 -276.009907) (xy 135.019552 -276.000063)
			(xy 134.973536 -275.982611) (xy 134.930915 -275.958004) (xy 134.892794 -275.926879) (xy 134.860159 -275.890042)
			(xy 134.833856 -275.848446) (xy 134.814565 -275.80317) (xy 134.802788 -275.755386) (xy 134.798828 -275.706332)
			(xy 134.47014 -275.706332) (xy 134.469645 -275.730939) (xy 134.46175 -275.779516) (xy 134.446166 -275.826197)
			(xy 134.423295 -275.869774) (xy 134.39373 -275.909118) (xy 134.358237 -275.94321) (xy 134.317734 -275.971166)
			(xy 134.273272 -275.992264) (xy 134.226001 -276.005956) (xy 134.177146 -276.011888) (xy 134.127971 -276.009907)
			(xy 134.079752 -276.000063) (xy 134.033736 -275.982611) (xy 133.991115 -275.958004) (xy 133.952994 -275.926879)
			(xy 133.920359 -275.890042) (xy 133.894056 -275.848446) (xy 133.874765 -275.80317) (xy 133.862988 -275.755386)
			(xy 133.859028 -275.706332) (xy 133.5405 -275.706332) (xy 133.539988 -275.731778) (xy 133.531824 -275.782012)
			(xy 133.515708 -275.830286) (xy 133.492057 -275.875349) (xy 133.461484 -275.916035) (xy 133.42478 -275.95129)
			(xy 133.382896 -275.9802) (xy 133.336917 -276.002017) (xy 133.288033 -276.016177) (xy 133.237512 -276.022311)
			(xy 133.18666 -276.020262) (xy 133.136796 -276.010082) (xy 133.08921 -275.992035) (xy 133.045136 -275.966589)
			(xy 133.005714 -275.934402) (xy 132.971966 -275.896308) (xy 132.944765 -275.853294) (xy 132.924817 -275.806474)
			(xy 132.912638 -275.75706) (xy 132.908543 -275.706332) (xy 132.590032 -275.706332) (xy 132.589537 -275.730939)
			(xy 132.581642 -275.779516) (xy 132.566058 -275.826197) (xy 132.543187 -275.869774) (xy 132.513622 -275.909118)
			(xy 132.478129 -275.94321) (xy 132.437626 -275.971166) (xy 132.393164 -275.992264) (xy 132.345893 -276.005956)
			(xy 132.297038 -276.011888) (xy 132.247863 -276.009907) (xy 132.199644 -276.000063) (xy 132.153628 -275.982611)
			(xy 132.111007 -275.958004) (xy 132.072886 -275.926879) (xy 132.040251 -275.890042) (xy 132.013948 -275.848446)
			(xy 131.994657 -275.80317) (xy 131.98288 -275.755386) (xy 131.97892 -275.706332) (xy 131.660392 -275.706332)
			(xy 131.65988 -275.731778) (xy 131.651716 -275.782012) (xy 131.6356 -275.830286) (xy 131.611949 -275.875349)
			(xy 131.581376 -275.916035) (xy 131.544672 -275.95129) (xy 131.502788 -275.9802) (xy 131.456809 -276.002017)
			(xy 131.407925 -276.016177) (xy 131.357404 -276.022311) (xy 131.306552 -276.020262) (xy 131.256688 -276.010082)
			(xy 131.209102 -275.992035) (xy 131.165028 -275.966589) (xy 131.125606 -275.934402) (xy 131.091858 -275.896308)
			(xy 131.064657 -275.853294) (xy 131.044709 -275.806474) (xy 131.03253 -275.75706) (xy 131.028435 -275.706332)
			(xy 130.710178 -275.706332) (xy 130.709683 -275.730939) (xy 130.701788 -275.779516) (xy 130.686204 -275.826197)
			(xy 130.663333 -275.869774) (xy 130.633768 -275.909118) (xy 130.598275 -275.94321) (xy 130.557772 -275.971166)
			(xy 130.51331 -275.992264) (xy 130.466039 -276.005956) (xy 130.417184 -276.011888) (xy 130.368009 -276.009907)
			(xy 130.31979 -276.000063) (xy 130.273774 -275.982611) (xy 130.231153 -275.958004) (xy 130.193032 -275.926879)
			(xy 130.160397 -275.890042) (xy 130.134094 -275.848446) (xy 130.114803 -275.80317) (xy 130.103026 -275.755386)
			(xy 130.099066 -275.706332) (xy 129.780538 -275.706332) (xy 129.780026 -275.731778) (xy 129.771862 -275.782012)
			(xy 129.755746 -275.830286) (xy 129.732095 -275.875349) (xy 129.701522 -275.916035) (xy 129.664818 -275.95129)
			(xy 129.622934 -275.9802) (xy 129.576955 -276.002017) (xy 129.528071 -276.016177) (xy 129.47755 -276.022311)
			(xy 129.426698 -276.020262) (xy 129.376834 -276.010082) (xy 129.329248 -275.992035) (xy 129.285174 -275.966589)
			(xy 129.245752 -275.934402) (xy 129.212004 -275.896308) (xy 129.184803 -275.853294) (xy 129.164855 -275.806474)
			(xy 129.152676 -275.75706) (xy 129.148581 -275.706332) (xy 128.840484 -275.706332) (xy 128.839972 -275.731778)
			(xy 128.831808 -275.782012) (xy 128.815692 -275.830286) (xy 128.792041 -275.875349) (xy 128.761468 -275.916035)
			(xy 128.724764 -275.95129) (xy 128.68288 -275.9802) (xy 128.636901 -276.002017) (xy 128.588017 -276.016177)
			(xy 128.537496 -276.022311) (xy 128.486644 -276.020262) (xy 128.43678 -276.010082) (xy 128.389194 -275.992035)
			(xy 128.34512 -275.966589) (xy 128.305698 -275.934402) (xy 128.27195 -275.896308) (xy 128.244749 -275.853294)
			(xy 128.224801 -275.806474) (xy 128.212622 -275.75706) (xy 128.208527 -275.706332) (xy 127.890016 -275.706332)
			(xy 127.890016 -275.707094) (xy 127.889888 -275.719471) (xy 127.887856 -275.74414) (xy 127.885952 -275.75637)
			(xy 127.881425 -275.780697) (xy 127.865555 -275.827562) (xy 127.842339 -275.871257) (xy 127.812384 -275.910639)
			(xy 127.776474 -275.944679) (xy 127.735548 -275.972486) (xy 127.690674 -275.993334) (xy 127.643028 -276.006677)
			(xy 127.61849 -276.009862) (xy 127.610362 -276.010878) (xy 127.58801 -276.021038) (xy 127.583718 -276.023123)
			(xy 127.57592 -276.028617) (xy 127.572516 -276.03196) (xy 127.558038 -276.046946) (xy 127.551558 -276.054298)
			(xy 127.544246 -276.072461) (xy 127.543814 -276.082252) (xy 127.543814 -276.516338) (xy 127.738627 -276.516338)
			(xy 127.742722 -276.46561) (xy 127.754901 -276.416196) (xy 127.774849 -276.369376) (xy 127.80205 -276.326362)
			(xy 127.835798 -276.288268) (xy 127.87522 -276.256081) (xy 127.919294 -276.230635) (xy 127.96688 -276.212588)
			(xy 128.016744 -276.202408) (xy 128.067596 -276.200359) (xy 128.118117 -276.206493) (xy 128.167001 -276.220653)
			(xy 128.21298 -276.24247) (xy 128.254864 -276.27138) (xy 128.291568 -276.306635) (xy 128.322141 -276.347321)
			(xy 128.345792 -276.392384) (xy 128.361908 -276.440658) (xy 128.370072 -276.490892) (xy 128.370584 -276.516338)
			(xy 128.688858 -276.516338) (xy 128.692818 -276.467284) (xy 128.704595 -276.4195) (xy 128.723886 -276.374224)
			(xy 128.750189 -276.332628) (xy 128.782824 -276.295791) (xy 128.820945 -276.264666) (xy 128.863566 -276.240059)
			(xy 128.909582 -276.222607) (xy 128.957801 -276.212763) (xy 129.006976 -276.210782) (xy 129.055831 -276.216714)
			(xy 129.103102 -276.230406) (xy 129.147564 -276.251504) (xy 129.188067 -276.27946) (xy 129.22356 -276.313552)
			(xy 129.253125 -276.352896) (xy 129.275996 -276.396473) (xy 129.29158 -276.443154) (xy 129.299475 -276.491731)
			(xy 129.29997 -276.516338) (xy 129.618481 -276.516338) (xy 129.622576 -276.46561) (xy 129.634755 -276.416196)
			(xy 129.654703 -276.369376) (xy 129.681904 -276.326362) (xy 129.715652 -276.288268) (xy 129.755074 -276.256081)
			(xy 129.799148 -276.230635) (xy 129.846734 -276.212588) (xy 129.896598 -276.202408) (xy 129.94745 -276.200359)
			(xy 129.997971 -276.206493) (xy 130.046855 -276.220653) (xy 130.092834 -276.24247) (xy 130.134718 -276.27138)
			(xy 130.171422 -276.306635) (xy 130.201995 -276.347321) (xy 130.225646 -276.392384) (xy 130.241762 -276.440658)
			(xy 130.249926 -276.490892) (xy 130.250438 -276.516338) (xy 130.568966 -276.516338) (xy 130.572926 -276.467284)
			(xy 130.584703 -276.4195) (xy 130.603994 -276.374224) (xy 130.630297 -276.332628) (xy 130.662932 -276.295791)
			(xy 130.701053 -276.264666) (xy 130.743674 -276.240059) (xy 130.78969 -276.222607) (xy 130.837909 -276.212763)
			(xy 130.887084 -276.210782) (xy 130.935939 -276.216714) (xy 130.98321 -276.230406) (xy 131.027672 -276.251504)
			(xy 131.068175 -276.27946) (xy 131.103668 -276.313552) (xy 131.133233 -276.352896) (xy 131.156104 -276.396473)
			(xy 131.171688 -276.443154) (xy 131.179583 -276.491731) (xy 131.180078 -276.516338) (xy 131.498589 -276.516338)
			(xy 131.502684 -276.46561) (xy 131.514863 -276.416196) (xy 131.534811 -276.369376) (xy 131.562012 -276.326362)
			(xy 131.59576 -276.288268) (xy 131.635182 -276.256081) (xy 131.679256 -276.230635) (xy 131.726842 -276.212588)
			(xy 131.776706 -276.202408) (xy 131.827558 -276.200359) (xy 131.878079 -276.206493) (xy 131.926963 -276.220653)
			(xy 131.972942 -276.24247) (xy 132.014826 -276.27138) (xy 132.05153 -276.306635) (xy 132.082103 -276.347321)
			(xy 132.105754 -276.392384) (xy 132.12187 -276.440658) (xy 132.130034 -276.490892) (xy 132.130546 -276.516338)
			(xy 132.438643 -276.516338) (xy 132.442738 -276.46561) (xy 132.454917 -276.416196) (xy 132.474865 -276.369376)
			(xy 132.502066 -276.326362) (xy 132.535814 -276.288268) (xy 132.575236 -276.256081) (xy 132.61931 -276.230635)
			(xy 132.666896 -276.212588) (xy 132.71676 -276.202408) (xy 132.767612 -276.200359) (xy 132.818133 -276.206493)
			(xy 132.867017 -276.220653) (xy 132.912996 -276.24247) (xy 132.95488 -276.27138) (xy 132.991584 -276.306635)
			(xy 133.022157 -276.347321) (xy 133.045808 -276.392384) (xy 133.061924 -276.440658) (xy 133.070088 -276.490892)
			(xy 133.0706 -276.516338) (xy 133.388874 -276.516338) (xy 133.392834 -276.467284) (xy 133.404611 -276.4195)
			(xy 133.423902 -276.374224) (xy 133.450205 -276.332628) (xy 133.48284 -276.295791) (xy 133.520961 -276.264666)
			(xy 133.563582 -276.240059) (xy 133.609598 -276.222607) (xy 133.657817 -276.212763) (xy 133.706992 -276.210782)
			(xy 133.755847 -276.216714) (xy 133.803118 -276.230406) (xy 133.84758 -276.251504) (xy 133.888083 -276.27946)
			(xy 133.923576 -276.313552) (xy 133.953141 -276.352896) (xy 133.976012 -276.396473) (xy 133.991596 -276.443154)
			(xy 133.999491 -276.491731) (xy 133.999986 -276.516338) (xy 134.328928 -276.516338) (xy 134.332888 -276.467284)
			(xy 134.344665 -276.4195) (xy 134.363956 -276.374224) (xy 134.390259 -276.332628) (xy 134.422894 -276.295791)
			(xy 134.461015 -276.264666) (xy 134.503636 -276.240059) (xy 134.549652 -276.222607) (xy 134.597871 -276.212763)
			(xy 134.647046 -276.210782) (xy 134.695901 -276.216714) (xy 134.743172 -276.230406) (xy 134.787634 -276.251504)
			(xy 134.828137 -276.27946) (xy 134.86363 -276.313552) (xy 134.893195 -276.352896) (xy 134.916066 -276.396473)
			(xy 134.93165 -276.443154) (xy 134.939545 -276.491731) (xy 134.94004 -276.516338) (xy 135.268982 -276.516338)
			(xy 135.272942 -276.467284) (xy 135.284719 -276.4195) (xy 135.30401 -276.374224) (xy 135.330313 -276.332628)
			(xy 135.362948 -276.295791) (xy 135.401069 -276.264666) (xy 135.44369 -276.240059) (xy 135.489706 -276.222607)
			(xy 135.537925 -276.212763) (xy 135.5871 -276.210782) (xy 135.635955 -276.216714) (xy 135.683226 -276.230406)
			(xy 135.727688 -276.251504) (xy 135.768191 -276.27946) (xy 135.803684 -276.313552) (xy 135.833249 -276.352896)
			(xy 135.85612 -276.396473) (xy 135.871704 -276.443154) (xy 135.879599 -276.491731) (xy 135.880094 -276.516338)
			(xy 136.209036 -276.516338) (xy 136.212996 -276.467284) (xy 136.224773 -276.4195) (xy 136.244064 -276.374224)
			(xy 136.270367 -276.332628) (xy 136.303002 -276.295791) (xy 136.341123 -276.264666) (xy 136.383744 -276.240059)
			(xy 136.42976 -276.222607) (xy 136.477979 -276.212763) (xy 136.527154 -276.210782) (xy 136.576009 -276.216714)
			(xy 136.62328 -276.230406) (xy 136.667742 -276.251504) (xy 136.708245 -276.27946) (xy 136.743738 -276.313552)
			(xy 136.773303 -276.352896) (xy 136.796174 -276.396473) (xy 136.811758 -276.443154) (xy 136.819653 -276.491731)
			(xy 136.820148 -276.516338) (xy 137.148836 -276.516338) (xy 137.152796 -276.467284) (xy 137.164573 -276.4195)
			(xy 137.183864 -276.374224) (xy 137.210167 -276.332628) (xy 137.242802 -276.295791) (xy 137.280923 -276.264666)
			(xy 137.323544 -276.240059) (xy 137.36956 -276.222607) (xy 137.417779 -276.212763) (xy 137.466954 -276.210782)
			(xy 137.515809 -276.216714) (xy 137.56308 -276.230406) (xy 137.607542 -276.251504) (xy 137.648045 -276.27946)
			(xy 137.683538 -276.313552) (xy 137.713103 -276.352896) (xy 137.735974 -276.396473) (xy 137.751558 -276.443154)
			(xy 137.759453 -276.491731) (xy 137.759948 -276.516338) (xy 138.08889 -276.516338) (xy 138.09285 -276.467284)
			(xy 138.104627 -276.4195) (xy 138.123918 -276.374224) (xy 138.150221 -276.332628) (xy 138.182856 -276.295791)
			(xy 138.220977 -276.264666) (xy 138.263598 -276.240059) (xy 138.309614 -276.222607) (xy 138.357833 -276.212763)
			(xy 138.407008 -276.210782) (xy 138.455863 -276.216714) (xy 138.503134 -276.230406) (xy 138.547596 -276.251504)
			(xy 138.588099 -276.27946) (xy 138.623592 -276.313552) (xy 138.653157 -276.352896) (xy 138.676028 -276.396473)
			(xy 138.691612 -276.443154) (xy 138.699507 -276.491731) (xy 138.700002 -276.516338) (xy 139.028944 -276.516338)
			(xy 139.032904 -276.467284) (xy 139.044681 -276.4195) (xy 139.063972 -276.374224) (xy 139.090275 -276.332628)
			(xy 139.12291 -276.295791) (xy 139.161031 -276.264666) (xy 139.203652 -276.240059) (xy 139.249668 -276.222607)
			(xy 139.297887 -276.212763) (xy 139.347062 -276.210782) (xy 139.395917 -276.216714) (xy 139.443188 -276.230406)
			(xy 139.48765 -276.251504) (xy 139.528153 -276.27946) (xy 139.563646 -276.313552) (xy 139.593211 -276.352896)
			(xy 139.616082 -276.396473) (xy 139.631666 -276.443154) (xy 139.639561 -276.491731) (xy 139.640056 -276.516338)
			(xy 139.639561 -276.540945) (xy 139.631666 -276.589522) (xy 139.616082 -276.636203) (xy 139.593211 -276.67978)
			(xy 139.563646 -276.719124) (xy 139.528153 -276.753216) (xy 139.48765 -276.781172) (xy 139.443188 -276.80227)
			(xy 139.395917 -276.815962) (xy 139.347062 -276.821894) (xy 139.297887 -276.819913) (xy 139.249668 -276.810069)
			(xy 139.203652 -276.792617) (xy 139.161031 -276.76801) (xy 139.12291 -276.736885) (xy 139.090275 -276.700048)
			(xy 139.063972 -276.658452) (xy 139.044681 -276.613176) (xy 139.032904 -276.565392) (xy 139.028944 -276.516338)
			(xy 138.700002 -276.516338) (xy 138.699507 -276.540945) (xy 138.691612 -276.589522) (xy 138.676028 -276.636203)
			(xy 138.653157 -276.67978) (xy 138.623592 -276.719124) (xy 138.588099 -276.753216) (xy 138.547596 -276.781172)
			(xy 138.503134 -276.80227) (xy 138.455863 -276.815962) (xy 138.407008 -276.821894) (xy 138.357833 -276.819913)
			(xy 138.309614 -276.810069) (xy 138.263598 -276.792617) (xy 138.220977 -276.76801) (xy 138.182856 -276.736885)
			(xy 138.150221 -276.700048) (xy 138.123918 -276.658452) (xy 138.104627 -276.613176) (xy 138.09285 -276.565392)
			(xy 138.08889 -276.516338) (xy 137.759948 -276.516338) (xy 137.759453 -276.540945) (xy 137.751558 -276.589522)
			(xy 137.735974 -276.636203) (xy 137.713103 -276.67978) (xy 137.683538 -276.719124) (xy 137.648045 -276.753216)
			(xy 137.607542 -276.781172) (xy 137.56308 -276.80227) (xy 137.515809 -276.815962) (xy 137.466954 -276.821894)
			(xy 137.417779 -276.819913) (xy 137.36956 -276.810069) (xy 137.323544 -276.792617) (xy 137.280923 -276.76801)
			(xy 137.242802 -276.736885) (xy 137.210167 -276.700048) (xy 137.183864 -276.658452) (xy 137.164573 -276.613176)
			(xy 137.152796 -276.565392) (xy 137.148836 -276.516338) (xy 136.820148 -276.516338) (xy 136.819653 -276.540945)
			(xy 136.811758 -276.589522) (xy 136.796174 -276.636203) (xy 136.773303 -276.67978) (xy 136.743738 -276.719124)
			(xy 136.708245 -276.753216) (xy 136.667742 -276.781172) (xy 136.62328 -276.80227) (xy 136.576009 -276.815962)
			(xy 136.527154 -276.821894) (xy 136.477979 -276.819913) (xy 136.42976 -276.810069) (xy 136.383744 -276.792617)
			(xy 136.341123 -276.76801) (xy 136.303002 -276.736885) (xy 136.270367 -276.700048) (xy 136.244064 -276.658452)
			(xy 136.224773 -276.613176) (xy 136.212996 -276.565392) (xy 136.209036 -276.516338) (xy 135.880094 -276.516338)
			(xy 135.879599 -276.540945) (xy 135.871704 -276.589522) (xy 135.85612 -276.636203) (xy 135.833249 -276.67978)
			(xy 135.803684 -276.719124) (xy 135.768191 -276.753216) (xy 135.727688 -276.781172) (xy 135.683226 -276.80227)
			(xy 135.635955 -276.815962) (xy 135.5871 -276.821894) (xy 135.537925 -276.819913) (xy 135.489706 -276.810069)
			(xy 135.44369 -276.792617) (xy 135.401069 -276.76801) (xy 135.362948 -276.736885) (xy 135.330313 -276.700048)
			(xy 135.30401 -276.658452) (xy 135.284719 -276.613176) (xy 135.272942 -276.565392) (xy 135.268982 -276.516338)
			(xy 134.94004 -276.516338) (xy 134.939545 -276.540945) (xy 134.93165 -276.589522) (xy 134.916066 -276.636203)
			(xy 134.893195 -276.67978) (xy 134.86363 -276.719124) (xy 134.828137 -276.753216) (xy 134.787634 -276.781172)
			(xy 134.743172 -276.80227) (xy 134.695901 -276.815962) (xy 134.647046 -276.821894) (xy 134.597871 -276.819913)
			(xy 134.549652 -276.810069) (xy 134.503636 -276.792617) (xy 134.461015 -276.76801) (xy 134.422894 -276.736885)
			(xy 134.390259 -276.700048) (xy 134.363956 -276.658452) (xy 134.344665 -276.613176) (xy 134.332888 -276.565392)
			(xy 134.328928 -276.516338) (xy 133.999986 -276.516338) (xy 133.999491 -276.540945) (xy 133.991596 -276.589522)
			(xy 133.976012 -276.636203) (xy 133.953141 -276.67978) (xy 133.923576 -276.719124) (xy 133.888083 -276.753216)
			(xy 133.84758 -276.781172) (xy 133.803118 -276.80227) (xy 133.755847 -276.815962) (xy 133.706992 -276.821894)
			(xy 133.657817 -276.819913) (xy 133.609598 -276.810069) (xy 133.563582 -276.792617) (xy 133.520961 -276.76801)
			(xy 133.48284 -276.736885) (xy 133.450205 -276.700048) (xy 133.423902 -276.658452) (xy 133.404611 -276.613176)
			(xy 133.392834 -276.565392) (xy 133.388874 -276.516338) (xy 133.0706 -276.516338) (xy 133.070088 -276.541784)
			(xy 133.061924 -276.592018) (xy 133.045808 -276.640292) (xy 133.022157 -276.685355) (xy 132.991584 -276.726041)
			(xy 132.95488 -276.761296) (xy 132.912996 -276.790206) (xy 132.867017 -276.812023) (xy 132.818133 -276.826183)
			(xy 132.767612 -276.832317) (xy 132.71676 -276.830268) (xy 132.666896 -276.820088) (xy 132.61931 -276.802041)
			(xy 132.575236 -276.776595) (xy 132.535814 -276.744408) (xy 132.502066 -276.706314) (xy 132.474865 -276.6633)
			(xy 132.454917 -276.61648) (xy 132.442738 -276.567066) (xy 132.438643 -276.516338) (xy 132.130546 -276.516338)
			(xy 132.130034 -276.541784) (xy 132.12187 -276.592018) (xy 132.105754 -276.640292) (xy 132.082103 -276.685355)
			(xy 132.05153 -276.726041) (xy 132.014826 -276.761296) (xy 131.972942 -276.790206) (xy 131.926963 -276.812023)
			(xy 131.878079 -276.826183) (xy 131.827558 -276.832317) (xy 131.776706 -276.830268) (xy 131.726842 -276.820088)
			(xy 131.679256 -276.802041) (xy 131.635182 -276.776595) (xy 131.59576 -276.744408) (xy 131.562012 -276.706314)
			(xy 131.534811 -276.6633) (xy 131.514863 -276.61648) (xy 131.502684 -276.567066) (xy 131.498589 -276.516338)
			(xy 131.180078 -276.516338) (xy 131.179583 -276.540945) (xy 131.171688 -276.589522) (xy 131.156104 -276.636203)
			(xy 131.133233 -276.67978) (xy 131.103668 -276.719124) (xy 131.068175 -276.753216) (xy 131.027672 -276.781172)
			(xy 130.98321 -276.80227) (xy 130.935939 -276.815962) (xy 130.887084 -276.821894) (xy 130.837909 -276.819913)
			(xy 130.78969 -276.810069) (xy 130.743674 -276.792617) (xy 130.701053 -276.76801) (xy 130.662932 -276.736885)
			(xy 130.630297 -276.700048) (xy 130.603994 -276.658452) (xy 130.584703 -276.613176) (xy 130.572926 -276.565392)
			(xy 130.568966 -276.516338) (xy 130.250438 -276.516338) (xy 130.249926 -276.541784) (xy 130.241762 -276.592018)
			(xy 130.225646 -276.640292) (xy 130.201995 -276.685355) (xy 130.171422 -276.726041) (xy 130.134718 -276.761296)
			(xy 130.092834 -276.790206) (xy 130.046855 -276.812023) (xy 129.997971 -276.826183) (xy 129.94745 -276.832317)
			(xy 129.896598 -276.830268) (xy 129.846734 -276.820088) (xy 129.799148 -276.802041) (xy 129.755074 -276.776595)
			(xy 129.715652 -276.744408) (xy 129.681904 -276.706314) (xy 129.654703 -276.6633) (xy 129.634755 -276.61648)
			(xy 129.622576 -276.567066) (xy 129.618481 -276.516338) (xy 129.29997 -276.516338) (xy 129.299475 -276.540945)
			(xy 129.29158 -276.589522) (xy 129.275996 -276.636203) (xy 129.253125 -276.67978) (xy 129.22356 -276.719124)
			(xy 129.188067 -276.753216) (xy 129.147564 -276.781172) (xy 129.103102 -276.80227) (xy 129.055831 -276.815962)
			(xy 129.006976 -276.821894) (xy 128.957801 -276.819913) (xy 128.909582 -276.810069) (xy 128.863566 -276.792617)
			(xy 128.820945 -276.76801) (xy 128.782824 -276.736885) (xy 128.750189 -276.700048) (xy 128.723886 -276.658452)
			(xy 128.704595 -276.613176) (xy 128.692818 -276.565392) (xy 128.688858 -276.516338) (xy 128.370584 -276.516338)
			(xy 128.370072 -276.541784) (xy 128.361908 -276.592018) (xy 128.345792 -276.640292) (xy 128.322141 -276.685355)
			(xy 128.291568 -276.726041) (xy 128.254864 -276.761296) (xy 128.21298 -276.790206) (xy 128.167001 -276.812023)
			(xy 128.118117 -276.826183) (xy 128.067596 -276.832317) (xy 128.016744 -276.830268) (xy 127.96688 -276.820088)
			(xy 127.919294 -276.802041) (xy 127.87522 -276.776595) (xy 127.835798 -276.744408) (xy 127.80205 -276.706314)
			(xy 127.774849 -276.6633) (xy 127.754901 -276.61648) (xy 127.742722 -276.567066) (xy 127.738627 -276.516338)
			(xy 127.543814 -276.516338) (xy 127.543814 -276.950424) (xy 127.544255 -276.960213) (xy 127.55156 -276.978379)
			(xy 127.558038 -276.98573) (xy 127.572516 -277.000716) (xy 127.575901 -277.004081) (xy 127.583702 -277.009583)
			(xy 127.58801 -277.011638) (xy 127.610362 -277.021798) (xy 127.61849 -277.022814) (xy 127.643067 -277.026035)
			(xy 127.690794 -277.039404) (xy 127.735736 -277.060305) (xy 127.776713 -277.08819) (xy 127.812648 -277.122326)
			(xy 127.842598 -277.161819) (xy 127.865777 -277.205629) (xy 127.881576 -277.252609) (xy 127.88958 -277.301523)
			(xy 127.889579 -277.326344) (xy 128.208527 -277.326344) (xy 128.212622 -277.275616) (xy 128.224801 -277.226202)
			(xy 128.244749 -277.179382) (xy 128.27195 -277.136368) (xy 128.305698 -277.098274) (xy 128.34512 -277.066087)
			(xy 128.389194 -277.040641) (xy 128.43678 -277.022594) (xy 128.486644 -277.012414) (xy 128.537496 -277.010365)
			(xy 128.588017 -277.016499) (xy 128.636901 -277.030659) (xy 128.68288 -277.052476) (xy 128.724764 -277.081386)
			(xy 128.761468 -277.116641) (xy 128.792041 -277.157327) (xy 128.815692 -277.20239) (xy 128.831808 -277.250664)
			(xy 128.839972 -277.300898) (xy 128.840484 -277.326344) (xy 129.148581 -277.326344) (xy 129.152676 -277.275616)
			(xy 129.164855 -277.226202) (xy 129.184803 -277.179382) (xy 129.212004 -277.136368) (xy 129.245752 -277.098274)
			(xy 129.285174 -277.066087) (xy 129.329248 -277.040641) (xy 129.376834 -277.022594) (xy 129.426698 -277.012414)
			(xy 129.47755 -277.010365) (xy 129.528071 -277.016499) (xy 129.576955 -277.030659) (xy 129.622934 -277.052476)
			(xy 129.664818 -277.081386) (xy 129.701522 -277.116641) (xy 129.732095 -277.157327) (xy 129.755746 -277.20239)
			(xy 129.771862 -277.250664) (xy 129.780026 -277.300898) (xy 129.780538 -277.326344) (xy 130.099066 -277.326344)
			(xy 130.103026 -277.27729) (xy 130.114803 -277.229506) (xy 130.134094 -277.18423) (xy 130.160397 -277.142634)
			(xy 130.193032 -277.105797) (xy 130.231153 -277.074672) (xy 130.273774 -277.050065) (xy 130.31979 -277.032613)
			(xy 130.368009 -277.022769) (xy 130.417184 -277.020788) (xy 130.466039 -277.02672) (xy 130.51331 -277.040412)
			(xy 130.557772 -277.06151) (xy 130.598275 -277.089466) (xy 130.633768 -277.123558) (xy 130.663333 -277.162902)
			(xy 130.686204 -277.206479) (xy 130.701788 -277.25316) (xy 130.709683 -277.301737) (xy 130.710178 -277.326344)
			(xy 131.028435 -277.326344) (xy 131.03253 -277.275616) (xy 131.044709 -277.226202) (xy 131.064657 -277.179382)
			(xy 131.091858 -277.136368) (xy 131.125606 -277.098274) (xy 131.165028 -277.066087) (xy 131.209102 -277.040641)
			(xy 131.256688 -277.022594) (xy 131.306552 -277.012414) (xy 131.357404 -277.010365) (xy 131.407925 -277.016499)
			(xy 131.456809 -277.030659) (xy 131.502788 -277.052476) (xy 131.544672 -277.081386) (xy 131.581376 -277.116641)
			(xy 131.611949 -277.157327) (xy 131.6356 -277.20239) (xy 131.651716 -277.250664) (xy 131.65988 -277.300898)
			(xy 131.660392 -277.326344) (xy 131.97892 -277.326344) (xy 131.98288 -277.27729) (xy 131.994657 -277.229506)
			(xy 132.013948 -277.18423) (xy 132.040251 -277.142634) (xy 132.072886 -277.105797) (xy 132.111007 -277.074672)
			(xy 132.153628 -277.050065) (xy 132.199644 -277.032613) (xy 132.247863 -277.022769) (xy 132.297038 -277.020788)
			(xy 132.345893 -277.02672) (xy 132.393164 -277.040412) (xy 132.437626 -277.06151) (xy 132.478129 -277.089466)
			(xy 132.513622 -277.123558) (xy 132.543187 -277.162902) (xy 132.566058 -277.206479) (xy 132.581642 -277.25316)
			(xy 132.589537 -277.301737) (xy 132.590032 -277.326344) (xy 132.908543 -277.326344) (xy 132.912638 -277.275616)
			(xy 132.924817 -277.226202) (xy 132.944765 -277.179382) (xy 132.971966 -277.136368) (xy 133.005714 -277.098274)
			(xy 133.045136 -277.066087) (xy 133.08921 -277.040641) (xy 133.136796 -277.022594) (xy 133.18666 -277.012414)
			(xy 133.237512 -277.010365) (xy 133.288033 -277.016499) (xy 133.336917 -277.030659) (xy 133.382896 -277.052476)
			(xy 133.42478 -277.081386) (xy 133.461484 -277.116641) (xy 133.492057 -277.157327) (xy 133.515708 -277.20239)
			(xy 133.531824 -277.250664) (xy 133.539988 -277.300898) (xy 133.5405 -277.326344) (xy 133.859028 -277.326344)
			(xy 133.862988 -277.27729) (xy 133.874765 -277.229506) (xy 133.894056 -277.18423) (xy 133.920359 -277.142634)
			(xy 133.952994 -277.105797) (xy 133.991115 -277.074672) (xy 134.033736 -277.050065) (xy 134.079752 -277.032613)
			(xy 134.127971 -277.022769) (xy 134.177146 -277.020788) (xy 134.226001 -277.02672) (xy 134.273272 -277.040412)
			(xy 134.317734 -277.06151) (xy 134.358237 -277.089466) (xy 134.39373 -277.123558) (xy 134.423295 -277.162902)
			(xy 134.446166 -277.206479) (xy 134.46175 -277.25316) (xy 134.469645 -277.301737) (xy 134.47014 -277.326344)
			(xy 134.798828 -277.326344) (xy 134.802788 -277.27729) (xy 134.814565 -277.229506) (xy 134.833856 -277.18423)
			(xy 134.860159 -277.142634) (xy 134.892794 -277.105797) (xy 134.930915 -277.074672) (xy 134.973536 -277.050065)
			(xy 135.019552 -277.032613) (xy 135.067771 -277.022769) (xy 135.116946 -277.020788) (xy 135.165801 -277.02672)
			(xy 135.213072 -277.040412) (xy 135.257534 -277.06151) (xy 135.298037 -277.089466) (xy 135.33353 -277.123558)
			(xy 135.363095 -277.162902) (xy 135.385966 -277.206479) (xy 135.40155 -277.25316) (xy 135.409445 -277.301737)
			(xy 135.40994 -277.326344) (xy 135.738882 -277.326344) (xy 135.742842 -277.27729) (xy 135.754619 -277.229506)
			(xy 135.77391 -277.18423) (xy 135.800213 -277.142634) (xy 135.832848 -277.105797) (xy 135.870969 -277.074672)
			(xy 135.91359 -277.050065) (xy 135.959606 -277.032613) (xy 136.007825 -277.022769) (xy 136.057 -277.020788)
			(xy 136.105855 -277.02672) (xy 136.153126 -277.040412) (xy 136.197588 -277.06151) (xy 136.238091 -277.089466)
			(xy 136.273584 -277.123558) (xy 136.303149 -277.162902) (xy 136.32602 -277.206479) (xy 136.341604 -277.25316)
			(xy 136.349499 -277.301737) (xy 136.349994 -277.326344) (xy 136.678936 -277.326344) (xy 136.682896 -277.27729)
			(xy 136.694673 -277.229506) (xy 136.713964 -277.18423) (xy 136.740267 -277.142634) (xy 136.772902 -277.105797)
			(xy 136.811023 -277.074672) (xy 136.853644 -277.050065) (xy 136.89966 -277.032613) (xy 136.947879 -277.022769)
			(xy 136.997054 -277.020788) (xy 137.045909 -277.02672) (xy 137.09318 -277.040412) (xy 137.137642 -277.06151)
			(xy 137.178145 -277.089466) (xy 137.213638 -277.123558) (xy 137.243203 -277.162902) (xy 137.266074 -277.206479)
			(xy 137.281658 -277.25316) (xy 137.289553 -277.301737) (xy 137.290048 -277.326344) (xy 137.61899 -277.326344)
			(xy 137.62295 -277.27729) (xy 137.634727 -277.229506) (xy 137.654018 -277.18423) (xy 137.680321 -277.142634)
			(xy 137.712956 -277.105797) (xy 137.751077 -277.074672) (xy 137.793698 -277.050065) (xy 137.839714 -277.032613)
			(xy 137.887933 -277.022769) (xy 137.937108 -277.020788) (xy 137.985963 -277.02672) (xy 138.033234 -277.040412)
			(xy 138.077696 -277.06151) (xy 138.118199 -277.089466) (xy 138.153692 -277.123558) (xy 138.183257 -277.162902)
			(xy 138.206128 -277.206479) (xy 138.221712 -277.25316) (xy 138.229607 -277.301737) (xy 138.230102 -277.326344)
			(xy 138.559044 -277.326344) (xy 138.563004 -277.27729) (xy 138.574781 -277.229506) (xy 138.594072 -277.18423)
			(xy 138.620375 -277.142634) (xy 138.65301 -277.105797) (xy 138.691131 -277.074672) (xy 138.733752 -277.050065)
			(xy 138.779768 -277.032613) (xy 138.827987 -277.022769) (xy 138.877162 -277.020788) (xy 138.926017 -277.02672)
			(xy 138.973288 -277.040412) (xy 139.01775 -277.06151) (xy 139.058253 -277.089466) (xy 139.093746 -277.123558)
			(xy 139.123311 -277.162902) (xy 139.146182 -277.206479) (xy 139.161766 -277.25316) (xy 139.169661 -277.301737)
			(xy 139.170156 -277.326344) (xy 139.498844 -277.326344) (xy 139.502804 -277.27729) (xy 139.514581 -277.229506)
			(xy 139.533872 -277.18423) (xy 139.560175 -277.142634) (xy 139.59281 -277.105797) (xy 139.630931 -277.074672)
			(xy 139.673552 -277.050065) (xy 139.719568 -277.032613) (xy 139.767787 -277.022769) (xy 139.816962 -277.020788)
			(xy 139.865817 -277.02672) (xy 139.913088 -277.040412) (xy 139.95755 -277.06151) (xy 139.998053 -277.089466)
			(xy 140.033546 -277.123558) (xy 140.063111 -277.162902) (xy 140.085982 -277.206479) (xy 140.101566 -277.25316)
			(xy 140.109461 -277.301737) (xy 140.109956 -277.326344) (xy 140.109461 -277.350951) (xy 140.101566 -277.399528)
			(xy 140.085982 -277.446209) (xy 140.063111 -277.489786) (xy 140.033546 -277.52913) (xy 139.998053 -277.563222)
			(xy 139.95755 -277.591178) (xy 139.913088 -277.612276) (xy 139.865817 -277.625968) (xy 139.816962 -277.6319)
			(xy 139.767787 -277.629919) (xy 139.719568 -277.620075) (xy 139.673552 -277.602623) (xy 139.630931 -277.578016)
			(xy 139.59281 -277.546891) (xy 139.560175 -277.510054) (xy 139.533872 -277.468458) (xy 139.514581 -277.423182)
			(xy 139.502804 -277.375398) (xy 139.498844 -277.326344) (xy 139.170156 -277.326344) (xy 139.169661 -277.350951)
			(xy 139.161766 -277.399528) (xy 139.146182 -277.446209) (xy 139.123311 -277.489786) (xy 139.093746 -277.52913)
			(xy 139.058253 -277.563222) (xy 139.01775 -277.591178) (xy 138.973288 -277.612276) (xy 138.926017 -277.625968)
			(xy 138.877162 -277.6319) (xy 138.827987 -277.629919) (xy 138.779768 -277.620075) (xy 138.733752 -277.602623)
			(xy 138.691131 -277.578016) (xy 138.65301 -277.546891) (xy 138.620375 -277.510054) (xy 138.594072 -277.468458)
			(xy 138.574781 -277.423182) (xy 138.563004 -277.375398) (xy 138.559044 -277.326344) (xy 138.230102 -277.326344)
			(xy 138.229607 -277.350951) (xy 138.221712 -277.399528) (xy 138.206128 -277.446209) (xy 138.183257 -277.489786)
			(xy 138.153692 -277.52913) (xy 138.118199 -277.563222) (xy 138.077696 -277.591178) (xy 138.033234 -277.612276)
			(xy 137.985963 -277.625968) (xy 137.937108 -277.6319) (xy 137.887933 -277.629919) (xy 137.839714 -277.620075)
			(xy 137.793698 -277.602623) (xy 137.751077 -277.578016) (xy 137.712956 -277.546891) (xy 137.680321 -277.510054)
			(xy 137.654018 -277.468458) (xy 137.634727 -277.423182) (xy 137.62295 -277.375398) (xy 137.61899 -277.326344)
			(xy 137.290048 -277.326344) (xy 137.289553 -277.350951) (xy 137.281658 -277.399528) (xy 137.266074 -277.446209)
			(xy 137.243203 -277.489786) (xy 137.213638 -277.52913) (xy 137.178145 -277.563222) (xy 137.137642 -277.591178)
			(xy 137.09318 -277.612276) (xy 137.045909 -277.625968) (xy 136.997054 -277.6319) (xy 136.947879 -277.629919)
			(xy 136.89966 -277.620075) (xy 136.853644 -277.602623) (xy 136.811023 -277.578016) (xy 136.772902 -277.546891)
			(xy 136.740267 -277.510054) (xy 136.713964 -277.468458) (xy 136.694673 -277.423182) (xy 136.682896 -277.375398)
			(xy 136.678936 -277.326344) (xy 136.349994 -277.326344) (xy 136.349499 -277.350951) (xy 136.341604 -277.399528)
			(xy 136.32602 -277.446209) (xy 136.303149 -277.489786) (xy 136.273584 -277.52913) (xy 136.238091 -277.563222)
			(xy 136.197588 -277.591178) (xy 136.153126 -277.612276) (xy 136.105855 -277.625968) (xy 136.057 -277.6319)
			(xy 136.007825 -277.629919) (xy 135.959606 -277.620075) (xy 135.91359 -277.602623) (xy 135.870969 -277.578016)
			(xy 135.832848 -277.546891) (xy 135.800213 -277.510054) (xy 135.77391 -277.468458) (xy 135.754619 -277.423182)
			(xy 135.742842 -277.375398) (xy 135.738882 -277.326344) (xy 135.40994 -277.326344) (xy 135.409445 -277.350951)
			(xy 135.40155 -277.399528) (xy 135.385966 -277.446209) (xy 135.363095 -277.489786) (xy 135.33353 -277.52913)
			(xy 135.298037 -277.563222) (xy 135.257534 -277.591178) (xy 135.213072 -277.612276) (xy 135.165801 -277.625968)
			(xy 135.116946 -277.6319) (xy 135.067771 -277.629919) (xy 135.019552 -277.620075) (xy 134.973536 -277.602623)
			(xy 134.930915 -277.578016) (xy 134.892794 -277.546891) (xy 134.860159 -277.510054) (xy 134.833856 -277.468458)
			(xy 134.814565 -277.423182) (xy 134.802788 -277.375398) (xy 134.798828 -277.326344) (xy 134.47014 -277.326344)
			(xy 134.469645 -277.350951) (xy 134.46175 -277.399528) (xy 134.446166 -277.446209) (xy 134.423295 -277.489786)
			(xy 134.39373 -277.52913) (xy 134.358237 -277.563222) (xy 134.317734 -277.591178) (xy 134.273272 -277.612276)
			(xy 134.226001 -277.625968) (xy 134.177146 -277.6319) (xy 134.127971 -277.629919) (xy 134.079752 -277.620075)
			(xy 134.033736 -277.602623) (xy 133.991115 -277.578016) (xy 133.952994 -277.546891) (xy 133.920359 -277.510054)
			(xy 133.894056 -277.468458) (xy 133.874765 -277.423182) (xy 133.862988 -277.375398) (xy 133.859028 -277.326344)
			(xy 133.5405 -277.326344) (xy 133.539988 -277.35179) (xy 133.531824 -277.402024) (xy 133.515708 -277.450298)
			(xy 133.492057 -277.495361) (xy 133.461484 -277.536047) (xy 133.42478 -277.571302) (xy 133.382896 -277.600212)
			(xy 133.336917 -277.622029) (xy 133.288033 -277.636189) (xy 133.237512 -277.642323) (xy 133.18666 -277.640274)
			(xy 133.136796 -277.630094) (xy 133.08921 -277.612047) (xy 133.045136 -277.586601) (xy 133.005714 -277.554414)
			(xy 132.971966 -277.51632) (xy 132.944765 -277.473306) (xy 132.924817 -277.426486) (xy 132.912638 -277.377072)
			(xy 132.908543 -277.326344) (xy 132.590032 -277.326344) (xy 132.589537 -277.350951) (xy 132.581642 -277.399528)
			(xy 132.566058 -277.446209) (xy 132.543187 -277.489786) (xy 132.513622 -277.52913) (xy 132.478129 -277.563222)
			(xy 132.437626 -277.591178) (xy 132.393164 -277.612276) (xy 132.345893 -277.625968) (xy 132.297038 -277.6319)
			(xy 132.247863 -277.629919) (xy 132.199644 -277.620075) (xy 132.153628 -277.602623) (xy 132.111007 -277.578016)
			(xy 132.072886 -277.546891) (xy 132.040251 -277.510054) (xy 132.013948 -277.468458) (xy 131.994657 -277.423182)
			(xy 131.98288 -277.375398) (xy 131.97892 -277.326344) (xy 131.660392 -277.326344) (xy 131.65988 -277.35179)
			(xy 131.651716 -277.402024) (xy 131.6356 -277.450298) (xy 131.611949 -277.495361) (xy 131.581376 -277.536047)
			(xy 131.544672 -277.571302) (xy 131.502788 -277.600212) (xy 131.456809 -277.622029) (xy 131.407925 -277.636189)
			(xy 131.357404 -277.642323) (xy 131.306552 -277.640274) (xy 131.256688 -277.630094) (xy 131.209102 -277.612047)
			(xy 131.165028 -277.586601) (xy 131.125606 -277.554414) (xy 131.091858 -277.51632) (xy 131.064657 -277.473306)
			(xy 131.044709 -277.426486) (xy 131.03253 -277.377072) (xy 131.028435 -277.326344) (xy 130.710178 -277.326344)
			(xy 130.709683 -277.350951) (xy 130.701788 -277.399528) (xy 130.686204 -277.446209) (xy 130.663333 -277.489786)
			(xy 130.633768 -277.52913) (xy 130.598275 -277.563222) (xy 130.557772 -277.591178) (xy 130.51331 -277.612276)
			(xy 130.466039 -277.625968) (xy 130.417184 -277.6319) (xy 130.368009 -277.629919) (xy 130.31979 -277.620075)
			(xy 130.273774 -277.602623) (xy 130.231153 -277.578016) (xy 130.193032 -277.546891) (xy 130.160397 -277.510054)
			(xy 130.134094 -277.468458) (xy 130.114803 -277.423182) (xy 130.103026 -277.375398) (xy 130.099066 -277.326344)
			(xy 129.780538 -277.326344) (xy 129.780026 -277.35179) (xy 129.771862 -277.402024) (xy 129.755746 -277.450298)
			(xy 129.732095 -277.495361) (xy 129.701522 -277.536047) (xy 129.664818 -277.571302) (xy 129.622934 -277.600212)
			(xy 129.576955 -277.622029) (xy 129.528071 -277.636189) (xy 129.47755 -277.642323) (xy 129.426698 -277.640274)
			(xy 129.376834 -277.630094) (xy 129.329248 -277.612047) (xy 129.285174 -277.586601) (xy 129.245752 -277.554414)
			(xy 129.212004 -277.51632) (xy 129.184803 -277.473306) (xy 129.164855 -277.426486) (xy 129.152676 -277.377072)
			(xy 129.148581 -277.326344) (xy 128.840484 -277.326344) (xy 128.839972 -277.35179) (xy 128.831808 -277.402024)
			(xy 128.815692 -277.450298) (xy 128.792041 -277.495361) (xy 128.761468 -277.536047) (xy 128.724764 -277.571302)
			(xy 128.68288 -277.600212) (xy 128.636901 -277.622029) (xy 128.588017 -277.636189) (xy 128.537496 -277.642323)
			(xy 128.486644 -277.640274) (xy 128.43678 -277.630094) (xy 128.389194 -277.612047) (xy 128.34512 -277.586601)
			(xy 128.305698 -277.554414) (xy 128.27195 -277.51632) (xy 128.244749 -277.473306) (xy 128.224801 -277.426486)
			(xy 128.212622 -277.377072) (xy 128.208527 -277.326344) (xy 127.889579 -277.326344) (xy 127.889579 -277.351087)
			(xy 127.881573 -277.400001) (xy 127.865773 -277.446979) (xy 127.842593 -277.49079) (xy 127.812641 -277.530281)
			(xy 127.776705 -277.564416) (xy 127.735728 -277.5923) (xy 127.690785 -277.6132) (xy 127.643057 -277.626566)
			(xy 127.61849 -277.629874) (xy 127.610362 -277.63089) (xy 127.58801 -277.64105) (xy 127.583719 -277.643135)
			(xy 127.575921 -277.64863) (xy 127.572516 -277.651972) (xy 127.558038 -277.666958) (xy 127.55156 -277.674311)
			(xy 127.544252 -277.692474) (xy 127.543814 -277.702264) (xy 127.543814 -278.13635) (xy 127.738627 -278.13635)
			(xy 127.742722 -278.085622) (xy 127.754901 -278.036208) (xy 127.774849 -277.989388) (xy 127.80205 -277.946374)
			(xy 127.835798 -277.90828) (xy 127.87522 -277.876093) (xy 127.919294 -277.850647) (xy 127.96688 -277.8326)
			(xy 128.016744 -277.82242) (xy 128.067596 -277.820371) (xy 128.118117 -277.826505) (xy 128.167001 -277.840665)
			(xy 128.21298 -277.862482) (xy 128.254864 -277.891392) (xy 128.291568 -277.926647) (xy 128.322141 -277.967333)
			(xy 128.345792 -278.012396) (xy 128.361908 -278.06067) (xy 128.370072 -278.110904) (xy 128.370584 -278.13635)
			(xy 128.688858 -278.13635) (xy 128.692818 -278.087296) (xy 128.704595 -278.039512) (xy 128.723886 -277.994236)
			(xy 128.750189 -277.95264) (xy 128.782824 -277.915803) (xy 128.820945 -277.884678) (xy 128.863566 -277.860071)
			(xy 128.909582 -277.842619) (xy 128.957801 -277.832775) (xy 129.006976 -277.830794) (xy 129.055831 -277.836726)
			(xy 129.103102 -277.850418) (xy 129.147564 -277.871516) (xy 129.188067 -277.899472) (xy 129.22356 -277.933564)
			(xy 129.253125 -277.972908) (xy 129.275996 -278.016485) (xy 129.29158 -278.063166) (xy 129.299475 -278.111743)
			(xy 129.29997 -278.13635) (xy 129.618481 -278.13635) (xy 129.622576 -278.085622) (xy 129.634755 -278.036208)
			(xy 129.654703 -277.989388) (xy 129.681904 -277.946374) (xy 129.715652 -277.90828) (xy 129.755074 -277.876093)
			(xy 129.799148 -277.850647) (xy 129.846734 -277.8326) (xy 129.896598 -277.82242) (xy 129.94745 -277.820371)
			(xy 129.997971 -277.826505) (xy 130.046855 -277.840665) (xy 130.092834 -277.862482) (xy 130.134718 -277.891392)
			(xy 130.171422 -277.926647) (xy 130.201995 -277.967333) (xy 130.225646 -278.012396) (xy 130.241762 -278.06067)
			(xy 130.249926 -278.110904) (xy 130.250438 -278.13635) (xy 130.568966 -278.13635) (xy 130.572926 -278.087296)
			(xy 130.584703 -278.039512) (xy 130.603994 -277.994236) (xy 130.630297 -277.95264) (xy 130.662932 -277.915803)
			(xy 130.701053 -277.884678) (xy 130.743674 -277.860071) (xy 130.78969 -277.842619) (xy 130.837909 -277.832775)
			(xy 130.887084 -277.830794) (xy 130.935939 -277.836726) (xy 130.98321 -277.850418) (xy 131.027672 -277.871516)
			(xy 131.068175 -277.899472) (xy 131.103668 -277.933564) (xy 131.133233 -277.972908) (xy 131.156104 -278.016485)
			(xy 131.171688 -278.063166) (xy 131.179583 -278.111743) (xy 131.180078 -278.13635) (xy 131.498589 -278.13635)
			(xy 131.502684 -278.085622) (xy 131.514863 -278.036208) (xy 131.534811 -277.989388) (xy 131.562012 -277.946374)
			(xy 131.59576 -277.90828) (xy 131.635182 -277.876093) (xy 131.679256 -277.850647) (xy 131.726842 -277.8326)
			(xy 131.776706 -277.82242) (xy 131.827558 -277.820371) (xy 131.878079 -277.826505) (xy 131.926963 -277.840665)
			(xy 131.972942 -277.862482) (xy 132.014826 -277.891392) (xy 132.05153 -277.926647) (xy 132.082103 -277.967333)
			(xy 132.105754 -278.012396) (xy 132.12187 -278.06067) (xy 132.130034 -278.110904) (xy 132.130546 -278.13635)
			(xy 132.438643 -278.13635) (xy 132.442738 -278.085622) (xy 132.454917 -278.036208) (xy 132.474865 -277.989388)
			(xy 132.502066 -277.946374) (xy 132.535814 -277.90828) (xy 132.575236 -277.876093) (xy 132.61931 -277.850647)
			(xy 132.666896 -277.8326) (xy 132.71676 -277.82242) (xy 132.767612 -277.820371) (xy 132.818133 -277.826505)
			(xy 132.867017 -277.840665) (xy 132.912996 -277.862482) (xy 132.95488 -277.891392) (xy 132.991584 -277.926647)
			(xy 133.022157 -277.967333) (xy 133.045808 -278.012396) (xy 133.061924 -278.06067) (xy 133.070088 -278.110904)
			(xy 133.0706 -278.13635) (xy 133.388874 -278.13635) (xy 133.392834 -278.087296) (xy 133.404611 -278.039512)
			(xy 133.423902 -277.994236) (xy 133.450205 -277.95264) (xy 133.48284 -277.915803) (xy 133.520961 -277.884678)
			(xy 133.563582 -277.860071) (xy 133.609598 -277.842619) (xy 133.657817 -277.832775) (xy 133.706992 -277.830794)
			(xy 133.755847 -277.836726) (xy 133.803118 -277.850418) (xy 133.84758 -277.871516) (xy 133.888083 -277.899472)
			(xy 133.923576 -277.933564) (xy 133.953141 -277.972908) (xy 133.976012 -278.016485) (xy 133.991596 -278.063166)
			(xy 133.999491 -278.111743) (xy 133.999986 -278.13635) (xy 134.328928 -278.13635) (xy 134.332888 -278.087296)
			(xy 134.344665 -278.039512) (xy 134.363956 -277.994236) (xy 134.390259 -277.95264) (xy 134.422894 -277.915803)
			(xy 134.461015 -277.884678) (xy 134.503636 -277.860071) (xy 134.549652 -277.842619) (xy 134.597871 -277.832775)
			(xy 134.647046 -277.830794) (xy 134.695901 -277.836726) (xy 134.743172 -277.850418) (xy 134.787634 -277.871516)
			(xy 134.828137 -277.899472) (xy 134.86363 -277.933564) (xy 134.893195 -277.972908) (xy 134.916066 -278.016485)
			(xy 134.93165 -278.063166) (xy 134.939545 -278.111743) (xy 134.94004 -278.13635) (xy 135.268982 -278.13635)
			(xy 135.272942 -278.087296) (xy 135.284719 -278.039512) (xy 135.30401 -277.994236) (xy 135.330313 -277.95264)
			(xy 135.362948 -277.915803) (xy 135.401069 -277.884678) (xy 135.44369 -277.860071) (xy 135.489706 -277.842619)
			(xy 135.537925 -277.832775) (xy 135.5871 -277.830794) (xy 135.635955 -277.836726) (xy 135.683226 -277.850418)
			(xy 135.727688 -277.871516) (xy 135.768191 -277.899472) (xy 135.803684 -277.933564) (xy 135.833249 -277.972908)
			(xy 135.85612 -278.016485) (xy 135.871704 -278.063166) (xy 135.879599 -278.111743) (xy 135.880094 -278.13635)
			(xy 136.209036 -278.13635) (xy 136.212996 -278.087296) (xy 136.224773 -278.039512) (xy 136.244064 -277.994236)
			(xy 136.270367 -277.95264) (xy 136.303002 -277.915803) (xy 136.341123 -277.884678) (xy 136.383744 -277.860071)
			(xy 136.42976 -277.842619) (xy 136.477979 -277.832775) (xy 136.527154 -277.830794) (xy 136.576009 -277.836726)
			(xy 136.62328 -277.850418) (xy 136.667742 -277.871516) (xy 136.708245 -277.899472) (xy 136.743738 -277.933564)
			(xy 136.773303 -277.972908) (xy 136.796174 -278.016485) (xy 136.811758 -278.063166) (xy 136.819653 -278.111743)
			(xy 136.820148 -278.13635) (xy 137.148836 -278.13635) (xy 137.152796 -278.087296) (xy 137.164573 -278.039512)
			(xy 137.183864 -277.994236) (xy 137.210167 -277.95264) (xy 137.242802 -277.915803) (xy 137.280923 -277.884678)
			(xy 137.323544 -277.860071) (xy 137.36956 -277.842619) (xy 137.417779 -277.832775) (xy 137.466954 -277.830794)
			(xy 137.515809 -277.836726) (xy 137.56308 -277.850418) (xy 137.607542 -277.871516) (xy 137.648045 -277.899472)
			(xy 137.683538 -277.933564) (xy 137.713103 -277.972908) (xy 137.735974 -278.016485) (xy 137.751558 -278.063166)
			(xy 137.759453 -278.111743) (xy 137.759948 -278.13635) (xy 138.08889 -278.13635) (xy 138.09285 -278.087296)
			(xy 138.104627 -278.039512) (xy 138.123918 -277.994236) (xy 138.150221 -277.95264) (xy 138.182856 -277.915803)
			(xy 138.220977 -277.884678) (xy 138.263598 -277.860071) (xy 138.309614 -277.842619) (xy 138.357833 -277.832775)
			(xy 138.407008 -277.830794) (xy 138.455863 -277.836726) (xy 138.503134 -277.850418) (xy 138.547596 -277.871516)
			(xy 138.588099 -277.899472) (xy 138.623592 -277.933564) (xy 138.653157 -277.972908) (xy 138.676028 -278.016485)
			(xy 138.691612 -278.063166) (xy 138.699507 -278.111743) (xy 138.700002 -278.13635) (xy 139.028944 -278.13635)
			(xy 139.032904 -278.087296) (xy 139.044681 -278.039512) (xy 139.063972 -277.994236) (xy 139.090275 -277.95264)
			(xy 139.12291 -277.915803) (xy 139.161031 -277.884678) (xy 139.203652 -277.860071) (xy 139.249668 -277.842619)
			(xy 139.297887 -277.832775) (xy 139.347062 -277.830794) (xy 139.395917 -277.836726) (xy 139.443188 -277.850418)
			(xy 139.48765 -277.871516) (xy 139.528153 -277.899472) (xy 139.563646 -277.933564) (xy 139.593211 -277.972908)
			(xy 139.616082 -278.016485) (xy 139.631666 -278.063166) (xy 139.639561 -278.111743) (xy 139.640056 -278.13635)
			(xy 139.639561 -278.160957) (xy 139.631666 -278.209534) (xy 139.616082 -278.256215) (xy 139.593211 -278.299792)
			(xy 139.563646 -278.339136) (xy 139.528153 -278.373228) (xy 139.48765 -278.401184) (xy 139.443188 -278.422282)
			(xy 139.395917 -278.435974) (xy 139.347062 -278.441906) (xy 139.297887 -278.439925) (xy 139.249668 -278.430081)
			(xy 139.203652 -278.412629) (xy 139.161031 -278.388022) (xy 139.12291 -278.356897) (xy 139.090275 -278.32006)
			(xy 139.063972 -278.278464) (xy 139.044681 -278.233188) (xy 139.032904 -278.185404) (xy 139.028944 -278.13635)
			(xy 138.700002 -278.13635) (xy 138.699507 -278.160957) (xy 138.691612 -278.209534) (xy 138.676028 -278.256215)
			(xy 138.653157 -278.299792) (xy 138.623592 -278.339136) (xy 138.588099 -278.373228) (xy 138.547596 -278.401184)
			(xy 138.503134 -278.422282) (xy 138.455863 -278.435974) (xy 138.407008 -278.441906) (xy 138.357833 -278.439925)
			(xy 138.309614 -278.430081) (xy 138.263598 -278.412629) (xy 138.220977 -278.388022) (xy 138.182856 -278.356897)
			(xy 138.150221 -278.32006) (xy 138.123918 -278.278464) (xy 138.104627 -278.233188) (xy 138.09285 -278.185404)
			(xy 138.08889 -278.13635) (xy 137.759948 -278.13635) (xy 137.759453 -278.160957) (xy 137.751558 -278.209534)
			(xy 137.735974 -278.256215) (xy 137.713103 -278.299792) (xy 137.683538 -278.339136) (xy 137.648045 -278.373228)
			(xy 137.607542 -278.401184) (xy 137.56308 -278.422282) (xy 137.515809 -278.435974) (xy 137.466954 -278.441906)
			(xy 137.417779 -278.439925) (xy 137.36956 -278.430081) (xy 137.323544 -278.412629) (xy 137.280923 -278.388022)
			(xy 137.242802 -278.356897) (xy 137.210167 -278.32006) (xy 137.183864 -278.278464) (xy 137.164573 -278.233188)
			(xy 137.152796 -278.185404) (xy 137.148836 -278.13635) (xy 136.820148 -278.13635) (xy 136.819653 -278.160957)
			(xy 136.811758 -278.209534) (xy 136.796174 -278.256215) (xy 136.773303 -278.299792) (xy 136.743738 -278.339136)
			(xy 136.708245 -278.373228) (xy 136.667742 -278.401184) (xy 136.62328 -278.422282) (xy 136.576009 -278.435974)
			(xy 136.527154 -278.441906) (xy 136.477979 -278.439925) (xy 136.42976 -278.430081) (xy 136.383744 -278.412629)
			(xy 136.341123 -278.388022) (xy 136.303002 -278.356897) (xy 136.270367 -278.32006) (xy 136.244064 -278.278464)
			(xy 136.224773 -278.233188) (xy 136.212996 -278.185404) (xy 136.209036 -278.13635) (xy 135.880094 -278.13635)
			(xy 135.879599 -278.160957) (xy 135.871704 -278.209534) (xy 135.85612 -278.256215) (xy 135.833249 -278.299792)
			(xy 135.803684 -278.339136) (xy 135.768191 -278.373228) (xy 135.727688 -278.401184) (xy 135.683226 -278.422282)
			(xy 135.635955 -278.435974) (xy 135.5871 -278.441906) (xy 135.537925 -278.439925) (xy 135.489706 -278.430081)
			(xy 135.44369 -278.412629) (xy 135.401069 -278.388022) (xy 135.362948 -278.356897) (xy 135.330313 -278.32006)
			(xy 135.30401 -278.278464) (xy 135.284719 -278.233188) (xy 135.272942 -278.185404) (xy 135.268982 -278.13635)
			(xy 134.94004 -278.13635) (xy 134.939545 -278.160957) (xy 134.93165 -278.209534) (xy 134.916066 -278.256215)
			(xy 134.893195 -278.299792) (xy 134.86363 -278.339136) (xy 134.828137 -278.373228) (xy 134.787634 -278.401184)
			(xy 134.743172 -278.422282) (xy 134.695901 -278.435974) (xy 134.647046 -278.441906) (xy 134.597871 -278.439925)
			(xy 134.549652 -278.430081) (xy 134.503636 -278.412629) (xy 134.461015 -278.388022) (xy 134.422894 -278.356897)
			(xy 134.390259 -278.32006) (xy 134.363956 -278.278464) (xy 134.344665 -278.233188) (xy 134.332888 -278.185404)
			(xy 134.328928 -278.13635) (xy 133.999986 -278.13635) (xy 133.999491 -278.160957) (xy 133.991596 -278.209534)
			(xy 133.976012 -278.256215) (xy 133.953141 -278.299792) (xy 133.923576 -278.339136) (xy 133.888083 -278.373228)
			(xy 133.84758 -278.401184) (xy 133.803118 -278.422282) (xy 133.755847 -278.435974) (xy 133.706992 -278.441906)
			(xy 133.657817 -278.439925) (xy 133.609598 -278.430081) (xy 133.563582 -278.412629) (xy 133.520961 -278.388022)
			(xy 133.48284 -278.356897) (xy 133.450205 -278.32006) (xy 133.423902 -278.278464) (xy 133.404611 -278.233188)
			(xy 133.392834 -278.185404) (xy 133.388874 -278.13635) (xy 133.0706 -278.13635) (xy 133.070088 -278.161796)
			(xy 133.061924 -278.21203) (xy 133.045808 -278.260304) (xy 133.022157 -278.305367) (xy 132.991584 -278.346053)
			(xy 132.95488 -278.381308) (xy 132.912996 -278.410218) (xy 132.867017 -278.432035) (xy 132.818133 -278.446195)
			(xy 132.767612 -278.452329) (xy 132.71676 -278.45028) (xy 132.666896 -278.4401) (xy 132.61931 -278.422053)
			(xy 132.575236 -278.396607) (xy 132.535814 -278.36442) (xy 132.502066 -278.326326) (xy 132.474865 -278.283312)
			(xy 132.454917 -278.236492) (xy 132.442738 -278.187078) (xy 132.438643 -278.13635) (xy 132.130546 -278.13635)
			(xy 132.130034 -278.161796) (xy 132.12187 -278.21203) (xy 132.105754 -278.260304) (xy 132.082103 -278.305367)
			(xy 132.05153 -278.346053) (xy 132.014826 -278.381308) (xy 131.972942 -278.410218) (xy 131.926963 -278.432035)
			(xy 131.878079 -278.446195) (xy 131.827558 -278.452329) (xy 131.776706 -278.45028) (xy 131.726842 -278.4401)
			(xy 131.679256 -278.422053) (xy 131.635182 -278.396607) (xy 131.59576 -278.36442) (xy 131.562012 -278.326326)
			(xy 131.534811 -278.283312) (xy 131.514863 -278.236492) (xy 131.502684 -278.187078) (xy 131.498589 -278.13635)
			(xy 131.180078 -278.13635) (xy 131.179583 -278.160957) (xy 131.171688 -278.209534) (xy 131.156104 -278.256215)
			(xy 131.133233 -278.299792) (xy 131.103668 -278.339136) (xy 131.068175 -278.373228) (xy 131.027672 -278.401184)
			(xy 130.98321 -278.422282) (xy 130.935939 -278.435974) (xy 130.887084 -278.441906) (xy 130.837909 -278.439925)
			(xy 130.78969 -278.430081) (xy 130.743674 -278.412629) (xy 130.701053 -278.388022) (xy 130.662932 -278.356897)
			(xy 130.630297 -278.32006) (xy 130.603994 -278.278464) (xy 130.584703 -278.233188) (xy 130.572926 -278.185404)
			(xy 130.568966 -278.13635) (xy 130.250438 -278.13635) (xy 130.249926 -278.161796) (xy 130.241762 -278.21203)
			(xy 130.225646 -278.260304) (xy 130.201995 -278.305367) (xy 130.171422 -278.346053) (xy 130.134718 -278.381308)
			(xy 130.092834 -278.410218) (xy 130.046855 -278.432035) (xy 129.997971 -278.446195) (xy 129.94745 -278.452329)
			(xy 129.896598 -278.45028) (xy 129.846734 -278.4401) (xy 129.799148 -278.422053) (xy 129.755074 -278.396607)
			(xy 129.715652 -278.36442) (xy 129.681904 -278.326326) (xy 129.654703 -278.283312) (xy 129.634755 -278.236492)
			(xy 129.622576 -278.187078) (xy 129.618481 -278.13635) (xy 129.29997 -278.13635) (xy 129.299475 -278.160957)
			(xy 129.29158 -278.209534) (xy 129.275996 -278.256215) (xy 129.253125 -278.299792) (xy 129.22356 -278.339136)
			(xy 129.188067 -278.373228) (xy 129.147564 -278.401184) (xy 129.103102 -278.422282) (xy 129.055831 -278.435974)
			(xy 129.006976 -278.441906) (xy 128.957801 -278.439925) (xy 128.909582 -278.430081) (xy 128.863566 -278.412629)
			(xy 128.820945 -278.388022) (xy 128.782824 -278.356897) (xy 128.750189 -278.32006) (xy 128.723886 -278.278464)
			(xy 128.704595 -278.233188) (xy 128.692818 -278.185404) (xy 128.688858 -278.13635) (xy 128.370584 -278.13635)
			(xy 128.370072 -278.161796) (xy 128.361908 -278.21203) (xy 128.345792 -278.260304) (xy 128.322141 -278.305367)
			(xy 128.291568 -278.346053) (xy 128.254864 -278.381308) (xy 128.21298 -278.410218) (xy 128.167001 -278.432035)
			(xy 128.118117 -278.446195) (xy 128.067596 -278.452329) (xy 128.016744 -278.45028) (xy 127.96688 -278.4401)
			(xy 127.919294 -278.422053) (xy 127.87522 -278.396607) (xy 127.835798 -278.36442) (xy 127.80205 -278.326326)
			(xy 127.774849 -278.283312) (xy 127.754901 -278.236492) (xy 127.742722 -278.187078) (xy 127.738627 -278.13635)
			(xy 127.543814 -278.13635) (xy 127.543814 -278.257) (xy 127.543864 -278.261072) (xy 127.545135 -278.269116)
			(xy 127.546354 -278.273002) (xy 127.54991 -278.283416) (xy 127.55118 -278.28748) (xy 127.55753 -278.30018)
			(xy 127.559816 -278.303482) (xy 127.56007 -278.303736) (xy 127.568706 -278.316182) (xy 127.587955 -278.344858)
			(xy 127.623289 -278.404208) (xy 127.639318 -278.4348) (xy 127.664932 -278.486345) (xy 127.706671 -278.59362)
			(xy 127.72263 -278.648922) (xy 127.72517 -278.65832) (xy 127.747014 -278.68753) (xy 127.754634 -278.69261)
			(xy 127.773124 -278.705479) (xy 127.806467 -278.73577) (xy 127.835004 -278.770627) (xy 127.858116 -278.809294)
			(xy 127.875304 -278.850934) (xy 127.881126 -278.872696) (xy 127.881634 -278.875236) (xy 127.883158 -278.882094)
			(xy 127.885284 -278.892219) (xy 127.888336 -278.912683) (xy 127.889254 -278.922988) (xy 127.889254 -278.923242)
			(xy 127.890016 -278.931878) (xy 127.896331 -278.946356) (xy 128.208527 -278.946356) (xy 128.212622 -278.895628)
			(xy 128.224801 -278.846214) (xy 128.244749 -278.799394) (xy 128.27195 -278.75638) (xy 128.305698 -278.718286)
			(xy 128.34512 -278.686099) (xy 128.389194 -278.660653) (xy 128.43678 -278.642606) (xy 128.486644 -278.632426)
			(xy 128.537496 -278.630377) (xy 128.588017 -278.636511) (xy 128.636901 -278.650671) (xy 128.68288 -278.672488)
			(xy 128.724764 -278.701398) (xy 128.761468 -278.736653) (xy 128.792041 -278.777339) (xy 128.815692 -278.822402)
			(xy 128.831808 -278.870676) (xy 128.839972 -278.92091) (xy 128.840484 -278.946356) (xy 129.148581 -278.946356)
			(xy 129.152676 -278.895628) (xy 129.164855 -278.846214) (xy 129.184803 -278.799394) (xy 129.212004 -278.75638)
			(xy 129.245752 -278.718286) (xy 129.285174 -278.686099) (xy 129.329248 -278.660653) (xy 129.376834 -278.642606)
			(xy 129.426698 -278.632426) (xy 129.47755 -278.630377) (xy 129.528071 -278.636511) (xy 129.576955 -278.650671)
			(xy 129.622934 -278.672488) (xy 129.664818 -278.701398) (xy 129.701522 -278.736653) (xy 129.732095 -278.777339)
			(xy 129.755746 -278.822402) (xy 129.771862 -278.870676) (xy 129.780026 -278.92091) (xy 129.780538 -278.946356)
			(xy 130.099066 -278.946356) (xy 130.103026 -278.897302) (xy 130.114803 -278.849518) (xy 130.134094 -278.804242)
			(xy 130.160397 -278.762646) (xy 130.193032 -278.725809) (xy 130.231153 -278.694684) (xy 130.273774 -278.670077)
			(xy 130.31979 -278.652625) (xy 130.368009 -278.642781) (xy 130.417184 -278.6408) (xy 130.466039 -278.646732)
			(xy 130.51331 -278.660424) (xy 130.557772 -278.681522) (xy 130.598275 -278.709478) (xy 130.633768 -278.74357)
			(xy 130.663333 -278.782914) (xy 130.686204 -278.826491) (xy 130.701788 -278.873172) (xy 130.709683 -278.921749)
			(xy 130.710178 -278.946356) (xy 131.028435 -278.946356) (xy 131.03253 -278.895628) (xy 131.044709 -278.846214)
			(xy 131.064657 -278.799394) (xy 131.091858 -278.75638) (xy 131.125606 -278.718286) (xy 131.165028 -278.686099)
			(xy 131.209102 -278.660653) (xy 131.256688 -278.642606) (xy 131.306552 -278.632426) (xy 131.357404 -278.630377)
			(xy 131.407925 -278.636511) (xy 131.456809 -278.650671) (xy 131.502788 -278.672488) (xy 131.544672 -278.701398)
			(xy 131.581376 -278.736653) (xy 131.611949 -278.777339) (xy 131.6356 -278.822402) (xy 131.651716 -278.870676)
			(xy 131.65988 -278.92091) (xy 131.660392 -278.946356) (xy 131.97892 -278.946356) (xy 131.98288 -278.897302)
			(xy 131.994657 -278.849518) (xy 132.013948 -278.804242) (xy 132.040251 -278.762646) (xy 132.072886 -278.725809)
			(xy 132.111007 -278.694684) (xy 132.153628 -278.670077) (xy 132.199644 -278.652625) (xy 132.247863 -278.642781)
			(xy 132.297038 -278.6408) (xy 132.345893 -278.646732) (xy 132.393164 -278.660424) (xy 132.437626 -278.681522)
			(xy 132.478129 -278.709478) (xy 132.513622 -278.74357) (xy 132.543187 -278.782914) (xy 132.566058 -278.826491)
			(xy 132.581642 -278.873172) (xy 132.589537 -278.921749) (xy 132.590032 -278.946356) (xy 132.908543 -278.946356)
			(xy 132.912638 -278.895628) (xy 132.924817 -278.846214) (xy 132.944765 -278.799394) (xy 132.971966 -278.75638)
			(xy 133.005714 -278.718286) (xy 133.045136 -278.686099) (xy 133.08921 -278.660653) (xy 133.136796 -278.642606)
			(xy 133.18666 -278.632426) (xy 133.237512 -278.630377) (xy 133.288033 -278.636511) (xy 133.336917 -278.650671)
			(xy 133.382896 -278.672488) (xy 133.42478 -278.701398) (xy 133.461484 -278.736653) (xy 133.492057 -278.777339)
			(xy 133.515708 -278.822402) (xy 133.531824 -278.870676) (xy 133.539988 -278.92091) (xy 133.5405 -278.946356)
			(xy 133.859028 -278.946356) (xy 133.862988 -278.897302) (xy 133.874765 -278.849518) (xy 133.894056 -278.804242)
			(xy 133.920359 -278.762646) (xy 133.952994 -278.725809) (xy 133.991115 -278.694684) (xy 134.033736 -278.670077)
			(xy 134.079752 -278.652625) (xy 134.127971 -278.642781) (xy 134.177146 -278.6408) (xy 134.226001 -278.646732)
			(xy 134.273272 -278.660424) (xy 134.317734 -278.681522) (xy 134.358237 -278.709478) (xy 134.39373 -278.74357)
			(xy 134.423295 -278.782914) (xy 134.446166 -278.826491) (xy 134.46175 -278.873172) (xy 134.469645 -278.921749)
			(xy 134.47014 -278.946356) (xy 134.798828 -278.946356) (xy 134.802788 -278.897302) (xy 134.814565 -278.849518)
			(xy 134.833856 -278.804242) (xy 134.860159 -278.762646) (xy 134.892794 -278.725809) (xy 134.930915 -278.694684)
			(xy 134.973536 -278.670077) (xy 135.019552 -278.652625) (xy 135.067771 -278.642781) (xy 135.116946 -278.6408)
			(xy 135.165801 -278.646732) (xy 135.213072 -278.660424) (xy 135.257534 -278.681522) (xy 135.298037 -278.709478)
			(xy 135.33353 -278.74357) (xy 135.363095 -278.782914) (xy 135.385966 -278.826491) (xy 135.40155 -278.873172)
			(xy 135.409445 -278.921749) (xy 135.40994 -278.946356) (xy 135.738882 -278.946356) (xy 135.742842 -278.897302)
			(xy 135.754619 -278.849518) (xy 135.77391 -278.804242) (xy 135.800213 -278.762646) (xy 135.832848 -278.725809)
			(xy 135.870969 -278.694684) (xy 135.91359 -278.670077) (xy 135.959606 -278.652625) (xy 136.007825 -278.642781)
			(xy 136.057 -278.6408) (xy 136.105855 -278.646732) (xy 136.153126 -278.660424) (xy 136.197588 -278.681522)
			(xy 136.238091 -278.709478) (xy 136.273584 -278.74357) (xy 136.303149 -278.782914) (xy 136.32602 -278.826491)
			(xy 136.341604 -278.873172) (xy 136.349499 -278.921749) (xy 136.349994 -278.946356) (xy 136.678936 -278.946356)
			(xy 136.682896 -278.897302) (xy 136.694673 -278.849518) (xy 136.713964 -278.804242) (xy 136.740267 -278.762646)
			(xy 136.772902 -278.725809) (xy 136.811023 -278.694684) (xy 136.853644 -278.670077) (xy 136.89966 -278.652625)
			(xy 136.947879 -278.642781) (xy 136.997054 -278.6408) (xy 137.045909 -278.646732) (xy 137.09318 -278.660424)
			(xy 137.137642 -278.681522) (xy 137.178145 -278.709478) (xy 137.213638 -278.74357) (xy 137.243203 -278.782914)
			(xy 137.266074 -278.826491) (xy 137.281658 -278.873172) (xy 137.289553 -278.921749) (xy 137.290048 -278.946356)
			(xy 137.61899 -278.946356) (xy 137.62295 -278.897302) (xy 137.634727 -278.849518) (xy 137.654018 -278.804242)
			(xy 137.680321 -278.762646) (xy 137.712956 -278.725809) (xy 137.751077 -278.694684) (xy 137.793698 -278.670077)
			(xy 137.839714 -278.652625) (xy 137.887933 -278.642781) (xy 137.937108 -278.6408) (xy 137.985963 -278.646732)
			(xy 138.033234 -278.660424) (xy 138.077696 -278.681522) (xy 138.118199 -278.709478) (xy 138.153692 -278.74357)
			(xy 138.183257 -278.782914) (xy 138.206128 -278.826491) (xy 138.221712 -278.873172) (xy 138.229607 -278.921749)
			(xy 138.230102 -278.946356) (xy 138.559044 -278.946356) (xy 138.563004 -278.897302) (xy 138.574781 -278.849518)
			(xy 138.594072 -278.804242) (xy 138.620375 -278.762646) (xy 138.65301 -278.725809) (xy 138.691131 -278.694684)
			(xy 138.733752 -278.670077) (xy 138.779768 -278.652625) (xy 138.827987 -278.642781) (xy 138.877162 -278.6408)
			(xy 138.926017 -278.646732) (xy 138.973288 -278.660424) (xy 139.01775 -278.681522) (xy 139.058253 -278.709478)
			(xy 139.093746 -278.74357) (xy 139.123311 -278.782914) (xy 139.146182 -278.826491) (xy 139.161766 -278.873172)
			(xy 139.169661 -278.921749) (xy 139.170156 -278.946356) (xy 139.498844 -278.946356) (xy 139.502804 -278.897302)
			(xy 139.514581 -278.849518) (xy 139.533872 -278.804242) (xy 139.560175 -278.762646) (xy 139.59281 -278.725809)
			(xy 139.630931 -278.694684) (xy 139.673552 -278.670077) (xy 139.719568 -278.652625) (xy 139.767787 -278.642781)
			(xy 139.816962 -278.6408) (xy 139.865817 -278.646732) (xy 139.913088 -278.660424) (xy 139.95755 -278.681522)
			(xy 139.998053 -278.709478) (xy 140.033546 -278.74357) (xy 140.063111 -278.782914) (xy 140.085982 -278.826491)
			(xy 140.101566 -278.873172) (xy 140.109461 -278.921749) (xy 140.109956 -278.946356) (xy 140.109461 -278.970963)
			(xy 140.101566 -279.01954) (xy 140.085982 -279.066221) (xy 140.063111 -279.109798) (xy 140.033546 -279.149142)
			(xy 139.998053 -279.183234) (xy 139.95755 -279.21119) (xy 139.913088 -279.232288) (xy 139.865817 -279.24598)
			(xy 139.816962 -279.251912) (xy 139.767787 -279.249931) (xy 139.719568 -279.240087) (xy 139.673552 -279.222635)
			(xy 139.630931 -279.198028) (xy 139.59281 -279.166903) (xy 139.560175 -279.130066) (xy 139.533872 -279.08847)
			(xy 139.514581 -279.043194) (xy 139.502804 -278.99541) (xy 139.498844 -278.946356) (xy 139.170156 -278.946356)
			(xy 139.169661 -278.970963) (xy 139.161766 -279.01954) (xy 139.146182 -279.066221) (xy 139.123311 -279.109798)
			(xy 139.093746 -279.149142) (xy 139.058253 -279.183234) (xy 139.01775 -279.21119) (xy 138.973288 -279.232288)
			(xy 138.926017 -279.24598) (xy 138.877162 -279.251912) (xy 138.827987 -279.249931) (xy 138.779768 -279.240087)
			(xy 138.733752 -279.222635) (xy 138.691131 -279.198028) (xy 138.65301 -279.166903) (xy 138.620375 -279.130066)
			(xy 138.594072 -279.08847) (xy 138.574781 -279.043194) (xy 138.563004 -278.99541) (xy 138.559044 -278.946356)
			(xy 138.230102 -278.946356) (xy 138.229607 -278.970963) (xy 138.221712 -279.01954) (xy 138.206128 -279.066221)
			(xy 138.183257 -279.109798) (xy 138.153692 -279.149142) (xy 138.118199 -279.183234) (xy 138.077696 -279.21119)
			(xy 138.033234 -279.232288) (xy 137.985963 -279.24598) (xy 137.937108 -279.251912) (xy 137.887933 -279.249931)
			(xy 137.839714 -279.240087) (xy 137.793698 -279.222635) (xy 137.751077 -279.198028) (xy 137.712956 -279.166903)
			(xy 137.680321 -279.130066) (xy 137.654018 -279.08847) (xy 137.634727 -279.043194) (xy 137.62295 -278.99541)
			(xy 137.61899 -278.946356) (xy 137.290048 -278.946356) (xy 137.289553 -278.970963) (xy 137.281658 -279.01954)
			(xy 137.266074 -279.066221) (xy 137.243203 -279.109798) (xy 137.213638 -279.149142) (xy 137.178145 -279.183234)
			(xy 137.137642 -279.21119) (xy 137.09318 -279.232288) (xy 137.045909 -279.24598) (xy 136.997054 -279.251912)
			(xy 136.947879 -279.249931) (xy 136.89966 -279.240087) (xy 136.853644 -279.222635) (xy 136.811023 -279.198028)
			(xy 136.772902 -279.166903) (xy 136.740267 -279.130066) (xy 136.713964 -279.08847) (xy 136.694673 -279.043194)
			(xy 136.682896 -278.99541) (xy 136.678936 -278.946356) (xy 136.349994 -278.946356) (xy 136.349499 -278.970963)
			(xy 136.341604 -279.01954) (xy 136.32602 -279.066221) (xy 136.303149 -279.109798) (xy 136.273584 -279.149142)
			(xy 136.238091 -279.183234) (xy 136.197588 -279.21119) (xy 136.153126 -279.232288) (xy 136.105855 -279.24598)
			(xy 136.057 -279.251912) (xy 136.007825 -279.249931) (xy 135.959606 -279.240087) (xy 135.91359 -279.222635)
			(xy 135.870969 -279.198028) (xy 135.832848 -279.166903) (xy 135.800213 -279.130066) (xy 135.77391 -279.08847)
			(xy 135.754619 -279.043194) (xy 135.742842 -278.99541) (xy 135.738882 -278.946356) (xy 135.40994 -278.946356)
			(xy 135.409445 -278.970963) (xy 135.40155 -279.01954) (xy 135.385966 -279.066221) (xy 135.363095 -279.109798)
			(xy 135.33353 -279.149142) (xy 135.298037 -279.183234) (xy 135.257534 -279.21119) (xy 135.213072 -279.232288)
			(xy 135.165801 -279.24598) (xy 135.116946 -279.251912) (xy 135.067771 -279.249931) (xy 135.019552 -279.240087)
			(xy 134.973536 -279.222635) (xy 134.930915 -279.198028) (xy 134.892794 -279.166903) (xy 134.860159 -279.130066)
			(xy 134.833856 -279.08847) (xy 134.814565 -279.043194) (xy 134.802788 -278.99541) (xy 134.798828 -278.946356)
			(xy 134.47014 -278.946356) (xy 134.469645 -278.970963) (xy 134.46175 -279.01954) (xy 134.446166 -279.066221)
			(xy 134.423295 -279.109798) (xy 134.39373 -279.149142) (xy 134.358237 -279.183234) (xy 134.317734 -279.21119)
			(xy 134.273272 -279.232288) (xy 134.226001 -279.24598) (xy 134.177146 -279.251912) (xy 134.127971 -279.249931)
			(xy 134.079752 -279.240087) (xy 134.033736 -279.222635) (xy 133.991115 -279.198028) (xy 133.952994 -279.166903)
			(xy 133.920359 -279.130066) (xy 133.894056 -279.08847) (xy 133.874765 -279.043194) (xy 133.862988 -278.99541)
			(xy 133.859028 -278.946356) (xy 133.5405 -278.946356) (xy 133.539988 -278.971802) (xy 133.531824 -279.022036)
			(xy 133.515708 -279.07031) (xy 133.492057 -279.115373) (xy 133.461484 -279.156059) (xy 133.42478 -279.191314)
			(xy 133.382896 -279.220224) (xy 133.336917 -279.242041) (xy 133.288033 -279.256201) (xy 133.237512 -279.262335)
			(xy 133.18666 -279.260286) (xy 133.136796 -279.250106) (xy 133.08921 -279.232059) (xy 133.045136 -279.206613)
			(xy 133.005714 -279.174426) (xy 132.971966 -279.136332) (xy 132.944765 -279.093318) (xy 132.924817 -279.046498)
			(xy 132.912638 -278.997084) (xy 132.908543 -278.946356) (xy 132.590032 -278.946356) (xy 132.589537 -278.970963)
			(xy 132.581642 -279.01954) (xy 132.566058 -279.066221) (xy 132.543187 -279.109798) (xy 132.513622 -279.149142)
			(xy 132.478129 -279.183234) (xy 132.437626 -279.21119) (xy 132.393164 -279.232288) (xy 132.345893 -279.24598)
			(xy 132.297038 -279.251912) (xy 132.247863 -279.249931) (xy 132.199644 -279.240087) (xy 132.153628 -279.222635)
			(xy 132.111007 -279.198028) (xy 132.072886 -279.166903) (xy 132.040251 -279.130066) (xy 132.013948 -279.08847)
			(xy 131.994657 -279.043194) (xy 131.98288 -278.99541) (xy 131.97892 -278.946356) (xy 131.660392 -278.946356)
			(xy 131.65988 -278.971802) (xy 131.651716 -279.022036) (xy 131.6356 -279.07031) (xy 131.611949 -279.115373)
			(xy 131.581376 -279.156059) (xy 131.544672 -279.191314) (xy 131.502788 -279.220224) (xy 131.456809 -279.242041)
			(xy 131.407925 -279.256201) (xy 131.357404 -279.262335) (xy 131.306552 -279.260286) (xy 131.256688 -279.250106)
			(xy 131.209102 -279.232059) (xy 131.165028 -279.206613) (xy 131.125606 -279.174426) (xy 131.091858 -279.136332)
			(xy 131.064657 -279.093318) (xy 131.044709 -279.046498) (xy 131.03253 -278.997084) (xy 131.028435 -278.946356)
			(xy 130.710178 -278.946356) (xy 130.709683 -278.970963) (xy 130.701788 -279.01954) (xy 130.686204 -279.066221)
			(xy 130.663333 -279.109798) (xy 130.633768 -279.149142) (xy 130.598275 -279.183234) (xy 130.557772 -279.21119)
			(xy 130.51331 -279.232288) (xy 130.466039 -279.24598) (xy 130.417184 -279.251912) (xy 130.368009 -279.249931)
			(xy 130.31979 -279.240087) (xy 130.273774 -279.222635) (xy 130.231153 -279.198028) (xy 130.193032 -279.166903)
			(xy 130.160397 -279.130066) (xy 130.134094 -279.08847) (xy 130.114803 -279.043194) (xy 130.103026 -278.99541)
			(xy 130.099066 -278.946356) (xy 129.780538 -278.946356) (xy 129.780026 -278.971802) (xy 129.771862 -279.022036)
			(xy 129.755746 -279.07031) (xy 129.732095 -279.115373) (xy 129.701522 -279.156059) (xy 129.664818 -279.191314)
			(xy 129.622934 -279.220224) (xy 129.576955 -279.242041) (xy 129.528071 -279.256201) (xy 129.47755 -279.262335)
			(xy 129.426698 -279.260286) (xy 129.376834 -279.250106) (xy 129.329248 -279.232059) (xy 129.285174 -279.206613)
			(xy 129.245752 -279.174426) (xy 129.212004 -279.136332) (xy 129.184803 -279.093318) (xy 129.164855 -279.046498)
			(xy 129.152676 -278.997084) (xy 129.148581 -278.946356) (xy 128.840484 -278.946356) (xy 128.839972 -278.971802)
			(xy 128.831808 -279.022036) (xy 128.815692 -279.07031) (xy 128.792041 -279.115373) (xy 128.761468 -279.156059)
			(xy 128.724764 -279.191314) (xy 128.68288 -279.220224) (xy 128.636901 -279.242041) (xy 128.588017 -279.256201)
			(xy 128.537496 -279.262335) (xy 128.486644 -279.260286) (xy 128.43678 -279.250106) (xy 128.389194 -279.232059)
			(xy 128.34512 -279.206613) (xy 128.305698 -279.174426) (xy 128.27195 -279.136332) (xy 128.244749 -279.093318)
			(xy 128.224801 -279.046498) (xy 128.212622 -278.997084) (xy 128.208527 -278.946356) (xy 127.896331 -278.946356)
			(xy 127.90043 -278.955754) (xy 127.903224 -278.959818) (xy 127.910336 -278.970232) (xy 127.913384 -278.97328)
			(xy 127.943221 -279.004311) (xy 127.998572 -279.070252) (xy 128.04869 -279.140253) (xy 128.093279 -279.213899)
			(xy 128.132075 -279.290755) (xy 128.148842 -279.330404) (xy 128.16109 -279.360761) (xy 128.182439 -279.42265)
			(xy 128.191514 -279.454102) (xy 128.194526 -279.463429) (xy 128.206408 -279.478993) (xy 128.214628 -279.484328)
			(xy 128.234637 -279.496565) (xy 128.271131 -279.526022) (xy 128.302868 -279.560553) (xy 128.329149 -279.599398)
			(xy 128.349396 -279.641702) (xy 128.363164 -279.686536) (xy 128.37015 -279.732912) (xy 128.370584 -279.756362)
			(xy 128.688858 -279.756362) (xy 128.692818 -279.707308) (xy 128.704595 -279.659524) (xy 128.723886 -279.614248)
			(xy 128.750189 -279.572652) (xy 128.782824 -279.535815) (xy 128.820945 -279.50469) (xy 128.863566 -279.480083)
			(xy 128.909582 -279.462631) (xy 128.957801 -279.452787) (xy 129.006976 -279.450806) (xy 129.055831 -279.456738)
			(xy 129.103102 -279.47043) (xy 129.147564 -279.491528) (xy 129.188067 -279.519484) (xy 129.22356 -279.553576)
			(xy 129.253125 -279.59292) (xy 129.275996 -279.636497) (xy 129.29158 -279.683178) (xy 129.299475 -279.731755)
			(xy 129.29997 -279.756362) (xy 129.618481 -279.756362) (xy 129.622576 -279.705634) (xy 129.634755 -279.65622)
			(xy 129.654703 -279.6094) (xy 129.681904 -279.566386) (xy 129.715652 -279.528292) (xy 129.755074 -279.496105)
			(xy 129.799148 -279.470659) (xy 129.846734 -279.452612) (xy 129.896598 -279.442432) (xy 129.94745 -279.440383)
			(xy 129.997971 -279.446517) (xy 130.046855 -279.460677) (xy 130.092834 -279.482494) (xy 130.134718 -279.511404)
			(xy 130.171422 -279.546659) (xy 130.201995 -279.587345) (xy 130.225646 -279.632408) (xy 130.241762 -279.680682)
			(xy 130.249926 -279.730916) (xy 130.250438 -279.756362) (xy 130.568966 -279.756362) (xy 130.572926 -279.707308)
			(xy 130.584703 -279.659524) (xy 130.603994 -279.614248) (xy 130.630297 -279.572652) (xy 130.662932 -279.535815)
			(xy 130.701053 -279.50469) (xy 130.743674 -279.480083) (xy 130.78969 -279.462631) (xy 130.837909 -279.452787)
			(xy 130.887084 -279.450806) (xy 130.935939 -279.456738) (xy 130.98321 -279.47043) (xy 131.027672 -279.491528)
			(xy 131.068175 -279.519484) (xy 131.103668 -279.553576) (xy 131.133233 -279.59292) (xy 131.156104 -279.636497)
			(xy 131.171688 -279.683178) (xy 131.179583 -279.731755) (xy 131.180078 -279.756362) (xy 131.498589 -279.756362)
			(xy 131.502684 -279.705634) (xy 131.514863 -279.65622) (xy 131.534811 -279.6094) (xy 131.562012 -279.566386)
			(xy 131.59576 -279.528292) (xy 131.635182 -279.496105) (xy 131.679256 -279.470659) (xy 131.726842 -279.452612)
			(xy 131.776706 -279.442432) (xy 131.827558 -279.440383) (xy 131.878079 -279.446517) (xy 131.926963 -279.460677)
			(xy 131.972942 -279.482494) (xy 132.014826 -279.511404) (xy 132.05153 -279.546659) (xy 132.082103 -279.587345)
			(xy 132.105754 -279.632408) (xy 132.12187 -279.680682) (xy 132.130034 -279.730916) (xy 132.130546 -279.756362)
			(xy 132.438643 -279.756362) (xy 132.442738 -279.705634) (xy 132.454917 -279.65622) (xy 132.474865 -279.6094)
			(xy 132.502066 -279.566386) (xy 132.535814 -279.528292) (xy 132.575236 -279.496105) (xy 132.61931 -279.470659)
			(xy 132.666896 -279.452612) (xy 132.71676 -279.442432) (xy 132.767612 -279.440383) (xy 132.818133 -279.446517)
			(xy 132.867017 -279.460677) (xy 132.912996 -279.482494) (xy 132.95488 -279.511404) (xy 132.991584 -279.546659)
			(xy 133.022157 -279.587345) (xy 133.045808 -279.632408) (xy 133.061924 -279.680682) (xy 133.070088 -279.730916)
			(xy 133.0706 -279.756362) (xy 133.388874 -279.756362) (xy 133.392834 -279.707308) (xy 133.404611 -279.659524)
			(xy 133.423902 -279.614248) (xy 133.450205 -279.572652) (xy 133.48284 -279.535815) (xy 133.520961 -279.50469)
			(xy 133.563582 -279.480083) (xy 133.609598 -279.462631) (xy 133.657817 -279.452787) (xy 133.706992 -279.450806)
			(xy 133.755847 -279.456738) (xy 133.803118 -279.47043) (xy 133.84758 -279.491528) (xy 133.888083 -279.519484)
			(xy 133.923576 -279.553576) (xy 133.953141 -279.59292) (xy 133.976012 -279.636497) (xy 133.991596 -279.683178)
			(xy 133.999491 -279.731755) (xy 133.999986 -279.756362) (xy 134.328928 -279.756362) (xy 134.332888 -279.707308)
			(xy 134.344665 -279.659524) (xy 134.363956 -279.614248) (xy 134.390259 -279.572652) (xy 134.422894 -279.535815)
			(xy 134.461015 -279.50469) (xy 134.503636 -279.480083) (xy 134.549652 -279.462631) (xy 134.597871 -279.452787)
			(xy 134.647046 -279.450806) (xy 134.695901 -279.456738) (xy 134.743172 -279.47043) (xy 134.787634 -279.491528)
			(xy 134.828137 -279.519484) (xy 134.86363 -279.553576) (xy 134.893195 -279.59292) (xy 134.916066 -279.636497)
			(xy 134.93165 -279.683178) (xy 134.939545 -279.731755) (xy 134.94004 -279.756362) (xy 135.268982 -279.756362)
			(xy 135.272942 -279.707308) (xy 135.284719 -279.659524) (xy 135.30401 -279.614248) (xy 135.330313 -279.572652)
			(xy 135.362948 -279.535815) (xy 135.401069 -279.50469) (xy 135.44369 -279.480083) (xy 135.489706 -279.462631)
			(xy 135.537925 -279.452787) (xy 135.5871 -279.450806) (xy 135.635955 -279.456738) (xy 135.683226 -279.47043)
			(xy 135.727688 -279.491528) (xy 135.768191 -279.519484) (xy 135.803684 -279.553576) (xy 135.833249 -279.59292)
			(xy 135.85612 -279.636497) (xy 135.871704 -279.683178) (xy 135.879599 -279.731755) (xy 135.880094 -279.756362)
			(xy 136.209036 -279.756362) (xy 136.212996 -279.707308) (xy 136.224773 -279.659524) (xy 136.244064 -279.614248)
			(xy 136.270367 -279.572652) (xy 136.303002 -279.535815) (xy 136.341123 -279.50469) (xy 136.383744 -279.480083)
			(xy 136.42976 -279.462631) (xy 136.477979 -279.452787) (xy 136.527154 -279.450806) (xy 136.576009 -279.456738)
			(xy 136.62328 -279.47043) (xy 136.667742 -279.491528) (xy 136.708245 -279.519484) (xy 136.743738 -279.553576)
			(xy 136.773303 -279.59292) (xy 136.796174 -279.636497) (xy 136.811758 -279.683178) (xy 136.819653 -279.731755)
			(xy 136.820148 -279.756362) (xy 137.148836 -279.756362) (xy 137.152796 -279.707308) (xy 137.164573 -279.659524)
			(xy 137.183864 -279.614248) (xy 137.210167 -279.572652) (xy 137.242802 -279.535815) (xy 137.280923 -279.50469)
			(xy 137.323544 -279.480083) (xy 137.36956 -279.462631) (xy 137.417779 -279.452787) (xy 137.466954 -279.450806)
			(xy 137.515809 -279.456738) (xy 137.56308 -279.47043) (xy 137.607542 -279.491528) (xy 137.648045 -279.519484)
			(xy 137.683538 -279.553576) (xy 137.713103 -279.59292) (xy 137.735974 -279.636497) (xy 137.751558 -279.683178)
			(xy 137.759453 -279.731755) (xy 137.759948 -279.756362) (xy 138.08889 -279.756362) (xy 138.09285 -279.707308)
			(xy 138.104627 -279.659524) (xy 138.123918 -279.614248) (xy 138.150221 -279.572652) (xy 138.182856 -279.535815)
			(xy 138.220977 -279.50469) (xy 138.263598 -279.480083) (xy 138.309614 -279.462631) (xy 138.357833 -279.452787)
			(xy 138.407008 -279.450806) (xy 138.455863 -279.456738) (xy 138.503134 -279.47043) (xy 138.547596 -279.491528)
			(xy 138.588099 -279.519484) (xy 138.623592 -279.553576) (xy 138.653157 -279.59292) (xy 138.676028 -279.636497)
			(xy 138.691612 -279.683178) (xy 138.699507 -279.731755) (xy 138.700002 -279.756362) (xy 139.028944 -279.756362)
			(xy 139.032904 -279.707308) (xy 139.044681 -279.659524) (xy 139.063972 -279.614248) (xy 139.090275 -279.572652)
			(xy 139.12291 -279.535815) (xy 139.161031 -279.50469) (xy 139.203652 -279.480083) (xy 139.249668 -279.462631)
			(xy 139.297887 -279.452787) (xy 139.347062 -279.450806) (xy 139.395917 -279.456738) (xy 139.443188 -279.47043)
			(xy 139.48765 -279.491528) (xy 139.528153 -279.519484) (xy 139.563646 -279.553576) (xy 139.593211 -279.59292)
			(xy 139.616082 -279.636497) (xy 139.631666 -279.683178) (xy 139.639561 -279.731755) (xy 139.640056 -279.756362)
			(xy 139.639561 -279.780969) (xy 139.631666 -279.829546) (xy 139.616082 -279.876227) (xy 139.593211 -279.919804)
			(xy 139.563646 -279.959148) (xy 139.528153 -279.99324) (xy 139.48765 -280.021196) (xy 139.443188 -280.042294)
			(xy 139.395917 -280.055986) (xy 139.347062 -280.061918) (xy 139.297887 -280.059937) (xy 139.249668 -280.050093)
			(xy 139.203652 -280.032641) (xy 139.161031 -280.008034) (xy 139.12291 -279.976909) (xy 139.090275 -279.940072)
			(xy 139.063972 -279.898476) (xy 139.044681 -279.8532) (xy 139.032904 -279.805416) (xy 139.028944 -279.756362)
			(xy 138.700002 -279.756362) (xy 138.699507 -279.780969) (xy 138.691612 -279.829546) (xy 138.676028 -279.876227)
			(xy 138.653157 -279.919804) (xy 138.623592 -279.959148) (xy 138.588099 -279.99324) (xy 138.547596 -280.021196)
			(xy 138.503134 -280.042294) (xy 138.455863 -280.055986) (xy 138.407008 -280.061918) (xy 138.357833 -280.059937)
			(xy 138.309614 -280.050093) (xy 138.263598 -280.032641) (xy 138.220977 -280.008034) (xy 138.182856 -279.976909)
			(xy 138.150221 -279.940072) (xy 138.123918 -279.898476) (xy 138.104627 -279.8532) (xy 138.09285 -279.805416)
			(xy 138.08889 -279.756362) (xy 137.759948 -279.756362) (xy 137.759453 -279.780969) (xy 137.751558 -279.829546)
			(xy 137.735974 -279.876227) (xy 137.713103 -279.919804) (xy 137.683538 -279.959148) (xy 137.648045 -279.99324)
			(xy 137.607542 -280.021196) (xy 137.56308 -280.042294) (xy 137.515809 -280.055986) (xy 137.466954 -280.061918)
			(xy 137.417779 -280.059937) (xy 137.36956 -280.050093) (xy 137.323544 -280.032641) (xy 137.280923 -280.008034)
			(xy 137.242802 -279.976909) (xy 137.210167 -279.940072) (xy 137.183864 -279.898476) (xy 137.164573 -279.8532)
			(xy 137.152796 -279.805416) (xy 137.148836 -279.756362) (xy 136.820148 -279.756362) (xy 136.819653 -279.780969)
			(xy 136.811758 -279.829546) (xy 136.796174 -279.876227) (xy 136.773303 -279.919804) (xy 136.743738 -279.959148)
			(xy 136.708245 -279.99324) (xy 136.667742 -280.021196) (xy 136.62328 -280.042294) (xy 136.576009 -280.055986)
			(xy 136.527154 -280.061918) (xy 136.477979 -280.059937) (xy 136.42976 -280.050093) (xy 136.383744 -280.032641)
			(xy 136.341123 -280.008034) (xy 136.303002 -279.976909) (xy 136.270367 -279.940072) (xy 136.244064 -279.898476)
			(xy 136.224773 -279.8532) (xy 136.212996 -279.805416) (xy 136.209036 -279.756362) (xy 135.880094 -279.756362)
			(xy 135.879599 -279.780969) (xy 135.871704 -279.829546) (xy 135.85612 -279.876227) (xy 135.833249 -279.919804)
			(xy 135.803684 -279.959148) (xy 135.768191 -279.99324) (xy 135.727688 -280.021196) (xy 135.683226 -280.042294)
			(xy 135.635955 -280.055986) (xy 135.5871 -280.061918) (xy 135.537925 -280.059937) (xy 135.489706 -280.050093)
			(xy 135.44369 -280.032641) (xy 135.401069 -280.008034) (xy 135.362948 -279.976909) (xy 135.330313 -279.940072)
			(xy 135.30401 -279.898476) (xy 135.284719 -279.8532) (xy 135.272942 -279.805416) (xy 135.268982 -279.756362)
			(xy 134.94004 -279.756362) (xy 134.939545 -279.780969) (xy 134.93165 -279.829546) (xy 134.916066 -279.876227)
			(xy 134.893195 -279.919804) (xy 134.86363 -279.959148) (xy 134.828137 -279.99324) (xy 134.787634 -280.021196)
			(xy 134.743172 -280.042294) (xy 134.695901 -280.055986) (xy 134.647046 -280.061918) (xy 134.597871 -280.059937)
			(xy 134.549652 -280.050093) (xy 134.503636 -280.032641) (xy 134.461015 -280.008034) (xy 134.422894 -279.976909)
			(xy 134.390259 -279.940072) (xy 134.363956 -279.898476) (xy 134.344665 -279.8532) (xy 134.332888 -279.805416)
			(xy 134.328928 -279.756362) (xy 133.999986 -279.756362) (xy 133.999491 -279.780969) (xy 133.991596 -279.829546)
			(xy 133.976012 -279.876227) (xy 133.953141 -279.919804) (xy 133.923576 -279.959148) (xy 133.888083 -279.99324)
			(xy 133.84758 -280.021196) (xy 133.803118 -280.042294) (xy 133.755847 -280.055986) (xy 133.706992 -280.061918)
			(xy 133.657817 -280.059937) (xy 133.609598 -280.050093) (xy 133.563582 -280.032641) (xy 133.520961 -280.008034)
			(xy 133.48284 -279.976909) (xy 133.450205 -279.940072) (xy 133.423902 -279.898476) (xy 133.404611 -279.8532)
			(xy 133.392834 -279.805416) (xy 133.388874 -279.756362) (xy 133.0706 -279.756362) (xy 133.070088 -279.781808)
			(xy 133.061924 -279.832042) (xy 133.045808 -279.880316) (xy 133.022157 -279.925379) (xy 132.991584 -279.966065)
			(xy 132.95488 -280.00132) (xy 132.912996 -280.03023) (xy 132.867017 -280.052047) (xy 132.818133 -280.066207)
			(xy 132.767612 -280.072341) (xy 132.71676 -280.070292) (xy 132.666896 -280.060112) (xy 132.61931 -280.042065)
			(xy 132.575236 -280.016619) (xy 132.535814 -279.984432) (xy 132.502066 -279.946338) (xy 132.474865 -279.903324)
			(xy 132.454917 -279.856504) (xy 132.442738 -279.80709) (xy 132.438643 -279.756362) (xy 132.130546 -279.756362)
			(xy 132.130034 -279.781808) (xy 132.12187 -279.832042) (xy 132.105754 -279.880316) (xy 132.082103 -279.925379)
			(xy 132.05153 -279.966065) (xy 132.014826 -280.00132) (xy 131.972942 -280.03023) (xy 131.926963 -280.052047)
			(xy 131.878079 -280.066207) (xy 131.827558 -280.072341) (xy 131.776706 -280.070292) (xy 131.726842 -280.060112)
			(xy 131.679256 -280.042065) (xy 131.635182 -280.016619) (xy 131.59576 -279.984432) (xy 131.562012 -279.946338)
			(xy 131.534811 -279.903324) (xy 131.514863 -279.856504) (xy 131.502684 -279.80709) (xy 131.498589 -279.756362)
			(xy 131.180078 -279.756362) (xy 131.179583 -279.780969) (xy 131.171688 -279.829546) (xy 131.156104 -279.876227)
			(xy 131.133233 -279.919804) (xy 131.103668 -279.959148) (xy 131.068175 -279.99324) (xy 131.027672 -280.021196)
			(xy 130.98321 -280.042294) (xy 130.935939 -280.055986) (xy 130.887084 -280.061918) (xy 130.837909 -280.059937)
			(xy 130.78969 -280.050093) (xy 130.743674 -280.032641) (xy 130.701053 -280.008034) (xy 130.662932 -279.976909)
			(xy 130.630297 -279.940072) (xy 130.603994 -279.898476) (xy 130.584703 -279.8532) (xy 130.572926 -279.805416)
			(xy 130.568966 -279.756362) (xy 130.250438 -279.756362) (xy 130.249926 -279.781808) (xy 130.241762 -279.832042)
			(xy 130.225646 -279.880316) (xy 130.201995 -279.925379) (xy 130.171422 -279.966065) (xy 130.134718 -280.00132)
			(xy 130.092834 -280.03023) (xy 130.046855 -280.052047) (xy 129.997971 -280.066207) (xy 129.94745 -280.072341)
			(xy 129.896598 -280.070292) (xy 129.846734 -280.060112) (xy 129.799148 -280.042065) (xy 129.755074 -280.016619)
			(xy 129.715652 -279.984432) (xy 129.681904 -279.946338) (xy 129.654703 -279.903324) (xy 129.634755 -279.856504)
			(xy 129.622576 -279.80709) (xy 129.618481 -279.756362) (xy 129.29997 -279.756362) (xy 129.299475 -279.780969)
			(xy 129.29158 -279.829546) (xy 129.275996 -279.876227) (xy 129.253125 -279.919804) (xy 129.22356 -279.959148)
			(xy 129.188067 -279.99324) (xy 129.147564 -280.021196) (xy 129.103102 -280.042294) (xy 129.055831 -280.055986)
			(xy 129.006976 -280.061918) (xy 128.957801 -280.059937) (xy 128.909582 -280.050093) (xy 128.863566 -280.032641)
			(xy 128.820945 -280.008034) (xy 128.782824 -279.976909) (xy 128.750189 -279.940072) (xy 128.723886 -279.898476)
			(xy 128.704595 -279.8532) (xy 128.692818 -279.805416) (xy 128.688858 -279.756362) (xy 128.370584 -279.756362)
			(xy 128.370136 -279.779812) (xy 128.363159 -279.82619) (xy 128.349397 -279.871025) (xy 128.329153 -279.913331)
			(xy 128.302872 -279.952176) (xy 128.271134 -279.986705) (xy 128.234637 -280.016159) (xy 128.214628 -280.028396)
			(xy 128.206438 -280.033768) (xy 128.194547 -280.04931) (xy 128.191514 -280.058622) (xy 128.182436 -280.090073)
			(xy 128.161084 -280.151961) (xy 128.148842 -280.18232) (xy 128.132084 -280.221973) (xy 128.093294 -280.298834)
			(xy 128.048708 -280.372484) (xy 127.99859 -280.442487) (xy 127.943237 -280.508428) (xy 127.913384 -280.539444)
			(xy 127.910336 -280.542492) (xy 127.903224 -280.552906) (xy 127.90043 -280.55697) (xy 127.896331 -280.566368)
			(xy 128.208527 -280.566368) (xy 128.212622 -280.51564) (xy 128.224801 -280.466226) (xy 128.244749 -280.419406)
			(xy 128.27195 -280.376392) (xy 128.305698 -280.338298) (xy 128.34512 -280.306111) (xy 128.389194 -280.280665)
			(xy 128.43678 -280.262618) (xy 128.486644 -280.252438) (xy 128.537496 -280.250389) (xy 128.588017 -280.256523)
			(xy 128.636901 -280.270683) (xy 128.68288 -280.2925) (xy 128.724764 -280.32141) (xy 128.761468 -280.356665)
			(xy 128.792041 -280.397351) (xy 128.815692 -280.442414) (xy 128.831808 -280.490688) (xy 128.839972 -280.540922)
			(xy 128.840484 -280.566368) (xy 129.148581 -280.566368) (xy 129.152676 -280.51564) (xy 129.164855 -280.466226)
			(xy 129.184803 -280.419406) (xy 129.212004 -280.376392) (xy 129.245752 -280.338298) (xy 129.285174 -280.306111)
			(xy 129.329248 -280.280665) (xy 129.376834 -280.262618) (xy 129.426698 -280.252438) (xy 129.47755 -280.250389)
			(xy 129.528071 -280.256523) (xy 129.576955 -280.270683) (xy 129.622934 -280.2925) (xy 129.664818 -280.32141)
			(xy 129.701522 -280.356665) (xy 129.732095 -280.397351) (xy 129.755746 -280.442414) (xy 129.771862 -280.490688)
			(xy 129.780026 -280.540922) (xy 129.780538 -280.566368) (xy 130.099066 -280.566368) (xy 130.103026 -280.517314)
			(xy 130.114803 -280.46953) (xy 130.134094 -280.424254) (xy 130.160397 -280.382658) (xy 130.193032 -280.345821)
			(xy 130.231153 -280.314696) (xy 130.273774 -280.290089) (xy 130.31979 -280.272637) (xy 130.368009 -280.262793)
			(xy 130.417184 -280.260812) (xy 130.466039 -280.266744) (xy 130.51331 -280.280436) (xy 130.557772 -280.301534)
			(xy 130.598275 -280.32949) (xy 130.633768 -280.363582) (xy 130.663333 -280.402926) (xy 130.686204 -280.446503)
			(xy 130.701788 -280.493184) (xy 130.709683 -280.541761) (xy 130.710178 -280.566368) (xy 131.028435 -280.566368)
			(xy 131.03253 -280.51564) (xy 131.044709 -280.466226) (xy 131.064657 -280.419406) (xy 131.091858 -280.376392)
			(xy 131.125606 -280.338298) (xy 131.165028 -280.306111) (xy 131.209102 -280.280665) (xy 131.256688 -280.262618)
			(xy 131.306552 -280.252438) (xy 131.357404 -280.250389) (xy 131.407925 -280.256523) (xy 131.456809 -280.270683)
			(xy 131.502788 -280.2925) (xy 131.544672 -280.32141) (xy 131.581376 -280.356665) (xy 131.611949 -280.397351)
			(xy 131.6356 -280.442414) (xy 131.651716 -280.490688) (xy 131.65988 -280.540922) (xy 131.660392 -280.566368)
			(xy 131.97892 -280.566368) (xy 131.98288 -280.517314) (xy 131.994657 -280.46953) (xy 132.013948 -280.424254)
			(xy 132.040251 -280.382658) (xy 132.072886 -280.345821) (xy 132.111007 -280.314696) (xy 132.153628 -280.290089)
			(xy 132.199644 -280.272637) (xy 132.247863 -280.262793) (xy 132.297038 -280.260812) (xy 132.345893 -280.266744)
			(xy 132.393164 -280.280436) (xy 132.437626 -280.301534) (xy 132.478129 -280.32949) (xy 132.513622 -280.363582)
			(xy 132.543187 -280.402926) (xy 132.566058 -280.446503) (xy 132.581642 -280.493184) (xy 132.589537 -280.541761)
			(xy 132.590032 -280.566368) (xy 132.908543 -280.566368) (xy 132.912638 -280.51564) (xy 132.924817 -280.466226)
			(xy 132.944765 -280.419406) (xy 132.971966 -280.376392) (xy 133.005714 -280.338298) (xy 133.045136 -280.306111)
			(xy 133.08921 -280.280665) (xy 133.136796 -280.262618) (xy 133.18666 -280.252438) (xy 133.237512 -280.250389)
			(xy 133.288033 -280.256523) (xy 133.336917 -280.270683) (xy 133.382896 -280.2925) (xy 133.42478 -280.32141)
			(xy 133.461484 -280.356665) (xy 133.492057 -280.397351) (xy 133.515708 -280.442414) (xy 133.531824 -280.490688)
			(xy 133.539988 -280.540922) (xy 133.5405 -280.566368) (xy 133.859028 -280.566368) (xy 133.862988 -280.517314)
			(xy 133.874765 -280.46953) (xy 133.894056 -280.424254) (xy 133.920359 -280.382658) (xy 133.952994 -280.345821)
			(xy 133.991115 -280.314696) (xy 134.033736 -280.290089) (xy 134.079752 -280.272637) (xy 134.127971 -280.262793)
			(xy 134.177146 -280.260812) (xy 134.226001 -280.266744) (xy 134.273272 -280.280436) (xy 134.317734 -280.301534)
			(xy 134.358237 -280.32949) (xy 134.39373 -280.363582) (xy 134.423295 -280.402926) (xy 134.446166 -280.446503)
			(xy 134.46175 -280.493184) (xy 134.469645 -280.541761) (xy 134.47014 -280.566368) (xy 134.798828 -280.566368)
			(xy 134.802788 -280.517314) (xy 134.814565 -280.46953) (xy 134.833856 -280.424254) (xy 134.860159 -280.382658)
			(xy 134.892794 -280.345821) (xy 134.930915 -280.314696) (xy 134.973536 -280.290089) (xy 135.019552 -280.272637)
			(xy 135.067771 -280.262793) (xy 135.116946 -280.260812) (xy 135.165801 -280.266744) (xy 135.213072 -280.280436)
			(xy 135.257534 -280.301534) (xy 135.298037 -280.32949) (xy 135.33353 -280.363582) (xy 135.363095 -280.402926)
			(xy 135.385966 -280.446503) (xy 135.40155 -280.493184) (xy 135.409445 -280.541761) (xy 135.40994 -280.566368)
			(xy 135.738882 -280.566368) (xy 135.742842 -280.517314) (xy 135.754619 -280.46953) (xy 135.77391 -280.424254)
			(xy 135.800213 -280.382658) (xy 135.832848 -280.345821) (xy 135.870969 -280.314696) (xy 135.91359 -280.290089)
			(xy 135.959606 -280.272637) (xy 136.007825 -280.262793) (xy 136.057 -280.260812) (xy 136.105855 -280.266744)
			(xy 136.153126 -280.280436) (xy 136.197588 -280.301534) (xy 136.238091 -280.32949) (xy 136.273584 -280.363582)
			(xy 136.303149 -280.402926) (xy 136.32602 -280.446503) (xy 136.341604 -280.493184) (xy 136.349499 -280.541761)
			(xy 136.349994 -280.566368) (xy 136.678936 -280.566368) (xy 136.682896 -280.517314) (xy 136.694673 -280.46953)
			(xy 136.713964 -280.424254) (xy 136.740267 -280.382658) (xy 136.772902 -280.345821) (xy 136.811023 -280.314696)
			(xy 136.853644 -280.290089) (xy 136.89966 -280.272637) (xy 136.947879 -280.262793) (xy 136.997054 -280.260812)
			(xy 137.045909 -280.266744) (xy 137.09318 -280.280436) (xy 137.137642 -280.301534) (xy 137.178145 -280.32949)
			(xy 137.213638 -280.363582) (xy 137.243203 -280.402926) (xy 137.266074 -280.446503) (xy 137.281658 -280.493184)
			(xy 137.289553 -280.541761) (xy 137.290048 -280.566368) (xy 137.61899 -280.566368) (xy 137.62295 -280.517314)
			(xy 137.634727 -280.46953) (xy 137.654018 -280.424254) (xy 137.680321 -280.382658) (xy 137.712956 -280.345821)
			(xy 137.751077 -280.314696) (xy 137.793698 -280.290089) (xy 137.839714 -280.272637) (xy 137.887933 -280.262793)
			(xy 137.937108 -280.260812) (xy 137.985963 -280.266744) (xy 138.033234 -280.280436) (xy 138.077696 -280.301534)
			(xy 138.118199 -280.32949) (xy 138.153692 -280.363582) (xy 138.183257 -280.402926) (xy 138.206128 -280.446503)
			(xy 138.221712 -280.493184) (xy 138.229607 -280.541761) (xy 138.230102 -280.566368) (xy 138.559044 -280.566368)
			(xy 138.563004 -280.517314) (xy 138.574781 -280.46953) (xy 138.594072 -280.424254) (xy 138.620375 -280.382658)
			(xy 138.65301 -280.345821) (xy 138.691131 -280.314696) (xy 138.733752 -280.290089) (xy 138.779768 -280.272637)
			(xy 138.827987 -280.262793) (xy 138.877162 -280.260812) (xy 138.926017 -280.266744) (xy 138.973288 -280.280436)
			(xy 139.01775 -280.301534) (xy 139.058253 -280.32949) (xy 139.093746 -280.363582) (xy 139.123311 -280.402926)
			(xy 139.146182 -280.446503) (xy 139.161766 -280.493184) (xy 139.169661 -280.541761) (xy 139.170156 -280.566368)
			(xy 139.498844 -280.566368) (xy 139.502804 -280.517314) (xy 139.514581 -280.46953) (xy 139.533872 -280.424254)
			(xy 139.560175 -280.382658) (xy 139.59281 -280.345821) (xy 139.630931 -280.314696) (xy 139.673552 -280.290089)
			(xy 139.719568 -280.272637) (xy 139.767787 -280.262793) (xy 139.816962 -280.260812) (xy 139.865817 -280.266744)
			(xy 139.913088 -280.280436) (xy 139.95755 -280.301534) (xy 139.998053 -280.32949) (xy 140.033546 -280.363582)
			(xy 140.063111 -280.402926) (xy 140.085982 -280.446503) (xy 140.101566 -280.493184) (xy 140.109461 -280.541761)
			(xy 140.109956 -280.566368) (xy 140.109461 -280.590975) (xy 140.101566 -280.639552) (xy 140.085982 -280.686233)
			(xy 140.063111 -280.72981) (xy 140.033546 -280.769154) (xy 139.998053 -280.803246) (xy 139.95755 -280.831202)
			(xy 139.913088 -280.8523) (xy 139.865817 -280.865992) (xy 139.816962 -280.871924) (xy 139.767787 -280.869943)
			(xy 139.719568 -280.860099) (xy 139.673552 -280.842647) (xy 139.630931 -280.81804) (xy 139.59281 -280.786915)
			(xy 139.560175 -280.750078) (xy 139.533872 -280.708482) (xy 139.514581 -280.663206) (xy 139.502804 -280.615422)
			(xy 139.498844 -280.566368) (xy 139.170156 -280.566368) (xy 139.169661 -280.590975) (xy 139.161766 -280.639552)
			(xy 139.146182 -280.686233) (xy 139.123311 -280.72981) (xy 139.093746 -280.769154) (xy 139.058253 -280.803246)
			(xy 139.01775 -280.831202) (xy 138.973288 -280.8523) (xy 138.926017 -280.865992) (xy 138.877162 -280.871924)
			(xy 138.827987 -280.869943) (xy 138.779768 -280.860099) (xy 138.733752 -280.842647) (xy 138.691131 -280.81804)
			(xy 138.65301 -280.786915) (xy 138.620375 -280.750078) (xy 138.594072 -280.708482) (xy 138.574781 -280.663206)
			(xy 138.563004 -280.615422) (xy 138.559044 -280.566368) (xy 138.230102 -280.566368) (xy 138.229607 -280.590975)
			(xy 138.221712 -280.639552) (xy 138.206128 -280.686233) (xy 138.183257 -280.72981) (xy 138.153692 -280.769154)
			(xy 138.118199 -280.803246) (xy 138.077696 -280.831202) (xy 138.033234 -280.8523) (xy 137.985963 -280.865992)
			(xy 137.937108 -280.871924) (xy 137.887933 -280.869943) (xy 137.839714 -280.860099) (xy 137.793698 -280.842647)
			(xy 137.751077 -280.81804) (xy 137.712956 -280.786915) (xy 137.680321 -280.750078) (xy 137.654018 -280.708482)
			(xy 137.634727 -280.663206) (xy 137.62295 -280.615422) (xy 137.61899 -280.566368) (xy 137.290048 -280.566368)
			(xy 137.289553 -280.590975) (xy 137.281658 -280.639552) (xy 137.266074 -280.686233) (xy 137.243203 -280.72981)
			(xy 137.213638 -280.769154) (xy 137.178145 -280.803246) (xy 137.137642 -280.831202) (xy 137.09318 -280.8523)
			(xy 137.045909 -280.865992) (xy 136.997054 -280.871924) (xy 136.947879 -280.869943) (xy 136.89966 -280.860099)
			(xy 136.853644 -280.842647) (xy 136.811023 -280.81804) (xy 136.772902 -280.786915) (xy 136.740267 -280.750078)
			(xy 136.713964 -280.708482) (xy 136.694673 -280.663206) (xy 136.682896 -280.615422) (xy 136.678936 -280.566368)
			(xy 136.349994 -280.566368) (xy 136.349499 -280.590975) (xy 136.341604 -280.639552) (xy 136.32602 -280.686233)
			(xy 136.303149 -280.72981) (xy 136.273584 -280.769154) (xy 136.238091 -280.803246) (xy 136.197588 -280.831202)
			(xy 136.153126 -280.8523) (xy 136.105855 -280.865992) (xy 136.057 -280.871924) (xy 136.007825 -280.869943)
			(xy 135.959606 -280.860099) (xy 135.91359 -280.842647) (xy 135.870969 -280.81804) (xy 135.832848 -280.786915)
			(xy 135.800213 -280.750078) (xy 135.77391 -280.708482) (xy 135.754619 -280.663206) (xy 135.742842 -280.615422)
			(xy 135.738882 -280.566368) (xy 135.40994 -280.566368) (xy 135.409445 -280.590975) (xy 135.40155 -280.639552)
			(xy 135.385966 -280.686233) (xy 135.363095 -280.72981) (xy 135.33353 -280.769154) (xy 135.298037 -280.803246)
			(xy 135.257534 -280.831202) (xy 135.213072 -280.8523) (xy 135.165801 -280.865992) (xy 135.116946 -280.871924)
			(xy 135.067771 -280.869943) (xy 135.019552 -280.860099) (xy 134.973536 -280.842647) (xy 134.930915 -280.81804)
			(xy 134.892794 -280.786915) (xy 134.860159 -280.750078) (xy 134.833856 -280.708482) (xy 134.814565 -280.663206)
			(xy 134.802788 -280.615422) (xy 134.798828 -280.566368) (xy 134.47014 -280.566368) (xy 134.469645 -280.590975)
			(xy 134.46175 -280.639552) (xy 134.446166 -280.686233) (xy 134.423295 -280.72981) (xy 134.39373 -280.769154)
			(xy 134.358237 -280.803246) (xy 134.317734 -280.831202) (xy 134.273272 -280.8523) (xy 134.226001 -280.865992)
			(xy 134.177146 -280.871924) (xy 134.127971 -280.869943) (xy 134.079752 -280.860099) (xy 134.033736 -280.842647)
			(xy 133.991115 -280.81804) (xy 133.952994 -280.786915) (xy 133.920359 -280.750078) (xy 133.894056 -280.708482)
			(xy 133.874765 -280.663206) (xy 133.862988 -280.615422) (xy 133.859028 -280.566368) (xy 133.5405 -280.566368)
			(xy 133.539988 -280.591814) (xy 133.531824 -280.642048) (xy 133.515708 -280.690322) (xy 133.492057 -280.735385)
			(xy 133.461484 -280.776071) (xy 133.42478 -280.811326) (xy 133.382896 -280.840236) (xy 133.336917 -280.862053)
			(xy 133.288033 -280.876213) (xy 133.237512 -280.882347) (xy 133.18666 -280.880298) (xy 133.136796 -280.870118)
			(xy 133.08921 -280.852071) (xy 133.045136 -280.826625) (xy 133.005714 -280.794438) (xy 132.971966 -280.756344)
			(xy 132.944765 -280.71333) (xy 132.924817 -280.66651) (xy 132.912638 -280.617096) (xy 132.908543 -280.566368)
			(xy 132.590032 -280.566368) (xy 132.589537 -280.590975) (xy 132.581642 -280.639552) (xy 132.566058 -280.686233)
			(xy 132.543187 -280.72981) (xy 132.513622 -280.769154) (xy 132.478129 -280.803246) (xy 132.437626 -280.831202)
			(xy 132.393164 -280.8523) (xy 132.345893 -280.865992) (xy 132.297038 -280.871924) (xy 132.247863 -280.869943)
			(xy 132.199644 -280.860099) (xy 132.153628 -280.842647) (xy 132.111007 -280.81804) (xy 132.072886 -280.786915)
			(xy 132.040251 -280.750078) (xy 132.013948 -280.708482) (xy 131.994657 -280.663206) (xy 131.98288 -280.615422)
			(xy 131.97892 -280.566368) (xy 131.660392 -280.566368) (xy 131.65988 -280.591814) (xy 131.651716 -280.642048)
			(xy 131.6356 -280.690322) (xy 131.611949 -280.735385) (xy 131.581376 -280.776071) (xy 131.544672 -280.811326)
			(xy 131.502788 -280.840236) (xy 131.456809 -280.862053) (xy 131.407925 -280.876213) (xy 131.357404 -280.882347)
			(xy 131.306552 -280.880298) (xy 131.256688 -280.870118) (xy 131.209102 -280.852071) (xy 131.165028 -280.826625)
			(xy 131.125606 -280.794438) (xy 131.091858 -280.756344) (xy 131.064657 -280.71333) (xy 131.044709 -280.66651)
			(xy 131.03253 -280.617096) (xy 131.028435 -280.566368) (xy 130.710178 -280.566368) (xy 130.709683 -280.590975)
			(xy 130.701788 -280.639552) (xy 130.686204 -280.686233) (xy 130.663333 -280.72981) (xy 130.633768 -280.769154)
			(xy 130.598275 -280.803246) (xy 130.557772 -280.831202) (xy 130.51331 -280.8523) (xy 130.466039 -280.865992)
			(xy 130.417184 -280.871924) (xy 130.368009 -280.869943) (xy 130.31979 -280.860099) (xy 130.273774 -280.842647)
			(xy 130.231153 -280.81804) (xy 130.193032 -280.786915) (xy 130.160397 -280.750078) (xy 130.134094 -280.708482)
			(xy 130.114803 -280.663206) (xy 130.103026 -280.615422) (xy 130.099066 -280.566368) (xy 129.780538 -280.566368)
			(xy 129.780026 -280.591814) (xy 129.771862 -280.642048) (xy 129.755746 -280.690322) (xy 129.732095 -280.735385)
			(xy 129.701522 -280.776071) (xy 129.664818 -280.811326) (xy 129.622934 -280.840236) (xy 129.576955 -280.862053)
			(xy 129.528071 -280.876213) (xy 129.47755 -280.882347) (xy 129.426698 -280.880298) (xy 129.376834 -280.870118)
			(xy 129.329248 -280.852071) (xy 129.285174 -280.826625) (xy 129.245752 -280.794438) (xy 129.212004 -280.756344)
			(xy 129.184803 -280.71333) (xy 129.164855 -280.66651) (xy 129.152676 -280.617096) (xy 129.148581 -280.566368)
			(xy 128.840484 -280.566368) (xy 128.839972 -280.591814) (xy 128.831808 -280.642048) (xy 128.815692 -280.690322)
			(xy 128.792041 -280.735385) (xy 128.761468 -280.776071) (xy 128.724764 -280.811326) (xy 128.68288 -280.840236)
			(xy 128.636901 -280.862053) (xy 128.588017 -280.876213) (xy 128.537496 -280.882347) (xy 128.486644 -280.880298)
			(xy 128.43678 -280.870118) (xy 128.389194 -280.852071) (xy 128.34512 -280.826625) (xy 128.305698 -280.794438)
			(xy 128.27195 -280.756344) (xy 128.244749 -280.71333) (xy 128.224801 -280.66651) (xy 128.212622 -280.617096)
			(xy 128.208527 -280.566368) (xy 127.896331 -280.566368) (xy 127.890016 -280.580846) (xy 127.889254 -280.589482)
			(xy 127.889254 -280.589736) (xy 127.888342 -280.600042) (xy 127.885292 -280.620507) (xy 127.883158 -280.63063)
			(xy 127.881634 -280.637488) (xy 127.881126 -280.640028) (xy 127.875306 -280.661793) (xy 127.858138 -280.703444)
			(xy 127.835033 -280.742119) (xy 127.806491 -280.776976) (xy 127.773134 -280.807257) (xy 127.754634 -280.820114)
			(xy 127.747014 -280.825194) (xy 127.72517 -280.854404) (xy 127.72263 -280.863802) (xy 127.706664 -280.919102)
			(xy 127.664926 -281.026376) (xy 127.639318 -281.077924) (xy 127.620151 -281.114454) (xy 127.577178 -281.184882)
			(xy 127.553466 -281.21864) (xy 127.54864 -281.225244) (xy 127.543814 -281.239976) (xy 127.543814 -281.376374)
			(xy 127.738627 -281.376374) (xy 127.742722 -281.325646) (xy 127.754901 -281.276232) (xy 127.774849 -281.229412)
			(xy 127.80205 -281.186398) (xy 127.835798 -281.148304) (xy 127.87522 -281.116117) (xy 127.919294 -281.090671)
			(xy 127.96688 -281.072624) (xy 128.016744 -281.062444) (xy 128.067596 -281.060395) (xy 128.118117 -281.066529)
			(xy 128.167001 -281.080689) (xy 128.21298 -281.102506) (xy 128.254864 -281.131416) (xy 128.291568 -281.166671)
			(xy 128.322141 -281.207357) (xy 128.345792 -281.25242) (xy 128.361908 -281.300694) (xy 128.370072 -281.350928)
			(xy 128.370584 -281.376374) (xy 128.688858 -281.376374) (xy 128.692818 -281.32732) (xy 128.704595 -281.279536)
			(xy 128.723886 -281.23426) (xy 128.750189 -281.192664) (xy 128.782824 -281.155827) (xy 128.820945 -281.124702)
			(xy 128.863566 -281.100095) (xy 128.909582 -281.082643) (xy 128.957801 -281.072799) (xy 129.006976 -281.070818)
			(xy 129.055831 -281.07675) (xy 129.103102 -281.090442) (xy 129.147564 -281.11154) (xy 129.188067 -281.139496)
			(xy 129.22356 -281.173588) (xy 129.253125 -281.212932) (xy 129.275996 -281.256509) (xy 129.29158 -281.30319)
			(xy 129.299475 -281.351767) (xy 129.29997 -281.376374) (xy 129.618481 -281.376374) (xy 129.622576 -281.325646)
			(xy 129.634755 -281.276232) (xy 129.654703 -281.229412) (xy 129.681904 -281.186398) (xy 129.715652 -281.148304)
			(xy 129.755074 -281.116117) (xy 129.799148 -281.090671) (xy 129.846734 -281.072624) (xy 129.896598 -281.062444)
			(xy 129.94745 -281.060395) (xy 129.997971 -281.066529) (xy 130.046855 -281.080689) (xy 130.092834 -281.102506)
			(xy 130.134718 -281.131416) (xy 130.171422 -281.166671) (xy 130.201995 -281.207357) (xy 130.225646 -281.25242)
			(xy 130.241762 -281.300694) (xy 130.249926 -281.350928) (xy 130.250438 -281.376374) (xy 130.568966 -281.376374)
			(xy 130.572926 -281.32732) (xy 130.584703 -281.279536) (xy 130.603994 -281.23426) (xy 130.630297 -281.192664)
			(xy 130.662932 -281.155827) (xy 130.701053 -281.124702) (xy 130.743674 -281.100095) (xy 130.78969 -281.082643)
			(xy 130.837909 -281.072799) (xy 130.887084 -281.070818) (xy 130.935939 -281.07675) (xy 130.98321 -281.090442)
			(xy 131.027672 -281.11154) (xy 131.068175 -281.139496) (xy 131.103668 -281.173588) (xy 131.133233 -281.212932)
			(xy 131.156104 -281.256509) (xy 131.171688 -281.30319) (xy 131.179583 -281.351767) (xy 131.180078 -281.376374)
			(xy 131.498589 -281.376374) (xy 131.502684 -281.325646) (xy 131.514863 -281.276232) (xy 131.534811 -281.229412)
			(xy 131.562012 -281.186398) (xy 131.59576 -281.148304) (xy 131.635182 -281.116117) (xy 131.679256 -281.090671)
			(xy 131.726842 -281.072624) (xy 131.776706 -281.062444) (xy 131.827558 -281.060395) (xy 131.878079 -281.066529)
			(xy 131.926963 -281.080689) (xy 131.972942 -281.102506) (xy 132.014826 -281.131416) (xy 132.05153 -281.166671)
			(xy 132.082103 -281.207357) (xy 132.105754 -281.25242) (xy 132.12187 -281.300694) (xy 132.130034 -281.350928)
			(xy 132.130546 -281.376374) (xy 132.438643 -281.376374) (xy 132.442738 -281.325646) (xy 132.454917 -281.276232)
			(xy 132.474865 -281.229412) (xy 132.502066 -281.186398) (xy 132.535814 -281.148304) (xy 132.575236 -281.116117)
			(xy 132.61931 -281.090671) (xy 132.666896 -281.072624) (xy 132.71676 -281.062444) (xy 132.767612 -281.060395)
			(xy 132.818133 -281.066529) (xy 132.867017 -281.080689) (xy 132.912996 -281.102506) (xy 132.95488 -281.131416)
			(xy 132.991584 -281.166671) (xy 133.022157 -281.207357) (xy 133.045808 -281.25242) (xy 133.061924 -281.300694)
			(xy 133.070088 -281.350928) (xy 133.0706 -281.376374) (xy 133.388874 -281.376374) (xy 133.392834 -281.32732)
			(xy 133.404611 -281.279536) (xy 133.423902 -281.23426) (xy 133.450205 -281.192664) (xy 133.48284 -281.155827)
			(xy 133.520961 -281.124702) (xy 133.563582 -281.100095) (xy 133.609598 -281.082643) (xy 133.657817 -281.072799)
			(xy 133.706992 -281.070818) (xy 133.755847 -281.07675) (xy 133.803118 -281.090442) (xy 133.84758 -281.11154)
			(xy 133.888083 -281.139496) (xy 133.923576 -281.173588) (xy 133.953141 -281.212932) (xy 133.976012 -281.256509)
			(xy 133.991596 -281.30319) (xy 133.999491 -281.351767) (xy 133.999986 -281.376374) (xy 134.328928 -281.376374)
			(xy 134.332888 -281.32732) (xy 134.344665 -281.279536) (xy 134.363956 -281.23426) (xy 134.390259 -281.192664)
			(xy 134.422894 -281.155827) (xy 134.461015 -281.124702) (xy 134.503636 -281.100095) (xy 134.549652 -281.082643)
			(xy 134.597871 -281.072799) (xy 134.647046 -281.070818) (xy 134.695901 -281.07675) (xy 134.743172 -281.090442)
			(xy 134.787634 -281.11154) (xy 134.828137 -281.139496) (xy 134.86363 -281.173588) (xy 134.893195 -281.212932)
			(xy 134.916066 -281.256509) (xy 134.93165 -281.30319) (xy 134.939545 -281.351767) (xy 134.94004 -281.376374)
			(xy 135.268982 -281.376374) (xy 135.272942 -281.32732) (xy 135.284719 -281.279536) (xy 135.30401 -281.23426)
			(xy 135.330313 -281.192664) (xy 135.362948 -281.155827) (xy 135.401069 -281.124702) (xy 135.44369 -281.100095)
			(xy 135.489706 -281.082643) (xy 135.537925 -281.072799) (xy 135.5871 -281.070818) (xy 135.635955 -281.07675)
			(xy 135.683226 -281.090442) (xy 135.727688 -281.11154) (xy 135.768191 -281.139496) (xy 135.803684 -281.173588)
			(xy 135.833249 -281.212932) (xy 135.85612 -281.256509) (xy 135.871704 -281.30319) (xy 135.879599 -281.351767)
			(xy 135.880094 -281.376374) (xy 136.209036 -281.376374) (xy 136.212996 -281.32732) (xy 136.224773 -281.279536)
			(xy 136.244064 -281.23426) (xy 136.270367 -281.192664) (xy 136.303002 -281.155827) (xy 136.341123 -281.124702)
			(xy 136.383744 -281.100095) (xy 136.42976 -281.082643) (xy 136.477979 -281.072799) (xy 136.527154 -281.070818)
			(xy 136.576009 -281.07675) (xy 136.62328 -281.090442) (xy 136.667742 -281.11154) (xy 136.708245 -281.139496)
			(xy 136.743738 -281.173588) (xy 136.773303 -281.212932) (xy 136.796174 -281.256509) (xy 136.811758 -281.30319)
			(xy 136.819653 -281.351767) (xy 136.820148 -281.376374) (xy 137.148836 -281.376374) (xy 137.152796 -281.32732)
			(xy 137.164573 -281.279536) (xy 137.183864 -281.23426) (xy 137.210167 -281.192664) (xy 137.242802 -281.155827)
			(xy 137.280923 -281.124702) (xy 137.323544 -281.100095) (xy 137.36956 -281.082643) (xy 137.417779 -281.072799)
			(xy 137.466954 -281.070818) (xy 137.515809 -281.07675) (xy 137.56308 -281.090442) (xy 137.607542 -281.11154)
			(xy 137.648045 -281.139496) (xy 137.683538 -281.173588) (xy 137.713103 -281.212932) (xy 137.735974 -281.256509)
			(xy 137.751558 -281.30319) (xy 137.759453 -281.351767) (xy 137.759948 -281.376374) (xy 138.08889 -281.376374)
			(xy 138.09285 -281.32732) (xy 138.104627 -281.279536) (xy 138.123918 -281.23426) (xy 138.150221 -281.192664)
			(xy 138.182856 -281.155827) (xy 138.220977 -281.124702) (xy 138.263598 -281.100095) (xy 138.309614 -281.082643)
			(xy 138.357833 -281.072799) (xy 138.407008 -281.070818) (xy 138.455863 -281.07675) (xy 138.503134 -281.090442)
			(xy 138.547596 -281.11154) (xy 138.588099 -281.139496) (xy 138.623592 -281.173588) (xy 138.653157 -281.212932)
			(xy 138.676028 -281.256509) (xy 138.691612 -281.30319) (xy 138.699507 -281.351767) (xy 138.700002 -281.376374)
			(xy 139.028944 -281.376374) (xy 139.032904 -281.32732) (xy 139.044681 -281.279536) (xy 139.063972 -281.23426)
			(xy 139.090275 -281.192664) (xy 139.12291 -281.155827) (xy 139.161031 -281.124702) (xy 139.203652 -281.100095)
			(xy 139.249668 -281.082643) (xy 139.297887 -281.072799) (xy 139.347062 -281.070818) (xy 139.395917 -281.07675)
			(xy 139.443188 -281.090442) (xy 139.48765 -281.11154) (xy 139.528153 -281.139496) (xy 139.563646 -281.173588)
			(xy 139.593211 -281.212932) (xy 139.616082 -281.256509) (xy 139.631666 -281.30319) (xy 139.639561 -281.351767)
			(xy 139.640056 -281.376374) (xy 139.639561 -281.400981) (xy 139.631666 -281.449558) (xy 139.616082 -281.496239)
			(xy 139.593211 -281.539816) (xy 139.563646 -281.57916) (xy 139.528153 -281.613252) (xy 139.48765 -281.641208)
			(xy 139.443188 -281.662306) (xy 139.395917 -281.675998) (xy 139.347062 -281.68193) (xy 139.297887 -281.679949)
			(xy 139.249668 -281.670105) (xy 139.203652 -281.652653) (xy 139.161031 -281.628046) (xy 139.12291 -281.596921)
			(xy 139.090275 -281.560084) (xy 139.063972 -281.518488) (xy 139.044681 -281.473212) (xy 139.032904 -281.425428)
			(xy 139.028944 -281.376374) (xy 138.700002 -281.376374) (xy 138.699507 -281.400981) (xy 138.691612 -281.449558)
			(xy 138.676028 -281.496239) (xy 138.653157 -281.539816) (xy 138.623592 -281.57916) (xy 138.588099 -281.613252)
			(xy 138.547596 -281.641208) (xy 138.503134 -281.662306) (xy 138.455863 -281.675998) (xy 138.407008 -281.68193)
			(xy 138.357833 -281.679949) (xy 138.309614 -281.670105) (xy 138.263598 -281.652653) (xy 138.220977 -281.628046)
			(xy 138.182856 -281.596921) (xy 138.150221 -281.560084) (xy 138.123918 -281.518488) (xy 138.104627 -281.473212)
			(xy 138.09285 -281.425428) (xy 138.08889 -281.376374) (xy 137.759948 -281.376374) (xy 137.759453 -281.400981)
			(xy 137.751558 -281.449558) (xy 137.735974 -281.496239) (xy 137.713103 -281.539816) (xy 137.683538 -281.57916)
			(xy 137.648045 -281.613252) (xy 137.607542 -281.641208) (xy 137.56308 -281.662306) (xy 137.515809 -281.675998)
			(xy 137.466954 -281.68193) (xy 137.417779 -281.679949) (xy 137.36956 -281.670105) (xy 137.323544 -281.652653)
			(xy 137.280923 -281.628046) (xy 137.242802 -281.596921) (xy 137.210167 -281.560084) (xy 137.183864 -281.518488)
			(xy 137.164573 -281.473212) (xy 137.152796 -281.425428) (xy 137.148836 -281.376374) (xy 136.820148 -281.376374)
			(xy 136.819653 -281.400981) (xy 136.811758 -281.449558) (xy 136.796174 -281.496239) (xy 136.773303 -281.539816)
			(xy 136.743738 -281.57916) (xy 136.708245 -281.613252) (xy 136.667742 -281.641208) (xy 136.62328 -281.662306)
			(xy 136.576009 -281.675998) (xy 136.527154 -281.68193) (xy 136.477979 -281.679949) (xy 136.42976 -281.670105)
			(xy 136.383744 -281.652653) (xy 136.341123 -281.628046) (xy 136.303002 -281.596921) (xy 136.270367 -281.560084)
			(xy 136.244064 -281.518488) (xy 136.224773 -281.473212) (xy 136.212996 -281.425428) (xy 136.209036 -281.376374)
			(xy 135.880094 -281.376374) (xy 135.879599 -281.400981) (xy 135.871704 -281.449558) (xy 135.85612 -281.496239)
			(xy 135.833249 -281.539816) (xy 135.803684 -281.57916) (xy 135.768191 -281.613252) (xy 135.727688 -281.641208)
			(xy 135.683226 -281.662306) (xy 135.635955 -281.675998) (xy 135.5871 -281.68193) (xy 135.537925 -281.679949)
			(xy 135.489706 -281.670105) (xy 135.44369 -281.652653) (xy 135.401069 -281.628046) (xy 135.362948 -281.596921)
			(xy 135.330313 -281.560084) (xy 135.30401 -281.518488) (xy 135.284719 -281.473212) (xy 135.272942 -281.425428)
			(xy 135.268982 -281.376374) (xy 134.94004 -281.376374) (xy 134.939545 -281.400981) (xy 134.93165 -281.449558)
			(xy 134.916066 -281.496239) (xy 134.893195 -281.539816) (xy 134.86363 -281.57916) (xy 134.828137 -281.613252)
			(xy 134.787634 -281.641208) (xy 134.743172 -281.662306) (xy 134.695901 -281.675998) (xy 134.647046 -281.68193)
			(xy 134.597871 -281.679949) (xy 134.549652 -281.670105) (xy 134.503636 -281.652653) (xy 134.461015 -281.628046)
			(xy 134.422894 -281.596921) (xy 134.390259 -281.560084) (xy 134.363956 -281.518488) (xy 134.344665 -281.473212)
			(xy 134.332888 -281.425428) (xy 134.328928 -281.376374) (xy 133.999986 -281.376374) (xy 133.999491 -281.400981)
			(xy 133.991596 -281.449558) (xy 133.976012 -281.496239) (xy 133.953141 -281.539816) (xy 133.923576 -281.57916)
			(xy 133.888083 -281.613252) (xy 133.84758 -281.641208) (xy 133.803118 -281.662306) (xy 133.755847 -281.675998)
			(xy 133.706992 -281.68193) (xy 133.657817 -281.679949) (xy 133.609598 -281.670105) (xy 133.563582 -281.652653)
			(xy 133.520961 -281.628046) (xy 133.48284 -281.596921) (xy 133.450205 -281.560084) (xy 133.423902 -281.518488)
			(xy 133.404611 -281.473212) (xy 133.392834 -281.425428) (xy 133.388874 -281.376374) (xy 133.0706 -281.376374)
			(xy 133.070088 -281.40182) (xy 133.061924 -281.452054) (xy 133.045808 -281.500328) (xy 133.022157 -281.545391)
			(xy 132.991584 -281.586077) (xy 132.95488 -281.621332) (xy 132.912996 -281.650242) (xy 132.867017 -281.672059)
			(xy 132.818133 -281.686219) (xy 132.767612 -281.692353) (xy 132.71676 -281.690304) (xy 132.666896 -281.680124)
			(xy 132.61931 -281.662077) (xy 132.575236 -281.636631) (xy 132.535814 -281.604444) (xy 132.502066 -281.56635)
			(xy 132.474865 -281.523336) (xy 132.454917 -281.476516) (xy 132.442738 -281.427102) (xy 132.438643 -281.376374)
			(xy 132.130546 -281.376374) (xy 132.130034 -281.40182) (xy 132.12187 -281.452054) (xy 132.105754 -281.500328)
			(xy 132.082103 -281.545391) (xy 132.05153 -281.586077) (xy 132.014826 -281.621332) (xy 131.972942 -281.650242)
			(xy 131.926963 -281.672059) (xy 131.878079 -281.686219) (xy 131.827558 -281.692353) (xy 131.776706 -281.690304)
			(xy 131.726842 -281.680124) (xy 131.679256 -281.662077) (xy 131.635182 -281.636631) (xy 131.59576 -281.604444)
			(xy 131.562012 -281.56635) (xy 131.534811 -281.523336) (xy 131.514863 -281.476516) (xy 131.502684 -281.427102)
			(xy 131.498589 -281.376374) (xy 131.180078 -281.376374) (xy 131.179583 -281.400981) (xy 131.171688 -281.449558)
			(xy 131.156104 -281.496239) (xy 131.133233 -281.539816) (xy 131.103668 -281.57916) (xy 131.068175 -281.613252)
			(xy 131.027672 -281.641208) (xy 130.98321 -281.662306) (xy 130.935939 -281.675998) (xy 130.887084 -281.68193)
			(xy 130.837909 -281.679949) (xy 130.78969 -281.670105) (xy 130.743674 -281.652653) (xy 130.701053 -281.628046)
			(xy 130.662932 -281.596921) (xy 130.630297 -281.560084) (xy 130.603994 -281.518488) (xy 130.584703 -281.473212)
			(xy 130.572926 -281.425428) (xy 130.568966 -281.376374) (xy 130.250438 -281.376374) (xy 130.249926 -281.40182)
			(xy 130.241762 -281.452054) (xy 130.225646 -281.500328) (xy 130.201995 -281.545391) (xy 130.171422 -281.586077)
			(xy 130.134718 -281.621332) (xy 130.092834 -281.650242) (xy 130.046855 -281.672059) (xy 129.997971 -281.686219)
			(xy 129.94745 -281.692353) (xy 129.896598 -281.690304) (xy 129.846734 -281.680124) (xy 129.799148 -281.662077)
			(xy 129.755074 -281.636631) (xy 129.715652 -281.604444) (xy 129.681904 -281.56635) (xy 129.654703 -281.523336)
			(xy 129.634755 -281.476516) (xy 129.622576 -281.427102) (xy 129.618481 -281.376374) (xy 129.29997 -281.376374)
			(xy 129.299475 -281.400981) (xy 129.29158 -281.449558) (xy 129.275996 -281.496239) (xy 129.253125 -281.539816)
			(xy 129.22356 -281.57916) (xy 129.188067 -281.613252) (xy 129.147564 -281.641208) (xy 129.103102 -281.662306)
			(xy 129.055831 -281.675998) (xy 129.006976 -281.68193) (xy 128.957801 -281.679949) (xy 128.909582 -281.670105)
			(xy 128.863566 -281.652653) (xy 128.820945 -281.628046) (xy 128.782824 -281.596921) (xy 128.750189 -281.560084)
			(xy 128.723886 -281.518488) (xy 128.704595 -281.473212) (xy 128.692818 -281.425428) (xy 128.688858 -281.376374)
			(xy 128.370584 -281.376374) (xy 128.370072 -281.40182) (xy 128.361908 -281.452054) (xy 128.345792 -281.500328)
			(xy 128.322141 -281.545391) (xy 128.291568 -281.586077) (xy 128.254864 -281.621332) (xy 128.21298 -281.650242)
			(xy 128.167001 -281.672059) (xy 128.118117 -281.686219) (xy 128.067596 -281.692353) (xy 128.016744 -281.690304)
			(xy 127.96688 -281.680124) (xy 127.919294 -281.662077) (xy 127.87522 -281.636631) (xy 127.835798 -281.604444)
			(xy 127.80205 -281.56635) (xy 127.774849 -281.523336) (xy 127.754901 -281.476516) (xy 127.742722 -281.427102)
			(xy 127.738627 -281.376374) (xy 127.543814 -281.376374) (xy 127.543814 -281.503374) (xy 127.543981 -281.50924)
			(xy 127.546679 -281.520657) (xy 127.549148 -281.52598) (xy 127.552958 -281.533854) (xy 127.555244 -281.536902)
			(xy 127.578417 -281.570023) (xy 127.620495 -281.639051) (xy 127.639318 -281.674824) (xy 127.665043 -281.726475)
			(xy 127.706914 -281.834006) (xy 127.722884 -281.889454) (xy 127.725424 -281.898598) (xy 127.74676 -281.927554)
			(xy 127.754126 -281.93238) (xy 127.774659 -281.946678) (xy 127.811198 -281.980853) (xy 127.841678 -282.020528)
			(xy 127.865281 -282.064641) (xy 127.881377 -282.112012) (xy 127.889535 -282.161373) (xy 127.889536 -282.18638)
			(xy 128.208527 -282.18638) (xy 128.212622 -282.135652) (xy 128.224801 -282.086238) (xy 128.244749 -282.039418)
			(xy 128.27195 -281.996404) (xy 128.305698 -281.95831) (xy 128.34512 -281.926123) (xy 128.389194 -281.900677)
			(xy 128.43678 -281.88263) (xy 128.486644 -281.87245) (xy 128.537496 -281.870401) (xy 128.588017 -281.876535)
			(xy 128.636901 -281.890695) (xy 128.68288 -281.912512) (xy 128.724764 -281.941422) (xy 128.761468 -281.976677)
			(xy 128.792041 -282.017363) (xy 128.815692 -282.062426) (xy 128.831808 -282.1107) (xy 128.839972 -282.160934)
			(xy 128.840484 -282.18638) (xy 129.148581 -282.18638) (xy 129.152676 -282.135652) (xy 129.164855 -282.086238)
			(xy 129.184803 -282.039418) (xy 129.212004 -281.996404) (xy 129.245752 -281.95831) (xy 129.285174 -281.926123)
			(xy 129.329248 -281.900677) (xy 129.376834 -281.88263) (xy 129.426698 -281.87245) (xy 129.47755 -281.870401)
			(xy 129.528071 -281.876535) (xy 129.576955 -281.890695) (xy 129.622934 -281.912512) (xy 129.664818 -281.941422)
			(xy 129.701522 -281.976677) (xy 129.732095 -282.017363) (xy 129.755746 -282.062426) (xy 129.771862 -282.1107)
			(xy 129.780026 -282.160934) (xy 129.780538 -282.18638) (xy 130.099066 -282.18638) (xy 130.103026 -282.137326)
			(xy 130.114803 -282.089542) (xy 130.134094 -282.044266) (xy 130.160397 -282.00267) (xy 130.193032 -281.965833)
			(xy 130.231153 -281.934708) (xy 130.273774 -281.910101) (xy 130.31979 -281.892649) (xy 130.368009 -281.882805)
			(xy 130.417184 -281.880824) (xy 130.466039 -281.886756) (xy 130.51331 -281.900448) (xy 130.557772 -281.921546)
			(xy 130.598275 -281.949502) (xy 130.633768 -281.983594) (xy 130.663333 -282.022938) (xy 130.686204 -282.066515)
			(xy 130.701788 -282.113196) (xy 130.709683 -282.161773) (xy 130.710178 -282.18638) (xy 131.028435 -282.18638)
			(xy 131.03253 -282.135652) (xy 131.044709 -282.086238) (xy 131.064657 -282.039418) (xy 131.091858 -281.996404)
			(xy 131.125606 -281.95831) (xy 131.165028 -281.926123) (xy 131.209102 -281.900677) (xy 131.256688 -281.88263)
			(xy 131.306552 -281.87245) (xy 131.357404 -281.870401) (xy 131.407925 -281.876535) (xy 131.456809 -281.890695)
			(xy 131.502788 -281.912512) (xy 131.544672 -281.941422) (xy 131.581376 -281.976677) (xy 131.611949 -282.017363)
			(xy 131.6356 -282.062426) (xy 131.651716 -282.1107) (xy 131.65988 -282.160934) (xy 131.660392 -282.18638)
			(xy 131.97892 -282.18638) (xy 131.98288 -282.137326) (xy 131.994657 -282.089542) (xy 132.013948 -282.044266)
			(xy 132.040251 -282.00267) (xy 132.072886 -281.965833) (xy 132.111007 -281.934708) (xy 132.153628 -281.910101)
			(xy 132.199644 -281.892649) (xy 132.247863 -281.882805) (xy 132.297038 -281.880824) (xy 132.345893 -281.886756)
			(xy 132.393164 -281.900448) (xy 132.437626 -281.921546) (xy 132.478129 -281.949502) (xy 132.513622 -281.983594)
			(xy 132.543187 -282.022938) (xy 132.566058 -282.066515) (xy 132.581642 -282.113196) (xy 132.589537 -282.161773)
			(xy 132.590032 -282.18638) (xy 132.908543 -282.18638) (xy 132.912638 -282.135652) (xy 132.924817 -282.086238)
			(xy 132.944765 -282.039418) (xy 132.971966 -281.996404) (xy 133.005714 -281.95831) (xy 133.045136 -281.926123)
			(xy 133.08921 -281.900677) (xy 133.136796 -281.88263) (xy 133.18666 -281.87245) (xy 133.237512 -281.870401)
			(xy 133.288033 -281.876535) (xy 133.336917 -281.890695) (xy 133.382896 -281.912512) (xy 133.42478 -281.941422)
			(xy 133.461484 -281.976677) (xy 133.492057 -282.017363) (xy 133.515708 -282.062426) (xy 133.531824 -282.1107)
			(xy 133.539988 -282.160934) (xy 133.5405 -282.18638) (xy 133.859028 -282.18638) (xy 133.862988 -282.137326)
			(xy 133.874765 -282.089542) (xy 133.894056 -282.044266) (xy 133.920359 -282.00267) (xy 133.952994 -281.965833)
			(xy 133.991115 -281.934708) (xy 134.033736 -281.910101) (xy 134.079752 -281.892649) (xy 134.127971 -281.882805)
			(xy 134.177146 -281.880824) (xy 134.226001 -281.886756) (xy 134.273272 -281.900448) (xy 134.317734 -281.921546)
			(xy 134.358237 -281.949502) (xy 134.39373 -281.983594) (xy 134.423295 -282.022938) (xy 134.446166 -282.066515)
			(xy 134.46175 -282.113196) (xy 134.469645 -282.161773) (xy 134.47014 -282.18638) (xy 134.798828 -282.18638)
			(xy 134.802788 -282.137326) (xy 134.814565 -282.089542) (xy 134.833856 -282.044266) (xy 134.860159 -282.00267)
			(xy 134.892794 -281.965833) (xy 134.930915 -281.934708) (xy 134.973536 -281.910101) (xy 135.019552 -281.892649)
			(xy 135.067771 -281.882805) (xy 135.116946 -281.880824) (xy 135.165801 -281.886756) (xy 135.213072 -281.900448)
			(xy 135.257534 -281.921546) (xy 135.298037 -281.949502) (xy 135.33353 -281.983594) (xy 135.363095 -282.022938)
			(xy 135.385966 -282.066515) (xy 135.40155 -282.113196) (xy 135.409445 -282.161773) (xy 135.40994 -282.18638)
			(xy 135.738882 -282.18638) (xy 135.742842 -282.137326) (xy 135.754619 -282.089542) (xy 135.77391 -282.044266)
			(xy 135.800213 -282.00267) (xy 135.832848 -281.965833) (xy 135.870969 -281.934708) (xy 135.91359 -281.910101)
			(xy 135.959606 -281.892649) (xy 136.007825 -281.882805) (xy 136.057 -281.880824) (xy 136.105855 -281.886756)
			(xy 136.153126 -281.900448) (xy 136.197588 -281.921546) (xy 136.238091 -281.949502) (xy 136.273584 -281.983594)
			(xy 136.303149 -282.022938) (xy 136.32602 -282.066515) (xy 136.341604 -282.113196) (xy 136.349499 -282.161773)
			(xy 136.349994 -282.18638) (xy 136.678936 -282.18638) (xy 136.682896 -282.137326) (xy 136.694673 -282.089542)
			(xy 136.713964 -282.044266) (xy 136.740267 -282.00267) (xy 136.772902 -281.965833) (xy 136.811023 -281.934708)
			(xy 136.853644 -281.910101) (xy 136.89966 -281.892649) (xy 136.947879 -281.882805) (xy 136.997054 -281.880824)
			(xy 137.045909 -281.886756) (xy 137.09318 -281.900448) (xy 137.137642 -281.921546) (xy 137.178145 -281.949502)
			(xy 137.213638 -281.983594) (xy 137.243203 -282.022938) (xy 137.266074 -282.066515) (xy 137.281658 -282.113196)
			(xy 137.289553 -282.161773) (xy 137.290048 -282.18638) (xy 137.61899 -282.18638) (xy 137.62295 -282.137326)
			(xy 137.634727 -282.089542) (xy 137.654018 -282.044266) (xy 137.680321 -282.00267) (xy 137.712956 -281.965833)
			(xy 137.751077 -281.934708) (xy 137.793698 -281.910101) (xy 137.839714 -281.892649) (xy 137.887933 -281.882805)
			(xy 137.937108 -281.880824) (xy 137.985963 -281.886756) (xy 138.033234 -281.900448) (xy 138.077696 -281.921546)
			(xy 138.118199 -281.949502) (xy 138.153692 -281.983594) (xy 138.183257 -282.022938) (xy 138.206128 -282.066515)
			(xy 138.221712 -282.113196) (xy 138.229607 -282.161773) (xy 138.230102 -282.18638) (xy 138.559044 -282.18638)
			(xy 138.563004 -282.137326) (xy 138.574781 -282.089542) (xy 138.594072 -282.044266) (xy 138.620375 -282.00267)
			(xy 138.65301 -281.965833) (xy 138.691131 -281.934708) (xy 138.733752 -281.910101) (xy 138.779768 -281.892649)
			(xy 138.827987 -281.882805) (xy 138.877162 -281.880824) (xy 138.926017 -281.886756) (xy 138.973288 -281.900448)
			(xy 139.01775 -281.921546) (xy 139.058253 -281.949502) (xy 139.093746 -281.983594) (xy 139.123311 -282.022938)
			(xy 139.146182 -282.066515) (xy 139.161766 -282.113196) (xy 139.169661 -282.161773) (xy 139.170156 -282.18638)
			(xy 139.498844 -282.18638) (xy 139.502804 -282.137326) (xy 139.514581 -282.089542) (xy 139.533872 -282.044266)
			(xy 139.560175 -282.00267) (xy 139.59281 -281.965833) (xy 139.630931 -281.934708) (xy 139.673552 -281.910101)
			(xy 139.719568 -281.892649) (xy 139.767787 -281.882805) (xy 139.816962 -281.880824) (xy 139.865817 -281.886756)
			(xy 139.913088 -281.900448) (xy 139.95755 -281.921546) (xy 139.998053 -281.949502) (xy 140.033546 -281.983594)
			(xy 140.063111 -282.022938) (xy 140.085982 -282.066515) (xy 140.101566 -282.113196) (xy 140.109461 -282.161773)
			(xy 140.109956 -282.18638) (xy 140.109461 -282.210987) (xy 140.101566 -282.259564) (xy 140.085982 -282.306245)
			(xy 140.063111 -282.349822) (xy 140.033546 -282.389166) (xy 139.998053 -282.423258) (xy 139.95755 -282.451214)
			(xy 139.913088 -282.472312) (xy 139.865817 -282.486004) (xy 139.816962 -282.491936) (xy 139.767787 -282.489955)
			(xy 139.719568 -282.480111) (xy 139.673552 -282.462659) (xy 139.630931 -282.438052) (xy 139.59281 -282.406927)
			(xy 139.560175 -282.37009) (xy 139.533872 -282.328494) (xy 139.514581 -282.283218) (xy 139.502804 -282.235434)
			(xy 139.498844 -282.18638) (xy 139.170156 -282.18638) (xy 139.169661 -282.210987) (xy 139.161766 -282.259564)
			(xy 139.146182 -282.306245) (xy 139.123311 -282.349822) (xy 139.093746 -282.389166) (xy 139.058253 -282.423258)
			(xy 139.01775 -282.451214) (xy 138.973288 -282.472312) (xy 138.926017 -282.486004) (xy 138.877162 -282.491936)
			(xy 138.827987 -282.489955) (xy 138.779768 -282.480111) (xy 138.733752 -282.462659) (xy 138.691131 -282.438052)
			(xy 138.65301 -282.406927) (xy 138.620375 -282.37009) (xy 138.594072 -282.328494) (xy 138.574781 -282.283218)
			(xy 138.563004 -282.235434) (xy 138.559044 -282.18638) (xy 138.230102 -282.18638) (xy 138.229607 -282.210987)
			(xy 138.221712 -282.259564) (xy 138.206128 -282.306245) (xy 138.183257 -282.349822) (xy 138.153692 -282.389166)
			(xy 138.118199 -282.423258) (xy 138.077696 -282.451214) (xy 138.033234 -282.472312) (xy 137.985963 -282.486004)
			(xy 137.937108 -282.491936) (xy 137.887933 -282.489955) (xy 137.839714 -282.480111) (xy 137.793698 -282.462659)
			(xy 137.751077 -282.438052) (xy 137.712956 -282.406927) (xy 137.680321 -282.37009) (xy 137.654018 -282.328494)
			(xy 137.634727 -282.283218) (xy 137.62295 -282.235434) (xy 137.61899 -282.18638) (xy 137.290048 -282.18638)
			(xy 137.289553 -282.210987) (xy 137.281658 -282.259564) (xy 137.266074 -282.306245) (xy 137.243203 -282.349822)
			(xy 137.213638 -282.389166) (xy 137.178145 -282.423258) (xy 137.137642 -282.451214) (xy 137.09318 -282.472312)
			(xy 137.045909 -282.486004) (xy 136.997054 -282.491936) (xy 136.947879 -282.489955) (xy 136.89966 -282.480111)
			(xy 136.853644 -282.462659) (xy 136.811023 -282.438052) (xy 136.772902 -282.406927) (xy 136.740267 -282.37009)
			(xy 136.713964 -282.328494) (xy 136.694673 -282.283218) (xy 136.682896 -282.235434) (xy 136.678936 -282.18638)
			(xy 136.349994 -282.18638) (xy 136.349499 -282.210987) (xy 136.341604 -282.259564) (xy 136.32602 -282.306245)
			(xy 136.303149 -282.349822) (xy 136.273584 -282.389166) (xy 136.238091 -282.423258) (xy 136.197588 -282.451214)
			(xy 136.153126 -282.472312) (xy 136.105855 -282.486004) (xy 136.057 -282.491936) (xy 136.007825 -282.489955)
			(xy 135.959606 -282.480111) (xy 135.91359 -282.462659) (xy 135.870969 -282.438052) (xy 135.832848 -282.406927)
			(xy 135.800213 -282.37009) (xy 135.77391 -282.328494) (xy 135.754619 -282.283218) (xy 135.742842 -282.235434)
			(xy 135.738882 -282.18638) (xy 135.40994 -282.18638) (xy 135.409445 -282.210987) (xy 135.40155 -282.259564)
			(xy 135.385966 -282.306245) (xy 135.363095 -282.349822) (xy 135.33353 -282.389166) (xy 135.298037 -282.423258)
			(xy 135.257534 -282.451214) (xy 135.213072 -282.472312) (xy 135.165801 -282.486004) (xy 135.116946 -282.491936)
			(xy 135.067771 -282.489955) (xy 135.019552 -282.480111) (xy 134.973536 -282.462659) (xy 134.930915 -282.438052)
			(xy 134.892794 -282.406927) (xy 134.860159 -282.37009) (xy 134.833856 -282.328494) (xy 134.814565 -282.283218)
			(xy 134.802788 -282.235434) (xy 134.798828 -282.18638) (xy 134.47014 -282.18638) (xy 134.469645 -282.210987)
			(xy 134.46175 -282.259564) (xy 134.446166 -282.306245) (xy 134.423295 -282.349822) (xy 134.39373 -282.389166)
			(xy 134.358237 -282.423258) (xy 134.317734 -282.451214) (xy 134.273272 -282.472312) (xy 134.226001 -282.486004)
			(xy 134.177146 -282.491936) (xy 134.127971 -282.489955) (xy 134.079752 -282.480111) (xy 134.033736 -282.462659)
			(xy 133.991115 -282.438052) (xy 133.952994 -282.406927) (xy 133.920359 -282.37009) (xy 133.894056 -282.328494)
			(xy 133.874765 -282.283218) (xy 133.862988 -282.235434) (xy 133.859028 -282.18638) (xy 133.5405 -282.18638)
			(xy 133.539988 -282.211826) (xy 133.531824 -282.26206) (xy 133.515708 -282.310334) (xy 133.492057 -282.355397)
			(xy 133.461484 -282.396083) (xy 133.42478 -282.431338) (xy 133.382896 -282.460248) (xy 133.336917 -282.482065)
			(xy 133.288033 -282.496225) (xy 133.237512 -282.502359) (xy 133.18666 -282.50031) (xy 133.136796 -282.49013)
			(xy 133.08921 -282.472083) (xy 133.045136 -282.446637) (xy 133.005714 -282.41445) (xy 132.971966 -282.376356)
			(xy 132.944765 -282.333342) (xy 132.924817 -282.286522) (xy 132.912638 -282.237108) (xy 132.908543 -282.18638)
			(xy 132.590032 -282.18638) (xy 132.589537 -282.210987) (xy 132.581642 -282.259564) (xy 132.566058 -282.306245)
			(xy 132.543187 -282.349822) (xy 132.513622 -282.389166) (xy 132.478129 -282.423258) (xy 132.437626 -282.451214)
			(xy 132.393164 -282.472312) (xy 132.345893 -282.486004) (xy 132.297038 -282.491936) (xy 132.247863 -282.489955)
			(xy 132.199644 -282.480111) (xy 132.153628 -282.462659) (xy 132.111007 -282.438052) (xy 132.072886 -282.406927)
			(xy 132.040251 -282.37009) (xy 132.013948 -282.328494) (xy 131.994657 -282.283218) (xy 131.98288 -282.235434)
			(xy 131.97892 -282.18638) (xy 131.660392 -282.18638) (xy 131.65988 -282.211826) (xy 131.651716 -282.26206)
			(xy 131.6356 -282.310334) (xy 131.611949 -282.355397) (xy 131.581376 -282.396083) (xy 131.544672 -282.431338)
			(xy 131.502788 -282.460248) (xy 131.456809 -282.482065) (xy 131.407925 -282.496225) (xy 131.357404 -282.502359)
			(xy 131.306552 -282.50031) (xy 131.256688 -282.49013) (xy 131.209102 -282.472083) (xy 131.165028 -282.446637)
			(xy 131.125606 -282.41445) (xy 131.091858 -282.376356) (xy 131.064657 -282.333342) (xy 131.044709 -282.286522)
			(xy 131.03253 -282.237108) (xy 131.028435 -282.18638) (xy 130.710178 -282.18638) (xy 130.709683 -282.210987)
			(xy 130.701788 -282.259564) (xy 130.686204 -282.306245) (xy 130.663333 -282.349822) (xy 130.633768 -282.389166)
			(xy 130.598275 -282.423258) (xy 130.557772 -282.451214) (xy 130.51331 -282.472312) (xy 130.466039 -282.486004)
			(xy 130.417184 -282.491936) (xy 130.368009 -282.489955) (xy 130.31979 -282.480111) (xy 130.273774 -282.462659)
			(xy 130.231153 -282.438052) (xy 130.193032 -282.406927) (xy 130.160397 -282.37009) (xy 130.134094 -282.328494)
			(xy 130.114803 -282.283218) (xy 130.103026 -282.235434) (xy 130.099066 -282.18638) (xy 129.780538 -282.18638)
			(xy 129.780026 -282.211826) (xy 129.771862 -282.26206) (xy 129.755746 -282.310334) (xy 129.732095 -282.355397)
			(xy 129.701522 -282.396083) (xy 129.664818 -282.431338) (xy 129.622934 -282.460248) (xy 129.576955 -282.482065)
			(xy 129.528071 -282.496225) (xy 129.47755 -282.502359) (xy 129.426698 -282.50031) (xy 129.376834 -282.49013)
			(xy 129.329248 -282.472083) (xy 129.285174 -282.446637) (xy 129.245752 -282.41445) (xy 129.212004 -282.376356)
			(xy 129.184803 -282.333342) (xy 129.164855 -282.286522) (xy 129.152676 -282.237108) (xy 129.148581 -282.18638)
			(xy 128.840484 -282.18638) (xy 128.839972 -282.211826) (xy 128.831808 -282.26206) (xy 128.815692 -282.310334)
			(xy 128.792041 -282.355397) (xy 128.761468 -282.396083) (xy 128.724764 -282.431338) (xy 128.68288 -282.460248)
			(xy 128.636901 -282.482065) (xy 128.588017 -282.496225) (xy 128.537496 -282.502359) (xy 128.486644 -282.50031)
			(xy 128.43678 -282.49013) (xy 128.389194 -282.472083) (xy 128.34512 -282.446637) (xy 128.305698 -282.41445)
			(xy 128.27195 -282.376356) (xy 128.244749 -282.333342) (xy 128.224801 -282.286522) (xy 128.212622 -282.237108)
			(xy 128.208527 -282.18638) (xy 127.889536 -282.18638) (xy 127.889537 -282.211404) (xy 127.881383 -282.260766)
			(xy 127.86529 -282.308138) (xy 127.84169 -282.352253) (xy 127.811213 -282.39193) (xy 127.774676 -282.426108)
			(xy 127.754126 -282.44038) (xy 127.74676 -282.445206) (xy 127.725424 -282.474162) (xy 127.722884 -282.483306)
			(xy 127.706872 -282.53874) (xy 127.665004 -282.646268) (xy 127.639318 -282.697936) (xy 127.620153 -282.734468)
			(xy 127.577185 -282.804899) (xy 127.553466 -282.838652) (xy 127.54864 -282.845256) (xy 127.543814 -282.859988)
			(xy 127.543814 -282.996386) (xy 127.738627 -282.996386) (xy 127.742722 -282.945658) (xy 127.754901 -282.896244)
			(xy 127.774849 -282.849424) (xy 127.80205 -282.80641) (xy 127.835798 -282.768316) (xy 127.87522 -282.736129)
			(xy 127.919294 -282.710683) (xy 127.96688 -282.692636) (xy 128.016744 -282.682456) (xy 128.067596 -282.680407)
			(xy 128.118117 -282.686541) (xy 128.167001 -282.700701) (xy 128.21298 -282.722518) (xy 128.254864 -282.751428)
			(xy 128.291568 -282.786683) (xy 128.322141 -282.827369) (xy 128.345792 -282.872432) (xy 128.361908 -282.920706)
			(xy 128.370072 -282.97094) (xy 128.370584 -282.996386) (xy 128.688858 -282.996386) (xy 128.692818 -282.947332)
			(xy 128.704595 -282.899548) (xy 128.723886 -282.854272) (xy 128.750189 -282.812676) (xy 128.782824 -282.775839)
			(xy 128.820945 -282.744714) (xy 128.863566 -282.720107) (xy 128.909582 -282.702655) (xy 128.957801 -282.692811)
			(xy 129.006976 -282.69083) (xy 129.055831 -282.696762) (xy 129.103102 -282.710454) (xy 129.147564 -282.731552)
			(xy 129.188067 -282.759508) (xy 129.22356 -282.7936) (xy 129.253125 -282.832944) (xy 129.275996 -282.876521)
			(xy 129.29158 -282.923202) (xy 129.299475 -282.971779) (xy 129.29997 -282.996386) (xy 129.618481 -282.996386)
			(xy 129.622576 -282.945658) (xy 129.634755 -282.896244) (xy 129.654703 -282.849424) (xy 129.681904 -282.80641)
			(xy 129.715652 -282.768316) (xy 129.755074 -282.736129) (xy 129.799148 -282.710683) (xy 129.846734 -282.692636)
			(xy 129.896598 -282.682456) (xy 129.94745 -282.680407) (xy 129.997971 -282.686541) (xy 130.046855 -282.700701)
			(xy 130.092834 -282.722518) (xy 130.134718 -282.751428) (xy 130.171422 -282.786683) (xy 130.201995 -282.827369)
			(xy 130.225646 -282.872432) (xy 130.241762 -282.920706) (xy 130.249926 -282.97094) (xy 130.250438 -282.996386)
			(xy 130.568966 -282.996386) (xy 130.572926 -282.947332) (xy 130.584703 -282.899548) (xy 130.603994 -282.854272)
			(xy 130.630297 -282.812676) (xy 130.662932 -282.775839) (xy 130.701053 -282.744714) (xy 130.743674 -282.720107)
			(xy 130.78969 -282.702655) (xy 130.837909 -282.692811) (xy 130.887084 -282.69083) (xy 130.935939 -282.696762)
			(xy 130.98321 -282.710454) (xy 131.027672 -282.731552) (xy 131.068175 -282.759508) (xy 131.103668 -282.7936)
			(xy 131.133233 -282.832944) (xy 131.156104 -282.876521) (xy 131.171688 -282.923202) (xy 131.179583 -282.971779)
			(xy 131.180078 -282.996386) (xy 131.498589 -282.996386) (xy 131.502684 -282.945658) (xy 131.514863 -282.896244)
			(xy 131.534811 -282.849424) (xy 131.562012 -282.80641) (xy 131.59576 -282.768316) (xy 131.635182 -282.736129)
			(xy 131.679256 -282.710683) (xy 131.726842 -282.692636) (xy 131.776706 -282.682456) (xy 131.827558 -282.680407)
			(xy 131.878079 -282.686541) (xy 131.926963 -282.700701) (xy 131.972942 -282.722518) (xy 132.014826 -282.751428)
			(xy 132.05153 -282.786683) (xy 132.082103 -282.827369) (xy 132.105754 -282.872432) (xy 132.12187 -282.920706)
			(xy 132.130034 -282.97094) (xy 132.130546 -282.996386) (xy 132.438643 -282.996386) (xy 132.442738 -282.945658)
			(xy 132.454917 -282.896244) (xy 132.474865 -282.849424) (xy 132.502066 -282.80641) (xy 132.535814 -282.768316)
			(xy 132.575236 -282.736129) (xy 132.61931 -282.710683) (xy 132.666896 -282.692636) (xy 132.71676 -282.682456)
			(xy 132.767612 -282.680407) (xy 132.818133 -282.686541) (xy 132.867017 -282.700701) (xy 132.912996 -282.722518)
			(xy 132.95488 -282.751428) (xy 132.991584 -282.786683) (xy 133.022157 -282.827369) (xy 133.045808 -282.872432)
			(xy 133.061924 -282.920706) (xy 133.070088 -282.97094) (xy 133.0706 -282.996386) (xy 133.388874 -282.996386)
			(xy 133.392834 -282.947332) (xy 133.404611 -282.899548) (xy 133.423902 -282.854272) (xy 133.450205 -282.812676)
			(xy 133.48284 -282.775839) (xy 133.520961 -282.744714) (xy 133.563582 -282.720107) (xy 133.609598 -282.702655)
			(xy 133.657817 -282.692811) (xy 133.706992 -282.69083) (xy 133.755847 -282.696762) (xy 133.803118 -282.710454)
			(xy 133.84758 -282.731552) (xy 133.888083 -282.759508) (xy 133.923576 -282.7936) (xy 133.953141 -282.832944)
			(xy 133.976012 -282.876521) (xy 133.991596 -282.923202) (xy 133.999491 -282.971779) (xy 133.999986 -282.996386)
			(xy 134.328928 -282.996386) (xy 134.332888 -282.947332) (xy 134.344665 -282.899548) (xy 134.363956 -282.854272)
			(xy 134.390259 -282.812676) (xy 134.422894 -282.775839) (xy 134.461015 -282.744714) (xy 134.503636 -282.720107)
			(xy 134.549652 -282.702655) (xy 134.597871 -282.692811) (xy 134.647046 -282.69083) (xy 134.695901 -282.696762)
			(xy 134.743172 -282.710454) (xy 134.787634 -282.731552) (xy 134.828137 -282.759508) (xy 134.86363 -282.7936)
			(xy 134.893195 -282.832944) (xy 134.916066 -282.876521) (xy 134.93165 -282.923202) (xy 134.939545 -282.971779)
			(xy 134.94004 -282.996386) (xy 135.268982 -282.996386) (xy 135.272942 -282.947332) (xy 135.284719 -282.899548)
			(xy 135.30401 -282.854272) (xy 135.330313 -282.812676) (xy 135.362948 -282.775839) (xy 135.401069 -282.744714)
			(xy 135.44369 -282.720107) (xy 135.489706 -282.702655) (xy 135.537925 -282.692811) (xy 135.5871 -282.69083)
			(xy 135.635955 -282.696762) (xy 135.683226 -282.710454) (xy 135.727688 -282.731552) (xy 135.768191 -282.759508)
			(xy 135.803684 -282.7936) (xy 135.833249 -282.832944) (xy 135.85612 -282.876521) (xy 135.871704 -282.923202)
			(xy 135.879599 -282.971779) (xy 135.880094 -282.996386) (xy 136.209036 -282.996386) (xy 136.212996 -282.947332)
			(xy 136.224773 -282.899548) (xy 136.244064 -282.854272) (xy 136.270367 -282.812676) (xy 136.303002 -282.775839)
			(xy 136.341123 -282.744714) (xy 136.383744 -282.720107) (xy 136.42976 -282.702655) (xy 136.477979 -282.692811)
			(xy 136.527154 -282.69083) (xy 136.576009 -282.696762) (xy 136.62328 -282.710454) (xy 136.667742 -282.731552)
			(xy 136.708245 -282.759508) (xy 136.743738 -282.7936) (xy 136.773303 -282.832944) (xy 136.796174 -282.876521)
			(xy 136.811758 -282.923202) (xy 136.819653 -282.971779) (xy 136.820148 -282.996386) (xy 137.148836 -282.996386)
			(xy 137.152796 -282.947332) (xy 137.164573 -282.899548) (xy 137.183864 -282.854272) (xy 137.210167 -282.812676)
			(xy 137.242802 -282.775839) (xy 137.280923 -282.744714) (xy 137.323544 -282.720107) (xy 137.36956 -282.702655)
			(xy 137.417779 -282.692811) (xy 137.466954 -282.69083) (xy 137.515809 -282.696762) (xy 137.56308 -282.710454)
			(xy 137.607542 -282.731552) (xy 137.648045 -282.759508) (xy 137.683538 -282.7936) (xy 137.713103 -282.832944)
			(xy 137.735974 -282.876521) (xy 137.751558 -282.923202) (xy 137.759453 -282.971779) (xy 137.759948 -282.996386)
			(xy 138.08889 -282.996386) (xy 138.09285 -282.947332) (xy 138.104627 -282.899548) (xy 138.123918 -282.854272)
			(xy 138.150221 -282.812676) (xy 138.182856 -282.775839) (xy 138.220977 -282.744714) (xy 138.263598 -282.720107)
			(xy 138.309614 -282.702655) (xy 138.357833 -282.692811) (xy 138.407008 -282.69083) (xy 138.455863 -282.696762)
			(xy 138.503134 -282.710454) (xy 138.547596 -282.731552) (xy 138.588099 -282.759508) (xy 138.623592 -282.7936)
			(xy 138.653157 -282.832944) (xy 138.676028 -282.876521) (xy 138.691612 -282.923202) (xy 138.699507 -282.971779)
			(xy 138.700002 -282.996386) (xy 139.028944 -282.996386) (xy 139.032904 -282.947332) (xy 139.044681 -282.899548)
			(xy 139.063972 -282.854272) (xy 139.090275 -282.812676) (xy 139.12291 -282.775839) (xy 139.161031 -282.744714)
			(xy 139.203652 -282.720107) (xy 139.249668 -282.702655) (xy 139.297887 -282.692811) (xy 139.347062 -282.69083)
			(xy 139.395917 -282.696762) (xy 139.443188 -282.710454) (xy 139.48765 -282.731552) (xy 139.528153 -282.759508)
			(xy 139.563646 -282.7936) (xy 139.593211 -282.832944) (xy 139.616082 -282.876521) (xy 139.631666 -282.923202)
			(xy 139.639561 -282.971779) (xy 139.640056 -282.996386) (xy 139.639561 -283.020993) (xy 139.631666 -283.06957)
			(xy 139.616082 -283.116251) (xy 139.593211 -283.159828) (xy 139.563646 -283.199172) (xy 139.528153 -283.233264)
			(xy 139.48765 -283.26122) (xy 139.443188 -283.282318) (xy 139.395917 -283.29601) (xy 139.347062 -283.301942)
			(xy 139.297887 -283.299961) (xy 139.249668 -283.290117) (xy 139.203652 -283.272665) (xy 139.161031 -283.248058)
			(xy 139.12291 -283.216933) (xy 139.090275 -283.180096) (xy 139.063972 -283.1385) (xy 139.044681 -283.093224)
			(xy 139.032904 -283.04544) (xy 139.028944 -282.996386) (xy 138.700002 -282.996386) (xy 138.699507 -283.020993)
			(xy 138.691612 -283.06957) (xy 138.676028 -283.116251) (xy 138.653157 -283.159828) (xy 138.623592 -283.199172)
			(xy 138.588099 -283.233264) (xy 138.547596 -283.26122) (xy 138.503134 -283.282318) (xy 138.455863 -283.29601)
			(xy 138.407008 -283.301942) (xy 138.357833 -283.299961) (xy 138.309614 -283.290117) (xy 138.263598 -283.272665)
			(xy 138.220977 -283.248058) (xy 138.182856 -283.216933) (xy 138.150221 -283.180096) (xy 138.123918 -283.1385)
			(xy 138.104627 -283.093224) (xy 138.09285 -283.04544) (xy 138.08889 -282.996386) (xy 137.759948 -282.996386)
			(xy 137.759453 -283.020993) (xy 137.751558 -283.06957) (xy 137.735974 -283.116251) (xy 137.713103 -283.159828)
			(xy 137.683538 -283.199172) (xy 137.648045 -283.233264) (xy 137.607542 -283.26122) (xy 137.56308 -283.282318)
			(xy 137.515809 -283.29601) (xy 137.466954 -283.301942) (xy 137.417779 -283.299961) (xy 137.36956 -283.290117)
			(xy 137.323544 -283.272665) (xy 137.280923 -283.248058) (xy 137.242802 -283.216933) (xy 137.210167 -283.180096)
			(xy 137.183864 -283.1385) (xy 137.164573 -283.093224) (xy 137.152796 -283.04544) (xy 137.148836 -282.996386)
			(xy 136.820148 -282.996386) (xy 136.819653 -283.020993) (xy 136.811758 -283.06957) (xy 136.796174 -283.116251)
			(xy 136.773303 -283.159828) (xy 136.743738 -283.199172) (xy 136.708245 -283.233264) (xy 136.667742 -283.26122)
			(xy 136.62328 -283.282318) (xy 136.576009 -283.29601) (xy 136.527154 -283.301942) (xy 136.477979 -283.299961)
			(xy 136.42976 -283.290117) (xy 136.383744 -283.272665) (xy 136.341123 -283.248058) (xy 136.303002 -283.216933)
			(xy 136.270367 -283.180096) (xy 136.244064 -283.1385) (xy 136.224773 -283.093224) (xy 136.212996 -283.04544)
			(xy 136.209036 -282.996386) (xy 135.880094 -282.996386) (xy 135.879599 -283.020993) (xy 135.871704 -283.06957)
			(xy 135.85612 -283.116251) (xy 135.833249 -283.159828) (xy 135.803684 -283.199172) (xy 135.768191 -283.233264)
			(xy 135.727688 -283.26122) (xy 135.683226 -283.282318) (xy 135.635955 -283.29601) (xy 135.5871 -283.301942)
			(xy 135.537925 -283.299961) (xy 135.489706 -283.290117) (xy 135.44369 -283.272665) (xy 135.401069 -283.248058)
			(xy 135.362948 -283.216933) (xy 135.330313 -283.180096) (xy 135.30401 -283.1385) (xy 135.284719 -283.093224)
			(xy 135.272942 -283.04544) (xy 135.268982 -282.996386) (xy 134.94004 -282.996386) (xy 134.939545 -283.020993)
			(xy 134.93165 -283.06957) (xy 134.916066 -283.116251) (xy 134.893195 -283.159828) (xy 134.86363 -283.199172)
			(xy 134.828137 -283.233264) (xy 134.787634 -283.26122) (xy 134.743172 -283.282318) (xy 134.695901 -283.29601)
			(xy 134.647046 -283.301942) (xy 134.597871 -283.299961) (xy 134.549652 -283.290117) (xy 134.503636 -283.272665)
			(xy 134.461015 -283.248058) (xy 134.422894 -283.216933) (xy 134.390259 -283.180096) (xy 134.363956 -283.1385)
			(xy 134.344665 -283.093224) (xy 134.332888 -283.04544) (xy 134.328928 -282.996386) (xy 133.999986 -282.996386)
			(xy 133.999491 -283.020993) (xy 133.991596 -283.06957) (xy 133.976012 -283.116251) (xy 133.953141 -283.159828)
			(xy 133.923576 -283.199172) (xy 133.888083 -283.233264) (xy 133.84758 -283.26122) (xy 133.803118 -283.282318)
			(xy 133.755847 -283.29601) (xy 133.706992 -283.301942) (xy 133.657817 -283.299961) (xy 133.609598 -283.290117)
			(xy 133.563582 -283.272665) (xy 133.520961 -283.248058) (xy 133.48284 -283.216933) (xy 133.450205 -283.180096)
			(xy 133.423902 -283.1385) (xy 133.404611 -283.093224) (xy 133.392834 -283.04544) (xy 133.388874 -282.996386)
			(xy 133.0706 -282.996386) (xy 133.070088 -283.021832) (xy 133.061924 -283.072066) (xy 133.045808 -283.12034)
			(xy 133.022157 -283.165403) (xy 132.991584 -283.206089) (xy 132.95488 -283.241344) (xy 132.912996 -283.270254)
			(xy 132.867017 -283.292071) (xy 132.818133 -283.306231) (xy 132.767612 -283.312365) (xy 132.71676 -283.310316)
			(xy 132.666896 -283.300136) (xy 132.61931 -283.282089) (xy 132.575236 -283.256643) (xy 132.535814 -283.224456)
			(xy 132.502066 -283.186362) (xy 132.474865 -283.143348) (xy 132.454917 -283.096528) (xy 132.442738 -283.047114)
			(xy 132.438643 -282.996386) (xy 132.130546 -282.996386) (xy 132.130034 -283.021832) (xy 132.12187 -283.072066)
			(xy 132.105754 -283.12034) (xy 132.082103 -283.165403) (xy 132.05153 -283.206089) (xy 132.014826 -283.241344)
			(xy 131.972942 -283.270254) (xy 131.926963 -283.292071) (xy 131.878079 -283.306231) (xy 131.827558 -283.312365)
			(xy 131.776706 -283.310316) (xy 131.726842 -283.300136) (xy 131.679256 -283.282089) (xy 131.635182 -283.256643)
			(xy 131.59576 -283.224456) (xy 131.562012 -283.186362) (xy 131.534811 -283.143348) (xy 131.514863 -283.096528)
			(xy 131.502684 -283.047114) (xy 131.498589 -282.996386) (xy 131.180078 -282.996386) (xy 131.179583 -283.020993)
			(xy 131.171688 -283.06957) (xy 131.156104 -283.116251) (xy 131.133233 -283.159828) (xy 131.103668 -283.199172)
			(xy 131.068175 -283.233264) (xy 131.027672 -283.26122) (xy 130.98321 -283.282318) (xy 130.935939 -283.29601)
			(xy 130.887084 -283.301942) (xy 130.837909 -283.299961) (xy 130.78969 -283.290117) (xy 130.743674 -283.272665)
			(xy 130.701053 -283.248058) (xy 130.662932 -283.216933) (xy 130.630297 -283.180096) (xy 130.603994 -283.1385)
			(xy 130.584703 -283.093224) (xy 130.572926 -283.04544) (xy 130.568966 -282.996386) (xy 130.250438 -282.996386)
			(xy 130.249926 -283.021832) (xy 130.241762 -283.072066) (xy 130.225646 -283.12034) (xy 130.201995 -283.165403)
			(xy 130.171422 -283.206089) (xy 130.134718 -283.241344) (xy 130.092834 -283.270254) (xy 130.046855 -283.292071)
			(xy 129.997971 -283.306231) (xy 129.94745 -283.312365) (xy 129.896598 -283.310316) (xy 129.846734 -283.300136)
			(xy 129.799148 -283.282089) (xy 129.755074 -283.256643) (xy 129.715652 -283.224456) (xy 129.681904 -283.186362)
			(xy 129.654703 -283.143348) (xy 129.634755 -283.096528) (xy 129.622576 -283.047114) (xy 129.618481 -282.996386)
			(xy 129.29997 -282.996386) (xy 129.299475 -283.020993) (xy 129.29158 -283.06957) (xy 129.275996 -283.116251)
			(xy 129.253125 -283.159828) (xy 129.22356 -283.199172) (xy 129.188067 -283.233264) (xy 129.147564 -283.26122)
			(xy 129.103102 -283.282318) (xy 129.055831 -283.29601) (xy 129.006976 -283.301942) (xy 128.957801 -283.299961)
			(xy 128.909582 -283.290117) (xy 128.863566 -283.272665) (xy 128.820945 -283.248058) (xy 128.782824 -283.216933)
			(xy 128.750189 -283.180096) (xy 128.723886 -283.1385) (xy 128.704595 -283.093224) (xy 128.692818 -283.04544)
			(xy 128.688858 -282.996386) (xy 128.370584 -282.996386) (xy 128.370072 -283.021832) (xy 128.361908 -283.072066)
			(xy 128.345792 -283.12034) (xy 128.322141 -283.165403) (xy 128.291568 -283.206089) (xy 128.254864 -283.241344)
			(xy 128.21298 -283.270254) (xy 128.167001 -283.292071) (xy 128.118117 -283.306231) (xy 128.067596 -283.312365)
			(xy 128.016744 -283.310316) (xy 127.96688 -283.300136) (xy 127.919294 -283.282089) (xy 127.87522 -283.256643)
			(xy 127.835798 -283.224456) (xy 127.80205 -283.186362) (xy 127.774849 -283.143348) (xy 127.754901 -283.096528)
			(xy 127.742722 -283.047114) (xy 127.738627 -282.996386) (xy 127.543814 -282.996386) (xy 127.543814 -283.123386)
			(xy 127.543982 -283.129251) (xy 127.546682 -283.140667) (xy 127.549148 -283.145992) (xy 127.552958 -283.153866)
			(xy 127.555244 -283.156914) (xy 127.578417 -283.190035) (xy 127.620494 -283.259064) (xy 127.639318 -283.294836)
			(xy 127.665042 -283.346487) (xy 127.706913 -283.454018) (xy 127.722884 -283.509466) (xy 127.725424 -283.51861)
			(xy 127.74676 -283.547566) (xy 127.754126 -283.552392) (xy 127.774658 -283.56669) (xy 127.811195 -283.600865)
			(xy 127.841673 -283.640539) (xy 127.865275 -283.684651) (xy 127.881369 -283.732021) (xy 127.889526 -283.781381)
			(xy 127.889526 -283.806392) (xy 128.208527 -283.806392) (xy 128.212622 -283.755664) (xy 128.224801 -283.70625)
			(xy 128.244749 -283.65943) (xy 128.27195 -283.616416) (xy 128.305698 -283.578322) (xy 128.34512 -283.546135)
			(xy 128.389194 -283.520689) (xy 128.43678 -283.502642) (xy 128.486644 -283.492462) (xy 128.537496 -283.490413)
			(xy 128.588017 -283.496547) (xy 128.636901 -283.510707) (xy 128.68288 -283.532524) (xy 128.724764 -283.561434)
			(xy 128.761468 -283.596689) (xy 128.792041 -283.637375) (xy 128.815692 -283.682438) (xy 128.831808 -283.730712)
			(xy 128.839972 -283.780946) (xy 128.840484 -283.806392) (xy 129.148581 -283.806392) (xy 129.152676 -283.755664)
			(xy 129.164855 -283.70625) (xy 129.184803 -283.65943) (xy 129.212004 -283.616416) (xy 129.245752 -283.578322)
			(xy 129.285174 -283.546135) (xy 129.329248 -283.520689) (xy 129.376834 -283.502642) (xy 129.426698 -283.492462)
			(xy 129.47755 -283.490413) (xy 129.528071 -283.496547) (xy 129.576955 -283.510707) (xy 129.622934 -283.532524)
			(xy 129.664818 -283.561434) (xy 129.701522 -283.596689) (xy 129.732095 -283.637375) (xy 129.755746 -283.682438)
			(xy 129.771862 -283.730712) (xy 129.780026 -283.780946) (xy 129.780538 -283.806392) (xy 130.099066 -283.806392)
			(xy 130.103026 -283.757338) (xy 130.114803 -283.709554) (xy 130.134094 -283.664278) (xy 130.160397 -283.622682)
			(xy 130.193032 -283.585845) (xy 130.231153 -283.55472) (xy 130.273774 -283.530113) (xy 130.31979 -283.512661)
			(xy 130.368009 -283.502817) (xy 130.417184 -283.500836) (xy 130.466039 -283.506768) (xy 130.51331 -283.52046)
			(xy 130.557772 -283.541558) (xy 130.598275 -283.569514) (xy 130.633768 -283.603606) (xy 130.663333 -283.64295)
			(xy 130.686204 -283.686527) (xy 130.701788 -283.733208) (xy 130.709683 -283.781785) (xy 130.710178 -283.806392)
			(xy 131.028435 -283.806392) (xy 131.03253 -283.755664) (xy 131.044709 -283.70625) (xy 131.064657 -283.65943)
			(xy 131.091858 -283.616416) (xy 131.125606 -283.578322) (xy 131.165028 -283.546135) (xy 131.209102 -283.520689)
			(xy 131.256688 -283.502642) (xy 131.306552 -283.492462) (xy 131.357404 -283.490413) (xy 131.407925 -283.496547)
			(xy 131.456809 -283.510707) (xy 131.502788 -283.532524) (xy 131.544672 -283.561434) (xy 131.581376 -283.596689)
			(xy 131.611949 -283.637375) (xy 131.6356 -283.682438) (xy 131.651716 -283.730712) (xy 131.65988 -283.780946)
			(xy 131.660392 -283.806392) (xy 131.97892 -283.806392) (xy 131.98288 -283.757338) (xy 131.994657 -283.709554)
			(xy 132.013948 -283.664278) (xy 132.040251 -283.622682) (xy 132.072886 -283.585845) (xy 132.111007 -283.55472)
			(xy 132.153628 -283.530113) (xy 132.199644 -283.512661) (xy 132.247863 -283.502817) (xy 132.297038 -283.500836)
			(xy 132.345893 -283.506768) (xy 132.393164 -283.52046) (xy 132.437626 -283.541558) (xy 132.478129 -283.569514)
			(xy 132.513622 -283.603606) (xy 132.543187 -283.64295) (xy 132.566058 -283.686527) (xy 132.581642 -283.733208)
			(xy 132.589537 -283.781785) (xy 132.590032 -283.806392) (xy 132.908543 -283.806392) (xy 132.912638 -283.755664)
			(xy 132.924817 -283.70625) (xy 132.944765 -283.65943) (xy 132.971966 -283.616416) (xy 133.005714 -283.578322)
			(xy 133.045136 -283.546135) (xy 133.08921 -283.520689) (xy 133.136796 -283.502642) (xy 133.18666 -283.492462)
			(xy 133.237512 -283.490413) (xy 133.288033 -283.496547) (xy 133.336917 -283.510707) (xy 133.382896 -283.532524)
			(xy 133.42478 -283.561434) (xy 133.461484 -283.596689) (xy 133.492057 -283.637375) (xy 133.515708 -283.682438)
			(xy 133.531824 -283.730712) (xy 133.539988 -283.780946) (xy 133.5405 -283.806392) (xy 133.859028 -283.806392)
			(xy 133.862988 -283.757338) (xy 133.874765 -283.709554) (xy 133.894056 -283.664278) (xy 133.920359 -283.622682)
			(xy 133.952994 -283.585845) (xy 133.991115 -283.55472) (xy 134.033736 -283.530113) (xy 134.079752 -283.512661)
			(xy 134.127971 -283.502817) (xy 134.177146 -283.500836) (xy 134.226001 -283.506768) (xy 134.273272 -283.52046)
			(xy 134.317734 -283.541558) (xy 134.358237 -283.569514) (xy 134.39373 -283.603606) (xy 134.423295 -283.64295)
			(xy 134.446166 -283.686527) (xy 134.46175 -283.733208) (xy 134.469645 -283.781785) (xy 134.47014 -283.806392)
			(xy 134.798828 -283.806392) (xy 134.802788 -283.757338) (xy 134.814565 -283.709554) (xy 134.833856 -283.664278)
			(xy 134.860159 -283.622682) (xy 134.892794 -283.585845) (xy 134.930915 -283.55472) (xy 134.973536 -283.530113)
			(xy 135.019552 -283.512661) (xy 135.067771 -283.502817) (xy 135.116946 -283.500836) (xy 135.165801 -283.506768)
			(xy 135.213072 -283.52046) (xy 135.257534 -283.541558) (xy 135.298037 -283.569514) (xy 135.33353 -283.603606)
			(xy 135.363095 -283.64295) (xy 135.385966 -283.686527) (xy 135.40155 -283.733208) (xy 135.409445 -283.781785)
			(xy 135.40994 -283.806392) (xy 135.738882 -283.806392) (xy 135.742842 -283.757338) (xy 135.754619 -283.709554)
			(xy 135.77391 -283.664278) (xy 135.800213 -283.622682) (xy 135.832848 -283.585845) (xy 135.870969 -283.55472)
			(xy 135.91359 -283.530113) (xy 135.959606 -283.512661) (xy 136.007825 -283.502817) (xy 136.057 -283.500836)
			(xy 136.105855 -283.506768) (xy 136.153126 -283.52046) (xy 136.197588 -283.541558) (xy 136.238091 -283.569514)
			(xy 136.273584 -283.603606) (xy 136.303149 -283.64295) (xy 136.32602 -283.686527) (xy 136.341604 -283.733208)
			(xy 136.349499 -283.781785) (xy 136.349994 -283.806392) (xy 136.678936 -283.806392) (xy 136.682896 -283.757338)
			(xy 136.694673 -283.709554) (xy 136.713964 -283.664278) (xy 136.740267 -283.622682) (xy 136.772902 -283.585845)
			(xy 136.811023 -283.55472) (xy 136.853644 -283.530113) (xy 136.89966 -283.512661) (xy 136.947879 -283.502817)
			(xy 136.997054 -283.500836) (xy 137.045909 -283.506768) (xy 137.09318 -283.52046) (xy 137.137642 -283.541558)
			(xy 137.178145 -283.569514) (xy 137.213638 -283.603606) (xy 137.243203 -283.64295) (xy 137.266074 -283.686527)
			(xy 137.281658 -283.733208) (xy 137.289553 -283.781785) (xy 137.290048 -283.806392) (xy 137.61899 -283.806392)
			(xy 137.62295 -283.757338) (xy 137.634727 -283.709554) (xy 137.654018 -283.664278) (xy 137.680321 -283.622682)
			(xy 137.712956 -283.585845) (xy 137.751077 -283.55472) (xy 137.793698 -283.530113) (xy 137.839714 -283.512661)
			(xy 137.887933 -283.502817) (xy 137.937108 -283.500836) (xy 137.985963 -283.506768) (xy 138.033234 -283.52046)
			(xy 138.077696 -283.541558) (xy 138.118199 -283.569514) (xy 138.153692 -283.603606) (xy 138.183257 -283.64295)
			(xy 138.206128 -283.686527) (xy 138.221712 -283.733208) (xy 138.229607 -283.781785) (xy 138.230102 -283.806392)
			(xy 138.559044 -283.806392) (xy 138.563004 -283.757338) (xy 138.574781 -283.709554) (xy 138.594072 -283.664278)
			(xy 138.620375 -283.622682) (xy 138.65301 -283.585845) (xy 138.691131 -283.55472) (xy 138.733752 -283.530113)
			(xy 138.779768 -283.512661) (xy 138.827987 -283.502817) (xy 138.877162 -283.500836) (xy 138.926017 -283.506768)
			(xy 138.973288 -283.52046) (xy 139.01775 -283.541558) (xy 139.058253 -283.569514) (xy 139.093746 -283.603606)
			(xy 139.123311 -283.64295) (xy 139.146182 -283.686527) (xy 139.161766 -283.733208) (xy 139.169661 -283.781785)
			(xy 139.170156 -283.806392) (xy 139.498844 -283.806392) (xy 139.502804 -283.757338) (xy 139.514581 -283.709554)
			(xy 139.533872 -283.664278) (xy 139.560175 -283.622682) (xy 139.59281 -283.585845) (xy 139.630931 -283.55472)
			(xy 139.673552 -283.530113) (xy 139.719568 -283.512661) (xy 139.767787 -283.502817) (xy 139.816962 -283.500836)
			(xy 139.865817 -283.506768) (xy 139.913088 -283.52046) (xy 139.95755 -283.541558) (xy 139.998053 -283.569514)
			(xy 140.033546 -283.603606) (xy 140.063111 -283.64295) (xy 140.085982 -283.686527) (xy 140.101566 -283.733208)
			(xy 140.109461 -283.781785) (xy 140.109956 -283.806392) (xy 140.109461 -283.830999) (xy 140.101566 -283.879576)
			(xy 140.085982 -283.926257) (xy 140.063111 -283.969834) (xy 140.033546 -284.009178) (xy 139.998053 -284.04327)
			(xy 139.95755 -284.071226) (xy 139.913088 -284.092324) (xy 139.865817 -284.106016) (xy 139.816962 -284.111948)
			(xy 139.767787 -284.109967) (xy 139.719568 -284.100123) (xy 139.673552 -284.082671) (xy 139.630931 -284.058064)
			(xy 139.59281 -284.026939) (xy 139.560175 -283.990102) (xy 139.533872 -283.948506) (xy 139.514581 -283.90323)
			(xy 139.502804 -283.855446) (xy 139.498844 -283.806392) (xy 139.170156 -283.806392) (xy 139.169661 -283.830999)
			(xy 139.161766 -283.879576) (xy 139.146182 -283.926257) (xy 139.123311 -283.969834) (xy 139.093746 -284.009178)
			(xy 139.058253 -284.04327) (xy 139.01775 -284.071226) (xy 138.973288 -284.092324) (xy 138.926017 -284.106016)
			(xy 138.877162 -284.111948) (xy 138.827987 -284.109967) (xy 138.779768 -284.100123) (xy 138.733752 -284.082671)
			(xy 138.691131 -284.058064) (xy 138.65301 -284.026939) (xy 138.620375 -283.990102) (xy 138.594072 -283.948506)
			(xy 138.574781 -283.90323) (xy 138.563004 -283.855446) (xy 138.559044 -283.806392) (xy 138.230102 -283.806392)
			(xy 138.229607 -283.830999) (xy 138.221712 -283.879576) (xy 138.206128 -283.926257) (xy 138.183257 -283.969834)
			(xy 138.153692 -284.009178) (xy 138.118199 -284.04327) (xy 138.077696 -284.071226) (xy 138.033234 -284.092324)
			(xy 137.985963 -284.106016) (xy 137.937108 -284.111948) (xy 137.887933 -284.109967) (xy 137.839714 -284.100123)
			(xy 137.793698 -284.082671) (xy 137.751077 -284.058064) (xy 137.712956 -284.026939) (xy 137.680321 -283.990102)
			(xy 137.654018 -283.948506) (xy 137.634727 -283.90323) (xy 137.62295 -283.855446) (xy 137.61899 -283.806392)
			(xy 137.290048 -283.806392) (xy 137.289553 -283.830999) (xy 137.281658 -283.879576) (xy 137.266074 -283.926257)
			(xy 137.243203 -283.969834) (xy 137.213638 -284.009178) (xy 137.178145 -284.04327) (xy 137.137642 -284.071226)
			(xy 137.09318 -284.092324) (xy 137.045909 -284.106016) (xy 136.997054 -284.111948) (xy 136.947879 -284.109967)
			(xy 136.89966 -284.100123) (xy 136.853644 -284.082671) (xy 136.811023 -284.058064) (xy 136.772902 -284.026939)
			(xy 136.740267 -283.990102) (xy 136.713964 -283.948506) (xy 136.694673 -283.90323) (xy 136.682896 -283.855446)
			(xy 136.678936 -283.806392) (xy 136.349994 -283.806392) (xy 136.349499 -283.830999) (xy 136.341604 -283.879576)
			(xy 136.32602 -283.926257) (xy 136.303149 -283.969834) (xy 136.273584 -284.009178) (xy 136.238091 -284.04327)
			(xy 136.197588 -284.071226) (xy 136.153126 -284.092324) (xy 136.105855 -284.106016) (xy 136.057 -284.111948)
			(xy 136.007825 -284.109967) (xy 135.959606 -284.100123) (xy 135.91359 -284.082671) (xy 135.870969 -284.058064)
			(xy 135.832848 -284.026939) (xy 135.800213 -283.990102) (xy 135.77391 -283.948506) (xy 135.754619 -283.90323)
			(xy 135.742842 -283.855446) (xy 135.738882 -283.806392) (xy 135.40994 -283.806392) (xy 135.409445 -283.830999)
			(xy 135.40155 -283.879576) (xy 135.385966 -283.926257) (xy 135.363095 -283.969834) (xy 135.33353 -284.009178)
			(xy 135.298037 -284.04327) (xy 135.257534 -284.071226) (xy 135.213072 -284.092324) (xy 135.165801 -284.106016)
			(xy 135.116946 -284.111948) (xy 135.067771 -284.109967) (xy 135.019552 -284.100123) (xy 134.973536 -284.082671)
			(xy 134.930915 -284.058064) (xy 134.892794 -284.026939) (xy 134.860159 -283.990102) (xy 134.833856 -283.948506)
			(xy 134.814565 -283.90323) (xy 134.802788 -283.855446) (xy 134.798828 -283.806392) (xy 134.47014 -283.806392)
			(xy 134.469645 -283.830999) (xy 134.46175 -283.879576) (xy 134.446166 -283.926257) (xy 134.423295 -283.969834)
			(xy 134.39373 -284.009178) (xy 134.358237 -284.04327) (xy 134.317734 -284.071226) (xy 134.273272 -284.092324)
			(xy 134.226001 -284.106016) (xy 134.177146 -284.111948) (xy 134.127971 -284.109967) (xy 134.079752 -284.100123)
			(xy 134.033736 -284.082671) (xy 133.991115 -284.058064) (xy 133.952994 -284.026939) (xy 133.920359 -283.990102)
			(xy 133.894056 -283.948506) (xy 133.874765 -283.90323) (xy 133.862988 -283.855446) (xy 133.859028 -283.806392)
			(xy 133.5405 -283.806392) (xy 133.539988 -283.831838) (xy 133.531824 -283.882072) (xy 133.515708 -283.930346)
			(xy 133.492057 -283.975409) (xy 133.461484 -284.016095) (xy 133.42478 -284.05135) (xy 133.382896 -284.08026)
			(xy 133.336917 -284.102077) (xy 133.288033 -284.116237) (xy 133.237512 -284.122371) (xy 133.18666 -284.120322)
			(xy 133.136796 -284.110142) (xy 133.08921 -284.092095) (xy 133.045136 -284.066649) (xy 133.005714 -284.034462)
			(xy 132.971966 -283.996368) (xy 132.944765 -283.953354) (xy 132.924817 -283.906534) (xy 132.912638 -283.85712)
			(xy 132.908543 -283.806392) (xy 132.590032 -283.806392) (xy 132.589537 -283.830999) (xy 132.581642 -283.879576)
			(xy 132.566058 -283.926257) (xy 132.543187 -283.969834) (xy 132.513622 -284.009178) (xy 132.478129 -284.04327)
			(xy 132.437626 -284.071226) (xy 132.393164 -284.092324) (xy 132.345893 -284.106016) (xy 132.297038 -284.111948)
			(xy 132.247863 -284.109967) (xy 132.199644 -284.100123) (xy 132.153628 -284.082671) (xy 132.111007 -284.058064)
			(xy 132.072886 -284.026939) (xy 132.040251 -283.990102) (xy 132.013948 -283.948506) (xy 131.994657 -283.90323)
			(xy 131.98288 -283.855446) (xy 131.97892 -283.806392) (xy 131.660392 -283.806392) (xy 131.65988 -283.831838)
			(xy 131.651716 -283.882072) (xy 131.6356 -283.930346) (xy 131.611949 -283.975409) (xy 131.581376 -284.016095)
			(xy 131.544672 -284.05135) (xy 131.502788 -284.08026) (xy 131.456809 -284.102077) (xy 131.407925 -284.116237)
			(xy 131.357404 -284.122371) (xy 131.306552 -284.120322) (xy 131.256688 -284.110142) (xy 131.209102 -284.092095)
			(xy 131.165028 -284.066649) (xy 131.125606 -284.034462) (xy 131.091858 -283.996368) (xy 131.064657 -283.953354)
			(xy 131.044709 -283.906534) (xy 131.03253 -283.85712) (xy 131.028435 -283.806392) (xy 130.710178 -283.806392)
			(xy 130.709683 -283.830999) (xy 130.701788 -283.879576) (xy 130.686204 -283.926257) (xy 130.663333 -283.969834)
			(xy 130.633768 -284.009178) (xy 130.598275 -284.04327) (xy 130.557772 -284.071226) (xy 130.51331 -284.092324)
			(xy 130.466039 -284.106016) (xy 130.417184 -284.111948) (xy 130.368009 -284.109967) (xy 130.31979 -284.100123)
			(xy 130.273774 -284.082671) (xy 130.231153 -284.058064) (xy 130.193032 -284.026939) (xy 130.160397 -283.990102)
			(xy 130.134094 -283.948506) (xy 130.114803 -283.90323) (xy 130.103026 -283.855446) (xy 130.099066 -283.806392)
			(xy 129.780538 -283.806392) (xy 129.780026 -283.831838) (xy 129.771862 -283.882072) (xy 129.755746 -283.930346)
			(xy 129.732095 -283.975409) (xy 129.701522 -284.016095) (xy 129.664818 -284.05135) (xy 129.622934 -284.08026)
			(xy 129.576955 -284.102077) (xy 129.528071 -284.116237) (xy 129.47755 -284.122371) (xy 129.426698 -284.120322)
			(xy 129.376834 -284.110142) (xy 129.329248 -284.092095) (xy 129.285174 -284.066649) (xy 129.245752 -284.034462)
			(xy 129.212004 -283.996368) (xy 129.184803 -283.953354) (xy 129.164855 -283.906534) (xy 129.152676 -283.85712)
			(xy 129.148581 -283.806392) (xy 128.840484 -283.806392) (xy 128.839972 -283.831838) (xy 128.831808 -283.882072)
			(xy 128.815692 -283.930346) (xy 128.792041 -283.975409) (xy 128.761468 -284.016095) (xy 128.724764 -284.05135)
			(xy 128.68288 -284.08026) (xy 128.636901 -284.102077) (xy 128.588017 -284.116237) (xy 128.537496 -284.122371)
			(xy 128.486644 -284.120322) (xy 128.43678 -284.110142) (xy 128.389194 -284.092095) (xy 128.34512 -284.066649)
			(xy 128.305698 -284.034462) (xy 128.27195 -283.996368) (xy 128.244749 -283.953354) (xy 128.224801 -283.906534)
			(xy 128.212622 -283.85712) (xy 128.208527 -283.806392) (xy 127.889526 -283.806392) (xy 127.889527 -283.83141)
			(xy 127.881371 -283.88077) (xy 127.865278 -283.92814) (xy 127.841678 -283.972253) (xy 127.811201 -284.011929)
			(xy 127.774665 -284.046105) (xy 127.754126 -284.060392) (xy 127.74676 -284.065218) (xy 127.725424 -284.094174)
			(xy 127.722884 -284.103318) (xy 127.706876 -284.158754) (xy 127.665016 -284.266286) (xy 127.639318 -284.317948)
			(xy 127.620153 -284.354479) (xy 127.577184 -284.42491) (xy 127.553466 -284.458664) (xy 127.54864 -284.465268)
			(xy 127.543814 -284.48) (xy 127.543814 -284.616398) (xy 127.738627 -284.616398) (xy 127.742722 -284.56567)
			(xy 127.754901 -284.516256) (xy 127.774849 -284.469436) (xy 127.80205 -284.426422) (xy 127.835798 -284.388328)
			(xy 127.87522 -284.356141) (xy 127.919294 -284.330695) (xy 127.96688 -284.312648) (xy 128.016744 -284.302468)
			(xy 128.067596 -284.300419) (xy 128.118117 -284.306553) (xy 128.167001 -284.320713) (xy 128.21298 -284.34253)
			(xy 128.254864 -284.37144) (xy 128.291568 -284.406695) (xy 128.322141 -284.447381) (xy 128.345792 -284.492444)
			(xy 128.361908 -284.540718) (xy 128.370072 -284.590952) (xy 128.370584 -284.616398) (xy 128.688858 -284.616398)
			(xy 128.692818 -284.567344) (xy 128.704595 -284.51956) (xy 128.723886 -284.474284) (xy 128.750189 -284.432688)
			(xy 128.782824 -284.395851) (xy 128.820945 -284.364726) (xy 128.863566 -284.340119) (xy 128.909582 -284.322667)
			(xy 128.957801 -284.312823) (xy 129.006976 -284.310842) (xy 129.055831 -284.316774) (xy 129.103102 -284.330466)
			(xy 129.147564 -284.351564) (xy 129.188067 -284.37952) (xy 129.22356 -284.413612) (xy 129.253125 -284.452956)
			(xy 129.275996 -284.496533) (xy 129.29158 -284.543214) (xy 129.299475 -284.591791) (xy 129.29997 -284.616398)
			(xy 129.618481 -284.616398) (xy 129.622576 -284.56567) (xy 129.634755 -284.516256) (xy 129.654703 -284.469436)
			(xy 129.681904 -284.426422) (xy 129.715652 -284.388328) (xy 129.755074 -284.356141) (xy 129.799148 -284.330695)
			(xy 129.846734 -284.312648) (xy 129.896598 -284.302468) (xy 129.94745 -284.300419) (xy 129.997971 -284.306553)
			(xy 130.046855 -284.320713) (xy 130.092834 -284.34253) (xy 130.134718 -284.37144) (xy 130.171422 -284.406695)
			(xy 130.201995 -284.447381) (xy 130.225646 -284.492444) (xy 130.241762 -284.540718) (xy 130.249926 -284.590952)
			(xy 130.250438 -284.616398) (xy 130.568966 -284.616398) (xy 130.572926 -284.567344) (xy 130.584703 -284.51956)
			(xy 130.603994 -284.474284) (xy 130.630297 -284.432688) (xy 130.662932 -284.395851) (xy 130.701053 -284.364726)
			(xy 130.743674 -284.340119) (xy 130.78969 -284.322667) (xy 130.837909 -284.312823) (xy 130.887084 -284.310842)
			(xy 130.935939 -284.316774) (xy 130.98321 -284.330466) (xy 131.027672 -284.351564) (xy 131.068175 -284.37952)
			(xy 131.103668 -284.413612) (xy 131.133233 -284.452956) (xy 131.156104 -284.496533) (xy 131.171688 -284.543214)
			(xy 131.179583 -284.591791) (xy 131.180078 -284.616398) (xy 131.498589 -284.616398) (xy 131.502684 -284.56567)
			(xy 131.514863 -284.516256) (xy 131.534811 -284.469436) (xy 131.562012 -284.426422) (xy 131.59576 -284.388328)
			(xy 131.635182 -284.356141) (xy 131.679256 -284.330695) (xy 131.726842 -284.312648) (xy 131.776706 -284.302468)
			(xy 131.827558 -284.300419) (xy 131.878079 -284.306553) (xy 131.926963 -284.320713) (xy 131.972942 -284.34253)
			(xy 132.014826 -284.37144) (xy 132.05153 -284.406695) (xy 132.082103 -284.447381) (xy 132.105754 -284.492444)
			(xy 132.12187 -284.540718) (xy 132.130034 -284.590952) (xy 132.130546 -284.616398) (xy 132.438643 -284.616398)
			(xy 132.442738 -284.56567) (xy 132.454917 -284.516256) (xy 132.474865 -284.469436) (xy 132.502066 -284.426422)
			(xy 132.535814 -284.388328) (xy 132.575236 -284.356141) (xy 132.61931 -284.330695) (xy 132.666896 -284.312648)
			(xy 132.71676 -284.302468) (xy 132.767612 -284.300419) (xy 132.818133 -284.306553) (xy 132.867017 -284.320713)
			(xy 132.912996 -284.34253) (xy 132.95488 -284.37144) (xy 132.991584 -284.406695) (xy 133.022157 -284.447381)
			(xy 133.045808 -284.492444) (xy 133.061924 -284.540718) (xy 133.070088 -284.590952) (xy 133.0706 -284.616398)
			(xy 133.388874 -284.616398) (xy 133.392834 -284.567344) (xy 133.404611 -284.51956) (xy 133.423902 -284.474284)
			(xy 133.450205 -284.432688) (xy 133.48284 -284.395851) (xy 133.520961 -284.364726) (xy 133.563582 -284.340119)
			(xy 133.609598 -284.322667) (xy 133.657817 -284.312823) (xy 133.706992 -284.310842) (xy 133.755847 -284.316774)
			(xy 133.803118 -284.330466) (xy 133.84758 -284.351564) (xy 133.888083 -284.37952) (xy 133.923576 -284.413612)
			(xy 133.953141 -284.452956) (xy 133.976012 -284.496533) (xy 133.991596 -284.543214) (xy 133.999491 -284.591791)
			(xy 133.999986 -284.616398) (xy 134.328928 -284.616398) (xy 134.332888 -284.567344) (xy 134.344665 -284.51956)
			(xy 134.363956 -284.474284) (xy 134.390259 -284.432688) (xy 134.422894 -284.395851) (xy 134.461015 -284.364726)
			(xy 134.503636 -284.340119) (xy 134.549652 -284.322667) (xy 134.597871 -284.312823) (xy 134.647046 -284.310842)
			(xy 134.695901 -284.316774) (xy 134.743172 -284.330466) (xy 134.787634 -284.351564) (xy 134.828137 -284.37952)
			(xy 134.86363 -284.413612) (xy 134.893195 -284.452956) (xy 134.916066 -284.496533) (xy 134.93165 -284.543214)
			(xy 134.939545 -284.591791) (xy 134.94004 -284.616398) (xy 135.268982 -284.616398) (xy 135.272942 -284.567344)
			(xy 135.284719 -284.51956) (xy 135.30401 -284.474284) (xy 135.330313 -284.432688) (xy 135.362948 -284.395851)
			(xy 135.401069 -284.364726) (xy 135.44369 -284.340119) (xy 135.489706 -284.322667) (xy 135.537925 -284.312823)
			(xy 135.5871 -284.310842) (xy 135.635955 -284.316774) (xy 135.683226 -284.330466) (xy 135.727688 -284.351564)
			(xy 135.768191 -284.37952) (xy 135.803684 -284.413612) (xy 135.833249 -284.452956) (xy 135.85612 -284.496533)
			(xy 135.871704 -284.543214) (xy 135.879599 -284.591791) (xy 135.880094 -284.616398) (xy 136.209036 -284.616398)
			(xy 136.212996 -284.567344) (xy 136.224773 -284.51956) (xy 136.244064 -284.474284) (xy 136.270367 -284.432688)
			(xy 136.303002 -284.395851) (xy 136.341123 -284.364726) (xy 136.383744 -284.340119) (xy 136.42976 -284.322667)
			(xy 136.477979 -284.312823) (xy 136.527154 -284.310842) (xy 136.576009 -284.316774) (xy 136.62328 -284.330466)
			(xy 136.667742 -284.351564) (xy 136.708245 -284.37952) (xy 136.743738 -284.413612) (xy 136.773303 -284.452956)
			(xy 136.796174 -284.496533) (xy 136.811758 -284.543214) (xy 136.819653 -284.591791) (xy 136.820148 -284.616398)
			(xy 137.148836 -284.616398) (xy 137.152796 -284.567344) (xy 137.164573 -284.51956) (xy 137.183864 -284.474284)
			(xy 137.210167 -284.432688) (xy 137.242802 -284.395851) (xy 137.280923 -284.364726) (xy 137.323544 -284.340119)
			(xy 137.36956 -284.322667) (xy 137.417779 -284.312823) (xy 137.466954 -284.310842) (xy 137.515809 -284.316774)
			(xy 137.56308 -284.330466) (xy 137.607542 -284.351564) (xy 137.648045 -284.37952) (xy 137.683538 -284.413612)
			(xy 137.713103 -284.452956) (xy 137.735974 -284.496533) (xy 137.751558 -284.543214) (xy 137.759453 -284.591791)
			(xy 137.759948 -284.616398) (xy 138.08889 -284.616398) (xy 138.09285 -284.567344) (xy 138.104627 -284.51956)
			(xy 138.123918 -284.474284) (xy 138.150221 -284.432688) (xy 138.182856 -284.395851) (xy 138.220977 -284.364726)
			(xy 138.263598 -284.340119) (xy 138.309614 -284.322667) (xy 138.357833 -284.312823) (xy 138.407008 -284.310842)
			(xy 138.455863 -284.316774) (xy 138.503134 -284.330466) (xy 138.547596 -284.351564) (xy 138.588099 -284.37952)
			(xy 138.623592 -284.413612) (xy 138.653157 -284.452956) (xy 138.676028 -284.496533) (xy 138.691612 -284.543214)
			(xy 138.699507 -284.591791) (xy 138.700002 -284.616398) (xy 139.028944 -284.616398) (xy 139.032904 -284.567344)
			(xy 139.044681 -284.51956) (xy 139.063972 -284.474284) (xy 139.090275 -284.432688) (xy 139.12291 -284.395851)
			(xy 139.161031 -284.364726) (xy 139.203652 -284.340119) (xy 139.249668 -284.322667) (xy 139.297887 -284.312823)
			(xy 139.347062 -284.310842) (xy 139.395917 -284.316774) (xy 139.443188 -284.330466) (xy 139.48765 -284.351564)
			(xy 139.528153 -284.37952) (xy 139.563646 -284.413612) (xy 139.593211 -284.452956) (xy 139.616082 -284.496533)
			(xy 139.631666 -284.543214) (xy 139.639561 -284.591791) (xy 139.640056 -284.616398) (xy 139.639561 -284.641005)
			(xy 139.631666 -284.689582) (xy 139.616082 -284.736263) (xy 139.593211 -284.77984) (xy 139.563646 -284.819184)
			(xy 139.528153 -284.853276) (xy 139.48765 -284.881232) (xy 139.443188 -284.90233) (xy 139.395917 -284.916022)
			(xy 139.347062 -284.921954) (xy 139.297887 -284.919973) (xy 139.249668 -284.910129) (xy 139.203652 -284.892677)
			(xy 139.161031 -284.86807) (xy 139.12291 -284.836945) (xy 139.090275 -284.800108) (xy 139.063972 -284.758512)
			(xy 139.044681 -284.713236) (xy 139.032904 -284.665452) (xy 139.028944 -284.616398) (xy 138.700002 -284.616398)
			(xy 138.699507 -284.641005) (xy 138.691612 -284.689582) (xy 138.676028 -284.736263) (xy 138.653157 -284.77984)
			(xy 138.623592 -284.819184) (xy 138.588099 -284.853276) (xy 138.547596 -284.881232) (xy 138.503134 -284.90233)
			(xy 138.455863 -284.916022) (xy 138.407008 -284.921954) (xy 138.357833 -284.919973) (xy 138.309614 -284.910129)
			(xy 138.263598 -284.892677) (xy 138.220977 -284.86807) (xy 138.182856 -284.836945) (xy 138.150221 -284.800108)
			(xy 138.123918 -284.758512) (xy 138.104627 -284.713236) (xy 138.09285 -284.665452) (xy 138.08889 -284.616398)
			(xy 137.759948 -284.616398) (xy 137.759453 -284.641005) (xy 137.751558 -284.689582) (xy 137.735974 -284.736263)
			(xy 137.713103 -284.77984) (xy 137.683538 -284.819184) (xy 137.648045 -284.853276) (xy 137.607542 -284.881232)
			(xy 137.56308 -284.90233) (xy 137.515809 -284.916022) (xy 137.466954 -284.921954) (xy 137.417779 -284.919973)
			(xy 137.36956 -284.910129) (xy 137.323544 -284.892677) (xy 137.280923 -284.86807) (xy 137.242802 -284.836945)
			(xy 137.210167 -284.800108) (xy 137.183864 -284.758512) (xy 137.164573 -284.713236) (xy 137.152796 -284.665452)
			(xy 137.148836 -284.616398) (xy 136.820148 -284.616398) (xy 136.819653 -284.641005) (xy 136.811758 -284.689582)
			(xy 136.796174 -284.736263) (xy 136.773303 -284.77984) (xy 136.743738 -284.819184) (xy 136.708245 -284.853276)
			(xy 136.667742 -284.881232) (xy 136.62328 -284.90233) (xy 136.576009 -284.916022) (xy 136.527154 -284.921954)
			(xy 136.477979 -284.919973) (xy 136.42976 -284.910129) (xy 136.383744 -284.892677) (xy 136.341123 -284.86807)
			(xy 136.303002 -284.836945) (xy 136.270367 -284.800108) (xy 136.244064 -284.758512) (xy 136.224773 -284.713236)
			(xy 136.212996 -284.665452) (xy 136.209036 -284.616398) (xy 135.880094 -284.616398) (xy 135.879599 -284.641005)
			(xy 135.871704 -284.689582) (xy 135.85612 -284.736263) (xy 135.833249 -284.77984) (xy 135.803684 -284.819184)
			(xy 135.768191 -284.853276) (xy 135.727688 -284.881232) (xy 135.683226 -284.90233) (xy 135.635955 -284.916022)
			(xy 135.5871 -284.921954) (xy 135.537925 -284.919973) (xy 135.489706 -284.910129) (xy 135.44369 -284.892677)
			(xy 135.401069 -284.86807) (xy 135.362948 -284.836945) (xy 135.330313 -284.800108) (xy 135.30401 -284.758512)
			(xy 135.284719 -284.713236) (xy 135.272942 -284.665452) (xy 135.268982 -284.616398) (xy 134.94004 -284.616398)
			(xy 134.939545 -284.641005) (xy 134.93165 -284.689582) (xy 134.916066 -284.736263) (xy 134.893195 -284.77984)
			(xy 134.86363 -284.819184) (xy 134.828137 -284.853276) (xy 134.787634 -284.881232) (xy 134.743172 -284.90233)
			(xy 134.695901 -284.916022) (xy 134.647046 -284.921954) (xy 134.597871 -284.919973) (xy 134.549652 -284.910129)
			(xy 134.503636 -284.892677) (xy 134.461015 -284.86807) (xy 134.422894 -284.836945) (xy 134.390259 -284.800108)
			(xy 134.363956 -284.758512) (xy 134.344665 -284.713236) (xy 134.332888 -284.665452) (xy 134.328928 -284.616398)
			(xy 133.999986 -284.616398) (xy 133.999491 -284.641005) (xy 133.991596 -284.689582) (xy 133.976012 -284.736263)
			(xy 133.953141 -284.77984) (xy 133.923576 -284.819184) (xy 133.888083 -284.853276) (xy 133.84758 -284.881232)
			(xy 133.803118 -284.90233) (xy 133.755847 -284.916022) (xy 133.706992 -284.921954) (xy 133.657817 -284.919973)
			(xy 133.609598 -284.910129) (xy 133.563582 -284.892677) (xy 133.520961 -284.86807) (xy 133.48284 -284.836945)
			(xy 133.450205 -284.800108) (xy 133.423902 -284.758512) (xy 133.404611 -284.713236) (xy 133.392834 -284.665452)
			(xy 133.388874 -284.616398) (xy 133.0706 -284.616398) (xy 133.070088 -284.641844) (xy 133.061924 -284.692078)
			(xy 133.045808 -284.740352) (xy 133.022157 -284.785415) (xy 132.991584 -284.826101) (xy 132.95488 -284.861356)
			(xy 132.912996 -284.890266) (xy 132.867017 -284.912083) (xy 132.818133 -284.926243) (xy 132.767612 -284.932377)
			(xy 132.71676 -284.930328) (xy 132.666896 -284.920148) (xy 132.61931 -284.902101) (xy 132.575236 -284.876655)
			(xy 132.535814 -284.844468) (xy 132.502066 -284.806374) (xy 132.474865 -284.76336) (xy 132.454917 -284.71654)
			(xy 132.442738 -284.667126) (xy 132.438643 -284.616398) (xy 132.130546 -284.616398) (xy 132.130034 -284.641844)
			(xy 132.12187 -284.692078) (xy 132.105754 -284.740352) (xy 132.082103 -284.785415) (xy 132.05153 -284.826101)
			(xy 132.014826 -284.861356) (xy 131.972942 -284.890266) (xy 131.926963 -284.912083) (xy 131.878079 -284.926243)
			(xy 131.827558 -284.932377) (xy 131.776706 -284.930328) (xy 131.726842 -284.920148) (xy 131.679256 -284.902101)
			(xy 131.635182 -284.876655) (xy 131.59576 -284.844468) (xy 131.562012 -284.806374) (xy 131.534811 -284.76336)
			(xy 131.514863 -284.71654) (xy 131.502684 -284.667126) (xy 131.498589 -284.616398) (xy 131.180078 -284.616398)
			(xy 131.179583 -284.641005) (xy 131.171688 -284.689582) (xy 131.156104 -284.736263) (xy 131.133233 -284.77984)
			(xy 131.103668 -284.819184) (xy 131.068175 -284.853276) (xy 131.027672 -284.881232) (xy 130.98321 -284.90233)
			(xy 130.935939 -284.916022) (xy 130.887084 -284.921954) (xy 130.837909 -284.919973) (xy 130.78969 -284.910129)
			(xy 130.743674 -284.892677) (xy 130.701053 -284.86807) (xy 130.662932 -284.836945) (xy 130.630297 -284.800108)
			(xy 130.603994 -284.758512) (xy 130.584703 -284.713236) (xy 130.572926 -284.665452) (xy 130.568966 -284.616398)
			(xy 130.250438 -284.616398) (xy 130.249926 -284.641844) (xy 130.241762 -284.692078) (xy 130.225646 -284.740352)
			(xy 130.201995 -284.785415) (xy 130.171422 -284.826101) (xy 130.134718 -284.861356) (xy 130.092834 -284.890266)
			(xy 130.046855 -284.912083) (xy 129.997971 -284.926243) (xy 129.94745 -284.932377) (xy 129.896598 -284.930328)
			(xy 129.846734 -284.920148) (xy 129.799148 -284.902101) (xy 129.755074 -284.876655) (xy 129.715652 -284.844468)
			(xy 129.681904 -284.806374) (xy 129.654703 -284.76336) (xy 129.634755 -284.71654) (xy 129.622576 -284.667126)
			(xy 129.618481 -284.616398) (xy 129.29997 -284.616398) (xy 129.299475 -284.641005) (xy 129.29158 -284.689582)
			(xy 129.275996 -284.736263) (xy 129.253125 -284.77984) (xy 129.22356 -284.819184) (xy 129.188067 -284.853276)
			(xy 129.147564 -284.881232) (xy 129.103102 -284.90233) (xy 129.055831 -284.916022) (xy 129.006976 -284.921954)
			(xy 128.957801 -284.919973) (xy 128.909582 -284.910129) (xy 128.863566 -284.892677) (xy 128.820945 -284.86807)
			(xy 128.782824 -284.836945) (xy 128.750189 -284.800108) (xy 128.723886 -284.758512) (xy 128.704595 -284.713236)
			(xy 128.692818 -284.665452) (xy 128.688858 -284.616398) (xy 128.370584 -284.616398) (xy 128.370072 -284.641844)
			(xy 128.361908 -284.692078) (xy 128.345792 -284.740352) (xy 128.322141 -284.785415) (xy 128.291568 -284.826101)
			(xy 128.254864 -284.861356) (xy 128.21298 -284.890266) (xy 128.167001 -284.912083) (xy 128.118117 -284.926243)
			(xy 128.067596 -284.932377) (xy 128.016744 -284.930328) (xy 127.96688 -284.920148) (xy 127.919294 -284.902101)
			(xy 127.87522 -284.876655) (xy 127.835798 -284.844468) (xy 127.80205 -284.806374) (xy 127.774849 -284.76336)
			(xy 127.754901 -284.71654) (xy 127.742722 -284.667126) (xy 127.738627 -284.616398) (xy 127.543814 -284.616398)
			(xy 127.543814 -284.731968) (xy 127.548894 -284.746954) (xy 127.55372 -284.753812) (xy 127.579493 -284.789336)
			(xy 127.626079 -284.863726) (xy 127.666757 -284.941505) (xy 127.70128 -285.022203) (xy 127.729443 -285.105336)
			(xy 127.740664 -285.147766) (xy 127.743256 -285.156469) (xy 127.753547 -285.171418) (xy 127.76073 -285.176976)
			(xy 127.781046 -285.191955) (xy 127.816934 -285.227444) (xy 127.846505 -285.268346) (xy 127.868956 -285.313549)
			(xy 127.883677 -285.361827) (xy 127.887476 -285.38678) (xy 127.888492 -285.395162) (xy 127.903478 -285.425896)
			(xy 127.903986 -285.426404) (xy 128.208527 -285.426404) (xy 128.212622 -285.375676) (xy 128.224801 -285.326262)
			(xy 128.244749 -285.279442) (xy 128.27195 -285.236428) (xy 128.305698 -285.198334) (xy 128.34512 -285.166147)
			(xy 128.389194 -285.140701) (xy 128.43678 -285.122654) (xy 128.486644 -285.112474) (xy 128.537496 -285.110425)
			(xy 128.588017 -285.116559) (xy 128.636901 -285.130719) (xy 128.68288 -285.152536) (xy 128.724764 -285.181446)
			(xy 128.761468 -285.216701) (xy 128.792041 -285.257387) (xy 128.815692 -285.30245) (xy 128.831808 -285.350724)
			(xy 128.839972 -285.400958) (xy 128.840484 -285.426404) (xy 129.148581 -285.426404) (xy 129.152676 -285.375676)
			(xy 129.164855 -285.326262) (xy 129.184803 -285.279442) (xy 129.212004 -285.236428) (xy 129.245752 -285.198334)
			(xy 129.285174 -285.166147) (xy 129.329248 -285.140701) (xy 129.376834 -285.122654) (xy 129.426698 -285.112474)
			(xy 129.47755 -285.110425) (xy 129.528071 -285.116559) (xy 129.576955 -285.130719) (xy 129.622934 -285.152536)
			(xy 129.664818 -285.181446) (xy 129.701522 -285.216701) (xy 129.732095 -285.257387) (xy 129.755746 -285.30245)
			(xy 129.771862 -285.350724) (xy 129.780026 -285.400958) (xy 129.780538 -285.426404) (xy 130.099066 -285.426404)
			(xy 130.103026 -285.37735) (xy 130.114803 -285.329566) (xy 130.134094 -285.28429) (xy 130.160397 -285.242694)
			(xy 130.193032 -285.205857) (xy 130.231153 -285.174732) (xy 130.273774 -285.150125) (xy 130.31979 -285.132673)
			(xy 130.368009 -285.122829) (xy 130.417184 -285.120848) (xy 130.466039 -285.12678) (xy 130.51331 -285.140472)
			(xy 130.557772 -285.16157) (xy 130.598275 -285.189526) (xy 130.633768 -285.223618) (xy 130.663333 -285.262962)
			(xy 130.686204 -285.306539) (xy 130.701788 -285.35322) (xy 130.709683 -285.401797) (xy 130.710178 -285.426404)
			(xy 131.028435 -285.426404) (xy 131.03253 -285.375676) (xy 131.044709 -285.326262) (xy 131.064657 -285.279442)
			(xy 131.091858 -285.236428) (xy 131.125606 -285.198334) (xy 131.165028 -285.166147) (xy 131.209102 -285.140701)
			(xy 131.256688 -285.122654) (xy 131.306552 -285.112474) (xy 131.357404 -285.110425) (xy 131.407925 -285.116559)
			(xy 131.456809 -285.130719) (xy 131.502788 -285.152536) (xy 131.544672 -285.181446) (xy 131.581376 -285.216701)
			(xy 131.611949 -285.257387) (xy 131.6356 -285.30245) (xy 131.651716 -285.350724) (xy 131.65988 -285.400958)
			(xy 131.660392 -285.426404) (xy 131.97892 -285.426404) (xy 131.98288 -285.37735) (xy 131.994657 -285.329566)
			(xy 132.013948 -285.28429) (xy 132.040251 -285.242694) (xy 132.072886 -285.205857) (xy 132.111007 -285.174732)
			(xy 132.153628 -285.150125) (xy 132.199644 -285.132673) (xy 132.247863 -285.122829) (xy 132.297038 -285.120848)
			(xy 132.345893 -285.12678) (xy 132.393164 -285.140472) (xy 132.437626 -285.16157) (xy 132.478129 -285.189526)
			(xy 132.513622 -285.223618) (xy 132.543187 -285.262962) (xy 132.566058 -285.306539) (xy 132.581642 -285.35322)
			(xy 132.589537 -285.401797) (xy 132.590032 -285.426404) (xy 132.908543 -285.426404) (xy 132.912638 -285.375676)
			(xy 132.924817 -285.326262) (xy 132.944765 -285.279442) (xy 132.971966 -285.236428) (xy 133.005714 -285.198334)
			(xy 133.045136 -285.166147) (xy 133.08921 -285.140701) (xy 133.136796 -285.122654) (xy 133.18666 -285.112474)
			(xy 133.237512 -285.110425) (xy 133.288033 -285.116559) (xy 133.336917 -285.130719) (xy 133.382896 -285.152536)
			(xy 133.42478 -285.181446) (xy 133.461484 -285.216701) (xy 133.492057 -285.257387) (xy 133.515708 -285.30245)
			(xy 133.531824 -285.350724) (xy 133.539988 -285.400958) (xy 133.5405 -285.426404) (xy 133.859028 -285.426404)
			(xy 133.862988 -285.37735) (xy 133.874765 -285.329566) (xy 133.894056 -285.28429) (xy 133.920359 -285.242694)
			(xy 133.952994 -285.205857) (xy 133.991115 -285.174732) (xy 134.033736 -285.150125) (xy 134.079752 -285.132673)
			(xy 134.127971 -285.122829) (xy 134.177146 -285.120848) (xy 134.226001 -285.12678) (xy 134.273272 -285.140472)
			(xy 134.317734 -285.16157) (xy 134.358237 -285.189526) (xy 134.39373 -285.223618) (xy 134.423295 -285.262962)
			(xy 134.446166 -285.306539) (xy 134.46175 -285.35322) (xy 134.469645 -285.401797) (xy 134.47014 -285.426404)
			(xy 134.798828 -285.426404) (xy 134.802788 -285.37735) (xy 134.814565 -285.329566) (xy 134.833856 -285.28429)
			(xy 134.860159 -285.242694) (xy 134.892794 -285.205857) (xy 134.930915 -285.174732) (xy 134.973536 -285.150125)
			(xy 135.019552 -285.132673) (xy 135.067771 -285.122829) (xy 135.116946 -285.120848) (xy 135.165801 -285.12678)
			(xy 135.213072 -285.140472) (xy 135.257534 -285.16157) (xy 135.298037 -285.189526) (xy 135.33353 -285.223618)
			(xy 135.363095 -285.262962) (xy 135.385966 -285.306539) (xy 135.40155 -285.35322) (xy 135.409445 -285.401797)
			(xy 135.40994 -285.426404) (xy 135.738882 -285.426404) (xy 135.742842 -285.37735) (xy 135.754619 -285.329566)
			(xy 135.77391 -285.28429) (xy 135.800213 -285.242694) (xy 135.832848 -285.205857) (xy 135.870969 -285.174732)
			(xy 135.91359 -285.150125) (xy 135.959606 -285.132673) (xy 136.007825 -285.122829) (xy 136.057 -285.120848)
			(xy 136.105855 -285.12678) (xy 136.153126 -285.140472) (xy 136.197588 -285.16157) (xy 136.238091 -285.189526)
			(xy 136.273584 -285.223618) (xy 136.303149 -285.262962) (xy 136.32602 -285.306539) (xy 136.341604 -285.35322)
			(xy 136.349499 -285.401797) (xy 136.349994 -285.426404) (xy 136.678936 -285.426404) (xy 136.682896 -285.37735)
			(xy 136.694673 -285.329566) (xy 136.713964 -285.28429) (xy 136.740267 -285.242694) (xy 136.772902 -285.205857)
			(xy 136.811023 -285.174732) (xy 136.853644 -285.150125) (xy 136.89966 -285.132673) (xy 136.947879 -285.122829)
			(xy 136.997054 -285.120848) (xy 137.045909 -285.12678) (xy 137.09318 -285.140472) (xy 137.137642 -285.16157)
			(xy 137.178145 -285.189526) (xy 137.213638 -285.223618) (xy 137.243203 -285.262962) (xy 137.266074 -285.306539)
			(xy 137.281658 -285.35322) (xy 137.289553 -285.401797) (xy 137.290048 -285.426404) (xy 137.61899 -285.426404)
			(xy 137.62295 -285.37735) (xy 137.634727 -285.329566) (xy 137.654018 -285.28429) (xy 137.680321 -285.242694)
			(xy 137.712956 -285.205857) (xy 137.751077 -285.174732) (xy 137.793698 -285.150125) (xy 137.839714 -285.132673)
			(xy 137.887933 -285.122829) (xy 137.937108 -285.120848) (xy 137.985963 -285.12678) (xy 138.033234 -285.140472)
			(xy 138.077696 -285.16157) (xy 138.118199 -285.189526) (xy 138.153692 -285.223618) (xy 138.183257 -285.262962)
			(xy 138.206128 -285.306539) (xy 138.221712 -285.35322) (xy 138.229607 -285.401797) (xy 138.230102 -285.426404)
			(xy 138.559044 -285.426404) (xy 138.563004 -285.37735) (xy 138.574781 -285.329566) (xy 138.594072 -285.28429)
			(xy 138.620375 -285.242694) (xy 138.65301 -285.205857) (xy 138.691131 -285.174732) (xy 138.733752 -285.150125)
			(xy 138.779768 -285.132673) (xy 138.827987 -285.122829) (xy 138.877162 -285.120848) (xy 138.926017 -285.12678)
			(xy 138.973288 -285.140472) (xy 139.01775 -285.16157) (xy 139.058253 -285.189526) (xy 139.093746 -285.223618)
			(xy 139.123311 -285.262962) (xy 139.146182 -285.306539) (xy 139.161766 -285.35322) (xy 139.169661 -285.401797)
			(xy 139.170156 -285.426404) (xy 139.498844 -285.426404) (xy 139.502804 -285.37735) (xy 139.514581 -285.329566)
			(xy 139.533872 -285.28429) (xy 139.560175 -285.242694) (xy 139.59281 -285.205857) (xy 139.630931 -285.174732)
			(xy 139.673552 -285.150125) (xy 139.719568 -285.132673) (xy 139.767787 -285.122829) (xy 139.816962 -285.120848)
			(xy 139.865817 -285.12678) (xy 139.913088 -285.140472) (xy 139.95755 -285.16157) (xy 139.998053 -285.189526)
			(xy 140.033546 -285.223618) (xy 140.063111 -285.262962) (xy 140.085982 -285.306539) (xy 140.101566 -285.35322)
			(xy 140.109461 -285.401797) (xy 140.109956 -285.426404) (xy 140.109461 -285.451011) (xy 140.101566 -285.499588)
			(xy 140.085982 -285.546269) (xy 140.063111 -285.589846) (xy 140.033546 -285.62919) (xy 139.998053 -285.663282)
			(xy 139.95755 -285.691238) (xy 139.913088 -285.712336) (xy 139.865817 -285.726028) (xy 139.816962 -285.73196)
			(xy 139.767787 -285.729979) (xy 139.719568 -285.720135) (xy 139.673552 -285.702683) (xy 139.630931 -285.678076)
			(xy 139.59281 -285.646951) (xy 139.560175 -285.610114) (xy 139.533872 -285.568518) (xy 139.514581 -285.523242)
			(xy 139.502804 -285.475458) (xy 139.498844 -285.426404) (xy 139.170156 -285.426404) (xy 139.169661 -285.451011)
			(xy 139.161766 -285.499588) (xy 139.146182 -285.546269) (xy 139.123311 -285.589846) (xy 139.093746 -285.62919)
			(xy 139.058253 -285.663282) (xy 139.01775 -285.691238) (xy 138.973288 -285.712336) (xy 138.926017 -285.726028)
			(xy 138.877162 -285.73196) (xy 138.827987 -285.729979) (xy 138.779768 -285.720135) (xy 138.733752 -285.702683)
			(xy 138.691131 -285.678076) (xy 138.65301 -285.646951) (xy 138.620375 -285.610114) (xy 138.594072 -285.568518)
			(xy 138.574781 -285.523242) (xy 138.563004 -285.475458) (xy 138.559044 -285.426404) (xy 138.230102 -285.426404)
			(xy 138.229607 -285.451011) (xy 138.221712 -285.499588) (xy 138.206128 -285.546269) (xy 138.183257 -285.589846)
			(xy 138.153692 -285.62919) (xy 138.118199 -285.663282) (xy 138.077696 -285.691238) (xy 138.033234 -285.712336)
			(xy 137.985963 -285.726028) (xy 137.937108 -285.73196) (xy 137.887933 -285.729979) (xy 137.839714 -285.720135)
			(xy 137.793698 -285.702683) (xy 137.751077 -285.678076) (xy 137.712956 -285.646951) (xy 137.680321 -285.610114)
			(xy 137.654018 -285.568518) (xy 137.634727 -285.523242) (xy 137.62295 -285.475458) (xy 137.61899 -285.426404)
			(xy 137.290048 -285.426404) (xy 137.289553 -285.451011) (xy 137.281658 -285.499588) (xy 137.266074 -285.546269)
			(xy 137.243203 -285.589846) (xy 137.213638 -285.62919) (xy 137.178145 -285.663282) (xy 137.137642 -285.691238)
			(xy 137.09318 -285.712336) (xy 137.045909 -285.726028) (xy 136.997054 -285.73196) (xy 136.947879 -285.729979)
			(xy 136.89966 -285.720135) (xy 136.853644 -285.702683) (xy 136.811023 -285.678076) (xy 136.772902 -285.646951)
			(xy 136.740267 -285.610114) (xy 136.713964 -285.568518) (xy 136.694673 -285.523242) (xy 136.682896 -285.475458)
			(xy 136.678936 -285.426404) (xy 136.349994 -285.426404) (xy 136.349499 -285.451011) (xy 136.341604 -285.499588)
			(xy 136.32602 -285.546269) (xy 136.303149 -285.589846) (xy 136.273584 -285.62919) (xy 136.238091 -285.663282)
			(xy 136.197588 -285.691238) (xy 136.153126 -285.712336) (xy 136.105855 -285.726028) (xy 136.057 -285.73196)
			(xy 136.007825 -285.729979) (xy 135.959606 -285.720135) (xy 135.91359 -285.702683) (xy 135.870969 -285.678076)
			(xy 135.832848 -285.646951) (xy 135.800213 -285.610114) (xy 135.77391 -285.568518) (xy 135.754619 -285.523242)
			(xy 135.742842 -285.475458) (xy 135.738882 -285.426404) (xy 135.40994 -285.426404) (xy 135.409445 -285.451011)
			(xy 135.40155 -285.499588) (xy 135.385966 -285.546269) (xy 135.363095 -285.589846) (xy 135.33353 -285.62919)
			(xy 135.298037 -285.663282) (xy 135.257534 -285.691238) (xy 135.213072 -285.712336) (xy 135.165801 -285.726028)
			(xy 135.116946 -285.73196) (xy 135.067771 -285.729979) (xy 135.019552 -285.720135) (xy 134.973536 -285.702683)
			(xy 134.930915 -285.678076) (xy 134.892794 -285.646951) (xy 134.860159 -285.610114) (xy 134.833856 -285.568518)
			(xy 134.814565 -285.523242) (xy 134.802788 -285.475458) (xy 134.798828 -285.426404) (xy 134.47014 -285.426404)
			(xy 134.469645 -285.451011) (xy 134.46175 -285.499588) (xy 134.446166 -285.546269) (xy 134.423295 -285.589846)
			(xy 134.39373 -285.62919) (xy 134.358237 -285.663282) (xy 134.317734 -285.691238) (xy 134.273272 -285.712336)
			(xy 134.226001 -285.726028) (xy 134.177146 -285.73196) (xy 134.127971 -285.729979) (xy 134.079752 -285.720135)
			(xy 134.033736 -285.702683) (xy 133.991115 -285.678076) (xy 133.952994 -285.646951) (xy 133.920359 -285.610114)
			(xy 133.894056 -285.568518) (xy 133.874765 -285.523242) (xy 133.862988 -285.475458) (xy 133.859028 -285.426404)
			(xy 133.5405 -285.426404) (xy 133.539988 -285.45185) (xy 133.531824 -285.502084) (xy 133.515708 -285.550358)
			(xy 133.492057 -285.595421) (xy 133.461484 -285.636107) (xy 133.42478 -285.671362) (xy 133.382896 -285.700272)
			(xy 133.336917 -285.722089) (xy 133.288033 -285.736249) (xy 133.237512 -285.742383) (xy 133.18666 -285.740334)
			(xy 133.136796 -285.730154) (xy 133.08921 -285.712107) (xy 133.045136 -285.686661) (xy 133.005714 -285.654474)
			(xy 132.971966 -285.61638) (xy 132.944765 -285.573366) (xy 132.924817 -285.526546) (xy 132.912638 -285.477132)
			(xy 132.908543 -285.426404) (xy 132.590032 -285.426404) (xy 132.589537 -285.451011) (xy 132.581642 -285.499588)
			(xy 132.566058 -285.546269) (xy 132.543187 -285.589846) (xy 132.513622 -285.62919) (xy 132.478129 -285.663282)
			(xy 132.437626 -285.691238) (xy 132.393164 -285.712336) (xy 132.345893 -285.726028) (xy 132.297038 -285.73196)
			(xy 132.247863 -285.729979) (xy 132.199644 -285.720135) (xy 132.153628 -285.702683) (xy 132.111007 -285.678076)
			(xy 132.072886 -285.646951) (xy 132.040251 -285.610114) (xy 132.013948 -285.568518) (xy 131.994657 -285.523242)
			(xy 131.98288 -285.475458) (xy 131.97892 -285.426404) (xy 131.660392 -285.426404) (xy 131.65988 -285.45185)
			(xy 131.651716 -285.502084) (xy 131.6356 -285.550358) (xy 131.611949 -285.595421) (xy 131.581376 -285.636107)
			(xy 131.544672 -285.671362) (xy 131.502788 -285.700272) (xy 131.456809 -285.722089) (xy 131.407925 -285.736249)
			(xy 131.357404 -285.742383) (xy 131.306552 -285.740334) (xy 131.256688 -285.730154) (xy 131.209102 -285.712107)
			(xy 131.165028 -285.686661) (xy 131.125606 -285.654474) (xy 131.091858 -285.61638) (xy 131.064657 -285.573366)
			(xy 131.044709 -285.526546) (xy 131.03253 -285.477132) (xy 131.028435 -285.426404) (xy 130.710178 -285.426404)
			(xy 130.709683 -285.451011) (xy 130.701788 -285.499588) (xy 130.686204 -285.546269) (xy 130.663333 -285.589846)
			(xy 130.633768 -285.62919) (xy 130.598275 -285.663282) (xy 130.557772 -285.691238) (xy 130.51331 -285.712336)
			(xy 130.466039 -285.726028) (xy 130.417184 -285.73196) (xy 130.368009 -285.729979) (xy 130.31979 -285.720135)
			(xy 130.273774 -285.702683) (xy 130.231153 -285.678076) (xy 130.193032 -285.646951) (xy 130.160397 -285.610114)
			(xy 130.134094 -285.568518) (xy 130.114803 -285.523242) (xy 130.103026 -285.475458) (xy 130.099066 -285.426404)
			(xy 129.780538 -285.426404) (xy 129.780026 -285.45185) (xy 129.771862 -285.502084) (xy 129.755746 -285.550358)
			(xy 129.732095 -285.595421) (xy 129.701522 -285.636107) (xy 129.664818 -285.671362) (xy 129.622934 -285.700272)
			(xy 129.576955 -285.722089) (xy 129.528071 -285.736249) (xy 129.47755 -285.742383) (xy 129.426698 -285.740334)
			(xy 129.376834 -285.730154) (xy 129.329248 -285.712107) (xy 129.285174 -285.686661) (xy 129.245752 -285.654474)
			(xy 129.212004 -285.61638) (xy 129.184803 -285.573366) (xy 129.164855 -285.526546) (xy 129.152676 -285.477132)
			(xy 129.148581 -285.426404) (xy 128.840484 -285.426404) (xy 128.839972 -285.45185) (xy 128.831808 -285.502084)
			(xy 128.815692 -285.550358) (xy 128.792041 -285.595421) (xy 128.761468 -285.636107) (xy 128.724764 -285.671362)
			(xy 128.68288 -285.700272) (xy 128.636901 -285.722089) (xy 128.588017 -285.736249) (xy 128.537496 -285.742383)
			(xy 128.486644 -285.740334) (xy 128.43678 -285.730154) (xy 128.389194 -285.712107) (xy 128.34512 -285.686661)
			(xy 128.305698 -285.654474) (xy 128.27195 -285.61638) (xy 128.244749 -285.573366) (xy 128.224801 -285.526546)
			(xy 128.212622 -285.477132) (xy 128.208527 -285.426404) (xy 127.903986 -285.426404) (xy 127.909574 -285.431992)
			(xy 127.94472 -285.467463) (xy 128.009318 -285.543618) (xy 128.066946 -285.625174) (xy 128.117155 -285.711497)
			(xy 128.159553 -285.801911) (xy 128.19381 -285.895714) (xy 128.207262 -285.943802) (xy 128.20853 -285.948077)
			(xy 128.212362 -285.956126) (xy 128.214882 -285.959804) (xy 128.220216 -285.967678) (xy 128.242787 -285.982183)
			(xy 128.283086 -286.0176) (xy 128.316818 -286.059319) (xy 128.343014 -286.106139) (xy 128.360919 -286.156713)
			(xy 128.370019 -286.209585) (xy 128.370584 -286.23641) (xy 128.688858 -286.23641) (xy 128.692818 -286.187356)
			(xy 128.704595 -286.139572) (xy 128.723886 -286.094296) (xy 128.750189 -286.0527) (xy 128.782824 -286.015863)
			(xy 128.820945 -285.984738) (xy 128.863566 -285.960131) (xy 128.909582 -285.942679) (xy 128.957801 -285.932835)
			(xy 129.006976 -285.930854) (xy 129.055831 -285.936786) (xy 129.103102 -285.950478) (xy 129.147564 -285.971576)
			(xy 129.188067 -285.999532) (xy 129.22356 -286.033624) (xy 129.253125 -286.072968) (xy 129.275996 -286.116545)
			(xy 129.29158 -286.163226) (xy 129.299475 -286.211803) (xy 129.29997 -286.23641) (xy 129.618481 -286.23641)
			(xy 129.622576 -286.185682) (xy 129.634755 -286.136268) (xy 129.654703 -286.089448) (xy 129.681904 -286.046434)
			(xy 129.715652 -286.00834) (xy 129.755074 -285.976153) (xy 129.799148 -285.950707) (xy 129.846734 -285.93266)
			(xy 129.896598 -285.92248) (xy 129.94745 -285.920431) (xy 129.997971 -285.926565) (xy 130.046855 -285.940725)
			(xy 130.092834 -285.962542) (xy 130.134718 -285.991452) (xy 130.171422 -286.026707) (xy 130.201995 -286.067393)
			(xy 130.225646 -286.112456) (xy 130.241762 -286.16073) (xy 130.249926 -286.210964) (xy 130.250438 -286.23641)
			(xy 130.568966 -286.23641) (xy 130.572926 -286.187356) (xy 130.584703 -286.139572) (xy 130.603994 -286.094296)
			(xy 130.630297 -286.0527) (xy 130.662932 -286.015863) (xy 130.701053 -285.984738) (xy 130.743674 -285.960131)
			(xy 130.78969 -285.942679) (xy 130.837909 -285.932835) (xy 130.887084 -285.930854) (xy 130.935939 -285.936786)
			(xy 130.98321 -285.950478) (xy 131.027672 -285.971576) (xy 131.068175 -285.999532) (xy 131.103668 -286.033624)
			(xy 131.133233 -286.072968) (xy 131.156104 -286.116545) (xy 131.171688 -286.163226) (xy 131.179583 -286.211803)
			(xy 131.180078 -286.23641) (xy 131.498589 -286.23641) (xy 131.502684 -286.185682) (xy 131.514863 -286.136268)
			(xy 131.534811 -286.089448) (xy 131.562012 -286.046434) (xy 131.59576 -286.00834) (xy 131.635182 -285.976153)
			(xy 131.679256 -285.950707) (xy 131.726842 -285.93266) (xy 131.776706 -285.92248) (xy 131.827558 -285.920431)
			(xy 131.878079 -285.926565) (xy 131.926963 -285.940725) (xy 131.972942 -285.962542) (xy 132.014826 -285.991452)
			(xy 132.05153 -286.026707) (xy 132.082103 -286.067393) (xy 132.105754 -286.112456) (xy 132.12187 -286.16073)
			(xy 132.130034 -286.210964) (xy 132.130546 -286.23641) (xy 132.438643 -286.23641) (xy 132.442738 -286.185682)
			(xy 132.454917 -286.136268) (xy 132.474865 -286.089448) (xy 132.502066 -286.046434) (xy 132.535814 -286.00834)
			(xy 132.575236 -285.976153) (xy 132.61931 -285.950707) (xy 132.666896 -285.93266) (xy 132.71676 -285.92248)
			(xy 132.767612 -285.920431) (xy 132.818133 -285.926565) (xy 132.867017 -285.940725) (xy 132.912996 -285.962542)
			(xy 132.95488 -285.991452) (xy 132.991584 -286.026707) (xy 133.022157 -286.067393) (xy 133.045808 -286.112456)
			(xy 133.061924 -286.16073) (xy 133.070088 -286.210964) (xy 133.0706 -286.23641) (xy 133.388874 -286.23641)
			(xy 133.392834 -286.187356) (xy 133.404611 -286.139572) (xy 133.423902 -286.094296) (xy 133.450205 -286.0527)
			(xy 133.48284 -286.015863) (xy 133.520961 -285.984738) (xy 133.563582 -285.960131) (xy 133.609598 -285.942679)
			(xy 133.657817 -285.932835) (xy 133.706992 -285.930854) (xy 133.755847 -285.936786) (xy 133.803118 -285.950478)
			(xy 133.84758 -285.971576) (xy 133.888083 -285.999532) (xy 133.923576 -286.033624) (xy 133.953141 -286.072968)
			(xy 133.976012 -286.116545) (xy 133.991596 -286.163226) (xy 133.999491 -286.211803) (xy 133.999986 -286.23641)
			(xy 134.328928 -286.23641) (xy 134.332888 -286.187356) (xy 134.344665 -286.139572) (xy 134.363956 -286.094296)
			(xy 134.390259 -286.0527) (xy 134.422894 -286.015863) (xy 134.461015 -285.984738) (xy 134.503636 -285.960131)
			(xy 134.549652 -285.942679) (xy 134.597871 -285.932835) (xy 134.647046 -285.930854) (xy 134.695901 -285.936786)
			(xy 134.743172 -285.950478) (xy 134.787634 -285.971576) (xy 134.828137 -285.999532) (xy 134.86363 -286.033624)
			(xy 134.893195 -286.072968) (xy 134.916066 -286.116545) (xy 134.93165 -286.163226) (xy 134.939545 -286.211803)
			(xy 134.94004 -286.23641) (xy 135.268982 -286.23641) (xy 135.272942 -286.187356) (xy 135.284719 -286.139572)
			(xy 135.30401 -286.094296) (xy 135.330313 -286.0527) (xy 135.362948 -286.015863) (xy 135.401069 -285.984738)
			(xy 135.44369 -285.960131) (xy 135.489706 -285.942679) (xy 135.537925 -285.932835) (xy 135.5871 -285.930854)
			(xy 135.635955 -285.936786) (xy 135.683226 -285.950478) (xy 135.727688 -285.971576) (xy 135.768191 -285.999532)
			(xy 135.803684 -286.033624) (xy 135.833249 -286.072968) (xy 135.85612 -286.116545) (xy 135.871704 -286.163226)
			(xy 135.879599 -286.211803) (xy 135.880094 -286.23641) (xy 136.209036 -286.23641) (xy 136.212996 -286.187356)
			(xy 136.224773 -286.139572) (xy 136.244064 -286.094296) (xy 136.270367 -286.0527) (xy 136.303002 -286.015863)
			(xy 136.341123 -285.984738) (xy 136.383744 -285.960131) (xy 136.42976 -285.942679) (xy 136.477979 -285.932835)
			(xy 136.527154 -285.930854) (xy 136.576009 -285.936786) (xy 136.62328 -285.950478) (xy 136.667742 -285.971576)
			(xy 136.708245 -285.999532) (xy 136.743738 -286.033624) (xy 136.773303 -286.072968) (xy 136.796174 -286.116545)
			(xy 136.811758 -286.163226) (xy 136.819653 -286.211803) (xy 136.820148 -286.23641) (xy 137.148836 -286.23641)
			(xy 137.152796 -286.187356) (xy 137.164573 -286.139572) (xy 137.183864 -286.094296) (xy 137.210167 -286.0527)
			(xy 137.242802 -286.015863) (xy 137.280923 -285.984738) (xy 137.323544 -285.960131) (xy 137.36956 -285.942679)
			(xy 137.417779 -285.932835) (xy 137.466954 -285.930854) (xy 137.515809 -285.936786) (xy 137.56308 -285.950478)
			(xy 137.607542 -285.971576) (xy 137.648045 -285.999532) (xy 137.683538 -286.033624) (xy 137.713103 -286.072968)
			(xy 137.735974 -286.116545) (xy 137.751558 -286.163226) (xy 137.759453 -286.211803) (xy 137.759948 -286.23641)
			(xy 138.08889 -286.23641) (xy 138.09285 -286.187356) (xy 138.104627 -286.139572) (xy 138.123918 -286.094296)
			(xy 138.150221 -286.0527) (xy 138.182856 -286.015863) (xy 138.220977 -285.984738) (xy 138.263598 -285.960131)
			(xy 138.309614 -285.942679) (xy 138.357833 -285.932835) (xy 138.407008 -285.930854) (xy 138.455863 -285.936786)
			(xy 138.503134 -285.950478) (xy 138.547596 -285.971576) (xy 138.588099 -285.999532) (xy 138.623592 -286.033624)
			(xy 138.653157 -286.072968) (xy 138.676028 -286.116545) (xy 138.691612 -286.163226) (xy 138.699507 -286.211803)
			(xy 138.700002 -286.23641) (xy 139.028944 -286.23641) (xy 139.032904 -286.187356) (xy 139.044681 -286.139572)
			(xy 139.063972 -286.094296) (xy 139.090275 -286.0527) (xy 139.12291 -286.015863) (xy 139.161031 -285.984738)
			(xy 139.203652 -285.960131) (xy 139.249668 -285.942679) (xy 139.297887 -285.932835) (xy 139.347062 -285.930854)
			(xy 139.395917 -285.936786) (xy 139.443188 -285.950478) (xy 139.48765 -285.971576) (xy 139.528153 -285.999532)
			(xy 139.563646 -286.033624) (xy 139.593211 -286.072968) (xy 139.616082 -286.116545) (xy 139.631666 -286.163226)
			(xy 139.639561 -286.211803) (xy 139.640056 -286.23641) (xy 139.639561 -286.261017) (xy 139.631666 -286.309594)
			(xy 139.616082 -286.356275) (xy 139.593211 -286.399852) (xy 139.563646 -286.439196) (xy 139.528153 -286.473288)
			(xy 139.48765 -286.501244) (xy 139.443188 -286.522342) (xy 139.395917 -286.536034) (xy 139.347062 -286.541966)
			(xy 139.297887 -286.539985) (xy 139.249668 -286.530141) (xy 139.203652 -286.512689) (xy 139.161031 -286.488082)
			(xy 139.12291 -286.456957) (xy 139.090275 -286.42012) (xy 139.063972 -286.378524) (xy 139.044681 -286.333248)
			(xy 139.032904 -286.285464) (xy 139.028944 -286.23641) (xy 138.700002 -286.23641) (xy 138.699507 -286.261017)
			(xy 138.691612 -286.309594) (xy 138.676028 -286.356275) (xy 138.653157 -286.399852) (xy 138.623592 -286.439196)
			(xy 138.588099 -286.473288) (xy 138.547596 -286.501244) (xy 138.503134 -286.522342) (xy 138.455863 -286.536034)
			(xy 138.407008 -286.541966) (xy 138.357833 -286.539985) (xy 138.309614 -286.530141) (xy 138.263598 -286.512689)
			(xy 138.220977 -286.488082) (xy 138.182856 -286.456957) (xy 138.150221 -286.42012) (xy 138.123918 -286.378524)
			(xy 138.104627 -286.333248) (xy 138.09285 -286.285464) (xy 138.08889 -286.23641) (xy 137.759948 -286.23641)
			(xy 137.759453 -286.261017) (xy 137.751558 -286.309594) (xy 137.735974 -286.356275) (xy 137.713103 -286.399852)
			(xy 137.683538 -286.439196) (xy 137.648045 -286.473288) (xy 137.607542 -286.501244) (xy 137.56308 -286.522342)
			(xy 137.515809 -286.536034) (xy 137.466954 -286.541966) (xy 137.417779 -286.539985) (xy 137.36956 -286.530141)
			(xy 137.323544 -286.512689) (xy 137.280923 -286.488082) (xy 137.242802 -286.456957) (xy 137.210167 -286.42012)
			(xy 137.183864 -286.378524) (xy 137.164573 -286.333248) (xy 137.152796 -286.285464) (xy 137.148836 -286.23641)
			(xy 136.820148 -286.23641) (xy 136.819653 -286.261017) (xy 136.811758 -286.309594) (xy 136.796174 -286.356275)
			(xy 136.773303 -286.399852) (xy 136.743738 -286.439196) (xy 136.708245 -286.473288) (xy 136.667742 -286.501244)
			(xy 136.62328 -286.522342) (xy 136.576009 -286.536034) (xy 136.527154 -286.541966) (xy 136.477979 -286.539985)
			(xy 136.42976 -286.530141) (xy 136.383744 -286.512689) (xy 136.341123 -286.488082) (xy 136.303002 -286.456957)
			(xy 136.270367 -286.42012) (xy 136.244064 -286.378524) (xy 136.224773 -286.333248) (xy 136.212996 -286.285464)
			(xy 136.209036 -286.23641) (xy 135.880094 -286.23641) (xy 135.879599 -286.261017) (xy 135.871704 -286.309594)
			(xy 135.85612 -286.356275) (xy 135.833249 -286.399852) (xy 135.803684 -286.439196) (xy 135.768191 -286.473288)
			(xy 135.727688 -286.501244) (xy 135.683226 -286.522342) (xy 135.635955 -286.536034) (xy 135.5871 -286.541966)
			(xy 135.537925 -286.539985) (xy 135.489706 -286.530141) (xy 135.44369 -286.512689) (xy 135.401069 -286.488082)
			(xy 135.362948 -286.456957) (xy 135.330313 -286.42012) (xy 135.30401 -286.378524) (xy 135.284719 -286.333248)
			(xy 135.272942 -286.285464) (xy 135.268982 -286.23641) (xy 134.94004 -286.23641) (xy 134.939545 -286.261017)
			(xy 134.93165 -286.309594) (xy 134.916066 -286.356275) (xy 134.893195 -286.399852) (xy 134.86363 -286.439196)
			(xy 134.828137 -286.473288) (xy 134.787634 -286.501244) (xy 134.743172 -286.522342) (xy 134.695901 -286.536034)
			(xy 134.647046 -286.541966) (xy 134.597871 -286.539985) (xy 134.549652 -286.530141) (xy 134.503636 -286.512689)
			(xy 134.461015 -286.488082) (xy 134.422894 -286.456957) (xy 134.390259 -286.42012) (xy 134.363956 -286.378524)
			(xy 134.344665 -286.333248) (xy 134.332888 -286.285464) (xy 134.328928 -286.23641) (xy 133.999986 -286.23641)
			(xy 133.999491 -286.261017) (xy 133.991596 -286.309594) (xy 133.976012 -286.356275) (xy 133.953141 -286.399852)
			(xy 133.923576 -286.439196) (xy 133.888083 -286.473288) (xy 133.84758 -286.501244) (xy 133.803118 -286.522342)
			(xy 133.755847 -286.536034) (xy 133.706992 -286.541966) (xy 133.657817 -286.539985) (xy 133.609598 -286.530141)
			(xy 133.563582 -286.512689) (xy 133.520961 -286.488082) (xy 133.48284 -286.456957) (xy 133.450205 -286.42012)
			(xy 133.423902 -286.378524) (xy 133.404611 -286.333248) (xy 133.392834 -286.285464) (xy 133.388874 -286.23641)
			(xy 133.0706 -286.23641) (xy 133.070088 -286.261856) (xy 133.061924 -286.31209) (xy 133.045808 -286.360364)
			(xy 133.022157 -286.405427) (xy 132.991584 -286.446113) (xy 132.95488 -286.481368) (xy 132.912996 -286.510278)
			(xy 132.867017 -286.532095) (xy 132.818133 -286.546255) (xy 132.767612 -286.552389) (xy 132.71676 -286.55034)
			(xy 132.666896 -286.54016) (xy 132.61931 -286.522113) (xy 132.575236 -286.496667) (xy 132.535814 -286.46448)
			(xy 132.502066 -286.426386) (xy 132.474865 -286.383372) (xy 132.454917 -286.336552) (xy 132.442738 -286.287138)
			(xy 132.438643 -286.23641) (xy 132.130546 -286.23641) (xy 132.130034 -286.261856) (xy 132.12187 -286.31209)
			(xy 132.105754 -286.360364) (xy 132.082103 -286.405427) (xy 132.05153 -286.446113) (xy 132.014826 -286.481368)
			(xy 131.972942 -286.510278) (xy 131.926963 -286.532095) (xy 131.878079 -286.546255) (xy 131.827558 -286.552389)
			(xy 131.776706 -286.55034) (xy 131.726842 -286.54016) (xy 131.679256 -286.522113) (xy 131.635182 -286.496667)
			(xy 131.59576 -286.46448) (xy 131.562012 -286.426386) (xy 131.534811 -286.383372) (xy 131.514863 -286.336552)
			(xy 131.502684 -286.287138) (xy 131.498589 -286.23641) (xy 131.180078 -286.23641) (xy 131.179583 -286.261017)
			(xy 131.171688 -286.309594) (xy 131.156104 -286.356275) (xy 131.133233 -286.399852) (xy 131.103668 -286.439196)
			(xy 131.068175 -286.473288) (xy 131.027672 -286.501244) (xy 130.98321 -286.522342) (xy 130.935939 -286.536034)
			(xy 130.887084 -286.541966) (xy 130.837909 -286.539985) (xy 130.78969 -286.530141) (xy 130.743674 -286.512689)
			(xy 130.701053 -286.488082) (xy 130.662932 -286.456957) (xy 130.630297 -286.42012) (xy 130.603994 -286.378524)
			(xy 130.584703 -286.333248) (xy 130.572926 -286.285464) (xy 130.568966 -286.23641) (xy 130.250438 -286.23641)
			(xy 130.249926 -286.261856) (xy 130.241762 -286.31209) (xy 130.225646 -286.360364) (xy 130.201995 -286.405427)
			(xy 130.171422 -286.446113) (xy 130.134718 -286.481368) (xy 130.092834 -286.510278) (xy 130.046855 -286.532095)
			(xy 129.997971 -286.546255) (xy 129.94745 -286.552389) (xy 129.896598 -286.55034) (xy 129.846734 -286.54016)
			(xy 129.799148 -286.522113) (xy 129.755074 -286.496667) (xy 129.715652 -286.46448) (xy 129.681904 -286.426386)
			(xy 129.654703 -286.383372) (xy 129.634755 -286.336552) (xy 129.622576 -286.287138) (xy 129.618481 -286.23641)
			(xy 129.29997 -286.23641) (xy 129.299475 -286.261017) (xy 129.29158 -286.309594) (xy 129.275996 -286.356275)
			(xy 129.253125 -286.399852) (xy 129.22356 -286.439196) (xy 129.188067 -286.473288) (xy 129.147564 -286.501244)
			(xy 129.103102 -286.522342) (xy 129.055831 -286.536034) (xy 129.006976 -286.541966) (xy 128.957801 -286.539985)
			(xy 128.909582 -286.530141) (xy 128.863566 -286.512689) (xy 128.820945 -286.488082) (xy 128.782824 -286.456957)
			(xy 128.750189 -286.42012) (xy 128.723886 -286.378524) (xy 128.704595 -286.333248) (xy 128.692818 -286.285464)
			(xy 128.688858 -286.23641) (xy 128.370584 -286.23641) (xy 128.370056 -286.262472) (xy 128.361506 -286.31389)
			(xy 128.344622 -286.363204) (xy 128.319865 -286.409073) (xy 128.287907 -286.450251) (xy 128.249617 -286.485617)
			(xy 128.22809 -286.500316) (xy 128.22414 -286.503031) (xy 128.217239 -286.509681) (xy 128.214374 -286.513524)
			(xy 128.209548 -286.520382) (xy 128.196076 -286.569985) (xy 128.161335 -286.666728) (xy 128.117955 -286.759918)
			(xy 128.066295 -286.848787) (xy 128.006782 -286.932599) (xy 127.939907 -287.010663) (xy 127.904244 -287.046162)
			(xy 128.208527 -287.046162) (xy 128.212622 -286.995434) (xy 128.224801 -286.94602) (xy 128.244749 -286.8992)
			(xy 128.27195 -286.856186) (xy 128.305698 -286.818092) (xy 128.34512 -286.785905) (xy 128.389194 -286.760459)
			(xy 128.43678 -286.742412) (xy 128.486644 -286.732232) (xy 128.537496 -286.730183) (xy 128.588017 -286.736317)
			(xy 128.636901 -286.750477) (xy 128.68288 -286.772294) (xy 128.724764 -286.801204) (xy 128.761468 -286.836459)
			(xy 128.792041 -286.877145) (xy 128.815692 -286.922208) (xy 128.831808 -286.970482) (xy 128.839972 -287.020716)
			(xy 128.840484 -287.046162) (xy 129.148581 -287.046162) (xy 129.152676 -286.995434) (xy 129.164855 -286.94602)
			(xy 129.184803 -286.8992) (xy 129.212004 -286.856186) (xy 129.245752 -286.818092) (xy 129.285174 -286.785905)
			(xy 129.329248 -286.760459) (xy 129.376834 -286.742412) (xy 129.426698 -286.732232) (xy 129.47755 -286.730183)
			(xy 129.528071 -286.736317) (xy 129.576955 -286.750477) (xy 129.622934 -286.772294) (xy 129.664818 -286.801204)
			(xy 129.701522 -286.836459) (xy 129.732095 -286.877145) (xy 129.755746 -286.922208) (xy 129.771862 -286.970482)
			(xy 129.780026 -287.020716) (xy 129.780538 -287.046162) (xy 129.780533 -287.046416) (xy 130.099066 -287.046416)
			(xy 130.103026 -286.997362) (xy 130.114803 -286.949578) (xy 130.134094 -286.904302) (xy 130.160397 -286.862706)
			(xy 130.193032 -286.825869) (xy 130.231153 -286.794744) (xy 130.273774 -286.770137) (xy 130.31979 -286.752685)
			(xy 130.368009 -286.742841) (xy 130.417184 -286.74086) (xy 130.466039 -286.746792) (xy 130.51331 -286.760484)
			(xy 130.557772 -286.781582) (xy 130.598275 -286.809538) (xy 130.633768 -286.84363) (xy 130.663333 -286.882974)
			(xy 130.686204 -286.926551) (xy 130.701788 -286.973232) (xy 130.709683 -287.021809) (xy 130.710173 -287.046162)
			(xy 131.028435 -287.046162) (xy 131.03253 -286.995434) (xy 131.044709 -286.94602) (xy 131.064657 -286.8992)
			(xy 131.091858 -286.856186) (xy 131.125606 -286.818092) (xy 131.165028 -286.785905) (xy 131.209102 -286.760459)
			(xy 131.256688 -286.742412) (xy 131.306552 -286.732232) (xy 131.357404 -286.730183) (xy 131.407925 -286.736317)
			(xy 131.456809 -286.750477) (xy 131.502788 -286.772294) (xy 131.544672 -286.801204) (xy 131.581376 -286.836459)
			(xy 131.611949 -286.877145) (xy 131.6356 -286.922208) (xy 131.651716 -286.970482) (xy 131.65988 -287.020716)
			(xy 131.660392 -287.046162) (xy 131.97892 -287.046162) (xy 131.98288 -286.997108) (xy 131.994657 -286.949324)
			(xy 132.013948 -286.904048) (xy 132.040251 -286.862452) (xy 132.072886 -286.825615) (xy 132.111007 -286.79449)
			(xy 132.153628 -286.769883) (xy 132.199644 -286.752431) (xy 132.247863 -286.742587) (xy 132.297038 -286.740606)
			(xy 132.345893 -286.746538) (xy 132.393164 -286.76023) (xy 132.437626 -286.781328) (xy 132.478129 -286.809284)
			(xy 132.513622 -286.843376) (xy 132.543187 -286.88272) (xy 132.566058 -286.926297) (xy 132.581642 -286.972978)
			(xy 132.589537 -287.021555) (xy 132.590032 -287.046162) (xy 132.908543 -287.046162) (xy 132.912638 -286.995434)
			(xy 132.924817 -286.94602) (xy 132.944765 -286.8992) (xy 132.971966 -286.856186) (xy 133.005714 -286.818092)
			(xy 133.045136 -286.785905) (xy 133.08921 -286.760459) (xy 133.136796 -286.742412) (xy 133.18666 -286.732232)
			(xy 133.237512 -286.730183) (xy 133.288033 -286.736317) (xy 133.336917 -286.750477) (xy 133.382896 -286.772294)
			(xy 133.42478 -286.801204) (xy 133.461484 -286.836459) (xy 133.492057 -286.877145) (xy 133.515708 -286.922208)
			(xy 133.531824 -286.970482) (xy 133.539988 -287.020716) (xy 133.5405 -287.046162) (xy 133.540495 -287.046416)
			(xy 133.859028 -287.046416) (xy 133.862988 -286.997362) (xy 133.874765 -286.949578) (xy 133.894056 -286.904302)
			(xy 133.920359 -286.862706) (xy 133.952994 -286.825869) (xy 133.991115 -286.794744) (xy 134.033736 -286.770137)
			(xy 134.079752 -286.752685) (xy 134.127971 -286.742841) (xy 134.177146 -286.74086) (xy 134.226001 -286.746792)
			(xy 134.273272 -286.760484) (xy 134.317734 -286.781582) (xy 134.358237 -286.809538) (xy 134.39373 -286.84363)
			(xy 134.423295 -286.882974) (xy 134.446166 -286.926551) (xy 134.46175 -286.973232) (xy 134.469645 -287.021809)
			(xy 134.470135 -287.046162) (xy 134.798828 -287.046162) (xy 134.802788 -286.997108) (xy 134.814565 -286.949324)
			(xy 134.833856 -286.904048) (xy 134.860159 -286.862452) (xy 134.892794 -286.825615) (xy 134.930915 -286.79449)
			(xy 134.973536 -286.769883) (xy 135.019552 -286.752431) (xy 135.067771 -286.742587) (xy 135.116946 -286.740606)
			(xy 135.165801 -286.746538) (xy 135.213072 -286.76023) (xy 135.257534 -286.781328) (xy 135.298037 -286.809284)
			(xy 135.33353 -286.843376) (xy 135.363095 -286.88272) (xy 135.385966 -286.926297) (xy 135.40155 -286.972978)
			(xy 135.409445 -287.021555) (xy 135.40994 -287.046162) (xy 135.738882 -287.046162) (xy 135.742842 -286.997108)
			(xy 135.754619 -286.949324) (xy 135.77391 -286.904048) (xy 135.800213 -286.862452) (xy 135.832848 -286.825615)
			(xy 135.870969 -286.79449) (xy 135.91359 -286.769883) (xy 135.959606 -286.752431) (xy 136.007825 -286.742587)
			(xy 136.057 -286.740606) (xy 136.105855 -286.746538) (xy 136.153126 -286.76023) (xy 136.197588 -286.781328)
			(xy 136.238091 -286.809284) (xy 136.273584 -286.843376) (xy 136.303149 -286.88272) (xy 136.32602 -286.926297)
			(xy 136.341604 -286.972978) (xy 136.349499 -287.021555) (xy 136.349994 -287.046162) (xy 136.678936 -287.046162)
			(xy 136.682896 -286.997108) (xy 136.694673 -286.949324) (xy 136.713964 -286.904048) (xy 136.740267 -286.862452)
			(xy 136.772902 -286.825615) (xy 136.811023 -286.79449) (xy 136.853644 -286.769883) (xy 136.89966 -286.752431)
			(xy 136.947879 -286.742587) (xy 136.997054 -286.740606) (xy 137.045909 -286.746538) (xy 137.09318 -286.76023)
			(xy 137.137642 -286.781328) (xy 137.178145 -286.809284) (xy 137.213638 -286.843376) (xy 137.243203 -286.88272)
			(xy 137.266074 -286.926297) (xy 137.281658 -286.972978) (xy 137.289553 -287.021555) (xy 137.290048 -287.046162)
			(xy 137.61899 -287.046162) (xy 137.62295 -286.997108) (xy 137.634727 -286.949324) (xy 137.654018 -286.904048)
			(xy 137.680321 -286.862452) (xy 137.712956 -286.825615) (xy 137.751077 -286.79449) (xy 137.793698 -286.769883)
			(xy 137.839714 -286.752431) (xy 137.887933 -286.742587) (xy 137.937108 -286.740606) (xy 137.985963 -286.746538)
			(xy 138.033234 -286.76023) (xy 138.077696 -286.781328) (xy 138.118199 -286.809284) (xy 138.153692 -286.843376)
			(xy 138.183257 -286.88272) (xy 138.206128 -286.926297) (xy 138.221712 -286.972978) (xy 138.229607 -287.021555)
			(xy 138.230102 -287.046162) (xy 138.230097 -287.046416) (xy 138.559044 -287.046416) (xy 138.563004 -286.997362)
			(xy 138.574781 -286.949578) (xy 138.594072 -286.904302) (xy 138.620375 -286.862706) (xy 138.65301 -286.825869)
			(xy 138.691131 -286.794744) (xy 138.733752 -286.770137) (xy 138.779768 -286.752685) (xy 138.827987 -286.742841)
			(xy 138.877162 -286.74086) (xy 138.926017 -286.746792) (xy 138.973288 -286.760484) (xy 139.01775 -286.781582)
			(xy 139.058253 -286.809538) (xy 139.093746 -286.84363) (xy 139.123311 -286.882974) (xy 139.146182 -286.926551)
			(xy 139.161766 -286.973232) (xy 139.169661 -287.021809) (xy 139.170151 -287.046162) (xy 139.498844 -287.046162)
			(xy 139.502804 -286.997108) (xy 139.514581 -286.949324) (xy 139.533872 -286.904048) (xy 139.560175 -286.862452)
			(xy 139.59281 -286.825615) (xy 139.630931 -286.79449) (xy 139.673552 -286.769883) (xy 139.719568 -286.752431)
			(xy 139.767787 -286.742587) (xy 139.816962 -286.740606) (xy 139.865817 -286.746538) (xy 139.913088 -286.76023)
			(xy 139.95755 -286.781328) (xy 139.998053 -286.809284) (xy 140.033546 -286.843376) (xy 140.063111 -286.88272)
			(xy 140.085982 -286.926297) (xy 140.101566 -286.972978) (xy 140.109461 -287.021555) (xy 140.109956 -287.046162)
			(xy 140.109461 -287.070769) (xy 140.101566 -287.119346) (xy 140.085982 -287.166027) (xy 140.063111 -287.209604)
			(xy 140.033546 -287.248948) (xy 139.998053 -287.28304) (xy 139.95755 -287.310996) (xy 139.913088 -287.332094)
			(xy 139.865817 -287.345786) (xy 139.816962 -287.351718) (xy 139.767787 -287.349737) (xy 139.719568 -287.339893)
			(xy 139.673552 -287.322441) (xy 139.630931 -287.297834) (xy 139.59281 -287.266709) (xy 139.560175 -287.229872)
			(xy 139.533872 -287.188276) (xy 139.514581 -287.143) (xy 139.502804 -287.095216) (xy 139.498844 -287.046162)
			(xy 139.170151 -287.046162) (xy 139.170156 -287.046416) (xy 139.169661 -287.071023) (xy 139.161766 -287.1196)
			(xy 139.146182 -287.166281) (xy 139.123311 -287.209858) (xy 139.093746 -287.249202) (xy 139.058253 -287.283294)
			(xy 139.01775 -287.31125) (xy 138.973288 -287.332348) (xy 138.926017 -287.34604) (xy 138.877162 -287.351972)
			(xy 138.827987 -287.349991) (xy 138.779768 -287.340147) (xy 138.733752 -287.322695) (xy 138.691131 -287.298088)
			(xy 138.65301 -287.266963) (xy 138.620375 -287.230126) (xy 138.594072 -287.18853) (xy 138.574781 -287.143254)
			(xy 138.563004 -287.09547) (xy 138.559044 -287.046416) (xy 138.230097 -287.046416) (xy 138.229607 -287.070769)
			(xy 138.221712 -287.119346) (xy 138.206128 -287.166027) (xy 138.183257 -287.209604) (xy 138.153692 -287.248948)
			(xy 138.118199 -287.28304) (xy 138.077696 -287.310996) (xy 138.033234 -287.332094) (xy 137.985963 -287.345786)
			(xy 137.937108 -287.351718) (xy 137.887933 -287.349737) (xy 137.839714 -287.339893) (xy 137.793698 -287.322441)
			(xy 137.751077 -287.297834) (xy 137.712956 -287.266709) (xy 137.680321 -287.229872) (xy 137.654018 -287.188276)
			(xy 137.634727 -287.143) (xy 137.62295 -287.095216) (xy 137.61899 -287.046162) (xy 137.290048 -287.046162)
			(xy 137.289553 -287.070769) (xy 137.281658 -287.119346) (xy 137.266074 -287.166027) (xy 137.243203 -287.209604)
			(xy 137.213638 -287.248948) (xy 137.178145 -287.28304) (xy 137.137642 -287.310996) (xy 137.09318 -287.332094)
			(xy 137.045909 -287.345786) (xy 136.997054 -287.351718) (xy 136.947879 -287.349737) (xy 136.89966 -287.339893)
			(xy 136.853644 -287.322441) (xy 136.811023 -287.297834) (xy 136.772902 -287.266709) (xy 136.740267 -287.229872)
			(xy 136.713964 -287.188276) (xy 136.694673 -287.143) (xy 136.682896 -287.095216) (xy 136.678936 -287.046162)
			(xy 136.349994 -287.046162) (xy 136.349499 -287.070769) (xy 136.341604 -287.119346) (xy 136.32602 -287.166027)
			(xy 136.303149 -287.209604) (xy 136.273584 -287.248948) (xy 136.238091 -287.28304) (xy 136.197588 -287.310996)
			(xy 136.153126 -287.332094) (xy 136.105855 -287.345786) (xy 136.057 -287.351718) (xy 136.007825 -287.349737)
			(xy 135.959606 -287.339893) (xy 135.91359 -287.322441) (xy 135.870969 -287.297834) (xy 135.832848 -287.266709)
			(xy 135.800213 -287.229872) (xy 135.77391 -287.188276) (xy 135.754619 -287.143) (xy 135.742842 -287.095216)
			(xy 135.738882 -287.046162) (xy 135.40994 -287.046162) (xy 135.409445 -287.070769) (xy 135.40155 -287.119346)
			(xy 135.385966 -287.166027) (xy 135.363095 -287.209604) (xy 135.33353 -287.248948) (xy 135.298037 -287.28304)
			(xy 135.257534 -287.310996) (xy 135.213072 -287.332094) (xy 135.165801 -287.345786) (xy 135.116946 -287.351718)
			(xy 135.067771 -287.349737) (xy 135.019552 -287.339893) (xy 134.973536 -287.322441) (xy 134.930915 -287.297834)
			(xy 134.892794 -287.266709) (xy 134.860159 -287.229872) (xy 134.833856 -287.188276) (xy 134.814565 -287.143)
			(xy 134.802788 -287.095216) (xy 134.798828 -287.046162) (xy 134.470135 -287.046162) (xy 134.47014 -287.046416)
			(xy 134.469645 -287.071023) (xy 134.46175 -287.1196) (xy 134.446166 -287.166281) (xy 134.423295 -287.209858)
			(xy 134.39373 -287.249202) (xy 134.358237 -287.283294) (xy 134.317734 -287.31125) (xy 134.273272 -287.332348)
			(xy 134.226001 -287.34604) (xy 134.177146 -287.351972) (xy 134.127971 -287.349991) (xy 134.079752 -287.340147)
			(xy 134.033736 -287.322695) (xy 133.991115 -287.298088) (xy 133.952994 -287.266963) (xy 133.920359 -287.230126)
			(xy 133.894056 -287.18853) (xy 133.874765 -287.143254) (xy 133.862988 -287.09547) (xy 133.859028 -287.046416)
			(xy 133.540495 -287.046416) (xy 133.539988 -287.071608) (xy 133.531824 -287.121842) (xy 133.515708 -287.170116)
			(xy 133.492057 -287.215179) (xy 133.461484 -287.255865) (xy 133.42478 -287.29112) (xy 133.382896 -287.32003)
			(xy 133.336917 -287.341847) (xy 133.288033 -287.356007) (xy 133.237512 -287.362141) (xy 133.18666 -287.360092)
			(xy 133.136796 -287.349912) (xy 133.08921 -287.331865) (xy 133.045136 -287.306419) (xy 133.005714 -287.274232)
			(xy 132.971966 -287.236138) (xy 132.944765 -287.193124) (xy 132.924817 -287.146304) (xy 132.912638 -287.09689)
			(xy 132.908543 -287.046162) (xy 132.590032 -287.046162) (xy 132.589537 -287.070769) (xy 132.581642 -287.119346)
			(xy 132.566058 -287.166027) (xy 132.543187 -287.209604) (xy 132.513622 -287.248948) (xy 132.478129 -287.28304)
			(xy 132.437626 -287.310996) (xy 132.393164 -287.332094) (xy 132.345893 -287.345786) (xy 132.297038 -287.351718)
			(xy 132.247863 -287.349737) (xy 132.199644 -287.339893) (xy 132.153628 -287.322441) (xy 132.111007 -287.297834)
			(xy 132.072886 -287.266709) (xy 132.040251 -287.229872) (xy 132.013948 -287.188276) (xy 131.994657 -287.143)
			(xy 131.98288 -287.095216) (xy 131.97892 -287.046162) (xy 131.660392 -287.046162) (xy 131.65988 -287.071608)
			(xy 131.651716 -287.121842) (xy 131.6356 -287.170116) (xy 131.611949 -287.215179) (xy 131.581376 -287.255865)
			(xy 131.544672 -287.29112) (xy 131.502788 -287.32003) (xy 131.456809 -287.341847) (xy 131.407925 -287.356007)
			(xy 131.357404 -287.362141) (xy 131.306552 -287.360092) (xy 131.256688 -287.349912) (xy 131.209102 -287.331865)
			(xy 131.165028 -287.306419) (xy 131.125606 -287.274232) (xy 131.091858 -287.236138) (xy 131.064657 -287.193124)
			(xy 131.044709 -287.146304) (xy 131.03253 -287.09689) (xy 131.028435 -287.046162) (xy 130.710173 -287.046162)
			(xy 130.710178 -287.046416) (xy 130.709683 -287.071023) (xy 130.701788 -287.1196) (xy 130.686204 -287.166281)
			(xy 130.663333 -287.209858) (xy 130.633768 -287.249202) (xy 130.598275 -287.283294) (xy 130.557772 -287.31125)
			(xy 130.51331 -287.332348) (xy 130.466039 -287.34604) (xy 130.417184 -287.351972) (xy 130.368009 -287.349991)
			(xy 130.31979 -287.340147) (xy 130.273774 -287.322695) (xy 130.231153 -287.298088) (xy 130.193032 -287.266963)
			(xy 130.160397 -287.230126) (xy 130.134094 -287.18853) (xy 130.114803 -287.143254) (xy 130.103026 -287.09547)
			(xy 130.099066 -287.046416) (xy 129.780533 -287.046416) (xy 129.780026 -287.071608) (xy 129.771862 -287.121842)
			(xy 129.755746 -287.170116) (xy 129.732095 -287.215179) (xy 129.701522 -287.255865) (xy 129.664818 -287.29112)
			(xy 129.622934 -287.32003) (xy 129.576955 -287.341847) (xy 129.528071 -287.356007) (xy 129.47755 -287.362141)
			(xy 129.426698 -287.360092) (xy 129.376834 -287.349912) (xy 129.329248 -287.331865) (xy 129.285174 -287.306419)
			(xy 129.245752 -287.274232) (xy 129.212004 -287.236138) (xy 129.184803 -287.193124) (xy 129.164855 -287.146304)
			(xy 129.152676 -287.09689) (xy 129.148581 -287.046162) (xy 128.840484 -287.046162) (xy 128.839972 -287.071608)
			(xy 128.831808 -287.121842) (xy 128.815692 -287.170116) (xy 128.792041 -287.215179) (xy 128.761468 -287.255865)
			(xy 128.724764 -287.29112) (xy 128.68288 -287.32003) (xy 128.636901 -287.341847) (xy 128.588017 -287.356007)
			(xy 128.537496 -287.362141) (xy 128.486644 -287.360092) (xy 128.43678 -287.349912) (xy 128.389194 -287.331865)
			(xy 128.34512 -287.306419) (xy 128.305698 -287.274232) (xy 128.27195 -287.236138) (xy 128.244749 -287.193124)
			(xy 128.224801 -287.146304) (xy 128.212622 -287.09689) (xy 128.208527 -287.046162) (xy 127.904244 -287.046162)
			(xy 127.903478 -287.046924) (xy 127.897872 -287.052718) (xy 127.890342 -287.066963) (xy 127.888746 -287.074864)
			(xy 127.885693 -287.101203) (xy 127.87168 -287.152337) (xy 127.849049 -287.200284) (xy 127.818481 -287.243605)
			(xy 127.780894 -287.280998) (xy 127.75946 -287.296606) (xy 127.753398 -287.301502) (xy 127.744346 -287.314176)
			(xy 127.74168 -287.321498) (xy 127.730471 -287.364291) (xy 127.702251 -287.44814) (xy 127.667571 -287.529529)
			(xy 127.626642 -287.607962) (xy 127.579715 -287.682961) (xy 127.55372 -287.718754) (xy 127.548894 -287.725612)
			(xy 127.543814 -287.740598) (xy 127.543814 -287.856422) (xy 127.738627 -287.856422) (xy 127.742722 -287.805694)
			(xy 127.754901 -287.75628) (xy 127.774849 -287.70946) (xy 127.80205 -287.666446) (xy 127.835798 -287.628352)
			(xy 127.87522 -287.596165) (xy 127.919294 -287.570719) (xy 127.96688 -287.552672) (xy 128.016744 -287.542492)
			(xy 128.067596 -287.540443) (xy 128.118117 -287.546577) (xy 128.167001 -287.560737) (xy 128.21298 -287.582554)
			(xy 128.254864 -287.611464) (xy 128.291568 -287.646719) (xy 128.322141 -287.687405) (xy 128.345792 -287.732468)
			(xy 128.361908 -287.780742) (xy 128.370072 -287.830976) (xy 128.370584 -287.856422) (xy 128.688858 -287.856422)
			(xy 128.692818 -287.807368) (xy 128.704595 -287.759584) (xy 128.723886 -287.714308) (xy 128.750189 -287.672712)
			(xy 128.782824 -287.635875) (xy 128.820945 -287.60475) (xy 128.863566 -287.580143) (xy 128.909582 -287.562691)
			(xy 128.957801 -287.552847) (xy 129.006976 -287.550866) (xy 129.055831 -287.556798) (xy 129.103102 -287.57049)
			(xy 129.147564 -287.591588) (xy 129.188067 -287.619544) (xy 129.22356 -287.653636) (xy 129.253125 -287.69298)
			(xy 129.275996 -287.736557) (xy 129.29158 -287.783238) (xy 129.299475 -287.831815) (xy 129.29997 -287.856422)
			(xy 129.618481 -287.856422) (xy 129.622576 -287.805694) (xy 129.634755 -287.75628) (xy 129.654703 -287.70946)
			(xy 129.681904 -287.666446) (xy 129.715652 -287.628352) (xy 129.755074 -287.596165) (xy 129.799148 -287.570719)
			(xy 129.846734 -287.552672) (xy 129.896598 -287.542492) (xy 129.94745 -287.540443) (xy 129.997971 -287.546577)
			(xy 130.046855 -287.560737) (xy 130.092834 -287.582554) (xy 130.134718 -287.611464) (xy 130.171422 -287.646719)
			(xy 130.201995 -287.687405) (xy 130.225646 -287.732468) (xy 130.241762 -287.780742) (xy 130.249926 -287.830976)
			(xy 130.250438 -287.856422) (xy 130.568966 -287.856422) (xy 130.572926 -287.807368) (xy 130.584703 -287.759584)
			(xy 130.603994 -287.714308) (xy 130.630297 -287.672712) (xy 130.662932 -287.635875) (xy 130.701053 -287.60475)
			(xy 130.743674 -287.580143) (xy 130.78969 -287.562691) (xy 130.837909 -287.552847) (xy 130.887084 -287.550866)
			(xy 130.935939 -287.556798) (xy 130.98321 -287.57049) (xy 131.027672 -287.591588) (xy 131.068175 -287.619544)
			(xy 131.103668 -287.653636) (xy 131.133233 -287.69298) (xy 131.156104 -287.736557) (xy 131.171688 -287.783238)
			(xy 131.179583 -287.831815) (xy 131.180078 -287.856422) (xy 131.498589 -287.856422) (xy 131.502684 -287.805694)
			(xy 131.514863 -287.75628) (xy 131.534811 -287.70946) (xy 131.562012 -287.666446) (xy 131.59576 -287.628352)
			(xy 131.635182 -287.596165) (xy 131.679256 -287.570719) (xy 131.726842 -287.552672) (xy 131.776706 -287.542492)
			(xy 131.827558 -287.540443) (xy 131.878079 -287.546577) (xy 131.926963 -287.560737) (xy 131.972942 -287.582554)
			(xy 132.014826 -287.611464) (xy 132.05153 -287.646719) (xy 132.082103 -287.687405) (xy 132.105754 -287.732468)
			(xy 132.12187 -287.780742) (xy 132.130034 -287.830976) (xy 132.130546 -287.856422) (xy 132.438643 -287.856422)
			(xy 132.442738 -287.805694) (xy 132.454917 -287.75628) (xy 132.474865 -287.70946) (xy 132.502066 -287.666446)
			(xy 132.535814 -287.628352) (xy 132.575236 -287.596165) (xy 132.61931 -287.570719) (xy 132.666896 -287.552672)
			(xy 132.71676 -287.542492) (xy 132.767612 -287.540443) (xy 132.818133 -287.546577) (xy 132.867017 -287.560737)
			(xy 132.912996 -287.582554) (xy 132.95488 -287.611464) (xy 132.991584 -287.646719) (xy 133.022157 -287.687405)
			(xy 133.045808 -287.732468) (xy 133.061924 -287.780742) (xy 133.070088 -287.830976) (xy 133.0706 -287.856422)
			(xy 133.388874 -287.856422) (xy 133.392834 -287.807368) (xy 133.404611 -287.759584) (xy 133.423902 -287.714308)
			(xy 133.450205 -287.672712) (xy 133.48284 -287.635875) (xy 133.520961 -287.60475) (xy 133.563582 -287.580143)
			(xy 133.609598 -287.562691) (xy 133.657817 -287.552847) (xy 133.706992 -287.550866) (xy 133.755847 -287.556798)
			(xy 133.803118 -287.57049) (xy 133.84758 -287.591588) (xy 133.888083 -287.619544) (xy 133.923576 -287.653636)
			(xy 133.953141 -287.69298) (xy 133.976012 -287.736557) (xy 133.991596 -287.783238) (xy 133.999491 -287.831815)
			(xy 133.999986 -287.856422) (xy 134.328928 -287.856422) (xy 134.332888 -287.807368) (xy 134.344665 -287.759584)
			(xy 134.363956 -287.714308) (xy 134.390259 -287.672712) (xy 134.422894 -287.635875) (xy 134.461015 -287.60475)
			(xy 134.503636 -287.580143) (xy 134.549652 -287.562691) (xy 134.597871 -287.552847) (xy 134.647046 -287.550866)
			(xy 134.695901 -287.556798) (xy 134.743172 -287.57049) (xy 134.787634 -287.591588) (xy 134.828137 -287.619544)
			(xy 134.86363 -287.653636) (xy 134.893195 -287.69298) (xy 134.916066 -287.736557) (xy 134.93165 -287.783238)
			(xy 134.939545 -287.831815) (xy 134.94004 -287.856422) (xy 135.268982 -287.856422) (xy 135.272942 -287.807368)
			(xy 135.284719 -287.759584) (xy 135.30401 -287.714308) (xy 135.330313 -287.672712) (xy 135.362948 -287.635875)
			(xy 135.401069 -287.60475) (xy 135.44369 -287.580143) (xy 135.489706 -287.562691) (xy 135.537925 -287.552847)
			(xy 135.5871 -287.550866) (xy 135.635955 -287.556798) (xy 135.683226 -287.57049) (xy 135.727688 -287.591588)
			(xy 135.768191 -287.619544) (xy 135.803684 -287.653636) (xy 135.833249 -287.69298) (xy 135.85612 -287.736557)
			(xy 135.871704 -287.783238) (xy 135.879599 -287.831815) (xy 135.880094 -287.856422) (xy 136.209036 -287.856422)
			(xy 136.212996 -287.807368) (xy 136.224773 -287.759584) (xy 136.244064 -287.714308) (xy 136.270367 -287.672712)
			(xy 136.303002 -287.635875) (xy 136.341123 -287.60475) (xy 136.383744 -287.580143) (xy 136.42976 -287.562691)
			(xy 136.477979 -287.552847) (xy 136.527154 -287.550866) (xy 136.576009 -287.556798) (xy 136.62328 -287.57049)
			(xy 136.667742 -287.591588) (xy 136.708245 -287.619544) (xy 136.743738 -287.653636) (xy 136.773303 -287.69298)
			(xy 136.796174 -287.736557) (xy 136.811758 -287.783238) (xy 136.819653 -287.831815) (xy 136.820148 -287.856422)
			(xy 137.148836 -287.856422) (xy 137.152796 -287.807368) (xy 137.164573 -287.759584) (xy 137.183864 -287.714308)
			(xy 137.210167 -287.672712) (xy 137.242802 -287.635875) (xy 137.280923 -287.60475) (xy 137.323544 -287.580143)
			(xy 137.36956 -287.562691) (xy 137.417779 -287.552847) (xy 137.466954 -287.550866) (xy 137.515809 -287.556798)
			(xy 137.56308 -287.57049) (xy 137.607542 -287.591588) (xy 137.648045 -287.619544) (xy 137.683538 -287.653636)
			(xy 137.713103 -287.69298) (xy 137.735974 -287.736557) (xy 137.751558 -287.783238) (xy 137.759453 -287.831815)
			(xy 137.759948 -287.856422) (xy 138.08889 -287.856422) (xy 138.09285 -287.807368) (xy 138.104627 -287.759584)
			(xy 138.123918 -287.714308) (xy 138.150221 -287.672712) (xy 138.182856 -287.635875) (xy 138.220977 -287.60475)
			(xy 138.263598 -287.580143) (xy 138.309614 -287.562691) (xy 138.357833 -287.552847) (xy 138.407008 -287.550866)
			(xy 138.455863 -287.556798) (xy 138.503134 -287.57049) (xy 138.547596 -287.591588) (xy 138.588099 -287.619544)
			(xy 138.623592 -287.653636) (xy 138.653157 -287.69298) (xy 138.676028 -287.736557) (xy 138.691612 -287.783238)
			(xy 138.699507 -287.831815) (xy 138.700002 -287.856422) (xy 139.028944 -287.856422) (xy 139.032904 -287.807368)
			(xy 139.044681 -287.759584) (xy 139.063972 -287.714308) (xy 139.090275 -287.672712) (xy 139.12291 -287.635875)
			(xy 139.161031 -287.60475) (xy 139.203652 -287.580143) (xy 139.249668 -287.562691) (xy 139.297887 -287.552847)
			(xy 139.347062 -287.550866) (xy 139.395917 -287.556798) (xy 139.443188 -287.57049) (xy 139.48765 -287.591588)
			(xy 139.528153 -287.619544) (xy 139.563646 -287.653636) (xy 139.593211 -287.69298) (xy 139.616082 -287.736557)
			(xy 139.631666 -287.783238) (xy 139.639561 -287.831815) (xy 139.640056 -287.856422) (xy 139.639561 -287.881029)
			(xy 139.631666 -287.929606) (xy 139.616082 -287.976287) (xy 139.593211 -288.019864) (xy 139.563646 -288.059208)
			(xy 139.528153 -288.0933) (xy 139.48765 -288.121256) (xy 139.443188 -288.142354) (xy 139.395917 -288.156046)
			(xy 139.347062 -288.161978) (xy 139.297887 -288.159997) (xy 139.249668 -288.150153) (xy 139.203652 -288.132701)
			(xy 139.161031 -288.108094) (xy 139.12291 -288.076969) (xy 139.090275 -288.040132) (xy 139.063972 -287.998536)
			(xy 139.044681 -287.95326) (xy 139.032904 -287.905476) (xy 139.028944 -287.856422) (xy 138.700002 -287.856422)
			(xy 138.699507 -287.881029) (xy 138.691612 -287.929606) (xy 138.676028 -287.976287) (xy 138.653157 -288.019864)
			(xy 138.623592 -288.059208) (xy 138.588099 -288.0933) (xy 138.547596 -288.121256) (xy 138.503134 -288.142354)
			(xy 138.455863 -288.156046) (xy 138.407008 -288.161978) (xy 138.357833 -288.159997) (xy 138.309614 -288.150153)
			(xy 138.263598 -288.132701) (xy 138.220977 -288.108094) (xy 138.182856 -288.076969) (xy 138.150221 -288.040132)
			(xy 138.123918 -287.998536) (xy 138.104627 -287.95326) (xy 138.09285 -287.905476) (xy 138.08889 -287.856422)
			(xy 137.759948 -287.856422) (xy 137.759453 -287.881029) (xy 137.751558 -287.929606) (xy 137.735974 -287.976287)
			(xy 137.713103 -288.019864) (xy 137.683538 -288.059208) (xy 137.648045 -288.0933) (xy 137.607542 -288.121256)
			(xy 137.56308 -288.142354) (xy 137.515809 -288.156046) (xy 137.466954 -288.161978) (xy 137.417779 -288.159997)
			(xy 137.36956 -288.150153) (xy 137.323544 -288.132701) (xy 137.280923 -288.108094) (xy 137.242802 -288.076969)
			(xy 137.210167 -288.040132) (xy 137.183864 -287.998536) (xy 137.164573 -287.95326) (xy 137.152796 -287.905476)
			(xy 137.148836 -287.856422) (xy 136.820148 -287.856422) (xy 136.819653 -287.881029) (xy 136.811758 -287.929606)
			(xy 136.796174 -287.976287) (xy 136.773303 -288.019864) (xy 136.743738 -288.059208) (xy 136.708245 -288.0933)
			(xy 136.667742 -288.121256) (xy 136.62328 -288.142354) (xy 136.576009 -288.156046) (xy 136.527154 -288.161978)
			(xy 136.477979 -288.159997) (xy 136.42976 -288.150153) (xy 136.383744 -288.132701) (xy 136.341123 -288.108094)
			(xy 136.303002 -288.076969) (xy 136.270367 -288.040132) (xy 136.244064 -287.998536) (xy 136.224773 -287.95326)
			(xy 136.212996 -287.905476) (xy 136.209036 -287.856422) (xy 135.880094 -287.856422) (xy 135.879599 -287.881029)
			(xy 135.871704 -287.929606) (xy 135.85612 -287.976287) (xy 135.833249 -288.019864) (xy 135.803684 -288.059208)
			(xy 135.768191 -288.0933) (xy 135.727688 -288.121256) (xy 135.683226 -288.142354) (xy 135.635955 -288.156046)
			(xy 135.5871 -288.161978) (xy 135.537925 -288.159997) (xy 135.489706 -288.150153) (xy 135.44369 -288.132701)
			(xy 135.401069 -288.108094) (xy 135.362948 -288.076969) (xy 135.330313 -288.040132) (xy 135.30401 -287.998536)
			(xy 135.284719 -287.95326) (xy 135.272942 -287.905476) (xy 135.268982 -287.856422) (xy 134.94004 -287.856422)
			(xy 134.939545 -287.881029) (xy 134.93165 -287.929606) (xy 134.916066 -287.976287) (xy 134.893195 -288.019864)
			(xy 134.86363 -288.059208) (xy 134.828137 -288.0933) (xy 134.787634 -288.121256) (xy 134.743172 -288.142354)
			(xy 134.695901 -288.156046) (xy 134.647046 -288.161978) (xy 134.597871 -288.159997) (xy 134.549652 -288.150153)
			(xy 134.503636 -288.132701) (xy 134.461015 -288.108094) (xy 134.422894 -288.076969) (xy 134.390259 -288.040132)
			(xy 134.363956 -287.998536) (xy 134.344665 -287.95326) (xy 134.332888 -287.905476) (xy 134.328928 -287.856422)
			(xy 133.999986 -287.856422) (xy 133.999491 -287.881029) (xy 133.991596 -287.929606) (xy 133.976012 -287.976287)
			(xy 133.953141 -288.019864) (xy 133.923576 -288.059208) (xy 133.888083 -288.0933) (xy 133.84758 -288.121256)
			(xy 133.803118 -288.142354) (xy 133.755847 -288.156046) (xy 133.706992 -288.161978) (xy 133.657817 -288.159997)
			(xy 133.609598 -288.150153) (xy 133.563582 -288.132701) (xy 133.520961 -288.108094) (xy 133.48284 -288.076969)
			(xy 133.450205 -288.040132) (xy 133.423902 -287.998536) (xy 133.404611 -287.95326) (xy 133.392834 -287.905476)
			(xy 133.388874 -287.856422) (xy 133.0706 -287.856422) (xy 133.070088 -287.881868) (xy 133.061924 -287.932102)
			(xy 133.045808 -287.980376) (xy 133.022157 -288.025439) (xy 132.991584 -288.066125) (xy 132.95488 -288.10138)
			(xy 132.912996 -288.13029) (xy 132.867017 -288.152107) (xy 132.818133 -288.166267) (xy 132.767612 -288.172401)
			(xy 132.71676 -288.170352) (xy 132.666896 -288.160172) (xy 132.61931 -288.142125) (xy 132.575236 -288.116679)
			(xy 132.535814 -288.084492) (xy 132.502066 -288.046398) (xy 132.474865 -288.003384) (xy 132.454917 -287.956564)
			(xy 132.442738 -287.90715) (xy 132.438643 -287.856422) (xy 132.130546 -287.856422) (xy 132.130034 -287.881868)
			(xy 132.12187 -287.932102) (xy 132.105754 -287.980376) (xy 132.082103 -288.025439) (xy 132.05153 -288.066125)
			(xy 132.014826 -288.10138) (xy 131.972942 -288.13029) (xy 131.926963 -288.152107) (xy 131.878079 -288.166267)
			(xy 131.827558 -288.172401) (xy 131.776706 -288.170352) (xy 131.726842 -288.160172) (xy 131.679256 -288.142125)
			(xy 131.635182 -288.116679) (xy 131.59576 -288.084492) (xy 131.562012 -288.046398) (xy 131.534811 -288.003384)
			(xy 131.514863 -287.956564) (xy 131.502684 -287.90715) (xy 131.498589 -287.856422) (xy 131.180078 -287.856422)
			(xy 131.179583 -287.881029) (xy 131.171688 -287.929606) (xy 131.156104 -287.976287) (xy 131.133233 -288.019864)
			(xy 131.103668 -288.059208) (xy 131.068175 -288.0933) (xy 131.027672 -288.121256) (xy 130.98321 -288.142354)
			(xy 130.935939 -288.156046) (xy 130.887084 -288.161978) (xy 130.837909 -288.159997) (xy 130.78969 -288.150153)
			(xy 130.743674 -288.132701) (xy 130.701053 -288.108094) (xy 130.662932 -288.076969) (xy 130.630297 -288.040132)
			(xy 130.603994 -287.998536) (xy 130.584703 -287.95326) (xy 130.572926 -287.905476) (xy 130.568966 -287.856422)
			(xy 130.250438 -287.856422) (xy 130.249926 -287.881868) (xy 130.241762 -287.932102) (xy 130.225646 -287.980376)
			(xy 130.201995 -288.025439) (xy 130.171422 -288.066125) (xy 130.134718 -288.10138) (xy 130.092834 -288.13029)
			(xy 130.046855 -288.152107) (xy 129.997971 -288.166267) (xy 129.94745 -288.172401) (xy 129.896598 -288.170352)
			(xy 129.846734 -288.160172) (xy 129.799148 -288.142125) (xy 129.755074 -288.116679) (xy 129.715652 -288.084492)
			(xy 129.681904 -288.046398) (xy 129.654703 -288.003384) (xy 129.634755 -287.956564) (xy 129.622576 -287.90715)
			(xy 129.618481 -287.856422) (xy 129.29997 -287.856422) (xy 129.299475 -287.881029) (xy 129.29158 -287.929606)
			(xy 129.275996 -287.976287) (xy 129.253125 -288.019864) (xy 129.22356 -288.059208) (xy 129.188067 -288.0933)
			(xy 129.147564 -288.121256) (xy 129.103102 -288.142354) (xy 129.055831 -288.156046) (xy 129.006976 -288.161978)
			(xy 128.957801 -288.159997) (xy 128.909582 -288.150153) (xy 128.863566 -288.132701) (xy 128.820945 -288.108094)
			(xy 128.782824 -288.076969) (xy 128.750189 -288.040132) (xy 128.723886 -287.998536) (xy 128.704595 -287.95326)
			(xy 128.692818 -287.905476) (xy 128.688858 -287.856422) (xy 128.370584 -287.856422) (xy 128.370072 -287.881868)
			(xy 128.361908 -287.932102) (xy 128.345792 -287.980376) (xy 128.322141 -288.025439) (xy 128.291568 -288.066125)
			(xy 128.254864 -288.10138) (xy 128.21298 -288.13029) (xy 128.167001 -288.152107) (xy 128.118117 -288.166267)
			(xy 128.067596 -288.172401) (xy 128.016744 -288.170352) (xy 127.96688 -288.160172) (xy 127.919294 -288.142125)
			(xy 127.87522 -288.116679) (xy 127.835798 -288.084492) (xy 127.80205 -288.046398) (xy 127.774849 -288.003384)
			(xy 127.754901 -287.956564) (xy 127.742722 -287.90715) (xy 127.738627 -287.856422) (xy 127.543814 -287.856422)
			(xy 127.543814 -287.971738) (xy 127.548894 -287.986724) (xy 127.55372 -287.993582) (xy 127.57971 -288.02938)
			(xy 127.626658 -288.104366) (xy 127.667597 -288.182795) (xy 127.702275 -288.264187) (xy 127.730479 -288.348042)
			(xy 127.74168 -288.390838) (xy 127.744364 -288.39815) (xy 127.753414 -288.410818) (xy 127.75946 -288.41573)
			(xy 127.779253 -288.430146) (xy 127.814407 -288.464227) (xy 127.843676 -288.503479) (xy 127.86631 -288.546897)
			(xy 127.88173 -288.593368) (xy 127.889541 -288.641704) (xy 127.889542 -288.666174) (xy 128.208527 -288.666174)
			(xy 128.212622 -288.615446) (xy 128.224801 -288.566032) (xy 128.244749 -288.519212) (xy 128.27195 -288.476198)
			(xy 128.305698 -288.438104) (xy 128.34512 -288.405917) (xy 128.389194 -288.380471) (xy 128.43678 -288.362424)
			(xy 128.486644 -288.352244) (xy 128.537496 -288.350195) (xy 128.588017 -288.356329) (xy 128.636901 -288.370489)
			(xy 128.68288 -288.392306) (xy 128.724764 -288.421216) (xy 128.761468 -288.456471) (xy 128.792041 -288.497157)
			(xy 128.815692 -288.54222) (xy 128.831808 -288.590494) (xy 128.839972 -288.640728) (xy 128.840484 -288.666174)
			(xy 129.148581 -288.666174) (xy 129.152676 -288.615446) (xy 129.164855 -288.566032) (xy 129.184803 -288.519212)
			(xy 129.212004 -288.476198) (xy 129.245752 -288.438104) (xy 129.285174 -288.405917) (xy 129.329248 -288.380471)
			(xy 129.376834 -288.362424) (xy 129.426698 -288.352244) (xy 129.47755 -288.350195) (xy 129.528071 -288.356329)
			(xy 129.576955 -288.370489) (xy 129.622934 -288.392306) (xy 129.664818 -288.421216) (xy 129.701522 -288.456471)
			(xy 129.732095 -288.497157) (xy 129.755746 -288.54222) (xy 129.771862 -288.590494) (xy 129.780026 -288.640728)
			(xy 129.780538 -288.666174) (xy 130.099066 -288.666174) (xy 130.103026 -288.61712) (xy 130.114803 -288.569336)
			(xy 130.134094 -288.52406) (xy 130.160397 -288.482464) (xy 130.193032 -288.445627) (xy 130.231153 -288.414502)
			(xy 130.273774 -288.389895) (xy 130.31979 -288.372443) (xy 130.368009 -288.362599) (xy 130.417184 -288.360618)
			(xy 130.466039 -288.36655) (xy 130.51331 -288.380242) (xy 130.557772 -288.40134) (xy 130.598275 -288.429296)
			(xy 130.633768 -288.463388) (xy 130.663333 -288.502732) (xy 130.686204 -288.546309) (xy 130.701788 -288.59299)
			(xy 130.709683 -288.641567) (xy 130.710178 -288.666174) (xy 131.028435 -288.666174) (xy 131.03253 -288.615446)
			(xy 131.044709 -288.566032) (xy 131.064657 -288.519212) (xy 131.091858 -288.476198) (xy 131.125606 -288.438104)
			(xy 131.165028 -288.405917) (xy 131.209102 -288.380471) (xy 131.256688 -288.362424) (xy 131.306552 -288.352244)
			(xy 131.357404 -288.350195) (xy 131.407925 -288.356329) (xy 131.456809 -288.370489) (xy 131.502788 -288.392306)
			(xy 131.544672 -288.421216) (xy 131.581376 -288.456471) (xy 131.611949 -288.497157) (xy 131.6356 -288.54222)
			(xy 131.651716 -288.590494) (xy 131.65988 -288.640728) (xy 131.660392 -288.666174) (xy 131.97892 -288.666174)
			(xy 131.98288 -288.61712) (xy 131.994657 -288.569336) (xy 132.013948 -288.52406) (xy 132.040251 -288.482464)
			(xy 132.072886 -288.445627) (xy 132.111007 -288.414502) (xy 132.153628 -288.389895) (xy 132.199644 -288.372443)
			(xy 132.247863 -288.362599) (xy 132.297038 -288.360618) (xy 132.345893 -288.36655) (xy 132.393164 -288.380242)
			(xy 132.437626 -288.40134) (xy 132.478129 -288.429296) (xy 132.513622 -288.463388) (xy 132.543187 -288.502732)
			(xy 132.566058 -288.546309) (xy 132.581642 -288.59299) (xy 132.589537 -288.641567) (xy 132.590032 -288.666174)
			(xy 132.908543 -288.666174) (xy 132.912638 -288.615446) (xy 132.924817 -288.566032) (xy 132.944765 -288.519212)
			(xy 132.971966 -288.476198) (xy 133.005714 -288.438104) (xy 133.045136 -288.405917) (xy 133.08921 -288.380471)
			(xy 133.136796 -288.362424) (xy 133.18666 -288.352244) (xy 133.237512 -288.350195) (xy 133.288033 -288.356329)
			(xy 133.336917 -288.370489) (xy 133.382896 -288.392306) (xy 133.42478 -288.421216) (xy 133.461484 -288.456471)
			(xy 133.492057 -288.497157) (xy 133.515708 -288.54222) (xy 133.531824 -288.590494) (xy 133.539988 -288.640728)
			(xy 133.5405 -288.666174) (xy 133.859028 -288.666174) (xy 133.862988 -288.61712) (xy 133.874765 -288.569336)
			(xy 133.894056 -288.52406) (xy 133.920359 -288.482464) (xy 133.952994 -288.445627) (xy 133.991115 -288.414502)
			(xy 134.033736 -288.389895) (xy 134.079752 -288.372443) (xy 134.127971 -288.362599) (xy 134.177146 -288.360618)
			(xy 134.226001 -288.36655) (xy 134.273272 -288.380242) (xy 134.317734 -288.40134) (xy 134.358237 -288.429296)
			(xy 134.39373 -288.463388) (xy 134.423295 -288.502732) (xy 134.446166 -288.546309) (xy 134.46175 -288.59299)
			(xy 134.469645 -288.641567) (xy 134.47014 -288.666174) (xy 134.798828 -288.666174) (xy 134.802788 -288.61712)
			(xy 134.814565 -288.569336) (xy 134.833856 -288.52406) (xy 134.860159 -288.482464) (xy 134.892794 -288.445627)
			(xy 134.930915 -288.414502) (xy 134.973536 -288.389895) (xy 135.019552 -288.372443) (xy 135.067771 -288.362599)
			(xy 135.116946 -288.360618) (xy 135.165801 -288.36655) (xy 135.213072 -288.380242) (xy 135.257534 -288.40134)
			(xy 135.298037 -288.429296) (xy 135.33353 -288.463388) (xy 135.363095 -288.502732) (xy 135.385966 -288.546309)
			(xy 135.40155 -288.59299) (xy 135.409445 -288.641567) (xy 135.40994 -288.666174) (xy 135.738882 -288.666174)
			(xy 135.742842 -288.61712) (xy 135.754619 -288.569336) (xy 135.77391 -288.52406) (xy 135.800213 -288.482464)
			(xy 135.832848 -288.445627) (xy 135.870969 -288.414502) (xy 135.91359 -288.389895) (xy 135.959606 -288.372443)
			(xy 136.007825 -288.362599) (xy 136.057 -288.360618) (xy 136.105855 -288.36655) (xy 136.153126 -288.380242)
			(xy 136.197588 -288.40134) (xy 136.238091 -288.429296) (xy 136.273584 -288.463388) (xy 136.303149 -288.502732)
			(xy 136.32602 -288.546309) (xy 136.341604 -288.59299) (xy 136.349499 -288.641567) (xy 136.349994 -288.666174)
			(xy 136.678936 -288.666174) (xy 136.682896 -288.61712) (xy 136.694673 -288.569336) (xy 136.713964 -288.52406)
			(xy 136.740267 -288.482464) (xy 136.772902 -288.445627) (xy 136.811023 -288.414502) (xy 136.853644 -288.389895)
			(xy 136.89966 -288.372443) (xy 136.947879 -288.362599) (xy 136.997054 -288.360618) (xy 137.045909 -288.36655)
			(xy 137.09318 -288.380242) (xy 137.137642 -288.40134) (xy 137.178145 -288.429296) (xy 137.213638 -288.463388)
			(xy 137.243203 -288.502732) (xy 137.266074 -288.546309) (xy 137.281658 -288.59299) (xy 137.289553 -288.641567)
			(xy 137.290048 -288.666174) (xy 137.61899 -288.666174) (xy 137.62295 -288.61712) (xy 137.634727 -288.569336)
			(xy 137.654018 -288.52406) (xy 137.680321 -288.482464) (xy 137.712956 -288.445627) (xy 137.751077 -288.414502)
			(xy 137.793698 -288.389895) (xy 137.839714 -288.372443) (xy 137.887933 -288.362599) (xy 137.937108 -288.360618)
			(xy 137.985963 -288.36655) (xy 138.033234 -288.380242) (xy 138.077696 -288.40134) (xy 138.118199 -288.429296)
			(xy 138.153692 -288.463388) (xy 138.183257 -288.502732) (xy 138.206128 -288.546309) (xy 138.221712 -288.59299)
			(xy 138.229607 -288.641567) (xy 138.230102 -288.666174) (xy 138.559044 -288.666174) (xy 138.563004 -288.61712)
			(xy 138.574781 -288.569336) (xy 138.594072 -288.52406) (xy 138.620375 -288.482464) (xy 138.65301 -288.445627)
			(xy 138.691131 -288.414502) (xy 138.733752 -288.389895) (xy 138.779768 -288.372443) (xy 138.827987 -288.362599)
			(xy 138.877162 -288.360618) (xy 138.926017 -288.36655) (xy 138.973288 -288.380242) (xy 139.01775 -288.40134)
			(xy 139.058253 -288.429296) (xy 139.093746 -288.463388) (xy 139.123311 -288.502732) (xy 139.146182 -288.546309)
			(xy 139.161766 -288.59299) (xy 139.169661 -288.641567) (xy 139.170156 -288.666174) (xy 139.498844 -288.666174)
			(xy 139.502804 -288.61712) (xy 139.514581 -288.569336) (xy 139.533872 -288.52406) (xy 139.560175 -288.482464)
			(xy 139.59281 -288.445627) (xy 139.630931 -288.414502) (xy 139.673552 -288.389895) (xy 139.719568 -288.372443)
			(xy 139.767787 -288.362599) (xy 139.816962 -288.360618) (xy 139.865817 -288.36655) (xy 139.913088 -288.380242)
			(xy 139.95755 -288.40134) (xy 139.998053 -288.429296) (xy 140.033546 -288.463388) (xy 140.063111 -288.502732)
			(xy 140.085982 -288.546309) (xy 140.101566 -288.59299) (xy 140.109461 -288.641567) (xy 140.109956 -288.666174)
			(xy 140.109461 -288.690781) (xy 140.101566 -288.739358) (xy 140.085982 -288.786039) (xy 140.063111 -288.829616)
			(xy 140.033546 -288.86896) (xy 139.998053 -288.903052) (xy 139.95755 -288.931008) (xy 139.913088 -288.952106)
			(xy 139.865817 -288.965798) (xy 139.816962 -288.97173) (xy 139.767787 -288.969749) (xy 139.719568 -288.959905)
			(xy 139.673552 -288.942453) (xy 139.630931 -288.917846) (xy 139.59281 -288.886721) (xy 139.560175 -288.849884)
			(xy 139.533872 -288.808288) (xy 139.514581 -288.763012) (xy 139.502804 -288.715228) (xy 139.498844 -288.666174)
			(xy 139.170156 -288.666174) (xy 139.169661 -288.690781) (xy 139.161766 -288.739358) (xy 139.146182 -288.786039)
			(xy 139.123311 -288.829616) (xy 139.093746 -288.86896) (xy 139.058253 -288.903052) (xy 139.01775 -288.931008)
			(xy 138.973288 -288.952106) (xy 138.926017 -288.965798) (xy 138.877162 -288.97173) (xy 138.827987 -288.969749)
			(xy 138.779768 -288.959905) (xy 138.733752 -288.942453) (xy 138.691131 -288.917846) (xy 138.65301 -288.886721)
			(xy 138.620375 -288.849884) (xy 138.594072 -288.808288) (xy 138.574781 -288.763012) (xy 138.563004 -288.715228)
			(xy 138.559044 -288.666174) (xy 138.230102 -288.666174) (xy 138.229607 -288.690781) (xy 138.221712 -288.739358)
			(xy 138.206128 -288.786039) (xy 138.183257 -288.829616) (xy 138.153692 -288.86896) (xy 138.118199 -288.903052)
			(xy 138.077696 -288.931008) (xy 138.033234 -288.952106) (xy 137.985963 -288.965798) (xy 137.937108 -288.97173)
			(xy 137.887933 -288.969749) (xy 137.839714 -288.959905) (xy 137.793698 -288.942453) (xy 137.751077 -288.917846)
			(xy 137.712956 -288.886721) (xy 137.680321 -288.849884) (xy 137.654018 -288.808288) (xy 137.634727 -288.763012)
			(xy 137.62295 -288.715228) (xy 137.61899 -288.666174) (xy 137.290048 -288.666174) (xy 137.289553 -288.690781)
			(xy 137.281658 -288.739358) (xy 137.266074 -288.786039) (xy 137.243203 -288.829616) (xy 137.213638 -288.86896)
			(xy 137.178145 -288.903052) (xy 137.137642 -288.931008) (xy 137.09318 -288.952106) (xy 137.045909 -288.965798)
			(xy 136.997054 -288.97173) (xy 136.947879 -288.969749) (xy 136.89966 -288.959905) (xy 136.853644 -288.942453)
			(xy 136.811023 -288.917846) (xy 136.772902 -288.886721) (xy 136.740267 -288.849884) (xy 136.713964 -288.808288)
			(xy 136.694673 -288.763012) (xy 136.682896 -288.715228) (xy 136.678936 -288.666174) (xy 136.349994 -288.666174)
			(xy 136.349499 -288.690781) (xy 136.341604 -288.739358) (xy 136.32602 -288.786039) (xy 136.303149 -288.829616)
			(xy 136.273584 -288.86896) (xy 136.238091 -288.903052) (xy 136.197588 -288.931008) (xy 136.153126 -288.952106)
			(xy 136.105855 -288.965798) (xy 136.057 -288.97173) (xy 136.007825 -288.969749) (xy 135.959606 -288.959905)
			(xy 135.91359 -288.942453) (xy 135.870969 -288.917846) (xy 135.832848 -288.886721) (xy 135.800213 -288.849884)
			(xy 135.77391 -288.808288) (xy 135.754619 -288.763012) (xy 135.742842 -288.715228) (xy 135.738882 -288.666174)
			(xy 135.40994 -288.666174) (xy 135.409445 -288.690781) (xy 135.40155 -288.739358) (xy 135.385966 -288.786039)
			(xy 135.363095 -288.829616) (xy 135.33353 -288.86896) (xy 135.298037 -288.903052) (xy 135.257534 -288.931008)
			(xy 135.213072 -288.952106) (xy 135.165801 -288.965798) (xy 135.116946 -288.97173) (xy 135.067771 -288.969749)
			(xy 135.019552 -288.959905) (xy 134.973536 -288.942453) (xy 134.930915 -288.917846) (xy 134.892794 -288.886721)
			(xy 134.860159 -288.849884) (xy 134.833856 -288.808288) (xy 134.814565 -288.763012) (xy 134.802788 -288.715228)
			(xy 134.798828 -288.666174) (xy 134.47014 -288.666174) (xy 134.469645 -288.690781) (xy 134.46175 -288.739358)
			(xy 134.446166 -288.786039) (xy 134.423295 -288.829616) (xy 134.39373 -288.86896) (xy 134.358237 -288.903052)
			(xy 134.317734 -288.931008) (xy 134.273272 -288.952106) (xy 134.226001 -288.965798) (xy 134.177146 -288.97173)
			(xy 134.127971 -288.969749) (xy 134.079752 -288.959905) (xy 134.033736 -288.942453) (xy 133.991115 -288.917846)
			(xy 133.952994 -288.886721) (xy 133.920359 -288.849884) (xy 133.894056 -288.808288) (xy 133.874765 -288.763012)
			(xy 133.862988 -288.715228) (xy 133.859028 -288.666174) (xy 133.5405 -288.666174) (xy 133.539988 -288.69162)
			(xy 133.531824 -288.741854) (xy 133.515708 -288.790128) (xy 133.492057 -288.835191) (xy 133.461484 -288.875877)
			(xy 133.42478 -288.911132) (xy 133.382896 -288.940042) (xy 133.336917 -288.961859) (xy 133.288033 -288.976019)
			(xy 133.237512 -288.982153) (xy 133.18666 -288.980104) (xy 133.136796 -288.969924) (xy 133.08921 -288.951877)
			(xy 133.045136 -288.926431) (xy 133.005714 -288.894244) (xy 132.971966 -288.85615) (xy 132.944765 -288.813136)
			(xy 132.924817 -288.766316) (xy 132.912638 -288.716902) (xy 132.908543 -288.666174) (xy 132.590032 -288.666174)
			(xy 132.589537 -288.690781) (xy 132.581642 -288.739358) (xy 132.566058 -288.786039) (xy 132.543187 -288.829616)
			(xy 132.513622 -288.86896) (xy 132.478129 -288.903052) (xy 132.437626 -288.931008) (xy 132.393164 -288.952106)
			(xy 132.345893 -288.965798) (xy 132.297038 -288.97173) (xy 132.247863 -288.969749) (xy 132.199644 -288.959905)
			(xy 132.153628 -288.942453) (xy 132.111007 -288.917846) (xy 132.072886 -288.886721) (xy 132.040251 -288.849884)
			(xy 132.013948 -288.808288) (xy 131.994657 -288.763012) (xy 131.98288 -288.715228) (xy 131.97892 -288.666174)
			(xy 131.660392 -288.666174) (xy 131.65988 -288.69162) (xy 131.651716 -288.741854) (xy 131.6356 -288.790128)
			(xy 131.611949 -288.835191) (xy 131.581376 -288.875877) (xy 131.544672 -288.911132) (xy 131.502788 -288.940042)
			(xy 131.456809 -288.961859) (xy 131.407925 -288.976019) (xy 131.357404 -288.982153) (xy 131.306552 -288.980104)
			(xy 131.256688 -288.969924) (xy 131.209102 -288.951877) (xy 131.165028 -288.926431) (xy 131.125606 -288.894244)
			(xy 131.091858 -288.85615) (xy 131.064657 -288.813136) (xy 131.044709 -288.766316) (xy 131.03253 -288.716902)
			(xy 131.028435 -288.666174) (xy 130.710178 -288.666174) (xy 130.709683 -288.690781) (xy 130.701788 -288.739358)
			(xy 130.686204 -288.786039) (xy 130.663333 -288.829616) (xy 130.633768 -288.86896) (xy 130.598275 -288.903052)
			(xy 130.557772 -288.931008) (xy 130.51331 -288.952106) (xy 130.466039 -288.965798) (xy 130.417184 -288.97173)
			(xy 130.368009 -288.969749) (xy 130.31979 -288.959905) (xy 130.273774 -288.942453) (xy 130.231153 -288.917846)
			(xy 130.193032 -288.886721) (xy 130.160397 -288.849884) (xy 130.134094 -288.808288) (xy 130.114803 -288.763012)
			(xy 130.103026 -288.715228) (xy 130.099066 -288.666174) (xy 129.780538 -288.666174) (xy 129.780026 -288.69162)
			(xy 129.771862 -288.741854) (xy 129.755746 -288.790128) (xy 129.732095 -288.835191) (xy 129.701522 -288.875877)
			(xy 129.664818 -288.911132) (xy 129.622934 -288.940042) (xy 129.576955 -288.961859) (xy 129.528071 -288.976019)
			(xy 129.47755 -288.982153) (xy 129.426698 -288.980104) (xy 129.376834 -288.969924) (xy 129.329248 -288.951877)
			(xy 129.285174 -288.926431) (xy 129.245752 -288.894244) (xy 129.212004 -288.85615) (xy 129.184803 -288.813136)
			(xy 129.164855 -288.766316) (xy 129.152676 -288.716902) (xy 129.148581 -288.666174) (xy 128.840484 -288.666174)
			(xy 128.839972 -288.69162) (xy 128.831808 -288.741854) (xy 128.815692 -288.790128) (xy 128.792041 -288.835191)
			(xy 128.761468 -288.875877) (xy 128.724764 -288.911132) (xy 128.68288 -288.940042) (xy 128.636901 -288.961859)
			(xy 128.588017 -288.976019) (xy 128.537496 -288.982153) (xy 128.486644 -288.980104) (xy 128.43678 -288.969924)
			(xy 128.389194 -288.951877) (xy 128.34512 -288.926431) (xy 128.305698 -288.894244) (xy 128.27195 -288.85615)
			(xy 128.244749 -288.813136) (xy 128.224801 -288.766316) (xy 128.212622 -288.716902) (xy 128.208527 -288.666174)
			(xy 127.889542 -288.666174) (xy 127.889544 -288.690667) (xy 127.881737 -288.739003) (xy 127.866322 -288.785476)
			(xy 127.843692 -288.828896) (xy 127.814427 -288.86815) (xy 127.779276 -288.902235) (xy 127.75946 -288.916618)
			(xy 127.753399 -288.921515) (xy 127.74435 -288.934189) (xy 127.74168 -288.94151) (xy 127.730471 -288.984303)
			(xy 127.70225 -289.068151) (xy 127.667569 -289.14954) (xy 127.62664 -289.227973) (xy 127.579712 -289.302971)
			(xy 127.55372 -289.338766) (xy 127.548894 -289.345624) (xy 127.543814 -289.36061) (xy 127.543814 -289.47618)
			(xy 127.738627 -289.47618) (xy 127.742722 -289.425452) (xy 127.754901 -289.376038) (xy 127.774849 -289.329218)
			(xy 127.80205 -289.286204) (xy 127.835798 -289.24811) (xy 127.87522 -289.215923) (xy 127.919294 -289.190477)
			(xy 127.96688 -289.17243) (xy 128.016744 -289.16225) (xy 128.067596 -289.160201) (xy 128.118117 -289.166335)
			(xy 128.167001 -289.180495) (xy 128.21298 -289.202312) (xy 128.254864 -289.231222) (xy 128.291568 -289.266477)
			(xy 128.322141 -289.307163) (xy 128.345792 -289.352226) (xy 128.361908 -289.4005) (xy 128.370072 -289.450734)
			(xy 128.370584 -289.47618) (xy 128.688858 -289.47618) (xy 128.692818 -289.427126) (xy 128.704595 -289.379342)
			(xy 128.723886 -289.334066) (xy 128.750189 -289.29247) (xy 128.782824 -289.255633) (xy 128.820945 -289.224508)
			(xy 128.863566 -289.199901) (xy 128.909582 -289.182449) (xy 128.957801 -289.172605) (xy 129.006976 -289.170624)
			(xy 129.055831 -289.176556) (xy 129.103102 -289.190248) (xy 129.147564 -289.211346) (xy 129.188067 -289.239302)
			(xy 129.22356 -289.273394) (xy 129.253125 -289.312738) (xy 129.275996 -289.356315) (xy 129.29158 -289.402996)
			(xy 129.299475 -289.451573) (xy 129.29997 -289.47618) (xy 129.618481 -289.47618) (xy 129.622576 -289.425452)
			(xy 129.634755 -289.376038) (xy 129.654703 -289.329218) (xy 129.681904 -289.286204) (xy 129.715652 -289.24811)
			(xy 129.755074 -289.215923) (xy 129.799148 -289.190477) (xy 129.846734 -289.17243) (xy 129.896598 -289.16225)
			(xy 129.94745 -289.160201) (xy 129.997971 -289.166335) (xy 130.046855 -289.180495) (xy 130.092834 -289.202312)
			(xy 130.134718 -289.231222) (xy 130.171422 -289.266477) (xy 130.201995 -289.307163) (xy 130.225646 -289.352226)
			(xy 130.241762 -289.4005) (xy 130.249926 -289.450734) (xy 130.250438 -289.47618) (xy 130.568966 -289.47618)
			(xy 130.572926 -289.427126) (xy 130.584703 -289.379342) (xy 130.603994 -289.334066) (xy 130.630297 -289.29247)
			(xy 130.662932 -289.255633) (xy 130.701053 -289.224508) (xy 130.743674 -289.199901) (xy 130.78969 -289.182449)
			(xy 130.837909 -289.172605) (xy 130.887084 -289.170624) (xy 130.935939 -289.176556) (xy 130.98321 -289.190248)
			(xy 131.027672 -289.211346) (xy 131.068175 -289.239302) (xy 131.103668 -289.273394) (xy 131.133233 -289.312738)
			(xy 131.156104 -289.356315) (xy 131.171688 -289.402996) (xy 131.179583 -289.451573) (xy 131.180078 -289.47618)
			(xy 131.498589 -289.47618) (xy 131.502684 -289.425452) (xy 131.514863 -289.376038) (xy 131.534811 -289.329218)
			(xy 131.562012 -289.286204) (xy 131.59576 -289.24811) (xy 131.635182 -289.215923) (xy 131.679256 -289.190477)
			(xy 131.726842 -289.17243) (xy 131.776706 -289.16225) (xy 131.827558 -289.160201) (xy 131.878079 -289.166335)
			(xy 131.926963 -289.180495) (xy 131.972942 -289.202312) (xy 132.014826 -289.231222) (xy 132.05153 -289.266477)
			(xy 132.082103 -289.307163) (xy 132.105754 -289.352226) (xy 132.12187 -289.4005) (xy 132.130034 -289.450734)
			(xy 132.130546 -289.47618) (xy 132.438643 -289.47618) (xy 132.442738 -289.425452) (xy 132.454917 -289.376038)
			(xy 132.474865 -289.329218) (xy 132.502066 -289.286204) (xy 132.535814 -289.24811) (xy 132.575236 -289.215923)
			(xy 132.61931 -289.190477) (xy 132.666896 -289.17243) (xy 132.71676 -289.16225) (xy 132.767612 -289.160201)
			(xy 132.818133 -289.166335) (xy 132.867017 -289.180495) (xy 132.912996 -289.202312) (xy 132.95488 -289.231222)
			(xy 132.991584 -289.266477) (xy 133.022157 -289.307163) (xy 133.045808 -289.352226) (xy 133.061924 -289.4005)
			(xy 133.070088 -289.450734) (xy 133.0706 -289.47618) (xy 133.388874 -289.47618) (xy 133.392834 -289.427126)
			(xy 133.404611 -289.379342) (xy 133.423902 -289.334066) (xy 133.450205 -289.29247) (xy 133.48284 -289.255633)
			(xy 133.520961 -289.224508) (xy 133.563582 -289.199901) (xy 133.609598 -289.182449) (xy 133.657817 -289.172605)
			(xy 133.706992 -289.170624) (xy 133.755847 -289.176556) (xy 133.803118 -289.190248) (xy 133.84758 -289.211346)
			(xy 133.888083 -289.239302) (xy 133.923576 -289.273394) (xy 133.953141 -289.312738) (xy 133.976012 -289.356315)
			(xy 133.991596 -289.402996) (xy 133.999491 -289.451573) (xy 133.999986 -289.47618) (xy 134.328928 -289.47618)
			(xy 134.332888 -289.427126) (xy 134.344665 -289.379342) (xy 134.363956 -289.334066) (xy 134.390259 -289.29247)
			(xy 134.422894 -289.255633) (xy 134.461015 -289.224508) (xy 134.503636 -289.199901) (xy 134.549652 -289.182449)
			(xy 134.597871 -289.172605) (xy 134.647046 -289.170624) (xy 134.695901 -289.176556) (xy 134.743172 -289.190248)
			(xy 134.787634 -289.211346) (xy 134.828137 -289.239302) (xy 134.86363 -289.273394) (xy 134.893195 -289.312738)
			(xy 134.916066 -289.356315) (xy 134.93165 -289.402996) (xy 134.939545 -289.451573) (xy 134.94004 -289.47618)
			(xy 135.268982 -289.47618) (xy 135.272942 -289.427126) (xy 135.284719 -289.379342) (xy 135.30401 -289.334066)
			(xy 135.330313 -289.29247) (xy 135.362948 -289.255633) (xy 135.401069 -289.224508) (xy 135.44369 -289.199901)
			(xy 135.489706 -289.182449) (xy 135.537925 -289.172605) (xy 135.5871 -289.170624) (xy 135.635955 -289.176556)
			(xy 135.683226 -289.190248) (xy 135.727688 -289.211346) (xy 135.768191 -289.239302) (xy 135.803684 -289.273394)
			(xy 135.833249 -289.312738) (xy 135.85612 -289.356315) (xy 135.871704 -289.402996) (xy 135.879599 -289.451573)
			(xy 135.880094 -289.47618) (xy 136.209036 -289.47618) (xy 136.212996 -289.427126) (xy 136.224773 -289.379342)
			(xy 136.244064 -289.334066) (xy 136.270367 -289.29247) (xy 136.303002 -289.255633) (xy 136.341123 -289.224508)
			(xy 136.383744 -289.199901) (xy 136.42976 -289.182449) (xy 136.477979 -289.172605) (xy 136.527154 -289.170624)
			(xy 136.576009 -289.176556) (xy 136.62328 -289.190248) (xy 136.667742 -289.211346) (xy 136.708245 -289.239302)
			(xy 136.743738 -289.273394) (xy 136.773303 -289.312738) (xy 136.796174 -289.356315) (xy 136.811758 -289.402996)
			(xy 136.819653 -289.451573) (xy 136.820148 -289.47618) (xy 137.148836 -289.47618) (xy 137.152796 -289.427126)
			(xy 137.164573 -289.379342) (xy 137.183864 -289.334066) (xy 137.210167 -289.29247) (xy 137.242802 -289.255633)
			(xy 137.280923 -289.224508) (xy 137.323544 -289.199901) (xy 137.36956 -289.182449) (xy 137.417779 -289.172605)
			(xy 137.466954 -289.170624) (xy 137.515809 -289.176556) (xy 137.56308 -289.190248) (xy 137.607542 -289.211346)
			(xy 137.648045 -289.239302) (xy 137.683538 -289.273394) (xy 137.713103 -289.312738) (xy 137.735974 -289.356315)
			(xy 137.751558 -289.402996) (xy 137.759453 -289.451573) (xy 137.759948 -289.47618) (xy 138.08889 -289.47618)
			(xy 138.09285 -289.427126) (xy 138.104627 -289.379342) (xy 138.123918 -289.334066) (xy 138.150221 -289.29247)
			(xy 138.182856 -289.255633) (xy 138.220977 -289.224508) (xy 138.263598 -289.199901) (xy 138.309614 -289.182449)
			(xy 138.357833 -289.172605) (xy 138.407008 -289.170624) (xy 138.455863 -289.176556) (xy 138.503134 -289.190248)
			(xy 138.547596 -289.211346) (xy 138.588099 -289.239302) (xy 138.623592 -289.273394) (xy 138.653157 -289.312738)
			(xy 138.676028 -289.356315) (xy 138.691612 -289.402996) (xy 138.699507 -289.451573) (xy 138.700002 -289.47618)
			(xy 139.028944 -289.47618) (xy 139.032904 -289.427126) (xy 139.044681 -289.379342) (xy 139.063972 -289.334066)
			(xy 139.090275 -289.29247) (xy 139.12291 -289.255633) (xy 139.161031 -289.224508) (xy 139.203652 -289.199901)
			(xy 139.249668 -289.182449) (xy 139.297887 -289.172605) (xy 139.347062 -289.170624) (xy 139.395917 -289.176556)
			(xy 139.443188 -289.190248) (xy 139.48765 -289.211346) (xy 139.528153 -289.239302) (xy 139.563646 -289.273394)
			(xy 139.593211 -289.312738) (xy 139.616082 -289.356315) (xy 139.631666 -289.402996) (xy 139.639561 -289.451573)
			(xy 139.640056 -289.47618) (xy 139.639561 -289.500787) (xy 139.631666 -289.549364) (xy 139.616082 -289.596045)
			(xy 139.593211 -289.639622) (xy 139.563646 -289.678966) (xy 139.528153 -289.713058) (xy 139.48765 -289.741014)
			(xy 139.443188 -289.762112) (xy 139.395917 -289.775804) (xy 139.347062 -289.781736) (xy 139.297887 -289.779755)
			(xy 139.249668 -289.769911) (xy 139.203652 -289.752459) (xy 139.161031 -289.727852) (xy 139.12291 -289.696727)
			(xy 139.090275 -289.65989) (xy 139.063972 -289.618294) (xy 139.044681 -289.573018) (xy 139.032904 -289.525234)
			(xy 139.028944 -289.47618) (xy 138.700002 -289.47618) (xy 138.699507 -289.500787) (xy 138.691612 -289.549364)
			(xy 138.676028 -289.596045) (xy 138.653157 -289.639622) (xy 138.623592 -289.678966) (xy 138.588099 -289.713058)
			(xy 138.547596 -289.741014) (xy 138.503134 -289.762112) (xy 138.455863 -289.775804) (xy 138.407008 -289.781736)
			(xy 138.357833 -289.779755) (xy 138.309614 -289.769911) (xy 138.263598 -289.752459) (xy 138.220977 -289.727852)
			(xy 138.182856 -289.696727) (xy 138.150221 -289.65989) (xy 138.123918 -289.618294) (xy 138.104627 -289.573018)
			(xy 138.09285 -289.525234) (xy 138.08889 -289.47618) (xy 137.759948 -289.47618) (xy 137.759453 -289.500787)
			(xy 137.751558 -289.549364) (xy 137.735974 -289.596045) (xy 137.713103 -289.639622) (xy 137.683538 -289.678966)
			(xy 137.648045 -289.713058) (xy 137.607542 -289.741014) (xy 137.56308 -289.762112) (xy 137.515809 -289.775804)
			(xy 137.466954 -289.781736) (xy 137.417779 -289.779755) (xy 137.36956 -289.769911) (xy 137.323544 -289.752459)
			(xy 137.280923 -289.727852) (xy 137.242802 -289.696727) (xy 137.210167 -289.65989) (xy 137.183864 -289.618294)
			(xy 137.164573 -289.573018) (xy 137.152796 -289.525234) (xy 137.148836 -289.47618) (xy 136.820148 -289.47618)
			(xy 136.819653 -289.500787) (xy 136.811758 -289.549364) (xy 136.796174 -289.596045) (xy 136.773303 -289.639622)
			(xy 136.743738 -289.678966) (xy 136.708245 -289.713058) (xy 136.667742 -289.741014) (xy 136.62328 -289.762112)
			(xy 136.576009 -289.775804) (xy 136.527154 -289.781736) (xy 136.477979 -289.779755) (xy 136.42976 -289.769911)
			(xy 136.383744 -289.752459) (xy 136.341123 -289.727852) (xy 136.303002 -289.696727) (xy 136.270367 -289.65989)
			(xy 136.244064 -289.618294) (xy 136.224773 -289.573018) (xy 136.212996 -289.525234) (xy 136.209036 -289.47618)
			(xy 135.880094 -289.47618) (xy 135.879599 -289.500787) (xy 135.871704 -289.549364) (xy 135.85612 -289.596045)
			(xy 135.833249 -289.639622) (xy 135.803684 -289.678966) (xy 135.768191 -289.713058) (xy 135.727688 -289.741014)
			(xy 135.683226 -289.762112) (xy 135.635955 -289.775804) (xy 135.5871 -289.781736) (xy 135.537925 -289.779755)
			(xy 135.489706 -289.769911) (xy 135.44369 -289.752459) (xy 135.401069 -289.727852) (xy 135.362948 -289.696727)
			(xy 135.330313 -289.65989) (xy 135.30401 -289.618294) (xy 135.284719 -289.573018) (xy 135.272942 -289.525234)
			(xy 135.268982 -289.47618) (xy 134.94004 -289.47618) (xy 134.939545 -289.500787) (xy 134.93165 -289.549364)
			(xy 134.916066 -289.596045) (xy 134.893195 -289.639622) (xy 134.86363 -289.678966) (xy 134.828137 -289.713058)
			(xy 134.787634 -289.741014) (xy 134.743172 -289.762112) (xy 134.695901 -289.775804) (xy 134.647046 -289.781736)
			(xy 134.597871 -289.779755) (xy 134.549652 -289.769911) (xy 134.503636 -289.752459) (xy 134.461015 -289.727852)
			(xy 134.422894 -289.696727) (xy 134.390259 -289.65989) (xy 134.363956 -289.618294) (xy 134.344665 -289.573018)
			(xy 134.332888 -289.525234) (xy 134.328928 -289.47618) (xy 133.999986 -289.47618) (xy 133.999491 -289.500787)
			(xy 133.991596 -289.549364) (xy 133.976012 -289.596045) (xy 133.953141 -289.639622) (xy 133.923576 -289.678966)
			(xy 133.888083 -289.713058) (xy 133.84758 -289.741014) (xy 133.803118 -289.762112) (xy 133.755847 -289.775804)
			(xy 133.706992 -289.781736) (xy 133.657817 -289.779755) (xy 133.609598 -289.769911) (xy 133.563582 -289.752459)
			(xy 133.520961 -289.727852) (xy 133.48284 -289.696727) (xy 133.450205 -289.65989) (xy 133.423902 -289.618294)
			(xy 133.404611 -289.573018) (xy 133.392834 -289.525234) (xy 133.388874 -289.47618) (xy 133.0706 -289.47618)
			(xy 133.070088 -289.501626) (xy 133.061924 -289.55186) (xy 133.045808 -289.600134) (xy 133.022157 -289.645197)
			(xy 132.991584 -289.685883) (xy 132.95488 -289.721138) (xy 132.912996 -289.750048) (xy 132.867017 -289.771865)
			(xy 132.818133 -289.786025) (xy 132.767612 -289.792159) (xy 132.71676 -289.79011) (xy 132.666896 -289.77993)
			(xy 132.61931 -289.761883) (xy 132.575236 -289.736437) (xy 132.535814 -289.70425) (xy 132.502066 -289.666156)
			(xy 132.474865 -289.623142) (xy 132.454917 -289.576322) (xy 132.442738 -289.526908) (xy 132.438643 -289.47618)
			(xy 132.130546 -289.47618) (xy 132.130034 -289.501626) (xy 132.12187 -289.55186) (xy 132.105754 -289.600134)
			(xy 132.082103 -289.645197) (xy 132.05153 -289.685883) (xy 132.014826 -289.721138) (xy 131.972942 -289.750048)
			(xy 131.926963 -289.771865) (xy 131.878079 -289.786025) (xy 131.827558 -289.792159) (xy 131.776706 -289.79011)
			(xy 131.726842 -289.77993) (xy 131.679256 -289.761883) (xy 131.635182 -289.736437) (xy 131.59576 -289.70425)
			(xy 131.562012 -289.666156) (xy 131.534811 -289.623142) (xy 131.514863 -289.576322) (xy 131.502684 -289.526908)
			(xy 131.498589 -289.47618) (xy 131.180078 -289.47618) (xy 131.179583 -289.500787) (xy 131.171688 -289.549364)
			(xy 131.156104 -289.596045) (xy 131.133233 -289.639622) (xy 131.103668 -289.678966) (xy 131.068175 -289.713058)
			(xy 131.027672 -289.741014) (xy 130.98321 -289.762112) (xy 130.935939 -289.775804) (xy 130.887084 -289.781736)
			(xy 130.837909 -289.779755) (xy 130.78969 -289.769911) (xy 130.743674 -289.752459) (xy 130.701053 -289.727852)
			(xy 130.662932 -289.696727) (xy 130.630297 -289.65989) (xy 130.603994 -289.618294) (xy 130.584703 -289.573018)
			(xy 130.572926 -289.525234) (xy 130.568966 -289.47618) (xy 130.250438 -289.47618) (xy 130.249926 -289.501626)
			(xy 130.241762 -289.55186) (xy 130.225646 -289.600134) (xy 130.201995 -289.645197) (xy 130.171422 -289.685883)
			(xy 130.134718 -289.721138) (xy 130.092834 -289.750048) (xy 130.046855 -289.771865) (xy 129.997971 -289.786025)
			(xy 129.94745 -289.792159) (xy 129.896598 -289.79011) (xy 129.846734 -289.77993) (xy 129.799148 -289.761883)
			(xy 129.755074 -289.736437) (xy 129.715652 -289.70425) (xy 129.681904 -289.666156) (xy 129.654703 -289.623142)
			(xy 129.634755 -289.576322) (xy 129.622576 -289.526908) (xy 129.618481 -289.47618) (xy 129.29997 -289.47618)
			(xy 129.299475 -289.500787) (xy 129.29158 -289.549364) (xy 129.275996 -289.596045) (xy 129.253125 -289.639622)
			(xy 129.22356 -289.678966) (xy 129.188067 -289.713058) (xy 129.147564 -289.741014) (xy 129.103102 -289.762112)
			(xy 129.055831 -289.775804) (xy 129.006976 -289.781736) (xy 128.957801 -289.779755) (xy 128.909582 -289.769911)
			(xy 128.863566 -289.752459) (xy 128.820945 -289.727852) (xy 128.782824 -289.696727) (xy 128.750189 -289.65989)
			(xy 128.723886 -289.618294) (xy 128.704595 -289.573018) (xy 128.692818 -289.525234) (xy 128.688858 -289.47618)
			(xy 128.370584 -289.47618) (xy 128.370072 -289.501626) (xy 128.361908 -289.55186) (xy 128.345792 -289.600134)
			(xy 128.322141 -289.645197) (xy 128.291568 -289.685883) (xy 128.254864 -289.721138) (xy 128.21298 -289.750048)
			(xy 128.167001 -289.771865) (xy 128.118117 -289.786025) (xy 128.067596 -289.792159) (xy 128.016744 -289.79011)
			(xy 127.96688 -289.77993) (xy 127.919294 -289.761883) (xy 127.87522 -289.736437) (xy 127.835798 -289.70425)
			(xy 127.80205 -289.666156) (xy 127.774849 -289.623142) (xy 127.754901 -289.576322) (xy 127.742722 -289.526908)
			(xy 127.738627 -289.47618) (xy 127.543814 -289.47618) (xy 127.543814 -289.59175) (xy 127.548894 -289.606736)
			(xy 127.55372 -289.613594) (xy 127.579709 -289.649392) (xy 127.626657 -289.724379) (xy 127.667595 -289.802808)
			(xy 127.702272 -289.8842) (xy 127.730476 -289.968055) (xy 127.74168 -290.01085) (xy 127.744366 -290.018161)
			(xy 127.753418 -290.030827) (xy 127.75946 -290.035742) (xy 127.779252 -290.050158) (xy 127.814404 -290.084239)
			(xy 127.843671 -290.12349) (xy 127.866304 -290.166907) (xy 127.881722 -290.213377) (xy 127.889532 -290.261711)
			(xy 127.889532 -290.286186) (xy 128.208527 -290.286186) (xy 128.212622 -290.235458) (xy 128.224801 -290.186044)
			(xy 128.244749 -290.139224) (xy 128.27195 -290.09621) (xy 128.305698 -290.058116) (xy 128.34512 -290.025929)
			(xy 128.389194 -290.000483) (xy 128.43678 -289.982436) (xy 128.486644 -289.972256) (xy 128.537496 -289.970207)
			(xy 128.588017 -289.976341) (xy 128.636901 -289.990501) (xy 128.68288 -290.012318) (xy 128.724764 -290.041228)
			(xy 128.761468 -290.076483) (xy 128.792041 -290.117169) (xy 128.815692 -290.162232) (xy 128.831808 -290.210506)
			(xy 128.839972 -290.26074) (xy 128.840484 -290.286186) (xy 129.148581 -290.286186) (xy 129.152676 -290.235458)
			(xy 129.164855 -290.186044) (xy 129.184803 -290.139224) (xy 129.212004 -290.09621) (xy 129.245752 -290.058116)
			(xy 129.285174 -290.025929) (xy 129.329248 -290.000483) (xy 129.376834 -289.982436) (xy 129.426698 -289.972256)
			(xy 129.47755 -289.970207) (xy 129.528071 -289.976341) (xy 129.576955 -289.990501) (xy 129.622934 -290.012318)
			(xy 129.664818 -290.041228) (xy 129.701522 -290.076483) (xy 129.732095 -290.117169) (xy 129.755746 -290.162232)
			(xy 129.771862 -290.210506) (xy 129.780026 -290.26074) (xy 129.780538 -290.286186) (xy 130.099066 -290.286186)
			(xy 130.103026 -290.237132) (xy 130.114803 -290.189348) (xy 130.134094 -290.144072) (xy 130.160397 -290.102476)
			(xy 130.193032 -290.065639) (xy 130.231153 -290.034514) (xy 130.273774 -290.009907) (xy 130.31979 -289.992455)
			(xy 130.368009 -289.982611) (xy 130.417184 -289.98063) (xy 130.466039 -289.986562) (xy 130.51331 -290.000254)
			(xy 130.557772 -290.021352) (xy 130.598275 -290.049308) (xy 130.633768 -290.0834) (xy 130.663333 -290.122744)
			(xy 130.686204 -290.166321) (xy 130.701788 -290.213002) (xy 130.709683 -290.261579) (xy 130.710178 -290.286186)
			(xy 131.028435 -290.286186) (xy 131.03253 -290.235458) (xy 131.044709 -290.186044) (xy 131.064657 -290.139224)
			(xy 131.091858 -290.09621) (xy 131.125606 -290.058116) (xy 131.165028 -290.025929) (xy 131.209102 -290.000483)
			(xy 131.256688 -289.982436) (xy 131.306552 -289.972256) (xy 131.357404 -289.970207) (xy 131.407925 -289.976341)
			(xy 131.456809 -289.990501) (xy 131.502788 -290.012318) (xy 131.544672 -290.041228) (xy 131.581376 -290.076483)
			(xy 131.611949 -290.117169) (xy 131.6356 -290.162232) (xy 131.651716 -290.210506) (xy 131.65988 -290.26074)
			(xy 131.660392 -290.286186) (xy 131.97892 -290.286186) (xy 131.98288 -290.237132) (xy 131.994657 -290.189348)
			(xy 132.013948 -290.144072) (xy 132.040251 -290.102476) (xy 132.072886 -290.065639) (xy 132.111007 -290.034514)
			(xy 132.153628 -290.009907) (xy 132.199644 -289.992455) (xy 132.247863 -289.982611) (xy 132.297038 -289.98063)
			(xy 132.345893 -289.986562) (xy 132.393164 -290.000254) (xy 132.437626 -290.021352) (xy 132.478129 -290.049308)
			(xy 132.513622 -290.0834) (xy 132.543187 -290.122744) (xy 132.566058 -290.166321) (xy 132.581642 -290.213002)
			(xy 132.589537 -290.261579) (xy 132.590032 -290.286186) (xy 132.908543 -290.286186) (xy 132.912638 -290.235458)
			(xy 132.924817 -290.186044) (xy 132.944765 -290.139224) (xy 132.971966 -290.09621) (xy 133.005714 -290.058116)
			(xy 133.045136 -290.025929) (xy 133.08921 -290.000483) (xy 133.136796 -289.982436) (xy 133.18666 -289.972256)
			(xy 133.237512 -289.970207) (xy 133.288033 -289.976341) (xy 133.336917 -289.990501) (xy 133.382896 -290.012318)
			(xy 133.42478 -290.041228) (xy 133.461484 -290.076483) (xy 133.492057 -290.117169) (xy 133.515708 -290.162232)
			(xy 133.531824 -290.210506) (xy 133.539988 -290.26074) (xy 133.5405 -290.286186) (xy 133.859028 -290.286186)
			(xy 133.862988 -290.237132) (xy 133.874765 -290.189348) (xy 133.894056 -290.144072) (xy 133.920359 -290.102476)
			(xy 133.952994 -290.065639) (xy 133.991115 -290.034514) (xy 134.033736 -290.009907) (xy 134.079752 -289.992455)
			(xy 134.127971 -289.982611) (xy 134.177146 -289.98063) (xy 134.226001 -289.986562) (xy 134.273272 -290.000254)
			(xy 134.317734 -290.021352) (xy 134.358237 -290.049308) (xy 134.39373 -290.0834) (xy 134.423295 -290.122744)
			(xy 134.446166 -290.166321) (xy 134.46175 -290.213002) (xy 134.469645 -290.261579) (xy 134.47014 -290.286186)
			(xy 134.798828 -290.286186) (xy 134.802788 -290.237132) (xy 134.814565 -290.189348) (xy 134.833856 -290.144072)
			(xy 134.860159 -290.102476) (xy 134.892794 -290.065639) (xy 134.930915 -290.034514) (xy 134.973536 -290.009907)
			(xy 135.019552 -289.992455) (xy 135.067771 -289.982611) (xy 135.116946 -289.98063) (xy 135.165801 -289.986562)
			(xy 135.213072 -290.000254) (xy 135.257534 -290.021352) (xy 135.298037 -290.049308) (xy 135.33353 -290.0834)
			(xy 135.363095 -290.122744) (xy 135.385966 -290.166321) (xy 135.40155 -290.213002) (xy 135.409445 -290.261579)
			(xy 135.40994 -290.286186) (xy 135.738882 -290.286186) (xy 135.742842 -290.237132) (xy 135.754619 -290.189348)
			(xy 135.77391 -290.144072) (xy 135.800213 -290.102476) (xy 135.832848 -290.065639) (xy 135.870969 -290.034514)
			(xy 135.91359 -290.009907) (xy 135.959606 -289.992455) (xy 136.007825 -289.982611) (xy 136.057 -289.98063)
			(xy 136.105855 -289.986562) (xy 136.153126 -290.000254) (xy 136.197588 -290.021352) (xy 136.238091 -290.049308)
			(xy 136.273584 -290.0834) (xy 136.303149 -290.122744) (xy 136.32602 -290.166321) (xy 136.341604 -290.213002)
			(xy 136.349499 -290.261579) (xy 136.349994 -290.286186) (xy 136.678936 -290.286186) (xy 136.682896 -290.237132)
			(xy 136.694673 -290.189348) (xy 136.713964 -290.144072) (xy 136.740267 -290.102476) (xy 136.772902 -290.065639)
			(xy 136.811023 -290.034514) (xy 136.853644 -290.009907) (xy 136.89966 -289.992455) (xy 136.947879 -289.982611)
			(xy 136.997054 -289.98063) (xy 137.045909 -289.986562) (xy 137.09318 -290.000254) (xy 137.137642 -290.021352)
			(xy 137.178145 -290.049308) (xy 137.213638 -290.0834) (xy 137.243203 -290.122744) (xy 137.266074 -290.166321)
			(xy 137.281658 -290.213002) (xy 137.289553 -290.261579) (xy 137.290048 -290.286186) (xy 137.61899 -290.286186)
			(xy 137.62295 -290.237132) (xy 137.634727 -290.189348) (xy 137.654018 -290.144072) (xy 137.680321 -290.102476)
			(xy 137.712956 -290.065639) (xy 137.751077 -290.034514) (xy 137.793698 -290.009907) (xy 137.839714 -289.992455)
			(xy 137.887933 -289.982611) (xy 137.937108 -289.98063) (xy 137.985963 -289.986562) (xy 138.033234 -290.000254)
			(xy 138.077696 -290.021352) (xy 138.118199 -290.049308) (xy 138.153692 -290.0834) (xy 138.183257 -290.122744)
			(xy 138.206128 -290.166321) (xy 138.221712 -290.213002) (xy 138.229607 -290.261579) (xy 138.230102 -290.286186)
			(xy 138.559044 -290.286186) (xy 138.563004 -290.237132) (xy 138.574781 -290.189348) (xy 138.594072 -290.144072)
			(xy 138.620375 -290.102476) (xy 138.65301 -290.065639) (xy 138.691131 -290.034514) (xy 138.733752 -290.009907)
			(xy 138.779768 -289.992455) (xy 138.827987 -289.982611) (xy 138.877162 -289.98063) (xy 138.926017 -289.986562)
			(xy 138.973288 -290.000254) (xy 139.01775 -290.021352) (xy 139.058253 -290.049308) (xy 139.093746 -290.0834)
			(xy 139.123311 -290.122744) (xy 139.146182 -290.166321) (xy 139.161766 -290.213002) (xy 139.169661 -290.261579)
			(xy 139.170156 -290.286186) (xy 139.498844 -290.286186) (xy 139.502804 -290.237132) (xy 139.514581 -290.189348)
			(xy 139.533872 -290.144072) (xy 139.560175 -290.102476) (xy 139.59281 -290.065639) (xy 139.630931 -290.034514)
			(xy 139.673552 -290.009907) (xy 139.719568 -289.992455) (xy 139.767787 -289.982611) (xy 139.816962 -289.98063)
			(xy 139.865817 -289.986562) (xy 139.913088 -290.000254) (xy 139.95755 -290.021352) (xy 139.998053 -290.049308)
			(xy 140.033546 -290.0834) (xy 140.063111 -290.122744) (xy 140.085982 -290.166321) (xy 140.101566 -290.213002)
			(xy 140.109461 -290.261579) (xy 140.109956 -290.286186) (xy 140.109461 -290.310793) (xy 140.101566 -290.35937)
			(xy 140.085982 -290.406051) (xy 140.063111 -290.449628) (xy 140.033546 -290.488972) (xy 139.998053 -290.523064)
			(xy 139.95755 -290.55102) (xy 139.913088 -290.572118) (xy 139.865817 -290.58581) (xy 139.816962 -290.591742)
			(xy 139.767787 -290.589761) (xy 139.719568 -290.579917) (xy 139.673552 -290.562465) (xy 139.630931 -290.537858)
			(xy 139.59281 -290.506733) (xy 139.560175 -290.469896) (xy 139.533872 -290.4283) (xy 139.514581 -290.383024)
			(xy 139.502804 -290.33524) (xy 139.498844 -290.286186) (xy 139.170156 -290.286186) (xy 139.169661 -290.310793)
			(xy 139.161766 -290.35937) (xy 139.146182 -290.406051) (xy 139.123311 -290.449628) (xy 139.093746 -290.488972)
			(xy 139.058253 -290.523064) (xy 139.01775 -290.55102) (xy 138.973288 -290.572118) (xy 138.926017 -290.58581)
			(xy 138.877162 -290.591742) (xy 138.827987 -290.589761) (xy 138.779768 -290.579917) (xy 138.733752 -290.562465)
			(xy 138.691131 -290.537858) (xy 138.65301 -290.506733) (xy 138.620375 -290.469896) (xy 138.594072 -290.4283)
			(xy 138.574781 -290.383024) (xy 138.563004 -290.33524) (xy 138.559044 -290.286186) (xy 138.230102 -290.286186)
			(xy 138.229607 -290.310793) (xy 138.221712 -290.35937) (xy 138.206128 -290.406051) (xy 138.183257 -290.449628)
			(xy 138.153692 -290.488972) (xy 138.118199 -290.523064) (xy 138.077696 -290.55102) (xy 138.033234 -290.572118)
			(xy 137.985963 -290.58581) (xy 137.937108 -290.591742) (xy 137.887933 -290.589761) (xy 137.839714 -290.579917)
			(xy 137.793698 -290.562465) (xy 137.751077 -290.537858) (xy 137.712956 -290.506733) (xy 137.680321 -290.469896)
			(xy 137.654018 -290.4283) (xy 137.634727 -290.383024) (xy 137.62295 -290.33524) (xy 137.61899 -290.286186)
			(xy 137.290048 -290.286186) (xy 137.289553 -290.310793) (xy 137.281658 -290.35937) (xy 137.266074 -290.406051)
			(xy 137.243203 -290.449628) (xy 137.213638 -290.488972) (xy 137.178145 -290.523064) (xy 137.137642 -290.55102)
			(xy 137.09318 -290.572118) (xy 137.045909 -290.58581) (xy 136.997054 -290.591742) (xy 136.947879 -290.589761)
			(xy 136.89966 -290.579917) (xy 136.853644 -290.562465) (xy 136.811023 -290.537858) (xy 136.772902 -290.506733)
			(xy 136.740267 -290.469896) (xy 136.713964 -290.4283) (xy 136.694673 -290.383024) (xy 136.682896 -290.33524)
			(xy 136.678936 -290.286186) (xy 136.349994 -290.286186) (xy 136.349499 -290.310793) (xy 136.341604 -290.35937)
			(xy 136.32602 -290.406051) (xy 136.303149 -290.449628) (xy 136.273584 -290.488972) (xy 136.238091 -290.523064)
			(xy 136.197588 -290.55102) (xy 136.153126 -290.572118) (xy 136.105855 -290.58581) (xy 136.057 -290.591742)
			(xy 136.007825 -290.589761) (xy 135.959606 -290.579917) (xy 135.91359 -290.562465) (xy 135.870969 -290.537858)
			(xy 135.832848 -290.506733) (xy 135.800213 -290.469896) (xy 135.77391 -290.4283) (xy 135.754619 -290.383024)
			(xy 135.742842 -290.33524) (xy 135.738882 -290.286186) (xy 135.40994 -290.286186) (xy 135.409445 -290.310793)
			(xy 135.40155 -290.35937) (xy 135.385966 -290.406051) (xy 135.363095 -290.449628) (xy 135.33353 -290.488972)
			(xy 135.298037 -290.523064) (xy 135.257534 -290.55102) (xy 135.213072 -290.572118) (xy 135.165801 -290.58581)
			(xy 135.116946 -290.591742) (xy 135.067771 -290.589761) (xy 135.019552 -290.579917) (xy 134.973536 -290.562465)
			(xy 134.930915 -290.537858) (xy 134.892794 -290.506733) (xy 134.860159 -290.469896) (xy 134.833856 -290.4283)
			(xy 134.814565 -290.383024) (xy 134.802788 -290.33524) (xy 134.798828 -290.286186) (xy 134.47014 -290.286186)
			(xy 134.469645 -290.310793) (xy 134.46175 -290.35937) (xy 134.446166 -290.406051) (xy 134.423295 -290.449628)
			(xy 134.39373 -290.488972) (xy 134.358237 -290.523064) (xy 134.317734 -290.55102) (xy 134.273272 -290.572118)
			(xy 134.226001 -290.58581) (xy 134.177146 -290.591742) (xy 134.127971 -290.589761) (xy 134.079752 -290.579917)
			(xy 134.033736 -290.562465) (xy 133.991115 -290.537858) (xy 133.952994 -290.506733) (xy 133.920359 -290.469896)
			(xy 133.894056 -290.4283) (xy 133.874765 -290.383024) (xy 133.862988 -290.33524) (xy 133.859028 -290.286186)
			(xy 133.5405 -290.286186) (xy 133.539988 -290.311632) (xy 133.531824 -290.361866) (xy 133.515708 -290.41014)
			(xy 133.492057 -290.455203) (xy 133.461484 -290.495889) (xy 133.42478 -290.531144) (xy 133.382896 -290.560054)
			(xy 133.336917 -290.581871) (xy 133.288033 -290.596031) (xy 133.237512 -290.602165) (xy 133.18666 -290.600116)
			(xy 133.136796 -290.589936) (xy 133.08921 -290.571889) (xy 133.045136 -290.546443) (xy 133.005714 -290.514256)
			(xy 132.971966 -290.476162) (xy 132.944765 -290.433148) (xy 132.924817 -290.386328) (xy 132.912638 -290.336914)
			(xy 132.908543 -290.286186) (xy 132.590032 -290.286186) (xy 132.589537 -290.310793) (xy 132.581642 -290.35937)
			(xy 132.566058 -290.406051) (xy 132.543187 -290.449628) (xy 132.513622 -290.488972) (xy 132.478129 -290.523064)
			(xy 132.437626 -290.55102) (xy 132.393164 -290.572118) (xy 132.345893 -290.58581) (xy 132.297038 -290.591742)
			(xy 132.247863 -290.589761) (xy 132.199644 -290.579917) (xy 132.153628 -290.562465) (xy 132.111007 -290.537858)
			(xy 132.072886 -290.506733) (xy 132.040251 -290.469896) (xy 132.013948 -290.4283) (xy 131.994657 -290.383024)
			(xy 131.98288 -290.33524) (xy 131.97892 -290.286186) (xy 131.660392 -290.286186) (xy 131.65988 -290.311632)
			(xy 131.651716 -290.361866) (xy 131.6356 -290.41014) (xy 131.611949 -290.455203) (xy 131.581376 -290.495889)
			(xy 131.544672 -290.531144) (xy 131.502788 -290.560054) (xy 131.456809 -290.581871) (xy 131.407925 -290.596031)
			(xy 131.357404 -290.602165) (xy 131.306552 -290.600116) (xy 131.256688 -290.589936) (xy 131.209102 -290.571889)
			(xy 131.165028 -290.546443) (xy 131.125606 -290.514256) (xy 131.091858 -290.476162) (xy 131.064657 -290.433148)
			(xy 131.044709 -290.386328) (xy 131.03253 -290.336914) (xy 131.028435 -290.286186) (xy 130.710178 -290.286186)
			(xy 130.709683 -290.310793) (xy 130.701788 -290.35937) (xy 130.686204 -290.406051) (xy 130.663333 -290.449628)
			(xy 130.633768 -290.488972) (xy 130.598275 -290.523064) (xy 130.557772 -290.55102) (xy 130.51331 -290.572118)
			(xy 130.466039 -290.58581) (xy 130.417184 -290.591742) (xy 130.368009 -290.589761) (xy 130.31979 -290.579917)
			(xy 130.273774 -290.562465) (xy 130.231153 -290.537858) (xy 130.193032 -290.506733) (xy 130.160397 -290.469896)
			(xy 130.134094 -290.4283) (xy 130.114803 -290.383024) (xy 130.103026 -290.33524) (xy 130.099066 -290.286186)
			(xy 129.780538 -290.286186) (xy 129.780026 -290.311632) (xy 129.771862 -290.361866) (xy 129.755746 -290.41014)
			(xy 129.732095 -290.455203) (xy 129.701522 -290.495889) (xy 129.664818 -290.531144) (xy 129.622934 -290.560054)
			(xy 129.576955 -290.581871) (xy 129.528071 -290.596031) (xy 129.47755 -290.602165) (xy 129.426698 -290.600116)
			(xy 129.376834 -290.589936) (xy 129.329248 -290.571889) (xy 129.285174 -290.546443) (xy 129.245752 -290.514256)
			(xy 129.212004 -290.476162) (xy 129.184803 -290.433148) (xy 129.164855 -290.386328) (xy 129.152676 -290.336914)
			(xy 129.148581 -290.286186) (xy 128.840484 -290.286186) (xy 128.839972 -290.311632) (xy 128.831808 -290.361866)
			(xy 128.815692 -290.41014) (xy 128.792041 -290.455203) (xy 128.761468 -290.495889) (xy 128.724764 -290.531144)
			(xy 128.68288 -290.560054) (xy 128.636901 -290.581871) (xy 128.588017 -290.596031) (xy 128.537496 -290.602165)
			(xy 128.486644 -290.600116) (xy 128.43678 -290.589936) (xy 128.389194 -290.571889) (xy 128.34512 -290.546443)
			(xy 128.305698 -290.514256) (xy 128.27195 -290.476162) (xy 128.244749 -290.433148) (xy 128.224801 -290.386328)
			(xy 128.212622 -290.336914) (xy 128.208527 -290.286186) (xy 127.889532 -290.286186) (xy 127.889533 -290.310673)
			(xy 127.881726 -290.359007) (xy 127.86631 -290.405479) (xy 127.84368 -290.448896) (xy 127.814415 -290.488149)
			(xy 127.779264 -290.522232) (xy 127.75946 -290.53663) (xy 127.7534 -290.541527) (xy 127.744353 -290.554203)
			(xy 127.74168 -290.561522) (xy 127.73047 -290.604315) (xy 127.702249 -290.688163) (xy 127.667567 -290.769551)
			(xy 127.626637 -290.847983) (xy 127.579709 -290.922981) (xy 127.55372 -290.958778) (xy 127.548894 -290.965636)
			(xy 127.543814 -290.980622) (xy 127.543814 -291.096192) (xy 127.738627 -291.096192) (xy 127.742722 -291.045464)
			(xy 127.754901 -290.99605) (xy 127.774849 -290.94923) (xy 127.80205 -290.906216) (xy 127.835798 -290.868122)
			(xy 127.87522 -290.835935) (xy 127.919294 -290.810489) (xy 127.96688 -290.792442) (xy 128.016744 -290.782262)
			(xy 128.067596 -290.780213) (xy 128.118117 -290.786347) (xy 128.167001 -290.800507) (xy 128.21298 -290.822324)
			(xy 128.254864 -290.851234) (xy 128.291568 -290.886489) (xy 128.322141 -290.927175) (xy 128.345792 -290.972238)
			(xy 128.361908 -291.020512) (xy 128.370072 -291.070746) (xy 128.370584 -291.096192) (xy 128.688858 -291.096192)
			(xy 128.692818 -291.047138) (xy 128.704595 -290.999354) (xy 128.723886 -290.954078) (xy 128.750189 -290.912482)
			(xy 128.782824 -290.875645) (xy 128.820945 -290.84452) (xy 128.863566 -290.819913) (xy 128.909582 -290.802461)
			(xy 128.957801 -290.792617) (xy 129.006976 -290.790636) (xy 129.055831 -290.796568) (xy 129.103102 -290.81026)
			(xy 129.147564 -290.831358) (xy 129.188067 -290.859314) (xy 129.22356 -290.893406) (xy 129.253125 -290.93275)
			(xy 129.275996 -290.976327) (xy 129.29158 -291.023008) (xy 129.299475 -291.071585) (xy 129.29997 -291.096192)
			(xy 129.618481 -291.096192) (xy 129.622576 -291.045464) (xy 129.634755 -290.99605) (xy 129.654703 -290.94923)
			(xy 129.681904 -290.906216) (xy 129.715652 -290.868122) (xy 129.755074 -290.835935) (xy 129.799148 -290.810489)
			(xy 129.846734 -290.792442) (xy 129.896598 -290.782262) (xy 129.94745 -290.780213) (xy 129.997971 -290.786347)
			(xy 130.046855 -290.800507) (xy 130.092834 -290.822324) (xy 130.134718 -290.851234) (xy 130.171422 -290.886489)
			(xy 130.201995 -290.927175) (xy 130.225646 -290.972238) (xy 130.241762 -291.020512) (xy 130.249926 -291.070746)
			(xy 130.250438 -291.096192) (xy 130.568966 -291.096192) (xy 130.572926 -291.047138) (xy 130.584703 -290.999354)
			(xy 130.603994 -290.954078) (xy 130.630297 -290.912482) (xy 130.662932 -290.875645) (xy 130.701053 -290.84452)
			(xy 130.743674 -290.819913) (xy 130.78969 -290.802461) (xy 130.837909 -290.792617) (xy 130.887084 -290.790636)
			(xy 130.935939 -290.796568) (xy 130.98321 -290.81026) (xy 131.027672 -290.831358) (xy 131.068175 -290.859314)
			(xy 131.103668 -290.893406) (xy 131.133233 -290.93275) (xy 131.156104 -290.976327) (xy 131.171688 -291.023008)
			(xy 131.179583 -291.071585) (xy 131.180078 -291.096192) (xy 131.498589 -291.096192) (xy 131.502684 -291.045464)
			(xy 131.514863 -290.99605) (xy 131.534811 -290.94923) (xy 131.562012 -290.906216) (xy 131.59576 -290.868122)
			(xy 131.635182 -290.835935) (xy 131.679256 -290.810489) (xy 131.726842 -290.792442) (xy 131.776706 -290.782262)
			(xy 131.827558 -290.780213) (xy 131.878079 -290.786347) (xy 131.926963 -290.800507) (xy 131.972942 -290.822324)
			(xy 132.014826 -290.851234) (xy 132.05153 -290.886489) (xy 132.082103 -290.927175) (xy 132.105754 -290.972238)
			(xy 132.12187 -291.020512) (xy 132.130034 -291.070746) (xy 132.130546 -291.096192) (xy 132.438643 -291.096192)
			(xy 132.442738 -291.045464) (xy 132.454917 -290.99605) (xy 132.474865 -290.94923) (xy 132.502066 -290.906216)
			(xy 132.535814 -290.868122) (xy 132.575236 -290.835935) (xy 132.61931 -290.810489) (xy 132.666896 -290.792442)
			(xy 132.71676 -290.782262) (xy 132.767612 -290.780213) (xy 132.818133 -290.786347) (xy 132.867017 -290.800507)
			(xy 132.912996 -290.822324) (xy 132.95488 -290.851234) (xy 132.991584 -290.886489) (xy 133.022157 -290.927175)
			(xy 133.045808 -290.972238) (xy 133.061924 -291.020512) (xy 133.070088 -291.070746) (xy 133.0706 -291.096192)
			(xy 133.388874 -291.096192) (xy 133.392834 -291.047138) (xy 133.404611 -290.999354) (xy 133.423902 -290.954078)
			(xy 133.450205 -290.912482) (xy 133.48284 -290.875645) (xy 133.520961 -290.84452) (xy 133.563582 -290.819913)
			(xy 133.609598 -290.802461) (xy 133.657817 -290.792617) (xy 133.706992 -290.790636) (xy 133.755847 -290.796568)
			(xy 133.803118 -290.81026) (xy 133.84758 -290.831358) (xy 133.888083 -290.859314) (xy 133.923576 -290.893406)
			(xy 133.953141 -290.93275) (xy 133.976012 -290.976327) (xy 133.991596 -291.023008) (xy 133.999491 -291.071585)
			(xy 133.999986 -291.096192) (xy 134.328928 -291.096192) (xy 134.332888 -291.047138) (xy 134.344665 -290.999354)
			(xy 134.363956 -290.954078) (xy 134.390259 -290.912482) (xy 134.422894 -290.875645) (xy 134.461015 -290.84452)
			(xy 134.503636 -290.819913) (xy 134.549652 -290.802461) (xy 134.597871 -290.792617) (xy 134.647046 -290.790636)
			(xy 134.695901 -290.796568) (xy 134.743172 -290.81026) (xy 134.787634 -290.831358) (xy 134.828137 -290.859314)
			(xy 134.86363 -290.893406) (xy 134.893195 -290.93275) (xy 134.916066 -290.976327) (xy 134.93165 -291.023008)
			(xy 134.939545 -291.071585) (xy 134.94004 -291.096192) (xy 135.268982 -291.096192) (xy 135.272942 -291.047138)
			(xy 135.284719 -290.999354) (xy 135.30401 -290.954078) (xy 135.330313 -290.912482) (xy 135.362948 -290.875645)
			(xy 135.401069 -290.84452) (xy 135.44369 -290.819913) (xy 135.489706 -290.802461) (xy 135.537925 -290.792617)
			(xy 135.5871 -290.790636) (xy 135.635955 -290.796568) (xy 135.683226 -290.81026) (xy 135.727688 -290.831358)
			(xy 135.768191 -290.859314) (xy 135.803684 -290.893406) (xy 135.833249 -290.93275) (xy 135.85612 -290.976327)
			(xy 135.871704 -291.023008) (xy 135.879599 -291.071585) (xy 135.880094 -291.096192) (xy 136.209036 -291.096192)
			(xy 136.212996 -291.047138) (xy 136.224773 -290.999354) (xy 136.244064 -290.954078) (xy 136.270367 -290.912482)
			(xy 136.303002 -290.875645) (xy 136.341123 -290.84452) (xy 136.383744 -290.819913) (xy 136.42976 -290.802461)
			(xy 136.477979 -290.792617) (xy 136.527154 -290.790636) (xy 136.576009 -290.796568) (xy 136.62328 -290.81026)
			(xy 136.667742 -290.831358) (xy 136.708245 -290.859314) (xy 136.743738 -290.893406) (xy 136.773303 -290.93275)
			(xy 136.796174 -290.976327) (xy 136.811758 -291.023008) (xy 136.819653 -291.071585) (xy 136.820148 -291.096192)
			(xy 137.148836 -291.096192) (xy 137.152796 -291.047138) (xy 137.164573 -290.999354) (xy 137.183864 -290.954078)
			(xy 137.210167 -290.912482) (xy 137.242802 -290.875645) (xy 137.280923 -290.84452) (xy 137.323544 -290.819913)
			(xy 137.36956 -290.802461) (xy 137.417779 -290.792617) (xy 137.466954 -290.790636) (xy 137.515809 -290.796568)
			(xy 137.56308 -290.81026) (xy 137.607542 -290.831358) (xy 137.648045 -290.859314) (xy 137.683538 -290.893406)
			(xy 137.713103 -290.93275) (xy 137.735974 -290.976327) (xy 137.751558 -291.023008) (xy 137.759453 -291.071585)
			(xy 137.759948 -291.096192) (xy 138.08889 -291.096192) (xy 138.09285 -291.047138) (xy 138.104627 -290.999354)
			(xy 138.123918 -290.954078) (xy 138.150221 -290.912482) (xy 138.182856 -290.875645) (xy 138.220977 -290.84452)
			(xy 138.263598 -290.819913) (xy 138.309614 -290.802461) (xy 138.357833 -290.792617) (xy 138.407008 -290.790636)
			(xy 138.455863 -290.796568) (xy 138.503134 -290.81026) (xy 138.547596 -290.831358) (xy 138.588099 -290.859314)
			(xy 138.623592 -290.893406) (xy 138.653157 -290.93275) (xy 138.676028 -290.976327) (xy 138.691612 -291.023008)
			(xy 138.699507 -291.071585) (xy 138.700002 -291.096192) (xy 139.028944 -291.096192) (xy 139.032904 -291.047138)
			(xy 139.044681 -290.999354) (xy 139.063972 -290.954078) (xy 139.090275 -290.912482) (xy 139.12291 -290.875645)
			(xy 139.161031 -290.84452) (xy 139.203652 -290.819913) (xy 139.249668 -290.802461) (xy 139.297887 -290.792617)
			(xy 139.347062 -290.790636) (xy 139.395917 -290.796568) (xy 139.443188 -290.81026) (xy 139.48765 -290.831358)
			(xy 139.528153 -290.859314) (xy 139.563646 -290.893406) (xy 139.593211 -290.93275) (xy 139.616082 -290.976327)
			(xy 139.631666 -291.023008) (xy 139.639561 -291.071585) (xy 139.640056 -291.096192) (xy 139.639561 -291.120799)
			(xy 139.631666 -291.169376) (xy 139.616082 -291.216057) (xy 139.593211 -291.259634) (xy 139.563646 -291.298978)
			(xy 139.528153 -291.33307) (xy 139.48765 -291.361026) (xy 139.443188 -291.382124) (xy 139.395917 -291.395816)
			(xy 139.347062 -291.401748) (xy 139.297887 -291.399767) (xy 139.249668 -291.389923) (xy 139.203652 -291.372471)
			(xy 139.161031 -291.347864) (xy 139.12291 -291.316739) (xy 139.090275 -291.279902) (xy 139.063972 -291.238306)
			(xy 139.044681 -291.19303) (xy 139.032904 -291.145246) (xy 139.028944 -291.096192) (xy 138.700002 -291.096192)
			(xy 138.699507 -291.120799) (xy 138.691612 -291.169376) (xy 138.676028 -291.216057) (xy 138.653157 -291.259634)
			(xy 138.623592 -291.298978) (xy 138.588099 -291.33307) (xy 138.547596 -291.361026) (xy 138.503134 -291.382124)
			(xy 138.455863 -291.395816) (xy 138.407008 -291.401748) (xy 138.357833 -291.399767) (xy 138.309614 -291.389923)
			(xy 138.263598 -291.372471) (xy 138.220977 -291.347864) (xy 138.182856 -291.316739) (xy 138.150221 -291.279902)
			(xy 138.123918 -291.238306) (xy 138.104627 -291.19303) (xy 138.09285 -291.145246) (xy 138.08889 -291.096192)
			(xy 137.759948 -291.096192) (xy 137.759453 -291.120799) (xy 137.751558 -291.169376) (xy 137.735974 -291.216057)
			(xy 137.713103 -291.259634) (xy 137.683538 -291.298978) (xy 137.648045 -291.33307) (xy 137.607542 -291.361026)
			(xy 137.56308 -291.382124) (xy 137.515809 -291.395816) (xy 137.466954 -291.401748) (xy 137.417779 -291.399767)
			(xy 137.36956 -291.389923) (xy 137.323544 -291.372471) (xy 137.280923 -291.347864) (xy 137.242802 -291.316739)
			(xy 137.210167 -291.279902) (xy 137.183864 -291.238306) (xy 137.164573 -291.19303) (xy 137.152796 -291.145246)
			(xy 137.148836 -291.096192) (xy 136.820148 -291.096192) (xy 136.819653 -291.120799) (xy 136.811758 -291.169376)
			(xy 136.796174 -291.216057) (xy 136.773303 -291.259634) (xy 136.743738 -291.298978) (xy 136.708245 -291.33307)
			(xy 136.667742 -291.361026) (xy 136.62328 -291.382124) (xy 136.576009 -291.395816) (xy 136.527154 -291.401748)
			(xy 136.477979 -291.399767) (xy 136.42976 -291.389923) (xy 136.383744 -291.372471) (xy 136.341123 -291.347864)
			(xy 136.303002 -291.316739) (xy 136.270367 -291.279902) (xy 136.244064 -291.238306) (xy 136.224773 -291.19303)
			(xy 136.212996 -291.145246) (xy 136.209036 -291.096192) (xy 135.880094 -291.096192) (xy 135.879599 -291.120799)
			(xy 135.871704 -291.169376) (xy 135.85612 -291.216057) (xy 135.833249 -291.259634) (xy 135.803684 -291.298978)
			(xy 135.768191 -291.33307) (xy 135.727688 -291.361026) (xy 135.683226 -291.382124) (xy 135.635955 -291.395816)
			(xy 135.5871 -291.401748) (xy 135.537925 -291.399767) (xy 135.489706 -291.389923) (xy 135.44369 -291.372471)
			(xy 135.401069 -291.347864) (xy 135.362948 -291.316739) (xy 135.330313 -291.279902) (xy 135.30401 -291.238306)
			(xy 135.284719 -291.19303) (xy 135.272942 -291.145246) (xy 135.268982 -291.096192) (xy 134.94004 -291.096192)
			(xy 134.939545 -291.120799) (xy 134.93165 -291.169376) (xy 134.916066 -291.216057) (xy 134.893195 -291.259634)
			(xy 134.86363 -291.298978) (xy 134.828137 -291.33307) (xy 134.787634 -291.361026) (xy 134.743172 -291.382124)
			(xy 134.695901 -291.395816) (xy 134.647046 -291.401748) (xy 134.597871 -291.399767) (xy 134.549652 -291.389923)
			(xy 134.503636 -291.372471) (xy 134.461015 -291.347864) (xy 134.422894 -291.316739) (xy 134.390259 -291.279902)
			(xy 134.363956 -291.238306) (xy 134.344665 -291.19303) (xy 134.332888 -291.145246) (xy 134.328928 -291.096192)
			(xy 133.999986 -291.096192) (xy 133.999491 -291.120799) (xy 133.991596 -291.169376) (xy 133.976012 -291.216057)
			(xy 133.953141 -291.259634) (xy 133.923576 -291.298978) (xy 133.888083 -291.33307) (xy 133.84758 -291.361026)
			(xy 133.803118 -291.382124) (xy 133.755847 -291.395816) (xy 133.706992 -291.401748) (xy 133.657817 -291.399767)
			(xy 133.609598 -291.389923) (xy 133.563582 -291.372471) (xy 133.520961 -291.347864) (xy 133.48284 -291.316739)
			(xy 133.450205 -291.279902) (xy 133.423902 -291.238306) (xy 133.404611 -291.19303) (xy 133.392834 -291.145246)
			(xy 133.388874 -291.096192) (xy 133.0706 -291.096192) (xy 133.070088 -291.121638) (xy 133.061924 -291.171872)
			(xy 133.045808 -291.220146) (xy 133.022157 -291.265209) (xy 132.991584 -291.305895) (xy 132.95488 -291.34115)
			(xy 132.912996 -291.37006) (xy 132.867017 -291.391877) (xy 132.818133 -291.406037) (xy 132.767612 -291.412171)
			(xy 132.71676 -291.410122) (xy 132.666896 -291.399942) (xy 132.61931 -291.381895) (xy 132.575236 -291.356449)
			(xy 132.535814 -291.324262) (xy 132.502066 -291.286168) (xy 132.474865 -291.243154) (xy 132.454917 -291.196334)
			(xy 132.442738 -291.14692) (xy 132.438643 -291.096192) (xy 132.130546 -291.096192) (xy 132.130034 -291.121638)
			(xy 132.12187 -291.171872) (xy 132.105754 -291.220146) (xy 132.082103 -291.265209) (xy 132.05153 -291.305895)
			(xy 132.014826 -291.34115) (xy 131.972942 -291.37006) (xy 131.926963 -291.391877) (xy 131.878079 -291.406037)
			(xy 131.827558 -291.412171) (xy 131.776706 -291.410122) (xy 131.726842 -291.399942) (xy 131.679256 -291.381895)
			(xy 131.635182 -291.356449) (xy 131.59576 -291.324262) (xy 131.562012 -291.286168) (xy 131.534811 -291.243154)
			(xy 131.514863 -291.196334) (xy 131.502684 -291.14692) (xy 131.498589 -291.096192) (xy 131.180078 -291.096192)
			(xy 131.179583 -291.120799) (xy 131.171688 -291.169376) (xy 131.156104 -291.216057) (xy 131.133233 -291.259634)
			(xy 131.103668 -291.298978) (xy 131.068175 -291.33307) (xy 131.027672 -291.361026) (xy 130.98321 -291.382124)
			(xy 130.935939 -291.395816) (xy 130.887084 -291.401748) (xy 130.837909 -291.399767) (xy 130.78969 -291.389923)
			(xy 130.743674 -291.372471) (xy 130.701053 -291.347864) (xy 130.662932 -291.316739) (xy 130.630297 -291.279902)
			(xy 130.603994 -291.238306) (xy 130.584703 -291.19303) (xy 130.572926 -291.145246) (xy 130.568966 -291.096192)
			(xy 130.250438 -291.096192) (xy 130.249926 -291.121638) (xy 130.241762 -291.171872) (xy 130.225646 -291.220146)
			(xy 130.201995 -291.265209) (xy 130.171422 -291.305895) (xy 130.134718 -291.34115) (xy 130.092834 -291.37006)
			(xy 130.046855 -291.391877) (xy 129.997971 -291.406037) (xy 129.94745 -291.412171) (xy 129.896598 -291.410122)
			(xy 129.846734 -291.399942) (xy 129.799148 -291.381895) (xy 129.755074 -291.356449) (xy 129.715652 -291.324262)
			(xy 129.681904 -291.286168) (xy 129.654703 -291.243154) (xy 129.634755 -291.196334) (xy 129.622576 -291.14692)
			(xy 129.618481 -291.096192) (xy 129.29997 -291.096192) (xy 129.299475 -291.120799) (xy 129.29158 -291.169376)
			(xy 129.275996 -291.216057) (xy 129.253125 -291.259634) (xy 129.22356 -291.298978) (xy 129.188067 -291.33307)
			(xy 129.147564 -291.361026) (xy 129.103102 -291.382124) (xy 129.055831 -291.395816) (xy 129.006976 -291.401748)
			(xy 128.957801 -291.399767) (xy 128.909582 -291.389923) (xy 128.863566 -291.372471) (xy 128.820945 -291.347864)
			(xy 128.782824 -291.316739) (xy 128.750189 -291.279902) (xy 128.723886 -291.238306) (xy 128.704595 -291.19303)
			(xy 128.692818 -291.145246) (xy 128.688858 -291.096192) (xy 128.370584 -291.096192) (xy 128.370072 -291.121638)
			(xy 128.361908 -291.171872) (xy 128.345792 -291.220146) (xy 128.322141 -291.265209) (xy 128.291568 -291.305895)
			(xy 128.254864 -291.34115) (xy 128.21298 -291.37006) (xy 128.167001 -291.391877) (xy 128.118117 -291.406037)
			(xy 128.067596 -291.412171) (xy 128.016744 -291.410122) (xy 127.96688 -291.399942) (xy 127.919294 -291.381895)
			(xy 127.87522 -291.356449) (xy 127.835798 -291.324262) (xy 127.80205 -291.286168) (xy 127.774849 -291.243154)
			(xy 127.754901 -291.196334) (xy 127.742722 -291.14692) (xy 127.738627 -291.096192) (xy 127.543814 -291.096192)
			(xy 127.543814 -291.211762) (xy 127.548894 -291.226748) (xy 127.55372 -291.233606) (xy 127.579709 -291.269404)
			(xy 127.626656 -291.344391) (xy 127.667593 -291.422821) (xy 127.70227 -291.504213) (xy 127.730472 -291.588068)
			(xy 127.74168 -291.630862) (xy 127.744367 -291.638172) (xy 127.753421 -291.650835) (xy 127.75946 -291.655754)
			(xy 127.779251 -291.67017) (xy 127.814401 -291.704251) (xy 127.843666 -291.743501) (xy 127.866297 -291.786917)
			(xy 127.881714 -291.833386) (xy 127.889523 -291.881719) (xy 127.889523 -291.906198) (xy 128.208527 -291.906198)
			(xy 128.212622 -291.85547) (xy 128.224801 -291.806056) (xy 128.244749 -291.759236) (xy 128.27195 -291.716222)
			(xy 128.305698 -291.678128) (xy 128.34512 -291.645941) (xy 128.389194 -291.620495) (xy 128.43678 -291.602448)
			(xy 128.486644 -291.592268) (xy 128.537496 -291.590219) (xy 128.588017 -291.596353) (xy 128.636901 -291.610513)
			(xy 128.68288 -291.63233) (xy 128.724764 -291.66124) (xy 128.761468 -291.696495) (xy 128.792041 -291.737181)
			(xy 128.815692 -291.782244) (xy 128.831808 -291.830518) (xy 128.839972 -291.880752) (xy 128.840484 -291.906198)
			(xy 129.148581 -291.906198) (xy 129.152676 -291.85547) (xy 129.164855 -291.806056) (xy 129.184803 -291.759236)
			(xy 129.212004 -291.716222) (xy 129.245752 -291.678128) (xy 129.285174 -291.645941) (xy 129.329248 -291.620495)
			(xy 129.376834 -291.602448) (xy 129.426698 -291.592268) (xy 129.47755 -291.590219) (xy 129.528071 -291.596353)
			(xy 129.576955 -291.610513) (xy 129.622934 -291.63233) (xy 129.664818 -291.66124) (xy 129.701522 -291.696495)
			(xy 129.732095 -291.737181) (xy 129.755746 -291.782244) (xy 129.771862 -291.830518) (xy 129.780026 -291.880752)
			(xy 129.780538 -291.906198) (xy 130.099066 -291.906198) (xy 130.103026 -291.857144) (xy 130.114803 -291.80936)
			(xy 130.134094 -291.764084) (xy 130.160397 -291.722488) (xy 130.193032 -291.685651) (xy 130.231153 -291.654526)
			(xy 130.273774 -291.629919) (xy 130.31979 -291.612467) (xy 130.368009 -291.602623) (xy 130.417184 -291.600642)
			(xy 130.466039 -291.606574) (xy 130.51331 -291.620266) (xy 130.557772 -291.641364) (xy 130.598275 -291.66932)
			(xy 130.633768 -291.703412) (xy 130.663333 -291.742756) (xy 130.686204 -291.786333) (xy 130.701788 -291.833014)
			(xy 130.709683 -291.881591) (xy 130.710178 -291.906198) (xy 131.028435 -291.906198) (xy 131.03253 -291.85547)
			(xy 131.044709 -291.806056) (xy 131.064657 -291.759236) (xy 131.091858 -291.716222) (xy 131.125606 -291.678128)
			(xy 131.165028 -291.645941) (xy 131.209102 -291.620495) (xy 131.256688 -291.602448) (xy 131.306552 -291.592268)
			(xy 131.357404 -291.590219) (xy 131.407925 -291.596353) (xy 131.456809 -291.610513) (xy 131.502788 -291.63233)
			(xy 131.544672 -291.66124) (xy 131.581376 -291.696495) (xy 131.611949 -291.737181) (xy 131.6356 -291.782244)
			(xy 131.651716 -291.830518) (xy 131.65988 -291.880752) (xy 131.660392 -291.906198) (xy 131.97892 -291.906198)
			(xy 131.98288 -291.857144) (xy 131.994657 -291.80936) (xy 132.013948 -291.764084) (xy 132.040251 -291.722488)
			(xy 132.072886 -291.685651) (xy 132.111007 -291.654526) (xy 132.153628 -291.629919) (xy 132.199644 -291.612467)
			(xy 132.247863 -291.602623) (xy 132.297038 -291.600642) (xy 132.345893 -291.606574) (xy 132.393164 -291.620266)
			(xy 132.437626 -291.641364) (xy 132.478129 -291.66932) (xy 132.513622 -291.703412) (xy 132.543187 -291.742756)
			(xy 132.566058 -291.786333) (xy 132.581642 -291.833014) (xy 132.589537 -291.881591) (xy 132.590032 -291.906198)
			(xy 132.908543 -291.906198) (xy 132.912638 -291.85547) (xy 132.924817 -291.806056) (xy 132.944765 -291.759236)
			(xy 132.971966 -291.716222) (xy 133.005714 -291.678128) (xy 133.045136 -291.645941) (xy 133.08921 -291.620495)
			(xy 133.136796 -291.602448) (xy 133.18666 -291.592268) (xy 133.237512 -291.590219) (xy 133.288033 -291.596353)
			(xy 133.336917 -291.610513) (xy 133.382896 -291.63233) (xy 133.42478 -291.66124) (xy 133.461484 -291.696495)
			(xy 133.492057 -291.737181) (xy 133.515708 -291.782244) (xy 133.531824 -291.830518) (xy 133.539988 -291.880752)
			(xy 133.5405 -291.906198) (xy 133.859028 -291.906198) (xy 133.862988 -291.857144) (xy 133.874765 -291.80936)
			(xy 133.894056 -291.764084) (xy 133.920359 -291.722488) (xy 133.952994 -291.685651) (xy 133.991115 -291.654526)
			(xy 134.033736 -291.629919) (xy 134.079752 -291.612467) (xy 134.127971 -291.602623) (xy 134.177146 -291.600642)
			(xy 134.226001 -291.606574) (xy 134.273272 -291.620266) (xy 134.317734 -291.641364) (xy 134.358237 -291.66932)
			(xy 134.39373 -291.703412) (xy 134.423295 -291.742756) (xy 134.446166 -291.786333) (xy 134.46175 -291.833014)
			(xy 134.469645 -291.881591) (xy 134.47014 -291.906198) (xy 134.798828 -291.906198) (xy 134.802788 -291.857144)
			(xy 134.814565 -291.80936) (xy 134.833856 -291.764084) (xy 134.860159 -291.722488) (xy 134.892794 -291.685651)
			(xy 134.930915 -291.654526) (xy 134.973536 -291.629919) (xy 135.019552 -291.612467) (xy 135.067771 -291.602623)
			(xy 135.116946 -291.600642) (xy 135.165801 -291.606574) (xy 135.213072 -291.620266) (xy 135.257534 -291.641364)
			(xy 135.298037 -291.66932) (xy 135.33353 -291.703412) (xy 135.363095 -291.742756) (xy 135.385966 -291.786333)
			(xy 135.40155 -291.833014) (xy 135.409445 -291.881591) (xy 135.40994 -291.906198) (xy 135.738882 -291.906198)
			(xy 135.742842 -291.857144) (xy 135.754619 -291.80936) (xy 135.77391 -291.764084) (xy 135.800213 -291.722488)
			(xy 135.832848 -291.685651) (xy 135.870969 -291.654526) (xy 135.91359 -291.629919) (xy 135.959606 -291.612467)
			(xy 136.007825 -291.602623) (xy 136.057 -291.600642) (xy 136.105855 -291.606574) (xy 136.153126 -291.620266)
			(xy 136.197588 -291.641364) (xy 136.238091 -291.66932) (xy 136.273584 -291.703412) (xy 136.303149 -291.742756)
			(xy 136.32602 -291.786333) (xy 136.341604 -291.833014) (xy 136.349499 -291.881591) (xy 136.349994 -291.906198)
			(xy 136.678936 -291.906198) (xy 136.682896 -291.857144) (xy 136.694673 -291.80936) (xy 136.713964 -291.764084)
			(xy 136.740267 -291.722488) (xy 136.772902 -291.685651) (xy 136.811023 -291.654526) (xy 136.853644 -291.629919)
			(xy 136.89966 -291.612467) (xy 136.947879 -291.602623) (xy 136.997054 -291.600642) (xy 137.045909 -291.606574)
			(xy 137.09318 -291.620266) (xy 137.137642 -291.641364) (xy 137.178145 -291.66932) (xy 137.213638 -291.703412)
			(xy 137.243203 -291.742756) (xy 137.266074 -291.786333) (xy 137.281658 -291.833014) (xy 137.289553 -291.881591)
			(xy 137.290048 -291.906198) (xy 137.61899 -291.906198) (xy 137.62295 -291.857144) (xy 137.634727 -291.80936)
			(xy 137.654018 -291.764084) (xy 137.680321 -291.722488) (xy 137.712956 -291.685651) (xy 137.751077 -291.654526)
			(xy 137.793698 -291.629919) (xy 137.839714 -291.612467) (xy 137.887933 -291.602623) (xy 137.937108 -291.600642)
			(xy 137.985963 -291.606574) (xy 138.033234 -291.620266) (xy 138.077696 -291.641364) (xy 138.118199 -291.66932)
			(xy 138.153692 -291.703412) (xy 138.183257 -291.742756) (xy 138.206128 -291.786333) (xy 138.221712 -291.833014)
			(xy 138.229607 -291.881591) (xy 138.230102 -291.906198) (xy 138.559044 -291.906198) (xy 138.563004 -291.857144)
			(xy 138.574781 -291.80936) (xy 138.594072 -291.764084) (xy 138.620375 -291.722488) (xy 138.65301 -291.685651)
			(xy 138.691131 -291.654526) (xy 138.733752 -291.629919) (xy 138.779768 -291.612467) (xy 138.827987 -291.602623)
			(xy 138.877162 -291.600642) (xy 138.926017 -291.606574) (xy 138.973288 -291.620266) (xy 139.01775 -291.641364)
			(xy 139.058253 -291.66932) (xy 139.093746 -291.703412) (xy 139.123311 -291.742756) (xy 139.146182 -291.786333)
			(xy 139.161766 -291.833014) (xy 139.169661 -291.881591) (xy 139.170156 -291.906198) (xy 139.498844 -291.906198)
			(xy 139.502804 -291.857144) (xy 139.514581 -291.80936) (xy 139.533872 -291.764084) (xy 139.560175 -291.722488)
			(xy 139.59281 -291.685651) (xy 139.630931 -291.654526) (xy 139.673552 -291.629919) (xy 139.719568 -291.612467)
			(xy 139.767787 -291.602623) (xy 139.816962 -291.600642) (xy 139.865817 -291.606574) (xy 139.913088 -291.620266)
			(xy 139.95755 -291.641364) (xy 139.998053 -291.66932) (xy 140.033546 -291.703412) (xy 140.063111 -291.742756)
			(xy 140.085982 -291.786333) (xy 140.101566 -291.833014) (xy 140.109461 -291.881591) (xy 140.109956 -291.906198)
			(xy 140.109461 -291.930805) (xy 140.101566 -291.979382) (xy 140.085982 -292.026063) (xy 140.063111 -292.06964)
			(xy 140.033546 -292.108984) (xy 139.998053 -292.143076) (xy 139.95755 -292.171032) (xy 139.913088 -292.19213)
			(xy 139.865817 -292.205822) (xy 139.816962 -292.211754) (xy 139.767787 -292.209773) (xy 139.719568 -292.199929)
			(xy 139.673552 -292.182477) (xy 139.630931 -292.15787) (xy 139.59281 -292.126745) (xy 139.560175 -292.089908)
			(xy 139.533872 -292.048312) (xy 139.514581 -292.003036) (xy 139.502804 -291.955252) (xy 139.498844 -291.906198)
			(xy 139.170156 -291.906198) (xy 139.169661 -291.930805) (xy 139.161766 -291.979382) (xy 139.146182 -292.026063)
			(xy 139.123311 -292.06964) (xy 139.093746 -292.108984) (xy 139.058253 -292.143076) (xy 139.01775 -292.171032)
			(xy 138.973288 -292.19213) (xy 138.926017 -292.205822) (xy 138.877162 -292.211754) (xy 138.827987 -292.209773)
			(xy 138.779768 -292.199929) (xy 138.733752 -292.182477) (xy 138.691131 -292.15787) (xy 138.65301 -292.126745)
			(xy 138.620375 -292.089908) (xy 138.594072 -292.048312) (xy 138.574781 -292.003036) (xy 138.563004 -291.955252)
			(xy 138.559044 -291.906198) (xy 138.230102 -291.906198) (xy 138.229607 -291.930805) (xy 138.221712 -291.979382)
			(xy 138.206128 -292.026063) (xy 138.183257 -292.06964) (xy 138.153692 -292.108984) (xy 138.118199 -292.143076)
			(xy 138.077696 -292.171032) (xy 138.033234 -292.19213) (xy 137.985963 -292.205822) (xy 137.937108 -292.211754)
			(xy 137.887933 -292.209773) (xy 137.839714 -292.199929) (xy 137.793698 -292.182477) (xy 137.751077 -292.15787)
			(xy 137.712956 -292.126745) (xy 137.680321 -292.089908) (xy 137.654018 -292.048312) (xy 137.634727 -292.003036)
			(xy 137.62295 -291.955252) (xy 137.61899 -291.906198) (xy 137.290048 -291.906198) (xy 137.289553 -291.930805)
			(xy 137.281658 -291.979382) (xy 137.266074 -292.026063) (xy 137.243203 -292.06964) (xy 137.213638 -292.108984)
			(xy 137.178145 -292.143076) (xy 137.137642 -292.171032) (xy 137.09318 -292.19213) (xy 137.045909 -292.205822)
			(xy 136.997054 -292.211754) (xy 136.947879 -292.209773) (xy 136.89966 -292.199929) (xy 136.853644 -292.182477)
			(xy 136.811023 -292.15787) (xy 136.772902 -292.126745) (xy 136.740267 -292.089908) (xy 136.713964 -292.048312)
			(xy 136.694673 -292.003036) (xy 136.682896 -291.955252) (xy 136.678936 -291.906198) (xy 136.349994 -291.906198)
			(xy 136.349499 -291.930805) (xy 136.341604 -291.979382) (xy 136.32602 -292.026063) (xy 136.303149 -292.06964)
			(xy 136.273584 -292.108984) (xy 136.238091 -292.143076) (xy 136.197588 -292.171032) (xy 136.153126 -292.19213)
			(xy 136.105855 -292.205822) (xy 136.057 -292.211754) (xy 136.007825 -292.209773) (xy 135.959606 -292.199929)
			(xy 135.91359 -292.182477) (xy 135.870969 -292.15787) (xy 135.832848 -292.126745) (xy 135.800213 -292.089908)
			(xy 135.77391 -292.048312) (xy 135.754619 -292.003036) (xy 135.742842 -291.955252) (xy 135.738882 -291.906198)
			(xy 135.40994 -291.906198) (xy 135.409445 -291.930805) (xy 135.40155 -291.979382) (xy 135.385966 -292.026063)
			(xy 135.363095 -292.06964) (xy 135.33353 -292.108984) (xy 135.298037 -292.143076) (xy 135.257534 -292.171032)
			(xy 135.213072 -292.19213) (xy 135.165801 -292.205822) (xy 135.116946 -292.211754) (xy 135.067771 -292.209773)
			(xy 135.019552 -292.199929) (xy 134.973536 -292.182477) (xy 134.930915 -292.15787) (xy 134.892794 -292.126745)
			(xy 134.860159 -292.089908) (xy 134.833856 -292.048312) (xy 134.814565 -292.003036) (xy 134.802788 -291.955252)
			(xy 134.798828 -291.906198) (xy 134.47014 -291.906198) (xy 134.469645 -291.930805) (xy 134.46175 -291.979382)
			(xy 134.446166 -292.026063) (xy 134.423295 -292.06964) (xy 134.39373 -292.108984) (xy 134.358237 -292.143076)
			(xy 134.317734 -292.171032) (xy 134.273272 -292.19213) (xy 134.226001 -292.205822) (xy 134.177146 -292.211754)
			(xy 134.127971 -292.209773) (xy 134.079752 -292.199929) (xy 134.033736 -292.182477) (xy 133.991115 -292.15787)
			(xy 133.952994 -292.126745) (xy 133.920359 -292.089908) (xy 133.894056 -292.048312) (xy 133.874765 -292.003036)
			(xy 133.862988 -291.955252) (xy 133.859028 -291.906198) (xy 133.5405 -291.906198) (xy 133.539988 -291.931644)
			(xy 133.531824 -291.981878) (xy 133.515708 -292.030152) (xy 133.492057 -292.075215) (xy 133.461484 -292.115901)
			(xy 133.42478 -292.151156) (xy 133.382896 -292.180066) (xy 133.336917 -292.201883) (xy 133.288033 -292.216043)
			(xy 133.237512 -292.222177) (xy 133.18666 -292.220128) (xy 133.136796 -292.209948) (xy 133.08921 -292.191901)
			(xy 133.045136 -292.166455) (xy 133.005714 -292.134268) (xy 132.971966 -292.096174) (xy 132.944765 -292.05316)
			(xy 132.924817 -292.00634) (xy 132.912638 -291.956926) (xy 132.908543 -291.906198) (xy 132.590032 -291.906198)
			(xy 132.589537 -291.930805) (xy 132.581642 -291.979382) (xy 132.566058 -292.026063) (xy 132.543187 -292.06964)
			(xy 132.513622 -292.108984) (xy 132.478129 -292.143076) (xy 132.437626 -292.171032) (xy 132.393164 -292.19213)
			(xy 132.345893 -292.205822) (xy 132.297038 -292.211754) (xy 132.247863 -292.209773) (xy 132.199644 -292.199929)
			(xy 132.153628 -292.182477) (xy 132.111007 -292.15787) (xy 132.072886 -292.126745) (xy 132.040251 -292.089908)
			(xy 132.013948 -292.048312) (xy 131.994657 -292.003036) (xy 131.98288 -291.955252) (xy 131.97892 -291.906198)
			(xy 131.660392 -291.906198) (xy 131.65988 -291.931644) (xy 131.651716 -291.981878) (xy 131.6356 -292.030152)
			(xy 131.611949 -292.075215) (xy 131.581376 -292.115901) (xy 131.544672 -292.151156) (xy 131.502788 -292.180066)
			(xy 131.456809 -292.201883) (xy 131.407925 -292.216043) (xy 131.357404 -292.222177) (xy 131.306552 -292.220128)
			(xy 131.256688 -292.209948) (xy 131.209102 -292.191901) (xy 131.165028 -292.166455) (xy 131.125606 -292.134268)
			(xy 131.091858 -292.096174) (xy 131.064657 -292.05316) (xy 131.044709 -292.00634) (xy 131.03253 -291.956926)
			(xy 131.028435 -291.906198) (xy 130.710178 -291.906198) (xy 130.709683 -291.930805) (xy 130.701788 -291.979382)
			(xy 130.686204 -292.026063) (xy 130.663333 -292.06964) (xy 130.633768 -292.108984) (xy 130.598275 -292.143076)
			(xy 130.557772 -292.171032) (xy 130.51331 -292.19213) (xy 130.466039 -292.205822) (xy 130.417184 -292.211754)
			(xy 130.368009 -292.209773) (xy 130.31979 -292.199929) (xy 130.273774 -292.182477) (xy 130.231153 -292.15787)
			(xy 130.193032 -292.126745) (xy 130.160397 -292.089908) (xy 130.134094 -292.048312) (xy 130.114803 -292.003036)
			(xy 130.103026 -291.955252) (xy 130.099066 -291.906198) (xy 129.780538 -291.906198) (xy 129.780026 -291.931644)
			(xy 129.771862 -291.981878) (xy 129.755746 -292.030152) (xy 129.732095 -292.075215) (xy 129.701522 -292.115901)
			(xy 129.664818 -292.151156) (xy 129.622934 -292.180066) (xy 129.576955 -292.201883) (xy 129.528071 -292.216043)
			(xy 129.47755 -292.222177) (xy 129.426698 -292.220128) (xy 129.376834 -292.209948) (xy 129.329248 -292.191901)
			(xy 129.285174 -292.166455) (xy 129.245752 -292.134268) (xy 129.212004 -292.096174) (xy 129.184803 -292.05316)
			(xy 129.164855 -292.00634) (xy 129.152676 -291.956926) (xy 129.148581 -291.906198) (xy 128.840484 -291.906198)
			(xy 128.839972 -291.931644) (xy 128.831808 -291.981878) (xy 128.815692 -292.030152) (xy 128.792041 -292.075215)
			(xy 128.761468 -292.115901) (xy 128.724764 -292.151156) (xy 128.68288 -292.180066) (xy 128.636901 -292.201883)
			(xy 128.588017 -292.216043) (xy 128.537496 -292.222177) (xy 128.486644 -292.220128) (xy 128.43678 -292.209948)
			(xy 128.389194 -292.191901) (xy 128.34512 -292.166455) (xy 128.305698 -292.134268) (xy 128.27195 -292.096174)
			(xy 128.244749 -292.05316) (xy 128.224801 -292.00634) (xy 128.212622 -291.956926) (xy 128.208527 -291.906198)
			(xy 127.889523 -291.906198) (xy 127.889523 -291.930679) (xy 127.881715 -291.979012) (xy 127.866298 -292.025481)
			(xy 127.843668 -292.068897) (xy 127.814403 -292.108148) (xy 127.779253 -292.142229) (xy 127.75946 -292.156642)
			(xy 127.753401 -292.16154) (xy 127.744357 -292.174217) (xy 127.74168 -292.181534) (xy 127.73047 -292.224327)
			(xy 127.702247 -292.308174) (xy 127.667565 -292.389562) (xy 127.626635 -292.467994) (xy 127.579706 -292.54299)
			(xy 127.55372 -292.57879) (xy 127.548894 -292.585648) (xy 127.543814 -292.600634) (xy 127.543814 -292.716204)
			(xy 127.738627 -292.716204) (xy 127.742722 -292.665476) (xy 127.754901 -292.616062) (xy 127.774849 -292.569242)
			(xy 127.80205 -292.526228) (xy 127.835798 -292.488134) (xy 127.87522 -292.455947) (xy 127.919294 -292.430501)
			(xy 127.96688 -292.412454) (xy 128.016744 -292.402274) (xy 128.067596 -292.400225) (xy 128.118117 -292.406359)
			(xy 128.167001 -292.420519) (xy 128.21298 -292.442336) (xy 128.254864 -292.471246) (xy 128.291568 -292.506501)
			(xy 128.322141 -292.547187) (xy 128.345792 -292.59225) (xy 128.361908 -292.640524) (xy 128.370072 -292.690758)
			(xy 128.370584 -292.716204) (xy 128.688858 -292.716204) (xy 128.692818 -292.66715) (xy 128.704595 -292.619366)
			(xy 128.723886 -292.57409) (xy 128.750189 -292.532494) (xy 128.782824 -292.495657) (xy 128.820945 -292.464532)
			(xy 128.863566 -292.439925) (xy 128.909582 -292.422473) (xy 128.957801 -292.412629) (xy 129.006976 -292.410648)
			(xy 129.055831 -292.41658) (xy 129.103102 -292.430272) (xy 129.147564 -292.45137) (xy 129.188067 -292.479326)
			(xy 129.22356 -292.513418) (xy 129.253125 -292.552762) (xy 129.275996 -292.596339) (xy 129.29158 -292.64302)
			(xy 129.299475 -292.691597) (xy 129.29997 -292.716204) (xy 129.618481 -292.716204) (xy 129.622576 -292.665476)
			(xy 129.634755 -292.616062) (xy 129.654703 -292.569242) (xy 129.681904 -292.526228) (xy 129.715652 -292.488134)
			(xy 129.755074 -292.455947) (xy 129.799148 -292.430501) (xy 129.846734 -292.412454) (xy 129.896598 -292.402274)
			(xy 129.94745 -292.400225) (xy 129.997971 -292.406359) (xy 130.046855 -292.420519) (xy 130.092834 -292.442336)
			(xy 130.134718 -292.471246) (xy 130.171422 -292.506501) (xy 130.201995 -292.547187) (xy 130.225646 -292.59225)
			(xy 130.241762 -292.640524) (xy 130.249926 -292.690758) (xy 130.250438 -292.716204) (xy 130.568966 -292.716204)
			(xy 130.572926 -292.66715) (xy 130.584703 -292.619366) (xy 130.603994 -292.57409) (xy 130.630297 -292.532494)
			(xy 130.662932 -292.495657) (xy 130.701053 -292.464532) (xy 130.743674 -292.439925) (xy 130.78969 -292.422473)
			(xy 130.837909 -292.412629) (xy 130.887084 -292.410648) (xy 130.935939 -292.41658) (xy 130.98321 -292.430272)
			(xy 131.027672 -292.45137) (xy 131.068175 -292.479326) (xy 131.103668 -292.513418) (xy 131.133233 -292.552762)
			(xy 131.156104 -292.596339) (xy 131.171688 -292.64302) (xy 131.179583 -292.691597) (xy 131.180078 -292.716204)
			(xy 131.498589 -292.716204) (xy 131.502684 -292.665476) (xy 131.514863 -292.616062) (xy 131.534811 -292.569242)
			(xy 131.562012 -292.526228) (xy 131.59576 -292.488134) (xy 131.635182 -292.455947) (xy 131.679256 -292.430501)
			(xy 131.726842 -292.412454) (xy 131.776706 -292.402274) (xy 131.827558 -292.400225) (xy 131.878079 -292.406359)
			(xy 131.926963 -292.420519) (xy 131.972942 -292.442336) (xy 132.014826 -292.471246) (xy 132.05153 -292.506501)
			(xy 132.082103 -292.547187) (xy 132.105754 -292.59225) (xy 132.12187 -292.640524) (xy 132.130034 -292.690758)
			(xy 132.130546 -292.716204) (xy 132.438643 -292.716204) (xy 132.442738 -292.665476) (xy 132.454917 -292.616062)
			(xy 132.474865 -292.569242) (xy 132.502066 -292.526228) (xy 132.535814 -292.488134) (xy 132.575236 -292.455947)
			(xy 132.61931 -292.430501) (xy 132.666896 -292.412454) (xy 132.71676 -292.402274) (xy 132.767612 -292.400225)
			(xy 132.818133 -292.406359) (xy 132.867017 -292.420519) (xy 132.912996 -292.442336) (xy 132.95488 -292.471246)
			(xy 132.991584 -292.506501) (xy 133.022157 -292.547187) (xy 133.045808 -292.59225) (xy 133.061924 -292.640524)
			(xy 133.070088 -292.690758) (xy 133.0706 -292.716204) (xy 133.388874 -292.716204) (xy 133.392834 -292.66715)
			(xy 133.404611 -292.619366) (xy 133.423902 -292.57409) (xy 133.450205 -292.532494) (xy 133.48284 -292.495657)
			(xy 133.520961 -292.464532) (xy 133.563582 -292.439925) (xy 133.609598 -292.422473) (xy 133.657817 -292.412629)
			(xy 133.706992 -292.410648) (xy 133.755847 -292.41658) (xy 133.803118 -292.430272) (xy 133.84758 -292.45137)
			(xy 133.888083 -292.479326) (xy 133.923576 -292.513418) (xy 133.953141 -292.552762) (xy 133.976012 -292.596339)
			(xy 133.991596 -292.64302) (xy 133.999491 -292.691597) (xy 133.999986 -292.716204) (xy 134.328928 -292.716204)
			(xy 134.332888 -292.66715) (xy 134.344665 -292.619366) (xy 134.363956 -292.57409) (xy 134.390259 -292.532494)
			(xy 134.422894 -292.495657) (xy 134.461015 -292.464532) (xy 134.503636 -292.439925) (xy 134.549652 -292.422473)
			(xy 134.597871 -292.412629) (xy 134.647046 -292.410648) (xy 134.695901 -292.41658) (xy 134.743172 -292.430272)
			(xy 134.787634 -292.45137) (xy 134.828137 -292.479326) (xy 134.86363 -292.513418) (xy 134.893195 -292.552762)
			(xy 134.916066 -292.596339) (xy 134.93165 -292.64302) (xy 134.939545 -292.691597) (xy 134.94004 -292.716204)
			(xy 135.268982 -292.716204) (xy 135.272942 -292.66715) (xy 135.284719 -292.619366) (xy 135.30401 -292.57409)
			(xy 135.330313 -292.532494) (xy 135.362948 -292.495657) (xy 135.401069 -292.464532) (xy 135.44369 -292.439925)
			(xy 135.489706 -292.422473) (xy 135.537925 -292.412629) (xy 135.5871 -292.410648) (xy 135.635955 -292.41658)
			(xy 135.683226 -292.430272) (xy 135.727688 -292.45137) (xy 135.768191 -292.479326) (xy 135.803684 -292.513418)
			(xy 135.833249 -292.552762) (xy 135.85612 -292.596339) (xy 135.871704 -292.64302) (xy 135.879599 -292.691597)
			(xy 135.880094 -292.716204) (xy 136.209036 -292.716204) (xy 136.212996 -292.66715) (xy 136.224773 -292.619366)
			(xy 136.244064 -292.57409) (xy 136.270367 -292.532494) (xy 136.303002 -292.495657) (xy 136.341123 -292.464532)
			(xy 136.383744 -292.439925) (xy 136.42976 -292.422473) (xy 136.477979 -292.412629) (xy 136.527154 -292.410648)
			(xy 136.576009 -292.41658) (xy 136.62328 -292.430272) (xy 136.667742 -292.45137) (xy 136.708245 -292.479326)
			(xy 136.743738 -292.513418) (xy 136.773303 -292.552762) (xy 136.796174 -292.596339) (xy 136.811758 -292.64302)
			(xy 136.819653 -292.691597) (xy 136.820148 -292.716204) (xy 137.148836 -292.716204) (xy 137.152796 -292.66715)
			(xy 137.164573 -292.619366) (xy 137.183864 -292.57409) (xy 137.210167 -292.532494) (xy 137.242802 -292.495657)
			(xy 137.280923 -292.464532) (xy 137.323544 -292.439925) (xy 137.36956 -292.422473) (xy 137.417779 -292.412629)
			(xy 137.466954 -292.410648) (xy 137.515809 -292.41658) (xy 137.56308 -292.430272) (xy 137.607542 -292.45137)
			(xy 137.648045 -292.479326) (xy 137.683538 -292.513418) (xy 137.713103 -292.552762) (xy 137.735974 -292.596339)
			(xy 137.751558 -292.64302) (xy 137.759453 -292.691597) (xy 137.759948 -292.716204) (xy 138.08889 -292.716204)
			(xy 138.09285 -292.66715) (xy 138.104627 -292.619366) (xy 138.123918 -292.57409) (xy 138.150221 -292.532494)
			(xy 138.182856 -292.495657) (xy 138.220977 -292.464532) (xy 138.263598 -292.439925) (xy 138.309614 -292.422473)
			(xy 138.357833 -292.412629) (xy 138.407008 -292.410648) (xy 138.455863 -292.41658) (xy 138.503134 -292.430272)
			(xy 138.547596 -292.45137) (xy 138.588099 -292.479326) (xy 138.623592 -292.513418) (xy 138.653157 -292.552762)
			(xy 138.676028 -292.596339) (xy 138.691612 -292.64302) (xy 138.699507 -292.691597) (xy 138.700002 -292.716204)
			(xy 139.028944 -292.716204) (xy 139.032904 -292.66715) (xy 139.044681 -292.619366) (xy 139.063972 -292.57409)
			(xy 139.090275 -292.532494) (xy 139.12291 -292.495657) (xy 139.161031 -292.464532) (xy 139.203652 -292.439925)
			(xy 139.249668 -292.422473) (xy 139.297887 -292.412629) (xy 139.347062 -292.410648) (xy 139.395917 -292.41658)
			(xy 139.443188 -292.430272) (xy 139.48765 -292.45137) (xy 139.528153 -292.479326) (xy 139.563646 -292.513418)
			(xy 139.593211 -292.552762) (xy 139.616082 -292.596339) (xy 139.631666 -292.64302) (xy 139.639561 -292.691597)
			(xy 139.640056 -292.716204) (xy 139.639561 -292.740811) (xy 139.631666 -292.789388) (xy 139.616082 -292.836069)
			(xy 139.593211 -292.879646) (xy 139.563646 -292.91899) (xy 139.528153 -292.953082) (xy 139.48765 -292.981038)
			(xy 139.443188 -293.002136) (xy 139.395917 -293.015828) (xy 139.347062 -293.02176) (xy 139.297887 -293.019779)
			(xy 139.249668 -293.009935) (xy 139.203652 -292.992483) (xy 139.161031 -292.967876) (xy 139.12291 -292.936751)
			(xy 139.090275 -292.899914) (xy 139.063972 -292.858318) (xy 139.044681 -292.813042) (xy 139.032904 -292.765258)
			(xy 139.028944 -292.716204) (xy 138.700002 -292.716204) (xy 138.699507 -292.740811) (xy 138.691612 -292.789388)
			(xy 138.676028 -292.836069) (xy 138.653157 -292.879646) (xy 138.623592 -292.91899) (xy 138.588099 -292.953082)
			(xy 138.547596 -292.981038) (xy 138.503134 -293.002136) (xy 138.455863 -293.015828) (xy 138.407008 -293.02176)
			(xy 138.357833 -293.019779) (xy 138.309614 -293.009935) (xy 138.263598 -292.992483) (xy 138.220977 -292.967876)
			(xy 138.182856 -292.936751) (xy 138.150221 -292.899914) (xy 138.123918 -292.858318) (xy 138.104627 -292.813042)
			(xy 138.09285 -292.765258) (xy 138.08889 -292.716204) (xy 137.759948 -292.716204) (xy 137.759453 -292.740811)
			(xy 137.751558 -292.789388) (xy 137.735974 -292.836069) (xy 137.713103 -292.879646) (xy 137.683538 -292.91899)
			(xy 137.648045 -292.953082) (xy 137.607542 -292.981038) (xy 137.56308 -293.002136) (xy 137.515809 -293.015828)
			(xy 137.466954 -293.02176) (xy 137.417779 -293.019779) (xy 137.36956 -293.009935) (xy 137.323544 -292.992483)
			(xy 137.280923 -292.967876) (xy 137.242802 -292.936751) (xy 137.210167 -292.899914) (xy 137.183864 -292.858318)
			(xy 137.164573 -292.813042) (xy 137.152796 -292.765258) (xy 137.148836 -292.716204) (xy 136.820148 -292.716204)
			(xy 136.819653 -292.740811) (xy 136.811758 -292.789388) (xy 136.796174 -292.836069) (xy 136.773303 -292.879646)
			(xy 136.743738 -292.91899) (xy 136.708245 -292.953082) (xy 136.667742 -292.981038) (xy 136.62328 -293.002136)
			(xy 136.576009 -293.015828) (xy 136.527154 -293.02176) (xy 136.477979 -293.019779) (xy 136.42976 -293.009935)
			(xy 136.383744 -292.992483) (xy 136.341123 -292.967876) (xy 136.303002 -292.936751) (xy 136.270367 -292.899914)
			(xy 136.244064 -292.858318) (xy 136.224773 -292.813042) (xy 136.212996 -292.765258) (xy 136.209036 -292.716204)
			(xy 135.880094 -292.716204) (xy 135.879599 -292.740811) (xy 135.871704 -292.789388) (xy 135.85612 -292.836069)
			(xy 135.833249 -292.879646) (xy 135.803684 -292.91899) (xy 135.768191 -292.953082) (xy 135.727688 -292.981038)
			(xy 135.683226 -293.002136) (xy 135.635955 -293.015828) (xy 135.5871 -293.02176) (xy 135.537925 -293.019779)
			(xy 135.489706 -293.009935) (xy 135.44369 -292.992483) (xy 135.401069 -292.967876) (xy 135.362948 -292.936751)
			(xy 135.330313 -292.899914) (xy 135.30401 -292.858318) (xy 135.284719 -292.813042) (xy 135.272942 -292.765258)
			(xy 135.268982 -292.716204) (xy 134.94004 -292.716204) (xy 134.939545 -292.740811) (xy 134.93165 -292.789388)
			(xy 134.916066 -292.836069) (xy 134.893195 -292.879646) (xy 134.86363 -292.91899) (xy 134.828137 -292.953082)
			(xy 134.787634 -292.981038) (xy 134.743172 -293.002136) (xy 134.695901 -293.015828) (xy 134.647046 -293.02176)
			(xy 134.597871 -293.019779) (xy 134.549652 -293.009935) (xy 134.503636 -292.992483) (xy 134.461015 -292.967876)
			(xy 134.422894 -292.936751) (xy 134.390259 -292.899914) (xy 134.363956 -292.858318) (xy 134.344665 -292.813042)
			(xy 134.332888 -292.765258) (xy 134.328928 -292.716204) (xy 133.999986 -292.716204) (xy 133.999491 -292.740811)
			(xy 133.991596 -292.789388) (xy 133.976012 -292.836069) (xy 133.953141 -292.879646) (xy 133.923576 -292.91899)
			(xy 133.888083 -292.953082) (xy 133.84758 -292.981038) (xy 133.803118 -293.002136) (xy 133.755847 -293.015828)
			(xy 133.706992 -293.02176) (xy 133.657817 -293.019779) (xy 133.609598 -293.009935) (xy 133.563582 -292.992483)
			(xy 133.520961 -292.967876) (xy 133.48284 -292.936751) (xy 133.450205 -292.899914) (xy 133.423902 -292.858318)
			(xy 133.404611 -292.813042) (xy 133.392834 -292.765258) (xy 133.388874 -292.716204) (xy 133.0706 -292.716204)
			(xy 133.070088 -292.74165) (xy 133.061924 -292.791884) (xy 133.045808 -292.840158) (xy 133.022157 -292.885221)
			(xy 132.991584 -292.925907) (xy 132.95488 -292.961162) (xy 132.912996 -292.990072) (xy 132.867017 -293.011889)
			(xy 132.818133 -293.026049) (xy 132.767612 -293.032183) (xy 132.71676 -293.030134) (xy 132.666896 -293.019954)
			(xy 132.61931 -293.001907) (xy 132.575236 -292.976461) (xy 132.535814 -292.944274) (xy 132.502066 -292.90618)
			(xy 132.474865 -292.863166) (xy 132.454917 -292.816346) (xy 132.442738 -292.766932) (xy 132.438643 -292.716204)
			(xy 132.130546 -292.716204) (xy 132.130034 -292.74165) (xy 132.12187 -292.791884) (xy 132.105754 -292.840158)
			(xy 132.082103 -292.885221) (xy 132.05153 -292.925907) (xy 132.014826 -292.961162) (xy 131.972942 -292.990072)
			(xy 131.926963 -293.011889) (xy 131.878079 -293.026049) (xy 131.827558 -293.032183) (xy 131.776706 -293.030134)
			(xy 131.726842 -293.019954) (xy 131.679256 -293.001907) (xy 131.635182 -292.976461) (xy 131.59576 -292.944274)
			(xy 131.562012 -292.90618) (xy 131.534811 -292.863166) (xy 131.514863 -292.816346) (xy 131.502684 -292.766932)
			(xy 131.498589 -292.716204) (xy 131.180078 -292.716204) (xy 131.179583 -292.740811) (xy 131.171688 -292.789388)
			(xy 131.156104 -292.836069) (xy 131.133233 -292.879646) (xy 131.103668 -292.91899) (xy 131.068175 -292.953082)
			(xy 131.027672 -292.981038) (xy 130.98321 -293.002136) (xy 130.935939 -293.015828) (xy 130.887084 -293.02176)
			(xy 130.837909 -293.019779) (xy 130.78969 -293.009935) (xy 130.743674 -292.992483) (xy 130.701053 -292.967876)
			(xy 130.662932 -292.936751) (xy 130.630297 -292.899914) (xy 130.603994 -292.858318) (xy 130.584703 -292.813042)
			(xy 130.572926 -292.765258) (xy 130.568966 -292.716204) (xy 130.250438 -292.716204) (xy 130.249926 -292.74165)
			(xy 130.241762 -292.791884) (xy 130.225646 -292.840158) (xy 130.201995 -292.885221) (xy 130.171422 -292.925907)
			(xy 130.134718 -292.961162) (xy 130.092834 -292.990072) (xy 130.046855 -293.011889) (xy 129.997971 -293.026049)
			(xy 129.94745 -293.032183) (xy 129.896598 -293.030134) (xy 129.846734 -293.019954) (xy 129.799148 -293.001907)
			(xy 129.755074 -292.976461) (xy 129.715652 -292.944274) (xy 129.681904 -292.90618) (xy 129.654703 -292.863166)
			(xy 129.634755 -292.816346) (xy 129.622576 -292.766932) (xy 129.618481 -292.716204) (xy 129.29997 -292.716204)
			(xy 129.299475 -292.740811) (xy 129.29158 -292.789388) (xy 129.275996 -292.836069) (xy 129.253125 -292.879646)
			(xy 129.22356 -292.91899) (xy 129.188067 -292.953082) (xy 129.147564 -292.981038) (xy 129.103102 -293.002136)
			(xy 129.055831 -293.015828) (xy 129.006976 -293.02176) (xy 128.957801 -293.019779) (xy 128.909582 -293.009935)
			(xy 128.863566 -292.992483) (xy 128.820945 -292.967876) (xy 128.782824 -292.936751) (xy 128.750189 -292.899914)
			(xy 128.723886 -292.858318) (xy 128.704595 -292.813042) (xy 128.692818 -292.765258) (xy 128.688858 -292.716204)
			(xy 128.370584 -292.716204) (xy 128.370072 -292.74165) (xy 128.361908 -292.791884) (xy 128.345792 -292.840158)
			(xy 128.322141 -292.885221) (xy 128.291568 -292.925907) (xy 128.254864 -292.961162) (xy 128.21298 -292.990072)
			(xy 128.167001 -293.011889) (xy 128.118117 -293.026049) (xy 128.067596 -293.032183) (xy 128.016744 -293.030134)
			(xy 127.96688 -293.019954) (xy 127.919294 -293.001907) (xy 127.87522 -292.976461) (xy 127.835798 -292.944274)
			(xy 127.80205 -292.90618) (xy 127.774849 -292.863166) (xy 127.754901 -292.816346) (xy 127.742722 -292.766932)
			(xy 127.738627 -292.716204) (xy 127.543814 -292.716204) (xy 127.543814 -292.831774) (xy 127.548894 -292.84676)
			(xy 127.55372 -292.853618) (xy 127.579709 -292.889416) (xy 127.626655 -292.964404) (xy 127.667591 -293.042834)
			(xy 127.702267 -293.124226) (xy 127.730469 -293.208081) (xy 127.74168 -293.250874) (xy 127.744368 -293.258183)
			(xy 127.753424 -293.270844) (xy 127.75946 -293.275766) (xy 127.77925 -293.290182) (xy 127.814398 -293.324262)
			(xy 127.843662 -293.363512) (xy 127.866291 -293.406927) (xy 127.881706 -293.453395) (xy 127.889513 -293.501727)
			(xy 127.889512 -293.52621) (xy 128.208527 -293.52621) (xy 128.212622 -293.475482) (xy 128.224801 -293.426068)
			(xy 128.244749 -293.379248) (xy 128.27195 -293.336234) (xy 128.305698 -293.29814) (xy 128.34512 -293.265953)
			(xy 128.389194 -293.240507) (xy 128.43678 -293.22246) (xy 128.486644 -293.21228) (xy 128.537496 -293.210231)
			(xy 128.588017 -293.216365) (xy 128.636901 -293.230525) (xy 128.68288 -293.252342) (xy 128.724764 -293.281252)
			(xy 128.761468 -293.316507) (xy 128.792041 -293.357193) (xy 128.815692 -293.402256) (xy 128.831808 -293.45053)
			(xy 128.839972 -293.500764) (xy 128.840484 -293.52621) (xy 129.159012 -293.52621) (xy 129.162972 -293.477156)
			(xy 129.174749 -293.429372) (xy 129.19404 -293.384096) (xy 129.220343 -293.3425) (xy 129.252978 -293.305663)
			(xy 129.291099 -293.274538) (xy 129.33372 -293.249931) (xy 129.379736 -293.232479) (xy 129.427955 -293.222635)
			(xy 129.47713 -293.220654) (xy 129.525985 -293.226586) (xy 129.573256 -293.240278) (xy 129.617718 -293.261376)
			(xy 129.658221 -293.289332) (xy 129.693714 -293.323424) (xy 129.723279 -293.362768) (xy 129.74615 -293.406345)
			(xy 129.761734 -293.453026) (xy 129.769629 -293.501603) (xy 129.770124 -293.52621) (xy 130.099066 -293.52621)
			(xy 130.103026 -293.477156) (xy 130.114803 -293.429372) (xy 130.134094 -293.384096) (xy 130.160397 -293.3425)
			(xy 130.193032 -293.305663) (xy 130.231153 -293.274538) (xy 130.273774 -293.249931) (xy 130.31979 -293.232479)
			(xy 130.368009 -293.222635) (xy 130.417184 -293.220654) (xy 130.466039 -293.226586) (xy 130.51331 -293.240278)
			(xy 130.557772 -293.261376) (xy 130.598275 -293.289332) (xy 130.633768 -293.323424) (xy 130.663333 -293.362768)
			(xy 130.686204 -293.406345) (xy 130.701788 -293.453026) (xy 130.709683 -293.501603) (xy 130.710178 -293.52621)
			(xy 131.038866 -293.52621) (xy 131.042826 -293.477156) (xy 131.054603 -293.429372) (xy 131.073894 -293.384096)
			(xy 131.100197 -293.3425) (xy 131.132832 -293.305663) (xy 131.170953 -293.274538) (xy 131.213574 -293.249931)
			(xy 131.25959 -293.232479) (xy 131.307809 -293.222635) (xy 131.356984 -293.220654) (xy 131.405839 -293.226586)
			(xy 131.45311 -293.240278) (xy 131.497572 -293.261376) (xy 131.538075 -293.289332) (xy 131.573568 -293.323424)
			(xy 131.603133 -293.362768) (xy 131.626004 -293.406345) (xy 131.641588 -293.453026) (xy 131.649483 -293.501603)
			(xy 131.649978 -293.52621) (xy 131.97892 -293.52621) (xy 131.98288 -293.477156) (xy 131.994657 -293.429372)
			(xy 132.013948 -293.384096) (xy 132.040251 -293.3425) (xy 132.072886 -293.305663) (xy 132.111007 -293.274538)
			(xy 132.153628 -293.249931) (xy 132.199644 -293.232479) (xy 132.247863 -293.222635) (xy 132.297038 -293.220654)
			(xy 132.345893 -293.226586) (xy 132.393164 -293.240278) (xy 132.437626 -293.261376) (xy 132.478129 -293.289332)
			(xy 132.513622 -293.323424) (xy 132.543187 -293.362768) (xy 132.566058 -293.406345) (xy 132.581642 -293.453026)
			(xy 132.589537 -293.501603) (xy 132.590032 -293.52621) (xy 132.908543 -293.52621) (xy 132.912638 -293.475482)
			(xy 132.924817 -293.426068) (xy 132.944765 -293.379248) (xy 132.971966 -293.336234) (xy 133.005714 -293.29814)
			(xy 133.045136 -293.265953) (xy 133.08921 -293.240507) (xy 133.136796 -293.22246) (xy 133.18666 -293.21228)
			(xy 133.237512 -293.210231) (xy 133.288033 -293.216365) (xy 133.336917 -293.230525) (xy 133.382896 -293.252342)
			(xy 133.42478 -293.281252) (xy 133.461484 -293.316507) (xy 133.492057 -293.357193) (xy 133.515708 -293.402256)
			(xy 133.531824 -293.45053) (xy 133.539988 -293.500764) (xy 133.5405 -293.52621) (xy 133.859028 -293.52621)
			(xy 133.862988 -293.477156) (xy 133.874765 -293.429372) (xy 133.894056 -293.384096) (xy 133.920359 -293.3425)
			(xy 133.952994 -293.305663) (xy 133.991115 -293.274538) (xy 134.033736 -293.249931) (xy 134.079752 -293.232479)
			(xy 134.127971 -293.222635) (xy 134.177146 -293.220654) (xy 134.226001 -293.226586) (xy 134.273272 -293.240278)
			(xy 134.317734 -293.261376) (xy 134.358237 -293.289332) (xy 134.39373 -293.323424) (xy 134.423295 -293.362768)
			(xy 134.446166 -293.406345) (xy 134.46175 -293.453026) (xy 134.469645 -293.501603) (xy 134.47014 -293.52621)
			(xy 134.798828 -293.52621) (xy 134.802788 -293.477156) (xy 134.814565 -293.429372) (xy 134.833856 -293.384096)
			(xy 134.860159 -293.3425) (xy 134.892794 -293.305663) (xy 134.930915 -293.274538) (xy 134.973536 -293.249931)
			(xy 135.019552 -293.232479) (xy 135.067771 -293.222635) (xy 135.116946 -293.220654) (xy 135.165801 -293.226586)
			(xy 135.213072 -293.240278) (xy 135.257534 -293.261376) (xy 135.298037 -293.289332) (xy 135.33353 -293.323424)
			(xy 135.363095 -293.362768) (xy 135.385966 -293.406345) (xy 135.40155 -293.453026) (xy 135.409445 -293.501603)
			(xy 135.40994 -293.52621) (xy 135.738882 -293.52621) (xy 135.742842 -293.477156) (xy 135.754619 -293.429372)
			(xy 135.77391 -293.384096) (xy 135.800213 -293.3425) (xy 135.832848 -293.305663) (xy 135.870969 -293.274538)
			(xy 135.91359 -293.249931) (xy 135.959606 -293.232479) (xy 136.007825 -293.222635) (xy 136.057 -293.220654)
			(xy 136.105855 -293.226586) (xy 136.153126 -293.240278) (xy 136.197588 -293.261376) (xy 136.238091 -293.289332)
			(xy 136.273584 -293.323424) (xy 136.303149 -293.362768) (xy 136.32602 -293.406345) (xy 136.341604 -293.453026)
			(xy 136.349499 -293.501603) (xy 136.349994 -293.52621) (xy 136.678936 -293.52621) (xy 136.682896 -293.477156)
			(xy 136.694673 -293.429372) (xy 136.713964 -293.384096) (xy 136.740267 -293.3425) (xy 136.772902 -293.305663)
			(xy 136.811023 -293.274538) (xy 136.853644 -293.249931) (xy 136.89966 -293.232479) (xy 136.947879 -293.222635)
			(xy 136.997054 -293.220654) (xy 137.045909 -293.226586) (xy 137.09318 -293.240278) (xy 137.137642 -293.261376)
			(xy 137.178145 -293.289332) (xy 137.213638 -293.323424) (xy 137.243203 -293.362768) (xy 137.266074 -293.406345)
			(xy 137.281658 -293.453026) (xy 137.289553 -293.501603) (xy 137.290048 -293.52621) (xy 137.61899 -293.52621)
			(xy 137.62295 -293.477156) (xy 137.634727 -293.429372) (xy 137.654018 -293.384096) (xy 137.680321 -293.3425)
			(xy 137.712956 -293.305663) (xy 137.751077 -293.274538) (xy 137.793698 -293.249931) (xy 137.839714 -293.232479)
			(xy 137.887933 -293.222635) (xy 137.937108 -293.220654) (xy 137.985963 -293.226586) (xy 138.033234 -293.240278)
			(xy 138.077696 -293.261376) (xy 138.118199 -293.289332) (xy 138.153692 -293.323424) (xy 138.183257 -293.362768)
			(xy 138.206128 -293.406345) (xy 138.221712 -293.453026) (xy 138.229607 -293.501603) (xy 138.230102 -293.52621)
			(xy 138.559044 -293.52621) (xy 138.563004 -293.477156) (xy 138.574781 -293.429372) (xy 138.594072 -293.384096)
			(xy 138.620375 -293.3425) (xy 138.65301 -293.305663) (xy 138.691131 -293.274538) (xy 138.733752 -293.249931)
			(xy 138.779768 -293.232479) (xy 138.827987 -293.222635) (xy 138.877162 -293.220654) (xy 138.926017 -293.226586)
			(xy 138.973288 -293.240278) (xy 139.01775 -293.261376) (xy 139.058253 -293.289332) (xy 139.093746 -293.323424)
			(xy 139.123311 -293.362768) (xy 139.146182 -293.406345) (xy 139.161766 -293.453026) (xy 139.169661 -293.501603)
			(xy 139.170156 -293.52621) (xy 139.498844 -293.52621) (xy 139.502804 -293.477156) (xy 139.514581 -293.429372)
			(xy 139.533872 -293.384096) (xy 139.560175 -293.3425) (xy 139.59281 -293.305663) (xy 139.630931 -293.274538)
			(xy 139.673552 -293.249931) (xy 139.719568 -293.232479) (xy 139.767787 -293.222635) (xy 139.816962 -293.220654)
			(xy 139.865817 -293.226586) (xy 139.913088 -293.240278) (xy 139.95755 -293.261376) (xy 139.998053 -293.289332)
			(xy 140.033546 -293.323424) (xy 140.063111 -293.362768) (xy 140.085982 -293.406345) (xy 140.101566 -293.453026)
			(xy 140.109461 -293.501603) (xy 140.109956 -293.52621) (xy 140.109461 -293.550817) (xy 140.101566 -293.599394)
			(xy 140.085982 -293.646075) (xy 140.063111 -293.689652) (xy 140.033546 -293.728996) (xy 139.998053 -293.763088)
			(xy 139.95755 -293.791044) (xy 139.913088 -293.812142) (xy 139.865817 -293.825834) (xy 139.816962 -293.831766)
			(xy 139.767787 -293.829785) (xy 139.719568 -293.819941) (xy 139.673552 -293.802489) (xy 139.630931 -293.777882)
			(xy 139.59281 -293.746757) (xy 139.560175 -293.70992) (xy 139.533872 -293.668324) (xy 139.514581 -293.623048)
			(xy 139.502804 -293.575264) (xy 139.498844 -293.52621) (xy 139.170156 -293.52621) (xy 139.169661 -293.550817)
			(xy 139.161766 -293.599394) (xy 139.146182 -293.646075) (xy 139.123311 -293.689652) (xy 139.093746 -293.728996)
			(xy 139.058253 -293.763088) (xy 139.01775 -293.791044) (xy 138.973288 -293.812142) (xy 138.926017 -293.825834)
			(xy 138.877162 -293.831766) (xy 138.827987 -293.829785) (xy 138.779768 -293.819941) (xy 138.733752 -293.802489)
			(xy 138.691131 -293.777882) (xy 138.65301 -293.746757) (xy 138.620375 -293.70992) (xy 138.594072 -293.668324)
			(xy 138.574781 -293.623048) (xy 138.563004 -293.575264) (xy 138.559044 -293.52621) (xy 138.230102 -293.52621)
			(xy 138.229607 -293.550817) (xy 138.221712 -293.599394) (xy 138.206128 -293.646075) (xy 138.183257 -293.689652)
			(xy 138.153692 -293.728996) (xy 138.118199 -293.763088) (xy 138.077696 -293.791044) (xy 138.033234 -293.812142)
			(xy 137.985963 -293.825834) (xy 137.937108 -293.831766) (xy 137.887933 -293.829785) (xy 137.839714 -293.819941)
			(xy 137.793698 -293.802489) (xy 137.751077 -293.777882) (xy 137.712956 -293.746757) (xy 137.680321 -293.70992)
			(xy 137.654018 -293.668324) (xy 137.634727 -293.623048) (xy 137.62295 -293.575264) (xy 137.61899 -293.52621)
			(xy 137.290048 -293.52621) (xy 137.289553 -293.550817) (xy 137.281658 -293.599394) (xy 137.266074 -293.646075)
			(xy 137.243203 -293.689652) (xy 137.213638 -293.728996) (xy 137.178145 -293.763088) (xy 137.137642 -293.791044)
			(xy 137.09318 -293.812142) (xy 137.045909 -293.825834) (xy 136.997054 -293.831766) (xy 136.947879 -293.829785)
			(xy 136.89966 -293.819941) (xy 136.853644 -293.802489) (xy 136.811023 -293.777882) (xy 136.772902 -293.746757)
			(xy 136.740267 -293.70992) (xy 136.713964 -293.668324) (xy 136.694673 -293.623048) (xy 136.682896 -293.575264)
			(xy 136.678936 -293.52621) (xy 136.349994 -293.52621) (xy 136.349499 -293.550817) (xy 136.341604 -293.599394)
			(xy 136.32602 -293.646075) (xy 136.303149 -293.689652) (xy 136.273584 -293.728996) (xy 136.238091 -293.763088)
			(xy 136.197588 -293.791044) (xy 136.153126 -293.812142) (xy 136.105855 -293.825834) (xy 136.057 -293.831766)
			(xy 136.007825 -293.829785) (xy 135.959606 -293.819941) (xy 135.91359 -293.802489) (xy 135.870969 -293.777882)
			(xy 135.832848 -293.746757) (xy 135.800213 -293.70992) (xy 135.77391 -293.668324) (xy 135.754619 -293.623048)
			(xy 135.742842 -293.575264) (xy 135.738882 -293.52621) (xy 135.40994 -293.52621) (xy 135.409445 -293.550817)
			(xy 135.40155 -293.599394) (xy 135.385966 -293.646075) (xy 135.363095 -293.689652) (xy 135.33353 -293.728996)
			(xy 135.298037 -293.763088) (xy 135.257534 -293.791044) (xy 135.213072 -293.812142) (xy 135.165801 -293.825834)
			(xy 135.116946 -293.831766) (xy 135.067771 -293.829785) (xy 135.019552 -293.819941) (xy 134.973536 -293.802489)
			(xy 134.930915 -293.777882) (xy 134.892794 -293.746757) (xy 134.860159 -293.70992) (xy 134.833856 -293.668324)
			(xy 134.814565 -293.623048) (xy 134.802788 -293.575264) (xy 134.798828 -293.52621) (xy 134.47014 -293.52621)
			(xy 134.469645 -293.550817) (xy 134.46175 -293.599394) (xy 134.446166 -293.646075) (xy 134.423295 -293.689652)
			(xy 134.39373 -293.728996) (xy 134.358237 -293.763088) (xy 134.317734 -293.791044) (xy 134.273272 -293.812142)
			(xy 134.226001 -293.825834) (xy 134.177146 -293.831766) (xy 134.127971 -293.829785) (xy 134.079752 -293.819941)
			(xy 134.033736 -293.802489) (xy 133.991115 -293.777882) (xy 133.952994 -293.746757) (xy 133.920359 -293.70992)
			(xy 133.894056 -293.668324) (xy 133.874765 -293.623048) (xy 133.862988 -293.575264) (xy 133.859028 -293.52621)
			(xy 133.5405 -293.52621) (xy 133.539988 -293.551656) (xy 133.531824 -293.60189) (xy 133.515708 -293.650164)
			(xy 133.492057 -293.695227) (xy 133.461484 -293.735913) (xy 133.42478 -293.771168) (xy 133.382896 -293.800078)
			(xy 133.336917 -293.821895) (xy 133.288033 -293.836055) (xy 133.237512 -293.842189) (xy 133.18666 -293.84014)
			(xy 133.136796 -293.82996) (xy 133.08921 -293.811913) (xy 133.045136 -293.786467) (xy 133.005714 -293.75428)
			(xy 132.971966 -293.716186) (xy 132.944765 -293.673172) (xy 132.924817 -293.626352) (xy 132.912638 -293.576938)
			(xy 132.908543 -293.52621) (xy 132.590032 -293.52621) (xy 132.589537 -293.550817) (xy 132.581642 -293.599394)
			(xy 132.566058 -293.646075) (xy 132.543187 -293.689652) (xy 132.513622 -293.728996) (xy 132.478129 -293.763088)
			(xy 132.437626 -293.791044) (xy 132.393164 -293.812142) (xy 132.345893 -293.825834) (xy 132.297038 -293.831766)
			(xy 132.247863 -293.829785) (xy 132.199644 -293.819941) (xy 132.153628 -293.802489) (xy 132.111007 -293.777882)
			(xy 132.072886 -293.746757) (xy 132.040251 -293.70992) (xy 132.013948 -293.668324) (xy 131.994657 -293.623048)
			(xy 131.98288 -293.575264) (xy 131.97892 -293.52621) (xy 131.649978 -293.52621) (xy 131.649483 -293.550817)
			(xy 131.641588 -293.599394) (xy 131.626004 -293.646075) (xy 131.603133 -293.689652) (xy 131.573568 -293.728996)
			(xy 131.538075 -293.763088) (xy 131.497572 -293.791044) (xy 131.45311 -293.812142) (xy 131.405839 -293.825834)
			(xy 131.356984 -293.831766) (xy 131.307809 -293.829785) (xy 131.25959 -293.819941) (xy 131.213574 -293.802489)
			(xy 131.170953 -293.777882) (xy 131.132832 -293.746757) (xy 131.100197 -293.70992) (xy 131.073894 -293.668324)
			(xy 131.054603 -293.623048) (xy 131.042826 -293.575264) (xy 131.038866 -293.52621) (xy 130.710178 -293.52621)
			(xy 130.709683 -293.550817) (xy 130.701788 -293.599394) (xy 130.686204 -293.646075) (xy 130.663333 -293.689652)
			(xy 130.633768 -293.728996) (xy 130.598275 -293.763088) (xy 130.557772 -293.791044) (xy 130.51331 -293.812142)
			(xy 130.466039 -293.825834) (xy 130.417184 -293.831766) (xy 130.368009 -293.829785) (xy 130.31979 -293.819941)
			(xy 130.273774 -293.802489) (xy 130.231153 -293.777882) (xy 130.193032 -293.746757) (xy 130.160397 -293.70992)
			(xy 130.134094 -293.668324) (xy 130.114803 -293.623048) (xy 130.103026 -293.575264) (xy 130.099066 -293.52621)
			(xy 129.770124 -293.52621) (xy 129.769629 -293.550817) (xy 129.761734 -293.599394) (xy 129.74615 -293.646075)
			(xy 129.723279 -293.689652) (xy 129.693714 -293.728996) (xy 129.658221 -293.763088) (xy 129.617718 -293.791044)
			(xy 129.573256 -293.812142) (xy 129.525985 -293.825834) (xy 129.47713 -293.831766) (xy 129.427955 -293.829785)
			(xy 129.379736 -293.819941) (xy 129.33372 -293.802489) (xy 129.291099 -293.777882) (xy 129.252978 -293.746757)
			(xy 129.220343 -293.70992) (xy 129.19404 -293.668324) (xy 129.174749 -293.623048) (xy 129.162972 -293.575264)
			(xy 129.159012 -293.52621) (xy 128.840484 -293.52621) (xy 128.839972 -293.551656) (xy 128.831808 -293.60189)
			(xy 128.815692 -293.650164) (xy 128.792041 -293.695227) (xy 128.761468 -293.735913) (xy 128.724764 -293.771168)
			(xy 128.68288 -293.800078) (xy 128.636901 -293.821895) (xy 128.588017 -293.836055) (xy 128.537496 -293.842189)
			(xy 128.486644 -293.84014) (xy 128.43678 -293.82996) (xy 128.389194 -293.811913) (xy 128.34512 -293.786467)
			(xy 128.305698 -293.75428) (xy 128.27195 -293.716186) (xy 128.244749 -293.673172) (xy 128.224801 -293.626352)
			(xy 128.212622 -293.576938) (xy 128.208527 -293.52621) (xy 127.889512 -293.52621) (xy 127.889512 -293.550685)
			(xy 127.881703 -293.599016) (xy 127.866286 -293.645484) (xy 127.843656 -293.688897) (xy 127.814391 -293.728146)
			(xy 127.779241 -293.762225) (xy 127.75946 -293.776654) (xy 127.753402 -293.781553) (xy 127.744362 -293.79423)
			(xy 127.74168 -293.801546) (xy 127.730469 -293.844339) (xy 127.702246 -293.928185) (xy 127.667563 -294.009573)
			(xy 127.626632 -294.088004) (xy 127.579703 -294.163) (xy 127.55372 -294.198802) (xy 127.548894 -294.20566)
			(xy 127.543814 -294.220646) (xy 127.543814 -294.336216) (xy 127.749058 -294.336216) (xy 127.753018 -294.287162)
			(xy 127.764795 -294.239378) (xy 127.784086 -294.194102) (xy 127.810389 -294.152506) (xy 127.843024 -294.115669)
			(xy 127.881145 -294.084544) (xy 127.923766 -294.059937) (xy 127.969782 -294.042485) (xy 128.018001 -294.032641)
			(xy 128.067176 -294.03066) (xy 128.116031 -294.036592) (xy 128.163302 -294.050284) (xy 128.207764 -294.071382)
			(xy 128.248267 -294.099338) (xy 128.28376 -294.13343) (xy 128.313325 -294.172774) (xy 128.336196 -294.216351)
			(xy 128.35178 -294.263032) (xy 128.359675 -294.311609) (xy 128.36017 -294.336216) (xy 128.688858 -294.336216)
			(xy 128.692818 -294.287162) (xy 128.704595 -294.239378) (xy 128.723886 -294.194102) (xy 128.750189 -294.152506)
			(xy 128.782824 -294.115669) (xy 128.820945 -294.084544) (xy 128.863566 -294.059937) (xy 128.909582 -294.042485)
			(xy 128.957801 -294.032641) (xy 129.006976 -294.03066) (xy 129.055831 -294.036592) (xy 129.103102 -294.050284)
			(xy 129.147564 -294.071382) (xy 129.188067 -294.099338) (xy 129.22356 -294.13343) (xy 129.253125 -294.172774)
			(xy 129.275996 -294.216351) (xy 129.29158 -294.263032) (xy 129.299475 -294.311609) (xy 129.29997 -294.336216)
			(xy 129.628912 -294.336216) (xy 129.632872 -294.287162) (xy 129.644649 -294.239378) (xy 129.66394 -294.194102)
			(xy 129.690243 -294.152506) (xy 129.722878 -294.115669) (xy 129.760999 -294.084544) (xy 129.80362 -294.059937)
			(xy 129.849636 -294.042485) (xy 129.897855 -294.032641) (xy 129.94703 -294.03066) (xy 129.995885 -294.036592)
			(xy 130.043156 -294.050284) (xy 130.087618 -294.071382) (xy 130.128121 -294.099338) (xy 130.163614 -294.13343)
			(xy 130.193179 -294.172774) (xy 130.21605 -294.216351) (xy 130.231634 -294.263032) (xy 130.239529 -294.311609)
			(xy 130.240024 -294.336216) (xy 130.568966 -294.336216) (xy 130.572926 -294.287162) (xy 130.584703 -294.239378)
			(xy 130.603994 -294.194102) (xy 130.630297 -294.152506) (xy 130.662932 -294.115669) (xy 130.701053 -294.084544)
			(xy 130.743674 -294.059937) (xy 130.78969 -294.042485) (xy 130.837909 -294.032641) (xy 130.887084 -294.03066)
			(xy 130.935939 -294.036592) (xy 130.98321 -294.050284) (xy 131.027672 -294.071382) (xy 131.068175 -294.099338)
			(xy 131.103668 -294.13343) (xy 131.133233 -294.172774) (xy 131.156104 -294.216351) (xy 131.171688 -294.263032)
			(xy 131.179583 -294.311609) (xy 131.180078 -294.336216) (xy 131.50902 -294.336216) (xy 131.51298 -294.287162)
			(xy 131.524757 -294.239378) (xy 131.544048 -294.194102) (xy 131.570351 -294.152506) (xy 131.602986 -294.115669)
			(xy 131.641107 -294.084544) (xy 131.683728 -294.059937) (xy 131.729744 -294.042485) (xy 131.777963 -294.032641)
			(xy 131.827138 -294.03066) (xy 131.875993 -294.036592) (xy 131.923264 -294.050284) (xy 131.967726 -294.071382)
			(xy 132.008229 -294.099338) (xy 132.043722 -294.13343) (xy 132.073287 -294.172774) (xy 132.096158 -294.216351)
			(xy 132.111742 -294.263032) (xy 132.119637 -294.311609) (xy 132.120132 -294.336216) (xy 132.449074 -294.336216)
			(xy 132.453034 -294.287162) (xy 132.464811 -294.239378) (xy 132.484102 -294.194102) (xy 132.510405 -294.152506)
			(xy 132.54304 -294.115669) (xy 132.581161 -294.084544) (xy 132.623782 -294.059937) (xy 132.669798 -294.042485)
			(xy 132.718017 -294.032641) (xy 132.767192 -294.03066) (xy 132.816047 -294.036592) (xy 132.863318 -294.050284)
			(xy 132.90778 -294.071382) (xy 132.948283 -294.099338) (xy 132.983776 -294.13343) (xy 133.013341 -294.172774)
			(xy 133.036212 -294.216351) (xy 133.051796 -294.263032) (xy 133.059691 -294.311609) (xy 133.060186 -294.336216)
			(xy 133.388874 -294.336216) (xy 133.392834 -294.287162) (xy 133.404611 -294.239378) (xy 133.423902 -294.194102)
			(xy 133.450205 -294.152506) (xy 133.48284 -294.115669) (xy 133.520961 -294.084544) (xy 133.563582 -294.059937)
			(xy 133.609598 -294.042485) (xy 133.657817 -294.032641) (xy 133.706992 -294.03066) (xy 133.755847 -294.036592)
			(xy 133.803118 -294.050284) (xy 133.84758 -294.071382) (xy 133.888083 -294.099338) (xy 133.923576 -294.13343)
			(xy 133.953141 -294.172774) (xy 133.976012 -294.216351) (xy 133.991596 -294.263032) (xy 133.999491 -294.311609)
			(xy 133.999986 -294.336216) (xy 134.328928 -294.336216) (xy 134.332888 -294.287162) (xy 134.344665 -294.239378)
			(xy 134.363956 -294.194102) (xy 134.390259 -294.152506) (xy 134.422894 -294.115669) (xy 134.461015 -294.084544)
			(xy 134.503636 -294.059937) (xy 134.549652 -294.042485) (xy 134.597871 -294.032641) (xy 134.647046 -294.03066)
			(xy 134.695901 -294.036592) (xy 134.743172 -294.050284) (xy 134.787634 -294.071382) (xy 134.828137 -294.099338)
			(xy 134.86363 -294.13343) (xy 134.893195 -294.172774) (xy 134.916066 -294.216351) (xy 134.93165 -294.263032)
			(xy 134.939545 -294.311609) (xy 134.94004 -294.336216) (xy 135.268982 -294.336216) (xy 135.272942 -294.287162)
			(xy 135.284719 -294.239378) (xy 135.30401 -294.194102) (xy 135.330313 -294.152506) (xy 135.362948 -294.115669)
			(xy 135.401069 -294.084544) (xy 135.44369 -294.059937) (xy 135.489706 -294.042485) (xy 135.537925 -294.032641)
			(xy 135.5871 -294.03066) (xy 135.635955 -294.036592) (xy 135.683226 -294.050284) (xy 135.727688 -294.071382)
			(xy 135.768191 -294.099338) (xy 135.803684 -294.13343) (xy 135.833249 -294.172774) (xy 135.85612 -294.216351)
			(xy 135.871704 -294.263032) (xy 135.879599 -294.311609) (xy 135.880094 -294.336216) (xy 136.209036 -294.336216)
			(xy 136.212996 -294.287162) (xy 136.224773 -294.239378) (xy 136.244064 -294.194102) (xy 136.270367 -294.152506)
			(xy 136.303002 -294.115669) (xy 136.341123 -294.084544) (xy 136.383744 -294.059937) (xy 136.42976 -294.042485)
			(xy 136.477979 -294.032641) (xy 136.527154 -294.03066) (xy 136.576009 -294.036592) (xy 136.62328 -294.050284)
			(xy 136.667742 -294.071382) (xy 136.708245 -294.099338) (xy 136.743738 -294.13343) (xy 136.773303 -294.172774)
			(xy 136.796174 -294.216351) (xy 136.811758 -294.263032) (xy 136.819653 -294.311609) (xy 136.820148 -294.336216)
			(xy 137.148836 -294.336216) (xy 137.152796 -294.287162) (xy 137.164573 -294.239378) (xy 137.183864 -294.194102)
			(xy 137.210167 -294.152506) (xy 137.242802 -294.115669) (xy 137.280923 -294.084544) (xy 137.323544 -294.059937)
			(xy 137.36956 -294.042485) (xy 137.417779 -294.032641) (xy 137.466954 -294.03066) (xy 137.515809 -294.036592)
			(xy 137.56308 -294.050284) (xy 137.607542 -294.071382) (xy 137.648045 -294.099338) (xy 137.683538 -294.13343)
			(xy 137.713103 -294.172774) (xy 137.735974 -294.216351) (xy 137.751558 -294.263032) (xy 137.759453 -294.311609)
			(xy 137.759948 -294.336216) (xy 138.08889 -294.336216) (xy 138.09285 -294.287162) (xy 138.104627 -294.239378)
			(xy 138.123918 -294.194102) (xy 138.150221 -294.152506) (xy 138.182856 -294.115669) (xy 138.220977 -294.084544)
			(xy 138.263598 -294.059937) (xy 138.309614 -294.042485) (xy 138.357833 -294.032641) (xy 138.407008 -294.03066)
			(xy 138.455863 -294.036592) (xy 138.503134 -294.050284) (xy 138.547596 -294.071382) (xy 138.588099 -294.099338)
			(xy 138.623592 -294.13343) (xy 138.653157 -294.172774) (xy 138.676028 -294.216351) (xy 138.691612 -294.263032)
			(xy 138.699507 -294.311609) (xy 138.700002 -294.336216) (xy 139.028944 -294.336216) (xy 139.032904 -294.287162)
			(xy 139.044681 -294.239378) (xy 139.063972 -294.194102) (xy 139.090275 -294.152506) (xy 139.12291 -294.115669)
			(xy 139.161031 -294.084544) (xy 139.203652 -294.059937) (xy 139.249668 -294.042485) (xy 139.297887 -294.032641)
			(xy 139.347062 -294.03066) (xy 139.395917 -294.036592) (xy 139.443188 -294.050284) (xy 139.48765 -294.071382)
			(xy 139.528153 -294.099338) (xy 139.563646 -294.13343) (xy 139.593211 -294.172774) (xy 139.616082 -294.216351)
			(xy 139.631666 -294.263032) (xy 139.639561 -294.311609) (xy 139.640056 -294.336216) (xy 139.968998 -294.336216)
			(xy 139.972958 -294.287162) (xy 139.984735 -294.239378) (xy 140.004026 -294.194102) (xy 140.030329 -294.152506)
			(xy 140.062964 -294.115669) (xy 140.101085 -294.084544) (xy 140.143706 -294.059937) (xy 140.189722 -294.042485)
			(xy 140.237941 -294.032641) (xy 140.287116 -294.03066) (xy 140.335971 -294.036592) (xy 140.383242 -294.050284)
			(xy 140.427704 -294.071382) (xy 140.468207 -294.099338) (xy 140.5037 -294.13343) (xy 140.533265 -294.172774)
			(xy 140.556136 -294.216351) (xy 140.57172 -294.263032) (xy 140.579615 -294.311609) (xy 140.58011 -294.336216)
			(xy 140.579615 -294.360823) (xy 140.57172 -294.4094) (xy 140.556136 -294.456081) (xy 140.533265 -294.499658)
			(xy 140.5037 -294.539002) (xy 140.468207 -294.573094) (xy 140.427704 -294.60105) (xy 140.383242 -294.622148)
			(xy 140.335971 -294.63584) (xy 140.287116 -294.641772) (xy 140.237941 -294.639791) (xy 140.189722 -294.629947)
			(xy 140.143706 -294.612495) (xy 140.101085 -294.587888) (xy 140.062964 -294.556763) (xy 140.030329 -294.519926)
			(xy 140.004026 -294.47833) (xy 139.984735 -294.433054) (xy 139.972958 -294.38527) (xy 139.968998 -294.336216)
			(xy 139.640056 -294.336216) (xy 139.639561 -294.360823) (xy 139.631666 -294.4094) (xy 139.616082 -294.456081)
			(xy 139.593211 -294.499658) (xy 139.563646 -294.539002) (xy 139.528153 -294.573094) (xy 139.48765 -294.60105)
			(xy 139.443188 -294.622148) (xy 139.395917 -294.63584) (xy 139.347062 -294.641772) (xy 139.297887 -294.639791)
			(xy 139.249668 -294.629947) (xy 139.203652 -294.612495) (xy 139.161031 -294.587888) (xy 139.12291 -294.556763)
			(xy 139.090275 -294.519926) (xy 139.063972 -294.47833) (xy 139.044681 -294.433054) (xy 139.032904 -294.38527)
			(xy 139.028944 -294.336216) (xy 138.700002 -294.336216) (xy 138.699507 -294.360823) (xy 138.691612 -294.4094)
			(xy 138.676028 -294.456081) (xy 138.653157 -294.499658) (xy 138.623592 -294.539002) (xy 138.588099 -294.573094)
			(xy 138.547596 -294.60105) (xy 138.503134 -294.622148) (xy 138.455863 -294.63584) (xy 138.407008 -294.641772)
			(xy 138.357833 -294.639791) (xy 138.309614 -294.629947) (xy 138.263598 -294.612495) (xy 138.220977 -294.587888)
			(xy 138.182856 -294.556763) (xy 138.150221 -294.519926) (xy 138.123918 -294.47833) (xy 138.104627 -294.433054)
			(xy 138.09285 -294.38527) (xy 138.08889 -294.336216) (xy 137.759948 -294.336216) (xy 137.759453 -294.360823)
			(xy 137.751558 -294.4094) (xy 137.735974 -294.456081) (xy 137.713103 -294.499658) (xy 137.683538 -294.539002)
			(xy 137.648045 -294.573094) (xy 137.607542 -294.60105) (xy 137.56308 -294.622148) (xy 137.515809 -294.63584)
			(xy 137.466954 -294.641772) (xy 137.417779 -294.639791) (xy 137.36956 -294.629947) (xy 137.323544 -294.612495)
			(xy 137.280923 -294.587888) (xy 137.242802 -294.556763) (xy 137.210167 -294.519926) (xy 137.183864 -294.47833)
			(xy 137.164573 -294.433054) (xy 137.152796 -294.38527) (xy 137.148836 -294.336216) (xy 136.820148 -294.336216)
			(xy 136.819653 -294.360823) (xy 136.811758 -294.4094) (xy 136.796174 -294.456081) (xy 136.773303 -294.499658)
			(xy 136.743738 -294.539002) (xy 136.708245 -294.573094) (xy 136.667742 -294.60105) (xy 136.62328 -294.622148)
			(xy 136.576009 -294.63584) (xy 136.527154 -294.641772) (xy 136.477979 -294.639791) (xy 136.42976 -294.629947)
			(xy 136.383744 -294.612495) (xy 136.341123 -294.587888) (xy 136.303002 -294.556763) (xy 136.270367 -294.519926)
			(xy 136.244064 -294.47833) (xy 136.224773 -294.433054) (xy 136.212996 -294.38527) (xy 136.209036 -294.336216)
			(xy 135.880094 -294.336216) (xy 135.879599 -294.360823) (xy 135.871704 -294.4094) (xy 135.85612 -294.456081)
			(xy 135.833249 -294.499658) (xy 135.803684 -294.539002) (xy 135.768191 -294.573094) (xy 135.727688 -294.60105)
			(xy 135.683226 -294.622148) (xy 135.635955 -294.63584) (xy 135.5871 -294.641772) (xy 135.537925 -294.639791)
			(xy 135.489706 -294.629947) (xy 135.44369 -294.612495) (xy 135.401069 -294.587888) (xy 135.362948 -294.556763)
			(xy 135.330313 -294.519926) (xy 135.30401 -294.47833) (xy 135.284719 -294.433054) (xy 135.272942 -294.38527)
			(xy 135.268982 -294.336216) (xy 134.94004 -294.336216) (xy 134.939545 -294.360823) (xy 134.93165 -294.4094)
			(xy 134.916066 -294.456081) (xy 134.893195 -294.499658) (xy 134.86363 -294.539002) (xy 134.828137 -294.573094)
			(xy 134.787634 -294.60105) (xy 134.743172 -294.622148) (xy 134.695901 -294.63584) (xy 134.647046 -294.641772)
			(xy 134.597871 -294.639791) (xy 134.549652 -294.629947) (xy 134.503636 -294.612495) (xy 134.461015 -294.587888)
			(xy 134.422894 -294.556763) (xy 134.390259 -294.519926) (xy 134.363956 -294.47833) (xy 134.344665 -294.433054)
			(xy 134.332888 -294.38527) (xy 134.328928 -294.336216) (xy 133.999986 -294.336216) (xy 133.999491 -294.360823)
			(xy 133.991596 -294.4094) (xy 133.976012 -294.456081) (xy 133.953141 -294.499658) (xy 133.923576 -294.539002)
			(xy 133.888083 -294.573094) (xy 133.84758 -294.60105) (xy 133.803118 -294.622148) (xy 133.755847 -294.63584)
			(xy 133.706992 -294.641772) (xy 133.657817 -294.639791) (xy 133.609598 -294.629947) (xy 133.563582 -294.612495)
			(xy 133.520961 -294.587888) (xy 133.48284 -294.556763) (xy 133.450205 -294.519926) (xy 133.423902 -294.47833)
			(xy 133.404611 -294.433054) (xy 133.392834 -294.38527) (xy 133.388874 -294.336216) (xy 133.060186 -294.336216)
			(xy 133.059691 -294.360823) (xy 133.051796 -294.4094) (xy 133.036212 -294.456081) (xy 133.013341 -294.499658)
			(xy 132.983776 -294.539002) (xy 132.948283 -294.573094) (xy 132.90778 -294.60105) (xy 132.863318 -294.622148)
			(xy 132.816047 -294.63584) (xy 132.767192 -294.641772) (xy 132.718017 -294.639791) (xy 132.669798 -294.629947)
			(xy 132.623782 -294.612495) (xy 132.581161 -294.587888) (xy 132.54304 -294.556763) (xy 132.510405 -294.519926)
			(xy 132.484102 -294.47833) (xy 132.464811 -294.433054) (xy 132.453034 -294.38527) (xy 132.449074 -294.336216)
			(xy 132.120132 -294.336216) (xy 132.119637 -294.360823) (xy 132.111742 -294.4094) (xy 132.096158 -294.456081)
			(xy 132.073287 -294.499658) (xy 132.043722 -294.539002) (xy 132.008229 -294.573094) (xy 131.967726 -294.60105)
			(xy 131.923264 -294.622148) (xy 131.875993 -294.63584) (xy 131.827138 -294.641772) (xy 131.777963 -294.639791)
			(xy 131.729744 -294.629947) (xy 131.683728 -294.612495) (xy 131.641107 -294.587888) (xy 131.602986 -294.556763)
			(xy 131.570351 -294.519926) (xy 131.544048 -294.47833) (xy 131.524757 -294.433054) (xy 131.51298 -294.38527)
			(xy 131.50902 -294.336216) (xy 131.180078 -294.336216) (xy 131.179583 -294.360823) (xy 131.171688 -294.4094)
			(xy 131.156104 -294.456081) (xy 131.133233 -294.499658) (xy 131.103668 -294.539002) (xy 131.068175 -294.573094)
			(xy 131.027672 -294.60105) (xy 130.98321 -294.622148) (xy 130.935939 -294.63584) (xy 130.887084 -294.641772)
			(xy 130.837909 -294.639791) (xy 130.78969 -294.629947) (xy 130.743674 -294.612495) (xy 130.701053 -294.587888)
			(xy 130.662932 -294.556763) (xy 130.630297 -294.519926) (xy 130.603994 -294.47833) (xy 130.584703 -294.433054)
			(xy 130.572926 -294.38527) (xy 130.568966 -294.336216) (xy 130.240024 -294.336216) (xy 130.239529 -294.360823)
			(xy 130.231634 -294.4094) (xy 130.21605 -294.456081) (xy 130.193179 -294.499658) (xy 130.163614 -294.539002)
			(xy 130.128121 -294.573094) (xy 130.087618 -294.60105) (xy 130.043156 -294.622148) (xy 129.995885 -294.63584)
			(xy 129.94703 -294.641772) (xy 129.897855 -294.639791) (xy 129.849636 -294.629947) (xy 129.80362 -294.612495)
			(xy 129.760999 -294.587888) (xy 129.722878 -294.556763) (xy 129.690243 -294.519926) (xy 129.66394 -294.47833)
			(xy 129.644649 -294.433054) (xy 129.632872 -294.38527) (xy 129.628912 -294.336216) (xy 129.29997 -294.336216)
			(xy 129.299475 -294.360823) (xy 129.29158 -294.4094) (xy 129.275996 -294.456081) (xy 129.253125 -294.499658)
			(xy 129.22356 -294.539002) (xy 129.188067 -294.573094) (xy 129.147564 -294.60105) (xy 129.103102 -294.622148)
			(xy 129.055831 -294.63584) (xy 129.006976 -294.641772) (xy 128.957801 -294.639791) (xy 128.909582 -294.629947)
			(xy 128.863566 -294.612495) (xy 128.820945 -294.587888) (xy 128.782824 -294.556763) (xy 128.750189 -294.519926)
			(xy 128.723886 -294.47833) (xy 128.704595 -294.433054) (xy 128.692818 -294.38527) (xy 128.688858 -294.336216)
			(xy 128.36017 -294.336216) (xy 128.359675 -294.360823) (xy 128.35178 -294.4094) (xy 128.336196 -294.456081)
			(xy 128.313325 -294.499658) (xy 128.28376 -294.539002) (xy 128.248267 -294.573094) (xy 128.207764 -294.60105)
			(xy 128.163302 -294.622148) (xy 128.116031 -294.63584) (xy 128.067176 -294.641772) (xy 128.018001 -294.639791)
			(xy 127.969782 -294.629947) (xy 127.923766 -294.612495) (xy 127.881145 -294.587888) (xy 127.843024 -294.556763)
			(xy 127.810389 -294.519926) (xy 127.784086 -294.47833) (xy 127.764795 -294.433054) (xy 127.753018 -294.38527)
			(xy 127.749058 -294.336216) (xy 127.543814 -294.336216) (xy 127.543814 -294.451786) (xy 127.548894 -294.466772)
			(xy 127.55372 -294.47363) (xy 127.579493 -294.509154) (xy 127.626078 -294.583545) (xy 127.666754 -294.661324)
			(xy 127.701276 -294.742023) (xy 127.729437 -294.825156) (xy 127.740664 -294.867584) (xy 127.743245 -294.876295)
			(xy 127.753522 -294.891264) (xy 127.76073 -294.896794) (xy 127.781025 -294.911759) (xy 127.816882 -294.947208)
			(xy 127.846438 -294.988059) (xy 127.868892 -295.033204) (xy 127.883638 -295.081422) (xy 127.887476 -295.106344)
			(xy 127.888492 -295.114472) (xy 127.899668 -295.13784) (xy 127.906526 -295.14419) (xy 127.908635 -295.146222)
			(xy 128.218958 -295.146222) (xy 128.222918 -295.097168) (xy 128.234695 -295.049384) (xy 128.253986 -295.004108)
			(xy 128.280289 -294.962512) (xy 128.312924 -294.925675) (xy 128.351045 -294.89455) (xy 128.393666 -294.869943)
			(xy 128.439682 -294.852491) (xy 128.487901 -294.842647) (xy 128.537076 -294.840666) (xy 128.585931 -294.846598)
			(xy 128.633202 -294.86029) (xy 128.677664 -294.881388) (xy 128.718167 -294.909344) (xy 128.75366 -294.943436)
			(xy 128.783225 -294.98278) (xy 128.806096 -295.026357) (xy 128.82168 -295.073038) (xy 128.829575 -295.121615)
			(xy 128.83007 -295.146222) (xy 129.159012 -295.146222) (xy 129.162972 -295.097168) (xy 129.174749 -295.049384)
			(xy 129.19404 -295.004108) (xy 129.220343 -294.962512) (xy 129.252978 -294.925675) (xy 129.291099 -294.89455)
			(xy 129.33372 -294.869943) (xy 129.379736 -294.852491) (xy 129.427955 -294.842647) (xy 129.47713 -294.840666)
			(xy 129.525985 -294.846598) (xy 129.573256 -294.86029) (xy 129.617718 -294.881388) (xy 129.658221 -294.909344)
			(xy 129.693714 -294.943436) (xy 129.723279 -294.98278) (xy 129.74615 -295.026357) (xy 129.761734 -295.073038)
			(xy 129.769629 -295.121615) (xy 129.770124 -295.146222) (xy 130.099066 -295.146222) (xy 130.103026 -295.097168)
			(xy 130.114803 -295.049384) (xy 130.134094 -295.004108) (xy 130.160397 -294.962512) (xy 130.193032 -294.925675)
			(xy 130.231153 -294.89455) (xy 130.273774 -294.869943) (xy 130.31979 -294.852491) (xy 130.368009 -294.842647)
			(xy 130.417184 -294.840666) (xy 130.466039 -294.846598) (xy 130.51331 -294.86029) (xy 130.557772 -294.881388)
			(xy 130.598275 -294.909344) (xy 130.633768 -294.943436) (xy 130.663333 -294.98278) (xy 130.686204 -295.026357)
			(xy 130.701788 -295.073038) (xy 130.709683 -295.121615) (xy 130.710178 -295.146222) (xy 131.038866 -295.146222)
			(xy 131.042826 -295.097168) (xy 131.054603 -295.049384) (xy 131.073894 -295.004108) (xy 131.100197 -294.962512)
			(xy 131.132832 -294.925675) (xy 131.170953 -294.89455) (xy 131.213574 -294.869943) (xy 131.25959 -294.852491)
			(xy 131.307809 -294.842647) (xy 131.356984 -294.840666) (xy 131.405839 -294.846598) (xy 131.45311 -294.86029)
			(xy 131.497572 -294.881388) (xy 131.538075 -294.909344) (xy 131.573568 -294.943436) (xy 131.603133 -294.98278)
			(xy 131.626004 -295.026357) (xy 131.641588 -295.073038) (xy 131.649483 -295.121615) (xy 131.649978 -295.146222)
			(xy 131.97892 -295.146222) (xy 131.98288 -295.097168) (xy 131.994657 -295.049384) (xy 132.013948 -295.004108)
			(xy 132.040251 -294.962512) (xy 132.072886 -294.925675) (xy 132.111007 -294.89455) (xy 132.153628 -294.869943)
			(xy 132.199644 -294.852491) (xy 132.247863 -294.842647) (xy 132.297038 -294.840666) (xy 132.345893 -294.846598)
			(xy 132.393164 -294.86029) (xy 132.437626 -294.881388) (xy 132.478129 -294.909344) (xy 132.513622 -294.943436)
			(xy 132.543187 -294.98278) (xy 132.566058 -295.026357) (xy 132.581642 -295.073038) (xy 132.589537 -295.121615)
			(xy 132.590032 -295.146222) (xy 132.918974 -295.146222) (xy 132.922934 -295.097168) (xy 132.934711 -295.049384)
			(xy 132.954002 -295.004108) (xy 132.980305 -294.962512) (xy 133.01294 -294.925675) (xy 133.051061 -294.89455)
			(xy 133.093682 -294.869943) (xy 133.139698 -294.852491) (xy 133.187917 -294.842647) (xy 133.237092 -294.840666)
			(xy 133.285947 -294.846598) (xy 133.333218 -294.86029) (xy 133.37768 -294.881388) (xy 133.418183 -294.909344)
			(xy 133.453676 -294.943436) (xy 133.483241 -294.98278) (xy 133.506112 -295.026357) (xy 133.521696 -295.073038)
			(xy 133.529591 -295.121615) (xy 133.530086 -295.146222) (xy 133.859028 -295.146222) (xy 133.862988 -295.097168)
			(xy 133.874765 -295.049384) (xy 133.894056 -295.004108) (xy 133.920359 -294.962512) (xy 133.952994 -294.925675)
			(xy 133.991115 -294.89455) (xy 134.033736 -294.869943) (xy 134.079752 -294.852491) (xy 134.127971 -294.842647)
			(xy 134.177146 -294.840666) (xy 134.226001 -294.846598) (xy 134.273272 -294.86029) (xy 134.317734 -294.881388)
			(xy 134.358237 -294.909344) (xy 134.39373 -294.943436) (xy 134.423295 -294.98278) (xy 134.446166 -295.026357)
			(xy 134.46175 -295.073038) (xy 134.469645 -295.121615) (xy 134.47014 -295.146222) (xy 134.798828 -295.146222)
			(xy 134.802788 -295.097168) (xy 134.814565 -295.049384) (xy 134.833856 -295.004108) (xy 134.860159 -294.962512)
			(xy 134.892794 -294.925675) (xy 134.930915 -294.89455) (xy 134.973536 -294.869943) (xy 135.019552 -294.852491)
			(xy 135.067771 -294.842647) (xy 135.116946 -294.840666) (xy 135.165801 -294.846598) (xy 135.213072 -294.86029)
			(xy 135.257534 -294.881388) (xy 135.298037 -294.909344) (xy 135.33353 -294.943436) (xy 135.363095 -294.98278)
			(xy 135.385966 -295.026357) (xy 135.40155 -295.073038) (xy 135.409445 -295.121615) (xy 135.40994 -295.146222)
			(xy 135.738882 -295.146222) (xy 135.742842 -295.097168) (xy 135.754619 -295.049384) (xy 135.77391 -295.004108)
			(xy 135.800213 -294.962512) (xy 135.832848 -294.925675) (xy 135.870969 -294.89455) (xy 135.91359 -294.869943)
			(xy 135.959606 -294.852491) (xy 136.007825 -294.842647) (xy 136.057 -294.840666) (xy 136.105855 -294.846598)
			(xy 136.153126 -294.86029) (xy 136.197588 -294.881388) (xy 136.238091 -294.909344) (xy 136.273584 -294.943436)
			(xy 136.303149 -294.98278) (xy 136.32602 -295.026357) (xy 136.341604 -295.073038) (xy 136.349499 -295.121615)
			(xy 136.349994 -295.146222) (xy 136.678936 -295.146222) (xy 136.682896 -295.097168) (xy 136.694673 -295.049384)
			(xy 136.713964 -295.004108) (xy 136.740267 -294.962512) (xy 136.772902 -294.925675) (xy 136.811023 -294.89455)
			(xy 136.853644 -294.869943) (xy 136.89966 -294.852491) (xy 136.947879 -294.842647) (xy 136.997054 -294.840666)
			(xy 137.045909 -294.846598) (xy 137.09318 -294.86029) (xy 137.137642 -294.881388) (xy 137.178145 -294.909344)
			(xy 137.213638 -294.943436) (xy 137.243203 -294.98278) (xy 137.266074 -295.026357) (xy 137.281658 -295.073038)
			(xy 137.289553 -295.121615) (xy 137.290048 -295.146222) (xy 137.61899 -295.146222) (xy 137.62295 -295.097168)
			(xy 137.634727 -295.049384) (xy 137.654018 -295.004108) (xy 137.680321 -294.962512) (xy 137.712956 -294.925675)
			(xy 137.751077 -294.89455) (xy 137.793698 -294.869943) (xy 137.839714 -294.852491) (xy 137.887933 -294.842647)
			(xy 137.937108 -294.840666) (xy 137.985963 -294.846598) (xy 138.033234 -294.86029) (xy 138.077696 -294.881388)
			(xy 138.118199 -294.909344) (xy 138.153692 -294.943436) (xy 138.183257 -294.98278) (xy 138.206128 -295.026357)
			(xy 138.221712 -295.073038) (xy 138.229607 -295.121615) (xy 138.230102 -295.146222) (xy 138.559044 -295.146222)
			(xy 138.563004 -295.097168) (xy 138.574781 -295.049384) (xy 138.594072 -295.004108) (xy 138.620375 -294.962512)
			(xy 138.65301 -294.925675) (xy 138.691131 -294.89455) (xy 138.733752 -294.869943) (xy 138.779768 -294.852491)
			(xy 138.827987 -294.842647) (xy 138.877162 -294.840666) (xy 138.926017 -294.846598) (xy 138.973288 -294.86029)
			(xy 139.01775 -294.881388) (xy 139.058253 -294.909344) (xy 139.093746 -294.943436) (xy 139.123311 -294.98278)
			(xy 139.146182 -295.026357) (xy 139.161766 -295.073038) (xy 139.169661 -295.121615) (xy 139.170156 -295.146222)
			(xy 140.438898 -295.146222) (xy 140.442858 -295.097168) (xy 140.454635 -295.049384) (xy 140.473926 -295.004108)
			(xy 140.500229 -294.962512) (xy 140.532864 -294.925675) (xy 140.570985 -294.89455) (xy 140.613606 -294.869943)
			(xy 140.659622 -294.852491) (xy 140.707841 -294.842647) (xy 140.757016 -294.840666) (xy 140.805871 -294.846598)
			(xy 140.853142 -294.86029) (xy 140.897604 -294.881388) (xy 140.938107 -294.909344) (xy 140.9736 -294.943436)
			(xy 141.003165 -294.98278) (xy 141.026036 -295.026357) (xy 141.04162 -295.073038) (xy 141.049515 -295.121615)
			(xy 141.05001 -295.146222) (xy 141.378952 -295.146222) (xy 141.382912 -295.097168) (xy 141.394689 -295.049384)
			(xy 141.41398 -295.004108) (xy 141.440283 -294.962512) (xy 141.472918 -294.925675) (xy 141.511039 -294.89455)
			(xy 141.55366 -294.869943) (xy 141.599676 -294.852491) (xy 141.647895 -294.842647) (xy 141.69707 -294.840666)
			(xy 141.745925 -294.846598) (xy 141.793196 -294.86029) (xy 141.837658 -294.881388) (xy 141.878161 -294.909344)
			(xy 141.913654 -294.943436) (xy 141.943219 -294.98278) (xy 141.96609 -295.026357) (xy 141.981674 -295.073038)
			(xy 141.989569 -295.121615) (xy 141.990064 -295.146222) (xy 143.258806 -295.146222) (xy 143.262766 -295.097168)
			(xy 143.274543 -295.049384) (xy 143.293834 -295.004108) (xy 143.320137 -294.962512) (xy 143.352772 -294.925675)
			(xy 143.390893 -294.89455) (xy 143.433514 -294.869943) (xy 143.47953 -294.852491) (xy 143.527749 -294.842647)
			(xy 143.576924 -294.840666) (xy 143.625779 -294.846598) (xy 143.67305 -294.86029) (xy 143.717512 -294.881388)
			(xy 143.758015 -294.909344) (xy 143.793508 -294.943436) (xy 143.823073 -294.98278) (xy 143.845944 -295.026357)
			(xy 143.861528 -295.073038) (xy 143.869423 -295.121615) (xy 143.869918 -295.146222) (xy 143.869423 -295.170829)
			(xy 143.861528 -295.219406) (xy 143.845944 -295.266087) (xy 143.823073 -295.309664) (xy 143.793508 -295.349008)
			(xy 143.758015 -295.3831) (xy 143.717512 -295.411056) (xy 143.67305 -295.432154) (xy 143.625779 -295.445846)
			(xy 143.576924 -295.451778) (xy 143.527749 -295.449797) (xy 143.47953 -295.439953) (xy 143.433514 -295.422501)
			(xy 143.390893 -295.397894) (xy 143.352772 -295.366769) (xy 143.320137 -295.329932) (xy 143.293834 -295.288336)
			(xy 143.274543 -295.24306) (xy 143.262766 -295.195276) (xy 143.258806 -295.146222) (xy 141.990064 -295.146222)
			(xy 141.989569 -295.170829) (xy 141.981674 -295.219406) (xy 141.96609 -295.266087) (xy 141.943219 -295.309664)
			(xy 141.913654 -295.349008) (xy 141.878161 -295.3831) (xy 141.837658 -295.411056) (xy 141.793196 -295.432154)
			(xy 141.745925 -295.445846) (xy 141.69707 -295.451778) (xy 141.647895 -295.449797) (xy 141.599676 -295.439953)
			(xy 141.55366 -295.422501) (xy 141.511039 -295.397894) (xy 141.472918 -295.366769) (xy 141.440283 -295.329932)
			(xy 141.41398 -295.288336) (xy 141.394689 -295.24306) (xy 141.382912 -295.195276) (xy 141.378952 -295.146222)
			(xy 141.05001 -295.146222) (xy 141.049515 -295.170829) (xy 141.04162 -295.219406) (xy 141.026036 -295.266087)
			(xy 141.003165 -295.309664) (xy 140.9736 -295.349008) (xy 140.938107 -295.3831) (xy 140.897604 -295.411056)
			(xy 140.853142 -295.432154) (xy 140.805871 -295.445846) (xy 140.757016 -295.451778) (xy 140.707841 -295.449797)
			(xy 140.659622 -295.439953) (xy 140.613606 -295.422501) (xy 140.570985 -295.397894) (xy 140.532864 -295.366769)
			(xy 140.500229 -295.329932) (xy 140.473926 -295.288336) (xy 140.454635 -295.24306) (xy 140.442858 -295.195276)
			(xy 140.438898 -295.146222) (xy 139.170156 -295.146222) (xy 139.169661 -295.170829) (xy 139.161766 -295.219406)
			(xy 139.146182 -295.266087) (xy 139.123311 -295.309664) (xy 139.093746 -295.349008) (xy 139.058253 -295.3831)
			(xy 139.01775 -295.411056) (xy 138.973288 -295.432154) (xy 138.926017 -295.445846) (xy 138.877162 -295.451778)
			(xy 138.827987 -295.449797) (xy 138.779768 -295.439953) (xy 138.733752 -295.422501) (xy 138.691131 -295.397894)
			(xy 138.65301 -295.366769) (xy 138.620375 -295.329932) (xy 138.594072 -295.288336) (xy 138.574781 -295.24306)
			(xy 138.563004 -295.195276) (xy 138.559044 -295.146222) (xy 138.230102 -295.146222) (xy 138.229607 -295.170829)
			(xy 138.221712 -295.219406) (xy 138.206128 -295.266087) (xy 138.183257 -295.309664) (xy 138.153692 -295.349008)
			(xy 138.118199 -295.3831) (xy 138.077696 -295.411056) (xy 138.033234 -295.432154) (xy 137.985963 -295.445846)
			(xy 137.937108 -295.451778) (xy 137.887933 -295.449797) (xy 137.839714 -295.439953) (xy 137.793698 -295.422501)
			(xy 137.751077 -295.397894) (xy 137.712956 -295.366769) (xy 137.680321 -295.329932) (xy 137.654018 -295.288336)
			(xy 137.634727 -295.24306) (xy 137.62295 -295.195276) (xy 137.61899 -295.146222) (xy 137.290048 -295.146222)
			(xy 137.289553 -295.170829) (xy 137.281658 -295.219406) (xy 137.266074 -295.266087) (xy 137.243203 -295.309664)
			(xy 137.213638 -295.349008) (xy 137.178145 -295.3831) (xy 137.137642 -295.411056) (xy 137.09318 -295.432154)
			(xy 137.045909 -295.445846) (xy 136.997054 -295.451778) (xy 136.947879 -295.449797) (xy 136.89966 -295.439953)
			(xy 136.853644 -295.422501) (xy 136.811023 -295.397894) (xy 136.772902 -295.366769) (xy 136.740267 -295.329932)
			(xy 136.713964 -295.288336) (xy 136.694673 -295.24306) (xy 136.682896 -295.195276) (xy 136.678936 -295.146222)
			(xy 136.349994 -295.146222) (xy 136.349499 -295.170829) (xy 136.341604 -295.219406) (xy 136.32602 -295.266087)
			(xy 136.303149 -295.309664) (xy 136.273584 -295.349008) (xy 136.238091 -295.3831) (xy 136.197588 -295.411056)
			(xy 136.153126 -295.432154) (xy 136.105855 -295.445846) (xy 136.057 -295.451778) (xy 136.007825 -295.449797)
			(xy 135.959606 -295.439953) (xy 135.91359 -295.422501) (xy 135.870969 -295.397894) (xy 135.832848 -295.366769)
			(xy 135.800213 -295.329932) (xy 135.77391 -295.288336) (xy 135.754619 -295.24306) (xy 135.742842 -295.195276)
			(xy 135.738882 -295.146222) (xy 135.40994 -295.146222) (xy 135.409445 -295.170829) (xy 135.40155 -295.219406)
			(xy 135.385966 -295.266087) (xy 135.363095 -295.309664) (xy 135.33353 -295.349008) (xy 135.298037 -295.3831)
			(xy 135.257534 -295.411056) (xy 135.213072 -295.432154) (xy 135.165801 -295.445846) (xy 135.116946 -295.451778)
			(xy 135.067771 -295.449797) (xy 135.019552 -295.439953) (xy 134.973536 -295.422501) (xy 134.930915 -295.397894)
			(xy 134.892794 -295.366769) (xy 134.860159 -295.329932) (xy 134.833856 -295.288336) (xy 134.814565 -295.24306)
			(xy 134.802788 -295.195276) (xy 134.798828 -295.146222) (xy 134.47014 -295.146222) (xy 134.469645 -295.170829)
			(xy 134.46175 -295.219406) (xy 134.446166 -295.266087) (xy 134.423295 -295.309664) (xy 134.39373 -295.349008)
			(xy 134.358237 -295.3831) (xy 134.317734 -295.411056) (xy 134.273272 -295.432154) (xy 134.226001 -295.445846)
			(xy 134.177146 -295.451778) (xy 134.127971 -295.449797) (xy 134.079752 -295.439953) (xy 134.033736 -295.422501)
			(xy 133.991115 -295.397894) (xy 133.952994 -295.366769) (xy 133.920359 -295.329932) (xy 133.894056 -295.288336)
			(xy 133.874765 -295.24306) (xy 133.862988 -295.195276) (xy 133.859028 -295.146222) (xy 133.530086 -295.146222)
			(xy 133.529591 -295.170829) (xy 133.521696 -295.219406) (xy 133.506112 -295.266087) (xy 133.483241 -295.309664)
			(xy 133.453676 -295.349008) (xy 133.418183 -295.3831) (xy 133.37768 -295.411056) (xy 133.333218 -295.432154)
			(xy 133.285947 -295.445846) (xy 133.237092 -295.451778) (xy 133.187917 -295.449797) (xy 133.139698 -295.439953)
			(xy 133.093682 -295.422501) (xy 133.051061 -295.397894) (xy 133.01294 -295.366769) (xy 132.980305 -295.329932)
			(xy 132.954002 -295.288336) (xy 132.934711 -295.24306) (xy 132.922934 -295.195276) (xy 132.918974 -295.146222)
			(xy 132.590032 -295.146222) (xy 132.589537 -295.170829) (xy 132.581642 -295.219406) (xy 132.566058 -295.266087)
			(xy 132.543187 -295.309664) (xy 132.513622 -295.349008) (xy 132.478129 -295.3831) (xy 132.437626 -295.411056)
			(xy 132.393164 -295.432154) (xy 132.345893 -295.445846) (xy 132.297038 -295.451778) (xy 132.247863 -295.449797)
			(xy 132.199644 -295.439953) (xy 132.153628 -295.422501) (xy 132.111007 -295.397894) (xy 132.072886 -295.366769)
			(xy 132.040251 -295.329932) (xy 132.013948 -295.288336) (xy 131.994657 -295.24306) (xy 131.98288 -295.195276)
			(xy 131.97892 -295.146222) (xy 131.649978 -295.146222) (xy 131.649483 -295.170829) (xy 131.641588 -295.219406)
			(xy 131.626004 -295.266087) (xy 131.603133 -295.309664) (xy 131.573568 -295.349008) (xy 131.538075 -295.3831)
			(xy 131.497572 -295.411056) (xy 131.45311 -295.432154) (xy 131.405839 -295.445846) (xy 131.356984 -295.451778)
			(xy 131.307809 -295.449797) (xy 131.25959 -295.439953) (xy 131.213574 -295.422501) (xy 131.170953 -295.397894)
			(xy 131.132832 -295.366769) (xy 131.100197 -295.329932) (xy 131.073894 -295.288336) (xy 131.054603 -295.24306)
			(xy 131.042826 -295.195276) (xy 131.038866 -295.146222) (xy 130.710178 -295.146222) (xy 130.709683 -295.170829)
			(xy 130.701788 -295.219406) (xy 130.686204 -295.266087) (xy 130.663333 -295.309664) (xy 130.633768 -295.349008)
			(xy 130.598275 -295.3831) (xy 130.557772 -295.411056) (xy 130.51331 -295.432154) (xy 130.466039 -295.445846)
			(xy 130.417184 -295.451778) (xy 130.368009 -295.449797) (xy 130.31979 -295.439953) (xy 130.273774 -295.422501)
			(xy 130.231153 -295.397894) (xy 130.193032 -295.366769) (xy 130.160397 -295.329932) (xy 130.134094 -295.288336)
			(xy 130.114803 -295.24306) (xy 130.103026 -295.195276) (xy 130.099066 -295.146222) (xy 129.770124 -295.146222)
			(xy 129.769629 -295.170829) (xy 129.761734 -295.219406) (xy 129.74615 -295.266087) (xy 129.723279 -295.309664)
			(xy 129.693714 -295.349008) (xy 129.658221 -295.3831) (xy 129.617718 -295.411056) (xy 129.573256 -295.432154)
			(xy 129.525985 -295.445846) (xy 129.47713 -295.451778) (xy 129.427955 -295.449797) (xy 129.379736 -295.439953)
			(xy 129.33372 -295.422501) (xy 129.291099 -295.397894) (xy 129.252978 -295.366769) (xy 129.220343 -295.329932)
			(xy 129.19404 -295.288336) (xy 129.174749 -295.24306) (xy 129.162972 -295.195276) (xy 129.159012 -295.146222)
			(xy 128.83007 -295.146222) (xy 128.829575 -295.170829) (xy 128.82168 -295.219406) (xy 128.806096 -295.266087)
			(xy 128.783225 -295.309664) (xy 128.75366 -295.349008) (xy 128.718167 -295.3831) (xy 128.677664 -295.411056)
			(xy 128.633202 -295.432154) (xy 128.585931 -295.445846) (xy 128.537076 -295.451778) (xy 128.487901 -295.449797)
			(xy 128.439682 -295.439953) (xy 128.393666 -295.422501) (xy 128.351045 -295.397894) (xy 128.312924 -295.366769)
			(xy 128.280289 -295.329932) (xy 128.253986 -295.288336) (xy 128.234695 -295.24306) (xy 128.222918 -295.195276)
			(xy 128.218958 -295.146222) (xy 127.908635 -295.146222) (xy 127.932696 -295.169404) (xy 127.982016 -295.222786)
			(xy 128.005078 -295.25087) (xy 128.008634 -295.254934) (xy 128.487932 -295.734232) (xy 128.49464 -295.741472)
			(xy 128.502223 -295.759677) (xy 128.502664 -295.769538) (xy 128.502664 -295.956228) (xy 128.688858 -295.956228)
			(xy 128.692818 -295.907174) (xy 128.704595 -295.85939) (xy 128.723886 -295.814114) (xy 128.750189 -295.772518)
			(xy 128.782824 -295.735681) (xy 128.820945 -295.704556) (xy 128.863566 -295.679949) (xy 128.909582 -295.662497)
			(xy 128.957801 -295.652653) (xy 129.006976 -295.650672) (xy 129.055831 -295.656604) (xy 129.103102 -295.670296)
			(xy 129.147564 -295.691394) (xy 129.188067 -295.71935) (xy 129.22356 -295.753442) (xy 129.253125 -295.792786)
			(xy 129.275996 -295.836363) (xy 129.29158 -295.883044) (xy 129.299475 -295.931621) (xy 129.29997 -295.956228)
			(xy 129.628912 -295.956228) (xy 129.632872 -295.907174) (xy 129.644649 -295.85939) (xy 129.66394 -295.814114)
			(xy 129.690243 -295.772518) (xy 129.722878 -295.735681) (xy 129.760999 -295.704556) (xy 129.80362 -295.679949)
			(xy 129.849636 -295.662497) (xy 129.897855 -295.652653) (xy 129.94703 -295.650672) (xy 129.995885 -295.656604)
			(xy 130.043156 -295.670296) (xy 130.087618 -295.691394) (xy 130.128121 -295.71935) (xy 130.163614 -295.753442)
			(xy 130.193179 -295.792786) (xy 130.21605 -295.836363) (xy 130.231634 -295.883044) (xy 130.239529 -295.931621)
			(xy 130.240024 -295.956228) (xy 130.239529 -295.980835) (xy 130.237718 -295.991975) (xy 130.572409 -295.991975)
			(xy 130.575097 -295.942413) (xy 130.585767 -295.893939) (xy 130.604139 -295.847829) (xy 130.629728 -295.805299)
			(xy 130.66186 -295.767469) (xy 130.699689 -295.735335) (xy 130.742219 -295.709744) (xy 130.788327 -295.691371)
			(xy 130.836801 -295.680699) (xy 130.886363 -295.678009) (xy 130.935707 -295.683372) (xy 130.983534 -295.696647)
			(xy 131.028583 -295.717485) (xy 131.069667 -295.745336) (xy 131.105705 -295.779467) (xy 131.135747 -295.818977)
			(xy 131.159001 -295.862828) (xy 131.174855 -295.909863) (xy 131.182891 -295.958843) (xy 131.18338 -295.98366)
			(xy 131.183198 -295.997843) (xy 131.18053 -296.026083) (xy 131.178046 -296.040048) (xy 131.17576 -296.05224)
			(xy 131.182872 -296.075608) (xy 131.258056 -296.153332) (xy 131.28117 -296.160952) (xy 131.293616 -296.15892)
			(xy 131.307122 -296.156993) (xy 131.33433 -296.154955) (xy 131.347972 -296.154856) (xy 131.361682 -296.155013)
			(xy 131.389018 -296.157171) (xy 131.402582 -296.159174) (xy 131.415028 -296.160952) (xy 131.438142 -296.153332)
			(xy 131.513326 -296.075608) (xy 131.520438 -296.05224) (xy 131.518152 -296.040048) (xy 131.515673 -296.026083)
			(xy 131.513003 -295.997843) (xy 131.512818 -295.98366) (xy 131.51334 -295.958405) (xy 131.521653 -295.908583)
			(xy 131.538054 -295.860809) (xy 131.562095 -295.816386) (xy 131.593119 -295.776526) (xy 131.630281 -295.742316)
			(xy 131.672567 -295.71469) (xy 131.718823 -295.6944) (xy 131.767788 -295.682) (xy 131.818126 -295.677829)
			(xy 131.868464 -295.682) (xy 131.917429 -295.6944) (xy 131.963685 -295.71469) (xy 132.005971 -295.742316)
			(xy 132.043133 -295.776526) (xy 132.074157 -295.816386) (xy 132.098198 -295.860809) (xy 132.114599 -295.908583)
			(xy 132.122912 -295.958405) (xy 132.123434 -295.98366) (xy 132.123249 -295.997779) (xy 132.120576 -296.025892)
			(xy 132.1181 -296.039794) (xy 132.115814 -296.05224) (xy 132.122926 -296.075608) (xy 132.19811 -296.153078)
			(xy 132.221224 -296.160952) (xy 132.233416 -296.15892) (xy 132.246922 -296.156993) (xy 132.27413 -296.154955)
			(xy 132.287772 -296.154856) (xy 132.301546 -296.154995) (xy 132.329009 -296.157158) (xy 132.342636 -296.159174)
			(xy 132.355082 -296.160952) (xy 132.378196 -296.153332) (xy 132.45338 -296.075608) (xy 132.460492 -296.05224)
			(xy 132.458206 -296.040048) (xy 132.455726 -296.026083) (xy 132.453057 -295.997843) (xy 132.452872 -295.98366)
			(xy 132.453421 -295.958843) (xy 132.461457 -295.909863) (xy 132.477312 -295.862829) (xy 132.500566 -295.818979)
			(xy 132.530609 -295.779469) (xy 132.566647 -295.74534) (xy 132.607732 -295.71749) (xy 132.652782 -295.696654)
			(xy 132.700609 -295.683381) (xy 132.749953 -295.67802) (xy 132.799514 -295.680713) (xy 132.847987 -295.691388)
			(xy 132.894095 -295.709764) (xy 132.936622 -295.735358) (xy 132.974448 -295.767494) (xy 133.006577 -295.805327)
			(xy 133.032162 -295.847859) (xy 133.05053 -295.89397) (xy 133.061195 -295.942445) (xy 133.063877 -295.991981)
			(xy 133.392301 -295.991981) (xy 133.394988 -295.942417) (xy 133.405658 -295.893941) (xy 133.42403 -295.84783)
			(xy 133.449619 -295.805298) (xy 133.481752 -295.767466) (xy 133.519582 -295.735331) (xy 133.562112 -295.709739)
			(xy 133.608222 -295.691364) (xy 133.656697 -295.680691) (xy 133.706261 -295.678001) (xy 133.755607 -295.683364)
			(xy 133.803435 -295.696639) (xy 133.848485 -295.717477) (xy 133.889571 -295.745329) (xy 133.92561 -295.77946)
			(xy 133.955653 -295.818972) (xy 133.978908 -295.862824) (xy 133.994763 -295.90986) (xy 134.002799 -295.958842)
			(xy 134.003288 -295.98366) (xy 134.003106 -295.997843) (xy 134.000438 -296.026083) (xy 133.997954 -296.040048)
			(xy 133.995668 -296.05224) (xy 134.00278 -296.075608) (xy 134.077964 -296.153332) (xy 134.101078 -296.160952)
			(xy 134.113524 -296.15892) (xy 134.12703 -296.156992) (xy 134.154238 -296.154955) (xy 134.16788 -296.154856)
			(xy 134.18159 -296.155012) (xy 134.208926 -296.157171) (xy 134.22249 -296.159174) (xy 134.234936 -296.160952)
			(xy 134.25805 -296.153332) (xy 134.333234 -296.075608) (xy 134.340346 -296.05224) (xy 134.33806 -296.040048)
			(xy 134.335581 -296.026083) (xy 134.332911 -295.997843) (xy 134.332726 -295.98366) (xy 134.333248 -295.958405)
			(xy 134.341561 -295.908583) (xy 134.357962 -295.860809) (xy 134.382003 -295.816386) (xy 134.413027 -295.776526)
			(xy 134.450189 -295.742316) (xy 134.492475 -295.71469) (xy 134.538731 -295.6944) (xy 134.587696 -295.682)
			(xy 134.638034 -295.677829) (xy 134.688372 -295.682) (xy 134.737337 -295.6944) (xy 134.783593 -295.71469)
			(xy 134.825879 -295.742316) (xy 134.863041 -295.776526) (xy 134.894065 -295.816386) (xy 134.918106 -295.860809)
			(xy 134.934507 -295.908583) (xy 134.94282 -295.958405) (xy 134.943342 -295.98366) (xy 134.943159 -295.997843)
			(xy 134.940491 -296.026083) (xy 134.938008 -296.040048) (xy 134.935722 -296.05224) (xy 134.942834 -296.075608)
			(xy 135.018018 -296.153332) (xy 135.041132 -296.160952) (xy 135.053578 -296.15892) (xy 135.067083 -296.156986)
			(xy 135.094292 -296.154953) (xy 135.107934 -296.154856) (xy 135.121644 -296.155006) (xy 135.14898 -296.157169)
			(xy 135.162544 -296.159174) (xy 135.17499 -296.160952) (xy 135.198104 -296.153332) (xy 135.273288 -296.075608)
			(xy 135.2804 -296.05224) (xy 135.278114 -296.040048) (xy 135.275634 -296.026083) (xy 135.272965 -295.997843)
			(xy 135.27278 -295.98366) (xy 135.273321 -295.958843) (xy 135.281357 -295.909864) (xy 135.297211 -295.862829)
			(xy 135.320466 -295.81898) (xy 135.350508 -295.77947) (xy 135.386546 -295.745341) (xy 135.427631 -295.717491)
			(xy 135.47268 -295.696655) (xy 135.520506 -295.683382) (xy 135.56985 -295.67802) (xy 135.619411 -295.680712)
			(xy 135.667884 -295.691387) (xy 135.713992 -295.709763) (xy 135.756519 -295.735356) (xy 135.794345 -295.767492)
			(xy 135.826475 -295.805324) (xy 135.85206 -295.847855) (xy 135.870428 -295.893966) (xy 135.881095 -295.94244)
			(xy 135.881841 -295.956228) (xy 140.909052 -295.956228) (xy 140.913012 -295.907174) (xy 140.924789 -295.85939)
			(xy 140.94408 -295.814114) (xy 140.970383 -295.772518) (xy 141.003018 -295.735681) (xy 141.041139 -295.704556)
			(xy 141.08376 -295.679949) (xy 141.129776 -295.662497) (xy 141.177995 -295.652653) (xy 141.22717 -295.650672)
			(xy 141.276025 -295.656604) (xy 141.323296 -295.670296) (xy 141.367758 -295.691394) (xy 141.408261 -295.71935)
			(xy 141.443754 -295.753442) (xy 141.473319 -295.792786) (xy 141.49619 -295.836363) (xy 141.511774 -295.883044)
			(xy 141.519669 -295.931621) (xy 141.520164 -295.956228) (xy 143.72896 -295.956228) (xy 143.73292 -295.907174)
			(xy 143.744697 -295.85939) (xy 143.763988 -295.814114) (xy 143.790291 -295.772518) (xy 143.822926 -295.735681)
			(xy 143.861047 -295.704556) (xy 143.903668 -295.679949) (xy 143.949684 -295.662497) (xy 143.997903 -295.652653)
			(xy 144.047078 -295.650672) (xy 144.095933 -295.656604) (xy 144.143204 -295.670296) (xy 144.187666 -295.691394)
			(xy 144.228169 -295.71935) (xy 144.263662 -295.753442) (xy 144.293227 -295.792786) (xy 144.316098 -295.836363)
			(xy 144.331682 -295.883044) (xy 144.339577 -295.931621) (xy 144.340072 -295.956228) (xy 144.339577 -295.980835)
			(xy 144.331682 -296.029412) (xy 144.316098 -296.076093) (xy 144.293227 -296.11967) (xy 144.263662 -296.159014)
			(xy 144.228169 -296.193106) (xy 144.187666 -296.221062) (xy 144.143204 -296.24216) (xy 144.095933 -296.255852)
			(xy 144.047078 -296.261784) (xy 143.997903 -296.259803) (xy 143.949684 -296.249959) (xy 143.903668 -296.232507)
			(xy 143.861047 -296.2079) (xy 143.822926 -296.176775) (xy 143.790291 -296.139938) (xy 143.763988 -296.098342)
			(xy 143.744697 -296.053066) (xy 143.73292 -296.005282) (xy 143.72896 -295.956228) (xy 141.520164 -295.956228)
			(xy 141.519669 -295.980835) (xy 141.511774 -296.029412) (xy 141.49619 -296.076093) (xy 141.473319 -296.11967)
			(xy 141.443754 -296.159014) (xy 141.408261 -296.193106) (xy 141.367758 -296.221062) (xy 141.323296 -296.24216)
			(xy 141.276025 -296.255852) (xy 141.22717 -296.261784) (xy 141.177995 -296.259803) (xy 141.129776 -296.249959)
			(xy 141.08376 -296.232507) (xy 141.041139 -296.2079) (xy 141.003018 -296.176775) (xy 140.970383 -296.139938)
			(xy 140.94408 -296.098342) (xy 140.924789 -296.053066) (xy 140.913012 -296.005282) (xy 140.909052 -295.956228)
			(xy 135.881841 -295.956228) (xy 135.883778 -295.992002) (xy 135.878409 -296.041345) (xy 135.865127 -296.089169)
			(xy 135.844283 -296.134215) (xy 135.816427 -296.175295) (xy 135.782291 -296.211327) (xy 135.742776 -296.241362)
			(xy 135.698923 -296.264609) (xy 135.651886 -296.280455) (xy 135.602905 -296.288483) (xy 135.578088 -296.288968)
			(xy 135.556498 -296.288206) (xy 135.543798 -296.28719) (xy 135.521446 -296.296842) (xy 135.45312 -296.380408)
			(xy 135.44804 -296.404284) (xy 135.451342 -296.416476) (xy 135.457299 -296.439642) (xy 135.463672 -296.487048)
			(xy 135.464042 -296.510964) (xy 135.463544 -296.537613) (xy 135.455601 -296.590317) (xy 135.447413 -296.616861)
			(xy 139.641824 -296.616861) (xy 139.641824 -296.563563) (xy 139.649767 -296.510859) (xy 139.665477 -296.459929)
			(xy 139.688603 -296.411908) (xy 139.718627 -296.367871) (xy 139.754879 -296.3288) (xy 139.79655 -296.295569)
			(xy 139.842708 -296.26892) (xy 139.892322 -296.249448) (xy 139.944284 -296.237588) (xy 139.997434 -296.233605)
			(xy 140.050584 -296.237588) (xy 140.102546 -296.249448) (xy 140.15216 -296.26892) (xy 140.198318 -296.295569)
			(xy 140.239989 -296.3288) (xy 140.276241 -296.367871) (xy 140.306265 -296.411908) (xy 140.329391 -296.459929)
			(xy 140.345101 -296.510859) (xy 140.353044 -296.563563) (xy 140.353542 -296.590212) (xy 140.353044 -296.616861)
			(xy 140.345101 -296.669565) (xy 140.329391 -296.720495) (xy 140.306265 -296.768516) (xy 140.276241 -296.812553)
			(xy 140.239989 -296.851624) (xy 140.198318 -296.884855) (xy 140.15216 -296.911504) (xy 140.102546 -296.930976)
			(xy 140.050584 -296.942836) (xy 139.997434 -296.94682) (xy 139.944284 -296.942836) (xy 139.892322 -296.930976)
			(xy 139.842708 -296.911504) (xy 139.79655 -296.884855) (xy 139.754879 -296.851624) (xy 139.718627 -296.812553)
			(xy 139.688603 -296.768516) (xy 139.665477 -296.720495) (xy 139.649767 -296.669565) (xy 139.641824 -296.616861)
			(xy 135.447413 -296.616861) (xy 135.439891 -296.641247) (xy 135.416765 -296.689268) (xy 135.386741 -296.733305)
			(xy 135.350489 -296.772376) (xy 135.308818 -296.805607) (xy 135.26266 -296.832256) (xy 135.213046 -296.851728)
			(xy 135.161084 -296.863588) (xy 135.107934 -296.867572) (xy 135.054784 -296.863588) (xy 135.002822 -296.851728)
			(xy 134.953208 -296.832256) (xy 134.90705 -296.805607) (xy 134.865379 -296.772376) (xy 134.829127 -296.733305)
			(xy 134.799103 -296.689268) (xy 134.775977 -296.641247) (xy 134.760267 -296.590317) (xy 134.752324 -296.537613)
			(xy 134.751826 -296.510964) (xy 134.752192 -296.487047) (xy 134.758568 -296.439642) (xy 134.764526 -296.416476)
			(xy 134.767828 -296.404284) (xy 134.762748 -296.380662) (xy 134.694422 -296.297096) (xy 134.67207 -296.287444)
			(xy 134.65937 -296.288206) (xy 134.638034 -296.288968) (xy 134.616444 -296.288206) (xy 134.603744 -296.28719)
			(xy 134.581392 -296.296842) (xy 134.513066 -296.380408) (xy 134.507986 -296.404284) (xy 134.511288 -296.416476)
			(xy 134.517244 -296.439642) (xy 134.523617 -296.487048) (xy 134.523988 -296.510964) (xy 134.52349 -296.537613)
			(xy 134.515547 -296.590317) (xy 134.499837 -296.641247) (xy 134.476711 -296.689268) (xy 134.446687 -296.733305)
			(xy 134.410435 -296.772376) (xy 134.368764 -296.805607) (xy 134.322606 -296.832256) (xy 134.272992 -296.851728)
			(xy 134.22103 -296.863588) (xy 134.16788 -296.867572) (xy 134.11473 -296.863588) (xy 134.062768 -296.851728)
			(xy 134.013154 -296.832256) (xy 133.966996 -296.805607) (xy 133.925325 -296.772376) (xy 133.889073 -296.733305)
			(xy 133.859049 -296.689268) (xy 133.835923 -296.641247) (xy 133.820213 -296.590317) (xy 133.81227 -296.537613)
			(xy 133.811772 -296.510964) (xy 133.812136 -296.487047) (xy 133.818514 -296.439642) (xy 133.824472 -296.416476)
			(xy 133.827774 -296.404284) (xy 133.822694 -296.380662) (xy 133.754368 -296.297096) (xy 133.732016 -296.287444)
			(xy 133.719316 -296.288206) (xy 133.69798 -296.288968) (xy 133.673162 -296.288501) (xy 133.62418 -296.280467)
			(xy 133.577143 -296.264616) (xy 133.533289 -296.241364) (xy 133.493775 -296.211324) (xy 133.459641 -296.175287)
			(xy 133.431787 -296.134203) (xy 133.410946 -296.089154) (xy 133.397668 -296.041326) (xy 133.392301 -295.991981)
			(xy 133.063877 -295.991981) (xy 133.063878 -295.992007) (xy 133.058507 -296.04135) (xy 133.045225 -296.089175)
			(xy 133.02438 -296.13422) (xy 132.996523 -296.1753) (xy 132.962386 -296.211332) (xy 132.92287 -296.241366)
			(xy 132.879016 -296.264612) (xy 132.831979 -296.280457) (xy 132.782997 -296.288484) (xy 132.75818 -296.288968)
			(xy 132.736336 -296.288206) (xy 132.72389 -296.28719) (xy 132.701284 -296.296842) (xy 132.632958 -296.380408)
			(xy 132.627878 -296.404284) (xy 132.63118 -296.416476) (xy 132.637136 -296.439642) (xy 132.643509 -296.487048)
			(xy 132.64388 -296.510964) (xy 132.643382 -296.537613) (xy 132.635439 -296.590317) (xy 132.619729 -296.641247)
			(xy 132.596603 -296.689268) (xy 132.566579 -296.733305) (xy 132.530327 -296.772376) (xy 132.488656 -296.805607)
			(xy 132.442498 -296.832256) (xy 132.392884 -296.851728) (xy 132.340922 -296.863588) (xy 132.287772 -296.867572)
			(xy 132.234622 -296.863588) (xy 132.18266 -296.851728) (xy 132.133046 -296.832256) (xy 132.086888 -296.805607)
			(xy 132.045217 -296.772376) (xy 132.008965 -296.733305) (xy 131.978941 -296.689268) (xy 131.955815 -296.641247)
			(xy 131.940105 -296.590317) (xy 131.932162 -296.537613) (xy 131.931664 -296.510964) (xy 131.932029 -296.487047)
			(xy 131.938406 -296.439642) (xy 131.944364 -296.416476) (xy 131.947666 -296.404538) (xy 131.942586 -296.380662)
			(xy 131.87426 -296.297096) (xy 131.851908 -296.287444) (xy 131.839462 -296.288206) (xy 131.818126 -296.288968)
			(xy 131.796536 -296.288206) (xy 131.783836 -296.28719) (xy 131.761484 -296.296842) (xy 131.693158 -296.380408)
			(xy 131.688078 -296.404284) (xy 131.69138 -296.416476) (xy 131.697336 -296.439642) (xy 131.703709 -296.487048)
			(xy 131.70408 -296.510964) (xy 131.703582 -296.537613) (xy 131.695639 -296.590317) (xy 131.679929 -296.641247)
			(xy 131.656803 -296.689268) (xy 131.626779 -296.733305) (xy 131.590527 -296.772376) (xy 131.548856 -296.805607)
			(xy 131.502698 -296.832256) (xy 131.453084 -296.851728) (xy 131.401122 -296.863588) (xy 131.347972 -296.867572)
			(xy 131.294822 -296.863588) (xy 131.24286 -296.851728) (xy 131.193246 -296.832256) (xy 131.147088 -296.805607)
			(xy 131.105417 -296.772376) (xy 131.069165 -296.733305) (xy 131.039141 -296.689268) (xy 131.016015 -296.641247)
			(xy 131.000305 -296.590317) (xy 130.992362 -296.537613) (xy 130.991864 -296.510964) (xy 130.992229 -296.487047)
			(xy 130.998606 -296.439642) (xy 131.004564 -296.416476) (xy 131.007866 -296.404284) (xy 131.002786 -296.380662)
			(xy 130.93446 -296.297096) (xy 130.912108 -296.287444) (xy 130.899408 -296.288206) (xy 130.878072 -296.288968)
			(xy 130.853255 -296.288492) (xy 130.804274 -296.280458) (xy 130.757239 -296.264606) (xy 130.713388 -296.241353)
			(xy 130.673875 -296.211313) (xy 130.639744 -296.175277) (xy 130.611891 -296.134193) (xy 130.591052 -296.089145)
			(xy 130.577774 -296.041319) (xy 130.572409 -295.991975) (xy 130.237718 -295.991975) (xy 130.231634 -296.029412)
			(xy 130.21605 -296.076093) (xy 130.193179 -296.11967) (xy 130.163614 -296.159014) (xy 130.128121 -296.193106)
			(xy 130.087618 -296.221062) (xy 130.043156 -296.24216) (xy 129.995885 -296.255852) (xy 129.94703 -296.261784)
			(xy 129.897855 -296.259803) (xy 129.849636 -296.249959) (xy 129.80362 -296.232507) (xy 129.760999 -296.2079)
			(xy 129.722878 -296.176775) (xy 129.690243 -296.139938) (xy 129.66394 -296.098342) (xy 129.644649 -296.053066)
			(xy 129.632872 -296.005282) (xy 129.628912 -295.956228) (xy 129.29997 -295.956228) (xy 129.299475 -295.980835)
			(xy 129.29158 -296.029412) (xy 129.275996 -296.076093) (xy 129.253125 -296.11967) (xy 129.22356 -296.159014)
			(xy 129.188067 -296.193106) (xy 129.147564 -296.221062) (xy 129.103102 -296.24216) (xy 129.055831 -296.255852)
			(xy 129.006976 -296.261784) (xy 128.957801 -296.259803) (xy 128.909582 -296.249959) (xy 128.863566 -296.232507)
			(xy 128.820945 -296.2079) (xy 128.782824 -296.176775) (xy 128.750189 -296.139938) (xy 128.723886 -296.098342)
			(xy 128.704595 -296.053066) (xy 128.692818 -296.005282) (xy 128.688858 -295.956228) (xy 128.502664 -295.956228)
			(xy 128.502664 -296.2402) (xy 128.502896 -296.247469) (xy 128.507032 -296.261406) (xy 128.510792 -296.267632)
			(xy 130.702304 -299.692822) (xy 130.706622 -299.698664) (xy 135.054615 -304.780442) (xy 140.011662 -304.780442)
			(xy 140.015692 -304.638092) (xy 140.027769 -304.496199) (xy 140.047854 -304.355216) (xy 140.075883 -304.215595)
			(xy 140.111767 -304.077783) (xy 140.155389 -303.942222) (xy 140.206611 -303.809347) (xy 140.265269 -303.679582)
			(xy 140.331174 -303.553343) (xy 140.404115 -303.431035) (xy 140.483859 -303.31305) (xy 140.570151 -303.199765)
			(xy 140.662713 -303.091544) (xy 140.76125 -302.988732) (xy 140.865445 -302.89166) (xy 140.974966 -302.800639)
			(xy 141.08946 -302.715959) (xy 141.208562 -302.637893) (xy 141.33189 -302.566689) (xy 141.459048 -302.502577)
			(xy 141.58963 -302.445762) (xy 141.723218 -302.396425) (xy 141.859382 -302.354725) (xy 141.997688 -302.320796)
			(xy 142.137691 -302.294745) (xy 142.278945 -302.276657) (xy 142.420995 -302.266589) (xy 142.563387 -302.264574)
			(xy 142.705666 -302.270618) (xy 142.847374 -302.284701) (xy 142.988059 -302.30678) (xy 143.127269 -302.336782)
			(xy 143.264559 -302.374612) (xy 143.399489 -302.420148) (xy 143.531627 -302.473246) (xy 143.660549 -302.533733)
			(xy 143.785842 -302.601418) (xy 143.907105 -302.676083) (xy 144.02395 -302.757489) (xy 144.136003 -302.845375)
			(xy 144.242903 -302.939459) (xy 144.34431 -303.039441) (xy 144.439898 -303.144999) (xy 144.529361 -303.255797)
			(xy 144.612412 -303.371478) (xy 144.688785 -303.491673) (xy 144.758236 -303.615996) (xy 144.820542 -303.744049)
			(xy 144.875504 -303.875422) (xy 144.922945 -304.009694) (xy 144.962714 -304.146435) (xy 144.994683 -304.285207)
			(xy 145.01875 -304.425565) (xy 145.034838 -304.56706) (xy 145.042894 -304.709239) (xy 145.043398 -304.780442)
			(xy 145.042894 -304.851645) (xy 145.034838 -304.993824) (xy 145.01875 -305.135319) (xy 144.994683 -305.275677)
			(xy 144.962714 -305.414449) (xy 144.922945 -305.55119) (xy 144.875504 -305.685462) (xy 144.820542 -305.816835)
			(xy 144.758236 -305.944888) (xy 144.688785 -306.069211) (xy 144.612412 -306.189406) (xy 144.529361 -306.305087)
			(xy 144.439898 -306.415885) (xy 144.34431 -306.521443) (xy 144.242903 -306.621425) (xy 144.136003 -306.715509)
			(xy 144.02395 -306.803395) (xy 143.907105 -306.884801) (xy 143.785842 -306.959466) (xy 143.660549 -307.027151)
			(xy 143.531627 -307.087638) (xy 143.399489 -307.140736) (xy 143.264559 -307.186272) (xy 143.127269 -307.224102)
			(xy 142.988059 -307.254104) (xy 142.847374 -307.276183) (xy 142.705666 -307.290266) (xy 142.563387 -307.29631)
			(xy 142.420995 -307.294295) (xy 142.278945 -307.284227) (xy 142.137691 -307.266139) (xy 141.997688 -307.240088)
			(xy 141.859382 -307.206159) (xy 141.723218 -307.164459) (xy 141.58963 -307.115122) (xy 141.459048 -307.058307)
			(xy 141.33189 -306.994195) (xy 141.208562 -306.922991) (xy 141.08946 -306.844925) (xy 140.974966 -306.760245)
			(xy 140.865445 -306.669224) (xy 140.76125 -306.572152) (xy 140.662713 -306.46934) (xy 140.570151 -306.361119)
			(xy 140.483859 -306.247834) (xy 140.404115 -306.129849) (xy 140.331174 -306.007541) (xy 140.265269 -305.881302)
			(xy 140.206611 -305.751537) (xy 140.155389 -305.618662) (xy 140.111767 -305.483101) (xy 140.075883 -305.345289)
			(xy 140.047854 -305.205668) (xy 140.027769 -305.064685) (xy 140.015692 -304.922792) (xy 140.011662 -304.780442)
			(xy 135.054615 -304.780442) (xy 137.185908 -307.27142) (xy 137.189464 -307.2765) (xy 137.189718 -307.276754)
			(xy 138.653556 -309.521352) (xy 146.640802 -309.521352) (xy 146.644873 -309.46573) (xy 146.656999 -309.411293)
			(xy 146.676922 -309.359202) (xy 146.704218 -309.310567) (xy 146.738304 -309.266424) (xy 146.778453 -309.227715)
			(xy 146.823811 -309.195264) (xy 146.873411 -309.169763) (xy 146.926195 -309.151756) (xy 146.981038 -309.141626)
			(xy 147.036772 -309.139589) (xy 147.092209 -309.145689) (xy 147.146166 -309.159795) (xy 147.197495 -309.181607)
			(xy 147.245101 -309.210661) (xy 147.287969 -309.246336) (xy 147.325186 -309.287873) (xy 147.355959 -309.334386)
			(xy 147.379631 -309.384883) (xy 147.395699 -309.43829) (xy 147.403819 -309.493466) (xy 147.404328 -309.521352)
			(xy 147.403819 -309.549238) (xy 147.395699 -309.604414) (xy 147.379631 -309.657821) (xy 147.355959 -309.708318)
			(xy 147.325186 -309.754831) (xy 147.287969 -309.796368) (xy 147.245101 -309.832043) (xy 147.197495 -309.861097)
			(xy 147.146166 -309.882909) (xy 147.092209 -309.897015) (xy 147.036772 -309.903115) (xy 146.981038 -309.901078)
			(xy 146.926195 -309.890948) (xy 146.873411 -309.872941) (xy 146.823811 -309.84744) (xy 146.778453 -309.814989)
			(xy 146.738304 -309.77628) (xy 146.704218 -309.732137) (xy 146.676922 -309.683502) (xy 146.656999 -309.631411)
			(xy 146.644873 -309.576974) (xy 146.640802 -309.521352) (xy 138.653556 -309.521352) (xy 139.001418 -310.054752)
			(xy 150.179276 -310.054752) (xy 150.183347 -309.99913) (xy 150.195473 -309.944693) (xy 150.215396 -309.892602)
			(xy 150.242692 -309.843967) (xy 150.276778 -309.799824) (xy 150.316927 -309.761115) (xy 150.362285 -309.728664)
			(xy 150.411885 -309.703163) (xy 150.464669 -309.685156) (xy 150.519512 -309.675026) (xy 150.575246 -309.672989)
			(xy 150.630683 -309.679089) (xy 150.68464 -309.693195) (xy 150.735969 -309.715007) (xy 150.783575 -309.744061)
			(xy 150.826443 -309.779736) (xy 150.86366 -309.821273) (xy 150.894433 -309.867786) (xy 150.918105 -309.918283)
			(xy 150.934173 -309.97169) (xy 150.942293 -310.026866) (xy 150.942802 -310.054752) (xy 150.942293 -310.082638)
			(xy 150.934173 -310.137814) (xy 150.918105 -310.191221) (xy 150.894433 -310.241718) (xy 150.86366 -310.288231)
			(xy 150.826443 -310.329768) (xy 150.783575 -310.365443) (xy 150.735969 -310.394497) (xy 150.68464 -310.416309)
			(xy 150.630683 -310.430415) (xy 150.575246 -310.436515) (xy 150.519512 -310.434478) (xy 150.464669 -310.424348)
			(xy 150.411885 -310.406341) (xy 150.362285 -310.38084) (xy 150.316927 -310.348389) (xy 150.276778 -310.30968)
			(xy 150.242692 -310.265537) (xy 150.215396 -310.216902) (xy 150.195473 -310.164811) (xy 150.183347 -310.110374)
			(xy 150.179276 -310.054752) (xy 139.001418 -310.054752) (xy 139.912828 -311.452277) (xy 141.398437 -311.452277)
			(xy 141.401049 -311.389254) (xy 141.411437 -311.327038) (xy 141.42944 -311.266584) (xy 141.454783 -311.208822)
			(xy 141.487075 -311.154638) (xy 141.525822 -311.104864) (xy 141.570429 -311.060265) (xy 141.620209 -311.021527)
			(xy 141.674398 -310.989243) (xy 141.732165 -310.96391) (xy 141.792621 -310.945917) (xy 141.854839 -310.93554)
			(xy 141.917863 -310.932939) (xy 141.980724 -310.938153) (xy 142.042458 -310.951103) (xy 142.102116 -310.97159)
			(xy 142.158781 -310.999298) (xy 142.211584 -311.033803) (xy 142.259714 -311.074574) (xy 142.302431 -311.120985)
			(xy 142.339079 -311.172323) (xy 142.369096 -311.227801) (xy 142.39202 -311.286565) (xy 142.407499 -311.347714)
			(xy 142.415295 -311.410307) (xy 142.415768 -311.441846) (xy 142.415768 -311.443878) (xy 142.415768 -311.4548)
			(xy 142.424404 -311.474358) (xy 142.496794 -311.53989) (xy 142.517114 -311.546494) (xy 142.528036 -311.545224)
			(xy 142.541459 -311.543907) (xy 142.568397 -311.542508) (xy 142.581884 -311.54243) (xy 142.612617 -311.542853)
			(xy 142.673636 -311.55026) (xy 142.733316 -311.564969) (xy 142.790789 -311.586765) (xy 142.845214 -311.61533)
			(xy 142.8958 -311.650248) (xy 142.941807 -311.691008) (xy 142.982566 -311.737017) (xy 143.017481 -311.787605)
			(xy 143.046044 -311.842032) (xy 143.067837 -311.899505) (xy 143.082544 -311.959186) (xy 143.089949 -312.020205)
			(xy 143.090392 -312.050938) (xy 143.090227 -312.067305) (xy 143.088067 -312.09997) (xy 143.086074 -312.116216)
			(xy 143.08455 -312.128662) (xy 143.093186 -312.15203) (xy 143.174212 -312.224928) (xy 143.198088 -312.231024)
			(xy 143.210534 -312.227976) (xy 143.239447 -312.221567) (xy 143.29827 -312.214691) (xy 143.327882 -312.21426)
			(xy 143.359425 -312.214749) (xy 143.422026 -312.22255) (xy 143.483182 -312.238035) (xy 143.541953 -312.260965)
			(xy 143.597435 -312.290989) (xy 143.648778 -312.327646) (xy 143.695193 -312.370371) (xy 143.735966 -312.41851)
			(xy 143.741226 -312.426561) (xy 145.338794 -312.426561) (xy 145.338794 -312.362639) (xy 145.346805 -312.299221)
			(xy 145.362702 -312.237307) (xy 145.386234 -312.177874) (xy 145.417028 -312.121859) (xy 145.454601 -312.070144)
			(xy 145.498358 -312.023547) (xy 145.547611 -311.982802) (xy 145.601582 -311.948551) (xy 145.659421 -311.921334)
			(xy 145.720214 -311.901581) (xy 145.783004 -311.889603) (xy 145.8468 -311.88559) (xy 145.910596 -311.889603)
			(xy 145.973386 -311.901581) (xy 146.034179 -311.921334) (xy 146.092018 -311.948551) (xy 146.145989 -311.982802)
			(xy 146.195242 -312.023547) (xy 146.238999 -312.070144) (xy 146.276572 -312.121859) (xy 146.307366 -312.177874)
			(xy 146.330898 -312.237307) (xy 146.346795 -312.299221) (xy 146.347164 -312.302144) (xy 148.335236 -312.302144)
			(xy 148.339307 -312.246522) (xy 148.351433 -312.192085) (xy 148.371356 -312.139994) (xy 148.398652 -312.091359)
			(xy 148.432738 -312.047216) (xy 148.472887 -312.008507) (xy 148.518245 -311.976056) (xy 148.567845 -311.950555)
			(xy 148.620629 -311.932548) (xy 148.675472 -311.922418) (xy 148.731206 -311.920381) (xy 148.786643 -311.926481)
			(xy 148.8406 -311.940587) (xy 148.891929 -311.962399) (xy 148.939535 -311.991453) (xy 148.982403 -312.027128)
			(xy 149.01962 -312.068665) (xy 149.050393 -312.115178) (xy 149.074065 -312.165675) (xy 149.090133 -312.219082)
			(xy 149.098253 -312.274258) (xy 149.098762 -312.302144) (xy 149.098253 -312.33003) (xy 149.090133 -312.385206)
			(xy 149.074065 -312.438613) (xy 149.050393 -312.48911) (xy 149.01962 -312.535623) (xy 148.982403 -312.57716)
			(xy 148.939535 -312.612835) (xy 148.891929 -312.641889) (xy 148.8406 -312.663701) (xy 148.786643 -312.677807)
			(xy 148.731206 -312.683907) (xy 148.675472 -312.68187) (xy 148.620629 -312.67174) (xy 148.567845 -312.653733)
			(xy 148.518245 -312.628232) (xy 148.472887 -312.595781) (xy 148.432738 -312.557072) (xy 148.398652 -312.512929)
			(xy 148.371356 -312.464294) (xy 148.351433 -312.412203) (xy 148.339307 -312.357766) (xy 148.335236 -312.302144)
			(xy 146.347164 -312.302144) (xy 146.354806 -312.362639) (xy 146.355308 -312.3946) (xy 146.354806 -312.426561)
			(xy 146.346795 -312.489979) (xy 146.330898 -312.551893) (xy 146.307366 -312.611326) (xy 146.276572 -312.667341)
			(xy 146.238999 -312.719056) (xy 146.195242 -312.765653) (xy 146.145989 -312.806398) (xy 146.092018 -312.840649)
			(xy 146.034179 -312.867866) (xy 145.973386 -312.887619) (xy 145.910596 -312.899597) (xy 145.8468 -312.903611)
			(xy 145.783004 -312.899597) (xy 145.720214 -312.887619) (xy 145.659421 -312.867866) (xy 145.601582 -312.840649)
			(xy 145.547611 -312.806398) (xy 145.498358 -312.765653) (xy 145.454601 -312.719056) (xy 145.417028 -312.667341)
			(xy 145.386234 -312.611326) (xy 145.362702 -312.551893) (xy 145.346805 -312.489979) (xy 145.338794 -312.426561)
			(xy 143.741226 -312.426561) (xy 143.770471 -312.471323) (xy 143.798179 -312.527998) (xy 143.818663 -312.587665)
			(xy 143.83161 -312.649408) (xy 143.83682 -312.712278) (xy 143.834213 -312.77531) (xy 143.823829 -312.837535)
			(xy 143.805828 -312.897998) (xy 143.780487 -312.95577) (xy 143.748194 -313.009964) (xy 143.709445 -313.059747)
			(xy 143.664836 -313.104355) (xy 143.615052 -313.143102) (xy 143.560858 -313.175393) (xy 143.503085 -313.200733)
			(xy 143.442622 -313.218732) (xy 143.380396 -313.229114) (xy 143.317364 -313.231719) (xy 143.254494 -313.226508)
			(xy 143.192752 -313.21356) (xy 143.133085 -313.193074) (xy 143.076411 -313.165364) (xy 143.023599 -313.130858)
			(xy 142.975461 -313.090083) (xy 142.932737 -313.043668) (xy 142.896082 -312.992324) (xy 142.866059 -312.93684)
			(xy 142.84313 -312.878069) (xy 142.827647 -312.816912) (xy 142.819848 -312.754311) (xy 142.819374 -312.722768)
			(xy 142.819539 -312.706401) (xy 142.821699 -312.673736) (xy 142.823692 -312.65749) (xy 142.825216 -312.645044)
			(xy 142.81658 -312.621676) (xy 142.735554 -312.548778) (xy 142.711678 -312.542682) (xy 142.699232 -312.54573)
			(xy 142.67032 -312.552145) (xy 142.611496 -312.559017) (xy 142.581884 -312.559446) (xy 142.551154 -312.558959)
			(xy 142.490143 -312.551549) (xy 142.430469 -312.53684) (xy 142.373003 -312.515046) (xy 142.318583 -312.486484)
			(xy 142.268003 -312.451572) (xy 142.221999 -312.410817) (xy 142.181242 -312.364815) (xy 142.146327 -312.314236)
			(xy 142.117763 -312.259817) (xy 142.095966 -312.202352) (xy 142.081255 -312.142679) (xy 142.073842 -312.081668)
			(xy 142.073376 -312.050938) (xy 142.073376 -312.048906) (xy 142.073376 -312.037984) (xy 142.06474 -312.018426)
			(xy 141.99235 -311.952894) (xy 141.97203 -311.94629) (xy 141.961108 -311.94756) (xy 141.947685 -311.948881)
			(xy 141.920747 -311.950278) (xy 141.90726 -311.950354) (xy 141.875721 -311.94979) (xy 141.813129 -311.941983)
			(xy 141.751983 -311.926493) (xy 141.693223 -311.90356) (xy 141.63775 -311.873534) (xy 141.586418 -311.836877)
			(xy 141.540014 -311.794152) (xy 141.499251 -311.746015) (xy 141.464755 -311.693207) (xy 141.437057 -311.636536)
			(xy 141.41658 -311.576875) (xy 141.403641 -311.515139) (xy 141.398437 -311.452277) (xy 139.912828 -311.452277)
			(xy 142.019371 -314.682378) (xy 142.917418 -314.682378) (xy 142.917838 -314.651847) (xy 142.925153 -314.591226)
			(xy 142.939675 -314.531916) (xy 142.961194 -314.474773) (xy 142.989402 -314.420617) (xy 143.023892 -314.37023)
			(xy 143.064168 -314.324335) (xy 143.109651 -314.283593) (xy 143.159684 -314.248592) (xy 143.186404 -314.233814)
			(xy 143.196056 -314.228734) (xy 143.209264 -314.211716) (xy 143.232886 -314.117736) (xy 143.22933 -314.096908)
			(xy 143.223234 -314.087764) (xy 143.207009 -314.062652) (xy 143.179919 -314.009351) (xy 143.159267 -313.953241)
			(xy 143.145337 -313.895096) (xy 143.138323 -313.835719) (xy 143.13789 -313.805824) (xy 143.138392 -313.773863)
			(xy 143.146403 -313.710445) (xy 143.1623 -313.648531) (xy 143.185832 -313.589098) (xy 143.216626 -313.533083)
			(xy 143.254199 -313.481368) (xy 143.297956 -313.434771) (xy 143.347209 -313.394026) (xy 143.40118 -313.359775)
			(xy 143.459019 -313.332558) (xy 143.519812 -313.312805) (xy 143.582602 -313.300827) (xy 143.646398 -313.296814)
			(xy 143.710194 -313.300827) (xy 143.772984 -313.312805) (xy 143.833777 -313.332558) (xy 143.891616 -313.359775)
			(xy 143.945587 -313.394026) (xy 143.99484 -313.434771) (xy 144.038597 -313.481368) (xy 144.07617 -313.533083)
			(xy 144.106964 -313.589098) (xy 144.130496 -313.648531) (xy 144.146393 -313.710445) (xy 144.154404 -313.773863)
			(xy 144.154906 -313.805824) (xy 144.154475 -313.836354) (xy 144.14716 -313.896975) (xy 144.132639 -313.956284)
			(xy 144.11112 -314.013427) (xy 144.082914 -314.067582) (xy 144.048425 -314.117969) (xy 144.008151 -314.163864)
			(xy 143.962671 -314.204607) (xy 143.912639 -314.239609) (xy 143.88592 -314.254388) (xy 143.876268 -314.259468)
			(xy 143.86306 -314.276486) (xy 143.839438 -314.370466) (xy 143.842994 -314.391294) (xy 143.84909 -314.400438)
			(xy 143.865319 -314.425548) (xy 143.888444 -314.47105) (xy 146.640802 -314.47105) (xy 146.644873 -314.415428)
			(xy 146.656999 -314.360991) (xy 146.676922 -314.3089) (xy 146.704218 -314.260265) (xy 146.738304 -314.216122)
			(xy 146.778453 -314.177413) (xy 146.823811 -314.144962) (xy 146.873411 -314.119461) (xy 146.926195 -314.101454)
			(xy 146.981038 -314.091324) (xy 147.036772 -314.089287) (xy 147.092209 -314.095387) (xy 147.146166 -314.109493)
			(xy 147.197495 -314.131305) (xy 147.245101 -314.160359) (xy 147.287969 -314.196034) (xy 147.325186 -314.237571)
			(xy 147.355959 -314.284084) (xy 147.379631 -314.334581) (xy 147.395699 -314.387988) (xy 147.403819 -314.443164)
			(xy 147.404328 -314.47105) (xy 147.403819 -314.498936) (xy 147.395699 -314.554112) (xy 147.379631 -314.607519)
			(xy 147.355959 -314.658016) (xy 147.325186 -314.704529) (xy 147.287969 -314.746066) (xy 147.245101 -314.781741)
			(xy 147.197495 -314.810795) (xy 147.146166 -314.832607) (xy 147.092209 -314.846713) (xy 147.036772 -314.852813)
			(xy 146.981038 -314.850776) (xy 146.926195 -314.840646) (xy 146.873411 -314.822639) (xy 146.823811 -314.797138)
			(xy 146.778453 -314.764687) (xy 146.738304 -314.725978) (xy 146.704218 -314.681835) (xy 146.676922 -314.6332)
			(xy 146.656999 -314.581109) (xy 146.644873 -314.526672) (xy 146.640802 -314.47105) (xy 143.888444 -314.47105)
			(xy 143.892408 -314.47885) (xy 143.913059 -314.53496) (xy 143.926987 -314.593106) (xy 143.934002 -314.652483)
			(xy 143.934434 -314.682378) (xy 143.933932 -314.714339) (xy 143.925921 -314.777757) (xy 143.910024 -314.839671)
			(xy 143.886492 -314.899104) (xy 143.855698 -314.955119) (xy 143.818125 -315.006834) (xy 143.774368 -315.053431)
			(xy 143.725115 -315.094176) (xy 143.671144 -315.128427) (xy 143.613305 -315.155644) (xy 143.552512 -315.175397)
			(xy 143.489722 -315.187375) (xy 143.425926 -315.191389) (xy 143.36213 -315.187375) (xy 143.29934 -315.175397)
			(xy 143.238547 -315.155644) (xy 143.180708 -315.128427) (xy 143.126737 -315.094176) (xy 143.077484 -315.053431)
			(xy 143.033727 -315.006834) (xy 142.996154 -314.955119) (xy 142.96536 -314.899104) (xy 142.941828 -314.839671)
			(xy 142.925931 -314.777757) (xy 142.91792 -314.714339) (xy 142.917418 -314.682378) (xy 142.019371 -314.682378)
			(xy 142.427198 -315.307726) (xy 142.463266 -315.317886) (xy 142.480792 -315.310012) (xy 142.506058 -315.298814)
			(xy 142.55901 -315.282998) (xy 142.613689 -315.274979) (xy 142.64132 -315.274452) (xy 142.668571 -315.274939)
			(xy 142.722519 -315.282698) (xy 142.774814 -315.298054) (xy 142.824391 -315.320696) (xy 142.870242 -315.350162)
			(xy 142.911433 -315.385853) (xy 142.947126 -315.427042) (xy 142.976594 -315.472891) (xy 142.999239 -315.522468)
			(xy 143.014598 -315.574761) (xy 143.022359 -315.628709) (xy 143.022828 -315.65596) (xy 143.022828 -315.657992)
			(xy 143.022828 -315.658246) (xy 143.022828 -315.660278) (xy 143.022373 -315.687134) (xy 143.014848 -315.740318)
			(xy 142.999944 -315.791922) (xy 142.977955 -315.840927) (xy 142.949315 -315.886368) (xy 142.91459 -315.927346)
			(xy 142.894812 -315.94552) (xy 142.880588 -315.95822) (xy 142.875762 -315.995558) (xy 142.933419 -316.08395)
			(xy 146.448526 -316.08395) (xy 146.449288 -316.059566) (xy 146.449288 -315.578998) (xy 146.449755 -315.568994)
			(xy 146.457469 -315.55053) (xy 146.464274 -315.543184) (xy 147.028662 -314.978796) (xy 147.036071 -314.972115)
			(xy 147.05451 -314.964542) (xy 147.064476 -314.964064) (xy 149.483064 -314.964064) (xy 149.512528 -314.936632)
			(xy 149.513798 -314.916566) (xy 149.51851 -314.853063) (xy 149.534997 -314.726782) (xy 149.559359 -314.601781)
			(xy 149.591499 -314.478551) (xy 149.631292 -314.357575) (xy 149.678581 -314.239328) (xy 149.733181 -314.124274)
			(xy 149.794877 -314.012863) (xy 149.863428 -313.905535) (xy 149.938564 -313.802708) (xy 150.019991 -313.704788)
			(xy 150.107388 -313.612158) (xy 150.200414 -313.525182) (xy 150.298703 -313.444201) (xy 150.40187 -313.369533)
			(xy 150.509509 -313.301471) (xy 150.621198 -313.240281) (xy 150.736499 -313.186204) (xy 150.85496 -313.139453)
			(xy 150.976116 -313.10021) (xy 151.099491 -313.06863) (xy 151.224601 -313.044836) (xy 151.350955 -313.028922)
			(xy 151.478058 -313.020951) (xy 151.541734 -313.020456) (xy 151.605592 -313.020961) (xy 151.733056 -313.028982)
			(xy 151.859765 -313.044991) (xy 151.985218 -313.068924) (xy 152.108922 -313.100687) (xy 152.230386 -313.140155)
			(xy 152.349133 -313.187171) (xy 152.464694 -313.241551) (xy 152.576612 -313.303079) (xy 152.684446 -313.371513)
			(xy 152.78777 -313.446583) (xy 152.886177 -313.527993) (xy 152.979278 -313.61542) (xy 153.066706 -313.708521)
			(xy 153.148115 -313.806928) (xy 153.223186 -313.910252) (xy 153.29162 -314.018086) (xy 153.353148 -314.130004)
			(xy 153.407528 -314.245565) (xy 153.454545 -314.364312) (xy 153.494012 -314.485776) (xy 153.525776 -314.60948)
			(xy 153.549709 -314.734933) (xy 153.565718 -314.861642) (xy 153.573739 -314.989106) (xy 153.573978 -315.019436)
			(xy 154.344368 -315.019436) (xy 154.348439 -314.963814) (xy 154.360565 -314.909377) (xy 154.380488 -314.857286)
			(xy 154.407784 -314.808651) (xy 154.44187 -314.764508) (xy 154.482019 -314.725799) (xy 154.527377 -314.693348)
			(xy 154.576977 -314.667847) (xy 154.629761 -314.64984) (xy 154.684604 -314.63971) (xy 154.740338 -314.637673)
			(xy 154.795775 -314.643773) (xy 154.849732 -314.657879) (xy 154.901061 -314.679691) (xy 154.948667 -314.708745)
			(xy 154.991535 -314.74442) (xy 155.028752 -314.785957) (xy 155.059525 -314.83247) (xy 155.083197 -314.882967)
			(xy 155.099265 -314.936374) (xy 155.107385 -314.99155) (xy 155.107894 -315.019436) (xy 155.107385 -315.047322)
			(xy 155.099265 -315.102498) (xy 155.083197 -315.155905) (xy 155.059525 -315.206402) (xy 155.028752 -315.252915)
			(xy 154.991535 -315.294452) (xy 154.948667 -315.330127) (xy 154.901061 -315.359181) (xy 154.849732 -315.380993)
			(xy 154.795775 -315.395099) (xy 154.740338 -315.401199) (xy 154.684604 -315.399162) (xy 154.629761 -315.389032)
			(xy 154.576977 -315.371025) (xy 154.527377 -315.345524) (xy 154.482019 -315.313073) (xy 154.44187 -315.274364)
			(xy 154.407784 -315.230221) (xy 154.380488 -315.181586) (xy 154.360565 -315.129495) (xy 154.348439 -315.075058)
			(xy 154.344368 -315.019436) (xy 153.573978 -315.019436) (xy 153.574242 -315.052964) (xy 153.573769 -315.115907)
			(xy 153.565975 -315.241551) (xy 153.550421 -315.366472) (xy 153.527167 -315.49019) (xy 153.496301 -315.612233)
			(xy 153.457943 -315.732132) (xy 153.412238 -315.849428) (xy 153.359363 -315.96367) (xy 153.29952 -316.074422)
			(xy 153.232938 -316.181258) (xy 153.196798 -316.232794) (xy 153.188416 -316.244732) (xy 153.186384 -316.272672)
			(xy 153.234136 -316.36589) (xy 153.238743 -316.37401) (xy 153.252605 -316.38649) (xy 153.270021 -316.393166)
			(xy 153.279348 -316.393576) (xy 155.777692 -316.393576) (xy 155.787661 -316.394036) (xy 155.806097 -316.401622)
			(xy 155.813506 -316.408308) (xy 156.192474 -316.787276) (xy 156.199199 -316.794679) (xy 156.206919 -316.813104)
			(xy 156.20746 -316.82309) (xy 156.20746 -319.905126) (xy 156.206993 -319.91513) (xy 156.199278 -319.933593)
			(xy 156.192474 -319.94094) (xy 155.936442 -320.196972) (xy 155.929028 -320.203647) (xy 155.910593 -320.211225)
			(xy 155.900628 -320.211704) (xy 155.44927 -320.211704) (xy 155.438676 -320.212274) (xy 155.419317 -320.220896)
			(xy 155.4051 -320.23661) (xy 155.401264 -320.246502) (xy 155.365196 -320.353182) (xy 155.374848 -320.384424)
			(xy 155.387802 -320.39433) (xy 155.414075 -320.415026) (xy 155.461552 -320.462133) (xy 155.50244 -320.515059)
			(xy 155.536033 -320.572892) (xy 155.561751 -320.63463) (xy 155.57915 -320.699209) (xy 155.587928 -320.765511)
			(xy 155.588462 -320.798952) (xy 155.587936 -320.831536) (xy 155.579597 -320.89617) (xy 155.563073 -320.959209)
			(xy 155.538637 -321.019623) (xy 155.506687 -321.076423) (xy 155.467747 -321.128678) (xy 155.422453 -321.175535)
			(xy 155.371549 -321.216225) (xy 155.315865 -321.250083) (xy 155.256315 -321.276554) (xy 155.225242 -321.286378)
			(xy 155.21559 -321.289172) (xy 155.199842 -321.301872) (xy 155.156154 -321.383406) (xy 155.154122 -321.403472)
			(xy 155.15717 -321.413378) (xy 155.167485 -321.449592) (xy 155.178584 -321.524066) (xy 155.179268 -321.561714)
			(xy 155.178705 -321.596273) (xy 155.169359 -321.664756) (xy 155.150829 -321.731343) (xy 155.123454 -321.794809)
			(xy 155.092008 -321.846913) (xy 156.657288 -321.846913) (xy 156.657288 -321.782991) (xy 156.665299 -321.719573)
			(xy 156.681196 -321.657659) (xy 156.704728 -321.598226) (xy 156.735522 -321.542211) (xy 156.773095 -321.490496)
			(xy 156.816852 -321.443899) (xy 156.866105 -321.403154) (xy 156.920076 -321.368903) (xy 156.977915 -321.341686)
			(xy 157.038708 -321.321933) (xy 157.101498 -321.309955) (xy 157.165294 -321.305942) (xy 157.22909 -321.309955)
			(xy 157.29188 -321.321933) (xy 157.352673 -321.341686) (xy 157.410512 -321.368903) (xy 157.464483 -321.403154)
			(xy 157.513736 -321.443899) (xy 157.557493 -321.490496) (xy 157.595066 -321.542211) (xy 157.62586 -321.598226)
			(xy 157.649392 -321.657659) (xy 157.665289 -321.719573) (xy 157.6733 -321.782991) (xy 157.673802 -321.814952)
			(xy 157.6733 -321.846913) (xy 157.665289 -321.910331) (xy 157.649392 -321.972245) (xy 157.62586 -322.031678)
			(xy 157.595066 -322.087693) (xy 157.557493 -322.139408) (xy 157.513736 -322.186005) (xy 157.464483 -322.22675)
			(xy 157.410512 -322.261001) (xy 157.352673 -322.288218) (xy 157.29188 -322.307971) (xy 157.22909 -322.319949)
			(xy 157.165294 -322.323963) (xy 157.101498 -322.319949) (xy 157.038708 -322.307971) (xy 156.977915 -322.288218)
			(xy 156.920076 -322.261001) (xy 156.866105 -322.22675) (xy 156.816852 -322.186005) (xy 156.773095 -322.139408)
			(xy 156.735522 -322.087693) (xy 156.704728 -322.031678) (xy 156.681196 -321.972245) (xy 156.665299 -321.910331)
			(xy 156.657288 -321.846913) (xy 155.092008 -321.846913) (xy 155.08774 -321.853985) (xy 155.066492 -321.881246)
			(xy 155.057602 -321.892168) (xy 155.053538 -321.919346) (xy 155.098496 -322.028058) (xy 155.120594 -322.044568)
			(xy 155.134564 -322.046092) (xy 155.165339 -322.04993) (xy 155.225736 -322.064016) (xy 155.28397 -322.085346)
			(xy 155.339176 -322.113604) (xy 155.390533 -322.148369) (xy 155.437279 -322.189124) (xy 155.478718 -322.235265)
			(xy 155.514236 -322.286105) (xy 155.543303 -322.340889) (xy 155.565489 -322.398803) (xy 155.580462 -322.458985)
			(xy 155.588002 -322.520543) (xy 155.588462 -322.551552) (xy 155.58796 -322.583513) (xy 155.579949 -322.646931)
			(xy 155.564052 -322.708845) (xy 155.54052 -322.768278) (xy 155.509726 -322.824293) (xy 155.472153 -322.876008)
			(xy 155.428396 -322.922605) (xy 155.379143 -322.96335) (xy 155.325172 -322.997601) (xy 155.267333 -323.024818)
			(xy 155.20654 -323.044571) (xy 155.14375 -323.056549) (xy 155.079954 -323.060563) (xy 155.016158 -323.056549)
			(xy 154.953368 -323.044571) (xy 154.892575 -323.024818) (xy 154.834736 -322.997601) (xy 154.780765 -322.96335)
			(xy 154.731512 -322.922605) (xy 154.687755 -322.876008) (xy 154.650182 -322.824293) (xy 154.619388 -322.768278)
			(xy 154.595856 -322.708845) (xy 154.579959 -322.646931) (xy 154.571948 -322.583513) (xy 154.571446 -322.551552)
			(xy 154.572009 -322.516993) (xy 154.581357 -322.448511) (xy 154.599889 -322.381924) (xy 154.627263 -322.318459)
			(xy 154.662976 -322.259282) (xy 154.684222 -322.23202) (xy 154.693112 -322.221098) (xy 154.697176 -322.19392)
			(xy 154.652218 -322.085208) (xy 154.63012 -322.068698) (xy 154.61615 -322.067174) (xy 154.582097 -322.06296)
			(xy 154.515484 -322.046506) (xy 154.451693 -322.021231) (xy 154.391888 -321.987593) (xy 154.364182 -321.967352)
			(xy 154.355038 -321.960494) (xy 154.332686 -321.955922) (xy 154.233626 -321.980306) (xy 154.215846 -321.994784)
			(xy 154.21102 -322.005198) (xy 154.199131 -322.029428) (xy 154.169527 -322.074556) (xy 154.133855 -322.115058)
			(xy 154.092829 -322.150126) (xy 154.047267 -322.179057) (xy 153.998081 -322.201275) (xy 153.946253 -322.216335)
			(xy 153.89282 -322.223937) (xy 153.865834 -322.2244) (xy 153.838579 -322.223955) (xy 153.784623 -322.216202)
			(xy 153.73232 -322.200848) (xy 153.682735 -322.178207) (xy 153.636876 -322.14874) (xy 153.595679 -322.113045)
			(xy 153.559981 -322.071851) (xy 153.530509 -322.025995) (xy 153.507864 -321.976412) (xy 153.492505 -321.92411)
			(xy 153.484747 -321.870155) (xy 153.484747 -321.815645) (xy 153.492505 -321.76169) (xy 153.507864 -321.709388)
			(xy 153.530509 -321.659805) (xy 153.559981 -321.613949) (xy 153.595679 -321.572755) (xy 153.636876 -321.53706)
			(xy 153.682735 -321.507593) (xy 153.73232 -321.484952) (xy 153.784623 -321.469598) (xy 153.838579 -321.461845)
			(xy 153.865834 -321.461384) (xy 153.895013 -321.461893) (xy 153.952695 -321.470747) (xy 154.008349 -321.488305)
			(xy 154.034744 -321.500754) (xy 154.045158 -321.506088) (xy 154.068018 -321.506342) (xy 154.160728 -321.463924)
			(xy 154.17546 -321.446144) (xy 154.178254 -321.434968) (xy 154.181048 -321.4243) (xy 154.185112 -321.41033)
			(xy 154.177238 -321.382898) (xy 154.088846 -321.302126) (xy 154.060652 -321.296792) (xy 154.04719 -321.301872)
			(xy 154.018149 -321.312495) (xy 153.958134 -321.327405) (xy 153.896754 -321.33493) (xy 153.865834 -321.3354)
			(xy 153.83429 -321.334968) (xy 153.771687 -321.327169) (xy 153.71053 -321.311686) (xy 153.651757 -321.288757)
			(xy 153.596272 -321.258734) (xy 153.544927 -321.222079) (xy 153.49851 -321.179354) (xy 153.457734 -321.131216)
			(xy 153.423225 -321.078404) (xy 153.395515 -321.021728) (xy 153.375027 -320.962061) (xy 153.362078 -320.900317)
			(xy 153.356865 -320.837446) (xy 153.359469 -320.774413) (xy 153.369849 -320.712186) (xy 153.387848 -320.65172)
			(xy 153.413187 -320.593946) (xy 153.445478 -320.539749) (xy 153.484224 -320.489963) (xy 153.528832 -320.445352)
			(xy 153.578615 -320.406601) (xy 153.632809 -320.374306) (xy 153.690581 -320.348962) (xy 153.751045 -320.330959)
			(xy 153.813271 -320.320573) (xy 153.876304 -320.317964) (xy 153.939175 -320.323172) (xy 154.00092 -320.336116)
			(xy 154.060589 -320.356599) (xy 154.117267 -320.384305) (xy 154.170082 -320.418809) (xy 154.218224 -320.45958)
			(xy 154.260953 -320.505994) (xy 154.297612 -320.557336) (xy 154.327639 -320.612819) (xy 154.350573 -320.67159)
			(xy 154.366061 -320.732746) (xy 154.373866 -320.795349) (xy 154.374342 -320.826892) (xy 154.373767 -320.861687)
			(xy 154.364338 -320.930635) (xy 154.355546 -320.964306) (xy 154.351482 -320.978276) (xy 154.359356 -321.005708)
			(xy 154.447748 -321.08648) (xy 154.475942 -321.091814) (xy 154.489404 -321.086734) (xy 154.525472 -321.074288)
			(xy 154.535124 -321.071494) (xy 154.550872 -321.058794) (xy 154.59456 -320.97726) (xy 154.596592 -320.957194)
			(xy 154.593544 -320.947288) (xy 154.58322 -320.911076) (xy 154.572127 -320.836601) (xy 154.571446 -320.798952)
			(xy 154.572005 -320.765511) (xy 154.580771 -320.699205) (xy 154.598159 -320.634622) (xy 154.623867 -320.572878)
			(xy 154.657453 -320.51504) (xy 154.698335 -320.462107) (xy 154.745807 -320.414993) (xy 154.772106 -320.39433)
			(xy 154.78506 -320.384424) (xy 154.794712 -320.353182) (xy 154.758644 -320.246502) (xy 154.754742 -320.236646)
			(xy 154.740537 -320.220954) (xy 154.721218 -320.212306) (xy 154.710638 -320.211704) (xy 151.722074 -320.211704)
			(xy 151.71234 -320.212183) (xy 151.694293 -320.219494) (xy 151.680251 -320.232983) (xy 151.675846 -320.241676)
			(xy 151.63165 -320.339974) (xy 151.635968 -320.369438) (xy 151.645874 -320.380614) (xy 151.665565 -320.403503)
			(xy 151.699973 -320.453121) (xy 151.728254 -320.506469) (xy 151.750008 -320.562795) (xy 151.757888 -320.591942)
			(xy 151.760618 -320.600987) (xy 151.771578 -320.616361) (xy 151.779224 -320.621914) (xy 151.804878 -320.638678)
			(xy 151.812965 -320.643493) (xy 151.831331 -320.647531) (xy 151.840692 -320.646552) (xy 151.860497 -320.643583)
			(xy 151.900422 -320.640404) (xy 151.920448 -320.640202) (xy 151.952408 -320.640687) (xy 152.015822 -320.648704)
			(xy 152.077733 -320.664605) (xy 152.137162 -320.688139) (xy 152.193173 -320.718936) (xy 152.244883 -320.75651)
			(xy 152.291476 -320.800268) (xy 152.332218 -320.849521) (xy 152.366465 -320.903491) (xy 152.39368 -320.961328)
			(xy 152.413431 -321.022119) (xy 152.425407 -321.084907) (xy 152.429421 -321.1487) (xy 152.425407 -321.212493)
			(xy 152.413431 -321.275281) (xy 152.39368 -321.336072) (xy 152.366465 -321.393909) (xy 152.332218 -321.447879)
			(xy 152.291476 -321.497132) (xy 152.244883 -321.54089) (xy 152.193173 -321.578464) (xy 152.137162 -321.609261)
			(xy 152.077733 -321.632795) (xy 152.015822 -321.648696) (xy 151.952408 -321.656713) (xy 151.920448 -321.657218)
			(xy 151.896099 -321.65691) (xy 151.847628 -321.652199) (xy 151.823674 -321.64782) (xy 151.812244 -321.645788)
			(xy 151.790908 -321.651122) (xy 151.712676 -321.714114) (xy 151.703024 -321.733926) (xy 151.702516 -321.745356)
			(xy 151.701468 -321.773766) (xy 151.693866 -321.830109) (xy 151.680036 -321.885254) (xy 151.66015 -321.938515)
			(xy 151.647652 -321.96405) (xy 151.642064 -321.974718) (xy 151.642064 -321.99834) (xy 151.688546 -322.093082)
			(xy 151.707342 -322.10756) (xy 151.71928 -322.109846) (xy 151.750578 -322.116289) (xy 151.811352 -322.136042)
			(xy 151.86917 -322.163257) (xy 151.92312 -322.197504) (xy 151.972353 -322.238243) (xy 152.016091 -322.284833)
			(xy 152.053644 -322.336537) (xy 152.08442 -322.39254) (xy 152.107933 -322.45196) (xy 152.123814 -322.513858)
			(xy 152.13181 -322.577259) (xy 152.132284 -322.60921) (xy 152.131782 -322.641171) (xy 152.123771 -322.704589)
			(xy 152.107874 -322.766503) (xy 152.084342 -322.825936) (xy 152.053548 -322.881951) (xy 152.015975 -322.933666)
			(xy 151.972218 -322.980263) (xy 151.922965 -323.021008) (xy 151.868994 -323.055259) (xy 151.811155 -323.082476)
			(xy 151.750362 -323.102229) (xy 151.687572 -323.114207) (xy 151.623776 -323.118221) (xy 151.55998 -323.114207)
			(xy 151.49719 -323.102229) (xy 151.436397 -323.082476) (xy 151.378558 -323.055259) (xy 151.324587 -323.021008)
			(xy 151.275334 -322.980263) (xy 151.231577 -322.933666) (xy 151.194004 -322.881951) (xy 151.16321 -322.825936)
			(xy 151.139678 -322.766503) (xy 151.123781 -322.704589) (xy 151.11577 -322.641171) (xy 151.115268 -322.60921)
			(xy 151.115663 -322.579315) (xy 151.122652 -322.519934) (xy 151.136569 -322.461786) (xy 151.157222 -322.405676)
			(xy 151.170386 -322.378832) (xy 151.175974 -322.368164) (xy 151.175974 -322.344542) (xy 151.129492 -322.2498)
			(xy 151.110696 -322.235322) (xy 151.098758 -322.233036) (xy 151.067473 -322.226541) (xy 151.006707 -322.206786)
			(xy 150.948896 -322.179572) (xy 150.894951 -322.145327) (xy 150.845723 -322.104592) (xy 150.801989 -322.058008)
			(xy 150.764437 -322.006311) (xy 150.73366 -321.950315) (xy 150.710144 -321.890903) (xy 150.694258 -321.829013)
			(xy 150.686254 -321.76562) (xy 150.685754 -321.733672) (xy 150.68633 -321.700062) (xy 150.695186 -321.633426)
			(xy 150.712738 -321.568537) (xy 150.738682 -321.506525) (xy 150.772566 -321.448469) (xy 150.8138 -321.39538)
			(xy 150.861665 -321.348182) (xy 150.915328 -321.307699) (xy 150.944326 -321.290696) (xy 150.955502 -321.284346)
			(xy 150.969218 -321.26301) (xy 150.976838 -321.15252) (xy 150.966424 -321.129406) (xy 150.956264 -321.121532)
			(xy 150.930103 -321.10084) (xy 150.882861 -321.053753) (xy 150.842183 -321.000893) (xy 150.808767 -320.943166)
			(xy 150.783186 -320.881566) (xy 150.765882 -320.817149) (xy 150.75715 -320.751022) (xy 150.75662 -320.717672)
			(xy 150.757043 -320.686291) (xy 150.764752 -320.624006) (xy 150.780073 -320.563143) (xy 150.802773 -320.504631)
			(xy 150.832507 -320.449361) (xy 150.868821 -320.398173) (xy 150.911164 -320.351847) (xy 150.958889 -320.311089)
			(xy 151.011271 -320.27652) (xy 151.067512 -320.248665) (xy 151.09698 -320.237866) (xy 151.10968 -320.233294)
			(xy 151.126698 -320.21399) (xy 151.148796 -320.117216) (xy 151.150419 -320.108793) (xy 151.148541 -320.091751)
			(xy 151.141144 -320.076284) (xy 151.135334 -320.069972) (xy 151.055578 -319.990216) (xy 151.048843 -319.982822)
			(xy 151.04113 -319.964389) (xy 151.040592 -319.954402) (xy 151.040592 -319.876678) (xy 151.037798 -319.86474)
			(xy 151.03475 -319.858898) (xy 151.020393 -319.830935) (xy 151.000032 -319.771472) (xy 150.989691 -319.709476)
			(xy 150.98903 -319.67805) (xy 150.989685 -319.646624) (xy 151.000029 -319.584628) (xy 151.020395 -319.525166)
			(xy 151.03475 -319.497202) (xy 151.037798 -319.49136) (xy 151.040592 -319.479422) (xy 151.040592 -319.434972)
			(xy 151.040214 -319.424928) (xy 151.032631 -319.406332) (xy 151.02586 -319.398904) (xy 150.87473 -319.247774)
			(xy 150.867317 -319.240951) (xy 150.848727 -319.233222) (xy 150.838662 -319.232788) (xy 147.124928 -319.232788)
			(xy 147.114963 -319.2323) (xy 147.096527 -319.224732) (xy 147.089114 -319.218056) (xy 146.464274 -318.593216)
			(xy 146.457538 -318.585822) (xy 146.449826 -318.56739) (xy 146.449288 -318.557402) (xy 146.449288 -316.108334)
			(xy 146.448526 -316.08395) (xy 142.933419 -316.08395) (xy 143.386556 -316.77864) (xy 143.389096 -316.783466)
			(xy 143.38935 -316.783974) (xy 143.567912 -317.143892) (xy 143.572108 -317.15158) (xy 143.584684 -317.163753)
			(xy 143.600624 -317.170982) (xy 143.609314 -317.172086) (xy 143.709136 -317.180468) (xy 143.733266 -317.169292)
			(xy 143.74114 -317.15837) (xy 143.756588 -317.137771) (xy 143.792129 -317.100517) (xy 143.832354 -317.068378)
			(xy 143.876534 -317.041936) (xy 143.923867 -317.021672) (xy 143.973494 -317.007953) (xy 144.024514 -317.001027)
			(xy 144.050258 -317.000636) (xy 144.07751 -317.001096) (xy 144.131459 -317.008848) (xy 144.183756 -317.024198)
			(xy 144.233335 -317.046836) (xy 144.279189 -317.076299) (xy 144.320382 -317.111989) (xy 144.356076 -317.153178)
			(xy 144.385544 -317.199028) (xy 144.408187 -317.248605) (xy 144.423543 -317.3009) (xy 144.431301 -317.354848)
			(xy 144.431301 -317.409352) (xy 144.423543 -317.4633) (xy 144.408187 -317.515595) (xy 144.385544 -317.565172)
			(xy 144.356076 -317.611022) (xy 144.320382 -317.652211) (xy 144.279189 -317.687901) (xy 144.233335 -317.717364)
			(xy 144.183756 -317.740002) (xy 144.131459 -317.755352) (xy 144.07751 -317.763104) (xy 144.050258 -317.763652)
			(xy 144.041368 -317.763652) (xy 144.027906 -317.763144) (xy 144.004538 -317.775844) (xy 143.95069 -317.860426)
			(xy 143.946289 -317.867953) (xy 143.94236 -317.88493) (xy 143.944361 -317.902239) (xy 143.947896 -317.91021)
			(xy 144.370806 -318.762634) (xy 144.372584 -318.766698) (xy 144.372584 -318.766952) (xy 144.686782 -319.585594)
			(xy 144.687036 -319.586356) (xy 144.692193 -319.597417) (xy 144.710652 -319.613319) (xy 144.722342 -319.616836)
			(xy 144.81556 -319.639442) (xy 144.83969 -319.633346) (xy 144.849088 -319.624964) (xy 144.870166 -319.606878)
			(xy 144.91657 -319.576363) (xy 144.966906 -319.552895) (xy 145.020112 -319.536971) (xy 145.075065 -319.528927)
			(xy 145.102834 -319.528444) (xy 145.130085 -319.528932) (xy 145.184032 -319.536692) (xy 145.236325 -319.55205)
			(xy 145.285901 -319.574692) (xy 145.331751 -319.604159) (xy 145.372941 -319.639849) (xy 145.408633 -319.681038)
			(xy 145.438101 -319.726887) (xy 145.460745 -319.776462) (xy 145.476105 -319.828755) (xy 145.483867 -319.882701)
			(xy 145.484342 -319.909952) (xy 145.483846 -319.937961) (xy 145.475651 -319.993378) (xy 145.459446 -320.047002)
			(xy 145.435577 -320.097682) (xy 145.404558 -320.144329) (xy 145.367055 -320.185942) (xy 145.323873 -320.221627)
			(xy 145.300192 -320.236596) (xy 145.28927 -320.2432) (xy 145.27657 -320.264282) (xy 145.269966 -320.372994)
			(xy 145.280126 -320.3956) (xy 145.290032 -320.403474) (xy 145.31569 -320.424178) (xy 145.361965 -320.47114)
			(xy 145.401776 -320.523692) (xy 145.434456 -320.580953) (xy 145.459453 -320.64196) (xy 145.47635 -320.705689)
			(xy 145.484861 -320.771067) (xy 145.485358 -320.804032) (xy 145.484864 -320.835929) (xy 145.476889 -320.899222)
			(xy 145.461056 -320.961019) (xy 145.437614 -321.020349) (xy 145.406932 -321.07628) (xy 145.400674 -321.084913)
			(xy 147.896828 -321.084913) (xy 147.896828 -321.020991) (xy 147.904839 -320.957573) (xy 147.920736 -320.895659)
			(xy 147.944268 -320.836226) (xy 147.975062 -320.780211) (xy 148.012635 -320.728496) (xy 148.056392 -320.681899)
			(xy 148.105645 -320.641154) (xy 148.159616 -320.606903) (xy 148.217455 -320.579686) (xy 148.278248 -320.559933)
			(xy 148.341038 -320.547955) (xy 148.404834 -320.543942) (xy 148.46863 -320.547955) (xy 148.53142 -320.559933)
			(xy 148.592213 -320.579686) (xy 148.650052 -320.606903) (xy 148.704023 -320.641154) (xy 148.753276 -320.681899)
			(xy 148.797033 -320.728496) (xy 148.834606 -320.780211) (xy 148.8654 -320.836226) (xy 148.888932 -320.895659)
			(xy 148.904829 -320.957573) (xy 148.91284 -321.020991) (xy 148.913342 -321.052952) (xy 148.91284 -321.084913)
			(xy 148.904829 -321.148331) (xy 148.888932 -321.210245) (xy 148.8654 -321.269678) (xy 148.834606 -321.325693)
			(xy 148.797033 -321.377408) (xy 148.753276 -321.424005) (xy 148.704023 -321.46475) (xy 148.650052 -321.499001)
			(xy 148.592213 -321.526218) (xy 148.53142 -321.545971) (xy 148.46863 -321.557949) (xy 148.404834 -321.561963)
			(xy 148.341038 -321.557949) (xy 148.278248 -321.545971) (xy 148.217455 -321.526218) (xy 148.159616 -321.499001)
			(xy 148.105645 -321.46475) (xy 148.056392 -321.424005) (xy 148.012635 -321.377408) (xy 147.975062 -321.325693)
			(xy 147.944268 -321.269678) (xy 147.920736 -321.210245) (xy 147.904839 -321.148331) (xy 147.896828 -321.084913)
			(xy 145.400674 -321.084913) (xy 145.369491 -321.127931) (xy 145.325882 -321.17449) (xy 145.276788 -321.215226)
			(xy 145.250154 -321.232784) (xy 145.23593 -321.241928) (xy 145.223992 -321.272916) (xy 146.161998 -324.720669)
			(xy 153.57322 -324.720669) (xy 153.57322 -324.656747) (xy 153.581231 -324.593329) (xy 153.597128 -324.531415)
			(xy 153.62066 -324.471982) (xy 153.651454 -324.415967) (xy 153.689027 -324.364252) (xy 153.732784 -324.317655)
			(xy 153.782037 -324.27691) (xy 153.836008 -324.242659) (xy 153.893847 -324.215442) (xy 153.95464 -324.195689)
			(xy 154.01743 -324.183711) (xy 154.081226 -324.179698) (xy 154.145022 -324.183711) (xy 154.207812 -324.195689)
			(xy 154.268605 -324.215442) (xy 154.326444 -324.242659) (xy 154.380415 -324.27691) (xy 154.429668 -324.317655)
			(xy 154.473425 -324.364252) (xy 154.510998 -324.415967) (xy 154.541792 -324.471982) (xy 154.565324 -324.531415)
			(xy 154.581221 -324.593329) (xy 154.589232 -324.656747) (xy 154.589734 -324.688708) (xy 154.589232 -324.720669)
			(xy 154.581221 -324.784087) (xy 154.573635 -324.813633) (xy 156.657288 -324.813633) (xy 156.657288 -324.749711)
			(xy 156.665299 -324.686293) (xy 156.681196 -324.624379) (xy 156.704728 -324.564946) (xy 156.735522 -324.508931)
			(xy 156.773095 -324.457216) (xy 156.816852 -324.410619) (xy 156.866105 -324.369874) (xy 156.920076 -324.335623)
			(xy 156.977915 -324.308406) (xy 157.038708 -324.288653) (xy 157.101498 -324.276675) (xy 157.165294 -324.272662)
			(xy 157.22909 -324.276675) (xy 157.29188 -324.288653) (xy 157.352673 -324.308406) (xy 157.410512 -324.335623)
			(xy 157.464483 -324.369874) (xy 157.513736 -324.410619) (xy 157.518666 -324.415869) (xy 160.805362 -324.415869)
			(xy 160.805362 -324.351947) (xy 160.813373 -324.288529) (xy 160.82927 -324.226615) (xy 160.852802 -324.167182)
			(xy 160.883596 -324.111167) (xy 160.921169 -324.059452) (xy 160.964926 -324.012855) (xy 161.014179 -323.97211)
			(xy 161.06815 -323.937859) (xy 161.125989 -323.910642) (xy 161.186782 -323.890889) (xy 161.249572 -323.878911)
			(xy 161.313368 -323.874898) (xy 161.377164 -323.878911) (xy 161.439954 -323.890889) (xy 161.500747 -323.910642)
			(xy 161.558586 -323.937859) (xy 161.612557 -323.97211) (xy 161.66181 -324.012855) (xy 161.705567 -324.059452)
			(xy 161.74314 -324.111167) (xy 161.773934 -324.167182) (xy 161.797466 -324.226615) (xy 161.813363 -324.288529)
			(xy 161.821374 -324.351947) (xy 161.821876 -324.383908) (xy 161.821374 -324.415869) (xy 161.813363 -324.479287)
			(xy 161.798981 -324.5353) (xy 164.610084 -324.5353) (xy 164.614076 -324.446415) (xy 164.626019 -324.358246)
			(xy 164.645817 -324.271502) (xy 164.673311 -324.186882) (xy 164.708279 -324.105067) (xy 164.75044 -324.026716)
			(xy 164.799454 -323.952459) (xy 164.854928 -323.882895) (xy 164.916413 -323.818583) (xy 164.983415 -323.760042)
			(xy 165.055396 -323.707742) (xy 165.131774 -323.662104) (xy 165.211936 -323.623497) (xy 165.295236 -323.59223)
			(xy 165.381003 -323.568556) (xy 165.468547 -323.552665) (xy 165.557163 -323.544685) (xy 165.60165 -323.544184)
			(xy 167.35425 -323.544184) (xy 167.39874 -323.544682) (xy 167.487362 -323.552654) (xy 167.574913 -323.568538)
			(xy 167.660688 -323.592207) (xy 167.743995 -323.623469) (xy 167.824165 -323.662073) (xy 167.900551 -323.707708)
			(xy 167.972539 -323.760007) (xy 168.039549 -323.818549) (xy 168.101041 -323.882862) (xy 168.156521 -323.952428)
			(xy 168.205541 -324.026687) (xy 168.247707 -324.105042) (xy 168.28268 -324.186861) (xy 168.310177 -324.271486)
			(xy 168.329977 -324.358235) (xy 168.341922 -324.44641) (xy 168.345914 -324.5353) (xy 172.15407 -324.5353)
			(xy 172.158062 -324.446411) (xy 172.170006 -324.358237) (xy 172.189806 -324.271489) (xy 172.217302 -324.186865)
			(xy 172.252273 -324.105047) (xy 172.294437 -324.026693) (xy 172.343455 -323.952433) (xy 172.398933 -323.882867)
			(xy 172.460423 -323.818554) (xy 172.527431 -323.760011) (xy 172.599416 -323.707711) (xy 172.6758 -323.662074)
			(xy 172.755967 -323.623468) (xy 172.839273 -323.592203) (xy 172.925045 -323.568531) (xy 173.012594 -323.552644)
			(xy 173.101215 -323.544668) (xy 173.145704 -323.544184) (xy 174.898304 -323.544184) (xy 174.942792 -323.544699)
			(xy 175.031409 -323.552675) (xy 175.118955 -323.568563) (xy 175.204724 -323.592234) (xy 175.288026 -323.623498)
			(xy 175.36819 -323.662103) (xy 175.444571 -323.707739) (xy 175.516554 -323.760038) (xy 175.583559 -323.818578)
			(xy 175.645046 -323.88289) (xy 175.700522 -323.952454) (xy 175.749538 -324.026711) (xy 175.791701 -324.105062)
			(xy 175.82667 -324.186878) (xy 175.854165 -324.271499) (xy 175.873964 -324.358244) (xy 175.885908 -324.446414)
			(xy 175.8899 -324.5353) (xy 179.698184 -324.5353) (xy 179.702176 -324.446415) (xy 179.714119 -324.358245)
			(xy 179.733918 -324.271501) (xy 179.761412 -324.18688) (xy 179.79638 -324.105065) (xy 179.838541 -324.026713)
			(xy 179.887556 -323.952457) (xy 179.94303 -323.882892) (xy 180.004516 -323.81858) (xy 180.071519 -323.760039)
			(xy 180.1435 -323.707739) (xy 180.219879 -323.662101) (xy 180.300042 -323.623494) (xy 180.383342 -323.592228)
			(xy 180.46911 -323.568554) (xy 180.556654 -323.552664) (xy 180.645271 -323.544685) (xy 180.689758 -323.544184)
			(xy 182.442358 -323.544184) (xy 182.486848 -323.544683) (xy 182.57547 -323.552655) (xy 182.66302 -323.56854)
			(xy 182.748794 -323.592209) (xy 182.8321 -323.623471) (xy 182.912269 -323.662075) (xy 182.988655 -323.707711)
			(xy 183.060642 -323.76001) (xy 183.127652 -323.818552) (xy 183.189144 -323.882864) (xy 183.244623 -323.95243)
			(xy 183.293642 -324.02669) (xy 183.335808 -324.105044) (xy 183.37078 -324.186863) (xy 183.398277 -324.271487)
			(xy 183.418077 -324.358236) (xy 183.430022 -324.44641) (xy 183.434014 -324.5353) (xy 187.24217 -324.5353)
			(xy 187.246162 -324.44641) (xy 187.258106 -324.358236) (xy 187.277906 -324.271488) (xy 187.305402 -324.186864)
			(xy 187.340374 -324.105045) (xy 187.382539 -324.02669) (xy 187.431557 -323.952431) (xy 187.487035 -323.882864)
			(xy 187.548526 -323.818551) (xy 187.615534 -323.760008) (xy 187.68752 -323.707708) (xy 187.763905 -323.662071)
			(xy 187.844073 -323.623465) (xy 187.927379 -323.592201) (xy 188.013152 -323.56853) (xy 188.100701 -323.552643)
			(xy 188.189322 -323.544668) (xy 188.233812 -323.544184) (xy 189.986412 -323.544184) (xy 190.0309 -323.544699)
			(xy 190.119517 -323.552676) (xy 190.207062 -323.568564) (xy 190.29283 -323.592236) (xy 190.376132 -323.6235)
			(xy 190.456295 -323.662106) (xy 190.532675 -323.707742) (xy 190.604658 -323.760041) (xy 190.671662 -323.818581)
			(xy 190.733149 -323.882892) (xy 190.788624 -323.952456) (xy 190.83764 -324.026713) (xy 190.879802 -324.105064)
			(xy 190.914771 -324.186879) (xy 190.942266 -324.2715) (xy 190.962064 -324.358244) (xy 190.974008 -324.446414)
			(xy 190.978 -324.5353) (xy 194.786284 -324.5353) (xy 194.790276 -324.446414) (xy 194.802219 -324.358244)
			(xy 194.822018 -324.271499) (xy 194.849512 -324.186879) (xy 194.884481 -324.105063) (xy 194.926643 -324.026711)
			(xy 194.975658 -323.952454) (xy 195.031132 -323.882889) (xy 195.092619 -323.818577) (xy 195.159623 -323.760036)
			(xy 195.231604 -323.707736) (xy 195.307984 -323.662099) (xy 195.388147 -323.623492) (xy 195.471448 -323.592226)
			(xy 195.557216 -323.568553) (xy 195.644761 -323.552663) (xy 195.733378 -323.544684) (xy 195.777866 -323.544184)
			(xy 197.530466 -323.544184) (xy 197.574956 -323.544683) (xy 197.663577 -323.552656) (xy 197.751126 -323.568541)
			(xy 197.8369 -323.592211) (xy 197.920206 -323.623473) (xy 198.000374 -323.662078) (xy 198.076759 -323.707714)
			(xy 198.148746 -323.760013) (xy 198.215755 -323.818554) (xy 198.277246 -323.882867) (xy 198.332725 -323.952433)
			(xy 198.381744 -324.026692) (xy 198.423909 -324.105046) (xy 198.458881 -324.186865) (xy 198.486378 -324.271489)
			(xy 198.506178 -324.358237) (xy 198.518122 -324.44641) (xy 198.522114 -324.5353) (xy 202.330084 -324.5353)
			(xy 202.334076 -324.446414) (xy 202.346019 -324.358244) (xy 202.365818 -324.271499) (xy 202.393312 -324.186879)
			(xy 202.428281 -324.105063) (xy 202.470443 -324.026711) (xy 202.519458 -323.952454) (xy 202.574932 -323.882889)
			(xy 202.636419 -323.818577) (xy 202.703423 -323.760036) (xy 202.775404 -323.707736) (xy 202.851784 -323.662099)
			(xy 202.931947 -323.623492) (xy 203.015248 -323.592226) (xy 203.101016 -323.568553) (xy 203.188561 -323.552663)
			(xy 203.277178 -323.544684) (xy 203.321666 -323.544184) (xy 205.074266 -323.544184) (xy 205.118756 -323.544683)
			(xy 205.207377 -323.552656) (xy 205.294926 -323.568541) (xy 205.3807 -323.592211) (xy 205.464006 -323.623473)
			(xy 205.544174 -323.662078) (xy 205.620559 -323.707714) (xy 205.692546 -323.760013) (xy 205.759555 -323.818554)
			(xy 205.821046 -323.882867) (xy 205.876525 -323.952433) (xy 205.925544 -324.026692) (xy 205.967709 -324.105046)
			(xy 206.002681 -324.186865) (xy 206.030178 -324.271489) (xy 206.049978 -324.358237) (xy 206.061922 -324.44641)
			(xy 206.065914 -324.5353) (xy 206.061922 -324.62419) (xy 206.049978 -324.712363) (xy 206.030178 -324.799111)
			(xy 206.002681 -324.883735) (xy 205.967709 -324.965554) (xy 205.925544 -325.043908) (xy 205.876525 -325.118167)
			(xy 205.821046 -325.187733) (xy 205.759555 -325.252046) (xy 205.692546 -325.310587) (xy 205.620559 -325.362886)
			(xy 205.544174 -325.408522) (xy 205.464006 -325.447127) (xy 205.3807 -325.478389) (xy 205.294926 -325.502059)
			(xy 205.207377 -325.517944) (xy 205.118756 -325.525917) (xy 205.074266 -325.5264) (xy 203.321666 -325.5264)
			(xy 203.277178 -325.525916) (xy 203.188561 -325.517937) (xy 203.101016 -325.502047) (xy 203.015248 -325.478374)
			(xy 202.931947 -325.447108) (xy 202.851784 -325.408501) (xy 202.775404 -325.362864) (xy 202.703423 -325.310564)
			(xy 202.636419 -325.252023) (xy 202.574932 -325.187711) (xy 202.519458 -325.118146) (xy 202.470443 -325.043889)
			(xy 202.428281 -324.965537) (xy 202.393312 -324.883721) (xy 202.365818 -324.799101) (xy 202.346019 -324.712356)
			(xy 202.334076 -324.624186) (xy 202.330084 -324.5353) (xy 198.522114 -324.5353) (xy 198.518122 -324.62419)
			(xy 198.506178 -324.712363) (xy 198.486378 -324.799111) (xy 198.458881 -324.883735) (xy 198.423909 -324.965554)
			(xy 198.381744 -325.043908) (xy 198.332725 -325.118167) (xy 198.277246 -325.187733) (xy 198.215755 -325.252046)
			(xy 198.148746 -325.310587) (xy 198.076759 -325.362886) (xy 198.000374 -325.408522) (xy 197.920206 -325.447127)
			(xy 197.8369 -325.478389) (xy 197.751126 -325.502059) (xy 197.663577 -325.517944) (xy 197.574956 -325.525917)
			(xy 197.530466 -325.5264) (xy 195.777866 -325.5264) (xy 195.733378 -325.525916) (xy 195.644761 -325.517937)
			(xy 195.557216 -325.502047) (xy 195.471448 -325.478374) (xy 195.388147 -325.447108) (xy 195.307984 -325.408501)
			(xy 195.231604 -325.362864) (xy 195.159623 -325.310564) (xy 195.092619 -325.252023) (xy 195.031132 -325.187711)
			(xy 194.975658 -325.118146) (xy 194.926643 -325.043889) (xy 194.884481 -324.965537) (xy 194.849512 -324.883721)
			(xy 194.822018 -324.799101) (xy 194.802219 -324.712356) (xy 194.790276 -324.624186) (xy 194.786284 -324.5353)
			(xy 190.978 -324.5353) (xy 190.974008 -324.624186) (xy 190.962064 -324.712356) (xy 190.942266 -324.7991)
			(xy 190.914771 -324.883721) (xy 190.879802 -324.965536) (xy 190.83764 -325.043887) (xy 190.788624 -325.118144)
			(xy 190.733149 -325.187708) (xy 190.671662 -325.252019) (xy 190.604658 -325.310559) (xy 190.532675 -325.362858)
			(xy 190.456295 -325.408494) (xy 190.376132 -325.4471) (xy 190.29283 -325.478364) (xy 190.207062 -325.502036)
			(xy 190.119517 -325.517924) (xy 190.0309 -325.525901) (xy 189.986412 -325.5264) (xy 188.233812 -325.5264)
			(xy 188.189322 -325.525932) (xy 188.100701 -325.517957) (xy 188.013152 -325.50207) (xy 187.927379 -325.478399)
			(xy 187.844073 -325.447135) (xy 187.763905 -325.408529) (xy 187.68752 -325.362892) (xy 187.615534 -325.310592)
			(xy 187.548526 -325.252049) (xy 187.487035 -325.187736) (xy 187.431557 -325.118169) (xy 187.382539 -325.04391)
			(xy 187.340374 -324.965555) (xy 187.305402 -324.883736) (xy 187.277906 -324.799112) (xy 187.258106 -324.712364)
			(xy 187.246162 -324.62419) (xy 187.24217 -324.5353) (xy 183.434014 -324.5353) (xy 183.430022 -324.62419)
			(xy 183.418077 -324.712364) (xy 183.398277 -324.799113) (xy 183.37078 -324.883737) (xy 183.335808 -324.965556)
			(xy 183.293642 -325.04391) (xy 183.244623 -325.11817) (xy 183.189144 -325.187736) (xy 183.127652 -325.252048)
			(xy 183.060642 -325.31059) (xy 182.988655 -325.362889) (xy 182.912269 -325.408525) (xy 182.8321 -325.447129)
			(xy 182.748794 -325.478391) (xy 182.66302 -325.50206) (xy 182.57547 -325.517945) (xy 182.486848 -325.525917)
			(xy 182.442358 -325.5264) (xy 180.689758 -325.5264) (xy 180.645271 -325.525915) (xy 180.556654 -325.517936)
			(xy 180.46911 -325.502046) (xy 180.383342 -325.478372) (xy 180.300042 -325.447106) (xy 180.219879 -325.408499)
			(xy 180.1435 -325.362861) (xy 180.071519 -325.310561) (xy 180.004516 -325.25202) (xy 179.94303 -325.187708)
			(xy 179.887556 -325.118143) (xy 179.838541 -325.043887) (xy 179.79638 -324.965535) (xy 179.761412 -324.88372)
			(xy 179.733918 -324.799099) (xy 179.714119 -324.712355) (xy 179.702176 -324.624185) (xy 179.698184 -324.5353)
			(xy 175.8899 -324.5353) (xy 175.885908 -324.624186) (xy 175.873964 -324.712356) (xy 175.854165 -324.799101)
			(xy 175.82667 -324.883722) (xy 175.791701 -324.965538) (xy 175.749538 -325.043889) (xy 175.700522 -325.118146)
			(xy 175.645046 -325.18771) (xy 175.583559 -325.252022) (xy 175.516554 -325.310562) (xy 175.444571 -325.362861)
			(xy 175.36819 -325.408497) (xy 175.288026 -325.447102) (xy 175.204724 -325.478366) (xy 175.118955 -325.502037)
			(xy 175.031409 -325.517925) (xy 174.942792 -325.525901) (xy 174.898304 -325.5264) (xy 173.145704 -325.5264)
			(xy 173.101215 -325.525932) (xy 173.012594 -325.517956) (xy 172.925045 -325.502069) (xy 172.839273 -325.478397)
			(xy 172.755967 -325.447132) (xy 172.6758 -325.408526) (xy 172.599416 -325.362889) (xy 172.527431 -325.310589)
			(xy 172.460423 -325.252046) (xy 172.398933 -325.187733) (xy 172.343455 -325.118167) (xy 172.294437 -325.043907)
			(xy 172.252273 -324.965553) (xy 172.217302 -324.883735) (xy 172.189806 -324.799111) (xy 172.170006 -324.712363)
			(xy 172.158062 -324.624189) (xy 172.15407 -324.5353) (xy 168.345914 -324.5353) (xy 168.341922 -324.62419)
			(xy 168.329977 -324.712365) (xy 168.310177 -324.799114) (xy 168.28268 -324.883739) (xy 168.247707 -324.965558)
			(xy 168.205541 -325.043913) (xy 168.156521 -325.118172) (xy 168.101041 -325.187738) (xy 168.039549 -325.252051)
			(xy 167.972539 -325.310593) (xy 167.900551 -325.362892) (xy 167.824165 -325.408527) (xy 167.743995 -325.447131)
			(xy 167.660688 -325.478393) (xy 167.574913 -325.502062) (xy 167.487362 -325.517946) (xy 167.39874 -325.525918)
			(xy 167.35425 -325.5264) (xy 165.60165 -325.5264) (xy 165.557163 -325.525915) (xy 165.468547 -325.517935)
			(xy 165.381003 -325.502044) (xy 165.295236 -325.47837) (xy 165.211936 -325.447103) (xy 165.131774 -325.408496)
			(xy 165.055396 -325.362858) (xy 164.983415 -325.310558) (xy 164.916413 -325.252017) (xy 164.854928 -325.187705)
			(xy 164.799454 -325.118141) (xy 164.75044 -325.043884) (xy 164.708279 -324.965533) (xy 164.673311 -324.883718)
			(xy 164.645817 -324.799098) (xy 164.626019 -324.712354) (xy 164.614076 -324.624185) (xy 164.610084 -324.5353)
			(xy 161.798981 -324.5353) (xy 161.797466 -324.541201) (xy 161.773934 -324.600634) (xy 161.74314 -324.656649)
			(xy 161.705567 -324.708364) (xy 161.66181 -324.754961) (xy 161.612557 -324.795706) (xy 161.558586 -324.829957)
			(xy 161.500747 -324.857174) (xy 161.439954 -324.876927) (xy 161.377164 -324.888905) (xy 161.313368 -324.892919)
			(xy 161.249572 -324.888905) (xy 161.186782 -324.876927) (xy 161.125989 -324.857174) (xy 161.06815 -324.829957)
			(xy 161.014179 -324.795706) (xy 160.964926 -324.754961) (xy 160.921169 -324.708364) (xy 160.883596 -324.656649)
			(xy 160.852802 -324.600634) (xy 160.82927 -324.541201) (xy 160.813373 -324.479287) (xy 160.805362 -324.415869)
			(xy 157.518666 -324.415869) (xy 157.557493 -324.457216) (xy 157.595066 -324.508931) (xy 157.62586 -324.564946)
			(xy 157.649392 -324.624379) (xy 157.665289 -324.686293) (xy 157.6733 -324.749711) (xy 157.673802 -324.781672)
			(xy 157.6733 -324.813633) (xy 157.665289 -324.877051) (xy 157.649392 -324.938965) (xy 157.62586 -324.998398)
			(xy 157.595066 -325.054413) (xy 157.557493 -325.106128) (xy 157.513736 -325.152725) (xy 157.464483 -325.19347)
			(xy 157.410512 -325.227721) (xy 157.352673 -325.254938) (xy 157.29188 -325.274691) (xy 157.22909 -325.286669)
			(xy 157.165294 -325.290683) (xy 157.101498 -325.286669) (xy 157.038708 -325.274691) (xy 156.977915 -325.254938)
			(xy 156.920076 -325.227721) (xy 156.866105 -325.19347) (xy 156.816852 -325.152725) (xy 156.773095 -325.106128)
			(xy 156.735522 -325.054413) (xy 156.704728 -324.998398) (xy 156.681196 -324.938965) (xy 156.665299 -324.877051)
			(xy 156.657288 -324.813633) (xy 154.573635 -324.813633) (xy 154.565324 -324.846001) (xy 154.541792 -324.905434)
			(xy 154.510998 -324.961449) (xy 154.473425 -325.013164) (xy 154.429668 -325.059761) (xy 154.380415 -325.100506)
			(xy 154.326444 -325.134757) (xy 154.268605 -325.161974) (xy 154.207812 -325.181727) (xy 154.145022 -325.193705)
			(xy 154.081226 -325.197719) (xy 154.01743 -325.193705) (xy 153.95464 -325.181727) (xy 153.893847 -325.161974)
			(xy 153.836008 -325.134757) (xy 153.782037 -325.100506) (xy 153.732784 -325.059761) (xy 153.689027 -325.013164)
			(xy 153.651454 -324.961449) (xy 153.62066 -324.905434) (xy 153.597128 -324.846001) (xy 153.581231 -324.784087)
			(xy 153.57322 -324.720669) (xy 146.161998 -324.720669) (xy 146.420171 -325.669613) (xy 155.852108 -325.669613)
			(xy 155.852108 -325.605691) (xy 155.860119 -325.542273) (xy 155.876016 -325.480359) (xy 155.899548 -325.420926)
			(xy 155.930342 -325.364911) (xy 155.967915 -325.313196) (xy 156.011672 -325.266599) (xy 156.060925 -325.225854)
			(xy 156.114896 -325.191603) (xy 156.172735 -325.164386) (xy 156.233528 -325.144633) (xy 156.296318 -325.132655)
			(xy 156.360114 -325.128642) (xy 156.42391 -325.132655) (xy 156.4867 -325.144633) (xy 156.547493 -325.164386)
			(xy 156.605332 -325.191603) (xy 156.659303 -325.225854) (xy 156.708556 -325.266599) (xy 156.752313 -325.313196)
			(xy 156.789886 -325.364911) (xy 156.82068 -325.420926) (xy 156.844212 -325.480359) (xy 156.860109 -325.542273)
			(xy 156.86812 -325.605691) (xy 156.868622 -325.637652) (xy 156.86812 -325.669613) (xy 156.860109 -325.733031)
			(xy 156.844212 -325.794945) (xy 156.82068 -325.854378) (xy 156.789886 -325.910393) (xy 156.752313 -325.962108)
			(xy 156.708556 -326.008705) (xy 156.659303 -326.04945) (xy 156.605332 -326.083701) (xy 156.547493 -326.110918)
			(xy 156.4867 -326.130671) (xy 156.42391 -326.142649) (xy 156.360114 -326.146663) (xy 156.296318 -326.142649)
			(xy 156.233528 -326.130671) (xy 156.172735 -326.110918) (xy 156.114896 -326.083701) (xy 156.060925 -326.04945)
			(xy 156.011672 -326.008705) (xy 155.967915 -325.962108) (xy 155.930342 -325.910393) (xy 155.899548 -325.854378)
			(xy 155.876016 -325.794945) (xy 155.860119 -325.733031) (xy 155.852108 -325.669613) (xy 146.420171 -325.669613)
			(xy 146.932796 -327.553828) (xy 150.365206 -327.553828) (xy 150.365667 -327.517078) (xy 150.372769 -327.443921)
			(xy 150.386872 -327.371785) (xy 150.407844 -327.30134) (xy 150.435492 -327.233237) (xy 150.469559 -327.168107)
			(xy 150.50973 -327.106555) (xy 150.532338 -327.077578) (xy 150.538967 -327.06819) (xy 150.54408 -327.045822)
			(xy 150.538986 -327.02345) (xy 150.532338 -327.014078) (xy 150.509698 -326.985122) (xy 150.469494 -326.923583)
			(xy 150.435406 -326.858457) (xy 150.40775 -326.79035) (xy 150.386785 -326.719896) (xy 150.372704 -326.647749)
			(xy 150.365639 -326.574582) (xy 150.365206 -326.537828) (xy 150.365695 -326.499183) (xy 150.373515 -326.422289)
			(xy 150.389073 -326.346581) (xy 150.412211 -326.272835) (xy 150.442691 -326.201808) (xy 150.4802 -326.13423)
			(xy 150.524354 -326.070792) (xy 150.574699 -326.012148) (xy 150.630718 -325.958897) (xy 150.691837 -325.911587)
			(xy 150.75743 -325.870703) (xy 150.826821 -325.836665) (xy 150.899301 -325.809822) (xy 150.974124 -325.790449)
			(xy 151.050523 -325.778745) (xy 151.127714 -325.77483) (xy 151.204905 -325.778745) (xy 151.281304 -325.790449)
			(xy 151.356127 -325.809822) (xy 151.428607 -325.836665) (xy 151.497998 -325.870703) (xy 151.563591 -325.911587)
			(xy 151.62471 -325.958897) (xy 151.680729 -326.012148) (xy 151.731074 -326.070792) (xy 151.775228 -326.13423)
			(xy 151.812737 -326.201808) (xy 151.843217 -326.272835) (xy 151.866355 -326.346581) (xy 151.881913 -326.422289)
			(xy 151.889733 -326.499183) (xy 151.890222 -326.537828) (xy 151.889787 -326.574579) (xy 151.88268 -326.647737)
			(xy 151.868573 -326.719873) (xy 151.847596 -326.790318) (xy 151.819944 -326.858421) (xy 151.785874 -326.92355)
			(xy 151.7457 -326.985102) (xy 151.72309 -327.014078) (xy 151.716418 -327.023437) (xy 151.711328 -327.045822)
			(xy 151.716437 -327.068203) (xy 151.72309 -327.077578) (xy 151.745714 -327.106546) (xy 151.785918 -327.168083)
			(xy 151.820008 -327.233207) (xy 151.847666 -327.301312) (xy 151.868634 -327.371764) (xy 151.882718 -327.443909)
			(xy 151.889787 -327.517075) (xy 151.890222 -327.553828) (xy 151.889733 -327.592473) (xy 151.881913 -327.669367)
			(xy 151.866355 -327.745075) (xy 151.843217 -327.818821) (xy 151.812737 -327.889848) (xy 151.775228 -327.957426)
			(xy 151.731074 -328.020864) (xy 151.680729 -328.079508) (xy 151.62471 -328.132759) (xy 151.563591 -328.180069)
			(xy 151.497998 -328.220953) (xy 151.428607 -328.254991) (xy 151.356127 -328.281834) (xy 151.281304 -328.301207)
			(xy 151.204905 -328.312911) (xy 151.127714 -328.316826) (xy 151.050523 -328.312911) (xy 150.974124 -328.301207)
			(xy 150.899301 -328.281834) (xy 150.826821 -328.254991) (xy 150.75743 -328.220953) (xy 150.691837 -328.180069)
			(xy 150.630718 -328.132759) (xy 150.574699 -328.079508) (xy 150.524354 -328.020864) (xy 150.4802 -327.957426)
			(xy 150.442691 -327.889848) (xy 150.412211 -327.818821) (xy 150.389073 -327.745075) (xy 150.373515 -327.669367)
			(xy 150.365695 -327.592473) (xy 150.365206 -327.553828) (xy 146.932796 -327.553828) (xy 148.447556 -333.121508)
			(xy 167.537892 -333.121508) (xy 167.53833 -333.08433) (xy 167.545581 -333.010329) (xy 167.560006 -332.937387)
			(xy 167.581466 -332.866196) (xy 167.609759 -332.797433) (xy 167.626792 -332.764384) (xy 167.632093 -332.753025)
			(xy 167.632097 -332.727989) (xy 167.626792 -332.716632) (xy 167.609761 -332.683583) (xy 167.581488 -332.614815)
			(xy 167.560038 -332.543623) (xy 167.545614 -332.470682) (xy 167.538353 -332.396684) (xy 167.537892 -332.359508)
			(xy 167.538381 -332.320863) (xy 167.546201 -332.243969) (xy 167.561759 -332.168261) (xy 167.584897 -332.094515)
			(xy 167.615377 -332.023488) (xy 167.652886 -331.95591) (xy 167.69704 -331.892472) (xy 167.747385 -331.833828)
			(xy 167.803404 -331.780577) (xy 167.864523 -331.733267) (xy 167.930116 -331.692383) (xy 167.999507 -331.658345)
			(xy 168.071987 -331.631502) (xy 168.14681 -331.612129) (xy 168.223209 -331.600425) (xy 168.3004 -331.59651)
			(xy 168.377591 -331.600425) (xy 168.45399 -331.612129) (xy 168.528813 -331.631502) (xy 168.601293 -331.658345)
			(xy 168.670684 -331.692383) (xy 168.736277 -331.733267) (xy 168.797396 -331.780577) (xy 168.853415 -331.833828)
			(xy 168.90376 -331.892472) (xy 168.947914 -331.95591) (xy 168.985423 -332.023488) (xy 169.015903 -332.094515)
			(xy 169.039041 -332.168261) (xy 169.054599 -332.243969) (xy 169.062419 -332.320863) (xy 169.062908 -332.359508)
			(xy 169.062477 -332.396686) (xy 169.055224 -332.470687) (xy 169.040798 -332.54363) (xy 169.019336 -332.614821)
			(xy 168.991041 -332.683583) (xy 168.974008 -332.716632) (xy 168.968696 -332.727987) (xy 168.968699 -332.753027)
			(xy 168.974008 -332.764384) (xy 168.991045 -332.79743) (xy 169.019317 -332.866199) (xy 169.040765 -332.937392)
			(xy 169.055188 -333.010333) (xy 169.062448 -333.084331) (xy 169.062908 -333.121508) (xy 169.062419 -333.160153)
			(xy 169.054599 -333.237047) (xy 169.039041 -333.312755) (xy 169.015903 -333.386501) (xy 168.985423 -333.457528)
			(xy 168.947914 -333.525106) (xy 168.90376 -333.588544) (xy 168.853415 -333.647188) (xy 168.797396 -333.700439)
			(xy 168.736277 -333.747749) (xy 168.670684 -333.788633) (xy 168.601293 -333.822671) (xy 168.528813 -333.849514)
			(xy 168.45399 -333.868887) (xy 168.377591 -333.880591) (xy 168.3004 -333.884506) (xy 168.223209 -333.880591)
			(xy 168.14681 -333.868887) (xy 168.071987 -333.849514) (xy 167.999507 -333.822671) (xy 167.930116 -333.788633)
			(xy 167.864523 -333.747749) (xy 167.803404 -333.700439) (xy 167.747385 -333.647188) (xy 167.69704 -333.588544)
			(xy 167.652886 -333.525106) (xy 167.615377 -333.457528) (xy 167.584897 -333.386501) (xy 167.561759 -333.312755)
			(xy 167.546201 -333.237047) (xy 167.538381 -333.160153) (xy 167.537892 -333.121508) (xy 148.447556 -333.121508)
			(xy 149.272244 -336.152744) (xy 149.274206 -336.159081) (xy 149.280896 -336.170529) (xy 149.285452 -336.17535)
			(xy 152.261824 -339.151722) (xy 152.26922 -339.158573) (xy 152.287819 -339.166311) (xy 152.297892 -339.166708)
		)
		(stroke
			(width 0)
			(type solid)
		)
		(fill yes)
		(layer "In6.Cu")
		(net "PVDD_33_S5")
	)
	(gr_poly
		(pts
			(xy 338.709508 -293.18585) (xy 338.719604 -293.185359) (xy 338.738202 -293.177482) (xy 338.752343 -293.16306)
			(xy 338.756498 -293.153846) (xy 338.772153 -293.110892) (xy 338.809544 -293.027456) (xy 338.85363 -292.947355)
			(xy 338.904115 -292.871126) (xy 338.960661 -292.799277) (xy 338.991448 -292.76548) (xy 338.996528 -292.758876)
			(xy 338.999407 -292.754333) (xy 339.003385 -292.744344) (xy 339.004402 -292.739064) (xy 339.00491 -292.730936)
			(xy 339.00491 -292.700964) (xy 339.004402 -292.692836) (xy 339.003329 -292.687482) (xy 338.999225 -292.677365)
			(xy 338.996274 -292.67277) (xy 338.991448 -292.66642) (xy 338.961733 -292.633762) (xy 338.906963 -292.564495)
			(xy 338.857824 -292.491127) (xy 338.814621 -292.414113) (xy 338.777624 -292.333934) (xy 338.747061 -292.251087)
			(xy 338.734654 -292.208712) (xy 338.733315 -292.204278) (xy 338.729219 -292.195971) (xy 338.726526 -292.192202)
			(xy 338.719668 -292.183058) (xy 338.710778 -292.177724) (xy 338.689316 -292.164493) (xy 338.650514 -292.132302)
			(xy 338.617324 -292.094351) (xy 338.590591 -292.051606) (xy 338.570993 -292.005155) (xy 338.55903 -291.956178)
			(xy 338.555005 -291.905922) (xy 338.559023 -291.855666) (xy 338.570979 -291.806688) (xy 338.59057 -291.760234)
			(xy 338.617298 -291.717485) (xy 338.650482 -291.67953) (xy 338.689279 -291.647333) (xy 338.710778 -291.634164)
			(xy 338.719668 -291.62883) (xy 338.726526 -291.619686) (xy 338.729186 -291.615898) (xy 338.733273 -291.607594)
			(xy 338.734654 -291.603176) (xy 338.747023 -291.560788) (xy 338.777571 -291.477933) (xy 338.814566 -291.397749)
			(xy 338.857778 -291.320737) (xy 338.906935 -291.247378) (xy 338.961733 -291.178129) (xy 338.991448 -291.145468)
			(xy 338.996274 -291.139118) (xy 338.999241 -291.134532) (xy 339.003341 -291.12441) (xy 339.004402 -291.119052)
			(xy 339.00491 -291.110924) (xy 339.00491 -291.080952) (xy 339.004402 -291.072824) (xy 339.003328 -291.06747)
			(xy 338.999222 -291.057355) (xy 338.996274 -291.052758) (xy 338.991448 -291.046408) (xy 338.96173 -291.013751)
			(xy 338.906956 -290.944486) (xy 338.857811 -290.87112) (xy 338.814603 -290.794108) (xy 338.777599 -290.71393)
			(xy 338.74703 -290.631085) (xy 338.734654 -290.5887) (xy 338.733314 -290.584266) (xy 338.729217 -290.57596)
			(xy 338.726526 -290.57219) (xy 338.719668 -290.563046) (xy 338.710778 -290.557712) (xy 338.689317 -290.544481)
			(xy 338.650517 -290.51229) (xy 338.617329 -290.47434) (xy 338.590597 -290.431596) (xy 338.571001 -290.385145)
			(xy 338.559039 -290.33617) (xy 338.555016 -290.285916) (xy 338.559034 -290.235662) (xy 338.57099 -290.186685)
			(xy 338.590582 -290.140233) (xy 338.61731 -290.097486) (xy 338.650494 -290.059533) (xy 338.68929 -290.027338)
			(xy 338.710778 -290.014152) (xy 338.719668 -290.008818) (xy 338.726526 -289.999674) (xy 338.729186 -289.995886)
			(xy 338.733271 -289.987581) (xy 338.734654 -289.983164) (xy 338.747024 -289.940777) (xy 338.777572 -289.857922)
			(xy 338.814568 -289.777739) (xy 338.85778 -289.700727) (xy 338.906938 -289.627368) (xy 338.961736 -289.55812)
			(xy 338.991448 -289.525456) (xy 338.996274 -289.519106) (xy 338.99924 -289.51452) (xy 339.003338 -289.504397)
			(xy 339.004402 -289.49904) (xy 339.00491 -289.490912) (xy 339.00491 -289.46094) (xy 339.004402 -289.452812)
			(xy 339.003326 -289.447459) (xy 338.999219 -289.437345) (xy 338.996274 -289.432746) (xy 338.991448 -289.426396)
			(xy 338.961731 -289.393739) (xy 338.906957 -289.324474) (xy 338.857813 -289.251107) (xy 338.814605 -289.174095)
			(xy 338.777602 -289.093917) (xy 338.747034 -289.011071) (xy 338.734654 -288.968688) (xy 338.733313 -288.964255)
			(xy 338.729214 -288.95595) (xy 338.726526 -288.952178) (xy 338.719668 -288.943034) (xy 338.710778 -288.9377)
			(xy 338.689318 -288.924469) (xy 338.65052 -288.892278) (xy 338.617334 -288.854329) (xy 338.590603 -288.811586)
			(xy 338.571009 -288.765136) (xy 338.559048 -288.716163) (xy 338.555026 -288.66591) (xy 338.559045 -288.615657)
			(xy 338.571002 -288.566683) (xy 338.590594 -288.520232) (xy 338.617322 -288.477488) (xy 338.650505 -288.439536)
			(xy 338.689301 -288.407343) (xy 338.710778 -288.39414) (xy 338.719668 -288.388806) (xy 338.726526 -288.379662)
			(xy 338.729185 -288.375874) (xy 338.733268 -288.367568) (xy 338.734654 -288.363152) (xy 338.747021 -288.320763)
			(xy 338.777564 -288.237905) (xy 338.814555 -288.157717) (xy 338.857762 -288.080701) (xy 338.906917 -288.007338)
			(xy 338.961711 -287.938086) (xy 338.991448 -287.905444) (xy 338.99602 -287.899602) (xy 338.999152 -287.894804)
			(xy 339.003378 -287.884158) (xy 339.004402 -287.87852) (xy 339.00491 -287.8709) (xy 339.00491 -287.840928)
			(xy 339.004656 -287.83534) (xy 339.003461 -287.827403) (xy 338.996867 -287.812781) (xy 338.991702 -287.806638)
			(xy 338.991448 -287.806384) (xy 338.961721 -287.773734) (xy 338.906933 -287.704479) (xy 338.857783 -287.631115)
			(xy 338.814579 -287.554099) (xy 338.77759 -287.473913) (xy 338.747046 -287.391057) (xy 338.734654 -287.348676)
			(xy 338.73332 -287.344239) (xy 338.729233 -287.335926) (xy 338.726526 -287.332166) (xy 338.719668 -287.323022)
			(xy 338.710778 -287.317688) (xy 338.689318 -287.304457) (xy 338.650523 -287.272267) (xy 338.617338 -287.234318)
			(xy 338.59061 -287.191576) (xy 338.571016 -287.145127) (xy 338.559057 -287.096155) (xy 338.555036 -287.045904)
			(xy 338.559056 -286.995653) (xy 338.571014 -286.94668) (xy 338.590606 -286.900232) (xy 338.617334 -286.857489)
			(xy 338.650517 -286.819539) (xy 338.689312 -286.787348) (xy 338.710778 -286.774128) (xy 338.719668 -286.768794)
			(xy 338.726526 -286.75965) (xy 338.729184 -286.755861) (xy 338.733266 -286.747555) (xy 338.734654 -286.74314)
			(xy 338.738718 -286.728662) (xy 338.753889 -286.679474) (xy 338.792052 -286.583867) (xy 338.83884 -286.492172)
			(xy 338.893855 -286.405163) (xy 338.956633 -286.323579) (xy 338.991194 -286.285432) (xy 338.993988 -286.282384)
			(xy 338.997777 -286.277168) (xy 339.002908 -286.265344) (xy 339.004148 -286.259016) (xy 339.00491 -286.250888)
			(xy 339.00491 -286.22117) (xy 339.004656 -286.215074) (xy 339.003405 -286.207082) (xy 338.996538 -286.192445)
			(xy 338.991194 -286.186372) (xy 338.961506 -286.153728) (xy 338.906788 -286.084495) (xy 338.857695 -286.011165)
			(xy 338.814532 -285.934196) (xy 338.777567 -285.854066) (xy 338.747031 -285.771272) (xy 338.734654 -285.728918)
			(xy 338.733315 -285.724483) (xy 338.729221 -285.716176) (xy 338.726526 -285.712408) (xy 338.719668 -285.703264)
			(xy 338.710778 -285.69793) (xy 338.689315 -285.684699) (xy 338.650513 -285.652507) (xy 338.617322 -285.614556)
			(xy 338.590587 -285.571811) (xy 338.570989 -285.525359) (xy 338.559025 -285.476382) (xy 338.555 -285.426125)
			(xy 338.559017 -285.375868) (xy 338.570973 -285.326889) (xy 338.590564 -285.280434) (xy 338.617292 -285.237684)
			(xy 338.650476 -285.199728) (xy 338.689274 -285.16753) (xy 338.710778 -285.15437) (xy 338.719668 -285.149036)
			(xy 338.726526 -285.139892) (xy 338.729187 -285.136104) (xy 338.733275 -285.127801) (xy 338.734654 -285.123382)
			(xy 338.747772 -285.0784) (xy 338.780551 -284.990614) (xy 338.820562 -284.905878) (xy 338.867523 -284.824788)
			(xy 338.893912 -284.78607) (xy 338.915003 -284.756408) (xy 338.960506 -284.699594) (xy 338.984844 -284.672532)
			(xy 338.989924 -284.667198) (xy 338.991194 -284.665674) (xy 339.001354 -284.640274) (xy 339.003042 -284.635761)
			(xy 339.004838 -284.626296) (xy 339.00491 -284.621478) (xy 339.00491 -284.61081) (xy 339.004791 -284.605997)
			(xy 339.003007 -284.596536) (xy 339.001354 -284.592014) (xy 338.991194 -284.566614) (xy 338.989416 -284.564836)
			(xy 338.984844 -284.559756) (xy 338.954364 -284.524958) (xy 338.923449 -284.487319) (xy 338.867531 -284.407556)
			(xy 338.818757 -284.323236) (xy 338.797646 -284.27934) (xy 338.777412 -284.234966) (xy 338.743834 -284.143396)
			(xy 338.73059 -284.09646) (xy 338.72932 -284.092904) (xy 338.725764 -284.0863) (xy 338.704122 -284.074526)
			(xy 338.66446 -284.045304) (xy 338.629818 -284.010275) (xy 338.601037 -283.970292) (xy 338.578815 -283.926323)
			(xy 338.563692 -283.879437) (xy 338.556034 -283.83077) (xy 338.555584 -283.806138) (xy 338.556154 -283.77897)
			(xy 338.565458 -283.725437) (xy 338.58378 -283.674283) (xy 338.610582 -283.627017) (xy 338.645073 -283.585032)
			(xy 338.686237 -283.549564) (xy 338.709254 -283.53512) (xy 338.71789 -283.53004) (xy 338.724748 -283.520896)
			(xy 338.727458 -283.517068) (xy 338.731554 -283.508632) (xy 338.732876 -283.504132) (xy 338.743941 -283.465568)
			(xy 338.770865 -283.389984) (xy 338.80312 -283.316516) (xy 338.821522 -283.280866) (xy 338.843936 -283.239493)
			(xy 338.894736 -283.160279) (xy 338.952005 -283.085609) (xy 338.98332 -283.050488) (xy 338.98967 -283.04363)
			(xy 338.999576 -283.01823) (xy 339.001203 -283.013766) (xy 339.002993 -283.004437) (xy 339.003132 -282.999688)
			(xy 339.003132 -282.988766) (xy 339.00304 -282.984011) (xy 339.001259 -282.974671) (xy 338.999576 -282.970224)
			(xy 338.98967 -282.944824) (xy 338.98332 -282.937966) (xy 338.952969 -282.903889) (xy 338.897308 -282.831563)
			(xy 338.847734 -282.754938) (xy 338.804576 -282.674524) (xy 338.768123 -282.590857) (xy 338.752942 -282.547822)
			(xy 338.734654 -282.488894) (xy 338.733314 -282.48446) (xy 338.729216 -282.476155) (xy 338.726526 -282.472384)
			(xy 338.719668 -282.46324) (xy 338.710778 -282.457906) (xy 338.689317 -282.444675) (xy 338.650518 -282.412484)
			(xy 338.617331 -282.374534) (xy 338.5906 -282.331791) (xy 338.571005 -282.285341) (xy 338.559043 -282.236366)
			(xy 338.555021 -282.186113) (xy 338.559039 -282.13586) (xy 338.570996 -282.086884) (xy 338.590588 -282.040433)
			(xy 338.617316 -281.997687) (xy 338.6505 -281.959734) (xy 338.689295 -281.92754) (xy 338.710778 -281.914346)
			(xy 338.719668 -281.909012) (xy 338.726526 -281.899868) (xy 338.729185 -281.89608) (xy 338.733269 -281.887775)
			(xy 338.734654 -281.883358) (xy 338.747021 -281.840969) (xy 338.777563 -281.75811) (xy 338.814554 -281.677923)
			(xy 338.857761 -281.600907) (xy 338.906915 -281.527543) (xy 338.961709 -281.45829) (xy 338.991448 -281.42565)
			(xy 338.996274 -281.4193) (xy 338.99924 -281.414713) (xy 339.003336 -281.404591) (xy 339.004402 -281.399234)
			(xy 339.00491 -281.391106) (xy 339.00491 -281.361134) (xy 339.004402 -281.353006) (xy 339.003326 -281.347653)
			(xy 338.999217 -281.337539) (xy 338.996274 -281.33294) (xy 338.991448 -281.32659) (xy 338.961731 -281.293933)
			(xy 338.906957 -281.224668) (xy 338.857814 -281.151301) (xy 338.814606 -281.074289) (xy 338.777604 -280.99411)
			(xy 338.747036 -280.911265) (xy 338.734654 -280.868882) (xy 338.733313 -280.864449) (xy 338.729213 -280.856145)
			(xy 338.726526 -280.852372) (xy 338.719668 -280.843228) (xy 338.710778 -280.837894) (xy 338.689318 -280.824663)
			(xy 338.650521 -280.792472) (xy 338.617336 -280.754523) (xy 338.590606 -280.711781) (xy 338.571013 -280.665332)
			(xy 338.559053 -280.616359) (xy 338.555031 -280.566107) (xy 338.55905 -280.515855) (xy 338.571008 -280.466882)
			(xy 338.5906 -280.420432) (xy 338.617328 -280.377688) (xy 338.650511 -280.339737) (xy 338.689306 -280.307545)
			(xy 338.710778 -280.294334) (xy 338.719668 -280.289) (xy 338.726526 -280.279856) (xy 338.729184 -280.276067)
			(xy 338.733267 -280.267762) (xy 338.734654 -280.263346) (xy 338.747021 -280.220957) (xy 338.777564 -280.138099)
			(xy 338.814555 -280.057912) (xy 338.857763 -279.980896) (xy 338.906918 -279.907533) (xy 338.961713 -279.838281)
			(xy 338.991448 -279.805638) (xy 338.996274 -279.799288) (xy 338.999239 -279.794701) (xy 339.003332 -279.784578)
			(xy 339.004402 -279.779222) (xy 339.00491 -279.771094) (xy 339.00491 -279.741122) (xy 339.004402 -279.732994)
			(xy 339.003334 -279.727638) (xy 338.99924 -279.717514) (xy 338.996274 -279.712928) (xy 338.991448 -279.706578)
			(xy 338.961731 -279.67392) (xy 338.906958 -279.604655) (xy 338.857815 -279.531288) (xy 338.814609 -279.454276)
			(xy 338.777607 -279.374097) (xy 338.747041 -279.291251) (xy 338.734654 -279.24887) (xy 338.73332 -279.244433)
			(xy 338.729232 -279.23612) (xy 338.726526 -279.23236) (xy 338.719668 -279.223216) (xy 338.710778 -279.217882)
			(xy 338.689319 -279.204651) (xy 338.650524 -279.172461) (xy 338.617341 -279.134512) (xy 338.590613 -279.09177)
			(xy 338.57102 -279.045323) (xy 338.559062 -278.996351) (xy 338.555042 -278.946101) (xy 338.559062 -278.895851)
			(xy 338.57102 -278.846879) (xy 338.590612 -278.800431) (xy 338.61734 -278.757689) (xy 338.650523 -278.719741)
			(xy 338.689317 -278.68755) (xy 338.710778 -278.674322) (xy 338.719668 -278.668988) (xy 338.726526 -278.659844)
			(xy 338.729184 -278.656055) (xy 338.733264 -278.647749) (xy 338.734654 -278.643334) (xy 338.747711 -278.598681)
			(xy 338.780265 -278.511521) (xy 338.819955 -278.42737) (xy 338.866505 -278.346812) (xy 338.919592 -278.270403)
			(xy 338.97885 -278.198673) (xy 339.011006 -278.165052) (xy 339.014124 -278.161661) (xy 339.019227 -278.153992)
			(xy 339.021166 -278.149812) (xy 339.025484 -278.139906) (xy 339.025738 -278.129746) (xy 339.026808 -278.103084)
			(xy 339.036793 -278.050672) (xy 339.055453 -278.000687) (xy 339.082257 -277.954554) (xy 339.116441 -277.913588)
			(xy 339.15703 -277.878958) (xy 339.179662 -277.864824) (xy 339.186012 -277.85314) (xy 339.188023 -277.849061)
			(xy 339.190702 -277.84037) (xy 339.191346 -277.835868) (xy 339.191854 -277.829518) (xy 339.191854 -277.66645)
			(xy 339.191463 -277.657318) (xy 339.185034 -277.640222) (xy 339.173013 -277.62647) (xy 339.165184 -277.621746)
			(xy 339.088476 -277.58009) (xy 339.083661 -277.577619) (xy 339.073286 -277.574541) (xy 339.067902 -277.573994)
			(xy 339.046566 -277.588218) (xy 339.027007 -277.600865) (xy 338.98495 -277.620878) (xy 338.940404 -277.634475)
			(xy 338.89434 -277.64136) (xy 338.871052 -277.641812) (xy 338.846246 -277.641322) (xy 338.797245 -277.633554)
			(xy 338.750062 -277.618217) (xy 338.705859 -277.595688) (xy 338.665724 -277.566523) (xy 338.630646 -277.531439)
			(xy 338.601486 -277.4913) (xy 338.578965 -277.447093) (xy 338.563635 -277.399908) (xy 338.555875 -277.350906)
			(xy 338.555875 -277.301294) (xy 338.563635 -277.252292) (xy 338.578965 -277.205107) (xy 338.601486 -277.1609)
			(xy 338.630646 -277.120761) (xy 338.665724 -277.085677) (xy 338.705859 -277.056512) (xy 338.750062 -277.033983)
			(xy 338.797245 -277.018646) (xy 338.846246 -277.010878) (xy 338.871052 -277.010368) (xy 338.894305 -277.010842)
			(xy 338.940294 -277.017778) (xy 338.984771 -277.031375) (xy 339.026777 -277.05134) (xy 339.046312 -277.063962)
			(xy 339.04682 -277.063962) (xy 339.068156 -277.078186) (xy 339.070696 -277.07844) (xy 339.076284 -277.078694)
			(xy 339.165184 -277.030434) (xy 339.173054 -277.025763) (xy 339.185086 -277.011992) (xy 339.191517 -276.994873)
			(xy 339.191854 -276.98573) (xy 339.191854 -276.822662) (xy 339.191346 -276.816312) (xy 339.190694 -276.811812)
			(xy 339.188006 -276.803127) (xy 339.186012 -276.79904) (xy 339.179662 -276.787356) (xy 339.158329 -276.774087)
			(xy 339.119781 -276.741871) (xy 339.086822 -276.703958) (xy 339.060282 -276.661304) (xy 339.040832 -276.614985)
			(xy 339.028963 -276.56617) (xy 339.024974 -276.516092) (xy 339.028966 -276.466014) (xy 339.040838 -276.4172)
			(xy 339.06029 -276.370882) (xy 339.086832 -276.328229) (xy 339.119793 -276.290317) (xy 339.158342 -276.258104)
			(xy 339.179662 -276.244812) (xy 339.186012 -276.233128) (xy 339.188022 -276.229048) (xy 339.190699 -276.220358)
			(xy 339.191346 -276.215856) (xy 339.191854 -276.209506) (xy 339.191854 -276.109684) (xy 339.192379 -276.099841)
			(xy 339.199947 -276.081662) (xy 339.206586 -276.074378) (xy 339.49386 -275.787104) (xy 339.496764 -275.784119)
			(xy 339.501614 -275.777349) (xy 339.503512 -275.773642) (xy 339.506126 -275.767905) (xy 339.508689 -275.755563)
			(xy 339.508592 -275.749258) (xy 339.508084 -275.74494) (xy 339.506967 -275.735264) (xy 339.505821 -275.715818)
			(xy 339.505798 -275.706078) (xy 339.50627 -275.682088) (xy 339.513779 -275.634699) (xy 339.528609 -275.589069)
			(xy 339.550393 -275.54632) (xy 339.578597 -275.507504) (xy 339.612526 -275.473579) (xy 339.651343 -275.445379)
			(xy 339.694095 -275.423598) (xy 339.739727 -275.408773) (xy 339.787116 -275.401268) (xy 339.811106 -275.40077)
			(xy 339.820786 -275.40087) (xy 339.840105 -275.402139) (xy 339.849714 -275.40331) (xy 339.861906 -275.404834)
			(xy 339.872828 -275.401024) (xy 339.878136 -275.399014) (xy 339.887748 -275.39298) (xy 339.891878 -275.389086)
			(xy 340.046818 -275.234146) (xy 340.053283 -275.227053) (xy 340.060841 -275.209428) (xy 340.06155 -275.199856)
			(xy 340.063582 -275.12772) (xy 340.061804 -275.122894) (xy 340.043914 -275.104942) (xy 340.013525 -275.064387)
			(xy 339.990007 -275.019498) (xy 339.973963 -274.971427) (xy 339.965807 -274.92141) (xy 339.965284 -274.896072)
			(xy 339.965771 -274.871295) (xy 339.973522 -274.822351) (xy 339.988829 -274.775221) (xy 340.011317 -274.731063)
			(xy 340.04043 -274.690964) (xy 340.075455 -274.655909) (xy 340.115529 -274.62676) (xy 340.159667 -274.604235)
			(xy 340.206784 -274.588886) (xy 340.255722 -274.581093) (xy 340.280498 -274.580604) (xy 340.281006 -274.580604)
			(xy 340.306336 -274.581102) (xy 340.356347 -274.58919) (xy 340.40442 -274.605173) (xy 340.449318 -274.62864)
			(xy 340.489884 -274.658985) (xy 340.507828 -274.67687) (xy 340.512654 -274.678648) (xy 340.58479 -274.676616)
			(xy 340.594367 -274.675929) (xy 340.611998 -274.668365) (xy 340.61908 -274.661884) (xy 340.729062 -274.551902)
			(xy 340.731856 -274.548854) (xy 340.737715 -274.541272) (xy 340.743841 -274.523131) (xy 340.743794 -274.513548)
			(xy 340.742016 -274.502118) (xy 340.72195 -274.43176) (xy 340.71941 -274.42287) (xy 340.717313 -274.41651)
			(xy 340.710355 -274.405074) (xy 340.705694 -274.400264) (xy 340.704424 -274.398994) (xy 340.683342 -274.394422)
			(xy 340.660234 -274.388887) (xy 340.61589 -274.371816) (xy 340.574606 -274.348291) (xy 340.537314 -274.318843)
			(xy 340.504859 -274.284138) (xy 340.477973 -274.24496) (xy 340.457263 -274.202194) (xy 340.443197 -274.156807)
			(xy 340.436095 -274.109824) (xy 340.435692 -274.086066) (xy 340.43618 -274.061271) (xy 340.443939 -274.012292)
			(xy 340.45926 -273.965129) (xy 340.481766 -273.920941) (xy 340.510905 -273.880815) (xy 340.545958 -273.845739)
			(xy 340.586065 -273.816574) (xy 340.630238 -273.794039) (xy 340.677392 -273.778687) (xy 340.726366 -273.770897)
			(xy 340.75116 -273.770344) (xy 340.77493 -273.770771) (xy 340.821933 -273.777892) (xy 340.867337 -273.791978)
			(xy 340.910117 -273.812712) (xy 340.949305 -273.839625) (xy 340.984015 -273.872108) (xy 341.013464 -273.909428)
			(xy 341.036985 -273.950741) (xy 341.054048 -273.995113) (xy 341.059516 -274.018248) (xy 341.06104 -274.02536)
			(xy 341.062722 -274.032165) (xy 341.069303 -274.044534) (xy 341.073994 -274.049744) (xy 341.074756 -274.050506)
			(xy 341.096854 -274.056856) (xy 341.167212 -274.076922) (xy 341.178642 -274.0787) (xy 341.188228 -274.078776)
			(xy 341.206374 -274.072639) (xy 341.213948 -274.066762) (xy 341.216996 -274.063968) (xy 341.553038 -273.727926)
			(xy 341.557102 -273.717258) (xy 341.575322 -273.668953) (xy 341.619502 -273.575634) (xy 341.672143 -273.486813)
			(xy 341.732793 -273.403255) (xy 341.800927 -273.32568) (xy 341.838026 -273.289776) (xy 341.838788 -273.289014)
			(xy 341.845646 -273.27987) (xy 341.845392 -273.277838) (xy 341.845392 -273.274282) (xy 341.846132 -273.247116)
			(xy 341.855774 -273.193639) (xy 341.874427 -273.142601) (xy 341.90154 -273.095509) (xy 341.936313 -273.053752)
			(xy 341.97772 -273.018563) (xy 342.00084 -273.00428) (xy 342.00973 -272.998946) (xy 342.016588 -272.989802)
			(xy 342.019251 -272.986016) (xy 342.023343 -272.977713) (xy 342.024716 -272.973292) (xy 342.037703 -272.928863)
			(xy 342.070058 -272.84213) (xy 342.10947 -272.758368) (xy 342.132158 -272.718022) (xy 342.155851 -272.67781)
			(xy 342.208982 -272.601066) (xy 342.268327 -272.529019) (xy 342.30056 -272.495264) (xy 342.307164 -272.48866)
			(xy 342.315292 -272.469864) (xy 342.315546 -272.459958) (xy 342.316627 -272.433171) (xy 342.326695 -272.380521)
			(xy 342.345516 -272.330328) (xy 342.372547 -272.284038) (xy 342.407012 -272.242981) (xy 342.447919 -272.208339)
			(xy 342.47074 -272.194274) (xy 342.47963 -272.18894) (xy 342.486488 -272.179796) (xy 342.489151 -272.176009)
			(xy 342.493242 -272.167706) (xy 342.494616 -272.163286) (xy 342.508542 -272.115846) (xy 342.543641 -272.023408)
			(xy 342.586763 -271.934428) (xy 342.63757 -271.849603) (xy 342.695667 -271.769593) (xy 342.760599 -271.695023)
			(xy 342.79586 -271.660366) (xy 342.79586 -271.656048) (xy 342.796114 -271.643602) (xy 342.796368 -271.637252)
			(xy 342.796368 -271.636998) (xy 342.798389 -271.612703) (xy 342.809166 -271.565162) (xy 342.827353 -271.519934)
			(xy 342.852487 -271.478166) (xy 342.883933 -271.440917) (xy 342.920892 -271.409131) (xy 342.941402 -271.395952)
			(xy 342.947568 -271.391149) (xy 342.956884 -271.378609) (xy 342.95969 -271.371314) (xy 342.971636 -271.327754)
			(xy 343.001637 -271.24255) (xy 343.038412 -271.160043) (xy 343.081722 -271.08077) (xy 343.131285 -271.00525)
			(xy 343.186778 -270.933973) (xy 343.216992 -270.900398) (xy 343.223596 -270.893032) (xy 343.226898 -270.884396)
			(xy 343.228521 -270.879932) (xy 343.230304 -270.870602) (xy 343.230454 -270.865854) (xy 343.230454 -270.543782)
			(xy 343.23098 -270.533939) (xy 343.238548 -270.51576) (xy 343.245186 -270.508476) (xy 343.717626 -270.036036)
			(xy 343.7255 -270.025876) (xy 343.72677 -270.009874) (xy 343.729337 -269.984876) (xy 343.741386 -269.936094)
			(xy 343.761017 -269.889838) (xy 343.787733 -269.84728) (xy 343.820859 -269.809497) (xy 343.859557 -269.777443)
			(xy 343.880948 -269.764256) (xy 343.889838 -269.758922) (xy 343.896696 -269.749778) (xy 343.899357 -269.745991)
			(xy 343.903445 -269.737687) (xy 343.904824 -269.733268) (xy 343.912596 -269.706216) (xy 343.930513 -269.652851)
			(xy 343.940638 -269.626588) (xy 343.957563 -269.584792) (xy 343.99724 -269.503809) (xy 344.04331 -269.426284)
			(xy 344.095473 -269.35272) (xy 344.153391 -269.283597) (xy 344.184732 -269.251176) (xy 344.189558 -269.24635)
			(xy 344.191336 -269.244572) (xy 344.206068 -269.211552) (xy 344.206068 -269.211298) (xy 344.206576 -269.204694)
			(xy 344.206576 -269.202662) (xy 344.208867 -269.178731) (xy 344.220016 -269.131969) (xy 344.23835 -269.08753)
			(xy 344.263417 -269.04651) (xy 344.294599 -269.009922) (xy 344.331125 -268.978669) (xy 344.351356 -268.96568)
			(xy 344.357579 -268.96089) (xy 344.367016 -268.948347) (xy 344.369898 -268.941042) (xy 344.375694 -268.919547)
			(xy 344.388777 -268.876989) (xy 344.39606 -268.855952) (xy 344.411552 -268.813094) (xy 344.448552 -268.729805)
			(xy 344.469974 -268.689582) (xy 344.474546 -268.677898) (xy 344.476324 -268.67104) (xy 344.477633 -268.665283)
			(xy 344.477884 -268.653482) (xy 344.476832 -268.647672) (xy 344.475054 -268.639036) (xy 344.473022 -268.634464)
			(xy 344.46591 -268.616938) (xy 344.46591 -268.616684) (xy 344.463286 -268.610388) (xy 344.455173 -268.59943)
			(xy 344.449908 -268.595094) (xy 344.444828 -268.59103) (xy 344.432128 -268.585696) (xy 344.336116 -268.573758)
			(xy 344.329378 -268.573176) (xy 344.315995 -268.575096) (xy 344.3097 -268.577568) (xy 344.303858 -268.580108)
			(xy 344.29319 -268.588744) (xy 344.288872 -268.594586) (xy 344.274417 -268.613857) (xy 344.240458 -268.648022)
			(xy 344.201556 -268.67643) (xy 344.158675 -268.698378) (xy 344.11288 -268.713321) (xy 344.065307 -268.720888)
			(xy 344.041222 -268.721332) (xy 344.015961 -268.720841) (xy 343.966128 -268.712529) (xy 343.918343 -268.696127)
			(xy 343.873909 -268.672083) (xy 343.834039 -268.641054) (xy 343.79982 -268.603885) (xy 343.772186 -268.561591)
			(xy 343.751891 -268.515325) (xy 343.739488 -268.466349) (xy 343.735316 -268.416) (xy 343.739488 -268.365651)
			(xy 343.751891 -268.316675) (xy 343.772186 -268.270409) (xy 343.79982 -268.228115) (xy 343.834039 -268.190946)
			(xy 343.873909 -268.159917) (xy 343.918343 -268.135873) (xy 343.966128 -268.119471) (xy 344.015961 -268.111159)
			(xy 344.041222 -268.110716) (xy 344.065306 -268.111171) (xy 344.112876 -268.118739) (xy 344.158667 -268.133683)
			(xy 344.201544 -268.155632) (xy 344.240442 -268.184042) (xy 344.274395 -268.218208) (xy 344.288872 -268.237462)
			(xy 344.289126 -268.237716) (xy 344.293307 -268.243171) (xy 344.303989 -268.251809) (xy 344.310208 -268.254734)
			(xy 344.31605 -268.257274) (xy 344.329258 -268.259306) (xy 344.42527 -268.247114) (xy 344.432103 -268.24609)
			(xy 344.444865 -268.240813) (xy 344.450416 -268.2367) (xy 344.455496 -268.232636) (xy 344.46337 -268.221968)
			(xy 344.46591 -268.21511) (xy 344.47712 -268.187586) (xy 344.504614 -268.134895) (xy 344.520774 -268.109954)
			(xy 344.541931 -268.079123) (xy 344.591249 -268.022921) (xy 344.619072 -267.99794) (xy 344.622986 -267.994363)
			(xy 344.629386 -267.985911) (xy 344.631772 -267.981176) (xy 344.645488 -267.951966) (xy 344.644995 -267.941186)
			(xy 344.636162 -267.921517) (xy 344.620056 -267.907182) (xy 344.609928 -267.903452) (xy 344.606086 -267.90235)
			(xy 344.598177 -267.901205) (xy 344.59418 -267.901166) (xy 344.58275 -267.90269) (xy 344.56524 -267.90668)
			(xy 344.529586 -267.911008) (xy 344.51163 -267.911326) (xy 344.509852 -267.911326) (xy 344.485924 -267.910762)
			(xy 344.438682 -267.903102) (xy 344.393214 -267.888165) (xy 344.350633 -267.866316) (xy 344.311982 -267.838091)
			(xy 344.278209 -267.804181) (xy 344.25014 -267.765417) (xy 344.228463 -267.722749) (xy 344.213709 -267.67722)
			(xy 344.206239 -267.629948) (xy 344.205814 -267.606018) (xy 344.206259 -267.582025) (xy 344.213763 -267.534628)
			(xy 344.228591 -267.48899) (xy 344.250375 -267.446232) (xy 344.278581 -267.40741) (xy 344.312513 -267.373479)
			(xy 344.351336 -267.345273) (xy 344.394093 -267.323489) (xy 344.439732 -267.308663) (xy 344.487129 -267.301159)
			(xy 344.511122 -267.30071) (xy 344.511376 -267.30071) (xy 344.534225 -267.301109) (xy 344.579414 -267.307913)
			(xy 344.623081 -267.321387) (xy 344.664247 -267.341229) (xy 344.683334 -267.353796) (xy 344.689176 -267.35786)
			(xy 344.703908 -267.362686) (xy 344.707725 -267.363948) (xy 344.715638 -267.365355) (xy 344.719656 -267.36548)
			(xy 344.72979 -267.365092) (xy 344.748526 -267.357372) (xy 344.755978 -267.350494) (xy 344.88882 -267.217652)
			(xy 344.89606 -267.210944) (xy 344.914265 -267.203359) (xy 344.924126 -267.20292) (xy 347.165168 -267.20292)
			(xy 347.175006 -267.202385) (xy 347.19317 -267.194801) (xy 347.200474 -267.188188) (xy 347.488002 -266.90066)
			(xy 347.492249 -266.896185) (xy 347.498681 -266.88566) (xy 347.500702 -266.879832) (xy 347.50248 -266.874244)
			(xy 347.502988 -266.861798) (xy 347.501718 -266.855194) (xy 347.498993 -266.84055) (xy 347.496062 -266.810906)
			(xy 347.495876 -266.796012) (xy 347.496346 -266.77202) (xy 347.50385 -266.724626) (xy 347.518676 -266.678989)
			(xy 347.540459 -266.636233) (xy 347.568662 -266.597412) (xy 347.602591 -266.56348) (xy 347.64141 -266.535274)
			(xy 347.684163 -266.513487) (xy 347.729798 -266.498657) (xy 347.777192 -266.491148) (xy 347.801184 -266.490704)
			(xy 347.816078 -266.490897) (xy 347.845721 -266.493827) (xy 347.860366 -266.496546) (xy 347.86062 -266.496546)
			(xy 347.866839 -266.497583) (xy 347.879427 -266.49693) (xy 347.885512 -266.495276) (xy 347.896942 -266.49172)
			(xy 348.050612 -266.33805) (xy 348.057164 -266.330724) (xy 348.06462 -266.31256) (xy 348.06509 -266.302744)
			(xy 348.065344 -266.262104) (xy 348.065344 -266.241276) (xy 348.0651 -266.236911) (xy 348.063313 -266.228355)
			(xy 348.061788 -266.224258) (xy 348.061788 -266.224004) (xy 348.061534 -266.223496) (xy 348.051628 -266.19835)
			(xy 348.045024 -266.191492) (xy 348.030159 -266.17456) (xy 348.005058 -266.137144) (xy 347.98573 -266.096445)
			(xy 347.972593 -266.053348) (xy 347.965933 -266.008787) (xy 347.965522 -265.98626) (xy 347.965522 -265.985752)
			(xy 347.965776 -265.97102) (xy 347.967046 -265.957558) (xy 347.969887 -265.932636) (xy 347.98266 -265.884134)
			(xy 348.003189 -265.838372) (xy 348.030922 -265.796582) (xy 348.065114 -265.759886) (xy 348.104843 -265.729273)
			(xy 348.149043 -265.705566) (xy 348.196523 -265.689403) (xy 348.246006 -265.681218) (xy 348.271084 -265.680698)
			(xy 348.284546 -265.680698) (xy 348.311003 -265.682461) (xy 348.362762 -265.693948) (xy 348.411768 -265.714181)
			(xy 348.456555 -265.742553) (xy 348.47657 -265.759946) (xy 348.483428 -265.76655) (xy 348.508574 -265.776456)
			(xy 348.509082 -265.77671) (xy 348.509336 -265.77671) (xy 348.513431 -265.778242) (xy 348.521988 -265.78003)
			(xy 348.526354 -265.780266) (xy 348.546674 -265.780266) (xy 348.547182 -265.780266) (xy 348.587822 -265.780012)
			(xy 348.59763 -265.779507) (xy 348.615782 -265.772054) (xy 348.623128 -265.765534) (xy 348.876874 -265.511788)
			(xy 349.129858 -265.25855) (xy 349.130366 -265.258042) (xy 349.136946 -265.25066) (xy 349.144393 -265.232361)
			(xy 349.144844 -265.222482) (xy 349.144844 -265.094466) (xy 349.144679 -265.088456) (xy 349.141861 -265.076771)
			(xy 349.139256 -265.071352) (xy 349.137413 -265.06788) (xy 349.132814 -265.061507) (xy 349.130112 -265.058652)
			(xy 348.754446 -264.682986) (xy 348.747597 -264.675589) (xy 348.73986 -264.65699) (xy 348.73946 -264.646918)
			(xy 348.73946 -264.038842) (xy 348.739895 -264.028778) (xy 348.747631 -264.010194) (xy 348.754446 -264.002774)
			(xy 349.852996 -262.904224) (xy 349.857957 -262.898976) (xy 349.864913 -262.886327) (xy 349.866712 -262.879332)
			(xy 349.867982 -262.872728) (xy 349.866966 -262.85825) (xy 349.864426 -262.851138) (xy 349.855778 -262.82591)
			(xy 349.846455 -262.773406) (xy 349.845884 -262.746744) (xy 349.845884 -262.745982) (xy 349.846356 -262.721991)
			(xy 349.853864 -262.674601) (xy 349.868693 -262.628969) (xy 349.890478 -262.586219) (xy 349.918681 -262.547402)
			(xy 349.952609 -262.513475) (xy 349.991427 -262.485272) (xy 350.034179 -262.463489) (xy 350.079811 -262.448662)
			(xy 350.127201 -262.441155) (xy 350.151192 -262.440674) (xy 350.151954 -262.440674) (xy 350.178611 -262.441303)
			(xy 350.231104 -262.45063) (xy 350.256348 -262.459216) (xy 350.263341 -262.461566) (xy 350.278052 -262.462604)
			(xy 350.285304 -262.461248) (xy 350.291908 -262.459724) (xy 350.304354 -262.452866) (xy 350.43491 -262.32231)
			(xy 350.441524 -262.315007) (xy 350.449103 -262.296842) (xy 350.449642 -262.287004) (xy 350.447102 -262.234172)
			(xy 350.445832 -262.208518) (xy 350.445426 -262.203238) (xy 350.442731 -262.193) (xy 350.440498 -262.188198)
			(xy 350.435926 -262.179054) (xy 350.42729 -262.171942) (xy 350.406797 -262.154372) (xy 350.371751 -262.113321)
			(xy 350.344469 -262.066748) (xy 350.325803 -262.016103) (xy 350.316333 -261.962964) (xy 350.315784 -261.935976)
			(xy 350.316256 -261.911986) (xy 350.323765 -261.864597) (xy 350.338595 -261.818965) (xy 350.36038 -261.776215)
			(xy 350.388583 -261.737399) (xy 350.422511 -261.703473) (xy 350.461329 -261.675271) (xy 350.50408 -261.653489)
			(xy 350.549712 -261.638662) (xy 350.597102 -261.631155) (xy 350.621092 -261.630668) (xy 350.645366 -261.631135)
			(xy 350.693303 -261.638814) (xy 350.739422 -261.653979) (xy 350.782561 -261.676249) (xy 350.821634 -261.705062)
			(xy 350.855658 -261.739694) (xy 350.883774 -261.779272) (xy 350.894904 -261.800848) (xy 350.897952 -261.807198)
			(xy 350.907604 -261.817612) (xy 350.9137 -261.821422) (xy 350.919806 -261.824923) (xy 350.933336 -261.828785)
			(xy 350.94037 -261.829042) (xy 352.542602 -261.829042) (xy 352.556572 -261.82701) (xy 352.562922 -261.825232)
			(xy 352.569018 -261.821676) (xy 352.569272 -261.821422) (xy 352.575176 -261.818148) (xy 352.588179 -261.814539)
			(xy 352.594926 -261.81431) (xy 353.569778 -261.81431) (xy 353.579615 -261.813773) (xy 353.597775 -261.806185)
			(xy 353.605084 -261.799578) (xy 353.75342 -261.651242) (xy 353.760661 -261.644535) (xy 353.778865 -261.636951)
			(xy 353.788726 -261.63651) (xy 354.11156 -261.63651) (xy 354.120454 -261.636112) (xy 354.137115 -261.629872)
			(xy 354.144072 -261.624318) (xy 354.152708 -261.615936) (xy 354.157687 -261.610817) (xy 354.164797 -261.59844)
			(xy 354.166678 -261.591552) (xy 354.1676 -261.587234) (xy 354.168112 -261.578421) (xy 354.167694 -261.574026)
			(xy 354.164392 -261.5438) (xy 354.163724 -261.538537) (xy 354.160527 -261.528421) (xy 354.158042 -261.523734)
			(xy 354.152708 -261.51459) (xy 354.143818 -261.50824) (xy 354.122219 -261.491978) (xy 354.083937 -261.453801)
			(xy 354.052111 -261.410098) (xy 354.027526 -261.361947) (xy 354.01079 -261.310538) (xy 354.002316 -261.257142)
			(xy 354.001832 -261.23011) (xy 354.0023 -261.204564) (xy 354.009867 -261.154035) (xy 354.024835 -261.105185)
			(xy 354.046875 -261.059091) (xy 354.0755 -261.016771) (xy 354.110079 -260.979157) (xy 354.149847 -260.947081)
			(xy 354.193929 -260.921251) (xy 354.217478 -260.91134) (xy 354.22713 -260.90753) (xy 354.343716 -260.790944)
			(xy 354.349661 -260.784557) (xy 354.357187 -260.768828) (xy 354.358949 -260.751481) (xy 354.357178 -260.742938)
			(xy 354.328476 -260.653276) (xy 354.326141 -260.64675) (xy 354.318535 -260.63517) (xy 354.31349 -260.630416)
			(xy 354.30841 -260.626098) (xy 354.295456 -260.620002) (xy 354.288598 -260.618986) (xy 354.262233 -260.61403)
			(xy 354.211356 -260.597025) (xy 354.163738 -260.572323) (xy 354.120536 -260.540524) (xy 354.082798 -260.502399)
			(xy 354.05144 -260.458875) (xy 354.027224 -260.411008) (xy 354.010738 -260.359961) (xy 354.002381 -260.306972)
			(xy 354.001832 -260.28015) (xy 354.002312 -260.254451) (xy 354.009973 -260.203627) (xy 354.025122 -260.154513)
			(xy 354.047423 -260.108205) (xy 354.076376 -260.065738) (xy 354.111336 -260.028061) (xy 354.15152 -259.996015)
			(xy 354.196032 -259.970316) (xy 354.243877 -259.951539) (xy 354.293986 -259.940101) (xy 354.34524 -259.936261)
			(xy 354.396494 -259.940101) (xy 354.446603 -259.951539) (xy 354.494448 -259.970316) (xy 354.53896 -259.996015)
			(xy 354.579144 -260.028061) (xy 354.614104 -260.065738) (xy 354.643057 -260.108205) (xy 354.665358 -260.154513)
			(xy 354.680507 -260.203627) (xy 354.688168 -260.254451) (xy 354.688648 -260.28015) (xy 354.688648 -260.280912)
			(xy 354.688562 -260.290713) (xy 354.687416 -260.310283) (xy 354.686362 -260.320028) (xy 354.685092 -260.33222)
			(xy 354.688648 -260.34238) (xy 354.690709 -260.347821) (xy 354.696865 -260.35769) (xy 354.70084 -260.361938)
			(xy 354.702618 -260.363716) (xy 354.710108 -260.369894) (xy 354.728307 -260.376617) (xy 354.747701 -260.376116)
			(xy 354.765528 -260.368462) (xy 354.772722 -260.361938) (xy 354.810314 -260.324346) (xy 354.817711 -260.317497)
			(xy 354.83631 -260.30976) (xy 354.846382 -260.30936) (xy 355.952298 -260.30936) (xy 355.96195 -260.308344)
			(xy 355.969194 -260.306716) (xy 355.982361 -260.299872) (xy 355.987858 -260.294882) (xy 356.221538 -260.061202)
			(xy 356.226526 -260.055703) (xy 356.233372 -260.042537) (xy 356.235 -260.035294) (xy 356.236016 -260.025642)
			(xy 356.236016 -258.32562) (xy 356.236454 -258.315557) (xy 356.244191 -258.296975) (xy 356.251002 -258.289552)
			(xy 356.251256 -258.289298) (xy 356.272592 -258.267708) (xy 356.27875 -258.260506) (xy 356.285681 -258.242885)
			(xy 356.286054 -258.233418) (xy 356.286054 -258.04368) (xy 356.285292 -258.035044) (xy 356.28276 -258.023546)
			(xy 356.269001 -258.004473) (xy 356.258876 -257.998468) (xy 356.253542 -257.996182) (xy 356.17277 -257.965194)
			(xy 356.163268 -257.961988) (xy 356.143237 -257.962528) (xy 356.133908 -257.96621) (xy 356.112572 -257.975608)
			(xy 356.109016 -257.979164) (xy 356.10546 -257.982974) (xy 356.085876 -258.002529) (xy 356.041614 -258.035745)
			(xy 355.992601 -258.061439) (xy 355.940104 -258.078946) (xy 355.88548 -258.087816) (xy 355.85781 -258.088384)
			(xy 355.832111 -258.087929) (xy 355.781286 -258.080269) (xy 355.73217 -258.06512) (xy 355.685861 -258.04282)
			(xy 355.643393 -258.013867) (xy 355.605714 -257.978908) (xy 355.573667 -257.938723) (xy 355.547968 -257.894211)
			(xy 355.529189 -257.846365) (xy 355.517752 -257.796255) (xy 355.51391 -257.745) (xy 355.517752 -257.693745)
			(xy 355.529189 -257.643635) (xy 355.547968 -257.595789) (xy 355.573667 -257.551277) (xy 355.605714 -257.511092)
			(xy 355.643393 -257.476133) (xy 355.685861 -257.44718) (xy 355.73217 -257.42488) (xy 355.781286 -257.409731)
			(xy 355.832111 -257.402071) (xy 355.85781 -257.401568) (xy 355.884594 -257.402082) (xy 355.937513 -257.410398)
			(xy 355.9885 -257.426828) (xy 356.036318 -257.450973) (xy 356.079809 -257.482248) (xy 356.117919 -257.519895)
			(xy 356.149723 -257.563) (xy 356.174451 -257.61052) (xy 356.183438 -257.635756) (xy 356.185978 -257.643122)
			(xy 356.19055 -257.649472) (xy 356.192763 -257.652319) (xy 356.197861 -257.65742) (xy 356.20071 -257.659632)
			(xy 356.204774 -257.662934) (xy 356.212533 -257.668222) (xy 356.23059 -257.673313) (xy 356.249267 -257.671548)
			(xy 356.25786 -257.66776) (xy 356.258114 -257.667506) (xy 356.264317 -257.6642) (xy 356.274749 -257.654786)
			(xy 356.278688 -257.648964) (xy 356.282244 -257.643376) (xy 356.286054 -257.62966) (xy 356.286054 -257.491992)
			(xy 356.285892 -257.485981) (xy 356.28308 -257.474293) (xy 356.280466 -257.468878) (xy 356.278625 -257.465405)
			(xy 356.274029 -257.459028) (xy 356.271322 -257.456178) (xy 355.94671 -257.131566) (xy 355.94386 -257.128858)
			(xy 355.937484 -257.124262) (xy 355.93401 -257.122422) (xy 355.928582 -257.119843) (xy 355.916903 -257.117029)
			(xy 355.910896 -257.116834) (xy 354.734622 -257.116834) (xy 354.733606 -257.116834) (xy 354.721534 -257.117767)
			(xy 354.700213 -257.129171) (xy 354.692712 -257.138678) (xy 354.690934 -257.141726) (xy 354.6475 -257.215386)
			(xy 354.644337 -257.221128) (xy 354.640741 -257.233731) (xy 354.640388 -257.240278) (xy 354.640134 -257.253486)
			(xy 354.646738 -257.265424) (xy 354.659784 -257.290571) (xy 354.678371 -257.344083) (xy 354.687939 -257.399917)
			(xy 354.688648 -257.428238) (xy 354.688648 -257.434334) (xy 354.687799 -257.461097) (xy 354.678825 -257.513883)
			(xy 354.661768 -257.564637) (xy 354.637041 -257.612129) (xy 354.605243 -257.655208) (xy 354.567145 -257.69283)
			(xy 354.523669 -257.724083) (xy 354.475871 -257.748211) (xy 354.424906 -257.764629) (xy 354.372012 -257.772939)
			(xy 354.318468 -257.772939) (xy 354.265574 -257.764629) (xy 354.214609 -257.748211) (xy 354.166811 -257.724083)
			(xy 354.123335 -257.69283) (xy 354.085237 -257.655208) (xy 354.053439 -257.612129) (xy 354.028712 -257.564637)
			(xy 354.011655 -257.513883) (xy 354.002681 -257.461097) (xy 354.001832 -257.434334) (xy 354.001832 -257.429762)
			(xy 354.002398 -257.401181) (xy 354.011868 -257.344809) (xy 354.030555 -257.290787) (xy 354.043742 -257.265424)
			(xy 354.046821 -257.259471) (xy 354.050054 -257.246471) (xy 354.050092 -257.23977) (xy 354.049838 -257.226816)
			(xy 353.999546 -257.141726) (xy 353.997768 -257.138678) (xy 353.99033 -257.129103) (xy 353.968969 -257.117713)
			(xy 353.956874 -257.116834) (xy 353.71913 -257.116834) (xy 353.717352 -257.11531) (xy 348.911926 -257.11531)
			(xy 348.902089 -257.114774) (xy 348.883927 -257.107187) (xy 348.87662 -257.100578) (xy 348.144084 -256.368042)
			(xy 348.141233 -256.365337) (xy 348.134854 -256.360745) (xy 348.131384 -256.358898) (xy 348.125958 -256.356312)
			(xy 348.114278 -256.353482) (xy 348.10827 -256.35331) (xy 347.394276 -256.35331) (xy 347.385636 -256.353644)
			(xy 347.369341 -256.359392) (xy 347.355901 -256.370252) (xy 347.351096 -256.37744) (xy 347.3069 -256.449322)
			(xy 347.303761 -256.45488) (xy 347.300046 -256.467088) (xy 347.299534 -256.473452) (xy 347.298772 -256.48666)
			(xy 347.304614 -256.498598) (xy 347.314636 -256.519788) (xy 347.328783 -256.564474) (xy 347.335938 -256.610798)
			(xy 347.336364 -256.634234) (xy 347.335915 -256.658224) (xy 347.328404 -256.705613) (xy 347.313572 -256.751243)
			(xy 347.291784 -256.793991) (xy 347.263577 -256.832805) (xy 347.229645 -256.866728) (xy 347.190825 -256.894925)
			(xy 347.148071 -256.916702) (xy 347.102437 -256.931522) (xy 347.055046 -256.939021) (xy 347.031056 -256.939542)
			(xy 347.006819 -256.939074) (xy 346.958953 -256.93141) (xy 346.912899 -256.916283) (xy 346.869812 -256.894071)
			(xy 346.830775 -256.865332) (xy 346.796766 -256.830789) (xy 346.768641 -256.791307) (xy 346.747105 -256.747878)
			(xy 346.732699 -256.701593) (xy 346.728796 -256.677668) (xy 346.727018 -256.664714) (xy 346.725494 -256.634234)
			(xy 346.725494 -256.633726) (xy 346.725961 -256.610335) (xy 346.733133 -256.564104) (xy 346.747267 -256.519506)
			(xy 346.757244 -256.498344) (xy 346.760292 -256.492502) (xy 346.763086 -256.479548) (xy 346.762832 -256.473452)
			(xy 346.762276 -256.467073) (xy 346.758414 -256.454868) (xy 346.755212 -256.449322) (xy 346.711016 -256.37744)
			(xy 346.706188 -256.370271) (xy 346.692749 -256.359422) (xy 346.676471 -256.353647) (xy 346.667836 -256.35331)
			(xy 345.514422 -256.35331) (xy 345.505787 -256.353653) (xy 345.489505 -256.359412) (xy 345.47608 -256.370277)
			(xy 345.471242 -256.37744) (xy 345.427046 -256.449322) (xy 345.423904 -256.454879) (xy 345.420186 -256.467088)
			(xy 345.41968 -256.473452) (xy 345.418918 -256.48666) (xy 345.42476 -256.498598) (xy 345.43478 -256.519788)
			(xy 345.448926 -256.564475) (xy 345.45608 -256.610798) (xy 345.45651 -256.634234) (xy 345.456037 -256.658224)
			(xy 345.448527 -256.705611) (xy 345.433696 -256.751241) (xy 345.411911 -256.793989) (xy 345.383707 -256.832803)
			(xy 345.349779 -256.866728) (xy 345.310962 -256.894928) (xy 345.268211 -256.916708) (xy 345.22258 -256.931534)
			(xy 345.175192 -256.939039) (xy 345.151202 -256.939542) (xy 345.126962 -256.939077) (xy 345.079091 -256.93142)
			(xy 345.033031 -256.916296) (xy 344.989938 -256.894087) (xy 344.950894 -256.86535) (xy 344.91688 -256.830805)
			(xy 344.88875 -256.791322) (xy 344.86721 -256.747891) (xy 344.852801 -256.701602) (xy 344.848942 -256.677668)
			(xy 344.847164 -256.664714) (xy 344.84564 -256.634234) (xy 344.84564 -256.633726) (xy 344.846106 -256.610334)
			(xy 344.853277 -256.564103) (xy 344.867409 -256.519504) (xy 344.87739 -256.498344) (xy 344.880438 -256.492502)
			(xy 344.883232 -256.479548) (xy 344.882978 -256.473452) (xy 344.882423 -256.467072) (xy 344.878564 -256.454866)
			(xy 344.875358 -256.449322) (xy 344.831162 -256.37744) (xy 344.826337 -256.370266) (xy 344.812899 -256.359405)
			(xy 344.79662 -256.353616) (xy 344.787982 -256.35331) (xy 344.253566 -256.35331) (xy 344.243725 -256.352781)
			(xy 344.225554 -256.345204) (xy 344.21826 -256.338578) (xy 343.971118 -256.091436) (xy 343.96476 -256.085599)
			(xy 343.94918 -256.078196) (xy 343.940638 -256.076958) (xy 343.931748 -256.075942) (xy 343.911097 -256.090923)
			(xy 343.865972 -256.114719) (xy 343.817608 -256.13095) (xy 343.767263 -256.139194) (xy 343.741756 -256.139696)
			(xy 343.740994 -256.139696) (xy 343.716202 -256.139209) (xy 343.66723 -256.131452) (xy 343.620074 -256.116129)
			(xy 343.575895 -256.093619) (xy 343.535782 -256.064474) (xy 343.500722 -256.029413) (xy 343.471578 -255.989299)
			(xy 343.449068 -255.94512) (xy 343.433746 -255.897964) (xy 343.42599 -255.848992) (xy 343.42599 -255.799408)
			(xy 343.433746 -255.750436) (xy 343.449068 -255.70328) (xy 343.471578 -255.659101) (xy 343.500722 -255.618987)
			(xy 343.535782 -255.583926) (xy 343.575895 -255.554781) (xy 343.620074 -255.532271) (xy 343.66723 -255.516948)
			(xy 343.716202 -255.509191) (xy 343.740994 -255.50876) (xy 343.763796 -255.509122) (xy 343.808934 -255.515621)
			(xy 343.83091 -255.521714) (xy 343.854786 -255.528826) (xy 343.85631 -255.528572) (xy 343.930478 -255.471676)
			(xy 343.938572 -255.464135) (xy 343.947922 -255.444114) (xy 343.948512 -255.433068) (xy 343.948512 -255.183386)
			(xy 343.946988 -255.171194) (xy 343.945464 -255.165098) (xy 343.942416 -255.159256) (xy 343.942162 -255.159002)
			(xy 343.931121 -255.13749) (xy 343.915226 -255.091826) (xy 343.906724 -255.044227) (xy 343.90584 -255.020064)
			(xy 343.90584 -255.014222) (xy 343.906366 -254.989025) (xy 343.914642 -254.939314) (xy 343.930943 -254.891628)
			(xy 343.942416 -254.869188) (xy 343.945235 -254.863558) (xy 343.948309 -254.851352) (xy 343.948512 -254.845058)
			(xy 343.948512 -254.595376) (xy 343.947873 -254.584149) (xy 343.938268 -254.563846) (xy 343.92997 -254.55626)
			(xy 343.90711 -254.538734) (xy 343.865962 -254.507238) (xy 343.863025 -254.505064) (xy 343.856649 -254.501496)
			(xy 343.853262 -254.500126) (xy 343.83091 -254.50673) (xy 343.80893 -254.512806) (xy 343.763795 -254.519309)
			(xy 343.740994 -254.519684) (xy 343.716203 -254.519198) (xy 343.667233 -254.51144) (xy 343.620079 -254.496118)
			(xy 343.575902 -254.473608) (xy 343.53579 -254.444465) (xy 343.500731 -254.409405) (xy 343.471588 -254.369293)
			(xy 343.449079 -254.325116) (xy 343.433758 -254.277961) (xy 343.426002 -254.228991) (xy 343.426002 -254.179409)
			(xy 343.433758 -254.130439) (xy 343.449079 -254.083284) (xy 343.471588 -254.039107) (xy 343.500731 -253.998995)
			(xy 343.53579 -253.963935) (xy 343.575902 -253.934792) (xy 343.620079 -253.912282) (xy 343.667233 -253.89696)
			(xy 343.716203 -253.889202) (xy 343.740994 -253.888748) (xy 343.763796 -253.88911) (xy 343.808934 -253.895608)
			(xy 343.83091 -253.901702) (xy 343.854786 -253.908814) (xy 343.85631 -253.90856) (xy 343.930478 -253.851664)
			(xy 343.93857 -253.844123) (xy 343.947915 -253.824102) (xy 343.948512 -253.813056) (xy 343.948512 -253.563374)
			(xy 343.946988 -253.551182) (xy 343.945464 -253.545086) (xy 343.942416 -253.539244) (xy 343.942162 -253.53899)
			(xy 343.931122 -253.517477) (xy 343.915229 -253.471813) (xy 343.906729 -253.424215) (xy 343.90584 -253.400052)
			(xy 343.90584 -253.39421) (xy 343.906359 -253.369011) (xy 343.914622 -253.319295) (xy 343.930911 -253.271601)
			(xy 343.942416 -253.249176) (xy 343.945234 -253.243546) (xy 343.948304 -253.231339) (xy 343.948512 -253.225046)
			(xy 343.948512 -252.975364) (xy 343.947871 -252.964139) (xy 343.938262 -252.943839) (xy 343.92997 -252.936248)
			(xy 343.90711 -252.918722) (xy 343.865962 -252.887226) (xy 343.863025 -252.885053) (xy 343.856649 -252.881485)
			(xy 343.853262 -252.880114) (xy 343.83091 -252.886718) (xy 343.80893 -252.892794) (xy 343.763795 -252.899297)
			(xy 343.740994 -252.899672) (xy 343.716204 -252.899186) (xy 343.667236 -252.891429) (xy 343.620083 -252.876107)
			(xy 343.575908 -252.853598) (xy 343.535798 -252.824456) (xy 343.50074 -252.789398) (xy 343.471599 -252.749287)
			(xy 343.44909 -252.705111) (xy 343.43377 -252.657959) (xy 343.426014 -252.60899) (xy 343.426014 -252.55941)
			(xy 343.43377 -252.510441) (xy 343.44909 -252.463289) (xy 343.471599 -252.419113) (xy 343.50074 -252.379002)
			(xy 343.535798 -252.343944) (xy 343.575908 -252.314802) (xy 343.620083 -252.292293) (xy 343.667236 -252.276971)
			(xy 343.716204 -252.269214) (xy 343.740994 -252.268736) (xy 343.763796 -252.269098) (xy 343.808934 -252.275596)
			(xy 343.83091 -252.28169) (xy 343.854786 -252.288802) (xy 343.85631 -252.288548) (xy 343.930478 -252.231652)
			(xy 343.938568 -252.22411) (xy 343.947909 -252.204089) (xy 343.948512 -252.193044) (xy 343.948512 -251.943362)
			(xy 343.946988 -251.93117) (xy 343.945464 -251.925074) (xy 343.942416 -251.919232) (xy 343.942162 -251.918978)
			(xy 343.931123 -251.897465) (xy 343.915232 -251.851801) (xy 343.906733 -251.804203) (xy 343.90584 -251.78004)
			(xy 343.90584 -251.774198) (xy 343.90636 -251.748999) (xy 343.914625 -251.699284) (xy 343.930916 -251.651591)
			(xy 343.942416 -251.629164) (xy 343.945244 -251.623536) (xy 343.948335 -251.61133) (xy 343.948512 -251.605034)
			(xy 343.948512 -251.355352) (xy 343.947869 -251.344128) (xy 343.938257 -251.323832) (xy 343.92997 -251.316236)
			(xy 343.90711 -251.29871) (xy 343.865962 -251.267214) (xy 343.863025 -251.265041) (xy 343.856648 -251.261474)
			(xy 343.853262 -251.260102) (xy 343.83091 -251.266706) (xy 343.80893 -251.272782) (xy 343.763795 -251.279286)
			(xy 343.740994 -251.27966) (xy 343.716205 -251.279173) (xy 343.667239 -251.271417) (xy 343.620088 -251.256096)
			(xy 343.575915 -251.233587) (xy 343.535806 -251.204446) (xy 343.50075 -251.169389) (xy 343.471609 -251.12928)
			(xy 343.449102 -251.085106) (xy 343.433782 -251.037956) (xy 343.426026 -250.988989) (xy 343.426026 -250.939411)
			(xy 343.433782 -250.890444) (xy 343.449102 -250.843294) (xy 343.471609 -250.79912) (xy 343.50075 -250.759011)
			(xy 343.535806 -250.723954) (xy 343.575915 -250.694813) (xy 343.620088 -250.672304) (xy 343.667239 -250.656983)
			(xy 343.716205 -250.649227) (xy 343.740994 -250.648724) (xy 343.763796 -250.649086) (xy 343.808934 -250.655584)
			(xy 343.83091 -250.661678) (xy 343.854786 -250.66879) (xy 343.85631 -250.668536) (xy 343.930478 -250.61164)
			(xy 343.938566 -250.604097) (xy 343.947902 -250.584076) (xy 343.948512 -250.573032) (xy 343.948512 -250.32335)
			(xy 343.946988 -250.311158) (xy 343.945464 -250.305062) (xy 343.942416 -250.29922) (xy 343.942162 -250.298966)
			(xy 343.931124 -250.277453) (xy 343.915234 -250.231788) (xy 343.906738 -250.184191) (xy 343.90584 -250.160028)
			(xy 343.90584 -250.154186) (xy 343.906361 -250.128987) (xy 343.914628 -250.079273) (xy 343.93092 -250.031581)
			(xy 343.942416 -250.009152) (xy 343.945242 -250.003524) (xy 343.948331 -249.991317) (xy 343.948512 -249.985022)
			(xy 343.948512 -249.73534) (xy 343.947866 -249.724117) (xy 343.938251 -249.703825) (xy 343.92997 -249.696224)
			(xy 343.90711 -249.678698) (xy 343.865962 -249.647202) (xy 343.863024 -249.64503) (xy 343.856648 -249.641464)
			(xy 343.853262 -249.64009) (xy 343.83091 -249.646694) (xy 343.80893 -249.65277) (xy 343.763795 -249.659274)
			(xy 343.740994 -249.659648) (xy 343.716206 -249.659161) (xy 343.667241 -249.651405) (xy 343.620093 -249.636085)
			(xy 343.575921 -249.613577) (xy 343.535814 -249.584437) (xy 343.500759 -249.549382) (xy 343.47162 -249.509274)
			(xy 343.449113 -249.465102) (xy 343.433794 -249.417953) (xy 343.426038 -249.368988) (xy 343.426038 -249.319412)
			(xy 343.433794 -249.270447) (xy 343.449113 -249.223298) (xy 343.47162 -249.179126) (xy 343.500759 -249.139018)
			(xy 343.535814 -249.103963) (xy 343.575921 -249.074823) (xy 343.620093 -249.052315) (xy 343.667241 -249.036995)
			(xy 343.716206 -249.029239) (xy 343.740994 -249.028712) (xy 343.765605 -249.029183) (xy 343.814231 -249.036827)
			(xy 343.861079 -249.05193) (xy 343.905013 -249.074125) (xy 343.944968 -249.102874) (xy 343.979972 -249.13748)
			(xy 343.994994 -249.156982) (xy 344.006932 -249.172984) (xy 344.013282 -249.176286) (xy 344.096594 -249.181112)
			(xy 344.106623 -249.180667) (xy 344.125189 -249.173083) (xy 344.132662 -249.16638) (xy 344.288618 -249.010424)
			(xy 344.295408 -249.002984) (xy 344.303008 -248.984348) (xy 344.302842 -248.964222) (xy 344.299286 -248.954798)
			(xy 344.263472 -248.87047) (xy 344.263472 -248.870216) (xy 344.259133 -248.861299) (xy 344.244993 -248.847425)
			(xy 344.226643 -248.839961) (xy 344.216736 -248.839482) (xy 344.211148 -248.839482) (xy 344.18589 -248.838993)
			(xy 344.136061 -248.830686) (xy 344.08828 -248.814289) (xy 344.04385 -248.790251) (xy 344.003983 -248.759227)
			(xy 343.969766 -248.722063) (xy 343.942134 -248.679774) (xy 343.92184 -248.633514) (xy 343.909438 -248.584544)
			(xy 343.905266 -248.5342) (xy 343.909438 -248.483856) (xy 343.92184 -248.434886) (xy 343.942134 -248.388626)
			(xy 343.969766 -248.346337) (xy 344.003983 -248.309173) (xy 344.04385 -248.278149) (xy 344.08828 -248.254111)
			(xy 344.136061 -248.237714) (xy 344.18589 -248.229407) (xy 344.211148 -248.228866) (xy 344.2208 -248.228866)
			(xy 344.243491 -248.22998) (xy 344.288191 -248.238085) (xy 344.331198 -248.252717) (xy 344.371565 -248.273556)
			(xy 344.390218 -248.286524) (xy 344.390726 -248.286778) (xy 344.396472 -248.290692) (xy 344.409479 -248.295586)
			(xy 344.41638 -248.29643) (xy 344.429842 -248.297446) (xy 344.521536 -248.250964) (xy 344.524584 -248.249186)
			(xy 344.530171 -248.245592) (xy 344.539435 -248.236076) (xy 344.542872 -248.23039) (xy 344.543888 -248.228104)
			(xy 344.546295 -248.222894) (xy 344.54899 -248.21174) (xy 344.549222 -248.206006) (xy 344.549222 -248.042684)
			(xy 344.54846 -248.033794) (xy 344.547609 -248.029535) (xy 344.544677 -248.021362) (xy 344.542618 -248.017538)
			(xy 344.531188 -247.997472) (xy 344.524076 -247.988074) (xy 344.520012 -247.983756) (xy 344.518234 -247.982486)
			(xy 344.514678 -247.9802) (xy 344.493715 -247.965987) (xy 344.456382 -247.931765) (xy 344.425209 -247.891852)
			(xy 344.401049 -247.847342) (xy 344.384566 -247.799455) (xy 344.376212 -247.749505) (xy 344.376214 -247.69886)
			(xy 344.384575 -247.648911) (xy 344.401063 -247.601026) (xy 344.425228 -247.556519) (xy 344.456406 -247.516609)
			(xy 344.493743 -247.482392) (xy 344.514678 -247.468136) (xy 344.518234 -247.46585) (xy 344.520012 -247.46458)
			(xy 344.524076 -247.460262) (xy 344.531188 -247.450864) (xy 344.542364 -247.431052) (xy 344.544696 -247.426773)
			(xy 344.547891 -247.417568) (xy 344.548714 -247.412764) (xy 344.549222 -247.405906) (xy 344.549222 -246.422672)
			(xy 344.54846 -246.413782) (xy 344.547608 -246.409524) (xy 344.544674 -246.401351) (xy 344.542618 -246.397526)
			(xy 344.531188 -246.37746) (xy 344.524076 -246.368062) (xy 344.520012 -246.363744) (xy 344.518234 -246.362474)
			(xy 344.514678 -246.360188) (xy 344.493716 -246.345975) (xy 344.456385 -246.311754) (xy 344.425214 -246.271841)
			(xy 344.401056 -246.227332) (xy 344.384574 -246.179446) (xy 344.376221 -246.129497) (xy 344.376225 -246.078855)
			(xy 344.384586 -246.028907) (xy 344.401075 -245.981024) (xy 344.42524 -245.936519) (xy 344.456418 -245.896611)
			(xy 344.493754 -245.862396) (xy 344.514678 -245.848124) (xy 344.518234 -245.845838) (xy 344.520012 -245.844568)
			(xy 344.524076 -245.84025) (xy 344.531188 -245.830852) (xy 344.542364 -245.81104) (xy 344.544695 -245.806761)
			(xy 344.547888 -245.797555) (xy 344.548714 -245.792752) (xy 344.549222 -245.785894) (xy 344.549222 -245.622318)
			(xy 344.549011 -245.616581) (xy 344.546312 -245.605425) (xy 344.543888 -245.60022) (xy 344.542872 -245.597934)
			(xy 344.539218 -245.591831) (xy 344.529163 -245.581777) (xy 344.52306 -245.578122) (xy 344.521536 -245.57736)
			(xy 344.476578 -245.5545) (xy 344.442288 -245.537228) (xy 344.435969 -245.534325) (xy 344.422307 -245.531753)
			(xy 344.415364 -245.532148) (xy 344.401902 -245.533164) (xy 344.390218 -245.541292) (xy 344.38971 -245.5418)
			(xy 344.370087 -245.555368) (xy 344.327517 -245.576901) (xy 344.282122 -245.591565) (xy 344.235 -245.599007)
			(xy 344.211148 -245.599458) (xy 344.185884 -245.598969) (xy 344.136043 -245.590659) (xy 344.08825 -245.574258)
			(xy 344.043809 -245.550214) (xy 344.003931 -245.519182) (xy 343.969706 -245.48201) (xy 343.942067 -245.43971)
			(xy 343.921768 -245.393438) (xy 343.909363 -245.344456) (xy 343.90519 -245.2941) (xy 343.909363 -245.243744)
			(xy 343.921768 -245.194762) (xy 343.942067 -245.14849) (xy 343.969706 -245.10619) (xy 344.003931 -245.069018)
			(xy 344.043809 -245.037986) (xy 344.08825 -245.013942) (xy 344.136043 -244.997541) (xy 344.185884 -244.989231)
			(xy 344.211148 -244.988842) (xy 344.2208 -244.988842) (xy 344.24349 -244.989957) (xy 344.288189 -244.998063)
			(xy 344.331195 -245.012698) (xy 344.371559 -245.033541) (xy 344.390218 -245.0465) (xy 344.390726 -245.046754)
			(xy 344.396472 -245.050669) (xy 344.409478 -245.055565) (xy 344.41638 -245.056406) (xy 344.429842 -245.057422)
			(xy 344.521536 -245.01094) (xy 344.524584 -245.009162) (xy 344.53017 -245.005566) (xy 344.53943 -244.996048)
			(xy 344.542872 -244.990366) (xy 344.543888 -244.98808) (xy 344.546293 -244.982869) (xy 344.548982 -244.971716)
			(xy 344.549222 -244.965982) (xy 344.549222 -244.80266) (xy 344.54846 -244.79377) (xy 344.547607 -244.789512)
			(xy 344.544671 -244.78134) (xy 344.542618 -244.777514) (xy 344.531188 -244.757448) (xy 344.524076 -244.74805)
			(xy 344.520012 -244.743732) (xy 344.518234 -244.742462) (xy 344.514678 -244.740176) (xy 344.493709 -244.725962)
			(xy 344.456364 -244.691739) (xy 344.425178 -244.651822) (xy 344.401008 -244.607306) (xy 344.384515 -244.559411)
			(xy 344.376151 -244.509451) (xy 344.376147 -244.458797) (xy 344.384503 -244.408836) (xy 344.400988 -244.360938)
			(xy 344.425152 -244.316418) (xy 344.456331 -244.276496) (xy 344.493671 -244.242267) (xy 344.514678 -244.228112)
			(xy 344.518234 -244.225826) (xy 344.520012 -244.224556) (xy 344.524076 -244.220238) (xy 344.531188 -244.21084)
			(xy 344.542364 -244.191028) (xy 344.544694 -244.186748) (xy 344.547885 -244.177542) (xy 344.548714 -244.17274)
			(xy 344.549222 -244.165882) (xy 344.549222 -243.182648) (xy 344.54846 -243.173758) (xy 344.547606 -243.1695)
			(xy 344.544669 -243.16133) (xy 344.542618 -243.157502) (xy 344.531188 -243.137436) (xy 344.524076 -243.128038)
			(xy 344.520012 -243.12372) (xy 344.518234 -243.12245) (xy 344.514678 -243.120164) (xy 344.49371 -243.10595)
			(xy 344.456367 -243.071727) (xy 344.425183 -243.031811) (xy 344.401014 -242.987296) (xy 344.384523 -242.939402)
			(xy 344.376161 -242.889444) (xy 344.376158 -242.838791) (xy 344.384514 -242.788832) (xy 344.401 -242.740936)
			(xy 344.425164 -242.696418) (xy 344.456343 -242.656498) (xy 344.493682 -242.622271) (xy 344.514678 -242.6081)
			(xy 344.518234 -242.605814) (xy 344.520012 -242.604544) (xy 344.524076 -242.600226) (xy 344.531188 -242.590828)
			(xy 344.542364 -242.571016) (xy 344.544693 -242.566736) (xy 344.547882 -242.55753) (xy 344.548714 -242.552728)
			(xy 344.549222 -242.54587) (xy 344.549222 -242.382294) (xy 344.54902 -242.376555) (xy 344.546336 -242.365391)
			(xy 344.543888 -242.360196) (xy 344.542872 -242.35791) (xy 344.539216 -242.351809) (xy 344.529158 -242.341759)
			(xy 344.52306 -242.338098) (xy 344.521536 -242.337336) (xy 344.476578 -242.314476) (xy 344.442288 -242.297204)
			(xy 344.435968 -242.294302) (xy 344.422307 -242.291731) (xy 344.415364 -242.292124) (xy 344.401902 -242.29314)
			(xy 344.390218 -242.301268) (xy 344.38971 -242.301776) (xy 344.370086 -242.315341) (xy 344.327515 -242.336868)
			(xy 344.28212 -242.351529) (xy 344.235 -242.358969) (xy 344.211148 -242.359434) (xy 344.185886 -242.358945)
			(xy 344.136049 -242.350636) (xy 344.088259 -242.334236) (xy 344.043822 -242.310194) (xy 344.003948 -242.279165)
			(xy 343.969725 -242.241995) (xy 343.942089 -242.199699) (xy 343.921791 -242.153431) (xy 343.909387 -242.104452)
			(xy 343.905214 -242.0541) (xy 343.909387 -242.003748) (xy 343.921791 -241.954769) (xy 343.942089 -241.908501)
			(xy 343.969725 -241.866205) (xy 344.003948 -241.829035) (xy 344.043822 -241.798006) (xy 344.088259 -241.773964)
			(xy 344.136049 -241.757564) (xy 344.185886 -241.749255) (xy 344.211148 -241.748818) (xy 344.2208 -241.748818)
			(xy 344.24349 -241.749932) (xy 344.28819 -241.758038) (xy 344.331196 -241.772673) (xy 344.371561 -241.793514)
			(xy 344.390218 -241.806476) (xy 344.390726 -241.80673) (xy 344.396471 -241.810646) (xy 344.409478 -241.815545)
			(xy 344.41638 -241.816382) (xy 344.429842 -241.817398) (xy 344.521536 -241.770916) (xy 344.524584 -241.769138)
			(xy 344.530168 -241.765541) (xy 344.539425 -241.75602) (xy 344.542872 -241.750342) (xy 344.543888 -241.748056)
			(xy 344.54629 -241.742845) (xy 344.548974 -241.731691) (xy 344.549222 -241.725958) (xy 344.549222 -241.562636)
			(xy 344.54846 -241.553746) (xy 344.547605 -241.549489) (xy 344.544666 -241.541319) (xy 344.542618 -241.53749)
			(xy 344.531188 -241.517424) (xy 344.524076 -241.508026) (xy 344.520012 -241.503708) (xy 344.518234 -241.502438)
			(xy 344.514678 -241.500152) (xy 344.493711 -241.485941) (xy 344.456371 -241.451721) (xy 344.425193 -241.411806)
			(xy 344.401031 -241.367292) (xy 344.38455 -241.3194) (xy 344.376202 -241.269444) (xy 344.37574 -241.24412)
			(xy 344.376277 -241.217954) (xy 344.385198 -241.166387) (xy 344.402783 -241.117097) (xy 344.428516 -241.071528)
			(xy 344.461644 -241.031015) (xy 344.501195 -240.996744) (xy 344.523314 -240.982754) (xy 344.531441 -240.975993)
			(xy 344.541793 -240.957589) (xy 344.543848 -240.936574) (xy 344.541094 -240.926366) (xy 344.541094 -240.926112)
			(xy 344.522806 -240.86439) (xy 344.514424 -240.832386) (xy 344.51347 -240.828853) (xy 344.510663 -240.822095)
			(xy 344.508836 -240.818924) (xy 344.498422 -240.801144) (xy 344.493596 -240.796318) (xy 344.438732 -240.740946)
			(xy 344.431366 -240.733326) (xy 344.41003 -240.723928) (xy 344.402399 -240.721148) (xy 344.386201 -240.720105)
			(xy 344.37828 -240.721896) (xy 344.371168 -240.723674) (xy 344.365834 -240.726468) (xy 344.341904 -240.738547)
			(xy 344.291101 -240.755645) (xy 344.238203 -240.764308) (xy 344.211402 -240.764822) (xy 344.211148 -240.764822)
			(xy 344.185156 -240.764342) (xy 344.133811 -240.756217) (xy 344.084369 -240.740159) (xy 344.038048 -240.716564)
			(xy 343.995989 -240.686013) (xy 343.959227 -240.649258) (xy 343.928668 -240.607205) (xy 343.905064 -240.560889)
			(xy 343.888997 -240.51145) (xy 343.880862 -240.460106) (xy 343.88044 -240.434114) (xy 343.880186 -240.434114)
			(xy 343.880727 -240.406645) (xy 343.8898 -240.352462) (xy 343.9077 -240.300523) (xy 343.933934 -240.252253)
			(xy 343.967781 -240.208981) (xy 344.008312 -240.171895) (xy 344.031062 -240.156492) (xy 344.03665 -240.152936)
			(xy 344.040714 -240.148618) (xy 344.047826 -240.138966) (xy 344.056716 -240.123218) (xy 344.059137 -240.118774)
			(xy 344.062342 -240.109176) (xy 344.063066 -240.104168) (xy 344.064082 -240.094516) (xy 344.061034 -240.084356)
			(xy 344.04427 -240.022126) (xy 344.042492 -240.015014) (xy 344.028014 -239.99063) (xy 344.023442 -239.986058)
			(xy 344.005027 -239.968143) (xy 343.969207 -239.931306) (xy 343.951814 -239.912398) (xy 343.944702 -239.904524)
			(xy 343.917016 -239.892332) (xy 343.906856 -239.892586) (xy 343.881795 -239.907271) (xy 343.827626 -239.928215)
			(xy 343.77054 -239.938904) (xy 343.741502 -239.939576) (xy 343.740994 -239.939576) (xy 343.716199 -239.93909)
			(xy 343.667218 -239.931334) (xy 343.620053 -239.916016) (xy 343.575864 -239.89351) (xy 343.535737 -239.864372)
			(xy 343.50066 -239.829317) (xy 343.471496 -239.789209) (xy 343.448962 -239.745034) (xy 343.433613 -239.697878)
			(xy 343.425826 -239.648903) (xy 343.425272 -239.624108) (xy 343.425857 -239.597026) (xy 343.435156 -239.543664)
			(xy 343.45343 -239.492675) (xy 343.480143 -239.445555) (xy 343.514511 -239.403688) (xy 343.555522 -239.368305)
			(xy 343.578434 -239.353852) (xy 343.584058 -239.350223) (xy 343.593319 -239.340566) (xy 343.596722 -239.334802)
			(xy 343.600024 -239.32896) (xy 343.60104 -239.319308) (xy 343.601426 -239.314177) (xy 343.600408 -239.303939)
			(xy 343.599008 -239.298988) (xy 343.587779 -239.262509) (xy 343.568339 -239.188692) (xy 343.560146 -239.151414)
			(xy 343.557606 -239.139476) (xy 343.550494 -239.130332) (xy 343.546644 -239.125803) (xy 343.537283 -239.118482)
			(xy 343.531952 -239.115854) (xy 343.456768 -239.08131) (xy 343.445592 -239.078008) (xy 343.425018 -239.089692)
			(xy 343.401328 -239.102269) (xy 343.350763 -239.120144) (xy 343.297909 -239.129245) (xy 343.271094 -239.129824)
			(xy 343.246285 -239.129337) (xy 343.197277 -239.121574) (xy 343.150087 -239.10624) (xy 343.105876 -239.083713)
			(xy 343.065734 -239.054547) (xy 343.030649 -239.019461) (xy 343.001484 -238.979319) (xy 342.978958 -238.935108)
			(xy 342.963625 -238.887917) (xy 342.955863 -238.838909) (xy 342.955863 -238.789291) (xy 342.963625 -238.740283)
			(xy 342.978958 -238.693092) (xy 343.001484 -238.648881) (xy 343.030649 -238.608739) (xy 343.065734 -238.573653)
			(xy 343.105876 -238.544487) (xy 343.150087 -238.52196) (xy 343.197277 -238.506626) (xy 343.246285 -238.498863)
			(xy 343.271094 -238.49838) (xy 343.297967 -238.49894) (xy 343.35093 -238.508086) (xy 343.401575 -238.52608)
			(xy 343.425272 -238.538766) (xy 343.446862 -238.550958) (xy 343.44864 -238.550958) (xy 343.52738 -238.514382)
			(xy 343.531952 -238.51235) (xy 343.537297 -238.509742) (xy 343.546675 -238.502431) (xy 343.550494 -238.497872)
			(xy 343.557606 -238.488728) (xy 343.560146 -238.47679) (xy 343.568339 -238.439512) (xy 343.587781 -238.365695)
			(xy 343.599008 -238.329216) (xy 343.600441 -238.32427) (xy 343.60147 -238.314027) (xy 343.60104 -238.308896)
			(xy 343.600024 -238.299244) (xy 343.596722 -238.293402) (xy 343.593329 -238.287631) (xy 343.584066 -238.277971)
			(xy 343.578434 -238.274352) (xy 343.555493 -238.259939) (xy 343.514474 -238.224551) (xy 343.480101 -238.182678)
			(xy 343.453383 -238.13555) (xy 343.435105 -238.084553) (xy 343.425804 -238.031183) (xy 343.425272 -238.004096)
			(xy 343.42585 -237.97701) (xy 343.435136 -237.923639) (xy 343.453401 -237.872639) (xy 343.480108 -237.825507)
			(xy 343.514472 -237.783628) (xy 343.555483 -237.748234) (xy 343.578434 -237.73384) (xy 343.584058 -237.730211)
			(xy 343.593316 -237.720552) (xy 343.596722 -237.71479) (xy 343.600024 -237.708948) (xy 343.60104 -237.699296)
			(xy 343.601424 -237.694165) (xy 343.600404 -237.683928) (xy 343.599008 -237.678976) (xy 343.587779 -237.642497)
			(xy 343.56834 -237.56868) (xy 343.560146 -237.531402) (xy 343.557606 -237.519464) (xy 343.550494 -237.51032)
			(xy 343.546644 -237.505792) (xy 343.537282 -237.498472) (xy 343.531952 -237.495842) (xy 343.456768 -237.461298)
			(xy 343.445592 -237.457996) (xy 343.425018 -237.46968) (xy 343.401328 -237.482258) (xy 343.350763 -237.500133)
			(xy 343.297909 -237.509234) (xy 343.271094 -237.509812) (xy 343.246286 -237.509325) (xy 343.19728 -237.501562)
			(xy 343.150091 -237.486229) (xy 343.105883 -237.463703) (xy 343.065742 -237.434538) (xy 343.030658 -237.399453)
			(xy 343.001494 -237.359312) (xy 342.978969 -237.315103) (xy 342.963636 -237.267915) (xy 342.955875 -237.218908)
			(xy 342.955875 -237.169292) (xy 342.963636 -237.120285) (xy 342.978969 -237.073097) (xy 343.001494 -237.028888)
			(xy 343.030658 -236.988747) (xy 343.065742 -236.953662) (xy 343.105883 -236.924497) (xy 343.150091 -236.901971)
			(xy 343.19728 -236.886638) (xy 343.246286 -236.878875) (xy 343.271094 -236.878368) (xy 343.297967 -236.878928)
			(xy 343.35093 -236.888074) (xy 343.401576 -236.906067) (xy 343.425272 -236.918754) (xy 343.446862 -236.930946)
			(xy 343.44864 -236.930946) (xy 343.52738 -236.89437) (xy 343.531952 -236.892338) (xy 343.537297 -236.889729)
			(xy 343.546673 -236.882417) (xy 343.550494 -236.87786) (xy 343.557606 -236.868716) (xy 343.560146 -236.856778)
			(xy 343.568337 -236.8195) (xy 343.587775 -236.745681) (xy 343.599008 -236.709204) (xy 343.60044 -236.704258)
			(xy 343.601466 -236.694015) (xy 343.60104 -236.688884) (xy 343.600024 -236.679232) (xy 343.596722 -236.67339)
			(xy 343.593328 -236.66762) (xy 343.584063 -236.657962) (xy 343.578434 -236.65434) (xy 343.555493 -236.639927)
			(xy 343.514476 -236.604538) (xy 343.480105 -236.562665) (xy 343.453388 -236.515537) (xy 343.435112 -236.46454)
			(xy 343.425813 -236.41117) (xy 343.425272 -236.384084) (xy 343.425851 -236.356999) (xy 343.435139 -236.303629)
			(xy 343.453405 -236.25263) (xy 343.480113 -236.2055) (xy 343.514477 -236.163623) (xy 343.555488 -236.12823)
			(xy 343.578434 -236.113828) (xy 343.584057 -236.110198) (xy 343.593314 -236.100539) (xy 343.596722 -236.094778)
			(xy 343.600024 -236.088936) (xy 343.60104 -236.079284) (xy 343.601423 -236.074153) (xy 343.600401 -236.063917)
			(xy 343.599008 -236.058964) (xy 343.587779 -236.022485) (xy 343.568341 -235.948668) (xy 343.560146 -235.91139)
			(xy 343.557606 -235.899452) (xy 343.550494 -235.890308) (xy 343.546643 -235.88578) (xy 343.537281 -235.878462)
			(xy 343.531952 -235.87583) (xy 343.456768 -235.841286) (xy 343.445592 -235.837984) (xy 343.425018 -235.849668)
			(xy 343.401328 -235.862246) (xy 343.350763 -235.880122) (xy 343.297909 -235.889224) (xy 343.271094 -235.8898)
			(xy 343.246286 -235.889313) (xy 343.197282 -235.881551) (xy 343.150096 -235.866218) (xy 343.105889 -235.843693)
			(xy 343.06575 -235.814529) (xy 343.030667 -235.779446) (xy 343.001504 -235.739306) (xy 342.97898 -235.695099)
			(xy 342.963648 -235.647912) (xy 342.955887 -235.598908) (xy 342.955887 -235.549292) (xy 342.963648 -235.500288)
			(xy 342.97898 -235.453101) (xy 343.001504 -235.408894) (xy 343.030667 -235.368754) (xy 343.06575 -235.333671)
			(xy 343.105889 -235.304507) (xy 343.150096 -235.281982) (xy 343.197282 -235.266649) (xy 343.246286 -235.258887)
			(xy 343.271094 -235.258356) (xy 343.297967 -235.258916) (xy 343.35093 -235.268061) (xy 343.401576 -235.286054)
			(xy 343.425272 -235.298742) (xy 343.446862 -235.310934) (xy 343.44864 -235.310934) (xy 343.52738 -235.274358)
			(xy 343.531952 -235.272326) (xy 343.537296 -235.269717) (xy 343.546671 -235.262403) (xy 343.550494 -235.257848)
			(xy 343.557606 -235.248704) (xy 343.560146 -235.236766) (xy 343.568338 -235.199488) (xy 343.587776 -235.12567)
			(xy 343.599008 -235.089192) (xy 343.600439 -235.084246) (xy 343.601463 -235.074003) (xy 343.60104 -235.068872)
			(xy 343.600024 -235.05922) (xy 343.596722 -235.053378) (xy 343.593327 -235.047609) (xy 343.584061 -235.037953)
			(xy 343.578434 -235.034328) (xy 343.555494 -235.019915) (xy 343.514478 -234.984526) (xy 343.480108 -234.942652)
			(xy 343.453394 -234.895524) (xy 343.43512 -234.844527) (xy 343.425823 -234.791158) (xy 343.425272 -234.764072)
			(xy 343.425852 -234.736987) (xy 343.435142 -234.683619) (xy 343.453409 -234.632621) (xy 343.480118 -234.585493)
			(xy 343.514482 -234.543617) (xy 343.555493 -234.508226) (xy 343.578434 -234.493816) (xy 343.584062 -234.490191)
			(xy 343.593333 -234.480539) (xy 343.596722 -234.474766) (xy 343.600024 -234.468924) (xy 343.60104 -234.459272)
			(xy 343.601422 -234.454141) (xy 343.600397 -234.443906) (xy 343.599008 -234.438952) (xy 343.58778 -234.402473)
			(xy 343.568342 -234.328655) (xy 343.560146 -234.291378) (xy 343.557606 -234.27944) (xy 343.550494 -234.270296)
			(xy 343.546642 -234.265769) (xy 343.537279 -234.258453) (xy 343.531952 -234.255818) (xy 343.456768 -234.221274)
			(xy 343.445592 -234.217972) (xy 343.425018 -234.229656) (xy 343.401328 -234.242235) (xy 343.350763 -234.260111)
			(xy 343.297909 -234.269213) (xy 343.271094 -234.269788) (xy 343.246287 -234.269301) (xy 343.197285 -234.261539)
			(xy 343.150101 -234.246207) (xy 343.105895 -234.223682) (xy 343.065758 -234.19452) (xy 343.030676 -234.159438)
			(xy 343.001515 -234.1193) (xy 342.978991 -234.075094) (xy 342.96366 -234.027909) (xy 342.955899 -233.978907)
			(xy 342.955899 -233.929293) (xy 342.96366 -233.880291) (xy 342.978991 -233.833106) (xy 343.001515 -233.7889)
			(xy 343.030676 -233.748762) (xy 343.065758 -233.71368) (xy 343.105895 -233.684518) (xy 343.150101 -233.661993)
			(xy 343.197285 -233.646661) (xy 343.246287 -233.638899) (xy 343.271094 -233.638344) (xy 343.297967 -233.638904)
			(xy 343.35093 -233.648049) (xy 343.401577 -233.666041) (xy 343.425272 -233.67873) (xy 343.446862 -233.690922)
			(xy 343.44864 -233.690922) (xy 343.52738 -233.654346) (xy 343.531952 -233.652314) (xy 343.537296 -233.649704)
			(xy 343.546669 -233.64239) (xy 343.550494 -233.637836) (xy 343.557606 -233.628692) (xy 343.560146 -233.616754)
			(xy 343.568338 -233.579476) (xy 343.587776 -233.505658) (xy 343.599008 -233.46918) (xy 343.600437 -233.464234)
			(xy 343.601459 -233.453991) (xy 343.60104 -233.44886) (xy 343.600024 -233.439208) (xy 343.596722 -233.433366)
			(xy 343.593326 -233.427598) (xy 343.584059 -233.417944) (xy 343.578434 -233.414316) (xy 343.555495 -233.399903)
			(xy 343.51448 -233.364513) (xy 343.480112 -233.322639) (xy 343.453399 -233.275511) (xy 343.435127 -233.224514)
			(xy 343.425832 -233.171146) (xy 343.425272 -233.14406) (xy 343.425853 -233.116976) (xy 343.435144 -233.063609)
			(xy 343.453413 -233.012613) (xy 343.480122 -232.965485) (xy 343.514488 -232.923612) (xy 343.555499 -232.888222)
			(xy 343.578434 -232.873804) (xy 343.584061 -232.870178) (xy 343.593331 -232.860526) (xy 343.596722 -232.854754)
			(xy 343.600024 -232.848912) (xy 343.60104 -232.83926) (xy 343.601421 -232.83413) (xy 343.600394 -232.823895)
			(xy 343.599008 -232.81894) (xy 343.587778 -232.782462) (xy 343.568336 -232.708645) (xy 343.560146 -232.671366)
			(xy 343.557606 -232.659428) (xy 343.550494 -232.650284) (xy 343.546642 -232.645758) (xy 343.537278 -232.638443)
			(xy 343.531952 -232.635806) (xy 343.456768 -232.601262) (xy 343.445592 -232.59796) (xy 343.425018 -232.609644)
			(xy 343.401329 -232.622223) (xy 343.350764 -232.640101) (xy 343.297909 -232.649203) (xy 343.271094 -232.649776)
			(xy 343.246288 -232.649289) (xy 343.197288 -232.641527) (xy 343.150105 -232.626196) (xy 343.105901 -232.603672)
			(xy 343.065765 -232.574511) (xy 343.030685 -232.53943) (xy 343.001525 -232.499293) (xy 342.979002 -232.455089)
			(xy 342.963671 -232.407906) (xy 342.955911 -232.358906) (xy 342.955911 -232.309294) (xy 342.963671 -232.260294)
			(xy 342.979002 -232.213111) (xy 343.001525 -232.168907) (xy 343.030685 -232.12877) (xy 343.065765 -232.093689)
			(xy 343.105901 -232.064528) (xy 343.150105 -232.042004) (xy 343.197288 -232.026673) (xy 343.246288 -232.018911)
			(xy 343.271094 -232.018332) (xy 343.297967 -232.018892) (xy 343.350929 -232.02804) (xy 343.401573 -232.046036)
			(xy 343.425272 -232.058718) (xy 343.446862 -232.07091) (xy 343.44864 -232.07091) (xy 343.52738 -232.034334)
			(xy 343.531952 -232.032302) (xy 343.537295 -232.029692) (xy 343.546667 -232.022376) (xy 343.550494 -232.017824)
			(xy 343.557606 -232.00868) (xy 343.560146 -231.996742) (xy 343.568338 -231.959464) (xy 343.587777 -231.885646)
			(xy 343.599008 -231.849168) (xy 343.600436 -231.844222) (xy 343.601455 -231.83398) (xy 343.60104 -231.828848)
			(xy 343.600024 -231.819196) (xy 343.596722 -231.813354) (xy 343.593325 -231.807586) (xy 343.584057 -231.797935)
			(xy 343.578434 -231.794304) (xy 343.555495 -231.77989) (xy 343.514482 -231.7445) (xy 343.480115 -231.702626)
			(xy 343.453405 -231.655498) (xy 343.435134 -231.604501) (xy 343.425841 -231.551133) (xy 343.425272 -231.524048)
			(xy 343.42583 -231.496941) (xy 343.435088 -231.443522) (xy 343.45334 -231.392472) (xy 343.480049 -231.345293)
			(xy 343.514428 -231.303373) (xy 343.555466 -231.267946) (xy 343.578434 -231.253538) (xy 343.584057 -231.249909)
			(xy 343.593316 -231.24025) (xy 343.596722 -231.234488) (xy 343.59977 -231.2289) (xy 343.601802 -231.20858)
			(xy 343.598754 -231.19842) (xy 343.587606 -231.162126) (xy 343.568296 -231.08869) (xy 343.560146 -231.051608)
			(xy 343.557606 -231.03967) (xy 343.550494 -231.030526) (xy 343.546644 -231.025997) (xy 343.537283 -231.018677)
			(xy 343.531952 -231.016048) (xy 343.456768 -230.981504) (xy 343.445592 -230.978202) (xy 343.425018 -230.989886)
			(xy 343.401445 -231.002394) (xy 343.351129 -231.020157) (xy 343.298536 -231.029173) (xy 343.271856 -231.029764)
			(xy 343.271094 -231.029764) (xy 343.246305 -231.029277) (xy 343.197338 -231.021521) (xy 343.150186 -231.006199)
			(xy 343.106012 -230.983691) (xy 343.065903 -230.954549) (xy 343.030847 -230.919492) (xy 343.001706 -230.879382)
			(xy 342.979198 -230.835208) (xy 342.963878 -230.788057) (xy 342.956122 -230.739089) (xy 342.956122 -230.689511)
			(xy 342.963878 -230.640543) (xy 342.979198 -230.593392) (xy 343.001706 -230.549218) (xy 343.030847 -230.509108)
			(xy 343.065903 -230.474051) (xy 343.106012 -230.444909) (xy 343.150186 -230.422401) (xy 343.197338 -230.407079)
			(xy 343.246305 -230.399323) (xy 343.271094 -230.398828) (xy 343.271348 -230.398828) (xy 343.298169 -230.399363)
			(xy 343.351037 -230.408436) (xy 343.401605 -230.42633) (xy 343.425272 -230.43896) (xy 343.446862 -230.451152)
			(xy 343.44864 -230.451152) (xy 343.52738 -230.414576) (xy 343.531952 -230.412544) (xy 343.537297 -230.409936)
			(xy 343.546674 -230.402624) (xy 343.550494 -230.398066) (xy 343.557606 -230.388922) (xy 343.560146 -230.376984)
			(xy 343.56834 -230.339769) (xy 343.587779 -230.266078) (xy 343.599008 -230.229664) (xy 343.602056 -230.219504)
			(xy 343.60104 -230.209852) (xy 343.600415 -230.204579) (xy 343.597217 -230.194456) (xy 343.59469 -230.189786)
			(xy 343.589864 -230.18115) (xy 343.56769 -230.168502) (xy 343.527388 -230.137173) (xy 343.492656 -230.099765)
			(xy 343.464397 -230.057254) (xy 343.44335 -230.010749) (xy 343.430063 -229.961462) (xy 343.424883 -229.910679)
			(xy 343.427945 -229.859725) (xy 343.439169 -229.809928) (xy 343.458262 -229.762587) (xy 343.484727 -229.718937)
			(xy 343.517873 -229.680116) (xy 343.556836 -229.647136) (xy 343.578434 -229.633526) (xy 343.584063 -229.629901)
			(xy 343.593336 -229.620251) (xy 343.596722 -229.614476) (xy 343.59977 -229.608888) (xy 343.601802 -229.588568)
			(xy 343.598754 -229.578408) (xy 343.587606 -229.542114) (xy 343.568297 -229.468678) (xy 343.560146 -229.431596)
			(xy 343.557606 -229.419658) (xy 343.550494 -229.410514) (xy 343.546643 -229.405986) (xy 343.537281 -229.398667)
			(xy 343.531952 -229.396036) (xy 343.456768 -229.361492) (xy 343.445592 -229.35819) (xy 343.425018 -229.369874)
			(xy 343.401445 -229.382383) (xy 343.351129 -229.400147) (xy 343.298536 -229.409162) (xy 343.271856 -229.409752)
			(xy 343.271094 -229.409752) (xy 343.246306 -229.409265) (xy 343.19734 -229.401509) (xy 343.150191 -229.386188)
			(xy 343.106019 -229.363681) (xy 343.065911 -229.33454) (xy 343.030856 -229.299484) (xy 343.001716 -229.259376)
			(xy 342.979209 -229.215203) (xy 342.96389 -229.168054) (xy 342.956134 -229.119088) (xy 342.956134 -229.069512)
			(xy 342.96389 -229.020546) (xy 342.979209 -228.973397) (xy 343.001716 -228.929224) (xy 343.030856 -228.889116)
			(xy 343.065911 -228.85406) (xy 343.106019 -228.824919) (xy 343.150191 -228.802412) (xy 343.19734 -228.787091)
			(xy 343.246306 -228.779335) (xy 343.271094 -228.778816) (xy 343.271348 -228.778816) (xy 343.298169 -228.779351)
			(xy 343.351037 -228.788424) (xy 343.401606 -228.806317) (xy 343.425272 -228.818948) (xy 343.446862 -228.83114)
			(xy 343.44864 -228.83114) (xy 343.52738 -228.794564) (xy 343.531952 -228.792532) (xy 343.537297 -228.789923)
			(xy 343.546672 -228.78261) (xy 343.550494 -228.778054) (xy 343.557606 -228.76891) (xy 343.560146 -228.756972)
			(xy 343.568338 -228.719694) (xy 343.587775 -228.645875) (xy 343.599008 -228.609398) (xy 343.600439 -228.604452)
			(xy 343.601465 -228.594209) (xy 343.60104 -228.589078) (xy 343.600024 -228.579426) (xy 343.596722 -228.573584)
			(xy 343.593327 -228.567814) (xy 343.584062 -228.558158) (xy 343.578434 -228.554534) (xy 343.555494 -228.540121)
			(xy 343.514477 -228.504732) (xy 343.480106 -228.462859) (xy 343.453391 -228.415731) (xy 343.435116 -228.364733)
			(xy 343.425818 -228.311364) (xy 343.425272 -228.284278) (xy 343.425851 -228.257193) (xy 343.43514 -228.203824)
			(xy 343.453407 -228.152826) (xy 343.480115 -228.105696) (xy 343.51448 -228.06382) (xy 343.555491 -228.028428)
			(xy 343.578434 -228.014022) (xy 343.584062 -228.010397) (xy 343.593335 -228.000746) (xy 343.596722 -227.994972)
			(xy 343.600024 -227.98913) (xy 343.60104 -227.979478) (xy 343.601423 -227.974347) (xy 343.600399 -227.964111)
			(xy 343.599008 -227.959158) (xy 343.587779 -227.922679) (xy 343.568341 -227.848861) (xy 343.560146 -227.811584)
			(xy 343.557606 -227.799646) (xy 343.550494 -227.790502) (xy 343.546643 -227.785975) (xy 343.53728 -227.778658)
			(xy 343.531952 -227.776024) (xy 343.456768 -227.74148) (xy 343.445592 -227.738178) (xy 343.425018 -227.749862)
			(xy 343.401445 -227.762371) (xy 343.351129 -227.780136) (xy 343.298536 -227.789152) (xy 343.271856 -227.78974)
			(xy 343.271094 -227.78974) (xy 343.246307 -227.789253) (xy 343.197343 -227.781497) (xy 343.150196 -227.766177)
			(xy 343.106025 -227.74367) (xy 343.065919 -227.714531) (xy 343.030865 -227.679476) (xy 343.001726 -227.63937)
			(xy 342.97922 -227.595199) (xy 342.963901 -227.548051) (xy 342.956146 -227.499087) (xy 342.956146 -227.449513)
			(xy 342.963901 -227.400549) (xy 342.97922 -227.353401) (xy 343.001726 -227.30923) (xy 343.030865 -227.269124)
			(xy 343.065919 -227.234069) (xy 343.106025 -227.20493) (xy 343.150196 -227.182423) (xy 343.197343 -227.167103)
			(xy 343.246307 -227.159347) (xy 343.271094 -227.158804) (xy 343.271348 -227.158804) (xy 343.298169 -227.159339)
			(xy 343.351037 -227.168412) (xy 343.401606 -227.186304) (xy 343.425272 -227.198936) (xy 343.446862 -227.211128)
			(xy 343.44864 -227.211128) (xy 343.531952 -227.17252) (xy 343.53737 -227.169858) (xy 343.546866 -227.162411)
			(xy 343.550748 -227.157788) (xy 343.557606 -227.148898) (xy 343.560146 -227.13696) (xy 343.572846 -227.081842)
			(xy 343.57437 -227.075746) (xy 343.57437 -227.06965) (xy 343.573873 -227.059651) (xy 343.566204 -227.041182)
			(xy 343.552051 -227.027052) (xy 343.53357 -227.019411) (xy 343.52357 -227.01885) (xy 331.807566 -227.01885)
			(xy 331.797725 -227.019378) (xy 331.779549 -227.026951) (xy 331.77226 -227.033582) (xy 331.474064 -227.331778)
			(xy 331.467348 -227.339015) (xy 331.459745 -227.35722) (xy 331.459332 -227.367084) (xy 331.459332 -227.474272)
			(xy 331.685404 -227.474272) (xy 331.689364 -227.425218) (xy 331.701141 -227.377434) (xy 331.720432 -227.332158)
			(xy 331.746735 -227.290562) (xy 331.77937 -227.253725) (xy 331.817491 -227.2226) (xy 331.860112 -227.197993)
			(xy 331.906128 -227.180541) (xy 331.954347 -227.170697) (xy 332.003522 -227.168716) (xy 332.052377 -227.174648)
			(xy 332.099648 -227.18834) (xy 332.14411 -227.209438) (xy 332.184613 -227.237394) (xy 332.220106 -227.271486)
			(xy 332.249671 -227.31083) (xy 332.272542 -227.354407) (xy 332.288126 -227.401088) (xy 332.296021 -227.449665)
			(xy 332.296516 -227.474272) (xy 332.625204 -227.474272) (xy 332.629164 -227.425218) (xy 332.640941 -227.377434)
			(xy 332.660232 -227.332158) (xy 332.686535 -227.290562) (xy 332.71917 -227.253725) (xy 332.757291 -227.2226)
			(xy 332.799912 -227.197993) (xy 332.845928 -227.180541) (xy 332.894147 -227.170697) (xy 332.943322 -227.168716)
			(xy 332.992177 -227.174648) (xy 333.039448 -227.18834) (xy 333.08391 -227.209438) (xy 333.124413 -227.237394)
			(xy 333.159906 -227.271486) (xy 333.189471 -227.31083) (xy 333.212342 -227.354407) (xy 333.227926 -227.401088)
			(xy 333.235821 -227.449665) (xy 333.236316 -227.474272) (xy 333.565258 -227.474272) (xy 333.569218 -227.425218)
			(xy 333.580995 -227.377434) (xy 333.600286 -227.332158) (xy 333.626589 -227.290562) (xy 333.659224 -227.253725)
			(xy 333.697345 -227.2226) (xy 333.739966 -227.197993) (xy 333.785982 -227.180541) (xy 333.834201 -227.170697)
			(xy 333.883376 -227.168716) (xy 333.932231 -227.174648) (xy 333.979502 -227.18834) (xy 334.023964 -227.209438)
			(xy 334.064467 -227.237394) (xy 334.09996 -227.271486) (xy 334.129525 -227.31083) (xy 334.152396 -227.354407)
			(xy 334.16798 -227.401088) (xy 334.175875 -227.449665) (xy 334.17637 -227.474272) (xy 335.445366 -227.474272)
			(xy 335.449326 -227.425218) (xy 335.461103 -227.377434) (xy 335.480394 -227.332158) (xy 335.506697 -227.290562)
			(xy 335.539332 -227.253725) (xy 335.577453 -227.2226) (xy 335.620074 -227.197993) (xy 335.66609 -227.180541)
			(xy 335.714309 -227.170697) (xy 335.763484 -227.168716) (xy 335.812339 -227.174648) (xy 335.85961 -227.18834)
			(xy 335.904072 -227.209438) (xy 335.944575 -227.237394) (xy 335.980068 -227.271486) (xy 336.009633 -227.31083)
			(xy 336.032504 -227.354407) (xy 336.048088 -227.401088) (xy 336.055983 -227.449665) (xy 336.056478 -227.474272)
			(xy 336.38542 -227.474272) (xy 336.38938 -227.425218) (xy 336.401157 -227.377434) (xy 336.420448 -227.332158)
			(xy 336.446751 -227.290562) (xy 336.479386 -227.253725) (xy 336.517507 -227.2226) (xy 336.560128 -227.197993)
			(xy 336.606144 -227.180541) (xy 336.654363 -227.170697) (xy 336.703538 -227.168716) (xy 336.752393 -227.174648)
			(xy 336.799664 -227.18834) (xy 336.844126 -227.209438) (xy 336.884629 -227.237394) (xy 336.920122 -227.271486)
			(xy 336.949687 -227.31083) (xy 336.972558 -227.354407) (xy 336.988142 -227.401088) (xy 336.996037 -227.449665)
			(xy 336.996532 -227.474272) (xy 337.32522 -227.474272) (xy 337.32918 -227.425218) (xy 337.340957 -227.377434)
			(xy 337.360248 -227.332158) (xy 337.386551 -227.290562) (xy 337.419186 -227.253725) (xy 337.457307 -227.2226)
			(xy 337.499928 -227.197993) (xy 337.545944 -227.180541) (xy 337.594163 -227.170697) (xy 337.643338 -227.168716)
			(xy 337.692193 -227.174648) (xy 337.739464 -227.18834) (xy 337.783926 -227.209438) (xy 337.824429 -227.237394)
			(xy 337.859922 -227.271486) (xy 337.889487 -227.31083) (xy 337.912358 -227.354407) (xy 337.927942 -227.401088)
			(xy 337.935837 -227.449665) (xy 337.936332 -227.474272) (xy 338.254843 -227.474272) (xy 338.258938 -227.423544)
			(xy 338.271117 -227.37413) (xy 338.291065 -227.32731) (xy 338.318266 -227.284296) (xy 338.352014 -227.246202)
			(xy 338.391436 -227.214015) (xy 338.43551 -227.188569) (xy 338.483096 -227.170522) (xy 338.53296 -227.160342)
			(xy 338.583812 -227.158293) (xy 338.634333 -227.164427) (xy 338.683217 -227.178587) (xy 338.729196 -227.200404)
			(xy 338.77108 -227.229314) (xy 338.807784 -227.264569) (xy 338.838357 -227.305255) (xy 338.862008 -227.350318)
			(xy 338.878124 -227.398592) (xy 338.886288 -227.448826) (xy 338.8868 -227.474272) (xy 339.205328 -227.474272)
			(xy 339.209288 -227.425218) (xy 339.221065 -227.377434) (xy 339.240356 -227.332158) (xy 339.266659 -227.290562)
			(xy 339.299294 -227.253725) (xy 339.337415 -227.2226) (xy 339.380036 -227.197993) (xy 339.426052 -227.180541)
			(xy 339.474271 -227.170697) (xy 339.523446 -227.168716) (xy 339.572301 -227.174648) (xy 339.619572 -227.18834)
			(xy 339.664034 -227.209438) (xy 339.704537 -227.237394) (xy 339.74003 -227.271486) (xy 339.769595 -227.31083)
			(xy 339.792466 -227.354407) (xy 339.80805 -227.401088) (xy 339.815945 -227.449665) (xy 339.81644 -227.474272)
			(xy 340.134951 -227.474272) (xy 340.139046 -227.423544) (xy 340.151225 -227.37413) (xy 340.171173 -227.32731)
			(xy 340.198374 -227.284296) (xy 340.232122 -227.246202) (xy 340.271544 -227.214015) (xy 340.315618 -227.188569)
			(xy 340.363204 -227.170522) (xy 340.413068 -227.160342) (xy 340.46392 -227.158293) (xy 340.514441 -227.164427)
			(xy 340.563325 -227.178587) (xy 340.609304 -227.200404) (xy 340.651188 -227.229314) (xy 340.687892 -227.264569)
			(xy 340.718465 -227.305255) (xy 340.742116 -227.350318) (xy 340.758232 -227.398592) (xy 340.766396 -227.448826)
			(xy 340.766908 -227.474272) (xy 342.014805 -227.474272) (xy 342.0189 -227.423544) (xy 342.031079 -227.37413)
			(xy 342.051027 -227.32731) (xy 342.078228 -227.284296) (xy 342.111976 -227.246202) (xy 342.151398 -227.214015)
			(xy 342.195472 -227.188569) (xy 342.243058 -227.170522) (xy 342.292922 -227.160342) (xy 342.343774 -227.158293)
			(xy 342.394295 -227.164427) (xy 342.443179 -227.178587) (xy 342.489158 -227.200404) (xy 342.531042 -227.229314)
			(xy 342.567746 -227.264569) (xy 342.598319 -227.305255) (xy 342.62197 -227.350318) (xy 342.638086 -227.398592)
			(xy 342.64625 -227.448826) (xy 342.646762 -227.474272) (xy 342.64625 -227.499718) (xy 342.638086 -227.549952)
			(xy 342.62197 -227.598226) (xy 342.598319 -227.643289) (xy 342.567746 -227.683975) (xy 342.531042 -227.71923)
			(xy 342.489158 -227.74814) (xy 342.443179 -227.769957) (xy 342.394295 -227.784117) (xy 342.343774 -227.790251)
			(xy 342.292922 -227.788202) (xy 342.243058 -227.778022) (xy 342.195472 -227.759975) (xy 342.151398 -227.734529)
			(xy 342.111976 -227.702342) (xy 342.078228 -227.664248) (xy 342.051027 -227.621234) (xy 342.031079 -227.574414)
			(xy 342.0189 -227.525) (xy 342.014805 -227.474272) (xy 340.766908 -227.474272) (xy 340.766396 -227.499718)
			(xy 340.758232 -227.549952) (xy 340.742116 -227.598226) (xy 340.718465 -227.643289) (xy 340.687892 -227.683975)
			(xy 340.651188 -227.71923) (xy 340.609304 -227.74814) (xy 340.563325 -227.769957) (xy 340.514441 -227.784117)
			(xy 340.46392 -227.790251) (xy 340.413068 -227.788202) (xy 340.363204 -227.778022) (xy 340.315618 -227.759975)
			(xy 340.271544 -227.734529) (xy 340.232122 -227.702342) (xy 340.198374 -227.664248) (xy 340.171173 -227.621234)
			(xy 340.151225 -227.574414) (xy 340.139046 -227.525) (xy 340.134951 -227.474272) (xy 339.81644 -227.474272)
			(xy 339.815945 -227.498879) (xy 339.80805 -227.547456) (xy 339.792466 -227.594137) (xy 339.769595 -227.637714)
			(xy 339.74003 -227.677058) (xy 339.704537 -227.71115) (xy 339.664034 -227.739106) (xy 339.619572 -227.760204)
			(xy 339.572301 -227.773896) (xy 339.523446 -227.779828) (xy 339.474271 -227.777847) (xy 339.426052 -227.768003)
			(xy 339.380036 -227.750551) (xy 339.337415 -227.725944) (xy 339.299294 -227.694819) (xy 339.266659 -227.657982)
			(xy 339.240356 -227.616386) (xy 339.221065 -227.57111) (xy 339.209288 -227.523326) (xy 339.205328 -227.474272)
			(xy 338.8868 -227.474272) (xy 338.886288 -227.499718) (xy 338.878124 -227.549952) (xy 338.862008 -227.598226)
			(xy 338.838357 -227.643289) (xy 338.807784 -227.683975) (xy 338.77108 -227.71923) (xy 338.729196 -227.74814)
			(xy 338.683217 -227.769957) (xy 338.634333 -227.784117) (xy 338.583812 -227.790251) (xy 338.53296 -227.788202)
			(xy 338.483096 -227.778022) (xy 338.43551 -227.759975) (xy 338.391436 -227.734529) (xy 338.352014 -227.702342)
			(xy 338.318266 -227.664248) (xy 338.291065 -227.621234) (xy 338.271117 -227.574414) (xy 338.258938 -227.525)
			(xy 338.254843 -227.474272) (xy 337.936332 -227.474272) (xy 337.935837 -227.498879) (xy 337.927942 -227.547456)
			(xy 337.912358 -227.594137) (xy 337.889487 -227.637714) (xy 337.859922 -227.677058) (xy 337.824429 -227.71115)
			(xy 337.783926 -227.739106) (xy 337.739464 -227.760204) (xy 337.692193 -227.773896) (xy 337.643338 -227.779828)
			(xy 337.594163 -227.777847) (xy 337.545944 -227.768003) (xy 337.499928 -227.750551) (xy 337.457307 -227.725944)
			(xy 337.419186 -227.694819) (xy 337.386551 -227.657982) (xy 337.360248 -227.616386) (xy 337.340957 -227.57111)
			(xy 337.32918 -227.523326) (xy 337.32522 -227.474272) (xy 336.996532 -227.474272) (xy 336.996037 -227.498879)
			(xy 336.988142 -227.547456) (xy 336.972558 -227.594137) (xy 336.949687 -227.637714) (xy 336.920122 -227.677058)
			(xy 336.884629 -227.71115) (xy 336.844126 -227.739106) (xy 336.799664 -227.760204) (xy 336.752393 -227.773896)
			(xy 336.703538 -227.779828) (xy 336.654363 -227.777847) (xy 336.606144 -227.768003) (xy 336.560128 -227.750551)
			(xy 336.517507 -227.725944) (xy 336.479386 -227.694819) (xy 336.446751 -227.657982) (xy 336.420448 -227.616386)
			(xy 336.401157 -227.57111) (xy 336.38938 -227.523326) (xy 336.38542 -227.474272) (xy 336.056478 -227.474272)
			(xy 336.055983 -227.498879) (xy 336.048088 -227.547456) (xy 336.032504 -227.594137) (xy 336.009633 -227.637714)
			(xy 335.980068 -227.677058) (xy 335.944575 -227.71115) (xy 335.904072 -227.739106) (xy 335.85961 -227.760204)
			(xy 335.812339 -227.773896) (xy 335.763484 -227.779828) (xy 335.714309 -227.777847) (xy 335.66609 -227.768003)
			(xy 335.620074 -227.750551) (xy 335.577453 -227.725944) (xy 335.539332 -227.694819) (xy 335.506697 -227.657982)
			(xy 335.480394 -227.616386) (xy 335.461103 -227.57111) (xy 335.449326 -227.523326) (xy 335.445366 -227.474272)
			(xy 334.17637 -227.474272) (xy 334.175875 -227.498879) (xy 334.16798 -227.547456) (xy 334.152396 -227.594137)
			(xy 334.129525 -227.637714) (xy 334.09996 -227.677058) (xy 334.064467 -227.71115) (xy 334.023964 -227.739106)
			(xy 333.979502 -227.760204) (xy 333.932231 -227.773896) (xy 333.883376 -227.779828) (xy 333.834201 -227.777847)
			(xy 333.785982 -227.768003) (xy 333.739966 -227.750551) (xy 333.697345 -227.725944) (xy 333.659224 -227.694819)
			(xy 333.626589 -227.657982) (xy 333.600286 -227.616386) (xy 333.580995 -227.57111) (xy 333.569218 -227.523326)
			(xy 333.565258 -227.474272) (xy 333.236316 -227.474272) (xy 333.235821 -227.498879) (xy 333.227926 -227.547456)
			(xy 333.212342 -227.594137) (xy 333.189471 -227.637714) (xy 333.159906 -227.677058) (xy 333.124413 -227.71115)
			(xy 333.08391 -227.739106) (xy 333.039448 -227.760204) (xy 332.992177 -227.773896) (xy 332.943322 -227.779828)
			(xy 332.894147 -227.777847) (xy 332.845928 -227.768003) (xy 332.799912 -227.750551) (xy 332.757291 -227.725944)
			(xy 332.71917 -227.694819) (xy 332.686535 -227.657982) (xy 332.660232 -227.616386) (xy 332.640941 -227.57111)
			(xy 332.629164 -227.523326) (xy 332.625204 -227.474272) (xy 332.296516 -227.474272) (xy 332.296021 -227.498879)
			(xy 332.288126 -227.547456) (xy 332.272542 -227.594137) (xy 332.249671 -227.637714) (xy 332.220106 -227.677058)
			(xy 332.184613 -227.71115) (xy 332.14411 -227.739106) (xy 332.099648 -227.760204) (xy 332.052377 -227.773896)
			(xy 332.003522 -227.779828) (xy 331.954347 -227.777847) (xy 331.906128 -227.768003) (xy 331.860112 -227.750551)
			(xy 331.817491 -227.725944) (xy 331.77937 -227.694819) (xy 331.746735 -227.657982) (xy 331.720432 -227.616386)
			(xy 331.701141 -227.57111) (xy 331.689364 -227.523326) (xy 331.685404 -227.474272) (xy 331.459332 -227.474272)
			(xy 331.459332 -227.880418) (xy 331.459812 -227.889772) (xy 331.466591 -227.907218) (xy 331.47254 -227.914454)
			(xy 331.517498 -227.963984) (xy 331.520809 -227.967453) (xy 331.528478 -227.973211) (xy 331.532738 -227.975414)
			(xy 331.540612 -227.979224) (xy 331.550264 -227.98024) (xy 331.550518 -227.98024) (xy 331.575389 -227.983151)
			(xy 331.623775 -227.996036) (xy 331.669411 -228.01664) (xy 331.711077 -228.044411) (xy 331.747656 -228.078605)
			(xy 331.778168 -228.118306) (xy 331.801797 -228.162452) (xy 331.817911 -228.20986) (xy 331.826077 -228.259262)
			(xy 331.826077 -228.284278) (xy 332.155304 -228.284278) (xy 332.159264 -228.235224) (xy 332.171041 -228.18744)
			(xy 332.190332 -228.142164) (xy 332.216635 -228.100568) (xy 332.24927 -228.063731) (xy 332.287391 -228.032606)
			(xy 332.330012 -228.007999) (xy 332.376028 -227.990547) (xy 332.424247 -227.980703) (xy 332.473422 -227.978722)
			(xy 332.522277 -227.984654) (xy 332.569548 -227.998346) (xy 332.61401 -228.019444) (xy 332.654513 -228.0474)
			(xy 332.690006 -228.081492) (xy 332.719571 -228.120836) (xy 332.742442 -228.164413) (xy 332.758026 -228.211094)
			(xy 332.765921 -228.259671) (xy 332.766416 -228.284278) (xy 333.095358 -228.284278) (xy 333.099318 -228.235224)
			(xy 333.111095 -228.18744) (xy 333.130386 -228.142164) (xy 333.156689 -228.100568) (xy 333.189324 -228.063731)
			(xy 333.227445 -228.032606) (xy 333.270066 -228.007999) (xy 333.316082 -227.990547) (xy 333.364301 -227.980703)
			(xy 333.413476 -227.978722) (xy 333.462331 -227.984654) (xy 333.509602 -227.998346) (xy 333.554064 -228.019444)
			(xy 333.594567 -228.0474) (xy 333.63006 -228.081492) (xy 333.659625 -228.120836) (xy 333.682496 -228.164413)
			(xy 333.69808 -228.211094) (xy 333.705975 -228.259671) (xy 333.70647 -228.284278) (xy 334.035412 -228.284278)
			(xy 334.039372 -228.235224) (xy 334.051149 -228.18744) (xy 334.07044 -228.142164) (xy 334.096743 -228.100568)
			(xy 334.129378 -228.063731) (xy 334.167499 -228.032606) (xy 334.21012 -228.007999) (xy 334.256136 -227.990547)
			(xy 334.304355 -227.980703) (xy 334.35353 -227.978722) (xy 334.402385 -227.984654) (xy 334.449656 -227.998346)
			(xy 334.494118 -228.019444) (xy 334.534621 -228.0474) (xy 334.570114 -228.081492) (xy 334.599679 -228.120836)
			(xy 334.62255 -228.164413) (xy 334.638134 -228.211094) (xy 334.646029 -228.259671) (xy 334.646524 -228.284278)
			(xy 334.975212 -228.284278) (xy 334.979172 -228.235224) (xy 334.990949 -228.18744) (xy 335.01024 -228.142164)
			(xy 335.036543 -228.100568) (xy 335.069178 -228.063731) (xy 335.107299 -228.032606) (xy 335.14992 -228.007999)
			(xy 335.195936 -227.990547) (xy 335.244155 -227.980703) (xy 335.29333 -227.978722) (xy 335.342185 -227.984654)
			(xy 335.389456 -227.998346) (xy 335.433918 -228.019444) (xy 335.474421 -228.0474) (xy 335.509914 -228.081492)
			(xy 335.539479 -228.120836) (xy 335.56235 -228.164413) (xy 335.577934 -228.211094) (xy 335.585829 -228.259671)
			(xy 335.586324 -228.284278) (xy 335.915266 -228.284278) (xy 335.919226 -228.235224) (xy 335.931003 -228.18744)
			(xy 335.950294 -228.142164) (xy 335.976597 -228.100568) (xy 336.009232 -228.063731) (xy 336.047353 -228.032606)
			(xy 336.089974 -228.007999) (xy 336.13599 -227.990547) (xy 336.184209 -227.980703) (xy 336.233384 -227.978722)
			(xy 336.282239 -227.984654) (xy 336.32951 -227.998346) (xy 336.373972 -228.019444) (xy 336.414475 -228.0474)
			(xy 336.449968 -228.081492) (xy 336.479533 -228.120836) (xy 336.502404 -228.164413) (xy 336.517988 -228.211094)
			(xy 336.525883 -228.259671) (xy 336.526378 -228.284278) (xy 336.85532 -228.284278) (xy 336.85928 -228.235224)
			(xy 336.871057 -228.18744) (xy 336.890348 -228.142164) (xy 336.916651 -228.100568) (xy 336.949286 -228.063731)
			(xy 336.987407 -228.032606) (xy 337.030028 -228.007999) (xy 337.076044 -227.990547) (xy 337.124263 -227.980703)
			(xy 337.173438 -227.978722) (xy 337.222293 -227.984654) (xy 337.269564 -227.998346) (xy 337.314026 -228.019444)
			(xy 337.354529 -228.0474) (xy 337.390022 -228.081492) (xy 337.419587 -228.120836) (xy 337.442458 -228.164413)
			(xy 337.458042 -228.211094) (xy 337.465937 -228.259671) (xy 337.466432 -228.284278) (xy 337.795374 -228.284278)
			(xy 337.799334 -228.235224) (xy 337.811111 -228.18744) (xy 337.830402 -228.142164) (xy 337.856705 -228.100568)
			(xy 337.88934 -228.063731) (xy 337.927461 -228.032606) (xy 337.970082 -228.007999) (xy 338.016098 -227.990547)
			(xy 338.064317 -227.980703) (xy 338.113492 -227.978722) (xy 338.162347 -227.984654) (xy 338.209618 -227.998346)
			(xy 338.25408 -228.019444) (xy 338.294583 -228.0474) (xy 338.330076 -228.081492) (xy 338.359641 -228.120836)
			(xy 338.382512 -228.164413) (xy 338.398096 -228.211094) (xy 338.405991 -228.259671) (xy 338.406486 -228.284278)
			(xy 338.724743 -228.284278) (xy 338.728838 -228.23355) (xy 338.741017 -228.184136) (xy 338.760965 -228.137316)
			(xy 338.788166 -228.094302) (xy 338.821914 -228.056208) (xy 338.861336 -228.024021) (xy 338.90541 -227.998575)
			(xy 338.952996 -227.980528) (xy 339.00286 -227.970348) (xy 339.053712 -227.968299) (xy 339.104233 -227.974433)
			(xy 339.153117 -227.988593) (xy 339.199096 -228.01041) (xy 339.24098 -228.03932) (xy 339.277684 -228.074575)
			(xy 339.308257 -228.115261) (xy 339.331908 -228.160324) (xy 339.348024 -228.208598) (xy 339.356188 -228.258832)
			(xy 339.3567 -228.284278) (xy 339.664797 -228.284278) (xy 339.668892 -228.23355) (xy 339.681071 -228.184136)
			(xy 339.701019 -228.137316) (xy 339.72822 -228.094302) (xy 339.761968 -228.056208) (xy 339.80139 -228.024021)
			(xy 339.845464 -227.998575) (xy 339.89305 -227.980528) (xy 339.942914 -227.970348) (xy 339.993766 -227.968299)
			(xy 340.044287 -227.974433) (xy 340.093171 -227.988593) (xy 340.13915 -228.01041) (xy 340.181034 -228.03932)
			(xy 340.217738 -228.074575) (xy 340.248311 -228.115261) (xy 340.271962 -228.160324) (xy 340.288078 -228.208598)
			(xy 340.296242 -228.258832) (xy 340.296754 -228.284278) (xy 340.615282 -228.284278) (xy 340.619242 -228.235224)
			(xy 340.631019 -228.18744) (xy 340.65031 -228.142164) (xy 340.676613 -228.100568) (xy 340.709248 -228.063731)
			(xy 340.747369 -228.032606) (xy 340.78999 -228.007999) (xy 340.836006 -227.990547) (xy 340.884225 -227.980703)
			(xy 340.9334 -227.978722) (xy 340.982255 -227.984654) (xy 341.029526 -227.998346) (xy 341.073988 -228.019444)
			(xy 341.114491 -228.0474) (xy 341.149984 -228.081492) (xy 341.179549 -228.120836) (xy 341.20242 -228.164413)
			(xy 341.218004 -228.211094) (xy 341.225899 -228.259671) (xy 341.226394 -228.284278) (xy 341.544905 -228.284278)
			(xy 341.549 -228.23355) (xy 341.561179 -228.184136) (xy 341.581127 -228.137316) (xy 341.608328 -228.094302)
			(xy 341.642076 -228.056208) (xy 341.681498 -228.024021) (xy 341.725572 -227.998575) (xy 341.773158 -227.980528)
			(xy 341.823022 -227.970348) (xy 341.873874 -227.968299) (xy 341.924395 -227.974433) (xy 341.973279 -227.988593)
			(xy 342.019258 -228.01041) (xy 342.061142 -228.03932) (xy 342.097846 -228.074575) (xy 342.128419 -228.115261)
			(xy 342.15207 -228.160324) (xy 342.168186 -228.208598) (xy 342.17635 -228.258832) (xy 342.176862 -228.284278)
			(xy 342.49539 -228.284278) (xy 342.49935 -228.235224) (xy 342.511127 -228.18744) (xy 342.530418 -228.142164)
			(xy 342.556721 -228.100568) (xy 342.589356 -228.063731) (xy 342.627477 -228.032606) (xy 342.670098 -228.007999)
			(xy 342.716114 -227.990547) (xy 342.764333 -227.980703) (xy 342.813508 -227.978722) (xy 342.862363 -227.984654)
			(xy 342.909634 -227.998346) (xy 342.954096 -228.019444) (xy 342.994599 -228.0474) (xy 343.030092 -228.081492)
			(xy 343.059657 -228.120836) (xy 343.082528 -228.164413) (xy 343.098112 -228.211094) (xy 343.106007 -228.259671)
			(xy 343.106502 -228.284278) (xy 343.106007 -228.308885) (xy 343.098112 -228.357462) (xy 343.082528 -228.404143)
			(xy 343.059657 -228.44772) (xy 343.030092 -228.487064) (xy 342.994599 -228.521156) (xy 342.954096 -228.549112)
			(xy 342.909634 -228.57021) (xy 342.862363 -228.583902) (xy 342.813508 -228.589834) (xy 342.764333 -228.587853)
			(xy 342.716114 -228.578009) (xy 342.670098 -228.560557) (xy 342.627477 -228.53595) (xy 342.589356 -228.504825)
			(xy 342.556721 -228.467988) (xy 342.530418 -228.426392) (xy 342.511127 -228.381116) (xy 342.49935 -228.333332)
			(xy 342.49539 -228.284278) (xy 342.176862 -228.284278) (xy 342.17635 -228.309724) (xy 342.168186 -228.359958)
			(xy 342.15207 -228.408232) (xy 342.128419 -228.453295) (xy 342.097846 -228.493981) (xy 342.061142 -228.529236)
			(xy 342.019258 -228.558146) (xy 341.973279 -228.579963) (xy 341.924395 -228.594123) (xy 341.873874 -228.600257)
			(xy 341.823022 -228.598208) (xy 341.773158 -228.588028) (xy 341.725572 -228.569981) (xy 341.681498 -228.544535)
			(xy 341.642076 -228.512348) (xy 341.608328 -228.474254) (xy 341.581127 -228.43124) (xy 341.561179 -228.38442)
			(xy 341.549 -228.335006) (xy 341.544905 -228.284278) (xy 341.226394 -228.284278) (xy 341.225899 -228.308885)
			(xy 341.218004 -228.357462) (xy 341.20242 -228.404143) (xy 341.179549 -228.44772) (xy 341.149984 -228.487064)
			(xy 341.114491 -228.521156) (xy 341.073988 -228.549112) (xy 341.029526 -228.57021) (xy 340.982255 -228.583902)
			(xy 340.9334 -228.589834) (xy 340.884225 -228.587853) (xy 340.836006 -228.578009) (xy 340.78999 -228.560557)
			(xy 340.747369 -228.53595) (xy 340.709248 -228.504825) (xy 340.676613 -228.467988) (xy 340.65031 -228.426392)
			(xy 340.631019 -228.381116) (xy 340.619242 -228.333332) (xy 340.615282 -228.284278) (xy 340.296754 -228.284278)
			(xy 340.296242 -228.309724) (xy 340.288078 -228.359958) (xy 340.271962 -228.408232) (xy 340.248311 -228.453295)
			(xy 340.217738 -228.493981) (xy 340.181034 -228.529236) (xy 340.13915 -228.558146) (xy 340.093171 -228.579963)
			(xy 340.044287 -228.594123) (xy 339.993766 -228.600257) (xy 339.942914 -228.598208) (xy 339.89305 -228.588028)
			(xy 339.845464 -228.569981) (xy 339.80139 -228.544535) (xy 339.761968 -228.512348) (xy 339.72822 -228.474254)
			(xy 339.701019 -228.43124) (xy 339.681071 -228.38442) (xy 339.668892 -228.335006) (xy 339.664797 -228.284278)
			(xy 339.3567 -228.284278) (xy 339.356188 -228.309724) (xy 339.348024 -228.359958) (xy 339.331908 -228.408232)
			(xy 339.308257 -228.453295) (xy 339.277684 -228.493981) (xy 339.24098 -228.529236) (xy 339.199096 -228.558146)
			(xy 339.153117 -228.579963) (xy 339.104233 -228.594123) (xy 339.053712 -228.600257) (xy 339.00286 -228.598208)
			(xy 338.952996 -228.588028) (xy 338.90541 -228.569981) (xy 338.861336 -228.544535) (xy 338.821914 -228.512348)
			(xy 338.788166 -228.474254) (xy 338.760965 -228.43124) (xy 338.741017 -228.38442) (xy 338.728838 -228.335006)
			(xy 338.724743 -228.284278) (xy 338.406486 -228.284278) (xy 338.405991 -228.308885) (xy 338.398096 -228.357462)
			(xy 338.382512 -228.404143) (xy 338.359641 -228.44772) (xy 338.330076 -228.487064) (xy 338.294583 -228.521156)
			(xy 338.25408 -228.549112) (xy 338.209618 -228.57021) (xy 338.162347 -228.583902) (xy 338.113492 -228.589834)
			(xy 338.064317 -228.587853) (xy 338.016098 -228.578009) (xy 337.970082 -228.560557) (xy 337.927461 -228.53595)
			(xy 337.88934 -228.504825) (xy 337.856705 -228.467988) (xy 337.830402 -228.426392) (xy 337.811111 -228.381116)
			(xy 337.799334 -228.333332) (xy 337.795374 -228.284278) (xy 337.466432 -228.284278) (xy 337.465937 -228.308885)
			(xy 337.458042 -228.357462) (xy 337.442458 -228.404143) (xy 337.419587 -228.44772) (xy 337.390022 -228.487064)
			(xy 337.354529 -228.521156) (xy 337.314026 -228.549112) (xy 337.269564 -228.57021) (xy 337.222293 -228.583902)
			(xy 337.173438 -228.589834) (xy 337.124263 -228.587853) (xy 337.076044 -228.578009) (xy 337.030028 -228.560557)
			(xy 336.987407 -228.53595) (xy 336.949286 -228.504825) (xy 336.916651 -228.467988) (xy 336.890348 -228.426392)
			(xy 336.871057 -228.381116) (xy 336.85928 -228.333332) (xy 336.85532 -228.284278) (xy 336.526378 -228.284278)
			(xy 336.525883 -228.308885) (xy 336.517988 -228.357462) (xy 336.502404 -228.404143) (xy 336.479533 -228.44772)
			(xy 336.449968 -228.487064) (xy 336.414475 -228.521156) (xy 336.373972 -228.549112) (xy 336.32951 -228.57021)
			(xy 336.282239 -228.583902) (xy 336.233384 -228.589834) (xy 336.184209 -228.587853) (xy 336.13599 -228.578009)
			(xy 336.089974 -228.560557) (xy 336.047353 -228.53595) (xy 336.009232 -228.504825) (xy 335.976597 -228.467988)
			(xy 335.950294 -228.426392) (xy 335.931003 -228.381116) (xy 335.919226 -228.333332) (xy 335.915266 -228.284278)
			(xy 335.586324 -228.284278) (xy 335.585829 -228.308885) (xy 335.577934 -228.357462) (xy 335.56235 -228.404143)
			(xy 335.539479 -228.44772) (xy 335.509914 -228.487064) (xy 335.474421 -228.521156) (xy 335.433918 -228.549112)
			(xy 335.389456 -228.57021) (xy 335.342185 -228.583902) (xy 335.29333 -228.589834) (xy 335.244155 -228.587853)
			(xy 335.195936 -228.578009) (xy 335.14992 -228.560557) (xy 335.107299 -228.53595) (xy 335.069178 -228.504825)
			(xy 335.036543 -228.467988) (xy 335.01024 -228.426392) (xy 334.990949 -228.381116) (xy 334.979172 -228.333332)
			(xy 334.975212 -228.284278) (xy 334.646524 -228.284278) (xy 334.646029 -228.308885) (xy 334.638134 -228.357462)
			(xy 334.62255 -228.404143) (xy 334.599679 -228.44772) (xy 334.570114 -228.487064) (xy 334.534621 -228.521156)
			(xy 334.494118 -228.549112) (xy 334.449656 -228.57021) (xy 334.402385 -228.583902) (xy 334.35353 -228.589834)
			(xy 334.304355 -228.587853) (xy 334.256136 -228.578009) (xy 334.21012 -228.560557) (xy 334.167499 -228.53595)
			(xy 334.129378 -228.504825) (xy 334.096743 -228.467988) (xy 334.07044 -228.426392) (xy 334.051149 -228.381116)
			(xy 334.039372 -228.333332) (xy 334.035412 -228.284278) (xy 333.70647 -228.284278) (xy 333.705975 -228.308885)
			(xy 333.69808 -228.357462) (xy 333.682496 -228.404143) (xy 333.659625 -228.44772) (xy 333.63006 -228.487064)
			(xy 333.594567 -228.521156) (xy 333.554064 -228.549112) (xy 333.509602 -228.57021) (xy 333.462331 -228.583902)
			(xy 333.413476 -228.589834) (xy 333.364301 -228.587853) (xy 333.316082 -228.578009) (xy 333.270066 -228.560557)
			(xy 333.227445 -228.53595) (xy 333.189324 -228.504825) (xy 333.156689 -228.467988) (xy 333.130386 -228.426392)
			(xy 333.111095 -228.381116) (xy 333.099318 -228.333332) (xy 333.095358 -228.284278) (xy 332.766416 -228.284278)
			(xy 332.765921 -228.308885) (xy 332.758026 -228.357462) (xy 332.742442 -228.404143) (xy 332.719571 -228.44772)
			(xy 332.690006 -228.487064) (xy 332.654513 -228.521156) (xy 332.61401 -228.549112) (xy 332.569548 -228.57021)
			(xy 332.522277 -228.583902) (xy 332.473422 -228.589834) (xy 332.424247 -228.587853) (xy 332.376028 -228.578009)
			(xy 332.330012 -228.560557) (xy 332.287391 -228.53595) (xy 332.24927 -228.504825) (xy 332.216635 -228.467988)
			(xy 332.190332 -228.426392) (xy 332.171041 -228.381116) (xy 332.159264 -228.333332) (xy 332.155304 -228.284278)
			(xy 331.826077 -228.284278) (xy 331.826078 -228.309334) (xy 331.817912 -228.358736) (xy 331.801799 -228.406144)
			(xy 331.77817 -228.450291) (xy 331.747658 -228.489992) (xy 331.71108 -228.524187) (xy 331.669415 -228.551958)
			(xy 331.623779 -228.572562) (xy 331.575393 -228.585448) (xy 331.550518 -228.588316) (xy 331.550264 -228.588316)
			(xy 331.540612 -228.589332) (xy 331.532738 -228.593142) (xy 331.528477 -228.595344) (xy 331.520802 -228.601096)
			(xy 331.517498 -228.604572) (xy 331.47254 -228.654102) (xy 331.46648 -228.661272) (xy 331.459682 -228.678758)
			(xy 331.459332 -228.688138) (xy 331.459332 -229.094284) (xy 331.685404 -229.094284) (xy 331.689364 -229.04523)
			(xy 331.701141 -228.997446) (xy 331.720432 -228.95217) (xy 331.746735 -228.910574) (xy 331.77937 -228.873737)
			(xy 331.817491 -228.842612) (xy 331.860112 -228.818005) (xy 331.906128 -228.800553) (xy 331.954347 -228.790709)
			(xy 332.003522 -228.788728) (xy 332.052377 -228.79466) (xy 332.099648 -228.808352) (xy 332.14411 -228.82945)
			(xy 332.184613 -228.857406) (xy 332.220106 -228.891498) (xy 332.249671 -228.930842) (xy 332.272542 -228.974419)
			(xy 332.288126 -229.0211) (xy 332.296021 -229.069677) (xy 332.296516 -229.094284) (xy 332.625204 -229.094284)
			(xy 332.629164 -229.04523) (xy 332.640941 -228.997446) (xy 332.660232 -228.95217) (xy 332.686535 -228.910574)
			(xy 332.71917 -228.873737) (xy 332.757291 -228.842612) (xy 332.799912 -228.818005) (xy 332.845928 -228.800553)
			(xy 332.894147 -228.790709) (xy 332.943322 -228.788728) (xy 332.992177 -228.79466) (xy 333.039448 -228.808352)
			(xy 333.08391 -228.82945) (xy 333.124413 -228.857406) (xy 333.159906 -228.891498) (xy 333.189471 -228.930842)
			(xy 333.212342 -228.974419) (xy 333.227926 -229.0211) (xy 333.235821 -229.069677) (xy 333.236316 -229.094284)
			(xy 333.565258 -229.094284) (xy 333.569218 -229.04523) (xy 333.580995 -228.997446) (xy 333.600286 -228.95217)
			(xy 333.626589 -228.910574) (xy 333.659224 -228.873737) (xy 333.697345 -228.842612) (xy 333.739966 -228.818005)
			(xy 333.785982 -228.800553) (xy 333.834201 -228.790709) (xy 333.883376 -228.788728) (xy 333.932231 -228.79466)
			(xy 333.979502 -228.808352) (xy 334.023964 -228.82945) (xy 334.064467 -228.857406) (xy 334.09996 -228.891498)
			(xy 334.129525 -228.930842) (xy 334.152396 -228.974419) (xy 334.16798 -229.0211) (xy 334.175875 -229.069677)
			(xy 334.17637 -229.094284) (xy 334.505312 -229.094284) (xy 334.509272 -229.04523) (xy 334.521049 -228.997446)
			(xy 334.54034 -228.95217) (xy 334.566643 -228.910574) (xy 334.599278 -228.873737) (xy 334.637399 -228.842612)
			(xy 334.68002 -228.818005) (xy 334.726036 -228.800553) (xy 334.774255 -228.790709) (xy 334.82343 -228.788728)
			(xy 334.872285 -228.79466) (xy 334.919556 -228.808352) (xy 334.964018 -228.82945) (xy 335.004521 -228.857406)
			(xy 335.040014 -228.891498) (xy 335.069579 -228.930842) (xy 335.09245 -228.974419) (xy 335.108034 -229.0211)
			(xy 335.115929 -229.069677) (xy 335.116424 -229.094284) (xy 335.445366 -229.094284) (xy 335.449326 -229.04523)
			(xy 335.461103 -228.997446) (xy 335.480394 -228.95217) (xy 335.506697 -228.910574) (xy 335.539332 -228.873737)
			(xy 335.577453 -228.842612) (xy 335.620074 -228.818005) (xy 335.66609 -228.800553) (xy 335.714309 -228.790709)
			(xy 335.763484 -228.788728) (xy 335.812339 -228.79466) (xy 335.85961 -228.808352) (xy 335.904072 -228.82945)
			(xy 335.944575 -228.857406) (xy 335.980068 -228.891498) (xy 336.009633 -228.930842) (xy 336.032504 -228.974419)
			(xy 336.048088 -229.0211) (xy 336.055983 -229.069677) (xy 336.056478 -229.094284) (xy 336.38542 -229.094284)
			(xy 336.38938 -229.04523) (xy 336.401157 -228.997446) (xy 336.420448 -228.95217) (xy 336.446751 -228.910574)
			(xy 336.479386 -228.873737) (xy 336.517507 -228.842612) (xy 336.560128 -228.818005) (xy 336.606144 -228.800553)
			(xy 336.654363 -228.790709) (xy 336.703538 -228.788728) (xy 336.752393 -228.79466) (xy 336.799664 -228.808352)
			(xy 336.844126 -228.82945) (xy 336.884629 -228.857406) (xy 336.920122 -228.891498) (xy 336.949687 -228.930842)
			(xy 336.972558 -228.974419) (xy 336.988142 -229.0211) (xy 336.996037 -229.069677) (xy 336.996532 -229.094284)
			(xy 337.32522 -229.094284) (xy 337.32918 -229.04523) (xy 337.340957 -228.997446) (xy 337.360248 -228.95217)
			(xy 337.386551 -228.910574) (xy 337.419186 -228.873737) (xy 337.457307 -228.842612) (xy 337.499928 -228.818005)
			(xy 337.545944 -228.800553) (xy 337.594163 -228.790709) (xy 337.643338 -228.788728) (xy 337.692193 -228.79466)
			(xy 337.739464 -228.808352) (xy 337.783926 -228.82945) (xy 337.824429 -228.857406) (xy 337.859922 -228.891498)
			(xy 337.889487 -228.930842) (xy 337.912358 -228.974419) (xy 337.927942 -229.0211) (xy 337.935837 -229.069677)
			(xy 337.936332 -229.094284) (xy 338.254843 -229.094284) (xy 338.258938 -229.043556) (xy 338.271117 -228.994142)
			(xy 338.291065 -228.947322) (xy 338.318266 -228.904308) (xy 338.352014 -228.866214) (xy 338.391436 -228.834027)
			(xy 338.43551 -228.808581) (xy 338.483096 -228.790534) (xy 338.53296 -228.780354) (xy 338.583812 -228.778305)
			(xy 338.634333 -228.784439) (xy 338.683217 -228.798599) (xy 338.729196 -228.820416) (xy 338.77108 -228.849326)
			(xy 338.807784 -228.884581) (xy 338.838357 -228.925267) (xy 338.862008 -228.97033) (xy 338.878124 -229.018604)
			(xy 338.886288 -229.068838) (xy 338.8868 -229.094284) (xy 339.205328 -229.094284) (xy 339.209288 -229.04523)
			(xy 339.221065 -228.997446) (xy 339.240356 -228.95217) (xy 339.266659 -228.910574) (xy 339.299294 -228.873737)
			(xy 339.337415 -228.842612) (xy 339.380036 -228.818005) (xy 339.426052 -228.800553) (xy 339.474271 -228.790709)
			(xy 339.523446 -228.788728) (xy 339.572301 -228.79466) (xy 339.619572 -228.808352) (xy 339.664034 -228.82945)
			(xy 339.704537 -228.857406) (xy 339.74003 -228.891498) (xy 339.769595 -228.930842) (xy 339.792466 -228.974419)
			(xy 339.80805 -229.0211) (xy 339.815945 -229.069677) (xy 339.81644 -229.094284) (xy 340.134951 -229.094284)
			(xy 340.139046 -229.043556) (xy 340.151225 -228.994142) (xy 340.171173 -228.947322) (xy 340.198374 -228.904308)
			(xy 340.232122 -228.866214) (xy 340.271544 -228.834027) (xy 340.315618 -228.808581) (xy 340.363204 -228.790534)
			(xy 340.413068 -228.780354) (xy 340.46392 -228.778305) (xy 340.514441 -228.784439) (xy 340.563325 -228.798599)
			(xy 340.609304 -228.820416) (xy 340.651188 -228.849326) (xy 340.687892 -228.884581) (xy 340.718465 -228.925267)
			(xy 340.742116 -228.97033) (xy 340.758232 -229.018604) (xy 340.766396 -229.068838) (xy 340.766908 -229.094284)
			(xy 341.085182 -229.094284) (xy 341.089142 -229.04523) (xy 341.100919 -228.997446) (xy 341.12021 -228.95217)
			(xy 341.146513 -228.910574) (xy 341.179148 -228.873737) (xy 341.217269 -228.842612) (xy 341.25989 -228.818005)
			(xy 341.305906 -228.800553) (xy 341.354125 -228.790709) (xy 341.4033 -228.788728) (xy 341.452155 -228.79466)
			(xy 341.499426 -228.808352) (xy 341.543888 -228.82945) (xy 341.584391 -228.857406) (xy 341.619884 -228.891498)
			(xy 341.649449 -228.930842) (xy 341.67232 -228.974419) (xy 341.687904 -229.0211) (xy 341.695799 -229.069677)
			(xy 341.696294 -229.094284) (xy 342.014805 -229.094284) (xy 342.0189 -229.043556) (xy 342.031079 -228.994142)
			(xy 342.051027 -228.947322) (xy 342.078228 -228.904308) (xy 342.111976 -228.866214) (xy 342.151398 -228.834027)
			(xy 342.195472 -228.808581) (xy 342.243058 -228.790534) (xy 342.292922 -228.780354) (xy 342.343774 -228.778305)
			(xy 342.394295 -228.784439) (xy 342.443179 -228.798599) (xy 342.489158 -228.820416) (xy 342.531042 -228.849326)
			(xy 342.567746 -228.884581) (xy 342.598319 -228.925267) (xy 342.62197 -228.97033) (xy 342.638086 -229.018604)
			(xy 342.64625 -229.068838) (xy 342.646762 -229.094284) (xy 342.64625 -229.11973) (xy 342.638086 -229.169964)
			(xy 342.62197 -229.218238) (xy 342.598319 -229.263301) (xy 342.567746 -229.303987) (xy 342.531042 -229.339242)
			(xy 342.489158 -229.368152) (xy 342.443179 -229.389969) (xy 342.394295 -229.404129) (xy 342.343774 -229.410263)
			(xy 342.292922 -229.408214) (xy 342.243058 -229.398034) (xy 342.195472 -229.379987) (xy 342.151398 -229.354541)
			(xy 342.111976 -229.322354) (xy 342.078228 -229.28426) (xy 342.051027 -229.241246) (xy 342.031079 -229.194426)
			(xy 342.0189 -229.145012) (xy 342.014805 -229.094284) (xy 341.696294 -229.094284) (xy 341.695799 -229.118891)
			(xy 341.687904 -229.167468) (xy 341.67232 -229.214149) (xy 341.649449 -229.257726) (xy 341.619884 -229.29707)
			(xy 341.584391 -229.331162) (xy 341.543888 -229.359118) (xy 341.499426 -229.380216) (xy 341.452155 -229.393908)
			(xy 341.4033 -229.39984) (xy 341.354125 -229.397859) (xy 341.305906 -229.388015) (xy 341.25989 -229.370563)
			(xy 341.217269 -229.345956) (xy 341.179148 -229.314831) (xy 341.146513 -229.277994) (xy 341.12021 -229.236398)
			(xy 341.100919 -229.191122) (xy 341.089142 -229.143338) (xy 341.085182 -229.094284) (xy 340.766908 -229.094284)
			(xy 340.766396 -229.11973) (xy 340.758232 -229.169964) (xy 340.742116 -229.218238) (xy 340.718465 -229.263301)
			(xy 340.687892 -229.303987) (xy 340.651188 -229.339242) (xy 340.609304 -229.368152) (xy 340.563325 -229.389969)
			(xy 340.514441 -229.404129) (xy 340.46392 -229.410263) (xy 340.413068 -229.408214) (xy 340.363204 -229.398034)
			(xy 340.315618 -229.379987) (xy 340.271544 -229.354541) (xy 340.232122 -229.322354) (xy 340.198374 -229.28426)
			(xy 340.171173 -229.241246) (xy 340.151225 -229.194426) (xy 340.139046 -229.145012) (xy 340.134951 -229.094284)
			(xy 339.81644 -229.094284) (xy 339.815945 -229.118891) (xy 339.80805 -229.167468) (xy 339.792466 -229.214149)
			(xy 339.769595 -229.257726) (xy 339.74003 -229.29707) (xy 339.704537 -229.331162) (xy 339.664034 -229.359118)
			(xy 339.619572 -229.380216) (xy 339.572301 -229.393908) (xy 339.523446 -229.39984) (xy 339.474271 -229.397859)
			(xy 339.426052 -229.388015) (xy 339.380036 -229.370563) (xy 339.337415 -229.345956) (xy 339.299294 -229.314831)
			(xy 339.266659 -229.277994) (xy 339.240356 -229.236398) (xy 339.221065 -229.191122) (xy 339.209288 -229.143338)
			(xy 339.205328 -229.094284) (xy 338.8868 -229.094284) (xy 338.886288 -229.11973) (xy 338.878124 -229.169964)
			(xy 338.862008 -229.218238) (xy 338.838357 -229.263301) (xy 338.807784 -229.303987) (xy 338.77108 -229.339242)
			(xy 338.729196 -229.368152) (xy 338.683217 -229.389969) (xy 338.634333 -229.404129) (xy 338.583812 -229.410263)
			(xy 338.53296 -229.408214) (xy 338.483096 -229.398034) (xy 338.43551 -229.379987) (xy 338.391436 -229.354541)
			(xy 338.352014 -229.322354) (xy 338.318266 -229.28426) (xy 338.291065 -229.241246) (xy 338.271117 -229.194426)
			(xy 338.258938 -229.145012) (xy 338.254843 -229.094284) (xy 337.936332 -229.094284) (xy 337.935837 -229.118891)
			(xy 337.927942 -229.167468) (xy 337.912358 -229.214149) (xy 337.889487 -229.257726) (xy 337.859922 -229.29707)
			(xy 337.824429 -229.331162) (xy 337.783926 -229.359118) (xy 337.739464 -229.380216) (xy 337.692193 -229.393908)
			(xy 337.643338 -229.39984) (xy 337.594163 -229.397859) (xy 337.545944 -229.388015) (xy 337.499928 -229.370563)
			(xy 337.457307 -229.345956) (xy 337.419186 -229.314831) (xy 337.386551 -229.277994) (xy 337.360248 -229.236398)
			(xy 337.340957 -229.191122) (xy 337.32918 -229.143338) (xy 337.32522 -229.094284) (xy 336.996532 -229.094284)
			(xy 336.996037 -229.118891) (xy 336.988142 -229.167468) (xy 336.972558 -229.214149) (xy 336.949687 -229.257726)
			(xy 336.920122 -229.29707) (xy 336.884629 -229.331162) (xy 336.844126 -229.359118) (xy 336.799664 -229.380216)
			(xy 336.752393 -229.393908) (xy 336.703538 -229.39984) (xy 336.654363 -229.397859) (xy 336.606144 -229.388015)
			(xy 336.560128 -229.370563) (xy 336.517507 -229.345956) (xy 336.479386 -229.314831) (xy 336.446751 -229.277994)
			(xy 336.420448 -229.236398) (xy 336.401157 -229.191122) (xy 336.38938 -229.143338) (xy 336.38542 -229.094284)
			(xy 336.056478 -229.094284) (xy 336.055983 -229.118891) (xy 336.048088 -229.167468) (xy 336.032504 -229.214149)
			(xy 336.009633 -229.257726) (xy 335.980068 -229.29707) (xy 335.944575 -229.331162) (xy 335.904072 -229.359118)
			(xy 335.85961 -229.380216) (xy 335.812339 -229.393908) (xy 335.763484 -229.39984) (xy 335.714309 -229.397859)
			(xy 335.66609 -229.388015) (xy 335.620074 -229.370563) (xy 335.577453 -229.345956) (xy 335.539332 -229.314831)
			(xy 335.506697 -229.277994) (xy 335.480394 -229.236398) (xy 335.461103 -229.191122) (xy 335.449326 -229.143338)
			(xy 335.445366 -229.094284) (xy 335.116424 -229.094284) (xy 335.115929 -229.118891) (xy 335.108034 -229.167468)
			(xy 335.09245 -229.214149) (xy 335.069579 -229.257726) (xy 335.040014 -229.29707) (xy 335.004521 -229.331162)
			(xy 334.964018 -229.359118) (xy 334.919556 -229.380216) (xy 334.872285 -229.393908) (xy 334.82343 -229.39984)
			(xy 334.774255 -229.397859) (xy 334.726036 -229.388015) (xy 334.68002 -229.370563) (xy 334.637399 -229.345956)
			(xy 334.599278 -229.314831) (xy 334.566643 -229.277994) (xy 334.54034 -229.236398) (xy 334.521049 -229.191122)
			(xy 334.509272 -229.143338) (xy 334.505312 -229.094284) (xy 334.17637 -229.094284) (xy 334.175875 -229.118891)
			(xy 334.16798 -229.167468) (xy 334.152396 -229.214149) (xy 334.129525 -229.257726) (xy 334.09996 -229.29707)
			(xy 334.064467 -229.331162) (xy 334.023964 -229.359118) (xy 333.979502 -229.380216) (xy 333.932231 -229.393908)
			(xy 333.883376 -229.39984) (xy 333.834201 -229.397859) (xy 333.785982 -229.388015) (xy 333.739966 -229.370563)
			(xy 333.697345 -229.345956) (xy 333.659224 -229.314831) (xy 333.626589 -229.277994) (xy 333.600286 -229.236398)
			(xy 333.580995 -229.191122) (xy 333.569218 -229.143338) (xy 333.565258 -229.094284) (xy 333.236316 -229.094284)
			(xy 333.235821 -229.118891) (xy 333.227926 -229.167468) (xy 333.212342 -229.214149) (xy 333.189471 -229.257726)
			(xy 333.159906 -229.29707) (xy 333.124413 -229.331162) (xy 333.08391 -229.359118) (xy 333.039448 -229.380216)
			(xy 332.992177 -229.393908) (xy 332.943322 -229.39984) (xy 332.894147 -229.397859) (xy 332.845928 -229.388015)
			(xy 332.799912 -229.370563) (xy 332.757291 -229.345956) (xy 332.71917 -229.314831) (xy 332.686535 -229.277994)
			(xy 332.660232 -229.236398) (xy 332.640941 -229.191122) (xy 332.629164 -229.143338) (xy 332.625204 -229.094284)
			(xy 332.296516 -229.094284) (xy 332.296021 -229.118891) (xy 332.288126 -229.167468) (xy 332.272542 -229.214149)
			(xy 332.249671 -229.257726) (xy 332.220106 -229.29707) (xy 332.184613 -229.331162) (xy 332.14411 -229.359118)
			(xy 332.099648 -229.380216) (xy 332.052377 -229.393908) (xy 332.003522 -229.39984) (xy 331.954347 -229.397859)
			(xy 331.906128 -229.388015) (xy 331.860112 -229.370563) (xy 331.817491 -229.345956) (xy 331.77937 -229.314831)
			(xy 331.746735 -229.277994) (xy 331.720432 -229.236398) (xy 331.701141 -229.191122) (xy 331.689364 -229.143338)
			(xy 331.685404 -229.094284) (xy 331.459332 -229.094284) (xy 331.459332 -229.500176) (xy 331.459805 -229.509533)
			(xy 331.466573 -229.526989) (xy 331.47254 -229.534212) (xy 331.517498 -229.583742) (xy 331.520812 -229.587208)
			(xy 331.528483 -229.59296) (xy 331.532738 -229.595172) (xy 331.540612 -229.598982) (xy 331.550264 -229.599998)
			(xy 331.550518 -229.599998) (xy 331.575385 -229.602909) (xy 331.623761 -229.615793) (xy 331.669388 -229.636393)
			(xy 331.711045 -229.66416) (xy 331.747617 -229.698348) (xy 331.778123 -229.738042) (xy 331.801747 -229.78218)
			(xy 331.817856 -229.82958) (xy 331.82602 -229.878972) (xy 331.82602 -229.904036) (xy 332.155304 -229.904036)
			(xy 332.159264 -229.854982) (xy 332.171041 -229.807198) (xy 332.190332 -229.761922) (xy 332.216635 -229.720326)
			(xy 332.24927 -229.683489) (xy 332.287391 -229.652364) (xy 332.330012 -229.627757) (xy 332.376028 -229.610305)
			(xy 332.424247 -229.600461) (xy 332.473422 -229.59848) (xy 332.522277 -229.604412) (xy 332.569548 -229.618104)
			(xy 332.61401 -229.639202) (xy 332.654513 -229.667158) (xy 332.690006 -229.70125) (xy 332.719571 -229.740594)
			(xy 332.742442 -229.784171) (xy 332.758026 -229.830852) (xy 332.765921 -229.879429) (xy 332.766416 -229.904036)
			(xy 333.095358 -229.904036) (xy 333.099318 -229.854982) (xy 333.111095 -229.807198) (xy 333.130386 -229.761922)
			(xy 333.156689 -229.720326) (xy 333.189324 -229.683489) (xy 333.227445 -229.652364) (xy 333.270066 -229.627757)
			(xy 333.316082 -229.610305) (xy 333.364301 -229.600461) (xy 333.413476 -229.59848) (xy 333.462331 -229.604412)
			(xy 333.509602 -229.618104) (xy 333.554064 -229.639202) (xy 333.594567 -229.667158) (xy 333.63006 -229.70125)
			(xy 333.659625 -229.740594) (xy 333.682496 -229.784171) (xy 333.69808 -229.830852) (xy 333.705975 -229.879429)
			(xy 333.70647 -229.904036) (xy 334.975212 -229.904036) (xy 334.979172 -229.854982) (xy 334.990949 -229.807198)
			(xy 335.01024 -229.761922) (xy 335.036543 -229.720326) (xy 335.069178 -229.683489) (xy 335.107299 -229.652364)
			(xy 335.14992 -229.627757) (xy 335.195936 -229.610305) (xy 335.244155 -229.600461) (xy 335.29333 -229.59848)
			(xy 335.342185 -229.604412) (xy 335.389456 -229.618104) (xy 335.433918 -229.639202) (xy 335.474421 -229.667158)
			(xy 335.509914 -229.70125) (xy 335.539479 -229.740594) (xy 335.56235 -229.784171) (xy 335.577934 -229.830852)
			(xy 335.585829 -229.879429) (xy 335.586324 -229.904036) (xy 335.915266 -229.904036) (xy 335.919226 -229.854982)
			(xy 335.931003 -229.807198) (xy 335.950294 -229.761922) (xy 335.976597 -229.720326) (xy 336.009232 -229.683489)
			(xy 336.047353 -229.652364) (xy 336.089974 -229.627757) (xy 336.13599 -229.610305) (xy 336.184209 -229.600461)
			(xy 336.233384 -229.59848) (xy 336.282239 -229.604412) (xy 336.32951 -229.618104) (xy 336.373972 -229.639202)
			(xy 336.414475 -229.667158) (xy 336.449968 -229.70125) (xy 336.479533 -229.740594) (xy 336.502404 -229.784171)
			(xy 336.517988 -229.830852) (xy 336.525883 -229.879429) (xy 336.526378 -229.904036) (xy 336.85532 -229.904036)
			(xy 336.85928 -229.854982) (xy 336.871057 -229.807198) (xy 336.890348 -229.761922) (xy 336.916651 -229.720326)
			(xy 336.949286 -229.683489) (xy 336.987407 -229.652364) (xy 337.030028 -229.627757) (xy 337.076044 -229.610305)
			(xy 337.124263 -229.600461) (xy 337.173438 -229.59848) (xy 337.222293 -229.604412) (xy 337.269564 -229.618104)
			(xy 337.314026 -229.639202) (xy 337.354529 -229.667158) (xy 337.390022 -229.70125) (xy 337.419587 -229.740594)
			(xy 337.442458 -229.784171) (xy 337.458042 -229.830852) (xy 337.465937 -229.879429) (xy 337.466432 -229.904036)
			(xy 337.795374 -229.904036) (xy 337.799334 -229.854982) (xy 337.811111 -229.807198) (xy 337.830402 -229.761922)
			(xy 337.856705 -229.720326) (xy 337.88934 -229.683489) (xy 337.927461 -229.652364) (xy 337.970082 -229.627757)
			(xy 338.016098 -229.610305) (xy 338.064317 -229.600461) (xy 338.113492 -229.59848) (xy 338.162347 -229.604412)
			(xy 338.209618 -229.618104) (xy 338.25408 -229.639202) (xy 338.294583 -229.667158) (xy 338.330076 -229.70125)
			(xy 338.359641 -229.740594) (xy 338.382512 -229.784171) (xy 338.398096 -229.830852) (xy 338.405991 -229.879429)
			(xy 338.406486 -229.904036) (xy 338.724743 -229.904036) (xy 338.728838 -229.853308) (xy 338.741017 -229.803894)
			(xy 338.760965 -229.757074) (xy 338.788166 -229.71406) (xy 338.821914 -229.675966) (xy 338.861336 -229.643779)
			(xy 338.90541 -229.618333) (xy 338.952996 -229.600286) (xy 339.00286 -229.590106) (xy 339.053712 -229.588057)
			(xy 339.104233 -229.594191) (xy 339.153117 -229.608351) (xy 339.199096 -229.630168) (xy 339.24098 -229.659078)
			(xy 339.277684 -229.694333) (xy 339.308257 -229.735019) (xy 339.331908 -229.780082) (xy 339.348024 -229.828356)
			(xy 339.356188 -229.87859) (xy 339.3567 -229.904036) (xy 339.664797 -229.904036) (xy 339.668892 -229.853308)
			(xy 339.681071 -229.803894) (xy 339.701019 -229.757074) (xy 339.72822 -229.71406) (xy 339.761968 -229.675966)
			(xy 339.80139 -229.643779) (xy 339.845464 -229.618333) (xy 339.89305 -229.600286) (xy 339.942914 -229.590106)
			(xy 339.993766 -229.588057) (xy 340.044287 -229.594191) (xy 340.093171 -229.608351) (xy 340.13915 -229.630168)
			(xy 340.181034 -229.659078) (xy 340.217738 -229.694333) (xy 340.248311 -229.735019) (xy 340.271962 -229.780082)
			(xy 340.288078 -229.828356) (xy 340.296242 -229.87859) (xy 340.296754 -229.904036) (xy 341.544905 -229.904036)
			(xy 341.549 -229.853308) (xy 341.561179 -229.803894) (xy 341.581127 -229.757074) (xy 341.608328 -229.71406)
			(xy 341.642076 -229.675966) (xy 341.681498 -229.643779) (xy 341.725572 -229.618333) (xy 341.773158 -229.600286)
			(xy 341.823022 -229.590106) (xy 341.873874 -229.588057) (xy 341.924395 -229.594191) (xy 341.973279 -229.608351)
			(xy 342.019258 -229.630168) (xy 342.061142 -229.659078) (xy 342.097846 -229.694333) (xy 342.128419 -229.735019)
			(xy 342.15207 -229.780082) (xy 342.168186 -229.828356) (xy 342.17635 -229.87859) (xy 342.176862 -229.904036)
			(xy 342.49539 -229.904036) (xy 342.49935 -229.854982) (xy 342.511127 -229.807198) (xy 342.530418 -229.761922)
			(xy 342.556721 -229.720326) (xy 342.589356 -229.683489) (xy 342.627477 -229.652364) (xy 342.670098 -229.627757)
			(xy 342.716114 -229.610305) (xy 342.764333 -229.600461) (xy 342.813508 -229.59848) (xy 342.862363 -229.604412)
			(xy 342.909634 -229.618104) (xy 342.954096 -229.639202) (xy 342.994599 -229.667158) (xy 343.030092 -229.70125)
			(xy 343.059657 -229.740594) (xy 343.082528 -229.784171) (xy 343.098112 -229.830852) (xy 343.106007 -229.879429)
			(xy 343.106502 -229.904036) (xy 343.106007 -229.928643) (xy 343.098112 -229.97722) (xy 343.082528 -230.023901)
			(xy 343.059657 -230.067478) (xy 343.030092 -230.106822) (xy 342.994599 -230.140914) (xy 342.954096 -230.16887)
			(xy 342.909634 -230.189968) (xy 342.862363 -230.20366) (xy 342.813508 -230.209592) (xy 342.764333 -230.207611)
			(xy 342.716114 -230.197767) (xy 342.670098 -230.180315) (xy 342.627477 -230.155708) (xy 342.589356 -230.124583)
			(xy 342.556721 -230.087746) (xy 342.530418 -230.04615) (xy 342.511127 -230.000874) (xy 342.49935 -229.95309)
			(xy 342.49539 -229.904036) (xy 342.176862 -229.904036) (xy 342.17635 -229.929482) (xy 342.168186 -229.979716)
			(xy 342.15207 -230.02799) (xy 342.128419 -230.073053) (xy 342.097846 -230.113739) (xy 342.061142 -230.148994)
			(xy 342.019258 -230.177904) (xy 341.973279 -230.199721) (xy 341.924395 -230.213881) (xy 341.873874 -230.220015)
			(xy 341.823022 -230.217966) (xy 341.773158 -230.207786) (xy 341.725572 -230.189739) (xy 341.681498 -230.164293)
			(xy 341.642076 -230.132106) (xy 341.608328 -230.094012) (xy 341.581127 -230.050998) (xy 341.561179 -230.004178)
			(xy 341.549 -229.954764) (xy 341.544905 -229.904036) (xy 340.296754 -229.904036) (xy 340.296242 -229.929482)
			(xy 340.288078 -229.979716) (xy 340.271962 -230.02799) (xy 340.248311 -230.073053) (xy 340.217738 -230.113739)
			(xy 340.181034 -230.148994) (xy 340.13915 -230.177904) (xy 340.093171 -230.199721) (xy 340.044287 -230.213881)
			(xy 339.993766 -230.220015) (xy 339.942914 -230.217966) (xy 339.89305 -230.207786) (xy 339.845464 -230.189739)
			(xy 339.80139 -230.164293) (xy 339.761968 -230.132106) (xy 339.72822 -230.094012) (xy 339.701019 -230.050998)
			(xy 339.681071 -230.004178) (xy 339.668892 -229.954764) (xy 339.664797 -229.904036) (xy 339.3567 -229.904036)
			(xy 339.356188 -229.929482) (xy 339.348024 -229.979716) (xy 339.331908 -230.02799) (xy 339.308257 -230.073053)
			(xy 339.277684 -230.113739) (xy 339.24098 -230.148994) (xy 339.199096 -230.177904) (xy 339.153117 -230.199721)
			(xy 339.104233 -230.213881) (xy 339.053712 -230.220015) (xy 339.00286 -230.217966) (xy 338.952996 -230.207786)
			(xy 338.90541 -230.189739) (xy 338.861336 -230.164293) (xy 338.821914 -230.132106) (xy 338.788166 -230.094012)
			(xy 338.760965 -230.050998) (xy 338.741017 -230.004178) (xy 338.728838 -229.954764) (xy 338.724743 -229.904036)
			(xy 338.406486 -229.904036) (xy 338.405991 -229.928643) (xy 338.398096 -229.97722) (xy 338.382512 -230.023901)
			(xy 338.359641 -230.067478) (xy 338.330076 -230.106822) (xy 338.294583 -230.140914) (xy 338.25408 -230.16887)
			(xy 338.209618 -230.189968) (xy 338.162347 -230.20366) (xy 338.113492 -230.209592) (xy 338.064317 -230.207611)
			(xy 338.016098 -230.197767) (xy 337.970082 -230.180315) (xy 337.927461 -230.155708) (xy 337.88934 -230.124583)
			(xy 337.856705 -230.087746) (xy 337.830402 -230.04615) (xy 337.811111 -230.000874) (xy 337.799334 -229.95309)
			(xy 337.795374 -229.904036) (xy 337.466432 -229.904036) (xy 337.465937 -229.928643) (xy 337.458042 -229.97722)
			(xy 337.442458 -230.023901) (xy 337.419587 -230.067478) (xy 337.390022 -230.106822) (xy 337.354529 -230.140914)
			(xy 337.314026 -230.16887) (xy 337.269564 -230.189968) (xy 337.222293 -230.20366) (xy 337.173438 -230.209592)
			(xy 337.124263 -230.207611) (xy 337.076044 -230.197767) (xy 337.030028 -230.180315) (xy 336.987407 -230.155708)
			(xy 336.949286 -230.124583) (xy 336.916651 -230.087746) (xy 336.890348 -230.04615) (xy 336.871057 -230.000874)
			(xy 336.85928 -229.95309) (xy 336.85532 -229.904036) (xy 336.526378 -229.904036) (xy 336.525883 -229.928643)
			(xy 336.517988 -229.97722) (xy 336.502404 -230.023901) (xy 336.479533 -230.067478) (xy 336.449968 -230.106822)
			(xy 336.414475 -230.140914) (xy 336.373972 -230.16887) (xy 336.32951 -230.189968) (xy 336.282239 -230.20366)
			(xy 336.233384 -230.209592) (xy 336.184209 -230.207611) (xy 336.13599 -230.197767) (xy 336.089974 -230.180315)
			(xy 336.047353 -230.155708) (xy 336.009232 -230.124583) (xy 335.976597 -230.087746) (xy 335.950294 -230.04615)
			(xy 335.931003 -230.000874) (xy 335.919226 -229.95309) (xy 335.915266 -229.904036) (xy 335.586324 -229.904036)
			(xy 335.585829 -229.928643) (xy 335.577934 -229.97722) (xy 335.56235 -230.023901) (xy 335.539479 -230.067478)
			(xy 335.509914 -230.106822) (xy 335.474421 -230.140914) (xy 335.433918 -230.16887) (xy 335.389456 -230.189968)
			(xy 335.342185 -230.20366) (xy 335.29333 -230.209592) (xy 335.244155 -230.207611) (xy 335.195936 -230.197767)
			(xy 335.14992 -230.180315) (xy 335.107299 -230.155708) (xy 335.069178 -230.124583) (xy 335.036543 -230.087746)
			(xy 335.01024 -230.04615) (xy 334.990949 -230.000874) (xy 334.979172 -229.95309) (xy 334.975212 -229.904036)
			(xy 333.70647 -229.904036) (xy 333.705975 -229.928643) (xy 333.69808 -229.97722) (xy 333.682496 -230.023901)
			(xy 333.659625 -230.067478) (xy 333.63006 -230.106822) (xy 333.594567 -230.140914) (xy 333.554064 -230.16887)
			(xy 333.509602 -230.189968) (xy 333.462331 -230.20366) (xy 333.413476 -230.209592) (xy 333.364301 -230.207611)
			(xy 333.316082 -230.197767) (xy 333.270066 -230.180315) (xy 333.227445 -230.155708) (xy 333.189324 -230.124583)
			(xy 333.156689 -230.087746) (xy 333.130386 -230.04615) (xy 333.111095 -230.000874) (xy 333.099318 -229.95309)
			(xy 333.095358 -229.904036) (xy 332.766416 -229.904036) (xy 332.765921 -229.928643) (xy 332.758026 -229.97722)
			(xy 332.742442 -230.023901) (xy 332.719571 -230.067478) (xy 332.690006 -230.106822) (xy 332.654513 -230.140914)
			(xy 332.61401 -230.16887) (xy 332.569548 -230.189968) (xy 332.522277 -230.20366) (xy 332.473422 -230.209592)
			(xy 332.424247 -230.207611) (xy 332.376028 -230.197767) (xy 332.330012 -230.180315) (xy 332.287391 -230.155708)
			(xy 332.24927 -230.124583) (xy 332.216635 -230.087746) (xy 332.190332 -230.04615) (xy 332.171041 -230.000874)
			(xy 332.159264 -229.95309) (xy 332.155304 -229.904036) (xy 331.82602 -229.904036) (xy 331.82602 -229.929035)
			(xy 331.817855 -229.978427) (xy 331.801744 -230.025826) (xy 331.778119 -230.069964) (xy 331.747612 -230.109658)
			(xy 331.71104 -230.143845) (xy 331.669382 -230.17161) (xy 331.623754 -230.19221) (xy 331.575378 -230.205092)
			(xy 331.550518 -230.208074) (xy 331.550264 -230.208074) (xy 331.540612 -230.20909) (xy 331.532738 -230.2129)
			(xy 331.528476 -230.215101) (xy 331.520798 -230.220849) (xy 331.517498 -230.22433) (xy 331.47254 -230.27386)
			(xy 331.466488 -230.281033) (xy 331.45971 -230.298518) (xy 331.459332 -230.307896) (xy 331.459332 -230.714296)
			(xy 331.685404 -230.714296) (xy 331.689364 -230.665242) (xy 331.701141 -230.617458) (xy 331.720432 -230.572182)
			(xy 331.746735 -230.530586) (xy 331.77937 -230.493749) (xy 331.817491 -230.462624) (xy 331.860112 -230.438017)
			(xy 331.906128 -230.420565) (xy 331.954347 -230.410721) (xy 332.003522 -230.40874) (xy 332.052377 -230.414672)
			(xy 332.099648 -230.428364) (xy 332.14411 -230.449462) (xy 332.184613 -230.477418) (xy 332.220106 -230.51151)
			(xy 332.249671 -230.550854) (xy 332.272542 -230.594431) (xy 332.288126 -230.641112) (xy 332.296021 -230.689689)
			(xy 332.296511 -230.714042) (xy 332.625204 -230.714042) (xy 332.629164 -230.664988) (xy 332.640941 -230.617204)
			(xy 332.660232 -230.571928) (xy 332.686535 -230.530332) (xy 332.71917 -230.493495) (xy 332.757291 -230.46237)
			(xy 332.799912 -230.437763) (xy 332.845928 -230.420311) (xy 332.894147 -230.410467) (xy 332.943322 -230.408486)
			(xy 332.992177 -230.414418) (xy 333.039448 -230.42811) (xy 333.08391 -230.449208) (xy 333.124413 -230.477164)
			(xy 333.159906 -230.511256) (xy 333.189471 -230.5506) (xy 333.212342 -230.594177) (xy 333.227926 -230.640858)
			(xy 333.235821 -230.689435) (xy 333.236316 -230.714042) (xy 333.236311 -230.714296) (xy 333.565258 -230.714296)
			(xy 333.569218 -230.665242) (xy 333.580995 -230.617458) (xy 333.600286 -230.572182) (xy 333.626589 -230.530586)
			(xy 333.659224 -230.493749) (xy 333.697345 -230.462624) (xy 333.739966 -230.438017) (xy 333.785982 -230.420565)
			(xy 333.834201 -230.410721) (xy 333.883376 -230.40874) (xy 333.932231 -230.414672) (xy 333.979502 -230.428364)
			(xy 334.023964 -230.449462) (xy 334.064467 -230.477418) (xy 334.09996 -230.51151) (xy 334.129525 -230.550854)
			(xy 334.152396 -230.594431) (xy 334.16798 -230.641112) (xy 334.175875 -230.689689) (xy 334.17637 -230.714296)
			(xy 334.505312 -230.714296) (xy 334.509272 -230.665242) (xy 334.521049 -230.617458) (xy 334.54034 -230.572182)
			(xy 334.566643 -230.530586) (xy 334.599278 -230.493749) (xy 334.637399 -230.462624) (xy 334.68002 -230.438017)
			(xy 334.726036 -230.420565) (xy 334.774255 -230.410721) (xy 334.82343 -230.40874) (xy 334.872285 -230.414672)
			(xy 334.919556 -230.428364) (xy 334.964018 -230.449462) (xy 335.004521 -230.477418) (xy 335.040014 -230.51151)
			(xy 335.069579 -230.550854) (xy 335.09245 -230.594431) (xy 335.108034 -230.641112) (xy 335.115929 -230.689689)
			(xy 335.116424 -230.714296) (xy 335.445366 -230.714296) (xy 335.449326 -230.665242) (xy 335.461103 -230.617458)
			(xy 335.480394 -230.572182) (xy 335.506697 -230.530586) (xy 335.539332 -230.493749) (xy 335.577453 -230.462624)
			(xy 335.620074 -230.438017) (xy 335.66609 -230.420565) (xy 335.714309 -230.410721) (xy 335.763484 -230.40874)
			(xy 335.812339 -230.414672) (xy 335.85961 -230.428364) (xy 335.904072 -230.449462) (xy 335.944575 -230.477418)
			(xy 335.980068 -230.51151) (xy 336.009633 -230.550854) (xy 336.032504 -230.594431) (xy 336.048088 -230.641112)
			(xy 336.055983 -230.689689) (xy 336.056478 -230.714296) (xy 336.38542 -230.714296) (xy 336.38938 -230.665242)
			(xy 336.401157 -230.617458) (xy 336.420448 -230.572182) (xy 336.446751 -230.530586) (xy 336.479386 -230.493749)
			(xy 336.517507 -230.462624) (xy 336.560128 -230.438017) (xy 336.606144 -230.420565) (xy 336.654363 -230.410721)
			(xy 336.703538 -230.40874) (xy 336.752393 -230.414672) (xy 336.799664 -230.428364) (xy 336.844126 -230.449462)
			(xy 336.884629 -230.477418) (xy 336.920122 -230.51151) (xy 336.949687 -230.550854) (xy 336.972558 -230.594431)
			(xy 336.988142 -230.641112) (xy 336.996037 -230.689689) (xy 336.996527 -230.714042) (xy 337.32522 -230.714042)
			(xy 337.32918 -230.664988) (xy 337.340957 -230.617204) (xy 337.360248 -230.571928) (xy 337.386551 -230.530332)
			(xy 337.419186 -230.493495) (xy 337.457307 -230.46237) (xy 337.499928 -230.437763) (xy 337.545944 -230.420311)
			(xy 337.594163 -230.410467) (xy 337.643338 -230.408486) (xy 337.692193 -230.414418) (xy 337.739464 -230.42811)
			(xy 337.783926 -230.449208) (xy 337.824429 -230.477164) (xy 337.859922 -230.511256) (xy 337.889487 -230.5506)
			(xy 337.912358 -230.594177) (xy 337.927942 -230.640858) (xy 337.935837 -230.689435) (xy 337.936332 -230.714042)
			(xy 337.936327 -230.714296) (xy 338.254843 -230.714296) (xy 338.258938 -230.663568) (xy 338.271117 -230.614154)
			(xy 338.291065 -230.567334) (xy 338.318266 -230.52432) (xy 338.352014 -230.486226) (xy 338.391436 -230.454039)
			(xy 338.43551 -230.428593) (xy 338.483096 -230.410546) (xy 338.53296 -230.400366) (xy 338.583812 -230.398317)
			(xy 338.634333 -230.404451) (xy 338.683217 -230.418611) (xy 338.729196 -230.440428) (xy 338.77108 -230.469338)
			(xy 338.807784 -230.504593) (xy 338.838357 -230.545279) (xy 338.862008 -230.590342) (xy 338.878124 -230.638616)
			(xy 338.886288 -230.68885) (xy 338.8868 -230.714296) (xy 339.205328 -230.714296) (xy 339.209288 -230.665242)
			(xy 339.221065 -230.617458) (xy 339.240356 -230.572182) (xy 339.266659 -230.530586) (xy 339.299294 -230.493749)
			(xy 339.337415 -230.462624) (xy 339.380036 -230.438017) (xy 339.426052 -230.420565) (xy 339.474271 -230.410721)
			(xy 339.523446 -230.40874) (xy 339.572301 -230.414672) (xy 339.619572 -230.428364) (xy 339.664034 -230.449462)
			(xy 339.704537 -230.477418) (xy 339.74003 -230.51151) (xy 339.769595 -230.550854) (xy 339.792466 -230.594431)
			(xy 339.80805 -230.641112) (xy 339.815945 -230.689689) (xy 339.81644 -230.714296) (xy 340.134951 -230.714296)
			(xy 340.139046 -230.663568) (xy 340.151225 -230.614154) (xy 340.171173 -230.567334) (xy 340.198374 -230.52432)
			(xy 340.232122 -230.486226) (xy 340.271544 -230.454039) (xy 340.315618 -230.428593) (xy 340.363204 -230.410546)
			(xy 340.413068 -230.400366) (xy 340.46392 -230.398317) (xy 340.514441 -230.404451) (xy 340.563325 -230.418611)
			(xy 340.609304 -230.440428) (xy 340.651188 -230.469338) (xy 340.687892 -230.504593) (xy 340.718465 -230.545279)
			(xy 340.742116 -230.590342) (xy 340.758232 -230.638616) (xy 340.766396 -230.68885) (xy 340.766903 -230.714042)
			(xy 341.085182 -230.714042) (xy 341.089142 -230.664988) (xy 341.100919 -230.617204) (xy 341.12021 -230.571928)
			(xy 341.146513 -230.530332) (xy 341.179148 -230.493495) (xy 341.217269 -230.46237) (xy 341.25989 -230.437763)
			(xy 341.305906 -230.420311) (xy 341.354125 -230.410467) (xy 341.4033 -230.408486) (xy 341.452155 -230.414418)
			(xy 341.499426 -230.42811) (xy 341.543888 -230.449208) (xy 341.584391 -230.477164) (xy 341.619884 -230.511256)
			(xy 341.649449 -230.5506) (xy 341.67232 -230.594177) (xy 341.687904 -230.640858) (xy 341.695799 -230.689435)
			(xy 341.696294 -230.714042) (xy 341.696289 -230.714296) (xy 342.014805 -230.714296) (xy 342.0189 -230.663568)
			(xy 342.031079 -230.614154) (xy 342.051027 -230.567334) (xy 342.078228 -230.52432) (xy 342.111976 -230.486226)
			(xy 342.151398 -230.454039) (xy 342.195472 -230.428593) (xy 342.243058 -230.410546) (xy 342.292922 -230.400366)
			(xy 342.343774 -230.398317) (xy 342.394295 -230.404451) (xy 342.443179 -230.418611) (xy 342.489158 -230.440428)
			(xy 342.531042 -230.469338) (xy 342.567746 -230.504593) (xy 342.598319 -230.545279) (xy 342.62197 -230.590342)
			(xy 342.638086 -230.638616) (xy 342.64625 -230.68885) (xy 342.646762 -230.714296) (xy 342.64625 -230.739742)
			(xy 342.638086 -230.789976) (xy 342.62197 -230.83825) (xy 342.598319 -230.883313) (xy 342.567746 -230.923999)
			(xy 342.531042 -230.959254) (xy 342.489158 -230.988164) (xy 342.443179 -231.009981) (xy 342.394295 -231.024141)
			(xy 342.343774 -231.030275) (xy 342.292922 -231.028226) (xy 342.243058 -231.018046) (xy 342.195472 -230.999999)
			(xy 342.151398 -230.974553) (xy 342.111976 -230.942366) (xy 342.078228 -230.904272) (xy 342.051027 -230.861258)
			(xy 342.031079 -230.814438) (xy 342.0189 -230.765024) (xy 342.014805 -230.714296) (xy 341.696289 -230.714296)
			(xy 341.695799 -230.738649) (xy 341.687904 -230.787226) (xy 341.67232 -230.833907) (xy 341.649449 -230.877484)
			(xy 341.619884 -230.916828) (xy 341.584391 -230.95092) (xy 341.543888 -230.978876) (xy 341.499426 -230.999974)
			(xy 341.452155 -231.013666) (xy 341.4033 -231.019598) (xy 341.354125 -231.017617) (xy 341.305906 -231.007773)
			(xy 341.25989 -230.990321) (xy 341.217269 -230.965714) (xy 341.179148 -230.934589) (xy 341.146513 -230.897752)
			(xy 341.12021 -230.856156) (xy 341.100919 -230.81088) (xy 341.089142 -230.763096) (xy 341.085182 -230.714042)
			(xy 340.766903 -230.714042) (xy 340.766908 -230.714296) (xy 340.766396 -230.739742) (xy 340.758232 -230.789976)
			(xy 340.742116 -230.83825) (xy 340.718465 -230.883313) (xy 340.687892 -230.923999) (xy 340.651188 -230.959254)
			(xy 340.609304 -230.988164) (xy 340.563325 -231.009981) (xy 340.514441 -231.024141) (xy 340.46392 -231.030275)
			(xy 340.413068 -231.028226) (xy 340.363204 -231.018046) (xy 340.315618 -230.999999) (xy 340.271544 -230.974553)
			(xy 340.232122 -230.942366) (xy 340.198374 -230.904272) (xy 340.171173 -230.861258) (xy 340.151225 -230.814438)
			(xy 340.139046 -230.765024) (xy 340.134951 -230.714296) (xy 339.81644 -230.714296) (xy 339.815945 -230.738903)
			(xy 339.80805 -230.78748) (xy 339.792466 -230.834161) (xy 339.769595 -230.877738) (xy 339.74003 -230.917082)
			(xy 339.704537 -230.951174) (xy 339.664034 -230.97913) (xy 339.619572 -231.000228) (xy 339.572301 -231.01392)
			(xy 339.523446 -231.019852) (xy 339.474271 -231.017871) (xy 339.426052 -231.008027) (xy 339.380036 -230.990575)
			(xy 339.337415 -230.965968) (xy 339.299294 -230.934843) (xy 339.266659 -230.898006) (xy 339.240356 -230.85641)
			(xy 339.221065 -230.811134) (xy 339.209288 -230.76335) (xy 339.205328 -230.714296) (xy 338.8868 -230.714296)
			(xy 338.886288 -230.739742) (xy 338.878124 -230.789976) (xy 338.862008 -230.83825) (xy 338.838357 -230.883313)
			(xy 338.807784 -230.923999) (xy 338.77108 -230.959254) (xy 338.729196 -230.988164) (xy 338.683217 -231.009981)
			(xy 338.634333 -231.024141) (xy 338.583812 -231.030275) (xy 338.53296 -231.028226) (xy 338.483096 -231.018046)
			(xy 338.43551 -230.999999) (xy 338.391436 -230.974553) (xy 338.352014 -230.942366) (xy 338.318266 -230.904272)
			(xy 338.291065 -230.861258) (xy 338.271117 -230.814438) (xy 338.258938 -230.765024) (xy 338.254843 -230.714296)
			(xy 337.936327 -230.714296) (xy 337.935837 -230.738649) (xy 337.927942 -230.787226) (xy 337.912358 -230.833907)
			(xy 337.889487 -230.877484) (xy 337.859922 -230.916828) (xy 337.824429 -230.95092) (xy 337.783926 -230.978876)
			(xy 337.739464 -230.999974) (xy 337.692193 -231.013666) (xy 337.643338 -231.019598) (xy 337.594163 -231.017617)
			(xy 337.545944 -231.007773) (xy 337.499928 -230.990321) (xy 337.457307 -230.965714) (xy 337.419186 -230.934589)
			(xy 337.386551 -230.897752) (xy 337.360248 -230.856156) (xy 337.340957 -230.81088) (xy 337.32918 -230.763096)
			(xy 337.32522 -230.714042) (xy 336.996527 -230.714042) (xy 336.996532 -230.714296) (xy 336.996037 -230.738903)
			(xy 336.988142 -230.78748) (xy 336.972558 -230.834161) (xy 336.949687 -230.877738) (xy 336.920122 -230.917082)
			(xy 336.884629 -230.951174) (xy 336.844126 -230.97913) (xy 336.799664 -231.000228) (xy 336.752393 -231.01392)
			(xy 336.703538 -231.019852) (xy 336.654363 -231.017871) (xy 336.606144 -231.008027) (xy 336.560128 -230.990575)
			(xy 336.517507 -230.965968) (xy 336.479386 -230.934843) (xy 336.446751 -230.898006) (xy 336.420448 -230.85641)
			(xy 336.401157 -230.811134) (xy 336.38938 -230.76335) (xy 336.38542 -230.714296) (xy 336.056478 -230.714296)
			(xy 336.055983 -230.738903) (xy 336.048088 -230.78748) (xy 336.032504 -230.834161) (xy 336.009633 -230.877738)
			(xy 335.980068 -230.917082) (xy 335.944575 -230.951174) (xy 335.904072 -230.97913) (xy 335.85961 -231.000228)
			(xy 335.812339 -231.01392) (xy 335.763484 -231.019852) (xy 335.714309 -231.017871) (xy 335.66609 -231.008027)
			(xy 335.620074 -230.990575) (xy 335.577453 -230.965968) (xy 335.539332 -230.934843) (xy 335.506697 -230.898006)
			(xy 335.480394 -230.85641) (xy 335.461103 -230.811134) (xy 335.449326 -230.76335) (xy 335.445366 -230.714296)
			(xy 335.116424 -230.714296) (xy 335.115929 -230.738903) (xy 335.108034 -230.78748) (xy 335.09245 -230.834161)
			(xy 335.069579 -230.877738) (xy 335.040014 -230.917082) (xy 335.004521 -230.951174) (xy 334.964018 -230.97913)
			(xy 334.919556 -231.000228) (xy 334.872285 -231.01392) (xy 334.82343 -231.019852) (xy 334.774255 -231.017871)
			(xy 334.726036 -231.008027) (xy 334.68002 -230.990575) (xy 334.637399 -230.965968) (xy 334.599278 -230.934843)
			(xy 334.566643 -230.898006) (xy 334.54034 -230.85641) (xy 334.521049 -230.811134) (xy 334.509272 -230.76335)
			(xy 334.505312 -230.714296) (xy 334.17637 -230.714296) (xy 334.175875 -230.738903) (xy 334.16798 -230.78748)
			(xy 334.152396 -230.834161) (xy 334.129525 -230.877738) (xy 334.09996 -230.917082) (xy 334.064467 -230.951174)
			(xy 334.023964 -230.97913) (xy 333.979502 -231.000228) (xy 333.932231 -231.01392) (xy 333.883376 -231.019852)
			(xy 333.834201 -231.017871) (xy 333.785982 -231.008027) (xy 333.739966 -230.990575) (xy 333.697345 -230.965968)
			(xy 333.659224 -230.934843) (xy 333.626589 -230.898006) (xy 333.600286 -230.85641) (xy 333.580995 -230.811134)
			(xy 333.569218 -230.76335) (xy 333.565258 -230.714296) (xy 333.236311 -230.714296) (xy 333.235821 -230.738649)
			(xy 333.227926 -230.787226) (xy 333.212342 -230.833907) (xy 333.189471 -230.877484) (xy 333.159906 -230.916828)
			(xy 333.124413 -230.95092) (xy 333.08391 -230.978876) (xy 333.039448 -230.999974) (xy 332.992177 -231.013666)
			(xy 332.943322 -231.019598) (xy 332.894147 -231.017617) (xy 332.845928 -231.007773) (xy 332.799912 -230.990321)
			(xy 332.757291 -230.965714) (xy 332.71917 -230.934589) (xy 332.686535 -230.897752) (xy 332.660232 -230.856156)
			(xy 332.640941 -230.81088) (xy 332.629164 -230.763096) (xy 332.625204 -230.714042) (xy 332.296511 -230.714042)
			(xy 332.296516 -230.714296) (xy 332.296021 -230.738903) (xy 332.288126 -230.78748) (xy 332.272542 -230.834161)
			(xy 332.249671 -230.877738) (xy 332.220106 -230.917082) (xy 332.184613 -230.951174) (xy 332.14411 -230.97913)
			(xy 332.099648 -231.000228) (xy 332.052377 -231.01392) (xy 332.003522 -231.019852) (xy 331.954347 -231.017871)
			(xy 331.906128 -231.008027) (xy 331.860112 -230.990575) (xy 331.817491 -230.965968) (xy 331.77937 -230.934843)
			(xy 331.746735 -230.898006) (xy 331.720432 -230.85641) (xy 331.701141 -230.811134) (xy 331.689364 -230.76335)
			(xy 331.685404 -230.714296) (xy 331.459332 -230.714296) (xy 331.459332 -231.120188) (xy 331.459807 -231.129545)
			(xy 331.466578 -231.146997) (xy 331.47254 -231.154224) (xy 331.517498 -231.203754) (xy 331.520812 -231.20722)
			(xy 331.528484 -231.21297) (xy 331.532738 -231.215184) (xy 331.540612 -231.218994) (xy 331.550264 -231.22001)
			(xy 331.550518 -231.22001) (xy 331.575384 -231.222921) (xy 331.623758 -231.235804) (xy 331.669384 -231.256405)
			(xy 331.711039 -231.28417) (xy 331.747608 -231.318356) (xy 331.778113 -231.358049) (xy 331.801736 -231.402186)
			(xy 331.817845 -231.449584) (xy 331.826008 -231.498974) (xy 331.826008 -231.524048) (xy 332.155304 -231.524048)
			(xy 332.159264 -231.474994) (xy 332.171041 -231.42721) (xy 332.190332 -231.381934) (xy 332.216635 -231.340338)
			(xy 332.24927 -231.303501) (xy 332.287391 -231.272376) (xy 332.330012 -231.247769) (xy 332.376028 -231.230317)
			(xy 332.424247 -231.220473) (xy 332.473422 -231.218492) (xy 332.522277 -231.224424) (xy 332.569548 -231.238116)
			(xy 332.61401 -231.259214) (xy 332.654513 -231.28717) (xy 332.690006 -231.321262) (xy 332.719571 -231.360606)
			(xy 332.742442 -231.404183) (xy 332.758026 -231.450864) (xy 332.765921 -231.499441) (xy 332.766416 -231.524048)
			(xy 333.095358 -231.524048) (xy 333.099318 -231.474994) (xy 333.111095 -231.42721) (xy 333.130386 -231.381934)
			(xy 333.156689 -231.340338) (xy 333.189324 -231.303501) (xy 333.227445 -231.272376) (xy 333.270066 -231.247769)
			(xy 333.316082 -231.230317) (xy 333.364301 -231.220473) (xy 333.413476 -231.218492) (xy 333.462331 -231.224424)
			(xy 333.509602 -231.238116) (xy 333.554064 -231.259214) (xy 333.594567 -231.28717) (xy 333.63006 -231.321262)
			(xy 333.659625 -231.360606) (xy 333.682496 -231.404183) (xy 333.69808 -231.450864) (xy 333.705975 -231.499441)
			(xy 333.70647 -231.524048) (xy 334.035412 -231.524048) (xy 334.039372 -231.474994) (xy 334.051149 -231.42721)
			(xy 334.07044 -231.381934) (xy 334.096743 -231.340338) (xy 334.129378 -231.303501) (xy 334.167499 -231.272376)
			(xy 334.21012 -231.247769) (xy 334.256136 -231.230317) (xy 334.304355 -231.220473) (xy 334.35353 -231.218492)
			(xy 334.402385 -231.224424) (xy 334.449656 -231.238116) (xy 334.494118 -231.259214) (xy 334.534621 -231.28717)
			(xy 334.570114 -231.321262) (xy 334.599679 -231.360606) (xy 334.62255 -231.404183) (xy 334.638134 -231.450864)
			(xy 334.646029 -231.499441) (xy 334.646524 -231.524048) (xy 334.975212 -231.524048) (xy 334.979172 -231.474994)
			(xy 334.990949 -231.42721) (xy 335.01024 -231.381934) (xy 335.036543 -231.340338) (xy 335.069178 -231.303501)
			(xy 335.107299 -231.272376) (xy 335.14992 -231.247769) (xy 335.195936 -231.230317) (xy 335.244155 -231.220473)
			(xy 335.29333 -231.218492) (xy 335.342185 -231.224424) (xy 335.389456 -231.238116) (xy 335.433918 -231.259214)
			(xy 335.474421 -231.28717) (xy 335.509914 -231.321262) (xy 335.539479 -231.360606) (xy 335.56235 -231.404183)
			(xy 335.577934 -231.450864) (xy 335.585829 -231.499441) (xy 335.586324 -231.524048) (xy 335.915266 -231.524048)
			(xy 335.919226 -231.474994) (xy 335.931003 -231.42721) (xy 335.950294 -231.381934) (xy 335.976597 -231.340338)
			(xy 336.009232 -231.303501) (xy 336.047353 -231.272376) (xy 336.089974 -231.247769) (xy 336.13599 -231.230317)
			(xy 336.184209 -231.220473) (xy 336.233384 -231.218492) (xy 336.282239 -231.224424) (xy 336.32951 -231.238116)
			(xy 336.373972 -231.259214) (xy 336.414475 -231.28717) (xy 336.449968 -231.321262) (xy 336.479533 -231.360606)
			(xy 336.502404 -231.404183) (xy 336.517988 -231.450864) (xy 336.525883 -231.499441) (xy 336.526378 -231.524048)
			(xy 336.85532 -231.524048) (xy 336.85928 -231.474994) (xy 336.871057 -231.42721) (xy 336.890348 -231.381934)
			(xy 336.916651 -231.340338) (xy 336.949286 -231.303501) (xy 336.987407 -231.272376) (xy 337.030028 -231.247769)
			(xy 337.076044 -231.230317) (xy 337.124263 -231.220473) (xy 337.173438 -231.218492) (xy 337.222293 -231.224424)
			(xy 337.269564 -231.238116) (xy 337.314026 -231.259214) (xy 337.354529 -231.28717) (xy 337.390022 -231.321262)
			(xy 337.419587 -231.360606) (xy 337.442458 -231.404183) (xy 337.458042 -231.450864) (xy 337.465937 -231.499441)
			(xy 337.466432 -231.524048) (xy 337.795374 -231.524048) (xy 337.799334 -231.474994) (xy 337.811111 -231.42721)
			(xy 337.830402 -231.381934) (xy 337.856705 -231.340338) (xy 337.88934 -231.303501) (xy 337.927461 -231.272376)
			(xy 337.970082 -231.247769) (xy 338.016098 -231.230317) (xy 338.064317 -231.220473) (xy 338.113492 -231.218492)
			(xy 338.162347 -231.224424) (xy 338.209618 -231.238116) (xy 338.25408 -231.259214) (xy 338.294583 -231.28717)
			(xy 338.330076 -231.321262) (xy 338.359641 -231.360606) (xy 338.382512 -231.404183) (xy 338.398096 -231.450864)
			(xy 338.405991 -231.499441) (xy 338.406486 -231.524048) (xy 338.724743 -231.524048) (xy 338.728838 -231.47332)
			(xy 338.741017 -231.423906) (xy 338.760965 -231.377086) (xy 338.788166 -231.334072) (xy 338.821914 -231.295978)
			(xy 338.861336 -231.263791) (xy 338.90541 -231.238345) (xy 338.952996 -231.220298) (xy 339.00286 -231.210118)
			(xy 339.053712 -231.208069) (xy 339.104233 -231.214203) (xy 339.153117 -231.228363) (xy 339.199096 -231.25018)
			(xy 339.24098 -231.27909) (xy 339.277684 -231.314345) (xy 339.308257 -231.355031) (xy 339.331908 -231.400094)
			(xy 339.348024 -231.448368) (xy 339.356188 -231.498602) (xy 339.3567 -231.524048) (xy 339.664797 -231.524048)
			(xy 339.668892 -231.47332) (xy 339.681071 -231.423906) (xy 339.701019 -231.377086) (xy 339.72822 -231.334072)
			(xy 339.761968 -231.295978) (xy 339.80139 -231.263791) (xy 339.845464 -231.238345) (xy 339.89305 -231.220298)
			(xy 339.942914 -231.210118) (xy 339.993766 -231.208069) (xy 340.044287 -231.214203) (xy 340.093171 -231.228363)
			(xy 340.13915 -231.25018) (xy 340.181034 -231.27909) (xy 340.217738 -231.314345) (xy 340.248311 -231.355031)
			(xy 340.271962 -231.400094) (xy 340.288078 -231.448368) (xy 340.296242 -231.498602) (xy 340.296754 -231.524048)
			(xy 340.615282 -231.524048) (xy 340.619242 -231.474994) (xy 340.631019 -231.42721) (xy 340.65031 -231.381934)
			(xy 340.676613 -231.340338) (xy 340.709248 -231.303501) (xy 340.747369 -231.272376) (xy 340.78999 -231.247769)
			(xy 340.836006 -231.230317) (xy 340.884225 -231.220473) (xy 340.9334 -231.218492) (xy 340.982255 -231.224424)
			(xy 341.029526 -231.238116) (xy 341.073988 -231.259214) (xy 341.114491 -231.28717) (xy 341.149984 -231.321262)
			(xy 341.179549 -231.360606) (xy 341.20242 -231.404183) (xy 341.218004 -231.450864) (xy 341.225899 -231.499441)
			(xy 341.226394 -231.524048) (xy 341.544905 -231.524048) (xy 341.549 -231.47332) (xy 341.561179 -231.423906)
			(xy 341.581127 -231.377086) (xy 341.608328 -231.334072) (xy 341.642076 -231.295978) (xy 341.681498 -231.263791)
			(xy 341.725572 -231.238345) (xy 341.773158 -231.220298) (xy 341.823022 -231.210118) (xy 341.873874 -231.208069)
			(xy 341.924395 -231.214203) (xy 341.973279 -231.228363) (xy 342.019258 -231.25018) (xy 342.061142 -231.27909)
			(xy 342.097846 -231.314345) (xy 342.128419 -231.355031) (xy 342.15207 -231.400094) (xy 342.168186 -231.448368)
			(xy 342.17635 -231.498602) (xy 342.176862 -231.524048) (xy 342.49539 -231.524048) (xy 342.49935 -231.474994)
			(xy 342.511127 -231.42721) (xy 342.530418 -231.381934) (xy 342.556721 -231.340338) (xy 342.589356 -231.303501)
			(xy 342.627477 -231.272376) (xy 342.670098 -231.247769) (xy 342.716114 -231.230317) (xy 342.764333 -231.220473)
			(xy 342.813508 -231.218492) (xy 342.862363 -231.224424) (xy 342.909634 -231.238116) (xy 342.954096 -231.259214)
			(xy 342.994599 -231.28717) (xy 343.030092 -231.321262) (xy 343.059657 -231.360606) (xy 343.082528 -231.404183)
			(xy 343.098112 -231.450864) (xy 343.106007 -231.499441) (xy 343.106502 -231.524048) (xy 343.106007 -231.548655)
			(xy 343.098112 -231.597232) (xy 343.082528 -231.643913) (xy 343.059657 -231.68749) (xy 343.030092 -231.726834)
			(xy 342.994599 -231.760926) (xy 342.954096 -231.788882) (xy 342.909634 -231.80998) (xy 342.862363 -231.823672)
			(xy 342.813508 -231.829604) (xy 342.764333 -231.827623) (xy 342.716114 -231.817779) (xy 342.670098 -231.800327)
			(xy 342.627477 -231.77572) (xy 342.589356 -231.744595) (xy 342.556721 -231.707758) (xy 342.530418 -231.666162)
			(xy 342.511127 -231.620886) (xy 342.49935 -231.573102) (xy 342.49539 -231.524048) (xy 342.176862 -231.524048)
			(xy 342.17635 -231.549494) (xy 342.168186 -231.599728) (xy 342.15207 -231.648002) (xy 342.128419 -231.693065)
			(xy 342.097846 -231.733751) (xy 342.061142 -231.769006) (xy 342.019258 -231.797916) (xy 341.973279 -231.819733)
			(xy 341.924395 -231.833893) (xy 341.873874 -231.840027) (xy 341.823022 -231.837978) (xy 341.773158 -231.827798)
			(xy 341.725572 -231.809751) (xy 341.681498 -231.784305) (xy 341.642076 -231.752118) (xy 341.608328 -231.714024)
			(xy 341.581127 -231.67101) (xy 341.561179 -231.62419) (xy 341.549 -231.574776) (xy 341.544905 -231.524048)
			(xy 341.226394 -231.524048) (xy 341.225899 -231.548655) (xy 341.218004 -231.597232) (xy 341.20242 -231.643913)
			(xy 341.179549 -231.68749) (xy 341.149984 -231.726834) (xy 341.114491 -231.760926) (xy 341.073988 -231.788882)
			(xy 341.029526 -231.80998) (xy 340.982255 -231.823672) (xy 340.9334 -231.829604) (xy 340.884225 -231.827623)
			(xy 340.836006 -231.817779) (xy 340.78999 -231.800327) (xy 340.747369 -231.77572) (xy 340.709248 -231.744595)
			(xy 340.676613 -231.707758) (xy 340.65031 -231.666162) (xy 340.631019 -231.620886) (xy 340.619242 -231.573102)
			(xy 340.615282 -231.524048) (xy 340.296754 -231.524048) (xy 340.296242 -231.549494) (xy 340.288078 -231.599728)
			(xy 340.271962 -231.648002) (xy 340.248311 -231.693065) (xy 340.217738 -231.733751) (xy 340.181034 -231.769006)
			(xy 340.13915 -231.797916) (xy 340.093171 -231.819733) (xy 340.044287 -231.833893) (xy 339.993766 -231.840027)
			(xy 339.942914 -231.837978) (xy 339.89305 -231.827798) (xy 339.845464 -231.809751) (xy 339.80139 -231.784305)
			(xy 339.761968 -231.752118) (xy 339.72822 -231.714024) (xy 339.701019 -231.67101) (xy 339.681071 -231.62419)
			(xy 339.668892 -231.574776) (xy 339.664797 -231.524048) (xy 339.3567 -231.524048) (xy 339.356188 -231.549494)
			(xy 339.348024 -231.599728) (xy 339.331908 -231.648002) (xy 339.308257 -231.693065) (xy 339.277684 -231.733751)
			(xy 339.24098 -231.769006) (xy 339.199096 -231.797916) (xy 339.153117 -231.819733) (xy 339.104233 -231.833893)
			(xy 339.053712 -231.840027) (xy 339.00286 -231.837978) (xy 338.952996 -231.827798) (xy 338.90541 -231.809751)
			(xy 338.861336 -231.784305) (xy 338.821914 -231.752118) (xy 338.788166 -231.714024) (xy 338.760965 -231.67101)
			(xy 338.741017 -231.62419) (xy 338.728838 -231.574776) (xy 338.724743 -231.524048) (xy 338.406486 -231.524048)
			(xy 338.405991 -231.548655) (xy 338.398096 -231.597232) (xy 338.382512 -231.643913) (xy 338.359641 -231.68749)
			(xy 338.330076 -231.726834) (xy 338.294583 -231.760926) (xy 338.25408 -231.788882) (xy 338.209618 -231.80998)
			(xy 338.162347 -231.823672) (xy 338.113492 -231.829604) (xy 338.064317 -231.827623) (xy 338.016098 -231.817779)
			(xy 337.970082 -231.800327) (xy 337.927461 -231.77572) (xy 337.88934 -231.744595) (xy 337.856705 -231.707758)
			(xy 337.830402 -231.666162) (xy 337.811111 -231.620886) (xy 337.799334 -231.573102) (xy 337.795374 -231.524048)
			(xy 337.466432 -231.524048) (xy 337.465937 -231.548655) (xy 337.458042 -231.597232) (xy 337.442458 -231.643913)
			(xy 337.419587 -231.68749) (xy 337.390022 -231.726834) (xy 337.354529 -231.760926) (xy 337.314026 -231.788882)
			(xy 337.269564 -231.80998) (xy 337.222293 -231.823672) (xy 337.173438 -231.829604) (xy 337.124263 -231.827623)
			(xy 337.076044 -231.817779) (xy 337.030028 -231.800327) (xy 336.987407 -231.77572) (xy 336.949286 -231.744595)
			(xy 336.916651 -231.707758) (xy 336.890348 -231.666162) (xy 336.871057 -231.620886) (xy 336.85928 -231.573102)
			(xy 336.85532 -231.524048) (xy 336.526378 -231.524048) (xy 336.525883 -231.548655) (xy 336.517988 -231.597232)
			(xy 336.502404 -231.643913) (xy 336.479533 -231.68749) (xy 336.449968 -231.726834) (xy 336.414475 -231.760926)
			(xy 336.373972 -231.788882) (xy 336.32951 -231.80998) (xy 336.282239 -231.823672) (xy 336.233384 -231.829604)
			(xy 336.184209 -231.827623) (xy 336.13599 -231.817779) (xy 336.089974 -231.800327) (xy 336.047353 -231.77572)
			(xy 336.009232 -231.744595) (xy 335.976597 -231.707758) (xy 335.950294 -231.666162) (xy 335.931003 -231.620886)
			(xy 335.919226 -231.573102) (xy 335.915266 -231.524048) (xy 335.586324 -231.524048) (xy 335.585829 -231.548655)
			(xy 335.577934 -231.597232) (xy 335.56235 -231.643913) (xy 335.539479 -231.68749) (xy 335.509914 -231.726834)
			(xy 335.474421 -231.760926) (xy 335.433918 -231.788882) (xy 335.389456 -231.80998) (xy 335.342185 -231.823672)
			(xy 335.29333 -231.829604) (xy 335.244155 -231.827623) (xy 335.195936 -231.817779) (xy 335.14992 -231.800327)
			(xy 335.107299 -231.77572) (xy 335.069178 -231.744595) (xy 335.036543 -231.707758) (xy 335.01024 -231.666162)
			(xy 334.990949 -231.620886) (xy 334.979172 -231.573102) (xy 334.975212 -231.524048) (xy 334.646524 -231.524048)
			(xy 334.646029 -231.548655) (xy 334.638134 -231.597232) (xy 334.62255 -231.643913) (xy 334.599679 -231.68749)
			(xy 334.570114 -231.726834) (xy 334.534621 -231.760926) (xy 334.494118 -231.788882) (xy 334.449656 -231.80998)
			(xy 334.402385 -231.823672) (xy 334.35353 -231.829604) (xy 334.304355 -231.827623) (xy 334.256136 -231.817779)
			(xy 334.21012 -231.800327) (xy 334.167499 -231.77572) (xy 334.129378 -231.744595) (xy 334.096743 -231.707758)
			(xy 334.07044 -231.666162) (xy 334.051149 -231.620886) (xy 334.039372 -231.573102) (xy 334.035412 -231.524048)
			(xy 333.70647 -231.524048) (xy 333.705975 -231.548655) (xy 333.69808 -231.597232) (xy 333.682496 -231.643913)
			(xy 333.659625 -231.68749) (xy 333.63006 -231.726834) (xy 333.594567 -231.760926) (xy 333.554064 -231.788882)
			(xy 333.509602 -231.80998) (xy 333.462331 -231.823672) (xy 333.413476 -231.829604) (xy 333.364301 -231.827623)
			(xy 333.316082 -231.817779) (xy 333.270066 -231.800327) (xy 333.227445 -231.77572) (xy 333.189324 -231.744595)
			(xy 333.156689 -231.707758) (xy 333.130386 -231.666162) (xy 333.111095 -231.620886) (xy 333.099318 -231.573102)
			(xy 333.095358 -231.524048) (xy 332.766416 -231.524048) (xy 332.765921 -231.548655) (xy 332.758026 -231.597232)
			(xy 332.742442 -231.643913) (xy 332.719571 -231.68749) (xy 332.690006 -231.726834) (xy 332.654513 -231.760926)
			(xy 332.61401 -231.788882) (xy 332.569548 -231.80998) (xy 332.522277 -231.823672) (xy 332.473422 -231.829604)
			(xy 332.424247 -231.827623) (xy 332.376028 -231.817779) (xy 332.330012 -231.800327) (xy 332.287391 -231.77572)
			(xy 332.24927 -231.744595) (xy 332.216635 -231.707758) (xy 332.190332 -231.666162) (xy 332.171041 -231.620886)
			(xy 332.159264 -231.573102) (xy 332.155304 -231.524048) (xy 331.826008 -231.524048) (xy 331.826008 -231.549035)
			(xy 331.817843 -231.598425) (xy 331.801732 -231.645823) (xy 331.778108 -231.689958) (xy 331.747602 -231.72965)
			(xy 331.711032 -231.763836) (xy 331.669376 -231.7916) (xy 331.623749 -231.812199) (xy 331.575374 -231.825081)
			(xy 331.550518 -231.828086) (xy 331.550264 -231.828086) (xy 331.540612 -231.829102) (xy 331.532738 -231.832912)
			(xy 331.528476 -231.835113) (xy 331.520799 -231.840862) (xy 331.517498 -231.844342) (xy 331.47254 -231.893872)
			(xy 331.466491 -231.901045) (xy 331.459717 -231.918531) (xy 331.459332 -231.927908) (xy 331.459332 -232.334054)
			(xy 331.685404 -232.334054) (xy 331.689364 -232.285) (xy 331.701141 -232.237216) (xy 331.720432 -232.19194)
			(xy 331.746735 -232.150344) (xy 331.77937 -232.113507) (xy 331.817491 -232.082382) (xy 331.860112 -232.057775)
			(xy 331.906128 -232.040323) (xy 331.954347 -232.030479) (xy 332.003522 -232.028498) (xy 332.052377 -232.03443)
			(xy 332.099648 -232.048122) (xy 332.14411 -232.06922) (xy 332.184613 -232.097176) (xy 332.220106 -232.131268)
			(xy 332.249671 -232.170612) (xy 332.272542 -232.214189) (xy 332.288126 -232.26087) (xy 332.296021 -232.309447)
			(xy 332.296516 -232.334054) (xy 332.625204 -232.334054) (xy 332.629164 -232.285) (xy 332.640941 -232.237216)
			(xy 332.660232 -232.19194) (xy 332.686535 -232.150344) (xy 332.71917 -232.113507) (xy 332.757291 -232.082382)
			(xy 332.799912 -232.057775) (xy 332.845928 -232.040323) (xy 332.894147 -232.030479) (xy 332.943322 -232.028498)
			(xy 332.992177 -232.03443) (xy 333.039448 -232.048122) (xy 333.08391 -232.06922) (xy 333.124413 -232.097176)
			(xy 333.159906 -232.131268) (xy 333.189471 -232.170612) (xy 333.212342 -232.214189) (xy 333.227926 -232.26087)
			(xy 333.235821 -232.309447) (xy 333.236316 -232.334054) (xy 333.565258 -232.334054) (xy 333.569218 -232.285)
			(xy 333.580995 -232.237216) (xy 333.600286 -232.19194) (xy 333.626589 -232.150344) (xy 333.659224 -232.113507)
			(xy 333.697345 -232.082382) (xy 333.739966 -232.057775) (xy 333.785982 -232.040323) (xy 333.834201 -232.030479)
			(xy 333.883376 -232.028498) (xy 333.932231 -232.03443) (xy 333.979502 -232.048122) (xy 334.023964 -232.06922)
			(xy 334.064467 -232.097176) (xy 334.09996 -232.131268) (xy 334.129525 -232.170612) (xy 334.152396 -232.214189)
			(xy 334.16798 -232.26087) (xy 334.175875 -232.309447) (xy 334.17637 -232.334054) (xy 335.445366 -232.334054)
			(xy 335.449326 -232.285) (xy 335.461103 -232.237216) (xy 335.480394 -232.19194) (xy 335.506697 -232.150344)
			(xy 335.539332 -232.113507) (xy 335.577453 -232.082382) (xy 335.620074 -232.057775) (xy 335.66609 -232.040323)
			(xy 335.714309 -232.030479) (xy 335.763484 -232.028498) (xy 335.812339 -232.03443) (xy 335.85961 -232.048122)
			(xy 335.904072 -232.06922) (xy 335.944575 -232.097176) (xy 335.980068 -232.131268) (xy 336.009633 -232.170612)
			(xy 336.032504 -232.214189) (xy 336.048088 -232.26087) (xy 336.055983 -232.309447) (xy 336.056478 -232.334054)
			(xy 336.38542 -232.334054) (xy 336.38938 -232.285) (xy 336.401157 -232.237216) (xy 336.420448 -232.19194)
			(xy 336.446751 -232.150344) (xy 336.479386 -232.113507) (xy 336.517507 -232.082382) (xy 336.560128 -232.057775)
			(xy 336.606144 -232.040323) (xy 336.654363 -232.030479) (xy 336.703538 -232.028498) (xy 336.752393 -232.03443)
			(xy 336.799664 -232.048122) (xy 336.844126 -232.06922) (xy 336.884629 -232.097176) (xy 336.920122 -232.131268)
			(xy 336.949687 -232.170612) (xy 336.972558 -232.214189) (xy 336.988142 -232.26087) (xy 336.996037 -232.309447)
			(xy 336.996532 -232.334054) (xy 337.32522 -232.334054) (xy 337.32918 -232.285) (xy 337.340957 -232.237216)
			(xy 337.360248 -232.19194) (xy 337.386551 -232.150344) (xy 337.419186 -232.113507) (xy 337.457307 -232.082382)
			(xy 337.499928 -232.057775) (xy 337.545944 -232.040323) (xy 337.594163 -232.030479) (xy 337.643338 -232.028498)
			(xy 337.692193 -232.03443) (xy 337.739464 -232.048122) (xy 337.783926 -232.06922) (xy 337.824429 -232.097176)
			(xy 337.859922 -232.131268) (xy 337.889487 -232.170612) (xy 337.912358 -232.214189) (xy 337.927942 -232.26087)
			(xy 337.935837 -232.309447) (xy 337.936332 -232.334054) (xy 338.254843 -232.334054) (xy 338.258938 -232.283326)
			(xy 338.271117 -232.233912) (xy 338.291065 -232.187092) (xy 338.318266 -232.144078) (xy 338.352014 -232.105984)
			(xy 338.391436 -232.073797) (xy 338.43551 -232.048351) (xy 338.483096 -232.030304) (xy 338.53296 -232.020124)
			(xy 338.583812 -232.018075) (xy 338.634333 -232.024209) (xy 338.683217 -232.038369) (xy 338.729196 -232.060186)
			(xy 338.77108 -232.089096) (xy 338.807784 -232.124351) (xy 338.838357 -232.165037) (xy 338.862008 -232.2101)
			(xy 338.878124 -232.258374) (xy 338.886288 -232.308608) (xy 338.8868 -232.334054) (xy 339.205328 -232.334054)
			(xy 339.209288 -232.285) (xy 339.221065 -232.237216) (xy 339.240356 -232.19194) (xy 339.266659 -232.150344)
			(xy 339.299294 -232.113507) (xy 339.337415 -232.082382) (xy 339.380036 -232.057775) (xy 339.426052 -232.040323)
			(xy 339.474271 -232.030479) (xy 339.523446 -232.028498) (xy 339.572301 -232.03443) (xy 339.619572 -232.048122)
			(xy 339.664034 -232.06922) (xy 339.704537 -232.097176) (xy 339.74003 -232.131268) (xy 339.769595 -232.170612)
			(xy 339.792466 -232.214189) (xy 339.80805 -232.26087) (xy 339.815945 -232.309447) (xy 339.81644 -232.334054)
			(xy 340.134951 -232.334054) (xy 340.139046 -232.283326) (xy 340.151225 -232.233912) (xy 340.171173 -232.187092)
			(xy 340.198374 -232.144078) (xy 340.232122 -232.105984) (xy 340.271544 -232.073797) (xy 340.315618 -232.048351)
			(xy 340.363204 -232.030304) (xy 340.413068 -232.020124) (xy 340.46392 -232.018075) (xy 340.514441 -232.024209)
			(xy 340.563325 -232.038369) (xy 340.609304 -232.060186) (xy 340.651188 -232.089096) (xy 340.687892 -232.124351)
			(xy 340.718465 -232.165037) (xy 340.742116 -232.2101) (xy 340.758232 -232.258374) (xy 340.766396 -232.308608)
			(xy 340.766908 -232.334054) (xy 342.014805 -232.334054) (xy 342.0189 -232.283326) (xy 342.031079 -232.233912)
			(xy 342.051027 -232.187092) (xy 342.078228 -232.144078) (xy 342.111976 -232.105984) (xy 342.151398 -232.073797)
			(xy 342.195472 -232.048351) (xy 342.243058 -232.030304) (xy 342.292922 -232.020124) (xy 342.343774 -232.018075)
			(xy 342.394295 -232.024209) (xy 342.443179 -232.038369) (xy 342.489158 -232.060186) (xy 342.531042 -232.089096)
			(xy 342.567746 -232.124351) (xy 342.598319 -232.165037) (xy 342.62197 -232.2101) (xy 342.638086 -232.258374)
			(xy 342.64625 -232.308608) (xy 342.646762 -232.334054) (xy 342.64625 -232.3595) (xy 342.638086 -232.409734)
			(xy 342.62197 -232.458008) (xy 342.598319 -232.503071) (xy 342.567746 -232.543757) (xy 342.531042 -232.579012)
			(xy 342.489158 -232.607922) (xy 342.443179 -232.629739) (xy 342.394295 -232.643899) (xy 342.343774 -232.650033)
			(xy 342.292922 -232.647984) (xy 342.243058 -232.637804) (xy 342.195472 -232.619757) (xy 342.151398 -232.594311)
			(xy 342.111976 -232.562124) (xy 342.078228 -232.52403) (xy 342.051027 -232.481016) (xy 342.031079 -232.434196)
			(xy 342.0189 -232.384782) (xy 342.014805 -232.334054) (xy 340.766908 -232.334054) (xy 340.766396 -232.3595)
			(xy 340.758232 -232.409734) (xy 340.742116 -232.458008) (xy 340.718465 -232.503071) (xy 340.687892 -232.543757)
			(xy 340.651188 -232.579012) (xy 340.609304 -232.607922) (xy 340.563325 -232.629739) (xy 340.514441 -232.643899)
			(xy 340.46392 -232.650033) (xy 340.413068 -232.647984) (xy 340.363204 -232.637804) (xy 340.315618 -232.619757)
			(xy 340.271544 -232.594311) (xy 340.232122 -232.562124) (xy 340.198374 -232.52403) (xy 340.171173 -232.481016)
			(xy 340.151225 -232.434196) (xy 340.139046 -232.384782) (xy 340.134951 -232.334054) (xy 339.81644 -232.334054)
			(xy 339.815945 -232.358661) (xy 339.80805 -232.407238) (xy 339.792466 -232.453919) (xy 339.769595 -232.497496)
			(xy 339.74003 -232.53684) (xy 339.704537 -232.570932) (xy 339.664034 -232.598888) (xy 339.619572 -232.619986)
			(xy 339.572301 -232.633678) (xy 339.523446 -232.63961) (xy 339.474271 -232.637629) (xy 339.426052 -232.627785)
			(xy 339.380036 -232.610333) (xy 339.337415 -232.585726) (xy 339.299294 -232.554601) (xy 339.266659 -232.517764)
			(xy 339.240356 -232.476168) (xy 339.221065 -232.430892) (xy 339.209288 -232.383108) (xy 339.205328 -232.334054)
			(xy 338.8868 -232.334054) (xy 338.886288 -232.3595) (xy 338.878124 -232.409734) (xy 338.862008 -232.458008)
			(xy 338.838357 -232.503071) (xy 338.807784 -232.543757) (xy 338.77108 -232.579012) (xy 338.729196 -232.607922)
			(xy 338.683217 -232.629739) (xy 338.634333 -232.643899) (xy 338.583812 -232.650033) (xy 338.53296 -232.647984)
			(xy 338.483096 -232.637804) (xy 338.43551 -232.619757) (xy 338.391436 -232.594311) (xy 338.352014 -232.562124)
			(xy 338.318266 -232.52403) (xy 338.291065 -232.481016) (xy 338.271117 -232.434196) (xy 338.258938 -232.384782)
			(xy 338.254843 -232.334054) (xy 337.936332 -232.334054) (xy 337.935837 -232.358661) (xy 337.927942 -232.407238)
			(xy 337.912358 -232.453919) (xy 337.889487 -232.497496) (xy 337.859922 -232.53684) (xy 337.824429 -232.570932)
			(xy 337.783926 -232.598888) (xy 337.739464 -232.619986) (xy 337.692193 -232.633678) (xy 337.643338 -232.63961)
			(xy 337.594163 -232.637629) (xy 337.545944 -232.627785) (xy 337.499928 -232.610333) (xy 337.457307 -232.585726)
			(xy 337.419186 -232.554601) (xy 337.386551 -232.517764) (xy 337.360248 -232.476168) (xy 337.340957 -232.430892)
			(xy 337.32918 -232.383108) (xy 337.32522 -232.334054) (xy 336.996532 -232.334054) (xy 336.996037 -232.358661)
			(xy 336.988142 -232.407238) (xy 336.972558 -232.453919) (xy 336.949687 -232.497496) (xy 336.920122 -232.53684)
			(xy 336.884629 -232.570932) (xy 336.844126 -232.598888) (xy 336.799664 -232.619986) (xy 336.752393 -232.633678)
			(xy 336.703538 -232.63961) (xy 336.654363 -232.637629) (xy 336.606144 -232.627785) (xy 336.560128 -232.610333)
			(xy 336.517507 -232.585726) (xy 336.479386 -232.554601) (xy 336.446751 -232.517764) (xy 336.420448 -232.476168)
			(xy 336.401157 -232.430892) (xy 336.38938 -232.383108) (xy 336.38542 -232.334054) (xy 336.056478 -232.334054)
			(xy 336.055983 -232.358661) (xy 336.048088 -232.407238) (xy 336.032504 -232.453919) (xy 336.009633 -232.497496)
			(xy 335.980068 -232.53684) (xy 335.944575 -232.570932) (xy 335.904072 -232.598888) (xy 335.85961 -232.619986)
			(xy 335.812339 -232.633678) (xy 335.763484 -232.63961) (xy 335.714309 -232.637629) (xy 335.66609 -232.627785)
			(xy 335.620074 -232.610333) (xy 335.577453 -232.585726) (xy 335.539332 -232.554601) (xy 335.506697 -232.517764)
			(xy 335.480394 -232.476168) (xy 335.461103 -232.430892) (xy 335.449326 -232.383108) (xy 335.445366 -232.334054)
			(xy 334.17637 -232.334054) (xy 334.175875 -232.358661) (xy 334.16798 -232.407238) (xy 334.152396 -232.453919)
			(xy 334.129525 -232.497496) (xy 334.09996 -232.53684) (xy 334.064467 -232.570932) (xy 334.023964 -232.598888)
			(xy 333.979502 -232.619986) (xy 333.932231 -232.633678) (xy 333.883376 -232.63961) (xy 333.834201 -232.637629)
			(xy 333.785982 -232.627785) (xy 333.739966 -232.610333) (xy 333.697345 -232.585726) (xy 333.659224 -232.554601)
			(xy 333.626589 -232.517764) (xy 333.600286 -232.476168) (xy 333.580995 -232.430892) (xy 333.569218 -232.383108)
			(xy 333.565258 -232.334054) (xy 333.236316 -232.334054) (xy 333.235821 -232.358661) (xy 333.227926 -232.407238)
			(xy 333.212342 -232.453919) (xy 333.189471 -232.497496) (xy 333.159906 -232.53684) (xy 333.124413 -232.570932)
			(xy 333.08391 -232.598888) (xy 333.039448 -232.619986) (xy 332.992177 -232.633678) (xy 332.943322 -232.63961)
			(xy 332.894147 -232.637629) (xy 332.845928 -232.627785) (xy 332.799912 -232.610333) (xy 332.757291 -232.585726)
			(xy 332.71917 -232.554601) (xy 332.686535 -232.517764) (xy 332.660232 -232.476168) (xy 332.640941 -232.430892)
			(xy 332.629164 -232.383108) (xy 332.625204 -232.334054) (xy 332.296516 -232.334054) (xy 332.296021 -232.358661)
			(xy 332.288126 -232.407238) (xy 332.272542 -232.453919) (xy 332.249671 -232.497496) (xy 332.220106 -232.53684)
			(xy 332.184613 -232.570932) (xy 332.14411 -232.598888) (xy 332.099648 -232.619986) (xy 332.052377 -232.633678)
			(xy 332.003522 -232.63961) (xy 331.954347 -232.637629) (xy 331.906128 -232.627785) (xy 331.860112 -232.610333)
			(xy 331.817491 -232.585726) (xy 331.77937 -232.554601) (xy 331.746735 -232.517764) (xy 331.720432 -232.476168)
			(xy 331.701141 -232.430892) (xy 331.689364 -232.383108) (xy 331.685404 -232.334054) (xy 331.459332 -232.334054)
			(xy 331.459332 -232.7402) (xy 331.459809 -232.749556) (xy 331.466584 -232.767005) (xy 331.47254 -232.774236)
			(xy 331.517498 -232.823766) (xy 331.520809 -232.827236) (xy 331.528476 -232.832996) (xy 331.532738 -232.835196)
			(xy 331.540612 -232.839006) (xy 331.550264 -232.840022) (xy 331.550518 -232.840022) (xy 331.575391 -232.842933)
			(xy 331.623779 -232.855819) (xy 331.669419 -232.876424) (xy 331.711087 -232.904196) (xy 331.747668 -232.938391)
			(xy 331.778182 -232.978095) (xy 331.801813 -233.022243) (xy 331.817928 -233.069654) (xy 331.826095 -233.119059)
			(xy 331.826095 -233.14406) (xy 332.155304 -233.14406) (xy 332.159264 -233.095006) (xy 332.171041 -233.047222)
			(xy 332.190332 -233.001946) (xy 332.216635 -232.96035) (xy 332.24927 -232.923513) (xy 332.287391 -232.892388)
			(xy 332.330012 -232.867781) (xy 332.376028 -232.850329) (xy 332.424247 -232.840485) (xy 332.473422 -232.838504)
			(xy 332.522277 -232.844436) (xy 332.569548 -232.858128) (xy 332.61401 -232.879226) (xy 332.654513 -232.907182)
			(xy 332.690006 -232.941274) (xy 332.719571 -232.980618) (xy 332.742442 -233.024195) (xy 332.758026 -233.070876)
			(xy 332.765921 -233.119453) (xy 332.766416 -233.14406) (xy 333.095358 -233.14406) (xy 333.099318 -233.095006)
			(xy 333.111095 -233.047222) (xy 333.130386 -233.001946) (xy 333.156689 -232.96035) (xy 333.189324 -232.923513)
			(xy 333.227445 -232.892388) (xy 333.270066 -232.867781) (xy 333.316082 -232.850329) (xy 333.364301 -232.840485)
			(xy 333.413476 -232.838504) (xy 333.462331 -232.844436) (xy 333.509602 -232.858128) (xy 333.554064 -232.879226)
			(xy 333.594567 -232.907182) (xy 333.63006 -232.941274) (xy 333.659625 -232.980618) (xy 333.682496 -233.024195)
			(xy 333.69808 -233.070876) (xy 333.705975 -233.119453) (xy 333.70647 -233.14406) (xy 334.035412 -233.14406)
			(xy 334.039372 -233.095006) (xy 334.051149 -233.047222) (xy 334.07044 -233.001946) (xy 334.096743 -232.96035)
			(xy 334.129378 -232.923513) (xy 334.167499 -232.892388) (xy 334.21012 -232.867781) (xy 334.256136 -232.850329)
			(xy 334.304355 -232.840485) (xy 334.35353 -232.838504) (xy 334.402385 -232.844436) (xy 334.449656 -232.858128)
			(xy 334.494118 -232.879226) (xy 334.534621 -232.907182) (xy 334.570114 -232.941274) (xy 334.599679 -232.980618)
			(xy 334.62255 -233.024195) (xy 334.638134 -233.070876) (xy 334.646029 -233.119453) (xy 334.646524 -233.14406)
			(xy 334.975212 -233.14406) (xy 334.979172 -233.095006) (xy 334.990949 -233.047222) (xy 335.01024 -233.001946)
			(xy 335.036543 -232.96035) (xy 335.069178 -232.923513) (xy 335.107299 -232.892388) (xy 335.14992 -232.867781)
			(xy 335.195936 -232.850329) (xy 335.244155 -232.840485) (xy 335.29333 -232.838504) (xy 335.342185 -232.844436)
			(xy 335.389456 -232.858128) (xy 335.433918 -232.879226) (xy 335.474421 -232.907182) (xy 335.509914 -232.941274)
			(xy 335.539479 -232.980618) (xy 335.56235 -233.024195) (xy 335.577934 -233.070876) (xy 335.585829 -233.119453)
			(xy 335.586324 -233.14406) (xy 335.915266 -233.14406) (xy 335.919226 -233.095006) (xy 335.931003 -233.047222)
			(xy 335.950294 -233.001946) (xy 335.976597 -232.96035) (xy 336.009232 -232.923513) (xy 336.047353 -232.892388)
			(xy 336.089974 -232.867781) (xy 336.13599 -232.850329) (xy 336.184209 -232.840485) (xy 336.233384 -232.838504)
			(xy 336.282239 -232.844436) (xy 336.32951 -232.858128) (xy 336.373972 -232.879226) (xy 336.414475 -232.907182)
			(xy 336.449968 -232.941274) (xy 336.479533 -232.980618) (xy 336.502404 -233.024195) (xy 336.517988 -233.070876)
			(xy 336.525883 -233.119453) (xy 336.526378 -233.14406) (xy 336.85532 -233.14406) (xy 336.85928 -233.095006)
			(xy 336.871057 -233.047222) (xy 336.890348 -233.001946) (xy 336.916651 -232.96035) (xy 336.949286 -232.923513)
			(xy 336.987407 -232.892388) (xy 337.030028 -232.867781) (xy 337.076044 -232.850329) (xy 337.124263 -232.840485)
			(xy 337.173438 -232.838504) (xy 337.222293 -232.844436) (xy 337.269564 -232.858128) (xy 337.314026 -232.879226)
			(xy 337.354529 -232.907182) (xy 337.390022 -232.941274) (xy 337.419587 -232.980618) (xy 337.442458 -233.024195)
			(xy 337.458042 -233.070876) (xy 337.465937 -233.119453) (xy 337.466432 -233.14406) (xy 337.795374 -233.14406)
			(xy 337.799334 -233.095006) (xy 337.811111 -233.047222) (xy 337.830402 -233.001946) (xy 337.856705 -232.96035)
			(xy 337.88934 -232.923513) (xy 337.927461 -232.892388) (xy 337.970082 -232.867781) (xy 338.016098 -232.850329)
			(xy 338.064317 -232.840485) (xy 338.113492 -232.838504) (xy 338.162347 -232.844436) (xy 338.209618 -232.858128)
			(xy 338.25408 -232.879226) (xy 338.294583 -232.907182) (xy 338.330076 -232.941274) (xy 338.359641 -232.980618)
			(xy 338.382512 -233.024195) (xy 338.398096 -233.070876) (xy 338.405991 -233.119453) (xy 338.406486 -233.14406)
			(xy 338.724743 -233.14406) (xy 338.728838 -233.093332) (xy 338.741017 -233.043918) (xy 338.760965 -232.997098)
			(xy 338.788166 -232.954084) (xy 338.821914 -232.91599) (xy 338.861336 -232.883803) (xy 338.90541 -232.858357)
			(xy 338.952996 -232.84031) (xy 339.00286 -232.83013) (xy 339.053712 -232.828081) (xy 339.104233 -232.834215)
			(xy 339.153117 -232.848375) (xy 339.199096 -232.870192) (xy 339.24098 -232.899102) (xy 339.277684 -232.934357)
			(xy 339.308257 -232.975043) (xy 339.331908 -233.020106) (xy 339.348024 -233.06838) (xy 339.356188 -233.118614)
			(xy 339.3567 -233.14406) (xy 339.664797 -233.14406) (xy 339.668892 -233.093332) (xy 339.681071 -233.043918)
			(xy 339.701019 -232.997098) (xy 339.72822 -232.954084) (xy 339.761968 -232.91599) (xy 339.80139 -232.883803)
			(xy 339.845464 -232.858357) (xy 339.89305 -232.84031) (xy 339.942914 -232.83013) (xy 339.993766 -232.828081)
			(xy 340.044287 -232.834215) (xy 340.093171 -232.848375) (xy 340.13915 -232.870192) (xy 340.181034 -232.899102)
			(xy 340.217738 -232.934357) (xy 340.248311 -232.975043) (xy 340.271962 -233.020106) (xy 340.288078 -233.06838)
			(xy 340.296242 -233.118614) (xy 340.296754 -233.14406) (xy 340.615282 -233.14406) (xy 340.619242 -233.095006)
			(xy 340.631019 -233.047222) (xy 340.65031 -233.001946) (xy 340.676613 -232.96035) (xy 340.709248 -232.923513)
			(xy 340.747369 -232.892388) (xy 340.78999 -232.867781) (xy 340.836006 -232.850329) (xy 340.884225 -232.840485)
			(xy 340.9334 -232.838504) (xy 340.982255 -232.844436) (xy 341.029526 -232.858128) (xy 341.073988 -232.879226)
			(xy 341.114491 -232.907182) (xy 341.149984 -232.941274) (xy 341.179549 -232.980618) (xy 341.20242 -233.024195)
			(xy 341.218004 -233.070876) (xy 341.225899 -233.119453) (xy 341.226394 -233.14406) (xy 341.544905 -233.14406)
			(xy 341.549 -233.093332) (xy 341.561179 -233.043918) (xy 341.581127 -232.997098) (xy 341.608328 -232.954084)
			(xy 341.642076 -232.91599) (xy 341.681498 -232.883803) (xy 341.725572 -232.858357) (xy 341.773158 -232.84031)
			(xy 341.823022 -232.83013) (xy 341.873874 -232.828081) (xy 341.924395 -232.834215) (xy 341.973279 -232.848375)
			(xy 342.019258 -232.870192) (xy 342.061142 -232.899102) (xy 342.097846 -232.934357) (xy 342.128419 -232.975043)
			(xy 342.15207 -233.020106) (xy 342.168186 -233.06838) (xy 342.17635 -233.118614) (xy 342.176862 -233.14406)
			(xy 342.49539 -233.14406) (xy 342.49935 -233.095006) (xy 342.511127 -233.047222) (xy 342.530418 -233.001946)
			(xy 342.556721 -232.96035) (xy 342.589356 -232.923513) (xy 342.627477 -232.892388) (xy 342.670098 -232.867781)
			(xy 342.716114 -232.850329) (xy 342.764333 -232.840485) (xy 342.813508 -232.838504) (xy 342.862363 -232.844436)
			(xy 342.909634 -232.858128) (xy 342.954096 -232.879226) (xy 342.994599 -232.907182) (xy 343.030092 -232.941274)
			(xy 343.059657 -232.980618) (xy 343.082528 -233.024195) (xy 343.098112 -233.070876) (xy 343.106007 -233.119453)
			(xy 343.106502 -233.14406) (xy 343.106007 -233.168667) (xy 343.098112 -233.217244) (xy 343.082528 -233.263925)
			(xy 343.059657 -233.307502) (xy 343.030092 -233.346846) (xy 342.994599 -233.380938) (xy 342.954096 -233.408894)
			(xy 342.909634 -233.429992) (xy 342.862363 -233.443684) (xy 342.813508 -233.449616) (xy 342.764333 -233.447635)
			(xy 342.716114 -233.437791) (xy 342.670098 -233.420339) (xy 342.627477 -233.395732) (xy 342.589356 -233.364607)
			(xy 342.556721 -233.32777) (xy 342.530418 -233.286174) (xy 342.511127 -233.240898) (xy 342.49935 -233.193114)
			(xy 342.49539 -233.14406) (xy 342.176862 -233.14406) (xy 342.17635 -233.169506) (xy 342.168186 -233.21974)
			(xy 342.15207 -233.268014) (xy 342.128419 -233.313077) (xy 342.097846 -233.353763) (xy 342.061142 -233.389018)
			(xy 342.019258 -233.417928) (xy 341.973279 -233.439745) (xy 341.924395 -233.453905) (xy 341.873874 -233.460039)
			(xy 341.823022 -233.45799) (xy 341.773158 -233.44781) (xy 341.725572 -233.429763) (xy 341.681498 -233.404317)
			(xy 341.642076 -233.37213) (xy 341.608328 -233.334036) (xy 341.581127 -233.291022) (xy 341.561179 -233.244202)
			(xy 341.549 -233.194788) (xy 341.544905 -233.14406) (xy 341.226394 -233.14406) (xy 341.225899 -233.168667)
			(xy 341.218004 -233.217244) (xy 341.20242 -233.263925) (xy 341.179549 -233.307502) (xy 341.149984 -233.346846)
			(xy 341.114491 -233.380938) (xy 341.073988 -233.408894) (xy 341.029526 -233.429992) (xy 340.982255 -233.443684)
			(xy 340.9334 -233.449616) (xy 340.884225 -233.447635) (xy 340.836006 -233.437791) (xy 340.78999 -233.420339)
			(xy 340.747369 -233.395732) (xy 340.709248 -233.364607) (xy 340.676613 -233.32777) (xy 340.65031 -233.286174)
			(xy 340.631019 -233.240898) (xy 340.619242 -233.193114) (xy 340.615282 -233.14406) (xy 340.296754 -233.14406)
			(xy 340.296242 -233.169506) (xy 340.288078 -233.21974) (xy 340.271962 -233.268014) (xy 340.248311 -233.313077)
			(xy 340.217738 -233.353763) (xy 340.181034 -233.389018) (xy 340.13915 -233.417928) (xy 340.093171 -233.439745)
			(xy 340.044287 -233.453905) (xy 339.993766 -233.460039) (xy 339.942914 -233.45799) (xy 339.89305 -233.44781)
			(xy 339.845464 -233.429763) (xy 339.80139 -233.404317) (xy 339.761968 -233.37213) (xy 339.72822 -233.334036)
			(xy 339.701019 -233.291022) (xy 339.681071 -233.244202) (xy 339.668892 -233.194788) (xy 339.664797 -233.14406)
			(xy 339.3567 -233.14406) (xy 339.356188 -233.169506) (xy 339.348024 -233.21974) (xy 339.331908 -233.268014)
			(xy 339.308257 -233.313077) (xy 339.277684 -233.353763) (xy 339.24098 -233.389018) (xy 339.199096 -233.417928)
			(xy 339.153117 -233.439745) (xy 339.104233 -233.453905) (xy 339.053712 -233.460039) (xy 339.00286 -233.45799)
			(xy 338.952996 -233.44781) (xy 338.90541 -233.429763) (xy 338.861336 -233.404317) (xy 338.821914 -233.37213)
			(xy 338.788166 -233.334036) (xy 338.760965 -233.291022) (xy 338.741017 -233.244202) (xy 338.728838 -233.194788)
			(xy 338.724743 -233.14406) (xy 338.406486 -233.14406) (xy 338.405991 -233.168667) (xy 338.398096 -233.217244)
			(xy 338.382512 -233.263925) (xy 338.359641 -233.307502) (xy 338.330076 -233.346846) (xy 338.294583 -233.380938)
			(xy 338.25408 -233.408894) (xy 338.209618 -233.429992) (xy 338.162347 -233.443684) (xy 338.113492 -233.449616)
			(xy 338.064317 -233.447635) (xy 338.016098 -233.437791) (xy 337.970082 -233.420339) (xy 337.927461 -233.395732)
			(xy 337.88934 -233.364607) (xy 337.856705 -233.32777) (xy 337.830402 -233.286174) (xy 337.811111 -233.240898)
			(xy 337.799334 -233.193114) (xy 337.795374 -233.14406) (xy 337.466432 -233.14406) (xy 337.465937 -233.168667)
			(xy 337.458042 -233.217244) (xy 337.442458 -233.263925) (xy 337.419587 -233.307502) (xy 337.390022 -233.346846)
			(xy 337.354529 -233.380938) (xy 337.314026 -233.408894) (xy 337.269564 -233.429992) (xy 337.222293 -233.443684)
			(xy 337.173438 -233.449616) (xy 337.124263 -233.447635) (xy 337.076044 -233.437791) (xy 337.030028 -233.420339)
			(xy 336.987407 -233.395732) (xy 336.949286 -233.364607) (xy 336.916651 -233.32777) (xy 336.890348 -233.286174)
			(xy 336.871057 -233.240898) (xy 336.85928 -233.193114) (xy 336.85532 -233.14406) (xy 336.526378 -233.14406)
			(xy 336.525883 -233.168667) (xy 336.517988 -233.217244) (xy 336.502404 -233.263925) (xy 336.479533 -233.307502)
			(xy 336.449968 -233.346846) (xy 336.414475 -233.380938) (xy 336.373972 -233.408894) (xy 336.32951 -233.429992)
			(xy 336.282239 -233.443684) (xy 336.233384 -233.449616) (xy 336.184209 -233.447635) (xy 336.13599 -233.437791)
			(xy 336.089974 -233.420339) (xy 336.047353 -233.395732) (xy 336.009232 -233.364607) (xy 335.976597 -233.32777)
			(xy 335.950294 -233.286174) (xy 335.931003 -233.240898) (xy 335.919226 -233.193114) (xy 335.915266 -233.14406)
			(xy 335.586324 -233.14406) (xy 335.585829 -233.168667) (xy 335.577934 -233.217244) (xy 335.56235 -233.263925)
			(xy 335.539479 -233.307502) (xy 335.509914 -233.346846) (xy 335.474421 -233.380938) (xy 335.433918 -233.408894)
			(xy 335.389456 -233.429992) (xy 335.342185 -233.443684) (xy 335.29333 -233.449616) (xy 335.244155 -233.447635)
			(xy 335.195936 -233.437791) (xy 335.14992 -233.420339) (xy 335.107299 -233.395732) (xy 335.069178 -233.364607)
			(xy 335.036543 -233.32777) (xy 335.01024 -233.286174) (xy 334.990949 -233.240898) (xy 334.979172 -233.193114)
			(xy 334.975212 -233.14406) (xy 334.646524 -233.14406) (xy 334.646029 -233.168667) (xy 334.638134 -233.217244)
			(xy 334.62255 -233.263925) (xy 334.599679 -233.307502) (xy 334.570114 -233.346846) (xy 334.534621 -233.380938)
			(xy 334.494118 -233.408894) (xy 334.449656 -233.429992) (xy 334.402385 -233.443684) (xy 334.35353 -233.449616)
			(xy 334.304355 -233.447635) (xy 334.256136 -233.437791) (xy 334.21012 -233.420339) (xy 334.167499 -233.395732)
			(xy 334.129378 -233.364607) (xy 334.096743 -233.32777) (xy 334.07044 -233.286174) (xy 334.051149 -233.240898)
			(xy 334.039372 -233.193114) (xy 334.035412 -233.14406) (xy 333.70647 -233.14406) (xy 333.705975 -233.168667)
			(xy 333.69808 -233.217244) (xy 333.682496 -233.263925) (xy 333.659625 -233.307502) (xy 333.63006 -233.346846)
			(xy 333.594567 -233.380938) (xy 333.554064 -233.408894) (xy 333.509602 -233.429992) (xy 333.462331 -233.443684)
			(xy 333.413476 -233.449616) (xy 333.364301 -233.447635) (xy 333.316082 -233.437791) (xy 333.270066 -233.420339)
			(xy 333.227445 -233.395732) (xy 333.189324 -233.364607) (xy 333.156689 -233.32777) (xy 333.130386 -233.286174)
			(xy 333.111095 -233.240898) (xy 333.099318 -233.193114) (xy 333.095358 -233.14406) (xy 332.766416 -233.14406)
			(xy 332.765921 -233.168667) (xy 332.758026 -233.217244) (xy 332.742442 -233.263925) (xy 332.719571 -233.307502)
			(xy 332.690006 -233.346846) (xy 332.654513 -233.380938) (xy 332.61401 -233.408894) (xy 332.569548 -233.429992)
			(xy 332.522277 -233.443684) (xy 332.473422 -233.449616) (xy 332.424247 -233.447635) (xy 332.376028 -233.437791)
			(xy 332.330012 -233.420339) (xy 332.287391 -233.395732) (xy 332.24927 -233.364607) (xy 332.216635 -233.32777)
			(xy 332.190332 -233.286174) (xy 332.171041 -233.240898) (xy 332.159264 -233.193114) (xy 332.155304 -233.14406)
			(xy 331.826095 -233.14406) (xy 331.826096 -233.169134) (xy 331.81793 -233.218538) (xy 331.801816 -233.26595)
			(xy 331.778186 -233.310099) (xy 331.747673 -233.349803) (xy 331.711093 -233.383999) (xy 331.669425 -233.411772)
			(xy 331.623787 -233.432378) (xy 331.575398 -233.445266) (xy 331.550518 -233.448098) (xy 331.550264 -233.448098)
			(xy 331.540612 -233.449114) (xy 331.532738 -233.452924) (xy 331.528476 -233.455126) (xy 331.5208 -233.460876)
			(xy 331.517498 -233.464354) (xy 331.47254 -233.513884) (xy 331.466477 -233.521053) (xy 331.459673 -233.538538)
			(xy 331.459332 -233.54792) (xy 331.459332 -233.954066) (xy 331.685404 -233.954066) (xy 331.689364 -233.905012)
			(xy 331.701141 -233.857228) (xy 331.720432 -233.811952) (xy 331.746735 -233.770356) (xy 331.77937 -233.733519)
			(xy 331.817491 -233.702394) (xy 331.860112 -233.677787) (xy 331.906128 -233.660335) (xy 331.954347 -233.650491)
			(xy 332.003522 -233.64851) (xy 332.052377 -233.654442) (xy 332.099648 -233.668134) (xy 332.14411 -233.689232)
			(xy 332.184613 -233.717188) (xy 332.220106 -233.75128) (xy 332.249671 -233.790624) (xy 332.272542 -233.834201)
			(xy 332.288126 -233.880882) (xy 332.296021 -233.929459) (xy 332.296516 -233.954066) (xy 332.625204 -233.954066)
			(xy 332.629164 -233.905012) (xy 332.640941 -233.857228) (xy 332.660232 -233.811952) (xy 332.686535 -233.770356)
			(xy 332.71917 -233.733519) (xy 332.757291 -233.702394) (xy 332.799912 -233.677787) (xy 332.845928 -233.660335)
			(xy 332.894147 -233.650491) (xy 332.943322 -233.64851) (xy 332.992177 -233.654442) (xy 333.039448 -233.668134)
			(xy 333.08391 -233.689232) (xy 333.124413 -233.717188) (xy 333.159906 -233.75128) (xy 333.189471 -233.790624)
			(xy 333.212342 -233.834201) (xy 333.227926 -233.880882) (xy 333.235821 -233.929459) (xy 333.236316 -233.954066)
			(xy 333.565258 -233.954066) (xy 333.569218 -233.905012) (xy 333.580995 -233.857228) (xy 333.600286 -233.811952)
			(xy 333.626589 -233.770356) (xy 333.659224 -233.733519) (xy 333.697345 -233.702394) (xy 333.739966 -233.677787)
			(xy 333.785982 -233.660335) (xy 333.834201 -233.650491) (xy 333.883376 -233.64851) (xy 333.932231 -233.654442)
			(xy 333.979502 -233.668134) (xy 334.023964 -233.689232) (xy 334.064467 -233.717188) (xy 334.09996 -233.75128)
			(xy 334.129525 -233.790624) (xy 334.152396 -233.834201) (xy 334.16798 -233.880882) (xy 334.175875 -233.929459)
			(xy 334.17637 -233.954066) (xy 334.505312 -233.954066) (xy 334.509272 -233.905012) (xy 334.521049 -233.857228)
			(xy 334.54034 -233.811952) (xy 334.566643 -233.770356) (xy 334.599278 -233.733519) (xy 334.637399 -233.702394)
			(xy 334.68002 -233.677787) (xy 334.726036 -233.660335) (xy 334.774255 -233.650491) (xy 334.82343 -233.64851)
			(xy 334.872285 -233.654442) (xy 334.919556 -233.668134) (xy 334.964018 -233.689232) (xy 335.004521 -233.717188)
			(xy 335.040014 -233.75128) (xy 335.069579 -233.790624) (xy 335.09245 -233.834201) (xy 335.108034 -233.880882)
			(xy 335.115929 -233.929459) (xy 335.116424 -233.954066) (xy 335.445366 -233.954066) (xy 335.449326 -233.905012)
			(xy 335.461103 -233.857228) (xy 335.480394 -233.811952) (xy 335.506697 -233.770356) (xy 335.539332 -233.733519)
			(xy 335.577453 -233.702394) (xy 335.620074 -233.677787) (xy 335.66609 -233.660335) (xy 335.714309 -233.650491)
			(xy 335.763484 -233.64851) (xy 335.812339 -233.654442) (xy 335.85961 -233.668134) (xy 335.904072 -233.689232)
			(xy 335.944575 -233.717188) (xy 335.980068 -233.75128) (xy 336.009633 -233.790624) (xy 336.032504 -233.834201)
			(xy 336.048088 -233.880882) (xy 336.055983 -233.929459) (xy 336.056478 -233.954066) (xy 336.38542 -233.954066)
			(xy 336.38938 -233.905012) (xy 336.401157 -233.857228) (xy 336.420448 -233.811952) (xy 336.446751 -233.770356)
			(xy 336.479386 -233.733519) (xy 336.517507 -233.702394) (xy 336.560128 -233.677787) (xy 336.606144 -233.660335)
			(xy 336.654363 -233.650491) (xy 336.703538 -233.64851) (xy 336.752393 -233.654442) (xy 336.799664 -233.668134)
			(xy 336.844126 -233.689232) (xy 336.884629 -233.717188) (xy 336.920122 -233.75128) (xy 336.949687 -233.790624)
			(xy 336.972558 -233.834201) (xy 336.988142 -233.880882) (xy 336.996037 -233.929459) (xy 336.996532 -233.954066)
			(xy 337.32522 -233.954066) (xy 337.32918 -233.905012) (xy 337.340957 -233.857228) (xy 337.360248 -233.811952)
			(xy 337.386551 -233.770356) (xy 337.419186 -233.733519) (xy 337.457307 -233.702394) (xy 337.499928 -233.677787)
			(xy 337.545944 -233.660335) (xy 337.594163 -233.650491) (xy 337.643338 -233.64851) (xy 337.692193 -233.654442)
			(xy 337.739464 -233.668134) (xy 337.783926 -233.689232) (xy 337.824429 -233.717188) (xy 337.859922 -233.75128)
			(xy 337.889487 -233.790624) (xy 337.912358 -233.834201) (xy 337.927942 -233.880882) (xy 337.935837 -233.929459)
			(xy 337.936332 -233.954066) (xy 338.254843 -233.954066) (xy 338.258938 -233.903338) (xy 338.271117 -233.853924)
			(xy 338.291065 -233.807104) (xy 338.318266 -233.76409) (xy 338.352014 -233.725996) (xy 338.391436 -233.693809)
			(xy 338.43551 -233.668363) (xy 338.483096 -233.650316) (xy 338.53296 -233.640136) (xy 338.583812 -233.638087)
			(xy 338.634333 -233.644221) (xy 338.683217 -233.658381) (xy 338.729196 -233.680198) (xy 338.77108 -233.709108)
			(xy 338.807784 -233.744363) (xy 338.838357 -233.785049) (xy 338.862008 -233.830112) (xy 338.878124 -233.878386)
			(xy 338.886288 -233.92862) (xy 338.8868 -233.954066) (xy 339.205328 -233.954066) (xy 339.209288 -233.905012)
			(xy 339.221065 -233.857228) (xy 339.240356 -233.811952) (xy 339.266659 -233.770356) (xy 339.299294 -233.733519)
			(xy 339.337415 -233.702394) (xy 339.380036 -233.677787) (xy 339.426052 -233.660335) (xy 339.474271 -233.650491)
			(xy 339.523446 -233.64851) (xy 339.572301 -233.654442) (xy 339.619572 -233.668134) (xy 339.664034 -233.689232)
			(xy 339.704537 -233.717188) (xy 339.74003 -233.75128) (xy 339.769595 -233.790624) (xy 339.792466 -233.834201)
			(xy 339.80805 -233.880882) (xy 339.815945 -233.929459) (xy 339.81644 -233.954066) (xy 340.134951 -233.954066)
			(xy 340.139046 -233.903338) (xy 340.151225 -233.853924) (xy 340.171173 -233.807104) (xy 340.198374 -233.76409)
			(xy 340.232122 -233.725996) (xy 340.271544 -233.693809) (xy 340.315618 -233.668363) (xy 340.363204 -233.650316)
			(xy 340.413068 -233.640136) (xy 340.46392 -233.638087) (xy 340.514441 -233.644221) (xy 340.563325 -233.658381)
			(xy 340.609304 -233.680198) (xy 340.651188 -233.709108) (xy 340.687892 -233.744363) (xy 340.718465 -233.785049)
			(xy 340.742116 -233.830112) (xy 340.758232 -233.878386) (xy 340.766396 -233.92862) (xy 340.766908 -233.954066)
			(xy 341.085182 -233.954066) (xy 341.089142 -233.905012) (xy 341.100919 -233.857228) (xy 341.12021 -233.811952)
			(xy 341.146513 -233.770356) (xy 341.179148 -233.733519) (xy 341.217269 -233.702394) (xy 341.25989 -233.677787)
			(xy 341.305906 -233.660335) (xy 341.354125 -233.650491) (xy 341.4033 -233.64851) (xy 341.452155 -233.654442)
			(xy 341.499426 -233.668134) (xy 341.543888 -233.689232) (xy 341.584391 -233.717188) (xy 341.619884 -233.75128)
			(xy 341.649449 -233.790624) (xy 341.67232 -233.834201) (xy 341.687904 -233.880882) (xy 341.695799 -233.929459)
			(xy 341.696294 -233.954066) (xy 342.014805 -233.954066) (xy 342.0189 -233.903338) (xy 342.031079 -233.853924)
			(xy 342.051027 -233.807104) (xy 342.078228 -233.76409) (xy 342.111976 -233.725996) (xy 342.151398 -233.693809)
			(xy 342.195472 -233.668363) (xy 342.243058 -233.650316) (xy 342.292922 -233.640136) (xy 342.343774 -233.638087)
			(xy 342.394295 -233.644221) (xy 342.443179 -233.658381) (xy 342.489158 -233.680198) (xy 342.531042 -233.709108)
			(xy 342.567746 -233.744363) (xy 342.598319 -233.785049) (xy 342.62197 -233.830112) (xy 342.638086 -233.878386)
			(xy 342.64625 -233.92862) (xy 342.646762 -233.954066) (xy 342.64625 -233.979512) (xy 342.638086 -234.029746)
			(xy 342.62197 -234.07802) (xy 342.598319 -234.123083) (xy 342.567746 -234.163769) (xy 342.531042 -234.199024)
			(xy 342.489158 -234.227934) (xy 342.443179 -234.249751) (xy 342.394295 -234.263911) (xy 342.343774 -234.270045)
			(xy 342.292922 -234.267996) (xy 342.243058 -234.257816) (xy 342.195472 -234.239769) (xy 342.151398 -234.214323)
			(xy 342.111976 -234.182136) (xy 342.078228 -234.144042) (xy 342.051027 -234.101028) (xy 342.031079 -234.054208)
			(xy 342.0189 -234.004794) (xy 342.014805 -233.954066) (xy 341.696294 -233.954066) (xy 341.695799 -233.978673)
			(xy 341.687904 -234.02725) (xy 341.67232 -234.073931) (xy 341.649449 -234.117508) (xy 341.619884 -234.156852)
			(xy 341.584391 -234.190944) (xy 341.543888 -234.2189) (xy 341.499426 -234.239998) (xy 341.452155 -234.25369)
			(xy 341.4033 -234.259622) (xy 341.354125 -234.257641) (xy 341.305906 -234.247797) (xy 341.25989 -234.230345)
			(xy 341.217269 -234.205738) (xy 341.179148 -234.174613) (xy 341.146513 -234.137776) (xy 341.12021 -234.09618)
			(xy 341.100919 -234.050904) (xy 341.089142 -234.00312) (xy 341.085182 -233.954066) (xy 340.766908 -233.954066)
			(xy 340.766396 -233.979512) (xy 340.758232 -234.029746) (xy 340.742116 -234.07802) (xy 340.718465 -234.123083)
			(xy 340.687892 -234.163769) (xy 340.651188 -234.199024) (xy 340.609304 -234.227934) (xy 340.563325 -234.249751)
			(xy 340.514441 -234.263911) (xy 340.46392 -234.270045) (xy 340.413068 -234.267996) (xy 340.363204 -234.257816)
			(xy 340.315618 -234.239769) (xy 340.271544 -234.214323) (xy 340.232122 -234.182136) (xy 340.198374 -234.144042)
			(xy 340.171173 -234.101028) (xy 340.151225 -234.054208) (xy 340.139046 -234.004794) (xy 340.134951 -233.954066)
			(xy 339.81644 -233.954066) (xy 339.815945 -233.978673) (xy 339.80805 -234.02725) (xy 339.792466 -234.073931)
			(xy 339.769595 -234.117508) (xy 339.74003 -234.156852) (xy 339.704537 -234.190944) (xy 339.664034 -234.2189)
			(xy 339.619572 -234.239998) (xy 339.572301 -234.25369) (xy 339.523446 -234.259622) (xy 339.474271 -234.257641)
			(xy 339.426052 -234.247797) (xy 339.380036 -234.230345) (xy 339.337415 -234.205738) (xy 339.299294 -234.174613)
			(xy 339.266659 -234.137776) (xy 339.240356 -234.09618) (xy 339.221065 -234.050904) (xy 339.209288 -234.00312)
			(xy 339.205328 -233.954066) (xy 338.8868 -233.954066) (xy 338.886288 -233.979512) (xy 338.878124 -234.029746)
			(xy 338.862008 -234.07802) (xy 338.838357 -234.123083) (xy 338.807784 -234.163769) (xy 338.77108 -234.199024)
			(xy 338.729196 -234.227934) (xy 338.683217 -234.249751) (xy 338.634333 -234.263911) (xy 338.583812 -234.270045)
			(xy 338.53296 -234.267996) (xy 338.483096 -234.257816) (xy 338.43551 -234.239769) (xy 338.391436 -234.214323)
			(xy 338.352014 -234.182136) (xy 338.318266 -234.144042) (xy 338.291065 -234.101028) (xy 338.271117 -234.054208)
			(xy 338.258938 -234.004794) (xy 338.254843 -233.954066) (xy 337.936332 -233.954066) (xy 337.935837 -233.978673)
			(xy 337.927942 -234.02725) (xy 337.912358 -234.073931) (xy 337.889487 -234.117508) (xy 337.859922 -234.156852)
			(xy 337.824429 -234.190944) (xy 337.783926 -234.2189) (xy 337.739464 -234.239998) (xy 337.692193 -234.25369)
			(xy 337.643338 -234.259622) (xy 337.594163 -234.257641) (xy 337.545944 -234.247797) (xy 337.499928 -234.230345)
			(xy 337.457307 -234.205738) (xy 337.419186 -234.174613) (xy 337.386551 -234.137776) (xy 337.360248 -234.09618)
			(xy 337.340957 -234.050904) (xy 337.32918 -234.00312) (xy 337.32522 -233.954066) (xy 336.996532 -233.954066)
			(xy 336.996037 -233.978673) (xy 336.988142 -234.02725) (xy 336.972558 -234.073931) (xy 336.949687 -234.117508)
			(xy 336.920122 -234.156852) (xy 336.884629 -234.190944) (xy 336.844126 -234.2189) (xy 336.799664 -234.239998)
			(xy 336.752393 -234.25369) (xy 336.703538 -234.259622) (xy 336.654363 -234.257641) (xy 336.606144 -234.247797)
			(xy 336.560128 -234.230345) (xy 336.517507 -234.205738) (xy 336.479386 -234.174613) (xy 336.446751 -234.137776)
			(xy 336.420448 -234.09618) (xy 336.401157 -234.050904) (xy 336.38938 -234.00312) (xy 336.38542 -233.954066)
			(xy 336.056478 -233.954066) (xy 336.055983 -233.978673) (xy 336.048088 -234.02725) (xy 336.032504 -234.073931)
			(xy 336.009633 -234.117508) (xy 335.980068 -234.156852) (xy 335.944575 -234.190944) (xy 335.904072 -234.2189)
			(xy 335.85961 -234.239998) (xy 335.812339 -234.25369) (xy 335.763484 -234.259622) (xy 335.714309 -234.257641)
			(xy 335.66609 -234.247797) (xy 335.620074 -234.230345) (xy 335.577453 -234.205738) (xy 335.539332 -234.174613)
			(xy 335.506697 -234.137776) (xy 335.480394 -234.09618) (xy 335.461103 -234.050904) (xy 335.449326 -234.00312)
			(xy 335.445366 -233.954066) (xy 335.116424 -233.954066) (xy 335.115929 -233.978673) (xy 335.108034 -234.02725)
			(xy 335.09245 -234.073931) (xy 335.069579 -234.117508) (xy 335.040014 -234.156852) (xy 335.004521 -234.190944)
			(xy 334.964018 -234.2189) (xy 334.919556 -234.239998) (xy 334.872285 -234.25369) (xy 334.82343 -234.259622)
			(xy 334.774255 -234.257641) (xy 334.726036 -234.247797) (xy 334.68002 -234.230345) (xy 334.637399 -234.205738)
			(xy 334.599278 -234.174613) (xy 334.566643 -234.137776) (xy 334.54034 -234.09618) (xy 334.521049 -234.050904)
			(xy 334.509272 -234.00312) (xy 334.505312 -233.954066) (xy 334.17637 -233.954066) (xy 334.175875 -233.978673)
			(xy 334.16798 -234.02725) (xy 334.152396 -234.073931) (xy 334.129525 -234.117508) (xy 334.09996 -234.156852)
			(xy 334.064467 -234.190944) (xy 334.023964 -234.2189) (xy 333.979502 -234.239998) (xy 333.932231 -234.25369)
			(xy 333.883376 -234.259622) (xy 333.834201 -234.257641) (xy 333.785982 -234.247797) (xy 333.739966 -234.230345)
			(xy 333.697345 -234.205738) (xy 333.659224 -234.174613) (xy 333.626589 -234.137776) (xy 333.600286 -234.09618)
			(xy 333.580995 -234.050904) (xy 333.569218 -234.00312) (xy 333.565258 -233.954066) (xy 333.236316 -233.954066)
			(xy 333.235821 -233.978673) (xy 333.227926 -234.02725) (xy 333.212342 -234.073931) (xy 333.189471 -234.117508)
			(xy 333.159906 -234.156852) (xy 333.124413 -234.190944) (xy 333.08391 -234.2189) (xy 333.039448 -234.239998)
			(xy 332.992177 -234.25369) (xy 332.943322 -234.259622) (xy 332.894147 -234.257641) (xy 332.845928 -234.247797)
			(xy 332.799912 -234.230345) (xy 332.757291 -234.205738) (xy 332.71917 -234.174613) (xy 332.686535 -234.137776)
			(xy 332.660232 -234.09618) (xy 332.640941 -234.050904) (xy 332.629164 -234.00312) (xy 332.625204 -233.954066)
			(xy 332.296516 -233.954066) (xy 332.296021 -233.978673) (xy 332.288126 -234.02725) (xy 332.272542 -234.073931)
			(xy 332.249671 -234.117508) (xy 332.220106 -234.156852) (xy 332.184613 -234.190944) (xy 332.14411 -234.2189)
			(xy 332.099648 -234.239998) (xy 332.052377 -234.25369) (xy 332.003522 -234.259622) (xy 331.954347 -234.257641)
			(xy 331.906128 -234.247797) (xy 331.860112 -234.230345) (xy 331.817491 -234.205738) (xy 331.77937 -234.174613)
			(xy 331.746735 -234.137776) (xy 331.720432 -234.09618) (xy 331.701141 -234.050904) (xy 331.689364 -234.00312)
			(xy 331.685404 -233.954066) (xy 331.459332 -233.954066) (xy 331.459332 -234.360212) (xy 331.459811 -234.369567)
			(xy 331.466589 -234.387014) (xy 331.47254 -234.394248) (xy 331.517498 -234.443778) (xy 331.520809 -234.447248)
			(xy 331.528478 -234.453006) (xy 331.532738 -234.455208) (xy 331.540612 -234.459018) (xy 331.550264 -234.460034)
			(xy 331.550518 -234.460034) (xy 331.57539 -234.462945) (xy 331.623776 -234.475831) (xy 331.669414 -234.496435)
			(xy 331.71108 -234.524206) (xy 331.74766 -234.5584) (xy 331.778173 -234.598102) (xy 331.801803 -234.642249)
			(xy 331.817917 -234.689658) (xy 331.826083 -234.739061) (xy 331.826083 -234.764072) (xy 332.155304 -234.764072)
			(xy 332.159264 -234.715018) (xy 332.171041 -234.667234) (xy 332.190332 -234.621958) (xy 332.216635 -234.580362)
			(xy 332.24927 -234.543525) (xy 332.287391 -234.5124) (xy 332.330012 -234.487793) (xy 332.376028 -234.470341)
			(xy 332.424247 -234.460497) (xy 332.473422 -234.458516) (xy 332.522277 -234.464448) (xy 332.569548 -234.47814)
			(xy 332.61401 -234.499238) (xy 332.654513 -234.527194) (xy 332.690006 -234.561286) (xy 332.719571 -234.60063)
			(xy 332.742442 -234.644207) (xy 332.758026 -234.690888) (xy 332.765921 -234.739465) (xy 332.766416 -234.764072)
			(xy 333.095358 -234.764072) (xy 333.099318 -234.715018) (xy 333.111095 -234.667234) (xy 333.130386 -234.621958)
			(xy 333.156689 -234.580362) (xy 333.189324 -234.543525) (xy 333.227445 -234.5124) (xy 333.270066 -234.487793)
			(xy 333.316082 -234.470341) (xy 333.364301 -234.460497) (xy 333.413476 -234.458516) (xy 333.462331 -234.464448)
			(xy 333.509602 -234.47814) (xy 333.554064 -234.499238) (xy 333.594567 -234.527194) (xy 333.63006 -234.561286)
			(xy 333.659625 -234.60063) (xy 333.682496 -234.644207) (xy 333.69808 -234.690888) (xy 333.705975 -234.739465)
			(xy 333.70647 -234.764072) (xy 334.975212 -234.764072) (xy 334.979172 -234.715018) (xy 334.990949 -234.667234)
			(xy 335.01024 -234.621958) (xy 335.036543 -234.580362) (xy 335.069178 -234.543525) (xy 335.107299 -234.5124)
			(xy 335.14992 -234.487793) (xy 335.195936 -234.470341) (xy 335.244155 -234.460497) (xy 335.29333 -234.458516)
			(xy 335.342185 -234.464448) (xy 335.389456 -234.47814) (xy 335.433918 -234.499238) (xy 335.474421 -234.527194)
			(xy 335.509914 -234.561286) (xy 335.539479 -234.60063) (xy 335.56235 -234.644207) (xy 335.577934 -234.690888)
			(xy 335.585829 -234.739465) (xy 335.586324 -234.764072) (xy 335.915266 -234.764072) (xy 335.919226 -234.715018)
			(xy 335.931003 -234.667234) (xy 335.950294 -234.621958) (xy 335.976597 -234.580362) (xy 336.009232 -234.543525)
			(xy 336.047353 -234.5124) (xy 336.089974 -234.487793) (xy 336.13599 -234.470341) (xy 336.184209 -234.460497)
			(xy 336.233384 -234.458516) (xy 336.282239 -234.464448) (xy 336.32951 -234.47814) (xy 336.373972 -234.499238)
			(xy 336.414475 -234.527194) (xy 336.449968 -234.561286) (xy 336.479533 -234.60063) (xy 336.502404 -234.644207)
			(xy 336.517988 -234.690888) (xy 336.525883 -234.739465) (xy 336.526378 -234.764072) (xy 336.85532 -234.764072)
			(xy 336.85928 -234.715018) (xy 336.871057 -234.667234) (xy 336.890348 -234.621958) (xy 336.916651 -234.580362)
			(xy 336.949286 -234.543525) (xy 336.987407 -234.5124) (xy 337.030028 -234.487793) (xy 337.076044 -234.470341)
			(xy 337.124263 -234.460497) (xy 337.173438 -234.458516) (xy 337.222293 -234.464448) (xy 337.269564 -234.47814)
			(xy 337.314026 -234.499238) (xy 337.354529 -234.527194) (xy 337.390022 -234.561286) (xy 337.419587 -234.60063)
			(xy 337.442458 -234.644207) (xy 337.458042 -234.690888) (xy 337.465937 -234.739465) (xy 337.466432 -234.764072)
			(xy 337.795374 -234.764072) (xy 337.799334 -234.715018) (xy 337.811111 -234.667234) (xy 337.830402 -234.621958)
			(xy 337.856705 -234.580362) (xy 337.88934 -234.543525) (xy 337.927461 -234.5124) (xy 337.970082 -234.487793)
			(xy 338.016098 -234.470341) (xy 338.064317 -234.460497) (xy 338.113492 -234.458516) (xy 338.162347 -234.464448)
			(xy 338.209618 -234.47814) (xy 338.25408 -234.499238) (xy 338.294583 -234.527194) (xy 338.330076 -234.561286)
			(xy 338.359641 -234.60063) (xy 338.382512 -234.644207) (xy 338.398096 -234.690888) (xy 338.405991 -234.739465)
			(xy 338.406486 -234.764072) (xy 338.724743 -234.764072) (xy 338.728838 -234.713344) (xy 338.741017 -234.66393)
			(xy 338.760965 -234.61711) (xy 338.788166 -234.574096) (xy 338.821914 -234.536002) (xy 338.861336 -234.503815)
			(xy 338.90541 -234.478369) (xy 338.952996 -234.460322) (xy 339.00286 -234.450142) (xy 339.053712 -234.448093)
			(xy 339.104233 -234.454227) (xy 339.153117 -234.468387) (xy 339.199096 -234.490204) (xy 339.24098 -234.519114)
			(xy 339.277684 -234.554369) (xy 339.308257 -234.595055) (xy 339.331908 -234.640118) (xy 339.348024 -234.688392)
			(xy 339.356188 -234.738626) (xy 339.3567 -234.764072) (xy 339.664797 -234.764072) (xy 339.668892 -234.713344)
			(xy 339.681071 -234.66393) (xy 339.701019 -234.61711) (xy 339.72822 -234.574096) (xy 339.761968 -234.536002)
			(xy 339.80139 -234.503815) (xy 339.845464 -234.478369) (xy 339.89305 -234.460322) (xy 339.942914 -234.450142)
			(xy 339.993766 -234.448093) (xy 340.044287 -234.454227) (xy 340.093171 -234.468387) (xy 340.13915 -234.490204)
			(xy 340.181034 -234.519114) (xy 340.217738 -234.554369) (xy 340.248311 -234.595055) (xy 340.271962 -234.640118)
			(xy 340.288078 -234.688392) (xy 340.296242 -234.738626) (xy 340.296754 -234.764072) (xy 341.544905 -234.764072)
			(xy 341.549 -234.713344) (xy 341.561179 -234.66393) (xy 341.581127 -234.61711) (xy 341.608328 -234.574096)
			(xy 341.642076 -234.536002) (xy 341.681498 -234.503815) (xy 341.725572 -234.478369) (xy 341.773158 -234.460322)
			(xy 341.823022 -234.450142) (xy 341.873874 -234.448093) (xy 341.924395 -234.454227) (xy 341.973279 -234.468387)
			(xy 342.019258 -234.490204) (xy 342.061142 -234.519114) (xy 342.097846 -234.554369) (xy 342.128419 -234.595055)
			(xy 342.15207 -234.640118) (xy 342.168186 -234.688392) (xy 342.17635 -234.738626) (xy 342.176862 -234.764072)
			(xy 342.49539 -234.764072) (xy 342.49935 -234.715018) (xy 342.511127 -234.667234) (xy 342.530418 -234.621958)
			(xy 342.556721 -234.580362) (xy 342.589356 -234.543525) (xy 342.627477 -234.5124) (xy 342.670098 -234.487793)
			(xy 342.716114 -234.470341) (xy 342.764333 -234.460497) (xy 342.813508 -234.458516) (xy 342.862363 -234.464448)
			(xy 342.909634 -234.47814) (xy 342.954096 -234.499238) (xy 342.994599 -234.527194) (xy 343.030092 -234.561286)
			(xy 343.059657 -234.60063) (xy 343.082528 -234.644207) (xy 343.098112 -234.690888) (xy 343.106007 -234.739465)
			(xy 343.106502 -234.764072) (xy 343.106007 -234.788679) (xy 343.098112 -234.837256) (xy 343.082528 -234.883937)
			(xy 343.059657 -234.927514) (xy 343.030092 -234.966858) (xy 342.994599 -235.00095) (xy 342.954096 -235.028906)
			(xy 342.909634 -235.050004) (xy 342.862363 -235.063696) (xy 342.813508 -235.069628) (xy 342.764333 -235.067647)
			(xy 342.716114 -235.057803) (xy 342.670098 -235.040351) (xy 342.627477 -235.015744) (xy 342.589356 -234.984619)
			(xy 342.556721 -234.947782) (xy 342.530418 -234.906186) (xy 342.511127 -234.86091) (xy 342.49935 -234.813126)
			(xy 342.49539 -234.764072) (xy 342.176862 -234.764072) (xy 342.17635 -234.789518) (xy 342.168186 -234.839752)
			(xy 342.15207 -234.888026) (xy 342.128419 -234.933089) (xy 342.097846 -234.973775) (xy 342.061142 -235.00903)
			(xy 342.019258 -235.03794) (xy 341.973279 -235.059757) (xy 341.924395 -235.073917) (xy 341.873874 -235.080051)
			(xy 341.823022 -235.078002) (xy 341.773158 -235.067822) (xy 341.725572 -235.049775) (xy 341.681498 -235.024329)
			(xy 341.642076 -234.992142) (xy 341.608328 -234.954048) (xy 341.581127 -234.911034) (xy 341.561179 -234.864214)
			(xy 341.549 -234.8148) (xy 341.544905 -234.764072) (xy 340.296754 -234.764072) (xy 340.296242 -234.789518)
			(xy 340.288078 -234.839752) (xy 340.271962 -234.888026) (xy 340.248311 -234.933089) (xy 340.217738 -234.973775)
			(xy 340.181034 -235.00903) (xy 340.13915 -235.03794) (xy 340.093171 -235.059757) (xy 340.044287 -235.073917)
			(xy 339.993766 -235.080051) (xy 339.942914 -235.078002) (xy 339.89305 -235.067822) (xy 339.845464 -235.049775)
			(xy 339.80139 -235.024329) (xy 339.761968 -234.992142) (xy 339.72822 -234.954048) (xy 339.701019 -234.911034)
			(xy 339.681071 -234.864214) (xy 339.668892 -234.8148) (xy 339.664797 -234.764072) (xy 339.3567 -234.764072)
			(xy 339.356188 -234.789518) (xy 339.348024 -234.839752) (xy 339.331908 -234.888026) (xy 339.308257 -234.933089)
			(xy 339.277684 -234.973775) (xy 339.24098 -235.00903) (xy 339.199096 -235.03794) (xy 339.153117 -235.059757)
			(xy 339.104233 -235.073917) (xy 339.053712 -235.080051) (xy 339.00286 -235.078002) (xy 338.952996 -235.067822)
			(xy 338.90541 -235.049775) (xy 338.861336 -235.024329) (xy 338.821914 -234.992142) (xy 338.788166 -234.954048)
			(xy 338.760965 -234.911034) (xy 338.741017 -234.864214) (xy 338.728838 -234.8148) (xy 338.724743 -234.764072)
			(xy 338.406486 -234.764072) (xy 338.405991 -234.788679) (xy 338.398096 -234.837256) (xy 338.382512 -234.883937)
			(xy 338.359641 -234.927514) (xy 338.330076 -234.966858) (xy 338.294583 -235.00095) (xy 338.25408 -235.028906)
			(xy 338.209618 -235.050004) (xy 338.162347 -235.063696) (xy 338.113492 -235.069628) (xy 338.064317 -235.067647)
			(xy 338.016098 -235.057803) (xy 337.970082 -235.040351) (xy 337.927461 -235.015744) (xy 337.88934 -234.984619)
			(xy 337.856705 -234.947782) (xy 337.830402 -234.906186) (xy 337.811111 -234.86091) (xy 337.799334 -234.813126)
			(xy 337.795374 -234.764072) (xy 337.466432 -234.764072) (xy 337.465937 -234.788679) (xy 337.458042 -234.837256)
			(xy 337.442458 -234.883937) (xy 337.419587 -234.927514) (xy 337.390022 -234.966858) (xy 337.354529 -235.00095)
			(xy 337.314026 -235.028906) (xy 337.269564 -235.050004) (xy 337.222293 -235.063696) (xy 337.173438 -235.069628)
			(xy 337.124263 -235.067647) (xy 337.076044 -235.057803) (xy 337.030028 -235.040351) (xy 336.987407 -235.015744)
			(xy 336.949286 -234.984619) (xy 336.916651 -234.947782) (xy 336.890348 -234.906186) (xy 336.871057 -234.86091)
			(xy 336.85928 -234.813126) (xy 336.85532 -234.764072) (xy 336.526378 -234.764072) (xy 336.525883 -234.788679)
			(xy 336.517988 -234.837256) (xy 336.502404 -234.883937) (xy 336.479533 -234.927514) (xy 336.449968 -234.966858)
			(xy 336.414475 -235.00095) (xy 336.373972 -235.028906) (xy 336.32951 -235.050004) (xy 336.282239 -235.063696)
			(xy 336.233384 -235.069628) (xy 336.184209 -235.067647) (xy 336.13599 -235.057803) (xy 336.089974 -235.040351)
			(xy 336.047353 -235.015744) (xy 336.009232 -234.984619) (xy 335.976597 -234.947782) (xy 335.950294 -234.906186)
			(xy 335.931003 -234.86091) (xy 335.919226 -234.813126) (xy 335.915266 -234.764072) (xy 335.586324 -234.764072)
			(xy 335.585829 -234.788679) (xy 335.577934 -234.837256) (xy 335.56235 -234.883937) (xy 335.539479 -234.927514)
			(xy 335.509914 -234.966858) (xy 335.474421 -235.00095) (xy 335.433918 -235.028906) (xy 335.389456 -235.050004)
			(xy 335.342185 -235.063696) (xy 335.29333 -235.069628) (xy 335.244155 -235.067647) (xy 335.195936 -235.057803)
			(xy 335.14992 -235.040351) (xy 335.107299 -235.015744) (xy 335.069178 -234.984619) (xy 335.036543 -234.947782)
			(xy 335.01024 -234.906186) (xy 334.990949 -234.86091) (xy 334.979172 -234.813126) (xy 334.975212 -234.764072)
			(xy 333.70647 -234.764072) (xy 333.705975 -234.788679) (xy 333.69808 -234.837256) (xy 333.682496 -234.883937)
			(xy 333.659625 -234.927514) (xy 333.63006 -234.966858) (xy 333.594567 -235.00095) (xy 333.554064 -235.028906)
			(xy 333.509602 -235.050004) (xy 333.462331 -235.063696) (xy 333.413476 -235.069628) (xy 333.364301 -235.067647)
			(xy 333.316082 -235.057803) (xy 333.270066 -235.040351) (xy 333.227445 -235.015744) (xy 333.189324 -234.984619)
			(xy 333.156689 -234.947782) (xy 333.130386 -234.906186) (xy 333.111095 -234.86091) (xy 333.099318 -234.813126)
			(xy 333.095358 -234.764072) (xy 332.766416 -234.764072) (xy 332.765921 -234.788679) (xy 332.758026 -234.837256)
			(xy 332.742442 -234.883937) (xy 332.719571 -234.927514) (xy 332.690006 -234.966858) (xy 332.654513 -235.00095)
			(xy 332.61401 -235.028906) (xy 332.569548 -235.050004) (xy 332.522277 -235.063696) (xy 332.473422 -235.069628)
			(xy 332.424247 -235.067647) (xy 332.376028 -235.057803) (xy 332.330012 -235.040351) (xy 332.287391 -235.015744)
			(xy 332.24927 -234.984619) (xy 332.216635 -234.947782) (xy 332.190332 -234.906186) (xy 332.171041 -234.86091)
			(xy 332.159264 -234.813126) (xy 332.155304 -234.764072) (xy 331.826083 -234.764072) (xy 331.826084 -234.789134)
			(xy 331.817918 -234.838537) (xy 331.801805 -234.885946) (xy 331.778176 -234.930093) (xy 331.747663 -234.969796)
			(xy 331.711084 -235.003991) (xy 331.669419 -235.031763) (xy 331.623782 -235.052368) (xy 331.575395 -235.065254)
			(xy 331.550518 -235.06811) (xy 331.550264 -235.06811) (xy 331.540612 -235.069126) (xy 331.532738 -235.072936)
			(xy 331.528477 -235.075138) (xy 331.520802 -235.080889) (xy 331.517498 -235.084366) (xy 331.47254 -235.133896)
			(xy 331.466479 -235.141066) (xy 331.459679 -235.158551) (xy 331.459332 -235.167932) (xy 331.459332 -235.574078)
			(xy 331.685404 -235.574078) (xy 331.689364 -235.525024) (xy 331.701141 -235.47724) (xy 331.720432 -235.431964)
			(xy 331.746735 -235.390368) (xy 331.77937 -235.353531) (xy 331.817491 -235.322406) (xy 331.860112 -235.297799)
			(xy 331.906128 -235.280347) (xy 331.954347 -235.270503) (xy 332.003522 -235.268522) (xy 332.052377 -235.274454)
			(xy 332.099648 -235.288146) (xy 332.14411 -235.309244) (xy 332.184613 -235.3372) (xy 332.220106 -235.371292)
			(xy 332.249671 -235.410636) (xy 332.272542 -235.454213) (xy 332.288126 -235.500894) (xy 332.296021 -235.549471)
			(xy 332.296516 -235.574078) (xy 332.625204 -235.574078) (xy 332.629164 -235.525024) (xy 332.640941 -235.47724)
			(xy 332.660232 -235.431964) (xy 332.686535 -235.390368) (xy 332.71917 -235.353531) (xy 332.757291 -235.322406)
			(xy 332.799912 -235.297799) (xy 332.845928 -235.280347) (xy 332.894147 -235.270503) (xy 332.943322 -235.268522)
			(xy 332.992177 -235.274454) (xy 333.039448 -235.288146) (xy 333.08391 -235.309244) (xy 333.124413 -235.3372)
			(xy 333.159906 -235.371292) (xy 333.189471 -235.410636) (xy 333.212342 -235.454213) (xy 333.227926 -235.500894)
			(xy 333.235821 -235.549471) (xy 333.236316 -235.574078) (xy 333.565258 -235.574078) (xy 333.569218 -235.525024)
			(xy 333.580995 -235.47724) (xy 333.600286 -235.431964) (xy 333.626589 -235.390368) (xy 333.659224 -235.353531)
			(xy 333.697345 -235.322406) (xy 333.739966 -235.297799) (xy 333.785982 -235.280347) (xy 333.834201 -235.270503)
			(xy 333.883376 -235.268522) (xy 333.932231 -235.274454) (xy 333.979502 -235.288146) (xy 334.023964 -235.309244)
			(xy 334.064467 -235.3372) (xy 334.09996 -235.371292) (xy 334.129525 -235.410636) (xy 334.152396 -235.454213)
			(xy 334.16798 -235.500894) (xy 334.175875 -235.549471) (xy 334.17637 -235.574078) (xy 334.505312 -235.574078)
			(xy 334.509272 -235.525024) (xy 334.521049 -235.47724) (xy 334.54034 -235.431964) (xy 334.566643 -235.390368)
			(xy 334.599278 -235.353531) (xy 334.637399 -235.322406) (xy 334.68002 -235.297799) (xy 334.726036 -235.280347)
			(xy 334.774255 -235.270503) (xy 334.82343 -235.268522) (xy 334.872285 -235.274454) (xy 334.919556 -235.288146)
			(xy 334.964018 -235.309244) (xy 335.004521 -235.3372) (xy 335.040014 -235.371292) (xy 335.069579 -235.410636)
			(xy 335.09245 -235.454213) (xy 335.108034 -235.500894) (xy 335.115929 -235.549471) (xy 335.116424 -235.574078)
			(xy 335.445366 -235.574078) (xy 335.449326 -235.525024) (xy 335.461103 -235.47724) (xy 335.480394 -235.431964)
			(xy 335.506697 -235.390368) (xy 335.539332 -235.353531) (xy 335.577453 -235.322406) (xy 335.620074 -235.297799)
			(xy 335.66609 -235.280347) (xy 335.714309 -235.270503) (xy 335.763484 -235.268522) (xy 335.812339 -235.274454)
			(xy 335.85961 -235.288146) (xy 335.904072 -235.309244) (xy 335.944575 -235.3372) (xy 335.980068 -235.371292)
			(xy 336.009633 -235.410636) (xy 336.032504 -235.454213) (xy 336.048088 -235.500894) (xy 336.055983 -235.549471)
			(xy 336.056478 -235.574078) (xy 336.38542 -235.574078) (xy 336.38938 -235.525024) (xy 336.401157 -235.47724)
			(xy 336.420448 -235.431964) (xy 336.446751 -235.390368) (xy 336.479386 -235.353531) (xy 336.517507 -235.322406)
			(xy 336.560128 -235.297799) (xy 336.606144 -235.280347) (xy 336.654363 -235.270503) (xy 336.703538 -235.268522)
			(xy 336.752393 -235.274454) (xy 336.799664 -235.288146) (xy 336.844126 -235.309244) (xy 336.884629 -235.3372)
			(xy 336.920122 -235.371292) (xy 336.949687 -235.410636) (xy 336.972558 -235.454213) (xy 336.988142 -235.500894)
			(xy 336.996037 -235.549471) (xy 336.996532 -235.574078) (xy 337.32522 -235.574078) (xy 337.32918 -235.525024)
			(xy 337.340957 -235.47724) (xy 337.360248 -235.431964) (xy 337.386551 -235.390368) (xy 337.419186 -235.353531)
			(xy 337.457307 -235.322406) (xy 337.499928 -235.297799) (xy 337.545944 -235.280347) (xy 337.594163 -235.270503)
			(xy 337.643338 -235.268522) (xy 337.692193 -235.274454) (xy 337.739464 -235.288146) (xy 337.783926 -235.309244)
			(xy 337.824429 -235.3372) (xy 337.859922 -235.371292) (xy 337.889487 -235.410636) (xy 337.912358 -235.454213)
			(xy 337.927942 -235.500894) (xy 337.935837 -235.549471) (xy 337.936332 -235.574078) (xy 338.254843 -235.574078)
			(xy 338.258938 -235.52335) (xy 338.271117 -235.473936) (xy 338.291065 -235.427116) (xy 338.318266 -235.384102)
			(xy 338.352014 -235.346008) (xy 338.391436 -235.313821) (xy 338.43551 -235.288375) (xy 338.483096 -235.270328)
			(xy 338.53296 -235.260148) (xy 338.583812 -235.258099) (xy 338.634333 -235.264233) (xy 338.683217 -235.278393)
			(xy 338.729196 -235.30021) (xy 338.77108 -235.32912) (xy 338.807784 -235.364375) (xy 338.838357 -235.405061)
			(xy 338.862008 -235.450124) (xy 338.878124 -235.498398) (xy 338.886288 -235.548632) (xy 338.8868 -235.574078)
			(xy 339.205328 -235.574078) (xy 339.209288 -235.525024) (xy 339.221065 -235.47724) (xy 339.240356 -235.431964)
			(xy 339.266659 -235.390368) (xy 339.299294 -235.353531) (xy 339.337415 -235.322406) (xy 339.380036 -235.297799)
			(xy 339.426052 -235.280347) (xy 339.474271 -235.270503) (xy 339.523446 -235.268522) (xy 339.572301 -235.274454)
			(xy 339.619572 -235.288146) (xy 339.664034 -235.309244) (xy 339.704537 -235.3372) (xy 339.74003 -235.371292)
			(xy 339.769595 -235.410636) (xy 339.792466 -235.454213) (xy 339.80805 -235.500894) (xy 339.815945 -235.549471)
			(xy 339.81644 -235.574078) (xy 340.134951 -235.574078) (xy 340.139046 -235.52335) (xy 340.151225 -235.473936)
			(xy 340.171173 -235.427116) (xy 340.198374 -235.384102) (xy 340.232122 -235.346008) (xy 340.271544 -235.313821)
			(xy 340.315618 -235.288375) (xy 340.363204 -235.270328) (xy 340.413068 -235.260148) (xy 340.46392 -235.258099)
			(xy 340.514441 -235.264233) (xy 340.563325 -235.278393) (xy 340.609304 -235.30021) (xy 340.651188 -235.32912)
			(xy 340.687892 -235.364375) (xy 340.718465 -235.405061) (xy 340.742116 -235.450124) (xy 340.758232 -235.498398)
			(xy 340.766396 -235.548632) (xy 340.766908 -235.574078) (xy 341.085182 -235.574078) (xy 341.089142 -235.525024)
			(xy 341.100919 -235.47724) (xy 341.12021 -235.431964) (xy 341.146513 -235.390368) (xy 341.179148 -235.353531)
			(xy 341.217269 -235.322406) (xy 341.25989 -235.297799) (xy 341.305906 -235.280347) (xy 341.354125 -235.270503)
			(xy 341.4033 -235.268522) (xy 341.452155 -235.274454) (xy 341.499426 -235.288146) (xy 341.543888 -235.309244)
			(xy 341.584391 -235.3372) (xy 341.619884 -235.371292) (xy 341.649449 -235.410636) (xy 341.67232 -235.454213)
			(xy 341.687904 -235.500894) (xy 341.695799 -235.549471) (xy 341.696294 -235.574078) (xy 342.014805 -235.574078)
			(xy 342.0189 -235.52335) (xy 342.031079 -235.473936) (xy 342.051027 -235.427116) (xy 342.078228 -235.384102)
			(xy 342.111976 -235.346008) (xy 342.151398 -235.313821) (xy 342.195472 -235.288375) (xy 342.243058 -235.270328)
			(xy 342.292922 -235.260148) (xy 342.343774 -235.258099) (xy 342.394295 -235.264233) (xy 342.443179 -235.278393)
			(xy 342.489158 -235.30021) (xy 342.531042 -235.32912) (xy 342.567746 -235.364375) (xy 342.598319 -235.405061)
			(xy 342.62197 -235.450124) (xy 342.638086 -235.498398) (xy 342.64625 -235.548632) (xy 342.646762 -235.574078)
			(xy 342.64625 -235.599524) (xy 342.638086 -235.649758) (xy 342.62197 -235.698032) (xy 342.598319 -235.743095)
			(xy 342.567746 -235.783781) (xy 342.531042 -235.819036) (xy 342.489158 -235.847946) (xy 342.443179 -235.869763)
			(xy 342.394295 -235.883923) (xy 342.343774 -235.890057) (xy 342.292922 -235.888008) (xy 342.243058 -235.877828)
			(xy 342.195472 -235.859781) (xy 342.151398 -235.834335) (xy 342.111976 -235.802148) (xy 342.078228 -235.764054)
			(xy 342.051027 -235.72104) (xy 342.031079 -235.67422) (xy 342.0189 -235.624806) (xy 342.014805 -235.574078)
			(xy 341.696294 -235.574078) (xy 341.695799 -235.598685) (xy 341.687904 -235.647262) (xy 341.67232 -235.693943)
			(xy 341.649449 -235.73752) (xy 341.619884 -235.776864) (xy 341.584391 -235.810956) (xy 341.543888 -235.838912)
			(xy 341.499426 -235.86001) (xy 341.452155 -235.873702) (xy 341.4033 -235.879634) (xy 341.354125 -235.877653)
			(xy 341.305906 -235.867809) (xy 341.25989 -235.850357) (xy 341.217269 -235.82575) (xy 341.179148 -235.794625)
			(xy 341.146513 -235.757788) (xy 341.12021 -235.716192) (xy 341.100919 -235.670916) (xy 341.089142 -235.623132)
			(xy 341.085182 -235.574078) (xy 340.766908 -235.574078) (xy 340.766396 -235.599524) (xy 340.758232 -235.649758)
			(xy 340.742116 -235.698032) (xy 340.718465 -235.743095) (xy 340.687892 -235.783781) (xy 340.651188 -235.819036)
			(xy 340.609304 -235.847946) (xy 340.563325 -235.869763) (xy 340.514441 -235.883923) (xy 340.46392 -235.890057)
			(xy 340.413068 -235.888008) (xy 340.363204 -235.877828) (xy 340.315618 -235.859781) (xy 340.271544 -235.834335)
			(xy 340.232122 -235.802148) (xy 340.198374 -235.764054) (xy 340.171173 -235.72104) (xy 340.151225 -235.67422)
			(xy 340.139046 -235.624806) (xy 340.134951 -235.574078) (xy 339.81644 -235.574078) (xy 339.815945 -235.598685)
			(xy 339.80805 -235.647262) (xy 339.792466 -235.693943) (xy 339.769595 -235.73752) (xy 339.74003 -235.776864)
			(xy 339.704537 -235.810956) (xy 339.664034 -235.838912) (xy 339.619572 -235.86001) (xy 339.572301 -235.873702)
			(xy 339.523446 -235.879634) (xy 339.474271 -235.877653) (xy 339.426052 -235.867809) (xy 339.380036 -235.850357)
			(xy 339.337415 -235.82575) (xy 339.299294 -235.794625) (xy 339.266659 -235.757788) (xy 339.240356 -235.716192)
			(xy 339.221065 -235.670916) (xy 339.209288 -235.623132) (xy 339.205328 -235.574078) (xy 338.8868 -235.574078)
			(xy 338.886288 -235.599524) (xy 338.878124 -235.649758) (xy 338.862008 -235.698032) (xy 338.838357 -235.743095)
			(xy 338.807784 -235.783781) (xy 338.77108 -235.819036) (xy 338.729196 -235.847946) (xy 338.683217 -235.869763)
			(xy 338.634333 -235.883923) (xy 338.583812 -235.890057) (xy 338.53296 -235.888008) (xy 338.483096 -235.877828)
			(xy 338.43551 -235.859781) (xy 338.391436 -235.834335) (xy 338.352014 -235.802148) (xy 338.318266 -235.764054)
			(xy 338.291065 -235.72104) (xy 338.271117 -235.67422) (xy 338.258938 -235.624806) (xy 338.254843 -235.574078)
			(xy 337.936332 -235.574078) (xy 337.935837 -235.598685) (xy 337.927942 -235.647262) (xy 337.912358 -235.693943)
			(xy 337.889487 -235.73752) (xy 337.859922 -235.776864) (xy 337.824429 -235.810956) (xy 337.783926 -235.838912)
			(xy 337.739464 -235.86001) (xy 337.692193 -235.873702) (xy 337.643338 -235.879634) (xy 337.594163 -235.877653)
			(xy 337.545944 -235.867809) (xy 337.499928 -235.850357) (xy 337.457307 -235.82575) (xy 337.419186 -235.794625)
			(xy 337.386551 -235.757788) (xy 337.360248 -235.716192) (xy 337.340957 -235.670916) (xy 337.32918 -235.623132)
			(xy 337.32522 -235.574078) (xy 336.996532 -235.574078) (xy 336.996037 -235.598685) (xy 336.988142 -235.647262)
			(xy 336.972558 -235.693943) (xy 336.949687 -235.73752) (xy 336.920122 -235.776864) (xy 336.884629 -235.810956)
			(xy 336.844126 -235.838912) (xy 336.799664 -235.86001) (xy 336.752393 -235.873702) (xy 336.703538 -235.879634)
			(xy 336.654363 -235.877653) (xy 336.606144 -235.867809) (xy 336.560128 -235.850357) (xy 336.517507 -235.82575)
			(xy 336.479386 -235.794625) (xy 336.446751 -235.757788) (xy 336.420448 -235.716192) (xy 336.401157 -235.670916)
			(xy 336.38938 -235.623132) (xy 336.38542 -235.574078) (xy 336.056478 -235.574078) (xy 336.055983 -235.598685)
			(xy 336.048088 -235.647262) (xy 336.032504 -235.693943) (xy 336.009633 -235.73752) (xy 335.980068 -235.776864)
			(xy 335.944575 -235.810956) (xy 335.904072 -235.838912) (xy 335.85961 -235.86001) (xy 335.812339 -235.873702)
			(xy 335.763484 -235.879634) (xy 335.714309 -235.877653) (xy 335.66609 -235.867809) (xy 335.620074 -235.850357)
			(xy 335.577453 -235.82575) (xy 335.539332 -235.794625) (xy 335.506697 -235.757788) (xy 335.480394 -235.716192)
			(xy 335.461103 -235.670916) (xy 335.449326 -235.623132) (xy 335.445366 -235.574078) (xy 335.116424 -235.574078)
			(xy 335.115929 -235.598685) (xy 335.108034 -235.647262) (xy 335.09245 -235.693943) (xy 335.069579 -235.73752)
			(xy 335.040014 -235.776864) (xy 335.004521 -235.810956) (xy 334.964018 -235.838912) (xy 334.919556 -235.86001)
			(xy 334.872285 -235.873702) (xy 334.82343 -235.879634) (xy 334.774255 -235.877653) (xy 334.726036 -235.867809)
			(xy 334.68002 -235.850357) (xy 334.637399 -235.82575) (xy 334.599278 -235.794625) (xy 334.566643 -235.757788)
			(xy 334.54034 -235.716192) (xy 334.521049 -235.670916) (xy 334.509272 -235.623132) (xy 334.505312 -235.574078)
			(xy 334.17637 -235.574078) (xy 334.175875 -235.598685) (xy 334.16798 -235.647262) (xy 334.152396 -235.693943)
			(xy 334.129525 -235.73752) (xy 334.09996 -235.776864) (xy 334.064467 -235.810956) (xy 334.023964 -235.838912)
			(xy 333.979502 -235.86001) (xy 333.932231 -235.873702) (xy 333.883376 -235.879634) (xy 333.834201 -235.877653)
			(xy 333.785982 -235.867809) (xy 333.739966 -235.850357) (xy 333.697345 -235.82575) (xy 333.659224 -235.794625)
			(xy 333.626589 -235.757788) (xy 333.600286 -235.716192) (xy 333.580995 -235.670916) (xy 333.569218 -235.623132)
			(xy 333.565258 -235.574078) (xy 333.236316 -235.574078) (xy 333.235821 -235.598685) (xy 333.227926 -235.647262)
			(xy 333.212342 -235.693943) (xy 333.189471 -235.73752) (xy 333.159906 -235.776864) (xy 333.124413 -235.810956)
			(xy 333.08391 -235.838912) (xy 333.039448 -235.86001) (xy 332.992177 -235.873702) (xy 332.943322 -235.879634)
			(xy 332.894147 -235.877653) (xy 332.845928 -235.867809) (xy 332.799912 -235.850357) (xy 332.757291 -235.82575)
			(xy 332.71917 -235.794625) (xy 332.686535 -235.757788) (xy 332.660232 -235.716192) (xy 332.640941 -235.670916)
			(xy 332.629164 -235.623132) (xy 332.625204 -235.574078) (xy 332.296516 -235.574078) (xy 332.296021 -235.598685)
			(xy 332.288126 -235.647262) (xy 332.272542 -235.693943) (xy 332.249671 -235.73752) (xy 332.220106 -235.776864)
			(xy 332.184613 -235.810956) (xy 332.14411 -235.838912) (xy 332.099648 -235.86001) (xy 332.052377 -235.873702)
			(xy 332.003522 -235.879634) (xy 331.954347 -235.877653) (xy 331.906128 -235.867809) (xy 331.860112 -235.850357)
			(xy 331.817491 -235.82575) (xy 331.77937 -235.794625) (xy 331.746735 -235.757788) (xy 331.720432 -235.716192)
			(xy 331.701141 -235.670916) (xy 331.689364 -235.623132) (xy 331.685404 -235.574078) (xy 331.459332 -235.574078)
			(xy 331.459332 -235.980224) (xy 331.459796 -235.989585) (xy 331.466552 -236.007052) (xy 331.47254 -236.01426)
			(xy 331.517498 -236.06379) (xy 331.52081 -236.067259) (xy 331.528479 -236.073016) (xy 331.532738 -236.07522)
			(xy 331.540612 -236.07903) (xy 331.550264 -236.080046) (xy 331.550518 -236.080046) (xy 331.575389 -236.082957)
			(xy 331.623774 -236.095842) (xy 331.669409 -236.116446) (xy 331.711074 -236.144216) (xy 331.747651 -236.178409)
			(xy 331.778163 -236.21811) (xy 331.801792 -236.262255) (xy 331.817905 -236.309662) (xy 331.826071 -236.359063)
			(xy 331.826071 -236.384084) (xy 332.155304 -236.384084) (xy 332.159264 -236.33503) (xy 332.171041 -236.287246)
			(xy 332.190332 -236.24197) (xy 332.216635 -236.200374) (xy 332.24927 -236.163537) (xy 332.287391 -236.132412)
			(xy 332.330012 -236.107805) (xy 332.376028 -236.090353) (xy 332.424247 -236.080509) (xy 332.473422 -236.078528)
			(xy 332.522277 -236.08446) (xy 332.569548 -236.098152) (xy 332.61401 -236.11925) (xy 332.654513 -236.147206)
			(xy 332.690006 -236.181298) (xy 332.719571 -236.220642) (xy 332.742442 -236.264219) (xy 332.758026 -236.3109)
			(xy 332.765921 -236.359477) (xy 332.766416 -236.384084) (xy 333.095358 -236.384084) (xy 333.099318 -236.33503)
			(xy 333.111095 -236.287246) (xy 333.130386 -236.24197) (xy 333.156689 -236.200374) (xy 333.189324 -236.163537)
			(xy 333.227445 -236.132412) (xy 333.270066 -236.107805) (xy 333.316082 -236.090353) (xy 333.364301 -236.080509)
			(xy 333.413476 -236.078528) (xy 333.462331 -236.08446) (xy 333.509602 -236.098152) (xy 333.554064 -236.11925)
			(xy 333.594567 -236.147206) (xy 333.63006 -236.181298) (xy 333.659625 -236.220642) (xy 333.682496 -236.264219)
			(xy 333.69808 -236.3109) (xy 333.705975 -236.359477) (xy 333.70647 -236.384084) (xy 334.035412 -236.384084)
			(xy 334.039372 -236.33503) (xy 334.051149 -236.287246) (xy 334.07044 -236.24197) (xy 334.096743 -236.200374)
			(xy 334.129378 -236.163537) (xy 334.167499 -236.132412) (xy 334.21012 -236.107805) (xy 334.256136 -236.090353)
			(xy 334.304355 -236.080509) (xy 334.35353 -236.078528) (xy 334.402385 -236.08446) (xy 334.449656 -236.098152)
			(xy 334.494118 -236.11925) (xy 334.534621 -236.147206) (xy 334.570114 -236.181298) (xy 334.599679 -236.220642)
			(xy 334.62255 -236.264219) (xy 334.638134 -236.3109) (xy 334.646029 -236.359477) (xy 334.646524 -236.384084)
			(xy 334.975212 -236.384084) (xy 334.979172 -236.33503) (xy 334.990949 -236.287246) (xy 335.01024 -236.24197)
			(xy 335.036543 -236.200374) (xy 335.069178 -236.163537) (xy 335.107299 -236.132412) (xy 335.14992 -236.107805)
			(xy 335.195936 -236.090353) (xy 335.244155 -236.080509) (xy 335.29333 -236.078528) (xy 335.342185 -236.08446)
			(xy 335.389456 -236.098152) (xy 335.433918 -236.11925) (xy 335.474421 -236.147206) (xy 335.509914 -236.181298)
			(xy 335.539479 -236.220642) (xy 335.56235 -236.264219) (xy 335.577934 -236.3109) (xy 335.585829 -236.359477)
			(xy 335.586324 -236.384084) (xy 335.915266 -236.384084) (xy 335.919226 -236.33503) (xy 335.931003 -236.287246)
			(xy 335.950294 -236.24197) (xy 335.976597 -236.200374) (xy 336.009232 -236.163537) (xy 336.047353 -236.132412)
			(xy 336.089974 -236.107805) (xy 336.13599 -236.090353) (xy 336.184209 -236.080509) (xy 336.233384 -236.078528)
			(xy 336.282239 -236.08446) (xy 336.32951 -236.098152) (xy 336.373972 -236.11925) (xy 336.414475 -236.147206)
			(xy 336.449968 -236.181298) (xy 336.479533 -236.220642) (xy 336.502404 -236.264219) (xy 336.517988 -236.3109)
			(xy 336.525883 -236.359477) (xy 336.526378 -236.384084) (xy 336.85532 -236.384084) (xy 336.85928 -236.33503)
			(xy 336.871057 -236.287246) (xy 336.890348 -236.24197) (xy 336.916651 -236.200374) (xy 336.949286 -236.163537)
			(xy 336.987407 -236.132412) (xy 337.030028 -236.107805) (xy 337.076044 -236.090353) (xy 337.124263 -236.080509)
			(xy 337.173438 -236.078528) (xy 337.222293 -236.08446) (xy 337.269564 -236.098152) (xy 337.314026 -236.11925)
			(xy 337.354529 -236.147206) (xy 337.390022 -236.181298) (xy 337.419587 -236.220642) (xy 337.442458 -236.264219)
			(xy 337.458042 -236.3109) (xy 337.465937 -236.359477) (xy 337.466432 -236.384084) (xy 337.795374 -236.384084)
			(xy 337.799334 -236.33503) (xy 337.811111 -236.287246) (xy 337.830402 -236.24197) (xy 337.856705 -236.200374)
			(xy 337.88934 -236.163537) (xy 337.927461 -236.132412) (xy 337.970082 -236.107805) (xy 338.016098 -236.090353)
			(xy 338.064317 -236.080509) (xy 338.113492 -236.078528) (xy 338.162347 -236.08446) (xy 338.209618 -236.098152)
			(xy 338.25408 -236.11925) (xy 338.294583 -236.147206) (xy 338.330076 -236.181298) (xy 338.359641 -236.220642)
			(xy 338.382512 -236.264219) (xy 338.398096 -236.3109) (xy 338.405991 -236.359477) (xy 338.406486 -236.384084)
			(xy 338.724743 -236.384084) (xy 338.728838 -236.333356) (xy 338.741017 -236.283942) (xy 338.760965 -236.237122)
			(xy 338.788166 -236.194108) (xy 338.821914 -236.156014) (xy 338.861336 -236.123827) (xy 338.90541 -236.098381)
			(xy 338.952996 -236.080334) (xy 339.00286 -236.070154) (xy 339.053712 -236.068105) (xy 339.104233 -236.074239)
			(xy 339.153117 -236.088399) (xy 339.199096 -236.110216) (xy 339.24098 -236.139126) (xy 339.277684 -236.174381)
			(xy 339.308257 -236.215067) (xy 339.331908 -236.26013) (xy 339.348024 -236.308404) (xy 339.356188 -236.358638)
			(xy 339.3567 -236.384084) (xy 339.664797 -236.384084) (xy 339.668892 -236.333356) (xy 339.681071 -236.283942)
			(xy 339.701019 -236.237122) (xy 339.72822 -236.194108) (xy 339.761968 -236.156014) (xy 339.80139 -236.123827)
			(xy 339.845464 -236.098381) (xy 339.89305 -236.080334) (xy 339.942914 -236.070154) (xy 339.993766 -236.068105)
			(xy 340.044287 -236.074239) (xy 340.093171 -236.088399) (xy 340.13915 -236.110216) (xy 340.181034 -236.139126)
			(xy 340.217738 -236.174381) (xy 340.248311 -236.215067) (xy 340.271962 -236.26013) (xy 340.288078 -236.308404)
			(xy 340.296242 -236.358638) (xy 340.296754 -236.384084) (xy 340.615282 -236.384084) (xy 340.619242 -236.33503)
			(xy 340.631019 -236.287246) (xy 340.65031 -236.24197) (xy 340.676613 -236.200374) (xy 340.709248 -236.163537)
			(xy 340.747369 -236.132412) (xy 340.78999 -236.107805) (xy 340.836006 -236.090353) (xy 340.884225 -236.080509)
			(xy 340.9334 -236.078528) (xy 340.982255 -236.08446) (xy 341.029526 -236.098152) (xy 341.073988 -236.11925)
			(xy 341.114491 -236.147206) (xy 341.149984 -236.181298) (xy 341.179549 -236.220642) (xy 341.20242 -236.264219)
			(xy 341.218004 -236.3109) (xy 341.225899 -236.359477) (xy 341.226394 -236.384084) (xy 341.544905 -236.384084)
			(xy 341.549 -236.333356) (xy 341.561179 -236.283942) (xy 341.581127 -236.237122) (xy 341.608328 -236.194108)
			(xy 341.642076 -236.156014) (xy 341.681498 -236.123827) (xy 341.725572 -236.098381) (xy 341.773158 -236.080334)
			(xy 341.823022 -236.070154) (xy 341.873874 -236.068105) (xy 341.924395 -236.074239) (xy 341.973279 -236.088399)
			(xy 342.019258 -236.110216) (xy 342.061142 -236.139126) (xy 342.097846 -236.174381) (xy 342.128419 -236.215067)
			(xy 342.15207 -236.26013) (xy 342.168186 -236.308404) (xy 342.17635 -236.358638) (xy 342.176862 -236.384084)
			(xy 342.49539 -236.384084) (xy 342.49935 -236.33503) (xy 342.511127 -236.287246) (xy 342.530418 -236.24197)
			(xy 342.556721 -236.200374) (xy 342.589356 -236.163537) (xy 342.627477 -236.132412) (xy 342.670098 -236.107805)
			(xy 342.716114 -236.090353) (xy 342.764333 -236.080509) (xy 342.813508 -236.078528) (xy 342.862363 -236.08446)
			(xy 342.909634 -236.098152) (xy 342.954096 -236.11925) (xy 342.994599 -236.147206) (xy 343.030092 -236.181298)
			(xy 343.059657 -236.220642) (xy 343.082528 -236.264219) (xy 343.098112 -236.3109) (xy 343.106007 -236.359477)
			(xy 343.106502 -236.384084) (xy 343.106007 -236.408691) (xy 343.098112 -236.457268) (xy 343.082528 -236.503949)
			(xy 343.059657 -236.547526) (xy 343.030092 -236.58687) (xy 342.994599 -236.620962) (xy 342.954096 -236.648918)
			(xy 342.909634 -236.670016) (xy 342.862363 -236.683708) (xy 342.813508 -236.68964) (xy 342.764333 -236.687659)
			(xy 342.716114 -236.677815) (xy 342.670098 -236.660363) (xy 342.627477 -236.635756) (xy 342.589356 -236.604631)
			(xy 342.556721 -236.567794) (xy 342.530418 -236.526198) (xy 342.511127 -236.480922) (xy 342.49935 -236.433138)
			(xy 342.49539 -236.384084) (xy 342.176862 -236.384084) (xy 342.17635 -236.40953) (xy 342.168186 -236.459764)
			(xy 342.15207 -236.508038) (xy 342.128419 -236.553101) (xy 342.097846 -236.593787) (xy 342.061142 -236.629042)
			(xy 342.019258 -236.657952) (xy 341.973279 -236.679769) (xy 341.924395 -236.693929) (xy 341.873874 -236.700063)
			(xy 341.823022 -236.698014) (xy 341.773158 -236.687834) (xy 341.725572 -236.669787) (xy 341.681498 -236.644341)
			(xy 341.642076 -236.612154) (xy 341.608328 -236.57406) (xy 341.581127 -236.531046) (xy 341.561179 -236.484226)
			(xy 341.549 -236.434812) (xy 341.544905 -236.384084) (xy 341.226394 -236.384084) (xy 341.225899 -236.408691)
			(xy 341.218004 -236.457268) (xy 341.20242 -236.503949) (xy 341.179549 -236.547526) (xy 341.149984 -236.58687)
			(xy 341.114491 -236.620962) (xy 341.073988 -236.648918) (xy 341.029526 -236.670016) (xy 340.982255 -236.683708)
			(xy 340.9334 -236.68964) (xy 340.884225 -236.687659) (xy 340.836006 -236.677815) (xy 340.78999 -236.660363)
			(xy 340.747369 -236.635756) (xy 340.709248 -236.604631) (xy 340.676613 -236.567794) (xy 340.65031 -236.526198)
			(xy 340.631019 -236.480922) (xy 340.619242 -236.433138) (xy 340.615282 -236.384084) (xy 340.296754 -236.384084)
			(xy 340.296242 -236.40953) (xy 340.288078 -236.459764) (xy 340.271962 -236.508038) (xy 340.248311 -236.553101)
			(xy 340.217738 -236.593787) (xy 340.181034 -236.629042) (xy 340.13915 -236.657952) (xy 340.093171 -236.679769)
			(xy 340.044287 -236.693929) (xy 339.993766 -236.700063) (xy 339.942914 -236.698014) (xy 339.89305 -236.687834)
			(xy 339.845464 -236.669787) (xy 339.80139 -236.644341) (xy 339.761968 -236.612154) (xy 339.72822 -236.57406)
			(xy 339.701019 -236.531046) (xy 339.681071 -236.484226) (xy 339.668892 -236.434812) (xy 339.664797 -236.384084)
			(xy 339.3567 -236.384084) (xy 339.356188 -236.40953) (xy 339.348024 -236.459764) (xy 339.331908 -236.508038)
			(xy 339.308257 -236.553101) (xy 339.277684 -236.593787) (xy 339.24098 -236.629042) (xy 339.199096 -236.657952)
			(xy 339.153117 -236.679769) (xy 339.104233 -236.693929) (xy 339.053712 -236.700063) (xy 339.00286 -236.698014)
			(xy 338.952996 -236.687834) (xy 338.90541 -236.669787) (xy 338.861336 -236.644341) (xy 338.821914 -236.612154)
			(xy 338.788166 -236.57406) (xy 338.760965 -236.531046) (xy 338.741017 -236.484226) (xy 338.728838 -236.434812)
			(xy 338.724743 -236.384084) (xy 338.406486 -236.384084) (xy 338.405991 -236.408691) (xy 338.398096 -236.457268)
			(xy 338.382512 -236.503949) (xy 338.359641 -236.547526) (xy 338.330076 -236.58687) (xy 338.294583 -236.620962)
			(xy 338.25408 -236.648918) (xy 338.209618 -236.670016) (xy 338.162347 -236.683708) (xy 338.113492 -236.68964)
			(xy 338.064317 -236.687659) (xy 338.016098 -236.677815) (xy 337.970082 -236.660363) (xy 337.927461 -236.635756)
			(xy 337.88934 -236.604631) (xy 337.856705 -236.567794) (xy 337.830402 -236.526198) (xy 337.811111 -236.480922)
			(xy 337.799334 -236.433138) (xy 337.795374 -236.384084) (xy 337.466432 -236.384084) (xy 337.465937 -236.408691)
			(xy 337.458042 -236.457268) (xy 337.442458 -236.503949) (xy 337.419587 -236.547526) (xy 337.390022 -236.58687)
			(xy 337.354529 -236.620962) (xy 337.314026 -236.648918) (xy 337.269564 -236.670016) (xy 337.222293 -236.683708)
			(xy 337.173438 -236.68964) (xy 337.124263 -236.687659) (xy 337.076044 -236.677815) (xy 337.030028 -236.660363)
			(xy 336.987407 -236.635756) (xy 336.949286 -236.604631) (xy 336.916651 -236.567794) (xy 336.890348 -236.526198)
			(xy 336.871057 -236.480922) (xy 336.85928 -236.433138) (xy 336.85532 -236.384084) (xy 336.526378 -236.384084)
			(xy 336.525883 -236.408691) (xy 336.517988 -236.457268) (xy 336.502404 -236.503949) (xy 336.479533 -236.547526)
			(xy 336.449968 -236.58687) (xy 336.414475 -236.620962) (xy 336.373972 -236.648918) (xy 336.32951 -236.670016)
			(xy 336.282239 -236.683708) (xy 336.233384 -236.68964) (xy 336.184209 -236.687659) (xy 336.13599 -236.677815)
			(xy 336.089974 -236.660363) (xy 336.047353 -236.635756) (xy 336.009232 -236.604631) (xy 335.976597 -236.567794)
			(xy 335.950294 -236.526198) (xy 335.931003 -236.480922) (xy 335.919226 -236.433138) (xy 335.915266 -236.384084)
			(xy 335.586324 -236.384084) (xy 335.585829 -236.408691) (xy 335.577934 -236.457268) (xy 335.56235 -236.503949)
			(xy 335.539479 -236.547526) (xy 335.509914 -236.58687) (xy 335.474421 -236.620962) (xy 335.433918 -236.648918)
			(xy 335.389456 -236.670016) (xy 335.342185 -236.683708) (xy 335.29333 -236.68964) (xy 335.244155 -236.687659)
			(xy 335.195936 -236.677815) (xy 335.14992 -236.660363) (xy 335.107299 -236.635756) (xy 335.069178 -236.604631)
			(xy 335.036543 -236.567794) (xy 335.01024 -236.526198) (xy 334.990949 -236.480922) (xy 334.979172 -236.433138)
			(xy 334.975212 -236.384084) (xy 334.646524 -236.384084) (xy 334.646029 -236.408691) (xy 334.638134 -236.457268)
			(xy 334.62255 -236.503949) (xy 334.599679 -236.547526) (xy 334.570114 -236.58687) (xy 334.534621 -236.620962)
			(xy 334.494118 -236.648918) (xy 334.449656 -236.670016) (xy 334.402385 -236.683708) (xy 334.35353 -236.68964)
			(xy 334.304355 -236.687659) (xy 334.256136 -236.677815) (xy 334.21012 -236.660363) (xy 334.167499 -236.635756)
			(xy 334.129378 -236.604631) (xy 334.096743 -236.567794) (xy 334.07044 -236.526198) (xy 334.051149 -236.480922)
			(xy 334.039372 -236.433138) (xy 334.035412 -236.384084) (xy 333.70647 -236.384084) (xy 333.705975 -236.408691)
			(xy 333.69808 -236.457268) (xy 333.682496 -236.503949) (xy 333.659625 -236.547526) (xy 333.63006 -236.58687)
			(xy 333.594567 -236.620962) (xy 333.554064 -236.648918) (xy 333.509602 -236.670016) (xy 333.462331 -236.683708)
			(xy 333.413476 -236.68964) (xy 333.364301 -236.687659) (xy 333.316082 -236.677815) (xy 333.270066 -236.660363)
			(xy 333.227445 -236.635756) (xy 333.189324 -236.604631) (xy 333.156689 -236.567794) (xy 333.130386 -236.526198)
			(xy 333.111095 -236.480922) (xy 333.099318 -236.433138) (xy 333.095358 -236.384084) (xy 332.766416 -236.384084)
			(xy 332.765921 -236.408691) (xy 332.758026 -236.457268) (xy 332.742442 -236.503949) (xy 332.719571 -236.547526)
			(xy 332.690006 -236.58687) (xy 332.654513 -236.620962) (xy 332.61401 -236.648918) (xy 332.569548 -236.670016)
			(xy 332.522277 -236.683708) (xy 332.473422 -236.68964) (xy 332.424247 -236.687659) (xy 332.376028 -236.677815)
			(xy 332.330012 -236.660363) (xy 332.287391 -236.635756) (xy 332.24927 -236.604631) (xy 332.216635 -236.567794)
			(xy 332.190332 -236.526198) (xy 332.171041 -236.480922) (xy 332.159264 -236.433138) (xy 332.155304 -236.384084)
			(xy 331.826071 -236.384084) (xy 331.826072 -236.409134) (xy 331.817906 -236.458535) (xy 331.801793 -236.505942)
			(xy 331.778165 -236.550088) (xy 331.747654 -236.589789) (xy 331.711076 -236.623982) (xy 331.669412 -236.651753)
			(xy 331.623776 -236.672357) (xy 331.575392 -236.685242) (xy 331.550518 -236.688122) (xy 331.550264 -236.688122)
			(xy 331.540612 -236.689138) (xy 331.532738 -236.692948) (xy 331.528477 -236.695151) (xy 331.520803 -236.700902)
			(xy 331.517498 -236.704378) (xy 331.47254 -236.753908) (xy 331.466481 -236.761078) (xy 331.459685 -236.778564)
			(xy 331.459332 -236.787944) (xy 331.459332 -237.19409) (xy 331.685404 -237.19409) (xy 331.689364 -237.145036)
			(xy 331.701141 -237.097252) (xy 331.720432 -237.051976) (xy 331.746735 -237.01038) (xy 331.77937 -236.973543)
			(xy 331.817491 -236.942418) (xy 331.860112 -236.917811) (xy 331.906128 -236.900359) (xy 331.954347 -236.890515)
			(xy 332.003522 -236.888534) (xy 332.052377 -236.894466) (xy 332.099648 -236.908158) (xy 332.14411 -236.929256)
			(xy 332.184613 -236.957212) (xy 332.220106 -236.991304) (xy 332.249671 -237.030648) (xy 332.272542 -237.074225)
			(xy 332.288126 -237.120906) (xy 332.296021 -237.169483) (xy 332.296516 -237.19409) (xy 332.625204 -237.19409)
			(xy 332.629164 -237.145036) (xy 332.640941 -237.097252) (xy 332.660232 -237.051976) (xy 332.686535 -237.01038)
			(xy 332.71917 -236.973543) (xy 332.757291 -236.942418) (xy 332.799912 -236.917811) (xy 332.845928 -236.900359)
			(xy 332.894147 -236.890515) (xy 332.943322 -236.888534) (xy 332.992177 -236.894466) (xy 333.039448 -236.908158)
			(xy 333.08391 -236.929256) (xy 333.124413 -236.957212) (xy 333.159906 -236.991304) (xy 333.189471 -237.030648)
			(xy 333.212342 -237.074225) (xy 333.227926 -237.120906) (xy 333.235821 -237.169483) (xy 333.236316 -237.19409)
			(xy 333.565258 -237.19409) (xy 333.569218 -237.145036) (xy 333.580995 -237.097252) (xy 333.600286 -237.051976)
			(xy 333.626589 -237.01038) (xy 333.659224 -236.973543) (xy 333.697345 -236.942418) (xy 333.739966 -236.917811)
			(xy 333.785982 -236.900359) (xy 333.834201 -236.890515) (xy 333.883376 -236.888534) (xy 333.932231 -236.894466)
			(xy 333.979502 -236.908158) (xy 334.023964 -236.929256) (xy 334.064467 -236.957212) (xy 334.09996 -236.991304)
			(xy 334.129525 -237.030648) (xy 334.152396 -237.074225) (xy 334.16798 -237.120906) (xy 334.175875 -237.169483)
			(xy 334.17637 -237.19409) (xy 335.445366 -237.19409) (xy 335.449326 -237.145036) (xy 335.461103 -237.097252)
			(xy 335.480394 -237.051976) (xy 335.506697 -237.01038) (xy 335.539332 -236.973543) (xy 335.577453 -236.942418)
			(xy 335.620074 -236.917811) (xy 335.66609 -236.900359) (xy 335.714309 -236.890515) (xy 335.763484 -236.888534)
			(xy 335.812339 -236.894466) (xy 335.85961 -236.908158) (xy 335.904072 -236.929256) (xy 335.944575 -236.957212)
			(xy 335.980068 -236.991304) (xy 336.009633 -237.030648) (xy 336.032504 -237.074225) (xy 336.048088 -237.120906)
			(xy 336.055983 -237.169483) (xy 336.056478 -237.19409) (xy 336.38542 -237.19409) (xy 336.38938 -237.145036)
			(xy 336.401157 -237.097252) (xy 336.420448 -237.051976) (xy 336.446751 -237.01038) (xy 336.479386 -236.973543)
			(xy 336.517507 -236.942418) (xy 336.560128 -236.917811) (xy 336.606144 -236.900359) (xy 336.654363 -236.890515)
			(xy 336.703538 -236.888534) (xy 336.752393 -236.894466) (xy 336.799664 -236.908158) (xy 336.844126 -236.929256)
			(xy 336.884629 -236.957212) (xy 336.920122 -236.991304) (xy 336.949687 -237.030648) (xy 336.972558 -237.074225)
			(xy 336.988142 -237.120906) (xy 336.996037 -237.169483) (xy 336.996532 -237.19409) (xy 337.32522 -237.19409)
			(xy 337.32918 -237.145036) (xy 337.340957 -237.097252) (xy 337.360248 -237.051976) (xy 337.386551 -237.01038)
			(xy 337.419186 -236.973543) (xy 337.457307 -236.942418) (xy 337.499928 -236.917811) (xy 337.545944 -236.900359)
			(xy 337.594163 -236.890515) (xy 337.643338 -236.888534) (xy 337.692193 -236.894466) (xy 337.739464 -236.908158)
			(xy 337.783926 -236.929256) (xy 337.824429 -236.957212) (xy 337.859922 -236.991304) (xy 337.889487 -237.030648)
			(xy 337.912358 -237.074225) (xy 337.927942 -237.120906) (xy 337.935837 -237.169483) (xy 337.936332 -237.19409)
			(xy 338.254843 -237.19409) (xy 338.258938 -237.143362) (xy 338.271117 -237.093948) (xy 338.291065 -237.047128)
			(xy 338.318266 -237.004114) (xy 338.352014 -236.96602) (xy 338.391436 -236.933833) (xy 338.43551 -236.908387)
			(xy 338.483096 -236.89034) (xy 338.53296 -236.88016) (xy 338.583812 -236.878111) (xy 338.634333 -236.884245)
			(xy 338.683217 -236.898405) (xy 338.729196 -236.920222) (xy 338.77108 -236.949132) (xy 338.807784 -236.984387)
			(xy 338.838357 -237.025073) (xy 338.862008 -237.070136) (xy 338.878124 -237.11841) (xy 338.886288 -237.168644)
			(xy 338.8868 -237.19409) (xy 339.205328 -237.19409) (xy 339.209288 -237.145036) (xy 339.221065 -237.097252)
			(xy 339.240356 -237.051976) (xy 339.266659 -237.01038) (xy 339.299294 -236.973543) (xy 339.337415 -236.942418)
			(xy 339.380036 -236.917811) (xy 339.426052 -236.900359) (xy 339.474271 -236.890515) (xy 339.523446 -236.888534)
			(xy 339.572301 -236.894466) (xy 339.619572 -236.908158) (xy 339.664034 -236.929256) (xy 339.704537 -236.957212)
			(xy 339.74003 -236.991304) (xy 339.769595 -237.030648) (xy 339.792466 -237.074225) (xy 339.80805 -237.120906)
			(xy 339.815945 -237.169483) (xy 339.81644 -237.19409) (xy 340.134951 -237.19409) (xy 340.139046 -237.143362)
			(xy 340.151225 -237.093948) (xy 340.171173 -237.047128) (xy 340.198374 -237.004114) (xy 340.232122 -236.96602)
			(xy 340.271544 -236.933833) (xy 340.315618 -236.908387) (xy 340.363204 -236.89034) (xy 340.413068 -236.88016)
			(xy 340.46392 -236.878111) (xy 340.514441 -236.884245) (xy 340.563325 -236.898405) (xy 340.609304 -236.920222)
			(xy 340.651188 -236.949132) (xy 340.687892 -236.984387) (xy 340.718465 -237.025073) (xy 340.742116 -237.070136)
			(xy 340.758232 -237.11841) (xy 340.766396 -237.168644) (xy 340.766908 -237.19409) (xy 342.014805 -237.19409)
			(xy 342.0189 -237.143362) (xy 342.031079 -237.093948) (xy 342.051027 -237.047128) (xy 342.078228 -237.004114)
			(xy 342.111976 -236.96602) (xy 342.151398 -236.933833) (xy 342.195472 -236.908387) (xy 342.243058 -236.89034)
			(xy 342.292922 -236.88016) (xy 342.343774 -236.878111) (xy 342.394295 -236.884245) (xy 342.443179 -236.898405)
			(xy 342.489158 -236.920222) (xy 342.531042 -236.949132) (xy 342.567746 -236.984387) (xy 342.598319 -237.025073)
			(xy 342.62197 -237.070136) (xy 342.638086 -237.11841) (xy 342.64625 -237.168644) (xy 342.646762 -237.19409)
			(xy 342.64625 -237.219536) (xy 342.638086 -237.26977) (xy 342.62197 -237.318044) (xy 342.598319 -237.363107)
			(xy 342.567746 -237.403793) (xy 342.531042 -237.439048) (xy 342.489158 -237.467958) (xy 342.443179 -237.489775)
			(xy 342.394295 -237.503935) (xy 342.343774 -237.510069) (xy 342.292922 -237.50802) (xy 342.243058 -237.49784)
			(xy 342.195472 -237.479793) (xy 342.151398 -237.454347) (xy 342.111976 -237.42216) (xy 342.078228 -237.384066)
			(xy 342.051027 -237.341052) (xy 342.031079 -237.294232) (xy 342.0189 -237.244818) (xy 342.014805 -237.19409)
			(xy 340.766908 -237.19409) (xy 340.766396 -237.219536) (xy 340.758232 -237.26977) (xy 340.742116 -237.318044)
			(xy 340.718465 -237.363107) (xy 340.687892 -237.403793) (xy 340.651188 -237.439048) (xy 340.609304 -237.467958)
			(xy 340.563325 -237.489775) (xy 340.514441 -237.503935) (xy 340.46392 -237.510069) (xy 340.413068 -237.50802)
			(xy 340.363204 -237.49784) (xy 340.315618 -237.479793) (xy 340.271544 -237.454347) (xy 340.232122 -237.42216)
			(xy 340.198374 -237.384066) (xy 340.171173 -237.341052) (xy 340.151225 -237.294232) (xy 340.139046 -237.244818)
			(xy 340.134951 -237.19409) (xy 339.81644 -237.19409) (xy 339.815945 -237.218697) (xy 339.80805 -237.267274)
			(xy 339.792466 -237.313955) (xy 339.769595 -237.357532) (xy 339.74003 -237.396876) (xy 339.704537 -237.430968)
			(xy 339.664034 -237.458924) (xy 339.619572 -237.480022) (xy 339.572301 -237.493714) (xy 339.523446 -237.499646)
			(xy 339.474271 -237.497665) (xy 339.426052 -237.487821) (xy 339.380036 -237.470369) (xy 339.337415 -237.445762)
			(xy 339.299294 -237.414637) (xy 339.266659 -237.3778) (xy 339.240356 -237.336204) (xy 339.221065 -237.290928)
			(xy 339.209288 -237.243144) (xy 339.205328 -237.19409) (xy 338.8868 -237.19409) (xy 338.886288 -237.219536)
			(xy 338.878124 -237.26977) (xy 338.862008 -237.318044) (xy 338.838357 -237.363107) (xy 338.807784 -237.403793)
			(xy 338.77108 -237.439048) (xy 338.729196 -237.467958) (xy 338.683217 -237.489775) (xy 338.634333 -237.503935)
			(xy 338.583812 -237.510069) (xy 338.53296 -237.50802) (xy 338.483096 -237.49784) (xy 338.43551 -237.479793)
			(xy 338.391436 -237.454347) (xy 338.352014 -237.42216) (xy 338.318266 -237.384066) (xy 338.291065 -237.341052)
			(xy 338.271117 -237.294232) (xy 338.258938 -237.244818) (xy 338.254843 -237.19409) (xy 337.936332 -237.19409)
			(xy 337.935837 -237.218697) (xy 337.927942 -237.267274) (xy 337.912358 -237.313955) (xy 337.889487 -237.357532)
			(xy 337.859922 -237.396876) (xy 337.824429 -237.430968) (xy 337.783926 -237.458924) (xy 337.739464 -237.480022)
			(xy 337.692193 -237.493714) (xy 337.643338 -237.499646) (xy 337.594163 -237.497665) (xy 337.545944 -237.487821)
			(xy 337.499928 -237.470369) (xy 337.457307 -237.445762) (xy 337.419186 -237.414637) (xy 337.386551 -237.3778)
			(xy 337.360248 -237.336204) (xy 337.340957 -237.290928) (xy 337.32918 -237.243144) (xy 337.32522 -237.19409)
			(xy 336.996532 -237.19409) (xy 336.996037 -237.218697) (xy 336.988142 -237.267274) (xy 336.972558 -237.313955)
			(xy 336.949687 -237.357532) (xy 336.920122 -237.396876) (xy 336.884629 -237.430968) (xy 336.844126 -237.458924)
			(xy 336.799664 -237.480022) (xy 336.752393 -237.493714) (xy 336.703538 -237.499646) (xy 336.654363 -237.497665)
			(xy 336.606144 -237.487821) (xy 336.560128 -237.470369) (xy 336.517507 -237.445762) (xy 336.479386 -237.414637)
			(xy 336.446751 -237.3778) (xy 336.420448 -237.336204) (xy 336.401157 -237.290928) (xy 336.38938 -237.243144)
			(xy 336.38542 -237.19409) (xy 336.056478 -237.19409) (xy 336.055983 -237.218697) (xy 336.048088 -237.267274)
			(xy 336.032504 -237.313955) (xy 336.009633 -237.357532) (xy 335.980068 -237.396876) (xy 335.944575 -237.430968)
			(xy 335.904072 -237.458924) (xy 335.85961 -237.480022) (xy 335.812339 -237.493714) (xy 335.763484 -237.499646)
			(xy 335.714309 -237.497665) (xy 335.66609 -237.487821) (xy 335.620074 -237.470369) (xy 335.577453 -237.445762)
			(xy 335.539332 -237.414637) (xy 335.506697 -237.3778) (xy 335.480394 -237.336204) (xy 335.461103 -237.290928)
			(xy 335.449326 -237.243144) (xy 335.445366 -237.19409) (xy 334.17637 -237.19409) (xy 334.175875 -237.218697)
			(xy 334.16798 -237.267274) (xy 334.152396 -237.313955) (xy 334.129525 -237.357532) (xy 334.09996 -237.396876)
			(xy 334.064467 -237.430968) (xy 334.023964 -237.458924) (xy 333.979502 -237.480022) (xy 333.932231 -237.493714)
			(xy 333.883376 -237.499646) (xy 333.834201 -237.497665) (xy 333.785982 -237.487821) (xy 333.739966 -237.470369)
			(xy 333.697345 -237.445762) (xy 333.659224 -237.414637) (xy 333.626589 -237.3778) (xy 333.600286 -237.336204)
			(xy 333.580995 -237.290928) (xy 333.569218 -237.243144) (xy 333.565258 -237.19409) (xy 333.236316 -237.19409)
			(xy 333.235821 -237.218697) (xy 333.227926 -237.267274) (xy 333.212342 -237.313955) (xy 333.189471 -237.357532)
			(xy 333.159906 -237.396876) (xy 333.124413 -237.430968) (xy 333.08391 -237.458924) (xy 333.039448 -237.480022)
			(xy 332.992177 -237.493714) (xy 332.943322 -237.499646) (xy 332.894147 -237.497665) (xy 332.845928 -237.487821)
			(xy 332.799912 -237.470369) (xy 332.757291 -237.445762) (xy 332.71917 -237.414637) (xy 332.686535 -237.3778)
			(xy 332.660232 -237.336204) (xy 332.640941 -237.290928) (xy 332.629164 -237.243144) (xy 332.625204 -237.19409)
			(xy 332.296516 -237.19409) (xy 332.296021 -237.218697) (xy 332.288126 -237.267274) (xy 332.272542 -237.313955)
			(xy 332.249671 -237.357532) (xy 332.220106 -237.396876) (xy 332.184613 -237.430968) (xy 332.14411 -237.458924)
			(xy 332.099648 -237.480022) (xy 332.052377 -237.493714) (xy 332.003522 -237.499646) (xy 331.954347 -237.497665)
			(xy 331.906128 -237.487821) (xy 331.860112 -237.470369) (xy 331.817491 -237.445762) (xy 331.77937 -237.414637)
			(xy 331.746735 -237.3778) (xy 331.720432 -237.336204) (xy 331.701141 -237.290928) (xy 331.689364 -237.243144)
			(xy 331.685404 -237.19409) (xy 331.459332 -237.19409) (xy 331.459332 -237.600236) (xy 331.459798 -237.609596)
			(xy 331.466557 -237.627061) (xy 331.47254 -237.634272) (xy 331.517498 -237.683802) (xy 331.52081 -237.68727)
			(xy 331.52848 -237.693026) (xy 331.532738 -237.695232) (xy 331.540612 -237.699042) (xy 331.550264 -237.700058)
			(xy 331.550518 -237.700058) (xy 331.575388 -237.702969) (xy 331.623771 -237.715854) (xy 331.669404 -237.736457)
			(xy 331.711067 -237.764226) (xy 331.747643 -237.798418) (xy 331.778154 -237.838117) (xy 331.801782 -237.882261)
			(xy 331.817894 -237.929666) (xy 331.82606 -237.979065) (xy 331.82606 -238.004096) (xy 332.155304 -238.004096)
			(xy 332.159264 -237.955042) (xy 332.171041 -237.907258) (xy 332.190332 -237.861982) (xy 332.216635 -237.820386)
			(xy 332.24927 -237.783549) (xy 332.287391 -237.752424) (xy 332.330012 -237.727817) (xy 332.376028 -237.710365)
			(xy 332.424247 -237.700521) (xy 332.473422 -237.69854) (xy 332.522277 -237.704472) (xy 332.569548 -237.718164)
			(xy 332.61401 -237.739262) (xy 332.654513 -237.767218) (xy 332.690006 -237.80131) (xy 332.719571 -237.840654)
			(xy 332.742442 -237.884231) (xy 332.758026 -237.930912) (xy 332.765921 -237.979489) (xy 332.766416 -238.004096)
			(xy 333.095358 -238.004096) (xy 333.099318 -237.955042) (xy 333.111095 -237.907258) (xy 333.130386 -237.861982)
			(xy 333.156689 -237.820386) (xy 333.189324 -237.783549) (xy 333.227445 -237.752424) (xy 333.270066 -237.727817)
			(xy 333.316082 -237.710365) (xy 333.364301 -237.700521) (xy 333.413476 -237.69854) (xy 333.462331 -237.704472)
			(xy 333.509602 -237.718164) (xy 333.554064 -237.739262) (xy 333.594567 -237.767218) (xy 333.63006 -237.80131)
			(xy 333.659625 -237.840654) (xy 333.682496 -237.884231) (xy 333.69808 -237.930912) (xy 333.705975 -237.979489)
			(xy 333.70647 -238.004096) (xy 334.035412 -238.004096) (xy 334.039372 -237.955042) (xy 334.051149 -237.907258)
			(xy 334.07044 -237.861982) (xy 334.096743 -237.820386) (xy 334.129378 -237.783549) (xy 334.167499 -237.752424)
			(xy 334.21012 -237.727817) (xy 334.256136 -237.710365) (xy 334.304355 -237.700521) (xy 334.35353 -237.69854)
			(xy 334.402385 -237.704472) (xy 334.449656 -237.718164) (xy 334.494118 -237.739262) (xy 334.534621 -237.767218)
			(xy 334.570114 -237.80131) (xy 334.599679 -237.840654) (xy 334.62255 -237.884231) (xy 334.638134 -237.930912)
			(xy 334.646029 -237.979489) (xy 334.646524 -238.004096) (xy 334.975212 -238.004096) (xy 334.979172 -237.955042)
			(xy 334.990949 -237.907258) (xy 335.01024 -237.861982) (xy 335.036543 -237.820386) (xy 335.069178 -237.783549)
			(xy 335.107299 -237.752424) (xy 335.14992 -237.727817) (xy 335.195936 -237.710365) (xy 335.244155 -237.700521)
			(xy 335.29333 -237.69854) (xy 335.342185 -237.704472) (xy 335.389456 -237.718164) (xy 335.433918 -237.739262)
			(xy 335.474421 -237.767218) (xy 335.509914 -237.80131) (xy 335.539479 -237.840654) (xy 335.56235 -237.884231)
			(xy 335.577934 -237.930912) (xy 335.585829 -237.979489) (xy 335.586324 -238.004096) (xy 335.915266 -238.004096)
			(xy 335.919226 -237.955042) (xy 335.931003 -237.907258) (xy 335.950294 -237.861982) (xy 335.976597 -237.820386)
			(xy 336.009232 -237.783549) (xy 336.047353 -237.752424) (xy 336.089974 -237.727817) (xy 336.13599 -237.710365)
			(xy 336.184209 -237.700521) (xy 336.233384 -237.69854) (xy 336.282239 -237.704472) (xy 336.32951 -237.718164)
			(xy 336.373972 -237.739262) (xy 336.414475 -237.767218) (xy 336.449968 -237.80131) (xy 336.479533 -237.840654)
			(xy 336.502404 -237.884231) (xy 336.517988 -237.930912) (xy 336.525883 -237.979489) (xy 336.526378 -238.004096)
			(xy 336.85532 -238.004096) (xy 336.85928 -237.955042) (xy 336.871057 -237.907258) (xy 336.890348 -237.861982)
			(xy 336.916651 -237.820386) (xy 336.949286 -237.783549) (xy 336.987407 -237.752424) (xy 337.030028 -237.727817)
			(xy 337.076044 -237.710365) (xy 337.124263 -237.700521) (xy 337.173438 -237.69854) (xy 337.222293 -237.704472)
			(xy 337.269564 -237.718164) (xy 337.314026 -237.739262) (xy 337.354529 -237.767218) (xy 337.390022 -237.80131)
			(xy 337.419587 -237.840654) (xy 337.442458 -237.884231) (xy 337.458042 -237.930912) (xy 337.465937 -237.979489)
			(xy 337.466432 -238.004096) (xy 337.795374 -238.004096) (xy 337.799334 -237.955042) (xy 337.811111 -237.907258)
			(xy 337.830402 -237.861982) (xy 337.856705 -237.820386) (xy 337.88934 -237.783549) (xy 337.927461 -237.752424)
			(xy 337.970082 -237.727817) (xy 338.016098 -237.710365) (xy 338.064317 -237.700521) (xy 338.113492 -237.69854)
			(xy 338.162347 -237.704472) (xy 338.209618 -237.718164) (xy 338.25408 -237.739262) (xy 338.294583 -237.767218)
			(xy 338.330076 -237.80131) (xy 338.359641 -237.840654) (xy 338.382512 -237.884231) (xy 338.398096 -237.930912)
			(xy 338.405991 -237.979489) (xy 338.406486 -238.004096) (xy 338.724743 -238.004096) (xy 338.728838 -237.953368)
			(xy 338.741017 -237.903954) (xy 338.760965 -237.857134) (xy 338.788166 -237.81412) (xy 338.821914 -237.776026)
			(xy 338.861336 -237.743839) (xy 338.90541 -237.718393) (xy 338.952996 -237.700346) (xy 339.00286 -237.690166)
			(xy 339.053712 -237.688117) (xy 339.104233 -237.694251) (xy 339.153117 -237.708411) (xy 339.199096 -237.730228)
			(xy 339.24098 -237.759138) (xy 339.277684 -237.794393) (xy 339.308257 -237.835079) (xy 339.331908 -237.880142)
			(xy 339.348024 -237.928416) (xy 339.356188 -237.97865) (xy 339.3567 -238.004096) (xy 339.664797 -238.004096)
			(xy 339.668892 -237.953368) (xy 339.681071 -237.903954) (xy 339.701019 -237.857134) (xy 339.72822 -237.81412)
			(xy 339.761968 -237.776026) (xy 339.80139 -237.743839) (xy 339.845464 -237.718393) (xy 339.89305 -237.700346)
			(xy 339.942914 -237.690166) (xy 339.993766 -237.688117) (xy 340.044287 -237.694251) (xy 340.093171 -237.708411)
			(xy 340.13915 -237.730228) (xy 340.181034 -237.759138) (xy 340.217738 -237.794393) (xy 340.248311 -237.835079)
			(xy 340.271962 -237.880142) (xy 340.288078 -237.928416) (xy 340.296242 -237.97865) (xy 340.296754 -238.004096)
			(xy 340.615282 -238.004096) (xy 340.619242 -237.955042) (xy 340.631019 -237.907258) (xy 340.65031 -237.861982)
			(xy 340.676613 -237.820386) (xy 340.709248 -237.783549) (xy 340.747369 -237.752424) (xy 340.78999 -237.727817)
			(xy 340.836006 -237.710365) (xy 340.884225 -237.700521) (xy 340.9334 -237.69854) (xy 340.982255 -237.704472)
			(xy 341.029526 -237.718164) (xy 341.073988 -237.739262) (xy 341.114491 -237.767218) (xy 341.149984 -237.80131)
			(xy 341.179549 -237.840654) (xy 341.20242 -237.884231) (xy 341.218004 -237.930912) (xy 341.225899 -237.979489)
			(xy 341.226394 -238.004096) (xy 341.544905 -238.004096) (xy 341.549 -237.953368) (xy 341.561179 -237.903954)
			(xy 341.581127 -237.857134) (xy 341.608328 -237.81412) (xy 341.642076 -237.776026) (xy 341.681498 -237.743839)
			(xy 341.725572 -237.718393) (xy 341.773158 -237.700346) (xy 341.823022 -237.690166) (xy 341.873874 -237.688117)
			(xy 341.924395 -237.694251) (xy 341.973279 -237.708411) (xy 342.019258 -237.730228) (xy 342.061142 -237.759138)
			(xy 342.097846 -237.794393) (xy 342.128419 -237.835079) (xy 342.15207 -237.880142) (xy 342.168186 -237.928416)
			(xy 342.17635 -237.97865) (xy 342.176862 -238.004096) (xy 342.49539 -238.004096) (xy 342.49935 -237.955042)
			(xy 342.511127 -237.907258) (xy 342.530418 -237.861982) (xy 342.556721 -237.820386) (xy 342.589356 -237.783549)
			(xy 342.627477 -237.752424) (xy 342.670098 -237.727817) (xy 342.716114 -237.710365) (xy 342.764333 -237.700521)
			(xy 342.813508 -237.69854) (xy 342.862363 -237.704472) (xy 342.909634 -237.718164) (xy 342.954096 -237.739262)
			(xy 342.994599 -237.767218) (xy 343.030092 -237.80131) (xy 343.059657 -237.840654) (xy 343.082528 -237.884231)
			(xy 343.098112 -237.930912) (xy 343.106007 -237.979489) (xy 343.106502 -238.004096) (xy 343.106007 -238.028703)
			(xy 343.098112 -238.07728) (xy 343.082528 -238.123961) (xy 343.059657 -238.167538) (xy 343.030092 -238.206882)
			(xy 342.994599 -238.240974) (xy 342.954096 -238.26893) (xy 342.909634 -238.290028) (xy 342.862363 -238.30372)
			(xy 342.813508 -238.309652) (xy 342.764333 -238.307671) (xy 342.716114 -238.297827) (xy 342.670098 -238.280375)
			(xy 342.627477 -238.255768) (xy 342.589356 -238.224643) (xy 342.556721 -238.187806) (xy 342.530418 -238.14621)
			(xy 342.511127 -238.100934) (xy 342.49935 -238.05315) (xy 342.49539 -238.004096) (xy 342.176862 -238.004096)
			(xy 342.17635 -238.029542) (xy 342.168186 -238.079776) (xy 342.15207 -238.12805) (xy 342.128419 -238.173113)
			(xy 342.097846 -238.213799) (xy 342.061142 -238.249054) (xy 342.019258 -238.277964) (xy 341.973279 -238.299781)
			(xy 341.924395 -238.313941) (xy 341.873874 -238.320075) (xy 341.823022 -238.318026) (xy 341.773158 -238.307846)
			(xy 341.725572 -238.289799) (xy 341.681498 -238.264353) (xy 341.642076 -238.232166) (xy 341.608328 -238.194072)
			(xy 341.581127 -238.151058) (xy 341.561179 -238.104238) (xy 341.549 -238.054824) (xy 341.544905 -238.004096)
			(xy 341.226394 -238.004096) (xy 341.225899 -238.028703) (xy 341.218004 -238.07728) (xy 341.20242 -238.123961)
			(xy 341.179549 -238.167538) (xy 341.149984 -238.206882) (xy 341.114491 -238.240974) (xy 341.073988 -238.26893)
			(xy 341.029526 -238.290028) (xy 340.982255 -238.30372) (xy 340.9334 -238.309652) (xy 340.884225 -238.307671)
			(xy 340.836006 -238.297827) (xy 340.78999 -238.280375) (xy 340.747369 -238.255768) (xy 340.709248 -238.224643)
			(xy 340.676613 -238.187806) (xy 340.65031 -238.14621) (xy 340.631019 -238.100934) (xy 340.619242 -238.05315)
			(xy 340.615282 -238.004096) (xy 340.296754 -238.004096) (xy 340.296242 -238.029542) (xy 340.288078 -238.079776)
			(xy 340.271962 -238.12805) (xy 340.248311 -238.173113) (xy 340.217738 -238.213799) (xy 340.181034 -238.249054)
			(xy 340.13915 -238.277964) (xy 340.093171 -238.299781) (xy 340.044287 -238.313941) (xy 339.993766 -238.320075)
			(xy 339.942914 -238.318026) (xy 339.89305 -238.307846) (xy 339.845464 -238.289799) (xy 339.80139 -238.264353)
			(xy 339.761968 -238.232166) (xy 339.72822 -238.194072) (xy 339.701019 -238.151058) (xy 339.681071 -238.104238)
			(xy 339.668892 -238.054824) (xy 339.664797 -238.004096) (xy 339.3567 -238.004096) (xy 339.356188 -238.029542)
			(xy 339.348024 -238.079776) (xy 339.331908 -238.12805) (xy 339.308257 -238.173113) (xy 339.277684 -238.213799)
			(xy 339.24098 -238.249054) (xy 339.199096 -238.277964) (xy 339.153117 -238.299781) (xy 339.104233 -238.313941)
			(xy 339.053712 -238.320075) (xy 339.00286 -238.318026) (xy 338.952996 -238.307846) (xy 338.90541 -238.289799)
			(xy 338.861336 -238.264353) (xy 338.821914 -238.232166) (xy 338.788166 -238.194072) (xy 338.760965 -238.151058)
			(xy 338.741017 -238.104238) (xy 338.728838 -238.054824) (xy 338.724743 -238.004096) (xy 338.406486 -238.004096)
			(xy 338.405991 -238.028703) (xy 338.398096 -238.07728) (xy 338.382512 -238.123961) (xy 338.359641 -238.167538)
			(xy 338.330076 -238.206882) (xy 338.294583 -238.240974) (xy 338.25408 -238.26893) (xy 338.209618 -238.290028)
			(xy 338.162347 -238.30372) (xy 338.113492 -238.309652) (xy 338.064317 -238.307671) (xy 338.016098 -238.297827)
			(xy 337.970082 -238.280375) (xy 337.927461 -238.255768) (xy 337.88934 -238.224643) (xy 337.856705 -238.187806)
			(xy 337.830402 -238.14621) (xy 337.811111 -238.100934) (xy 337.799334 -238.05315) (xy 337.795374 -238.004096)
			(xy 337.466432 -238.004096) (xy 337.465937 -238.028703) (xy 337.458042 -238.07728) (xy 337.442458 -238.123961)
			(xy 337.419587 -238.167538) (xy 337.390022 -238.206882) (xy 337.354529 -238.240974) (xy 337.314026 -238.26893)
			(xy 337.269564 -238.290028) (xy 337.222293 -238.30372) (xy 337.173438 -238.309652) (xy 337.124263 -238.307671)
			(xy 337.076044 -238.297827) (xy 337.030028 -238.280375) (xy 336.987407 -238.255768) (xy 336.949286 -238.224643)
			(xy 336.916651 -238.187806) (xy 336.890348 -238.14621) (xy 336.871057 -238.100934) (xy 336.85928 -238.05315)
			(xy 336.85532 -238.004096) (xy 336.526378 -238.004096) (xy 336.525883 -238.028703) (xy 336.517988 -238.07728)
			(xy 336.502404 -238.123961) (xy 336.479533 -238.167538) (xy 336.449968 -238.206882) (xy 336.414475 -238.240974)
			(xy 336.373972 -238.26893) (xy 336.32951 -238.290028) (xy 336.282239 -238.30372) (xy 336.233384 -238.309652)
			(xy 336.184209 -238.307671) (xy 336.13599 -238.297827) (xy 336.089974 -238.280375) (xy 336.047353 -238.255768)
			(xy 336.009232 -238.224643) (xy 335.976597 -238.187806) (xy 335.950294 -238.14621) (xy 335.931003 -238.100934)
			(xy 335.919226 -238.05315) (xy 335.915266 -238.004096) (xy 335.586324 -238.004096) (xy 335.585829 -238.028703)
			(xy 335.577934 -238.07728) (xy 335.56235 -238.123961) (xy 335.539479 -238.167538) (xy 335.509914 -238.206882)
			(xy 335.474421 -238.240974) (xy 335.433918 -238.26893) (xy 335.389456 -238.290028) (xy 335.342185 -238.30372)
			(xy 335.29333 -238.309652) (xy 335.244155 -238.307671) (xy 335.195936 -238.297827) (xy 335.14992 -238.280375)
			(xy 335.107299 -238.255768) (xy 335.069178 -238.224643) (xy 335.036543 -238.187806) (xy 335.01024 -238.14621)
			(xy 334.990949 -238.100934) (xy 334.979172 -238.05315) (xy 334.975212 -238.004096) (xy 334.646524 -238.004096)
			(xy 334.646029 -238.028703) (xy 334.638134 -238.07728) (xy 334.62255 -238.123961) (xy 334.599679 -238.167538)
			(xy 334.570114 -238.206882) (xy 334.534621 -238.240974) (xy 334.494118 -238.26893) (xy 334.449656 -238.290028)
			(xy 334.402385 -238.30372) (xy 334.35353 -238.309652) (xy 334.304355 -238.307671) (xy 334.256136 -238.297827)
			(xy 334.21012 -238.280375) (xy 334.167499 -238.255768) (xy 334.129378 -238.224643) (xy 334.096743 -238.187806)
			(xy 334.07044 -238.14621) (xy 334.051149 -238.100934) (xy 334.039372 -238.05315) (xy 334.035412 -238.004096)
			(xy 333.70647 -238.004096) (xy 333.705975 -238.028703) (xy 333.69808 -238.07728) (xy 333.682496 -238.123961)
			(xy 333.659625 -238.167538) (xy 333.63006 -238.206882) (xy 333.594567 -238.240974) (xy 333.554064 -238.26893)
			(xy 333.509602 -238.290028) (xy 333.462331 -238.30372) (xy 333.413476 -238.309652) (xy 333.364301 -238.307671)
			(xy 333.316082 -238.297827) (xy 333.270066 -238.280375) (xy 333.227445 -238.255768) (xy 333.189324 -238.224643)
			(xy 333.156689 -238.187806) (xy 333.130386 -238.14621) (xy 333.111095 -238.100934) (xy 333.099318 -238.05315)
			(xy 333.095358 -238.004096) (xy 332.766416 -238.004096) (xy 332.765921 -238.028703) (xy 332.758026 -238.07728)
			(xy 332.742442 -238.123961) (xy 332.719571 -238.167538) (xy 332.690006 -238.206882) (xy 332.654513 -238.240974)
			(xy 332.61401 -238.26893) (xy 332.569548 -238.290028) (xy 332.522277 -238.30372) (xy 332.473422 -238.309652)
			(xy 332.424247 -238.307671) (xy 332.376028 -238.297827) (xy 332.330012 -238.280375) (xy 332.287391 -238.255768)
			(xy 332.24927 -238.224643) (xy 332.216635 -238.187806) (xy 332.190332 -238.14621) (xy 332.171041 -238.100934)
			(xy 332.159264 -238.05315) (xy 332.155304 -238.004096) (xy 331.82606 -238.004096) (xy 331.82606 -238.029134)
			(xy 331.817894 -238.078533) (xy 331.801782 -238.125939) (xy 331.778154 -238.170082) (xy 331.747644 -238.209782)
			(xy 331.711068 -238.243974) (xy 331.669405 -238.271743) (xy 331.623771 -238.292346) (xy 331.575389 -238.305231)
			(xy 331.550518 -238.308134) (xy 331.550264 -238.308134) (xy 331.540612 -238.30915) (xy 331.532738 -238.31296)
			(xy 331.528478 -238.315163) (xy 331.520804 -238.320916) (xy 331.517498 -238.32439) (xy 331.47254 -238.37392)
			(xy 331.466482 -238.381091) (xy 331.459691 -238.398576) (xy 331.459332 -238.407956) (xy 331.459332 -238.814102)
			(xy 331.685404 -238.814102) (xy 331.689364 -238.765048) (xy 331.701141 -238.717264) (xy 331.720432 -238.671988)
			(xy 331.746735 -238.630392) (xy 331.77937 -238.593555) (xy 331.817491 -238.56243) (xy 331.860112 -238.537823)
			(xy 331.906128 -238.520371) (xy 331.954347 -238.510527) (xy 332.003522 -238.508546) (xy 332.052377 -238.514478)
			(xy 332.099648 -238.52817) (xy 332.14411 -238.549268) (xy 332.184613 -238.577224) (xy 332.220106 -238.611316)
			(xy 332.249671 -238.65066) (xy 332.272542 -238.694237) (xy 332.288126 -238.740918) (xy 332.296021 -238.789495)
			(xy 332.296516 -238.814102) (xy 332.625204 -238.814102) (xy 332.629164 -238.765048) (xy 332.640941 -238.717264)
			(xy 332.660232 -238.671988) (xy 332.686535 -238.630392) (xy 332.71917 -238.593555) (xy 332.757291 -238.56243)
			(xy 332.799912 -238.537823) (xy 332.845928 -238.520371) (xy 332.894147 -238.510527) (xy 332.943322 -238.508546)
			(xy 332.992177 -238.514478) (xy 333.039448 -238.52817) (xy 333.08391 -238.549268) (xy 333.124413 -238.577224)
			(xy 333.159906 -238.611316) (xy 333.189471 -238.65066) (xy 333.212342 -238.694237) (xy 333.227926 -238.740918)
			(xy 333.235821 -238.789495) (xy 333.236316 -238.814102) (xy 333.565258 -238.814102) (xy 333.569218 -238.765048)
			(xy 333.580995 -238.717264) (xy 333.600286 -238.671988) (xy 333.626589 -238.630392) (xy 333.659224 -238.593555)
			(xy 333.697345 -238.56243) (xy 333.739966 -238.537823) (xy 333.785982 -238.520371) (xy 333.834201 -238.510527)
			(xy 333.883376 -238.508546) (xy 333.932231 -238.514478) (xy 333.979502 -238.52817) (xy 334.023964 -238.549268)
			(xy 334.064467 -238.577224) (xy 334.09996 -238.611316) (xy 334.129525 -238.65066) (xy 334.152396 -238.694237)
			(xy 334.16798 -238.740918) (xy 334.175875 -238.789495) (xy 334.17637 -238.814102) (xy 334.505312 -238.814102)
			(xy 334.509272 -238.765048) (xy 334.521049 -238.717264) (xy 334.54034 -238.671988) (xy 334.566643 -238.630392)
			(xy 334.599278 -238.593555) (xy 334.637399 -238.56243) (xy 334.68002 -238.537823) (xy 334.726036 -238.520371)
			(xy 334.774255 -238.510527) (xy 334.82343 -238.508546) (xy 334.872285 -238.514478) (xy 334.919556 -238.52817)
			(xy 334.964018 -238.549268) (xy 335.004521 -238.577224) (xy 335.040014 -238.611316) (xy 335.069579 -238.65066)
			(xy 335.09245 -238.694237) (xy 335.108034 -238.740918) (xy 335.115929 -238.789495) (xy 335.116424 -238.814102)
			(xy 335.445366 -238.814102) (xy 335.449326 -238.765048) (xy 335.461103 -238.717264) (xy 335.480394 -238.671988)
			(xy 335.506697 -238.630392) (xy 335.539332 -238.593555) (xy 335.577453 -238.56243) (xy 335.620074 -238.537823)
			(xy 335.66609 -238.520371) (xy 335.714309 -238.510527) (xy 335.763484 -238.508546) (xy 335.812339 -238.514478)
			(xy 335.85961 -238.52817) (xy 335.904072 -238.549268) (xy 335.944575 -238.577224) (xy 335.980068 -238.611316)
			(xy 336.009633 -238.65066) (xy 336.032504 -238.694237) (xy 336.048088 -238.740918) (xy 336.055983 -238.789495)
			(xy 336.056478 -238.814102) (xy 336.38542 -238.814102) (xy 336.38938 -238.765048) (xy 336.401157 -238.717264)
			(xy 336.420448 -238.671988) (xy 336.446751 -238.630392) (xy 336.479386 -238.593555) (xy 336.517507 -238.56243)
			(xy 336.560128 -238.537823) (xy 336.606144 -238.520371) (xy 336.654363 -238.510527) (xy 336.703538 -238.508546)
			(xy 336.752393 -238.514478) (xy 336.799664 -238.52817) (xy 336.844126 -238.549268) (xy 336.884629 -238.577224)
			(xy 336.920122 -238.611316) (xy 336.949687 -238.65066) (xy 336.972558 -238.694237) (xy 336.988142 -238.740918)
			(xy 336.996037 -238.789495) (xy 336.996532 -238.814102) (xy 337.32522 -238.814102) (xy 337.32918 -238.765048)
			(xy 337.340957 -238.717264) (xy 337.360248 -238.671988) (xy 337.386551 -238.630392) (xy 337.419186 -238.593555)
			(xy 337.457307 -238.56243) (xy 337.499928 -238.537823) (xy 337.545944 -238.520371) (xy 337.594163 -238.510527)
			(xy 337.643338 -238.508546) (xy 337.692193 -238.514478) (xy 337.739464 -238.52817) (xy 337.783926 -238.549268)
			(xy 337.824429 -238.577224) (xy 337.859922 -238.611316) (xy 337.889487 -238.65066) (xy 337.912358 -238.694237)
			(xy 337.927942 -238.740918) (xy 337.935837 -238.789495) (xy 337.936332 -238.814102) (xy 338.254843 -238.814102)
			(xy 338.258938 -238.763374) (xy 338.271117 -238.71396) (xy 338.291065 -238.66714) (xy 338.318266 -238.624126)
			(xy 338.352014 -238.586032) (xy 338.391436 -238.553845) (xy 338.43551 -238.528399) (xy 338.483096 -238.510352)
			(xy 338.53296 -238.500172) (xy 338.583812 -238.498123) (xy 338.634333 -238.504257) (xy 338.683217 -238.518417)
			(xy 338.729196 -238.540234) (xy 338.77108 -238.569144) (xy 338.807784 -238.604399) (xy 338.838357 -238.645085)
			(xy 338.862008 -238.690148) (xy 338.878124 -238.738422) (xy 338.886288 -238.788656) (xy 338.8868 -238.814102)
			(xy 339.205328 -238.814102) (xy 339.209288 -238.765048) (xy 339.221065 -238.717264) (xy 339.240356 -238.671988)
			(xy 339.266659 -238.630392) (xy 339.299294 -238.593555) (xy 339.337415 -238.56243) (xy 339.380036 -238.537823)
			(xy 339.426052 -238.520371) (xy 339.474271 -238.510527) (xy 339.523446 -238.508546) (xy 339.572301 -238.514478)
			(xy 339.619572 -238.52817) (xy 339.664034 -238.549268) (xy 339.704537 -238.577224) (xy 339.74003 -238.611316)
			(xy 339.769595 -238.65066) (xy 339.792466 -238.694237) (xy 339.80805 -238.740918) (xy 339.815945 -238.789495)
			(xy 339.81644 -238.814102) (xy 340.134951 -238.814102) (xy 340.139046 -238.763374) (xy 340.151225 -238.71396)
			(xy 340.171173 -238.66714) (xy 340.198374 -238.624126) (xy 340.232122 -238.586032) (xy 340.271544 -238.553845)
			(xy 340.315618 -238.528399) (xy 340.363204 -238.510352) (xy 340.413068 -238.500172) (xy 340.46392 -238.498123)
			(xy 340.514441 -238.504257) (xy 340.563325 -238.518417) (xy 340.609304 -238.540234) (xy 340.651188 -238.569144)
			(xy 340.687892 -238.604399) (xy 340.718465 -238.645085) (xy 340.742116 -238.690148) (xy 340.758232 -238.738422)
			(xy 340.766396 -238.788656) (xy 340.766908 -238.814102) (xy 341.085182 -238.814102) (xy 341.089142 -238.765048)
			(xy 341.100919 -238.717264) (xy 341.12021 -238.671988) (xy 341.146513 -238.630392) (xy 341.179148 -238.593555)
			(xy 341.217269 -238.56243) (xy 341.25989 -238.537823) (xy 341.305906 -238.520371) (xy 341.354125 -238.510527)
			(xy 341.4033 -238.508546) (xy 341.452155 -238.514478) (xy 341.499426 -238.52817) (xy 341.543888 -238.549268)
			(xy 341.584391 -238.577224) (xy 341.619884 -238.611316) (xy 341.649449 -238.65066) (xy 341.67232 -238.694237)
			(xy 341.687904 -238.740918) (xy 341.695799 -238.789495) (xy 341.696294 -238.814102) (xy 342.014805 -238.814102)
			(xy 342.0189 -238.763374) (xy 342.031079 -238.71396) (xy 342.051027 -238.66714) (xy 342.078228 -238.624126)
			(xy 342.111976 -238.586032) (xy 342.151398 -238.553845) (xy 342.195472 -238.528399) (xy 342.243058 -238.510352)
			(xy 342.292922 -238.500172) (xy 342.343774 -238.498123) (xy 342.394295 -238.504257) (xy 342.443179 -238.518417)
			(xy 342.489158 -238.540234) (xy 342.531042 -238.569144) (xy 342.567746 -238.604399) (xy 342.598319 -238.645085)
			(xy 342.62197 -238.690148) (xy 342.638086 -238.738422) (xy 342.64625 -238.788656) (xy 342.646762 -238.814102)
			(xy 342.64625 -238.839548) (xy 342.638086 -238.889782) (xy 342.62197 -238.938056) (xy 342.598319 -238.983119)
			(xy 342.567746 -239.023805) (xy 342.531042 -239.05906) (xy 342.489158 -239.08797) (xy 342.443179 -239.109787)
			(xy 342.394295 -239.123947) (xy 342.343774 -239.130081) (xy 342.292922 -239.128032) (xy 342.243058 -239.117852)
			(xy 342.195472 -239.099805) (xy 342.151398 -239.074359) (xy 342.111976 -239.042172) (xy 342.078228 -239.004078)
			(xy 342.051027 -238.961064) (xy 342.031079 -238.914244) (xy 342.0189 -238.86483) (xy 342.014805 -238.814102)
			(xy 341.696294 -238.814102) (xy 341.695799 -238.838709) (xy 341.687904 -238.887286) (xy 341.67232 -238.933967)
			(xy 341.649449 -238.977544) (xy 341.619884 -239.016888) (xy 341.584391 -239.05098) (xy 341.543888 -239.078936)
			(xy 341.499426 -239.100034) (xy 341.452155 -239.113726) (xy 341.4033 -239.119658) (xy 341.354125 -239.117677)
			(xy 341.305906 -239.107833) (xy 341.25989 -239.090381) (xy 341.217269 -239.065774) (xy 341.179148 -239.034649)
			(xy 341.146513 -238.997812) (xy 341.12021 -238.956216) (xy 341.100919 -238.91094) (xy 341.089142 -238.863156)
			(xy 341.085182 -238.814102) (xy 340.766908 -238.814102) (xy 340.766396 -238.839548) (xy 340.758232 -238.889782)
			(xy 340.742116 -238.938056) (xy 340.718465 -238.983119) (xy 340.687892 -239.023805) (xy 340.651188 -239.05906)
			(xy 340.609304 -239.08797) (xy 340.563325 -239.109787) (xy 340.514441 -239.123947) (xy 340.46392 -239.130081)
			(xy 340.413068 -239.128032) (xy 340.363204 -239.117852) (xy 340.315618 -239.099805) (xy 340.271544 -239.074359)
			(xy 340.232122 -239.042172) (xy 340.198374 -239.004078) (xy 340.171173 -238.961064) (xy 340.151225 -238.914244)
			(xy 340.139046 -238.86483) (xy 340.134951 -238.814102) (xy 339.81644 -238.814102) (xy 339.815945 -238.838709)
			(xy 339.80805 -238.887286) (xy 339.792466 -238.933967) (xy 339.769595 -238.977544) (xy 339.74003 -239.016888)
			(xy 339.704537 -239.05098) (xy 339.664034 -239.078936) (xy 339.619572 -239.100034) (xy 339.572301 -239.113726)
			(xy 339.523446 -239.119658) (xy 339.474271 -239.117677) (xy 339.426052 -239.107833) (xy 339.380036 -239.090381)
			(xy 339.337415 -239.065774) (xy 339.299294 -239.034649) (xy 339.266659 -238.997812) (xy 339.240356 -238.956216)
			(xy 339.221065 -238.91094) (xy 339.209288 -238.863156) (xy 339.205328 -238.814102) (xy 338.8868 -238.814102)
			(xy 338.886288 -238.839548) (xy 338.878124 -238.889782) (xy 338.862008 -238.938056) (xy 338.838357 -238.983119)
			(xy 338.807784 -239.023805) (xy 338.77108 -239.05906) (xy 338.729196 -239.08797) (xy 338.683217 -239.109787)
			(xy 338.634333 -239.123947) (xy 338.583812 -239.130081) (xy 338.53296 -239.128032) (xy 338.483096 -239.117852)
			(xy 338.43551 -239.099805) (xy 338.391436 -239.074359) (xy 338.352014 -239.042172) (xy 338.318266 -239.004078)
			(xy 338.291065 -238.961064) (xy 338.271117 -238.914244) (xy 338.258938 -238.86483) (xy 338.254843 -238.814102)
			(xy 337.936332 -238.814102) (xy 337.935837 -238.838709) (xy 337.927942 -238.887286) (xy 337.912358 -238.933967)
			(xy 337.889487 -238.977544) (xy 337.859922 -239.016888) (xy 337.824429 -239.05098) (xy 337.783926 -239.078936)
			(xy 337.739464 -239.100034) (xy 337.692193 -239.113726) (xy 337.643338 -239.119658) (xy 337.594163 -239.117677)
			(xy 337.545944 -239.107833) (xy 337.499928 -239.090381) (xy 337.457307 -239.065774) (xy 337.419186 -239.034649)
			(xy 337.386551 -238.997812) (xy 337.360248 -238.956216) (xy 337.340957 -238.91094) (xy 337.32918 -238.863156)
			(xy 337.32522 -238.814102) (xy 336.996532 -238.814102) (xy 336.996037 -238.838709) (xy 336.988142 -238.887286)
			(xy 336.972558 -238.933967) (xy 336.949687 -238.977544) (xy 336.920122 -239.016888) (xy 336.884629 -239.05098)
			(xy 336.844126 -239.078936) (xy 336.799664 -239.100034) (xy 336.752393 -239.113726) (xy 336.703538 -239.119658)
			(xy 336.654363 -239.117677) (xy 336.606144 -239.107833) (xy 336.560128 -239.090381) (xy 336.517507 -239.065774)
			(xy 336.479386 -239.034649) (xy 336.446751 -238.997812) (xy 336.420448 -238.956216) (xy 336.401157 -238.91094)
			(xy 336.38938 -238.863156) (xy 336.38542 -238.814102) (xy 336.056478 -238.814102) (xy 336.055983 -238.838709)
			(xy 336.048088 -238.887286) (xy 336.032504 -238.933967) (xy 336.009633 -238.977544) (xy 335.980068 -239.016888)
			(xy 335.944575 -239.05098) (xy 335.904072 -239.078936) (xy 335.85961 -239.100034) (xy 335.812339 -239.113726)
			(xy 335.763484 -239.119658) (xy 335.714309 -239.117677) (xy 335.66609 -239.107833) (xy 335.620074 -239.090381)
			(xy 335.577453 -239.065774) (xy 335.539332 -239.034649) (xy 335.506697 -238.997812) (xy 335.480394 -238.956216)
			(xy 335.461103 -238.91094) (xy 335.449326 -238.863156) (xy 335.445366 -238.814102) (xy 335.116424 -238.814102)
			(xy 335.115929 -238.838709) (xy 335.108034 -238.887286) (xy 335.09245 -238.933967) (xy 335.069579 -238.977544)
			(xy 335.040014 -239.016888) (xy 335.004521 -239.05098) (xy 334.964018 -239.078936) (xy 334.919556 -239.100034)
			(xy 334.872285 -239.113726) (xy 334.82343 -239.119658) (xy 334.774255 -239.117677) (xy 334.726036 -239.107833)
			(xy 334.68002 -239.090381) (xy 334.637399 -239.065774) (xy 334.599278 -239.034649) (xy 334.566643 -238.997812)
			(xy 334.54034 -238.956216) (xy 334.521049 -238.91094) (xy 334.509272 -238.863156) (xy 334.505312 -238.814102)
			(xy 334.17637 -238.814102) (xy 334.175875 -238.838709) (xy 334.16798 -238.887286) (xy 334.152396 -238.933967)
			(xy 334.129525 -238.977544) (xy 334.09996 -239.016888) (xy 334.064467 -239.05098) (xy 334.023964 -239.078936)
			(xy 333.979502 -239.100034) (xy 333.932231 -239.113726) (xy 333.883376 -239.119658) (xy 333.834201 -239.117677)
			(xy 333.785982 -239.107833) (xy 333.739966 -239.090381) (xy 333.697345 -239.065774) (xy 333.659224 -239.034649)
			(xy 333.626589 -238.997812) (xy 333.600286 -238.956216) (xy 333.580995 -238.91094) (xy 333.569218 -238.863156)
			(xy 333.565258 -238.814102) (xy 333.236316 -238.814102) (xy 333.235821 -238.838709) (xy 333.227926 -238.887286)
			(xy 333.212342 -238.933967) (xy 333.189471 -238.977544) (xy 333.159906 -239.016888) (xy 333.124413 -239.05098)
			(xy 333.08391 -239.078936) (xy 333.039448 -239.100034) (xy 332.992177 -239.113726) (xy 332.943322 -239.119658)
			(xy 332.894147 -239.117677) (xy 332.845928 -239.107833) (xy 332.799912 -239.090381) (xy 332.757291 -239.065774)
			(xy 332.71917 -239.034649) (xy 332.686535 -238.997812) (xy 332.660232 -238.956216) (xy 332.640941 -238.91094)
			(xy 332.629164 -238.863156) (xy 332.625204 -238.814102) (xy 332.296516 -238.814102) (xy 332.296021 -238.838709)
			(xy 332.288126 -238.887286) (xy 332.272542 -238.933967) (xy 332.249671 -238.977544) (xy 332.220106 -239.016888)
			(xy 332.184613 -239.05098) (xy 332.14411 -239.078936) (xy 332.099648 -239.100034) (xy 332.052377 -239.113726)
			(xy 332.003522 -239.119658) (xy 331.954347 -239.117677) (xy 331.906128 -239.107833) (xy 331.860112 -239.090381)
			(xy 331.817491 -239.065774) (xy 331.77937 -239.034649) (xy 331.746735 -238.997812) (xy 331.720432 -238.956216)
			(xy 331.701141 -238.91094) (xy 331.689364 -238.863156) (xy 331.685404 -238.814102) (xy 331.459332 -238.814102)
			(xy 331.459332 -239.220248) (xy 331.4598 -239.229607) (xy 331.466562 -239.247069) (xy 331.47254 -239.254284)
			(xy 331.517498 -239.303814) (xy 331.52081 -239.307282) (xy 331.528481 -239.313036) (xy 331.532738 -239.315244)
			(xy 331.540612 -239.319054) (xy 331.550264 -239.32007) (xy 331.550518 -239.32007) (xy 331.575387 -239.322981)
			(xy 331.623768 -239.335866) (xy 331.6694 -239.356468) (xy 331.711061 -239.384236) (xy 331.747635 -239.418427)
			(xy 331.778145 -239.458125) (xy 331.801771 -239.502266) (xy 331.817883 -239.54967) (xy 331.826048 -239.599067)
			(xy 331.826048 -239.624108) (xy 332.155304 -239.624108) (xy 332.159264 -239.575054) (xy 332.171041 -239.52727)
			(xy 332.190332 -239.481994) (xy 332.216635 -239.440398) (xy 332.24927 -239.403561) (xy 332.287391 -239.372436)
			(xy 332.330012 -239.347829) (xy 332.376028 -239.330377) (xy 332.424247 -239.320533) (xy 332.473422 -239.318552)
			(xy 332.522277 -239.324484) (xy 332.569548 -239.338176) (xy 332.61401 -239.359274) (xy 332.654513 -239.38723)
			(xy 332.690006 -239.421322) (xy 332.719571 -239.460666) (xy 332.742442 -239.504243) (xy 332.758026 -239.550924)
			(xy 332.765921 -239.599501) (xy 332.766416 -239.624108) (xy 333.095358 -239.624108) (xy 333.099318 -239.575054)
			(xy 333.111095 -239.52727) (xy 333.130386 -239.481994) (xy 333.156689 -239.440398) (xy 333.189324 -239.403561)
			(xy 333.227445 -239.372436) (xy 333.270066 -239.347829) (xy 333.316082 -239.330377) (xy 333.364301 -239.320533)
			(xy 333.413476 -239.318552) (xy 333.462331 -239.324484) (xy 333.509602 -239.338176) (xy 333.554064 -239.359274)
			(xy 333.594567 -239.38723) (xy 333.63006 -239.421322) (xy 333.659625 -239.460666) (xy 333.682496 -239.504243)
			(xy 333.69808 -239.550924) (xy 333.705975 -239.599501) (xy 333.70647 -239.624108) (xy 334.975212 -239.624108)
			(xy 334.979172 -239.575054) (xy 334.990949 -239.52727) (xy 335.01024 -239.481994) (xy 335.036543 -239.440398)
			(xy 335.069178 -239.403561) (xy 335.107299 -239.372436) (xy 335.14992 -239.347829) (xy 335.195936 -239.330377)
			(xy 335.244155 -239.320533) (xy 335.29333 -239.318552) (xy 335.342185 -239.324484) (xy 335.389456 -239.338176)
			(xy 335.433918 -239.359274) (xy 335.474421 -239.38723) (xy 335.509914 -239.421322) (xy 335.539479 -239.460666)
			(xy 335.56235 -239.504243) (xy 335.577934 -239.550924) (xy 335.585829 -239.599501) (xy 335.586324 -239.624108)
			(xy 335.915266 -239.624108) (xy 335.919226 -239.575054) (xy 335.931003 -239.52727) (xy 335.950294 -239.481994)
			(xy 335.976597 -239.440398) (xy 336.009232 -239.403561) (xy 336.047353 -239.372436) (xy 336.089974 -239.347829)
			(xy 336.13599 -239.330377) (xy 336.184209 -239.320533) (xy 336.233384 -239.318552) (xy 336.282239 -239.324484)
			(xy 336.32951 -239.338176) (xy 336.373972 -239.359274) (xy 336.414475 -239.38723) (xy 336.449968 -239.421322)
			(xy 336.479533 -239.460666) (xy 336.502404 -239.504243) (xy 336.517988 -239.550924) (xy 336.525883 -239.599501)
			(xy 336.526378 -239.624108) (xy 336.85532 -239.624108) (xy 336.85928 -239.575054) (xy 336.871057 -239.52727)
			(xy 336.890348 -239.481994) (xy 336.916651 -239.440398) (xy 336.949286 -239.403561) (xy 336.987407 -239.372436)
			(xy 337.030028 -239.347829) (xy 337.076044 -239.330377) (xy 337.124263 -239.320533) (xy 337.173438 -239.318552)
			(xy 337.222293 -239.324484) (xy 337.269564 -239.338176) (xy 337.314026 -239.359274) (xy 337.354529 -239.38723)
			(xy 337.390022 -239.421322) (xy 337.419587 -239.460666) (xy 337.442458 -239.504243) (xy 337.458042 -239.550924)
			(xy 337.465937 -239.599501) (xy 337.466432 -239.624108) (xy 337.795374 -239.624108) (xy 337.799334 -239.575054)
			(xy 337.811111 -239.52727) (xy 337.830402 -239.481994) (xy 337.856705 -239.440398) (xy 337.88934 -239.403561)
			(xy 337.927461 -239.372436) (xy 337.970082 -239.347829) (xy 338.016098 -239.330377) (xy 338.064317 -239.320533)
			(xy 338.113492 -239.318552) (xy 338.162347 -239.324484) (xy 338.209618 -239.338176) (xy 338.25408 -239.359274)
			(xy 338.294583 -239.38723) (xy 338.330076 -239.421322) (xy 338.359641 -239.460666) (xy 338.382512 -239.504243)
			(xy 338.398096 -239.550924) (xy 338.405991 -239.599501) (xy 338.406486 -239.624108) (xy 338.724743 -239.624108)
			(xy 338.728838 -239.57338) (xy 338.741017 -239.523966) (xy 338.760965 -239.477146) (xy 338.788166 -239.434132)
			(xy 338.821914 -239.396038) (xy 338.861336 -239.363851) (xy 338.90541 -239.338405) (xy 338.952996 -239.320358)
			(xy 339.00286 -239.310178) (xy 339.053712 -239.308129) (xy 339.104233 -239.314263) (xy 339.153117 -239.328423)
			(xy 339.199096 -239.35024) (xy 339.24098 -239.37915) (xy 339.277684 -239.414405) (xy 339.308257 -239.455091)
			(xy 339.331908 -239.500154) (xy 339.348024 -239.548428) (xy 339.356188 -239.598662) (xy 339.3567 -239.624108)
			(xy 339.664797 -239.624108) (xy 339.668892 -239.57338) (xy 339.681071 -239.523966) (xy 339.701019 -239.477146)
			(xy 339.72822 -239.434132) (xy 339.761968 -239.396038) (xy 339.80139 -239.363851) (xy 339.845464 -239.338405)
			(xy 339.89305 -239.320358) (xy 339.942914 -239.310178) (xy 339.993766 -239.308129) (xy 340.044287 -239.314263)
			(xy 340.093171 -239.328423) (xy 340.13915 -239.35024) (xy 340.181034 -239.37915) (xy 340.217738 -239.414405)
			(xy 340.248311 -239.455091) (xy 340.271962 -239.500154) (xy 340.288078 -239.548428) (xy 340.296242 -239.598662)
			(xy 340.296754 -239.624108) (xy 341.544905 -239.624108) (xy 341.549 -239.57338) (xy 341.561179 -239.523966)
			(xy 341.581127 -239.477146) (xy 341.608328 -239.434132) (xy 341.642076 -239.396038) (xy 341.681498 -239.363851)
			(xy 341.725572 -239.338405) (xy 341.773158 -239.320358) (xy 341.823022 -239.310178) (xy 341.873874 -239.308129)
			(xy 341.924395 -239.314263) (xy 341.973279 -239.328423) (xy 342.019258 -239.35024) (xy 342.061142 -239.37915)
			(xy 342.097846 -239.414405) (xy 342.128419 -239.455091) (xy 342.15207 -239.500154) (xy 342.168186 -239.548428)
			(xy 342.17635 -239.598662) (xy 342.176862 -239.624108) (xy 342.49539 -239.624108) (xy 342.49935 -239.575054)
			(xy 342.511127 -239.52727) (xy 342.530418 -239.481994) (xy 342.556721 -239.440398) (xy 342.589356 -239.403561)
			(xy 342.627477 -239.372436) (xy 342.670098 -239.347829) (xy 342.716114 -239.330377) (xy 342.764333 -239.320533)
			(xy 342.813508 -239.318552) (xy 342.862363 -239.324484) (xy 342.909634 -239.338176) (xy 342.954096 -239.359274)
			(xy 342.994599 -239.38723) (xy 343.030092 -239.421322) (xy 343.059657 -239.460666) (xy 343.082528 -239.504243)
			(xy 343.098112 -239.550924) (xy 343.106007 -239.599501) (xy 343.106502 -239.624108) (xy 343.106007 -239.648715)
			(xy 343.098112 -239.697292) (xy 343.082528 -239.743973) (xy 343.059657 -239.78755) (xy 343.030092 -239.826894)
			(xy 342.994599 -239.860986) (xy 342.954096 -239.888942) (xy 342.909634 -239.91004) (xy 342.862363 -239.923732)
			(xy 342.813508 -239.929664) (xy 342.764333 -239.927683) (xy 342.716114 -239.917839) (xy 342.670098 -239.900387)
			(xy 342.627477 -239.87578) (xy 342.589356 -239.844655) (xy 342.556721 -239.807818) (xy 342.530418 -239.766222)
			(xy 342.511127 -239.720946) (xy 342.49935 -239.673162) (xy 342.49539 -239.624108) (xy 342.176862 -239.624108)
			(xy 342.17635 -239.649554) (xy 342.168186 -239.699788) (xy 342.15207 -239.748062) (xy 342.128419 -239.793125)
			(xy 342.097846 -239.833811) (xy 342.061142 -239.869066) (xy 342.019258 -239.897976) (xy 341.973279 -239.919793)
			(xy 341.924395 -239.933953) (xy 341.873874 -239.940087) (xy 341.823022 -239.938038) (xy 341.773158 -239.927858)
			(xy 341.725572 -239.909811) (xy 341.681498 -239.884365) (xy 341.642076 -239.852178) (xy 341.608328 -239.814084)
			(xy 341.581127 -239.77107) (xy 341.561179 -239.72425) (xy 341.549 -239.674836) (xy 341.544905 -239.624108)
			(xy 340.296754 -239.624108) (xy 340.296242 -239.649554) (xy 340.288078 -239.699788) (xy 340.271962 -239.748062)
			(xy 340.248311 -239.793125) (xy 340.217738 -239.833811) (xy 340.181034 -239.869066) (xy 340.13915 -239.897976)
			(xy 340.093171 -239.919793) (xy 340.044287 -239.933953) (xy 339.993766 -239.940087) (xy 339.942914 -239.938038)
			(xy 339.89305 -239.927858) (xy 339.845464 -239.909811) (xy 339.80139 -239.884365) (xy 339.761968 -239.852178)
			(xy 339.72822 -239.814084) (xy 339.701019 -239.77107) (xy 339.681071 -239.72425) (xy 339.668892 -239.674836)
			(xy 339.664797 -239.624108) (xy 339.3567 -239.624108) (xy 339.356188 -239.649554) (xy 339.348024 -239.699788)
			(xy 339.331908 -239.748062) (xy 339.308257 -239.793125) (xy 339.277684 -239.833811) (xy 339.24098 -239.869066)
			(xy 339.199096 -239.897976) (xy 339.153117 -239.919793) (xy 339.104233 -239.933953) (xy 339.053712 -239.940087)
			(xy 339.00286 -239.938038) (xy 338.952996 -239.927858) (xy 338.90541 -239.909811) (xy 338.861336 -239.884365)
			(xy 338.821914 -239.852178) (xy 338.788166 -239.814084) (xy 338.760965 -239.77107) (xy 338.741017 -239.72425)
			(xy 338.728838 -239.674836) (xy 338.724743 -239.624108) (xy 338.406486 -239.624108) (xy 338.405991 -239.648715)
			(xy 338.398096 -239.697292) (xy 338.382512 -239.743973) (xy 338.359641 -239.78755) (xy 338.330076 -239.826894)
			(xy 338.294583 -239.860986) (xy 338.25408 -239.888942) (xy 338.209618 -239.91004) (xy 338.162347 -239.923732)
			(xy 338.113492 -239.929664) (xy 338.064317 -239.927683) (xy 338.016098 -239.917839) (xy 337.970082 -239.900387)
			(xy 337.927461 -239.87578) (xy 337.88934 -239.844655) (xy 337.856705 -239.807818) (xy 337.830402 -239.766222)
			(xy 337.811111 -239.720946) (xy 337.799334 -239.673162) (xy 337.795374 -239.624108) (xy 337.466432 -239.624108)
			(xy 337.465937 -239.648715) (xy 337.458042 -239.697292) (xy 337.442458 -239.743973) (xy 337.419587 -239.78755)
			(xy 337.390022 -239.826894) (xy 337.354529 -239.860986) (xy 337.314026 -239.888942) (xy 337.269564 -239.91004)
			(xy 337.222293 -239.923732) (xy 337.173438 -239.929664) (xy 337.124263 -239.927683) (xy 337.076044 -239.917839)
			(xy 337.030028 -239.900387) (xy 336.987407 -239.87578) (xy 336.949286 -239.844655) (xy 336.916651 -239.807818)
			(xy 336.890348 -239.766222) (xy 336.871057 -239.720946) (xy 336.85928 -239.673162) (xy 336.85532 -239.624108)
			(xy 336.526378 -239.624108) (xy 336.525883 -239.648715) (xy 336.517988 -239.697292) (xy 336.502404 -239.743973)
			(xy 336.479533 -239.78755) (xy 336.449968 -239.826894) (xy 336.414475 -239.860986) (xy 336.373972 -239.888942)
			(xy 336.32951 -239.91004) (xy 336.282239 -239.923732) (xy 336.233384 -239.929664) (xy 336.184209 -239.927683)
			(xy 336.13599 -239.917839) (xy 336.089974 -239.900387) (xy 336.047353 -239.87578) (xy 336.009232 -239.844655)
			(xy 335.976597 -239.807818) (xy 335.950294 -239.766222) (xy 335.931003 -239.720946) (xy 335.919226 -239.673162)
			(xy 335.915266 -239.624108) (xy 335.586324 -239.624108) (xy 335.585829 -239.648715) (xy 335.577934 -239.697292)
			(xy 335.56235 -239.743973) (xy 335.539479 -239.78755) (xy 335.509914 -239.826894) (xy 335.474421 -239.860986)
			(xy 335.433918 -239.888942) (xy 335.389456 -239.91004) (xy 335.342185 -239.923732) (xy 335.29333 -239.929664)
			(xy 335.244155 -239.927683) (xy 335.195936 -239.917839) (xy 335.14992 -239.900387) (xy 335.107299 -239.87578)
			(xy 335.069178 -239.844655) (xy 335.036543 -239.807818) (xy 335.01024 -239.766222) (xy 334.990949 -239.720946)
			(xy 334.979172 -239.673162) (xy 334.975212 -239.624108) (xy 333.70647 -239.624108) (xy 333.705975 -239.648715)
			(xy 333.69808 -239.697292) (xy 333.682496 -239.743973) (xy 333.659625 -239.78755) (xy 333.63006 -239.826894)
			(xy 333.594567 -239.860986) (xy 333.554064 -239.888942) (xy 333.509602 -239.91004) (xy 333.462331 -239.923732)
			(xy 333.413476 -239.929664) (xy 333.364301 -239.927683) (xy 333.316082 -239.917839) (xy 333.270066 -239.900387)
			(xy 333.227445 -239.87578) (xy 333.189324 -239.844655) (xy 333.156689 -239.807818) (xy 333.130386 -239.766222)
			(xy 333.111095 -239.720946) (xy 333.099318 -239.673162) (xy 333.095358 -239.624108) (xy 332.766416 -239.624108)
			(xy 332.765921 -239.648715) (xy 332.758026 -239.697292) (xy 332.742442 -239.743973) (xy 332.719571 -239.78755)
			(xy 332.690006 -239.826894) (xy 332.654513 -239.860986) (xy 332.61401 -239.888942) (xy 332.569548 -239.91004)
			(xy 332.522277 -239.923732) (xy 332.473422 -239.929664) (xy 332.424247 -239.927683) (xy 332.376028 -239.917839)
			(xy 332.330012 -239.900387) (xy 332.287391 -239.87578) (xy 332.24927 -239.844655) (xy 332.216635 -239.807818)
			(xy 332.190332 -239.766222) (xy 332.171041 -239.720946) (xy 332.159264 -239.673162) (xy 332.155304 -239.624108)
			(xy 331.826048 -239.624108) (xy 331.826048 -239.649134) (xy 331.817882 -239.698531) (xy 331.801771 -239.745935)
			(xy 331.778144 -239.790077) (xy 331.747634 -239.829774) (xy 331.711059 -239.863965) (xy 331.669398 -239.891733)
			(xy 331.623766 -239.912335) (xy 331.575385 -239.925219) (xy 331.550518 -239.928146) (xy 331.550264 -239.928146)
			(xy 331.540612 -239.929162) (xy 331.532738 -239.932972) (xy 331.528475 -239.935172) (xy 331.520795 -239.940918)
			(xy 331.517498 -239.944402) (xy 331.47254 -239.993932) (xy 331.466484 -240.001103) (xy 331.459697 -240.018589)
			(xy 331.459332 -240.027968) (xy 331.459332 -240.434114) (xy 331.685404 -240.434114) (xy 331.689364 -240.38506)
			(xy 331.701141 -240.337276) (xy 331.720432 -240.292) (xy 331.746735 -240.250404) (xy 331.77937 -240.213567)
			(xy 331.817491 -240.182442) (xy 331.860112 -240.157835) (xy 331.906128 -240.140383) (xy 331.954347 -240.130539)
			(xy 332.003522 -240.128558) (xy 332.052377 -240.13449) (xy 332.099648 -240.148182) (xy 332.14411 -240.16928)
			(xy 332.184613 -240.197236) (xy 332.220106 -240.231328) (xy 332.249671 -240.270672) (xy 332.272542 -240.314249)
			(xy 332.288126 -240.36093) (xy 332.296021 -240.409507) (xy 332.296516 -240.434114) (xy 332.625204 -240.434114)
			(xy 332.629164 -240.38506) (xy 332.640941 -240.337276) (xy 332.660232 -240.292) (xy 332.686535 -240.250404)
			(xy 332.71917 -240.213567) (xy 332.757291 -240.182442) (xy 332.799912 -240.157835) (xy 332.845928 -240.140383)
			(xy 332.894147 -240.130539) (xy 332.943322 -240.128558) (xy 332.992177 -240.13449) (xy 333.039448 -240.148182)
			(xy 333.08391 -240.16928) (xy 333.124413 -240.197236) (xy 333.159906 -240.231328) (xy 333.189471 -240.270672)
			(xy 333.212342 -240.314249) (xy 333.227926 -240.36093) (xy 333.235821 -240.409507) (xy 333.236316 -240.434114)
			(xy 333.565258 -240.434114) (xy 333.569218 -240.38506) (xy 333.580995 -240.337276) (xy 333.600286 -240.292)
			(xy 333.626589 -240.250404) (xy 333.659224 -240.213567) (xy 333.697345 -240.182442) (xy 333.739966 -240.157835)
			(xy 333.785982 -240.140383) (xy 333.834201 -240.130539) (xy 333.883376 -240.128558) (xy 333.932231 -240.13449)
			(xy 333.979502 -240.148182) (xy 334.023964 -240.16928) (xy 334.064467 -240.197236) (xy 334.09996 -240.231328)
			(xy 334.129525 -240.270672) (xy 334.152396 -240.314249) (xy 334.16798 -240.36093) (xy 334.175875 -240.409507)
			(xy 334.17637 -240.434114) (xy 334.505312 -240.434114) (xy 334.509272 -240.38506) (xy 334.521049 -240.337276)
			(xy 334.54034 -240.292) (xy 334.566643 -240.250404) (xy 334.599278 -240.213567) (xy 334.637399 -240.182442)
			(xy 334.68002 -240.157835) (xy 334.726036 -240.140383) (xy 334.774255 -240.130539) (xy 334.82343 -240.128558)
			(xy 334.872285 -240.13449) (xy 334.919556 -240.148182) (xy 334.964018 -240.16928) (xy 335.004521 -240.197236)
			(xy 335.040014 -240.231328) (xy 335.069579 -240.270672) (xy 335.09245 -240.314249) (xy 335.108034 -240.36093)
			(xy 335.115929 -240.409507) (xy 335.116424 -240.434114) (xy 335.445366 -240.434114) (xy 335.449326 -240.38506)
			(xy 335.461103 -240.337276) (xy 335.480394 -240.292) (xy 335.506697 -240.250404) (xy 335.539332 -240.213567)
			(xy 335.577453 -240.182442) (xy 335.620074 -240.157835) (xy 335.66609 -240.140383) (xy 335.714309 -240.130539)
			(xy 335.763484 -240.128558) (xy 335.812339 -240.13449) (xy 335.85961 -240.148182) (xy 335.904072 -240.16928)
			(xy 335.944575 -240.197236) (xy 335.980068 -240.231328) (xy 336.009633 -240.270672) (xy 336.032504 -240.314249)
			(xy 336.048088 -240.36093) (xy 336.055983 -240.409507) (xy 336.056478 -240.434114) (xy 336.38542 -240.434114)
			(xy 336.38938 -240.38506) (xy 336.401157 -240.337276) (xy 336.420448 -240.292) (xy 336.446751 -240.250404)
			(xy 336.479386 -240.213567) (xy 336.517507 -240.182442) (xy 336.560128 -240.157835) (xy 336.606144 -240.140383)
			(xy 336.654363 -240.130539) (xy 336.703538 -240.128558) (xy 336.752393 -240.13449) (xy 336.799664 -240.148182)
			(xy 336.844126 -240.16928) (xy 336.884629 -240.197236) (xy 336.920122 -240.231328) (xy 336.949687 -240.270672)
			(xy 336.972558 -240.314249) (xy 336.988142 -240.36093) (xy 336.996037 -240.409507) (xy 336.996532 -240.434114)
			(xy 337.32522 -240.434114) (xy 337.32918 -240.38506) (xy 337.340957 -240.337276) (xy 337.360248 -240.292)
			(xy 337.386551 -240.250404) (xy 337.419186 -240.213567) (xy 337.457307 -240.182442) (xy 337.499928 -240.157835)
			(xy 337.545944 -240.140383) (xy 337.594163 -240.130539) (xy 337.643338 -240.128558) (xy 337.692193 -240.13449)
			(xy 337.739464 -240.148182) (xy 337.783926 -240.16928) (xy 337.824429 -240.197236) (xy 337.859922 -240.231328)
			(xy 337.889487 -240.270672) (xy 337.912358 -240.314249) (xy 337.927942 -240.36093) (xy 337.935837 -240.409507)
			(xy 337.936332 -240.434114) (xy 338.254843 -240.434114) (xy 338.258938 -240.383386) (xy 338.271117 -240.333972)
			(xy 338.291065 -240.287152) (xy 338.318266 -240.244138) (xy 338.352014 -240.206044) (xy 338.391436 -240.173857)
			(xy 338.43551 -240.148411) (xy 338.483096 -240.130364) (xy 338.53296 -240.120184) (xy 338.583812 -240.118135)
			(xy 338.634333 -240.124269) (xy 338.683217 -240.138429) (xy 338.729196 -240.160246) (xy 338.77108 -240.189156)
			(xy 338.807784 -240.224411) (xy 338.838357 -240.265097) (xy 338.862008 -240.31016) (xy 338.878124 -240.358434)
			(xy 338.886288 -240.408668) (xy 338.8868 -240.434114) (xy 339.205328 -240.434114) (xy 339.209288 -240.38506)
			(xy 339.221065 -240.337276) (xy 339.240356 -240.292) (xy 339.266659 -240.250404) (xy 339.299294 -240.213567)
			(xy 339.337415 -240.182442) (xy 339.380036 -240.157835) (xy 339.426052 -240.140383) (xy 339.474271 -240.130539)
			(xy 339.523446 -240.128558) (xy 339.572301 -240.13449) (xy 339.619572 -240.148182) (xy 339.664034 -240.16928)
			(xy 339.704537 -240.197236) (xy 339.74003 -240.231328) (xy 339.769595 -240.270672) (xy 339.792466 -240.314249)
			(xy 339.80805 -240.36093) (xy 339.815945 -240.409507) (xy 339.81644 -240.434114) (xy 340.134951 -240.434114)
			(xy 340.139046 -240.383386) (xy 340.151225 -240.333972) (xy 340.171173 -240.287152) (xy 340.198374 -240.244138)
			(xy 340.232122 -240.206044) (xy 340.271544 -240.173857) (xy 340.315618 -240.148411) (xy 340.363204 -240.130364)
			(xy 340.413068 -240.120184) (xy 340.46392 -240.118135) (xy 340.514441 -240.124269) (xy 340.563325 -240.138429)
			(xy 340.609304 -240.160246) (xy 340.651188 -240.189156) (xy 340.687892 -240.224411) (xy 340.718465 -240.265097)
			(xy 340.742116 -240.31016) (xy 340.758232 -240.358434) (xy 340.766396 -240.408668) (xy 340.766908 -240.434114)
			(xy 341.085182 -240.434114) (xy 341.089142 -240.38506) (xy 341.100919 -240.337276) (xy 341.12021 -240.292)
			(xy 341.146513 -240.250404) (xy 341.179148 -240.213567) (xy 341.217269 -240.182442) (xy 341.25989 -240.157835)
			(xy 341.305906 -240.140383) (xy 341.354125 -240.130539) (xy 341.4033 -240.128558) (xy 341.452155 -240.13449)
			(xy 341.499426 -240.148182) (xy 341.543888 -240.16928) (xy 341.584391 -240.197236) (xy 341.619884 -240.231328)
			(xy 341.649449 -240.270672) (xy 341.67232 -240.314249) (xy 341.687904 -240.36093) (xy 341.695799 -240.409507)
			(xy 341.696294 -240.434114) (xy 342.014805 -240.434114) (xy 342.0189 -240.383386) (xy 342.031079 -240.333972)
			(xy 342.051027 -240.287152) (xy 342.078228 -240.244138) (xy 342.111976 -240.206044) (xy 342.151398 -240.173857)
			(xy 342.195472 -240.148411) (xy 342.243058 -240.130364) (xy 342.292922 -240.120184) (xy 342.343774 -240.118135)
			(xy 342.394295 -240.124269) (xy 342.443179 -240.138429) (xy 342.489158 -240.160246) (xy 342.531042 -240.189156)
			(xy 342.567746 -240.224411) (xy 342.598319 -240.265097) (xy 342.62197 -240.31016) (xy 342.638086 -240.358434)
			(xy 342.64625 -240.408668) (xy 342.646762 -240.434114) (xy 342.954859 -240.434114) (xy 342.958954 -240.383386)
			(xy 342.971133 -240.333972) (xy 342.991081 -240.287152) (xy 343.018282 -240.244138) (xy 343.05203 -240.206044)
			(xy 343.091452 -240.173857) (xy 343.135526 -240.148411) (xy 343.183112 -240.130364) (xy 343.232976 -240.120184)
			(xy 343.283828 -240.118135) (xy 343.334349 -240.124269) (xy 343.383233 -240.138429) (xy 343.429212 -240.160246)
			(xy 343.471096 -240.189156) (xy 343.5078 -240.224411) (xy 343.538373 -240.265097) (xy 343.562024 -240.31016)
			(xy 343.57814 -240.358434) (xy 343.586304 -240.408668) (xy 343.586816 -240.434114) (xy 343.586304 -240.45956)
			(xy 343.57814 -240.509794) (xy 343.562024 -240.558068) (xy 343.538373 -240.603131) (xy 343.5078 -240.643817)
			(xy 343.471096 -240.679072) (xy 343.429212 -240.707982) (xy 343.383233 -240.729799) (xy 343.334349 -240.743959)
			(xy 343.283828 -240.750093) (xy 343.232976 -240.748044) (xy 343.183112 -240.737864) (xy 343.135526 -240.719817)
			(xy 343.091452 -240.694371) (xy 343.05203 -240.662184) (xy 343.018282 -240.62409) (xy 342.991081 -240.581076)
			(xy 342.971133 -240.534256) (xy 342.958954 -240.484842) (xy 342.954859 -240.434114) (xy 342.646762 -240.434114)
			(xy 342.64625 -240.45956) (xy 342.638086 -240.509794) (xy 342.62197 -240.558068) (xy 342.598319 -240.603131)
			(xy 342.567746 -240.643817) (xy 342.531042 -240.679072) (xy 342.489158 -240.707982) (xy 342.443179 -240.729799)
			(xy 342.394295 -240.743959) (xy 342.343774 -240.750093) (xy 342.292922 -240.748044) (xy 342.243058 -240.737864)
			(xy 342.195472 -240.719817) (xy 342.151398 -240.694371) (xy 342.111976 -240.662184) (xy 342.078228 -240.62409)
			(xy 342.051027 -240.581076) (xy 342.031079 -240.534256) (xy 342.0189 -240.484842) (xy 342.014805 -240.434114)
			(xy 341.696294 -240.434114) (xy 341.695799 -240.458721) (xy 341.687904 -240.507298) (xy 341.67232 -240.553979)
			(xy 341.649449 -240.597556) (xy 341.619884 -240.6369) (xy 341.584391 -240.670992) (xy 341.543888 -240.698948)
			(xy 341.499426 -240.720046) (xy 341.452155 -240.733738) (xy 341.4033 -240.73967) (xy 341.354125 -240.737689)
			(xy 341.305906 -240.727845) (xy 341.25989 -240.710393) (xy 341.217269 -240.685786) (xy 341.179148 -240.654661)
			(xy 341.146513 -240.617824) (xy 341.12021 -240.576228) (xy 341.100919 -240.530952) (xy 341.089142 -240.483168)
			(xy 341.085182 -240.434114) (xy 340.766908 -240.434114) (xy 340.766396 -240.45956) (xy 340.758232 -240.509794)
			(xy 340.742116 -240.558068) (xy 340.718465 -240.603131) (xy 340.687892 -240.643817) (xy 340.651188 -240.679072)
			(xy 340.609304 -240.707982) (xy 340.563325 -240.729799) (xy 340.514441 -240.743959) (xy 340.46392 -240.750093)
			(xy 340.413068 -240.748044) (xy 340.363204 -240.737864) (xy 340.315618 -240.719817) (xy 340.271544 -240.694371)
			(xy 340.232122 -240.662184) (xy 340.198374 -240.62409) (xy 340.171173 -240.581076) (xy 340.151225 -240.534256)
			(xy 340.139046 -240.484842) (xy 340.134951 -240.434114) (xy 339.81644 -240.434114) (xy 339.815945 -240.458721)
			(xy 339.80805 -240.507298) (xy 339.792466 -240.553979) (xy 339.769595 -240.597556) (xy 339.74003 -240.6369)
			(xy 339.704537 -240.670992) (xy 339.664034 -240.698948) (xy 339.619572 -240.720046) (xy 339.572301 -240.733738)
			(xy 339.523446 -240.73967) (xy 339.474271 -240.737689) (xy 339.426052 -240.727845) (xy 339.380036 -240.710393)
			(xy 339.337415 -240.685786) (xy 339.299294 -240.654661) (xy 339.266659 -240.617824) (xy 339.240356 -240.576228)
			(xy 339.221065 -240.530952) (xy 339.209288 -240.483168) (xy 339.205328 -240.434114) (xy 338.8868 -240.434114)
			(xy 338.886288 -240.45956) (xy 338.878124 -240.509794) (xy 338.862008 -240.558068) (xy 338.838357 -240.603131)
			(xy 338.807784 -240.643817) (xy 338.77108 -240.679072) (xy 338.729196 -240.707982) (xy 338.683217 -240.729799)
			(xy 338.634333 -240.743959) (xy 338.583812 -240.750093) (xy 338.53296 -240.748044) (xy 338.483096 -240.737864)
			(xy 338.43551 -240.719817) (xy 338.391436 -240.694371) (xy 338.352014 -240.662184) (xy 338.318266 -240.62409)
			(xy 338.291065 -240.581076) (xy 338.271117 -240.534256) (xy 338.258938 -240.484842) (xy 338.254843 -240.434114)
			(xy 337.936332 -240.434114) (xy 337.935837 -240.458721) (xy 337.927942 -240.507298) (xy 337.912358 -240.553979)
			(xy 337.889487 -240.597556) (xy 337.859922 -240.6369) (xy 337.824429 -240.670992) (xy 337.783926 -240.698948)
			(xy 337.739464 -240.720046) (xy 337.692193 -240.733738) (xy 337.643338 -240.73967) (xy 337.594163 -240.737689)
			(xy 337.545944 -240.727845) (xy 337.499928 -240.710393) (xy 337.457307 -240.685786) (xy 337.419186 -240.654661)
			(xy 337.386551 -240.617824) (xy 337.360248 -240.576228) (xy 337.340957 -240.530952) (xy 337.32918 -240.483168)
			(xy 337.32522 -240.434114) (xy 336.996532 -240.434114) (xy 336.996037 -240.458721) (xy 336.988142 -240.507298)
			(xy 336.972558 -240.553979) (xy 336.949687 -240.597556) (xy 336.920122 -240.6369) (xy 336.884629 -240.670992)
			(xy 336.844126 -240.698948) (xy 336.799664 -240.720046) (xy 336.752393 -240.733738) (xy 336.703538 -240.73967)
			(xy 336.654363 -240.737689) (xy 336.606144 -240.727845) (xy 336.560128 -240.710393) (xy 336.517507 -240.685786)
			(xy 336.479386 -240.654661) (xy 336.446751 -240.617824) (xy 336.420448 -240.576228) (xy 336.401157 -240.530952)
			(xy 336.38938 -240.483168) (xy 336.38542 -240.434114) (xy 336.056478 -240.434114) (xy 336.055983 -240.458721)
			(xy 336.048088 -240.507298) (xy 336.032504 -240.553979) (xy 336.009633 -240.597556) (xy 335.980068 -240.6369)
			(xy 335.944575 -240.670992) (xy 335.904072 -240.698948) (xy 335.85961 -240.720046) (xy 335.812339 -240.733738)
			(xy 335.763484 -240.73967) (xy 335.714309 -240.737689) (xy 335.66609 -240.727845) (xy 335.620074 -240.710393)
			(xy 335.577453 -240.685786) (xy 335.539332 -240.654661) (xy 335.506697 -240.617824) (xy 335.480394 -240.576228)
			(xy 335.461103 -240.530952) (xy 335.449326 -240.483168) (xy 335.445366 -240.434114) (xy 335.116424 -240.434114)
			(xy 335.115929 -240.458721) (xy 335.108034 -240.507298) (xy 335.09245 -240.553979) (xy 335.069579 -240.597556)
			(xy 335.040014 -240.6369) (xy 335.004521 -240.670992) (xy 334.964018 -240.698948) (xy 334.919556 -240.720046)
			(xy 334.872285 -240.733738) (xy 334.82343 -240.73967) (xy 334.774255 -240.737689) (xy 334.726036 -240.727845)
			(xy 334.68002 -240.710393) (xy 334.637399 -240.685786) (xy 334.599278 -240.654661) (xy 334.566643 -240.617824)
			(xy 334.54034 -240.576228) (xy 334.521049 -240.530952) (xy 334.509272 -240.483168) (xy 334.505312 -240.434114)
			(xy 334.17637 -240.434114) (xy 334.175875 -240.458721) (xy 334.16798 -240.507298) (xy 334.152396 -240.553979)
			(xy 334.129525 -240.597556) (xy 334.09996 -240.6369) (xy 334.064467 -240.670992) (xy 334.023964 -240.698948)
			(xy 333.979502 -240.720046) (xy 333.932231 -240.733738) (xy 333.883376 -240.73967) (xy 333.834201 -240.737689)
			(xy 333.785982 -240.727845) (xy 333.739966 -240.710393) (xy 333.697345 -240.685786) (xy 333.659224 -240.654661)
			(xy 333.626589 -240.617824) (xy 333.600286 -240.576228) (xy 333.580995 -240.530952) (xy 333.569218 -240.483168)
			(xy 333.565258 -240.434114) (xy 333.236316 -240.434114) (xy 333.235821 -240.458721) (xy 333.227926 -240.507298)
			(xy 333.212342 -240.553979) (xy 333.189471 -240.597556) (xy 333.159906 -240.6369) (xy 333.124413 -240.670992)
			(xy 333.08391 -240.698948) (xy 333.039448 -240.720046) (xy 332.992177 -240.733738) (xy 332.943322 -240.73967)
			(xy 332.894147 -240.737689) (xy 332.845928 -240.727845) (xy 332.799912 -240.710393) (xy 332.757291 -240.685786)
			(xy 332.71917 -240.654661) (xy 332.686535 -240.617824) (xy 332.660232 -240.576228) (xy 332.640941 -240.530952)
			(xy 332.629164 -240.483168) (xy 332.625204 -240.434114) (xy 332.296516 -240.434114) (xy 332.296021 -240.458721)
			(xy 332.288126 -240.507298) (xy 332.272542 -240.553979) (xy 332.249671 -240.597556) (xy 332.220106 -240.6369)
			(xy 332.184613 -240.670992) (xy 332.14411 -240.698948) (xy 332.099648 -240.720046) (xy 332.052377 -240.733738)
			(xy 332.003522 -240.73967) (xy 331.954347 -240.737689) (xy 331.906128 -240.727845) (xy 331.860112 -240.710393)
			(xy 331.817491 -240.685786) (xy 331.77937 -240.654661) (xy 331.746735 -240.617824) (xy 331.720432 -240.576228)
			(xy 331.701141 -240.530952) (xy 331.689364 -240.483168) (xy 331.685404 -240.434114) (xy 331.459332 -240.434114)
			(xy 331.459332 -240.84026) (xy 331.459803 -240.849619) (xy 331.466567 -240.867077) (xy 331.47254 -240.874296)
			(xy 331.517498 -240.923826) (xy 331.520811 -240.927293) (xy 331.528482 -240.933047) (xy 331.532738 -240.935256)
			(xy 331.540612 -240.939066) (xy 331.550264 -240.940082) (xy 331.550518 -240.940082) (xy 331.575386 -240.942993)
			(xy 331.623765 -240.955877) (xy 331.669395 -240.976479) (xy 331.711054 -241.004246) (xy 331.747627 -241.038436)
			(xy 331.778135 -241.078132) (xy 331.801761 -241.122272) (xy 331.817871 -241.169674) (xy 331.826036 -241.219069)
			(xy 331.826036 -241.24412) (xy 332.155304 -241.24412) (xy 332.159264 -241.195066) (xy 332.171041 -241.147282)
			(xy 332.190332 -241.102006) (xy 332.216635 -241.06041) (xy 332.24927 -241.023573) (xy 332.287391 -240.992448)
			(xy 332.330012 -240.967841) (xy 332.376028 -240.950389) (xy 332.424247 -240.940545) (xy 332.473422 -240.938564)
			(xy 332.522277 -240.944496) (xy 332.569548 -240.958188) (xy 332.61401 -240.979286) (xy 332.654513 -241.007242)
			(xy 332.690006 -241.041334) (xy 332.719571 -241.080678) (xy 332.742442 -241.124255) (xy 332.758026 -241.170936)
			(xy 332.765921 -241.219513) (xy 332.766416 -241.24412) (xy 333.095358 -241.24412) (xy 333.099318 -241.195066)
			(xy 333.111095 -241.147282) (xy 333.130386 -241.102006) (xy 333.156689 -241.06041) (xy 333.189324 -241.023573)
			(xy 333.227445 -240.992448) (xy 333.270066 -240.967841) (xy 333.316082 -240.950389) (xy 333.364301 -240.940545)
			(xy 333.413476 -240.938564) (xy 333.462331 -240.944496) (xy 333.509602 -240.958188) (xy 333.554064 -240.979286)
			(xy 333.594567 -241.007242) (xy 333.63006 -241.041334) (xy 333.659625 -241.080678) (xy 333.682496 -241.124255)
			(xy 333.69808 -241.170936) (xy 333.705975 -241.219513) (xy 333.70647 -241.24412) (xy 334.035412 -241.24412)
			(xy 334.039372 -241.195066) (xy 334.051149 -241.147282) (xy 334.07044 -241.102006) (xy 334.096743 -241.06041)
			(xy 334.129378 -241.023573) (xy 334.167499 -240.992448) (xy 334.21012 -240.967841) (xy 334.256136 -240.950389)
			(xy 334.304355 -240.940545) (xy 334.35353 -240.938564) (xy 334.402385 -240.944496) (xy 334.449656 -240.958188)
			(xy 334.494118 -240.979286) (xy 334.534621 -241.007242) (xy 334.570114 -241.041334) (xy 334.599679 -241.080678)
			(xy 334.62255 -241.124255) (xy 334.638134 -241.170936) (xy 334.646029 -241.219513) (xy 334.646524 -241.24412)
			(xy 334.975212 -241.24412) (xy 334.979172 -241.195066) (xy 334.990949 -241.147282) (xy 335.01024 -241.102006)
			(xy 335.036543 -241.06041) (xy 335.069178 -241.023573) (xy 335.107299 -240.992448) (xy 335.14992 -240.967841)
			(xy 335.195936 -240.950389) (xy 335.244155 -240.940545) (xy 335.29333 -240.938564) (xy 335.342185 -240.944496)
			(xy 335.389456 -240.958188) (xy 335.433918 -240.979286) (xy 335.474421 -241.007242) (xy 335.509914 -241.041334)
			(xy 335.539479 -241.080678) (xy 335.56235 -241.124255) (xy 335.577934 -241.170936) (xy 335.585829 -241.219513)
			(xy 335.586324 -241.24412) (xy 335.915266 -241.24412) (xy 335.919226 -241.195066) (xy 335.931003 -241.147282)
			(xy 335.950294 -241.102006) (xy 335.976597 -241.06041) (xy 336.009232 -241.023573) (xy 336.047353 -240.992448)
			(xy 336.089974 -240.967841) (xy 336.13599 -240.950389) (xy 336.184209 -240.940545) (xy 336.233384 -240.938564)
			(xy 336.282239 -240.944496) (xy 336.32951 -240.958188) (xy 336.373972 -240.979286) (xy 336.414475 -241.007242)
			(xy 336.449968 -241.041334) (xy 336.479533 -241.080678) (xy 336.502404 -241.124255) (xy 336.517988 -241.170936)
			(xy 336.525883 -241.219513) (xy 336.526378 -241.24412) (xy 336.85532 -241.24412) (xy 336.85928 -241.195066)
			(xy 336.871057 -241.147282) (xy 336.890348 -241.102006) (xy 336.916651 -241.06041) (xy 336.949286 -241.023573)
			(xy 336.987407 -240.992448) (xy 337.030028 -240.967841) (xy 337.076044 -240.950389) (xy 337.124263 -240.940545)
			(xy 337.173438 -240.938564) (xy 337.222293 -240.944496) (xy 337.269564 -240.958188) (xy 337.314026 -240.979286)
			(xy 337.354529 -241.007242) (xy 337.390022 -241.041334) (xy 337.419587 -241.080678) (xy 337.442458 -241.124255)
			(xy 337.458042 -241.170936) (xy 337.465937 -241.219513) (xy 337.466432 -241.24412) (xy 337.795374 -241.24412)
			(xy 337.799334 -241.195066) (xy 337.811111 -241.147282) (xy 337.830402 -241.102006) (xy 337.856705 -241.06041)
			(xy 337.88934 -241.023573) (xy 337.927461 -240.992448) (xy 337.970082 -240.967841) (xy 338.016098 -240.950389)
			(xy 338.064317 -240.940545) (xy 338.113492 -240.938564) (xy 338.162347 -240.944496) (xy 338.209618 -240.958188)
			(xy 338.25408 -240.979286) (xy 338.294583 -241.007242) (xy 338.330076 -241.041334) (xy 338.359641 -241.080678)
			(xy 338.382512 -241.124255) (xy 338.398096 -241.170936) (xy 338.405991 -241.219513) (xy 338.406486 -241.24412)
			(xy 338.724743 -241.24412) (xy 338.728838 -241.193392) (xy 338.741017 -241.143978) (xy 338.760965 -241.097158)
			(xy 338.788166 -241.054144) (xy 338.821914 -241.01605) (xy 338.861336 -240.983863) (xy 338.90541 -240.958417)
			(xy 338.952996 -240.94037) (xy 339.00286 -240.93019) (xy 339.053712 -240.928141) (xy 339.104233 -240.934275)
			(xy 339.153117 -240.948435) (xy 339.199096 -240.970252) (xy 339.24098 -240.999162) (xy 339.277684 -241.034417)
			(xy 339.308257 -241.075103) (xy 339.331908 -241.120166) (xy 339.348024 -241.16844) (xy 339.356188 -241.218674)
			(xy 339.3567 -241.24412) (xy 339.664797 -241.24412) (xy 339.668892 -241.193392) (xy 339.681071 -241.143978)
			(xy 339.701019 -241.097158) (xy 339.72822 -241.054144) (xy 339.761968 -241.01605) (xy 339.80139 -240.983863)
			(xy 339.845464 -240.958417) (xy 339.89305 -240.94037) (xy 339.942914 -240.93019) (xy 339.993766 -240.928141)
			(xy 340.044287 -240.934275) (xy 340.093171 -240.948435) (xy 340.13915 -240.970252) (xy 340.181034 -240.999162)
			(xy 340.217738 -241.034417) (xy 340.248311 -241.075103) (xy 340.271962 -241.120166) (xy 340.288078 -241.16844)
			(xy 340.296242 -241.218674) (xy 340.296754 -241.24412) (xy 340.615282 -241.24412) (xy 340.619242 -241.195066)
			(xy 340.631019 -241.147282) (xy 340.65031 -241.102006) (xy 340.676613 -241.06041) (xy 340.709248 -241.023573)
			(xy 340.747369 -240.992448) (xy 340.78999 -240.967841) (xy 340.836006 -240.950389) (xy 340.884225 -240.940545)
			(xy 340.9334 -240.938564) (xy 340.982255 -240.944496) (xy 341.029526 -240.958188) (xy 341.073988 -240.979286)
			(xy 341.114491 -241.007242) (xy 341.149984 -241.041334) (xy 341.179549 -241.080678) (xy 341.20242 -241.124255)
			(xy 341.218004 -241.170936) (xy 341.225899 -241.219513) (xy 341.226394 -241.24412) (xy 341.544905 -241.24412)
			(xy 341.549 -241.193392) (xy 341.561179 -241.143978) (xy 341.581127 -241.097158) (xy 341.608328 -241.054144)
			(xy 341.642076 -241.01605) (xy 341.681498 -240.983863) (xy 341.725572 -240.958417) (xy 341.773158 -240.94037)
			(xy 341.823022 -240.93019) (xy 341.873874 -240.928141) (xy 341.924395 -240.934275) (xy 341.973279 -240.948435)
			(xy 342.019258 -240.970252) (xy 342.061142 -240.999162) (xy 342.097846 -241.034417) (xy 342.128419 -241.075103)
			(xy 342.15207 -241.120166) (xy 342.168186 -241.16844) (xy 342.17635 -241.218674) (xy 342.176862 -241.24412)
			(xy 342.49539 -241.24412) (xy 342.49935 -241.195066) (xy 342.511127 -241.147282) (xy 342.530418 -241.102006)
			(xy 342.556721 -241.06041) (xy 342.589356 -241.023573) (xy 342.627477 -240.992448) (xy 342.670098 -240.967841)
			(xy 342.716114 -240.950389) (xy 342.764333 -240.940545) (xy 342.813508 -240.938564) (xy 342.862363 -240.944496)
			(xy 342.909634 -240.958188) (xy 342.954096 -240.979286) (xy 342.994599 -241.007242) (xy 343.030092 -241.041334)
			(xy 343.059657 -241.080678) (xy 343.082528 -241.124255) (xy 343.098112 -241.170936) (xy 343.106007 -241.219513)
			(xy 343.106502 -241.24412) (xy 343.424759 -241.24412) (xy 343.428854 -241.193392) (xy 343.441033 -241.143978)
			(xy 343.460981 -241.097158) (xy 343.488182 -241.054144) (xy 343.52193 -241.01605) (xy 343.561352 -240.983863)
			(xy 343.605426 -240.958417) (xy 343.653012 -240.94037) (xy 343.702876 -240.93019) (xy 343.753728 -240.928141)
			(xy 343.804249 -240.934275) (xy 343.853133 -240.948435) (xy 343.899112 -240.970252) (xy 343.940996 -240.999162)
			(xy 343.9777 -241.034417) (xy 344.008273 -241.075103) (xy 344.031924 -241.120166) (xy 344.04804 -241.16844)
			(xy 344.056204 -241.218674) (xy 344.056716 -241.24412) (xy 344.056204 -241.269566) (xy 344.04804 -241.3198)
			(xy 344.031924 -241.368074) (xy 344.008273 -241.413137) (xy 343.9777 -241.453823) (xy 343.940996 -241.489078)
			(xy 343.899112 -241.517988) (xy 343.853133 -241.539805) (xy 343.804249 -241.553965) (xy 343.753728 -241.560099)
			(xy 343.702876 -241.55805) (xy 343.653012 -241.54787) (xy 343.605426 -241.529823) (xy 343.561352 -241.504377)
			(xy 343.52193 -241.47219) (xy 343.488182 -241.434096) (xy 343.460981 -241.391082) (xy 343.441033 -241.344262)
			(xy 343.428854 -241.294848) (xy 343.424759 -241.24412) (xy 343.106502 -241.24412) (xy 343.106007 -241.268727)
			(xy 343.098112 -241.317304) (xy 343.082528 -241.363985) (xy 343.059657 -241.407562) (xy 343.030092 -241.446906)
			(xy 342.994599 -241.480998) (xy 342.954096 -241.508954) (xy 342.909634 -241.530052) (xy 342.862363 -241.543744)
			(xy 342.813508 -241.549676) (xy 342.764333 -241.547695) (xy 342.716114 -241.537851) (xy 342.670098 -241.520399)
			(xy 342.627477 -241.495792) (xy 342.589356 -241.464667) (xy 342.556721 -241.42783) (xy 342.530418 -241.386234)
			(xy 342.511127 -241.340958) (xy 342.49935 -241.293174) (xy 342.49539 -241.24412) (xy 342.176862 -241.24412)
			(xy 342.17635 -241.269566) (xy 342.168186 -241.3198) (xy 342.15207 -241.368074) (xy 342.128419 -241.413137)
			(xy 342.097846 -241.453823) (xy 342.061142 -241.489078) (xy 342.019258 -241.517988) (xy 341.973279 -241.539805)
			(xy 341.924395 -241.553965) (xy 341.873874 -241.560099) (xy 341.823022 -241.55805) (xy 341.773158 -241.54787)
			(xy 341.725572 -241.529823) (xy 341.681498 -241.504377) (xy 341.642076 -241.47219) (xy 341.608328 -241.434096)
			(xy 341.581127 -241.391082) (xy 341.561179 -241.344262) (xy 341.549 -241.294848) (xy 341.544905 -241.24412)
			(xy 341.226394 -241.24412) (xy 341.225899 -241.268727) (xy 341.218004 -241.317304) (xy 341.20242 -241.363985)
			(xy 341.179549 -241.407562) (xy 341.149984 -241.446906) (xy 341.114491 -241.480998) (xy 341.073988 -241.508954)
			(xy 341.029526 -241.530052) (xy 340.982255 -241.543744) (xy 340.9334 -241.549676) (xy 340.884225 -241.547695)
			(xy 340.836006 -241.537851) (xy 340.78999 -241.520399) (xy 340.747369 -241.495792) (xy 340.709248 -241.464667)
			(xy 340.676613 -241.42783) (xy 340.65031 -241.386234) (xy 340.631019 -241.340958) (xy 340.619242 -241.293174)
			(xy 340.615282 -241.24412) (xy 340.296754 -241.24412) (xy 340.296242 -241.269566) (xy 340.288078 -241.3198)
			(xy 340.271962 -241.368074) (xy 340.248311 -241.413137) (xy 340.217738 -241.453823) (xy 340.181034 -241.489078)
			(xy 340.13915 -241.517988) (xy 340.093171 -241.539805) (xy 340.044287 -241.553965) (xy 339.993766 -241.560099)
			(xy 339.942914 -241.55805) (xy 339.89305 -241.54787) (xy 339.845464 -241.529823) (xy 339.80139 -241.504377)
			(xy 339.761968 -241.47219) (xy 339.72822 -241.434096) (xy 339.701019 -241.391082) (xy 339.681071 -241.344262)
			(xy 339.668892 -241.294848) (xy 339.664797 -241.24412) (xy 339.3567 -241.24412) (xy 339.356188 -241.269566)
			(xy 339.348024 -241.3198) (xy 339.331908 -241.368074) (xy 339.308257 -241.413137) (xy 339.277684 -241.453823)
			(xy 339.24098 -241.489078) (xy 339.199096 -241.517988) (xy 339.153117 -241.539805) (xy 339.104233 -241.553965)
			(xy 339.053712 -241.560099) (xy 339.00286 -241.55805) (xy 338.952996 -241.54787) (xy 338.90541 -241.529823)
			(xy 338.861336 -241.504377) (xy 338.821914 -241.47219) (xy 338.788166 -241.434096) (xy 338.760965 -241.391082)
			(xy 338.741017 -241.344262) (xy 338.728838 -241.294848) (xy 338.724743 -241.24412) (xy 338.406486 -241.24412)
			(xy 338.405991 -241.268727) (xy 338.398096 -241.317304) (xy 338.382512 -241.363985) (xy 338.359641 -241.407562)
			(xy 338.330076 -241.446906) (xy 338.294583 -241.480998) (xy 338.25408 -241.508954) (xy 338.209618 -241.530052)
			(xy 338.162347 -241.543744) (xy 338.113492 -241.549676) (xy 338.064317 -241.547695) (xy 338.016098 -241.537851)
			(xy 337.970082 -241.520399) (xy 337.927461 -241.495792) (xy 337.88934 -241.464667) (xy 337.856705 -241.42783)
			(xy 337.830402 -241.386234) (xy 337.811111 -241.340958) (xy 337.799334 -241.293174) (xy 337.795374 -241.24412)
			(xy 337.466432 -241.24412) (xy 337.465937 -241.268727) (xy 337.458042 -241.317304) (xy 337.442458 -241.363985)
			(xy 337.419587 -241.407562) (xy 337.390022 -241.446906) (xy 337.354529 -241.480998) (xy 337.314026 -241.508954)
			(xy 337.269564 -241.530052) (xy 337.222293 -241.543744) (xy 337.173438 -241.549676) (xy 337.124263 -241.547695)
			(xy 337.076044 -241.537851) (xy 337.030028 -241.520399) (xy 336.987407 -241.495792) (xy 336.949286 -241.464667)
			(xy 336.916651 -241.42783) (xy 336.890348 -241.386234) (xy 336.871057 -241.340958) (xy 336.85928 -241.293174)
			(xy 336.85532 -241.24412) (xy 336.526378 -241.24412) (xy 336.525883 -241.268727) (xy 336.517988 -241.317304)
			(xy 336.502404 -241.363985) (xy 336.479533 -241.407562) (xy 336.449968 -241.446906) (xy 336.414475 -241.480998)
			(xy 336.373972 -241.508954) (xy 336.32951 -241.530052) (xy 336.282239 -241.543744) (xy 336.233384 -241.549676)
			(xy 336.184209 -241.547695) (xy 336.13599 -241.537851) (xy 336.089974 -241.520399) (xy 336.047353 -241.495792)
			(xy 336.009232 -241.464667) (xy 335.976597 -241.42783) (xy 335.950294 -241.386234) (xy 335.931003 -241.340958)
			(xy 335.919226 -241.293174) (xy 335.915266 -241.24412) (xy 335.586324 -241.24412) (xy 335.585829 -241.268727)
			(xy 335.577934 -241.317304) (xy 335.56235 -241.363985) (xy 335.539479 -241.407562) (xy 335.509914 -241.446906)
			(xy 335.474421 -241.480998) (xy 335.433918 -241.508954) (xy 335.389456 -241.530052) (xy 335.342185 -241.543744)
			(xy 335.29333 -241.549676) (xy 335.244155 -241.547695) (xy 335.195936 -241.537851) (xy 335.14992 -241.520399)
			(xy 335.107299 -241.495792) (xy 335.069178 -241.464667) (xy 335.036543 -241.42783) (xy 335.01024 -241.386234)
			(xy 334.990949 -241.340958) (xy 334.979172 -241.293174) (xy 334.975212 -241.24412) (xy 334.646524 -241.24412)
			(xy 334.646029 -241.268727) (xy 334.638134 -241.317304) (xy 334.62255 -241.363985) (xy 334.599679 -241.407562)
			(xy 334.570114 -241.446906) (xy 334.534621 -241.480998) (xy 334.494118 -241.508954) (xy 334.449656 -241.530052)
			(xy 334.402385 -241.543744) (xy 334.35353 -241.549676) (xy 334.304355 -241.547695) (xy 334.256136 -241.537851)
			(xy 334.21012 -241.520399) (xy 334.167499 -241.495792) (xy 334.129378 -241.464667) (xy 334.096743 -241.42783)
			(xy 334.07044 -241.386234) (xy 334.051149 -241.340958) (xy 334.039372 -241.293174) (xy 334.035412 -241.24412)
			(xy 333.70647 -241.24412) (xy 333.705975 -241.268727) (xy 333.69808 -241.317304) (xy 333.682496 -241.363985)
			(xy 333.659625 -241.407562) (xy 333.63006 -241.446906) (xy 333.594567 -241.480998) (xy 333.554064 -241.508954)
			(xy 333.509602 -241.530052) (xy 333.462331 -241.543744) (xy 333.413476 -241.549676) (xy 333.364301 -241.547695)
			(xy 333.316082 -241.537851) (xy 333.270066 -241.520399) (xy 333.227445 -241.495792) (xy 333.189324 -241.464667)
			(xy 333.156689 -241.42783) (xy 333.130386 -241.386234) (xy 333.111095 -241.340958) (xy 333.099318 -241.293174)
			(xy 333.095358 -241.24412) (xy 332.766416 -241.24412) (xy 332.765921 -241.268727) (xy 332.758026 -241.317304)
			(xy 332.742442 -241.363985) (xy 332.719571 -241.407562) (xy 332.690006 -241.446906) (xy 332.654513 -241.480998)
			(xy 332.61401 -241.508954) (xy 332.569548 -241.530052) (xy 332.522277 -241.543744) (xy 332.473422 -241.549676)
			(xy 332.424247 -241.547695) (xy 332.376028 -241.537851) (xy 332.330012 -241.520399) (xy 332.287391 -241.495792)
			(xy 332.24927 -241.464667) (xy 332.216635 -241.42783) (xy 332.190332 -241.386234) (xy 332.171041 -241.340958)
			(xy 332.159264 -241.293174) (xy 332.155304 -241.24412) (xy 331.826036 -241.24412) (xy 331.826036 -241.269135)
			(xy 331.81787 -241.318529) (xy 331.801759 -241.365931) (xy 331.778133 -241.410071) (xy 331.747625 -241.449767)
			(xy 331.711051 -241.483956) (xy 331.669391 -241.511723) (xy 331.623761 -241.532324) (xy 331.575382 -241.545208)
			(xy 331.550518 -241.548158) (xy 331.550264 -241.548158) (xy 331.540612 -241.549174) (xy 331.532738 -241.552984)
			(xy 331.528475 -241.555184) (xy 331.520796 -241.560931) (xy 331.517498 -241.564414) (xy 331.47254 -241.613944)
			(xy 331.466486 -241.621116) (xy 331.459703 -241.638602) (xy 331.459332 -241.64798) (xy 331.459332 -242.054126)
			(xy 331.685404 -242.054126) (xy 331.689364 -242.005072) (xy 331.701141 -241.957288) (xy 331.720432 -241.912012)
			(xy 331.746735 -241.870416) (xy 331.77937 -241.833579) (xy 331.817491 -241.802454) (xy 331.860112 -241.777847)
			(xy 331.906128 -241.760395) (xy 331.954347 -241.750551) (xy 332.003522 -241.74857) (xy 332.052377 -241.754502)
			(xy 332.099648 -241.768194) (xy 332.14411 -241.789292) (xy 332.184613 -241.817248) (xy 332.220106 -241.85134)
			(xy 332.249671 -241.890684) (xy 332.272542 -241.934261) (xy 332.288126 -241.980942) (xy 332.296021 -242.029519)
			(xy 332.296516 -242.054126) (xy 332.625204 -242.054126) (xy 332.629164 -242.005072) (xy 332.640941 -241.957288)
			(xy 332.660232 -241.912012) (xy 332.686535 -241.870416) (xy 332.71917 -241.833579) (xy 332.757291 -241.802454)
			(xy 332.799912 -241.777847) (xy 332.845928 -241.760395) (xy 332.894147 -241.750551) (xy 332.943322 -241.74857)
			(xy 332.992177 -241.754502) (xy 333.039448 -241.768194) (xy 333.08391 -241.789292) (xy 333.124413 -241.817248)
			(xy 333.159906 -241.85134) (xy 333.189471 -241.890684) (xy 333.212342 -241.934261) (xy 333.227926 -241.980942)
			(xy 333.235821 -242.029519) (xy 333.236316 -242.054126) (xy 333.565258 -242.054126) (xy 333.569218 -242.005072)
			(xy 333.580995 -241.957288) (xy 333.600286 -241.912012) (xy 333.626589 -241.870416) (xy 333.659224 -241.833579)
			(xy 333.697345 -241.802454) (xy 333.739966 -241.777847) (xy 333.785982 -241.760395) (xy 333.834201 -241.750551)
			(xy 333.883376 -241.74857) (xy 333.932231 -241.754502) (xy 333.979502 -241.768194) (xy 334.023964 -241.789292)
			(xy 334.064467 -241.817248) (xy 334.09996 -241.85134) (xy 334.129525 -241.890684) (xy 334.152396 -241.934261)
			(xy 334.16798 -241.980942) (xy 334.175875 -242.029519) (xy 334.17637 -242.054126) (xy 335.445366 -242.054126)
			(xy 335.449326 -242.005072) (xy 335.461103 -241.957288) (xy 335.480394 -241.912012) (xy 335.506697 -241.870416)
			(xy 335.539332 -241.833579) (xy 335.577453 -241.802454) (xy 335.620074 -241.777847) (xy 335.66609 -241.760395)
			(xy 335.714309 -241.750551) (xy 335.763484 -241.74857) (xy 335.812339 -241.754502) (xy 335.85961 -241.768194)
			(xy 335.904072 -241.789292) (xy 335.944575 -241.817248) (xy 335.980068 -241.85134) (xy 336.009633 -241.890684)
			(xy 336.032504 -241.934261) (xy 336.048088 -241.980942) (xy 336.055983 -242.029519) (xy 336.056478 -242.054126)
			(xy 336.38542 -242.054126) (xy 336.38938 -242.005072) (xy 336.401157 -241.957288) (xy 336.420448 -241.912012)
			(xy 336.446751 -241.870416) (xy 336.479386 -241.833579) (xy 336.517507 -241.802454) (xy 336.560128 -241.777847)
			(xy 336.606144 -241.760395) (xy 336.654363 -241.750551) (xy 336.703538 -241.74857) (xy 336.752393 -241.754502)
			(xy 336.799664 -241.768194) (xy 336.844126 -241.789292) (xy 336.884629 -241.817248) (xy 336.920122 -241.85134)
			(xy 336.949687 -241.890684) (xy 336.972558 -241.934261) (xy 336.988142 -241.980942) (xy 336.996037 -242.029519)
			(xy 336.996532 -242.054126) (xy 337.32522 -242.054126) (xy 337.32918 -242.005072) (xy 337.340957 -241.957288)
			(xy 337.360248 -241.912012) (xy 337.386551 -241.870416) (xy 337.419186 -241.833579) (xy 337.457307 -241.802454)
			(xy 337.499928 -241.777847) (xy 337.545944 -241.760395) (xy 337.594163 -241.750551) (xy 337.643338 -241.74857)
			(xy 337.692193 -241.754502) (xy 337.739464 -241.768194) (xy 337.783926 -241.789292) (xy 337.824429 -241.817248)
			(xy 337.859922 -241.85134) (xy 337.889487 -241.890684) (xy 337.912358 -241.934261) (xy 337.927942 -241.980942)
			(xy 337.935837 -242.029519) (xy 337.936332 -242.054126) (xy 338.254843 -242.054126) (xy 338.258938 -242.003398)
			(xy 338.271117 -241.953984) (xy 338.291065 -241.907164) (xy 338.318266 -241.86415) (xy 338.352014 -241.826056)
			(xy 338.391436 -241.793869) (xy 338.43551 -241.768423) (xy 338.483096 -241.750376) (xy 338.53296 -241.740196)
			(xy 338.583812 -241.738147) (xy 338.634333 -241.744281) (xy 338.683217 -241.758441) (xy 338.729196 -241.780258)
			(xy 338.77108 -241.809168) (xy 338.807784 -241.844423) (xy 338.838357 -241.885109) (xy 338.862008 -241.930172)
			(xy 338.878124 -241.978446) (xy 338.886288 -242.02868) (xy 338.8868 -242.054126) (xy 339.205328 -242.054126)
			(xy 339.209288 -242.005072) (xy 339.221065 -241.957288) (xy 339.240356 -241.912012) (xy 339.266659 -241.870416)
			(xy 339.299294 -241.833579) (xy 339.337415 -241.802454) (xy 339.380036 -241.777847) (xy 339.426052 -241.760395)
			(xy 339.474271 -241.750551) (xy 339.523446 -241.74857) (xy 339.572301 -241.754502) (xy 339.619572 -241.768194)
			(xy 339.664034 -241.789292) (xy 339.704537 -241.817248) (xy 339.74003 -241.85134) (xy 339.769595 -241.890684)
			(xy 339.792466 -241.934261) (xy 339.80805 -241.980942) (xy 339.815945 -242.029519) (xy 339.81644 -242.054126)
			(xy 340.134951 -242.054126) (xy 340.139046 -242.003398) (xy 340.151225 -241.953984) (xy 340.171173 -241.907164)
			(xy 340.198374 -241.86415) (xy 340.232122 -241.826056) (xy 340.271544 -241.793869) (xy 340.315618 -241.768423)
			(xy 340.363204 -241.750376) (xy 340.413068 -241.740196) (xy 340.46392 -241.738147) (xy 340.514441 -241.744281)
			(xy 340.563325 -241.758441) (xy 340.609304 -241.780258) (xy 340.651188 -241.809168) (xy 340.687892 -241.844423)
			(xy 340.718465 -241.885109) (xy 340.742116 -241.930172) (xy 340.758232 -241.978446) (xy 340.766396 -242.02868)
			(xy 340.766908 -242.054126) (xy 342.014805 -242.054126) (xy 342.0189 -242.003398) (xy 342.031079 -241.953984)
			(xy 342.051027 -241.907164) (xy 342.078228 -241.86415) (xy 342.111976 -241.826056) (xy 342.151398 -241.793869)
			(xy 342.195472 -241.768423) (xy 342.243058 -241.750376) (xy 342.292922 -241.740196) (xy 342.343774 -241.738147)
			(xy 342.394295 -241.744281) (xy 342.443179 -241.758441) (xy 342.489158 -241.780258) (xy 342.531042 -241.809168)
			(xy 342.567746 -241.844423) (xy 342.598319 -241.885109) (xy 342.62197 -241.930172) (xy 342.638086 -241.978446)
			(xy 342.64625 -242.02868) (xy 342.646762 -242.054126) (xy 342.954859 -242.054126) (xy 342.958954 -242.003398)
			(xy 342.971133 -241.953984) (xy 342.991081 -241.907164) (xy 343.018282 -241.86415) (xy 343.05203 -241.826056)
			(xy 343.091452 -241.793869) (xy 343.135526 -241.768423) (xy 343.183112 -241.750376) (xy 343.232976 -241.740196)
			(xy 343.283828 -241.738147) (xy 343.334349 -241.744281) (xy 343.383233 -241.758441) (xy 343.429212 -241.780258)
			(xy 343.471096 -241.809168) (xy 343.5078 -241.844423) (xy 343.538373 -241.885109) (xy 343.562024 -241.930172)
			(xy 343.57814 -241.978446) (xy 343.586304 -242.02868) (xy 343.586816 -242.054126) (xy 343.586304 -242.079572)
			(xy 343.57814 -242.129806) (xy 343.562024 -242.17808) (xy 343.538373 -242.223143) (xy 343.5078 -242.263829)
			(xy 343.471096 -242.299084) (xy 343.429212 -242.327994) (xy 343.383233 -242.349811) (xy 343.334349 -242.363971)
			(xy 343.283828 -242.370105) (xy 343.232976 -242.368056) (xy 343.183112 -242.357876) (xy 343.135526 -242.339829)
			(xy 343.091452 -242.314383) (xy 343.05203 -242.282196) (xy 343.018282 -242.244102) (xy 342.991081 -242.201088)
			(xy 342.971133 -242.154268) (xy 342.958954 -242.104854) (xy 342.954859 -242.054126) (xy 342.646762 -242.054126)
			(xy 342.64625 -242.079572) (xy 342.638086 -242.129806) (xy 342.62197 -242.17808) (xy 342.598319 -242.223143)
			(xy 342.567746 -242.263829) (xy 342.531042 -242.299084) (xy 342.489158 -242.327994) (xy 342.443179 -242.349811)
			(xy 342.394295 -242.363971) (xy 342.343774 -242.370105) (xy 342.292922 -242.368056) (xy 342.243058 -242.357876)
			(xy 342.195472 -242.339829) (xy 342.151398 -242.314383) (xy 342.111976 -242.282196) (xy 342.078228 -242.244102)
			(xy 342.051027 -242.201088) (xy 342.031079 -242.154268) (xy 342.0189 -242.104854) (xy 342.014805 -242.054126)
			(xy 340.766908 -242.054126) (xy 340.766396 -242.079572) (xy 340.758232 -242.129806) (xy 340.742116 -242.17808)
			(xy 340.718465 -242.223143) (xy 340.687892 -242.263829) (xy 340.651188 -242.299084) (xy 340.609304 -242.327994)
			(xy 340.563325 -242.349811) (xy 340.514441 -242.363971) (xy 340.46392 -242.370105) (xy 340.413068 -242.368056)
			(xy 340.363204 -242.357876) (xy 340.315618 -242.339829) (xy 340.271544 -242.314383) (xy 340.232122 -242.282196)
			(xy 340.198374 -242.244102) (xy 340.171173 -242.201088) (xy 340.151225 -242.154268) (xy 340.139046 -242.104854)
			(xy 340.134951 -242.054126) (xy 339.81644 -242.054126) (xy 339.815945 -242.078733) (xy 339.80805 -242.12731)
			(xy 339.792466 -242.173991) (xy 339.769595 -242.217568) (xy 339.74003 -242.256912) (xy 339.704537 -242.291004)
			(xy 339.664034 -242.31896) (xy 339.619572 -242.340058) (xy 339.572301 -242.35375) (xy 339.523446 -242.359682)
			(xy 339.474271 -242.357701) (xy 339.426052 -242.347857) (xy 339.380036 -242.330405) (xy 339.337415 -242.305798)
			(xy 339.299294 -242.274673) (xy 339.266659 -242.237836) (xy 339.240356 -242.19624) (xy 339.221065 -242.150964)
			(xy 339.209288 -242.10318) (xy 339.205328 -242.054126) (xy 338.8868 -242.054126) (xy 338.886288 -242.079572)
			(xy 338.878124 -242.129806) (xy 338.862008 -242.17808) (xy 338.838357 -242.223143) (xy 338.807784 -242.263829)
			(xy 338.77108 -242.299084) (xy 338.729196 -242.327994) (xy 338.683217 -242.349811) (xy 338.634333 -242.363971)
			(xy 338.583812 -242.370105) (xy 338.53296 -242.368056) (xy 338.483096 -242.357876) (xy 338.43551 -242.339829)
			(xy 338.391436 -242.314383) (xy 338.352014 -242.282196) (xy 338.318266 -242.244102) (xy 338.291065 -242.201088)
			(xy 338.271117 -242.154268) (xy 338.258938 -242.104854) (xy 338.254843 -242.054126) (xy 337.936332 -242.054126)
			(xy 337.935837 -242.078733) (xy 337.927942 -242.12731) (xy 337.912358 -242.173991) (xy 337.889487 -242.217568)
			(xy 337.859922 -242.256912) (xy 337.824429 -242.291004) (xy 337.783926 -242.31896) (xy 337.739464 -242.340058)
			(xy 337.692193 -242.35375) (xy 337.643338 -242.359682) (xy 337.594163 -242.357701) (xy 337.545944 -242.347857)
			(xy 337.499928 -242.330405) (xy 337.457307 -242.305798) (xy 337.419186 -242.274673) (xy 337.386551 -242.237836)
			(xy 337.360248 -242.19624) (xy 337.340957 -242.150964) (xy 337.32918 -242.10318) (xy 337.32522 -242.054126)
			(xy 336.996532 -242.054126) (xy 336.996037 -242.078733) (xy 336.988142 -242.12731) (xy 336.972558 -242.173991)
			(xy 336.949687 -242.217568) (xy 336.920122 -242.256912) (xy 336.884629 -242.291004) (xy 336.844126 -242.31896)
			(xy 336.799664 -242.340058) (xy 336.752393 -242.35375) (xy 336.703538 -242.359682) (xy 336.654363 -242.357701)
			(xy 336.606144 -242.347857) (xy 336.560128 -242.330405) (xy 336.517507 -242.305798) (xy 336.479386 -242.274673)
			(xy 336.446751 -242.237836) (xy 336.420448 -242.19624) (xy 336.401157 -242.150964) (xy 336.38938 -242.10318)
			(xy 336.38542 -242.054126) (xy 336.056478 -242.054126) (xy 336.055983 -242.078733) (xy 336.048088 -242.12731)
			(xy 336.032504 -242.173991) (xy 336.009633 -242.217568) (xy 335.980068 -242.256912) (xy 335.944575 -242.291004)
			(xy 335.904072 -242.31896) (xy 335.85961 -242.340058) (xy 335.812339 -242.35375) (xy 335.763484 -242.359682)
			(xy 335.714309 -242.357701) (xy 335.66609 -242.347857) (xy 335.620074 -242.330405) (xy 335.577453 -242.305798)
			(xy 335.539332 -242.274673) (xy 335.506697 -242.237836) (xy 335.480394 -242.19624) (xy 335.461103 -242.150964)
			(xy 335.449326 -242.10318) (xy 335.445366 -242.054126) (xy 334.17637 -242.054126) (xy 334.175875 -242.078733)
			(xy 334.16798 -242.12731) (xy 334.152396 -242.173991) (xy 334.129525 -242.217568) (xy 334.09996 -242.256912)
			(xy 334.064467 -242.291004) (xy 334.023964 -242.31896) (xy 333.979502 -242.340058) (xy 333.932231 -242.35375)
			(xy 333.883376 -242.359682) (xy 333.834201 -242.357701) (xy 333.785982 -242.347857) (xy 333.739966 -242.330405)
			(xy 333.697345 -242.305798) (xy 333.659224 -242.274673) (xy 333.626589 -242.237836) (xy 333.600286 -242.19624)
			(xy 333.580995 -242.150964) (xy 333.569218 -242.10318) (xy 333.565258 -242.054126) (xy 333.236316 -242.054126)
			(xy 333.235821 -242.078733) (xy 333.227926 -242.12731) (xy 333.212342 -242.173991) (xy 333.189471 -242.217568)
			(xy 333.159906 -242.256912) (xy 333.124413 -242.291004) (xy 333.08391 -242.31896) (xy 333.039448 -242.340058)
			(xy 332.992177 -242.35375) (xy 332.943322 -242.359682) (xy 332.894147 -242.357701) (xy 332.845928 -242.347857)
			(xy 332.799912 -242.330405) (xy 332.757291 -242.305798) (xy 332.71917 -242.274673) (xy 332.686535 -242.237836)
			(xy 332.660232 -242.19624) (xy 332.640941 -242.150964) (xy 332.629164 -242.10318) (xy 332.625204 -242.054126)
			(xy 332.296516 -242.054126) (xy 332.296021 -242.078733) (xy 332.288126 -242.12731) (xy 332.272542 -242.173991)
			(xy 332.249671 -242.217568) (xy 332.220106 -242.256912) (xy 332.184613 -242.291004) (xy 332.14411 -242.31896)
			(xy 332.099648 -242.340058) (xy 332.052377 -242.35375) (xy 332.003522 -242.359682) (xy 331.954347 -242.357701)
			(xy 331.906128 -242.347857) (xy 331.860112 -242.330405) (xy 331.817491 -242.305798) (xy 331.77937 -242.274673)
			(xy 331.746735 -242.237836) (xy 331.720432 -242.19624) (xy 331.701141 -242.150964) (xy 331.689364 -242.10318)
			(xy 331.685404 -242.054126) (xy 331.459332 -242.054126) (xy 331.459332 -242.460272) (xy 331.459805 -242.46963)
			(xy 331.466572 -242.487086) (xy 331.47254 -242.494308) (xy 331.517498 -242.543838) (xy 331.520811 -242.547305)
			(xy 331.528483 -242.553057) (xy 331.532738 -242.555268) (xy 331.540612 -242.559078) (xy 331.550264 -242.560094)
			(xy 331.550518 -242.560094) (xy 331.575385 -242.563005) (xy 331.623762 -242.575889) (xy 331.66939 -242.59649)
			(xy 331.711048 -242.624256) (xy 331.747619 -242.658445) (xy 331.778126 -242.698139) (xy 331.80175 -242.742278)
			(xy 331.81786 -242.789678) (xy 331.826024 -242.839071) (xy 331.826024 -242.864132) (xy 332.155304 -242.864132)
			(xy 332.159264 -242.815078) (xy 332.171041 -242.767294) (xy 332.190332 -242.722018) (xy 332.216635 -242.680422)
			(xy 332.24927 -242.643585) (xy 332.287391 -242.61246) (xy 332.330012 -242.587853) (xy 332.376028 -242.570401)
			(xy 332.424247 -242.560557) (xy 332.473422 -242.558576) (xy 332.522277 -242.564508) (xy 332.569548 -242.5782)
			(xy 332.61401 -242.599298) (xy 332.654513 -242.627254) (xy 332.690006 -242.661346) (xy 332.719571 -242.70069)
			(xy 332.742442 -242.744267) (xy 332.758026 -242.790948) (xy 332.765921 -242.839525) (xy 332.766416 -242.864132)
			(xy 333.095358 -242.864132) (xy 333.099318 -242.815078) (xy 333.111095 -242.767294) (xy 333.130386 -242.722018)
			(xy 333.156689 -242.680422) (xy 333.189324 -242.643585) (xy 333.227445 -242.61246) (xy 333.270066 -242.587853)
			(xy 333.316082 -242.570401) (xy 333.364301 -242.560557) (xy 333.413476 -242.558576) (xy 333.462331 -242.564508)
			(xy 333.509602 -242.5782) (xy 333.554064 -242.599298) (xy 333.594567 -242.627254) (xy 333.63006 -242.661346)
			(xy 333.659625 -242.70069) (xy 333.682496 -242.744267) (xy 333.69808 -242.790948) (xy 333.705975 -242.839525)
			(xy 333.70647 -242.864132) (xy 334.035412 -242.864132) (xy 334.039372 -242.815078) (xy 334.051149 -242.767294)
			(xy 334.07044 -242.722018) (xy 334.096743 -242.680422) (xy 334.129378 -242.643585) (xy 334.167499 -242.61246)
			(xy 334.21012 -242.587853) (xy 334.256136 -242.570401) (xy 334.304355 -242.560557) (xy 334.35353 -242.558576)
			(xy 334.402385 -242.564508) (xy 334.449656 -242.5782) (xy 334.494118 -242.599298) (xy 334.534621 -242.627254)
			(xy 334.570114 -242.661346) (xy 334.599679 -242.70069) (xy 334.62255 -242.744267) (xy 334.638134 -242.790948)
			(xy 334.646029 -242.839525) (xy 334.646524 -242.864132) (xy 334.975212 -242.864132) (xy 334.979172 -242.815078)
			(xy 334.990949 -242.767294) (xy 335.01024 -242.722018) (xy 335.036543 -242.680422) (xy 335.069178 -242.643585)
			(xy 335.107299 -242.61246) (xy 335.14992 -242.587853) (xy 335.195936 -242.570401) (xy 335.244155 -242.560557)
			(xy 335.29333 -242.558576) (xy 335.342185 -242.564508) (xy 335.389456 -242.5782) (xy 335.433918 -242.599298)
			(xy 335.474421 -242.627254) (xy 335.509914 -242.661346) (xy 335.539479 -242.70069) (xy 335.56235 -242.744267)
			(xy 335.577934 -242.790948) (xy 335.585829 -242.839525) (xy 335.586324 -242.864132) (xy 335.915266 -242.864132)
			(xy 335.919226 -242.815078) (xy 335.931003 -242.767294) (xy 335.950294 -242.722018) (xy 335.976597 -242.680422)
			(xy 336.009232 -242.643585) (xy 336.047353 -242.61246) (xy 336.089974 -242.587853) (xy 336.13599 -242.570401)
			(xy 336.184209 -242.560557) (xy 336.233384 -242.558576) (xy 336.282239 -242.564508) (xy 336.32951 -242.5782)
			(xy 336.373972 -242.599298) (xy 336.414475 -242.627254) (xy 336.449968 -242.661346) (xy 336.479533 -242.70069)
			(xy 336.502404 -242.744267) (xy 336.517988 -242.790948) (xy 336.525883 -242.839525) (xy 336.526378 -242.864132)
			(xy 336.85532 -242.864132) (xy 336.85928 -242.815078) (xy 336.871057 -242.767294) (xy 336.890348 -242.722018)
			(xy 336.916651 -242.680422) (xy 336.949286 -242.643585) (xy 336.987407 -242.61246) (xy 337.030028 -242.587853)
			(xy 337.076044 -242.570401) (xy 337.124263 -242.560557) (xy 337.173438 -242.558576) (xy 337.222293 -242.564508)
			(xy 337.269564 -242.5782) (xy 337.314026 -242.599298) (xy 337.354529 -242.627254) (xy 337.390022 -242.661346)
			(xy 337.419587 -242.70069) (xy 337.442458 -242.744267) (xy 337.458042 -242.790948) (xy 337.465937 -242.839525)
			(xy 337.466432 -242.864132) (xy 337.795374 -242.864132) (xy 337.799334 -242.815078) (xy 337.811111 -242.767294)
			(xy 337.830402 -242.722018) (xy 337.856705 -242.680422) (xy 337.88934 -242.643585) (xy 337.927461 -242.61246)
			(xy 337.970082 -242.587853) (xy 338.016098 -242.570401) (xy 338.064317 -242.560557) (xy 338.113492 -242.558576)
			(xy 338.162347 -242.564508) (xy 338.209618 -242.5782) (xy 338.25408 -242.599298) (xy 338.294583 -242.627254)
			(xy 338.330076 -242.661346) (xy 338.359641 -242.70069) (xy 338.382512 -242.744267) (xy 338.398096 -242.790948)
			(xy 338.405991 -242.839525) (xy 338.406486 -242.864132) (xy 338.724743 -242.864132) (xy 338.728838 -242.813404)
			(xy 338.741017 -242.76399) (xy 338.760965 -242.71717) (xy 338.788166 -242.674156) (xy 338.821914 -242.636062)
			(xy 338.861336 -242.603875) (xy 338.90541 -242.578429) (xy 338.952996 -242.560382) (xy 339.00286 -242.550202)
			(xy 339.053712 -242.548153) (xy 339.104233 -242.554287) (xy 339.153117 -242.568447) (xy 339.199096 -242.590264)
			(xy 339.24098 -242.619174) (xy 339.277684 -242.654429) (xy 339.308257 -242.695115) (xy 339.331908 -242.740178)
			(xy 339.348024 -242.788452) (xy 339.356188 -242.838686) (xy 339.3567 -242.864132) (xy 339.664797 -242.864132)
			(xy 339.668892 -242.813404) (xy 339.681071 -242.76399) (xy 339.701019 -242.71717) (xy 339.72822 -242.674156)
			(xy 339.761968 -242.636062) (xy 339.80139 -242.603875) (xy 339.845464 -242.578429) (xy 339.89305 -242.560382)
			(xy 339.942914 -242.550202) (xy 339.993766 -242.548153) (xy 340.044287 -242.554287) (xy 340.093171 -242.568447)
			(xy 340.13915 -242.590264) (xy 340.181034 -242.619174) (xy 340.217738 -242.654429) (xy 340.248311 -242.695115)
			(xy 340.271962 -242.740178) (xy 340.288078 -242.788452) (xy 340.296242 -242.838686) (xy 340.296754 -242.864132)
			(xy 340.615282 -242.864132) (xy 340.619242 -242.815078) (xy 340.631019 -242.767294) (xy 340.65031 -242.722018)
			(xy 340.676613 -242.680422) (xy 340.709248 -242.643585) (xy 340.747369 -242.61246) (xy 340.78999 -242.587853)
			(xy 340.836006 -242.570401) (xy 340.884225 -242.560557) (xy 340.9334 -242.558576) (xy 340.982255 -242.564508)
			(xy 341.029526 -242.5782) (xy 341.073988 -242.599298) (xy 341.114491 -242.627254) (xy 341.149984 -242.661346)
			(xy 341.179549 -242.70069) (xy 341.20242 -242.744267) (xy 341.218004 -242.790948) (xy 341.225899 -242.839525)
			(xy 341.226394 -242.864132) (xy 341.544905 -242.864132) (xy 341.549 -242.813404) (xy 341.561179 -242.76399)
			(xy 341.581127 -242.71717) (xy 341.608328 -242.674156) (xy 341.642076 -242.636062) (xy 341.681498 -242.603875)
			(xy 341.725572 -242.578429) (xy 341.773158 -242.560382) (xy 341.823022 -242.550202) (xy 341.873874 -242.548153)
			(xy 341.924395 -242.554287) (xy 341.973279 -242.568447) (xy 342.019258 -242.590264) (xy 342.061142 -242.619174)
			(xy 342.097846 -242.654429) (xy 342.128419 -242.695115) (xy 342.15207 -242.740178) (xy 342.168186 -242.788452)
			(xy 342.17635 -242.838686) (xy 342.176862 -242.864132) (xy 342.49539 -242.864132) (xy 342.49935 -242.815078)
			(xy 342.511127 -242.767294) (xy 342.530418 -242.722018) (xy 342.556721 -242.680422) (xy 342.589356 -242.643585)
			(xy 342.627477 -242.61246) (xy 342.670098 -242.587853) (xy 342.716114 -242.570401) (xy 342.764333 -242.560557)
			(xy 342.813508 -242.558576) (xy 342.862363 -242.564508) (xy 342.909634 -242.5782) (xy 342.954096 -242.599298)
			(xy 342.994599 -242.627254) (xy 343.030092 -242.661346) (xy 343.059657 -242.70069) (xy 343.082528 -242.744267)
			(xy 343.098112 -242.790948) (xy 343.106007 -242.839525) (xy 343.106502 -242.864132) (xy 343.424759 -242.864132)
			(xy 343.428854 -242.813404) (xy 343.441033 -242.76399) (xy 343.460981 -242.71717) (xy 343.488182 -242.674156)
			(xy 343.52193 -242.636062) (xy 343.561352 -242.603875) (xy 343.605426 -242.578429) (xy 343.653012 -242.560382)
			(xy 343.702876 -242.550202) (xy 343.753728 -242.548153) (xy 343.804249 -242.554287) (xy 343.853133 -242.568447)
			(xy 343.899112 -242.590264) (xy 343.940996 -242.619174) (xy 343.9777 -242.654429) (xy 344.008273 -242.695115)
			(xy 344.031924 -242.740178) (xy 344.04804 -242.788452) (xy 344.056204 -242.838686) (xy 344.056716 -242.864132)
			(xy 344.056204 -242.889578) (xy 344.04804 -242.939812) (xy 344.031924 -242.988086) (xy 344.008273 -243.033149)
			(xy 343.9777 -243.073835) (xy 343.940996 -243.10909) (xy 343.899112 -243.138) (xy 343.853133 -243.159817)
			(xy 343.804249 -243.173977) (xy 343.753728 -243.180111) (xy 343.702876 -243.178062) (xy 343.653012 -243.167882)
			(xy 343.605426 -243.149835) (xy 343.561352 -243.124389) (xy 343.52193 -243.092202) (xy 343.488182 -243.054108)
			(xy 343.460981 -243.011094) (xy 343.441033 -242.964274) (xy 343.428854 -242.91486) (xy 343.424759 -242.864132)
			(xy 343.106502 -242.864132) (xy 343.106007 -242.888739) (xy 343.098112 -242.937316) (xy 343.082528 -242.983997)
			(xy 343.059657 -243.027574) (xy 343.030092 -243.066918) (xy 342.994599 -243.10101) (xy 342.954096 -243.128966)
			(xy 342.909634 -243.150064) (xy 342.862363 -243.163756) (xy 342.813508 -243.169688) (xy 342.764333 -243.167707)
			(xy 342.716114 -243.157863) (xy 342.670098 -243.140411) (xy 342.627477 -243.115804) (xy 342.589356 -243.084679)
			(xy 342.556721 -243.047842) (xy 342.530418 -243.006246) (xy 342.511127 -242.96097) (xy 342.49935 -242.913186)
			(xy 342.49539 -242.864132) (xy 342.176862 -242.864132) (xy 342.17635 -242.889578) (xy 342.168186 -242.939812)
			(xy 342.15207 -242.988086) (xy 342.128419 -243.033149) (xy 342.097846 -243.073835) (xy 342.061142 -243.10909)
			(xy 342.019258 -243.138) (xy 341.973279 -243.159817) (xy 341.924395 -243.173977) (xy 341.873874 -243.180111)
			(xy 341.823022 -243.178062) (xy 341.773158 -243.167882) (xy 341.725572 -243.149835) (xy 341.681498 -243.124389)
			(xy 341.642076 -243.092202) (xy 341.608328 -243.054108) (xy 341.581127 -243.011094) (xy 341.561179 -242.964274)
			(xy 341.549 -242.91486) (xy 341.544905 -242.864132) (xy 341.226394 -242.864132) (xy 341.225899 -242.888739)
			(xy 341.218004 -242.937316) (xy 341.20242 -242.983997) (xy 341.179549 -243.027574) (xy 341.149984 -243.066918)
			(xy 341.114491 -243.10101) (xy 341.073988 -243.128966) (xy 341.029526 -243.150064) (xy 340.982255 -243.163756)
			(xy 340.9334 -243.169688) (xy 340.884225 -243.167707) (xy 340.836006 -243.157863) (xy 340.78999 -243.140411)
			(xy 340.747369 -243.115804) (xy 340.709248 -243.084679) (xy 340.676613 -243.047842) (xy 340.65031 -243.006246)
			(xy 340.631019 -242.96097) (xy 340.619242 -242.913186) (xy 340.615282 -242.864132) (xy 340.296754 -242.864132)
			(xy 340.296242 -242.889578) (xy 340.288078 -242.939812) (xy 340.271962 -242.988086) (xy 340.248311 -243.033149)
			(xy 340.217738 -243.073835) (xy 340.181034 -243.10909) (xy 340.13915 -243.138) (xy 340.093171 -243.159817)
			(xy 340.044287 -243.173977) (xy 339.993766 -243.180111) (xy 339.942914 -243.178062) (xy 339.89305 -243.167882)
			(xy 339.845464 -243.149835) (xy 339.80139 -243.124389) (xy 339.761968 -243.092202) (xy 339.72822 -243.054108)
			(xy 339.701019 -243.011094) (xy 339.681071 -242.964274) (xy 339.668892 -242.91486) (xy 339.664797 -242.864132)
			(xy 339.3567 -242.864132) (xy 339.356188 -242.889578) (xy 339.348024 -242.939812) (xy 339.331908 -242.988086)
			(xy 339.308257 -243.033149) (xy 339.277684 -243.073835) (xy 339.24098 -243.10909) (xy 339.199096 -243.138)
			(xy 339.153117 -243.159817) (xy 339.104233 -243.173977) (xy 339.053712 -243.180111) (xy 339.00286 -243.178062)
			(xy 338.952996 -243.167882) (xy 338.90541 -243.149835) (xy 338.861336 -243.124389) (xy 338.821914 -243.092202)
			(xy 338.788166 -243.054108) (xy 338.760965 -243.011094) (xy 338.741017 -242.964274) (xy 338.728838 -242.91486)
			(xy 338.724743 -242.864132) (xy 338.406486 -242.864132) (xy 338.405991 -242.888739) (xy 338.398096 -242.937316)
			(xy 338.382512 -242.983997) (xy 338.359641 -243.027574) (xy 338.330076 -243.066918) (xy 338.294583 -243.10101)
			(xy 338.25408 -243.128966) (xy 338.209618 -243.150064) (xy 338.162347 -243.163756) (xy 338.113492 -243.169688)
			(xy 338.064317 -243.167707) (xy 338.016098 -243.157863) (xy 337.970082 -243.140411) (xy 337.927461 -243.115804)
			(xy 337.88934 -243.084679) (xy 337.856705 -243.047842) (xy 337.830402 -243.006246) (xy 337.811111 -242.96097)
			(xy 337.799334 -242.913186) (xy 337.795374 -242.864132) (xy 337.466432 -242.864132) (xy 337.465937 -242.888739)
			(xy 337.458042 -242.937316) (xy 337.442458 -242.983997) (xy 337.419587 -243.027574) (xy 337.390022 -243.066918)
			(xy 337.354529 -243.10101) (xy 337.314026 -243.128966) (xy 337.269564 -243.150064) (xy 337.222293 -243.163756)
			(xy 337.173438 -243.169688) (xy 337.124263 -243.167707) (xy 337.076044 -243.157863) (xy 337.030028 -243.140411)
			(xy 336.987407 -243.115804) (xy 336.949286 -243.084679) (xy 336.916651 -243.047842) (xy 336.890348 -243.006246)
			(xy 336.871057 -242.96097) (xy 336.85928 -242.913186) (xy 336.85532 -242.864132) (xy 336.526378 -242.864132)
			(xy 336.525883 -242.888739) (xy 336.517988 -242.937316) (xy 336.502404 -242.983997) (xy 336.479533 -243.027574)
			(xy 336.449968 -243.066918) (xy 336.414475 -243.10101) (xy 336.373972 -243.128966) (xy 336.32951 -243.150064)
			(xy 336.282239 -243.163756) (xy 336.233384 -243.169688) (xy 336.184209 -243.167707) (xy 336.13599 -243.157863)
			(xy 336.089974 -243.140411) (xy 336.047353 -243.115804) (xy 336.009232 -243.084679) (xy 335.976597 -243.047842)
			(xy 335.950294 -243.006246) (xy 335.931003 -242.96097) (xy 335.919226 -242.913186) (xy 335.915266 -242.864132)
			(xy 335.586324 -242.864132) (xy 335.585829 -242.888739) (xy 335.577934 -242.937316) (xy 335.56235 -242.983997)
			(xy 335.539479 -243.027574) (xy 335.509914 -243.066918) (xy 335.474421 -243.10101) (xy 335.433918 -243.128966)
			(xy 335.389456 -243.150064) (xy 335.342185 -243.163756) (xy 335.29333 -243.169688) (xy 335.244155 -243.167707)
			(xy 335.195936 -243.157863) (xy 335.14992 -243.140411) (xy 335.107299 -243.115804) (xy 335.069178 -243.084679)
			(xy 335.036543 -243.047842) (xy 335.01024 -243.006246) (xy 334.990949 -242.96097) (xy 334.979172 -242.913186)
			(xy 334.975212 -242.864132) (xy 334.646524 -242.864132) (xy 334.646029 -242.888739) (xy 334.638134 -242.937316)
			(xy 334.62255 -242.983997) (xy 334.599679 -243.027574) (xy 334.570114 -243.066918) (xy 334.534621 -243.10101)
			(xy 334.494118 -243.128966) (xy 334.449656 -243.150064) (xy 334.402385 -243.163756) (xy 334.35353 -243.169688)
			(xy 334.304355 -243.167707) (xy 334.256136 -243.157863) (xy 334.21012 -243.140411) (xy 334.167499 -243.115804)
			(xy 334.129378 -243.084679) (xy 334.096743 -243.047842) (xy 334.07044 -243.006246) (xy 334.051149 -242.96097)
			(xy 334.039372 -242.913186) (xy 334.035412 -242.864132) (xy 333.70647 -242.864132) (xy 333.705975 -242.888739)
			(xy 333.69808 -242.937316) (xy 333.682496 -242.983997) (xy 333.659625 -243.027574) (xy 333.63006 -243.066918)
			(xy 333.594567 -243.10101) (xy 333.554064 -243.128966) (xy 333.509602 -243.150064) (xy 333.462331 -243.163756)
			(xy 333.413476 -243.169688) (xy 333.364301 -243.167707) (xy 333.316082 -243.157863) (xy 333.270066 -243.140411)
			(xy 333.227445 -243.115804) (xy 333.189324 -243.084679) (xy 333.156689 -243.047842) (xy 333.130386 -243.006246)
			(xy 333.111095 -242.96097) (xy 333.099318 -242.913186) (xy 333.095358 -242.864132) (xy 332.766416 -242.864132)
			(xy 332.765921 -242.888739) (xy 332.758026 -242.937316) (xy 332.742442 -242.983997) (xy 332.719571 -243.027574)
			(xy 332.690006 -243.066918) (xy 332.654513 -243.10101) (xy 332.61401 -243.128966) (xy 332.569548 -243.150064)
			(xy 332.522277 -243.163756) (xy 332.473422 -243.169688) (xy 332.424247 -243.167707) (xy 332.376028 -243.157863)
			(xy 332.330012 -243.140411) (xy 332.287391 -243.115804) (xy 332.24927 -243.084679) (xy 332.216635 -243.047842)
			(xy 332.190332 -243.006246) (xy 332.171041 -242.96097) (xy 332.159264 -242.913186) (xy 332.155304 -242.864132)
			(xy 331.826024 -242.864132) (xy 331.826024 -242.889135) (xy 331.817859 -242.938528) (xy 331.801748 -242.985928)
			(xy 331.778122 -243.030066) (xy 331.747615 -243.06976) (xy 331.711043 -243.103948) (xy 331.669385 -243.131713)
			(xy 331.623756 -243.152313) (xy 331.575379 -243.165196) (xy 331.550518 -243.16817) (xy 331.550264 -243.16817)
			(xy 331.540612 -243.169186) (xy 331.532738 -243.172996) (xy 331.528476 -243.175197) (xy 331.520797 -243.180944)
			(xy 331.517498 -243.184426) (xy 331.47254 -243.233956) (xy 331.466488 -243.241128) (xy 331.459709 -243.258614)
			(xy 331.459332 -243.267992) (xy 331.459332 -243.674138) (xy 331.685404 -243.674138) (xy 331.689364 -243.625084)
			(xy 331.701141 -243.5773) (xy 331.720432 -243.532024) (xy 331.746735 -243.490428) (xy 331.77937 -243.453591)
			(xy 331.817491 -243.422466) (xy 331.860112 -243.397859) (xy 331.906128 -243.380407) (xy 331.954347 -243.370563)
			(xy 332.003522 -243.368582) (xy 332.052377 -243.374514) (xy 332.099648 -243.388206) (xy 332.14411 -243.409304)
			(xy 332.184613 -243.43726) (xy 332.220106 -243.471352) (xy 332.249671 -243.510696) (xy 332.272542 -243.554273)
			(xy 332.288126 -243.600954) (xy 332.296021 -243.649531) (xy 332.296516 -243.674138) (xy 332.625204 -243.674138)
			(xy 332.629164 -243.625084) (xy 332.640941 -243.5773) (xy 332.660232 -243.532024) (xy 332.686535 -243.490428)
			(xy 332.71917 -243.453591) (xy 332.757291 -243.422466) (xy 332.799912 -243.397859) (xy 332.845928 -243.380407)
			(xy 332.894147 -243.370563) (xy 332.943322 -243.368582) (xy 332.992177 -243.374514) (xy 333.039448 -243.388206)
			(xy 333.08391 -243.409304) (xy 333.124413 -243.43726) (xy 333.159906 -243.471352) (xy 333.189471 -243.510696)
			(xy 333.212342 -243.554273) (xy 333.227926 -243.600954) (xy 333.235821 -243.649531) (xy 333.236316 -243.674138)
			(xy 333.565258 -243.674138) (xy 333.569218 -243.625084) (xy 333.580995 -243.5773) (xy 333.600286 -243.532024)
			(xy 333.626589 -243.490428) (xy 333.659224 -243.453591) (xy 333.697345 -243.422466) (xy 333.739966 -243.397859)
			(xy 333.785982 -243.380407) (xy 333.834201 -243.370563) (xy 333.883376 -243.368582) (xy 333.932231 -243.374514)
			(xy 333.979502 -243.388206) (xy 334.023964 -243.409304) (xy 334.064467 -243.43726) (xy 334.09996 -243.471352)
			(xy 334.129525 -243.510696) (xy 334.152396 -243.554273) (xy 334.16798 -243.600954) (xy 334.175875 -243.649531)
			(xy 334.17637 -243.674138) (xy 334.505312 -243.674138) (xy 334.509272 -243.625084) (xy 334.521049 -243.5773)
			(xy 334.54034 -243.532024) (xy 334.566643 -243.490428) (xy 334.599278 -243.453591) (xy 334.637399 -243.422466)
			(xy 334.68002 -243.397859) (xy 334.726036 -243.380407) (xy 334.774255 -243.370563) (xy 334.82343 -243.368582)
			(xy 334.872285 -243.374514) (xy 334.919556 -243.388206) (xy 334.964018 -243.409304) (xy 335.004521 -243.43726)
			(xy 335.040014 -243.471352) (xy 335.069579 -243.510696) (xy 335.09245 -243.554273) (xy 335.108034 -243.600954)
			(xy 335.115929 -243.649531) (xy 335.116424 -243.674138) (xy 335.445366 -243.674138) (xy 335.449326 -243.625084)
			(xy 335.461103 -243.5773) (xy 335.480394 -243.532024) (xy 335.506697 -243.490428) (xy 335.539332 -243.453591)
			(xy 335.577453 -243.422466) (xy 335.620074 -243.397859) (xy 335.66609 -243.380407) (xy 335.714309 -243.370563)
			(xy 335.763484 -243.368582) (xy 335.812339 -243.374514) (xy 335.85961 -243.388206) (xy 335.904072 -243.409304)
			(xy 335.944575 -243.43726) (xy 335.980068 -243.471352) (xy 336.009633 -243.510696) (xy 336.032504 -243.554273)
			(xy 336.048088 -243.600954) (xy 336.055983 -243.649531) (xy 336.056478 -243.674138) (xy 336.38542 -243.674138)
			(xy 336.38938 -243.625084) (xy 336.401157 -243.5773) (xy 336.420448 -243.532024) (xy 336.446751 -243.490428)
			(xy 336.479386 -243.453591) (xy 336.517507 -243.422466) (xy 336.560128 -243.397859) (xy 336.606144 -243.380407)
			(xy 336.654363 -243.370563) (xy 336.703538 -243.368582) (xy 336.752393 -243.374514) (xy 336.799664 -243.388206)
			(xy 336.844126 -243.409304) (xy 336.884629 -243.43726) (xy 336.920122 -243.471352) (xy 336.949687 -243.510696)
			(xy 336.972558 -243.554273) (xy 336.988142 -243.600954) (xy 336.996037 -243.649531) (xy 336.996532 -243.674138)
			(xy 337.32522 -243.674138) (xy 337.32918 -243.625084) (xy 337.340957 -243.5773) (xy 337.360248 -243.532024)
			(xy 337.386551 -243.490428) (xy 337.419186 -243.453591) (xy 337.457307 -243.422466) (xy 337.499928 -243.397859)
			(xy 337.545944 -243.380407) (xy 337.594163 -243.370563) (xy 337.643338 -243.368582) (xy 337.692193 -243.374514)
			(xy 337.739464 -243.388206) (xy 337.783926 -243.409304) (xy 337.824429 -243.43726) (xy 337.859922 -243.471352)
			(xy 337.889487 -243.510696) (xy 337.912358 -243.554273) (xy 337.927942 -243.600954) (xy 337.935837 -243.649531)
			(xy 337.936332 -243.674138) (xy 338.254843 -243.674138) (xy 338.258938 -243.62341) (xy 338.271117 -243.573996)
			(xy 338.291065 -243.527176) (xy 338.318266 -243.484162) (xy 338.352014 -243.446068) (xy 338.391436 -243.413881)
			(xy 338.43551 -243.388435) (xy 338.483096 -243.370388) (xy 338.53296 -243.360208) (xy 338.583812 -243.358159)
			(xy 338.634333 -243.364293) (xy 338.683217 -243.378453) (xy 338.729196 -243.40027) (xy 338.77108 -243.42918)
			(xy 338.807784 -243.464435) (xy 338.838357 -243.505121) (xy 338.862008 -243.550184) (xy 338.878124 -243.598458)
			(xy 338.886288 -243.648692) (xy 338.8868 -243.674138) (xy 339.205328 -243.674138) (xy 339.209288 -243.625084)
			(xy 339.221065 -243.5773) (xy 339.240356 -243.532024) (xy 339.266659 -243.490428) (xy 339.299294 -243.453591)
			(xy 339.337415 -243.422466) (xy 339.380036 -243.397859) (xy 339.426052 -243.380407) (xy 339.474271 -243.370563)
			(xy 339.523446 -243.368582) (xy 339.572301 -243.374514) (xy 339.619572 -243.388206) (xy 339.664034 -243.409304)
			(xy 339.704537 -243.43726) (xy 339.74003 -243.471352) (xy 339.769595 -243.510696) (xy 339.792466 -243.554273)
			(xy 339.80805 -243.600954) (xy 339.815945 -243.649531) (xy 339.81644 -243.674138) (xy 340.134951 -243.674138)
			(xy 340.139046 -243.62341) (xy 340.151225 -243.573996) (xy 340.171173 -243.527176) (xy 340.198374 -243.484162)
			(xy 340.232122 -243.446068) (xy 340.271544 -243.413881) (xy 340.315618 -243.388435) (xy 340.363204 -243.370388)
			(xy 340.413068 -243.360208) (xy 340.46392 -243.358159) (xy 340.514441 -243.364293) (xy 340.563325 -243.378453)
			(xy 340.609304 -243.40027) (xy 340.651188 -243.42918) (xy 340.687892 -243.464435) (xy 340.718465 -243.505121)
			(xy 340.742116 -243.550184) (xy 340.758232 -243.598458) (xy 340.766396 -243.648692) (xy 340.766908 -243.674138)
			(xy 341.085182 -243.674138) (xy 341.089142 -243.625084) (xy 341.100919 -243.5773) (xy 341.12021 -243.532024)
			(xy 341.146513 -243.490428) (xy 341.179148 -243.453591) (xy 341.217269 -243.422466) (xy 341.25989 -243.397859)
			(xy 341.305906 -243.380407) (xy 341.354125 -243.370563) (xy 341.4033 -243.368582) (xy 341.452155 -243.374514)
			(xy 341.499426 -243.388206) (xy 341.543888 -243.409304) (xy 341.584391 -243.43726) (xy 341.619884 -243.471352)
			(xy 341.649449 -243.510696) (xy 341.67232 -243.554273) (xy 341.687904 -243.600954) (xy 341.695799 -243.649531)
			(xy 341.696294 -243.674138) (xy 342.014805 -243.674138) (xy 342.0189 -243.62341) (xy 342.031079 -243.573996)
			(xy 342.051027 -243.527176) (xy 342.078228 -243.484162) (xy 342.111976 -243.446068) (xy 342.151398 -243.413881)
			(xy 342.195472 -243.388435) (xy 342.243058 -243.370388) (xy 342.292922 -243.360208) (xy 342.343774 -243.358159)
			(xy 342.394295 -243.364293) (xy 342.443179 -243.378453) (xy 342.489158 -243.40027) (xy 342.531042 -243.42918)
			(xy 342.567746 -243.464435) (xy 342.598319 -243.505121) (xy 342.62197 -243.550184) (xy 342.638086 -243.598458)
			(xy 342.64625 -243.648692) (xy 342.646762 -243.674138) (xy 342.954859 -243.674138) (xy 342.958954 -243.62341)
			(xy 342.971133 -243.573996) (xy 342.991081 -243.527176) (xy 343.018282 -243.484162) (xy 343.05203 -243.446068)
			(xy 343.091452 -243.413881) (xy 343.135526 -243.388435) (xy 343.183112 -243.370388) (xy 343.232976 -243.360208)
			(xy 343.283828 -243.358159) (xy 343.334349 -243.364293) (xy 343.383233 -243.378453) (xy 343.429212 -243.40027)
			(xy 343.471096 -243.42918) (xy 343.5078 -243.464435) (xy 343.538373 -243.505121) (xy 343.562024 -243.550184)
			(xy 343.57814 -243.598458) (xy 343.586304 -243.648692) (xy 343.586816 -243.674138) (xy 343.586304 -243.699584)
			(xy 343.57814 -243.749818) (xy 343.562024 -243.798092) (xy 343.538373 -243.843155) (xy 343.5078 -243.883841)
			(xy 343.471096 -243.919096) (xy 343.429212 -243.948006) (xy 343.383233 -243.969823) (xy 343.334349 -243.983983)
			(xy 343.283828 -243.990117) (xy 343.232976 -243.988068) (xy 343.183112 -243.977888) (xy 343.135526 -243.959841)
			(xy 343.091452 -243.934395) (xy 343.05203 -243.902208) (xy 343.018282 -243.864114) (xy 342.991081 -243.8211)
			(xy 342.971133 -243.77428) (xy 342.958954 -243.724866) (xy 342.954859 -243.674138) (xy 342.646762 -243.674138)
			(xy 342.64625 -243.699584) (xy 342.638086 -243.749818) (xy 342.62197 -243.798092) (xy 342.598319 -243.843155)
			(xy 342.567746 -243.883841) (xy 342.531042 -243.919096) (xy 342.489158 -243.948006) (xy 342.443179 -243.969823)
			(xy 342.394295 -243.983983) (xy 342.343774 -243.990117) (xy 342.292922 -243.988068) (xy 342.243058 -243.977888)
			(xy 342.195472 -243.959841) (xy 342.151398 -243.934395) (xy 342.111976 -243.902208) (xy 342.078228 -243.864114)
			(xy 342.051027 -243.8211) (xy 342.031079 -243.77428) (xy 342.0189 -243.724866) (xy 342.014805 -243.674138)
			(xy 341.696294 -243.674138) (xy 341.695799 -243.698745) (xy 341.687904 -243.747322) (xy 341.67232 -243.794003)
			(xy 341.649449 -243.83758) (xy 341.619884 -243.876924) (xy 341.584391 -243.911016) (xy 341.543888 -243.938972)
			(xy 341.499426 -243.96007) (xy 341.452155 -243.973762) (xy 341.4033 -243.979694) (xy 341.354125 -243.977713)
			(xy 341.305906 -243.967869) (xy 341.25989 -243.950417) (xy 341.217269 -243.92581) (xy 341.179148 -243.894685)
			(xy 341.146513 -243.857848) (xy 341.12021 -243.816252) (xy 341.100919 -243.770976) (xy 341.089142 -243.723192)
			(xy 341.085182 -243.674138) (xy 340.766908 -243.674138) (xy 340.766396 -243.699584) (xy 340.758232 -243.749818)
			(xy 340.742116 -243.798092) (xy 340.718465 -243.843155) (xy 340.687892 -243.883841) (xy 340.651188 -243.919096)
			(xy 340.609304 -243.948006) (xy 340.563325 -243.969823) (xy 340.514441 -243.983983) (xy 340.46392 -243.990117)
			(xy 340.413068 -243.988068) (xy 340.363204 -243.977888) (xy 340.315618 -243.959841) (xy 340.271544 -243.934395)
			(xy 340.232122 -243.902208) (xy 340.198374 -243.864114) (xy 340.171173 -243.8211) (xy 340.151225 -243.77428)
			(xy 340.139046 -243.724866) (xy 340.134951 -243.674138) (xy 339.81644 -243.674138) (xy 339.815945 -243.698745)
			(xy 339.80805 -243.747322) (xy 339.792466 -243.794003) (xy 339.769595 -243.83758) (xy 339.74003 -243.876924)
			(xy 339.704537 -243.911016) (xy 339.664034 -243.938972) (xy 339.619572 -243.96007) (xy 339.572301 -243.973762)
			(xy 339.523446 -243.979694) (xy 339.474271 -243.977713) (xy 339.426052 -243.967869) (xy 339.380036 -243.950417)
			(xy 339.337415 -243.92581) (xy 339.299294 -243.894685) (xy 339.266659 -243.857848) (xy 339.240356 -243.816252)
			(xy 339.221065 -243.770976) (xy 339.209288 -243.723192) (xy 339.205328 -243.674138) (xy 338.8868 -243.674138)
			(xy 338.886288 -243.699584) (xy 338.878124 -243.749818) (xy 338.862008 -243.798092) (xy 338.838357 -243.843155)
			(xy 338.807784 -243.883841) (xy 338.77108 -243.919096) (xy 338.729196 -243.948006) (xy 338.683217 -243.969823)
			(xy 338.634333 -243.983983) (xy 338.583812 -243.990117) (xy 338.53296 -243.988068) (xy 338.483096 -243.977888)
			(xy 338.43551 -243.959841) (xy 338.391436 -243.934395) (xy 338.352014 -243.902208) (xy 338.318266 -243.864114)
			(xy 338.291065 -243.8211) (xy 338.271117 -243.77428) (xy 338.258938 -243.724866) (xy 338.254843 -243.674138)
			(xy 337.936332 -243.674138) (xy 337.935837 -243.698745) (xy 337.927942 -243.747322) (xy 337.912358 -243.794003)
			(xy 337.889487 -243.83758) (xy 337.859922 -243.876924) (xy 337.824429 -243.911016) (xy 337.783926 -243.938972)
			(xy 337.739464 -243.96007) (xy 337.692193 -243.973762) (xy 337.643338 -243.979694) (xy 337.594163 -243.977713)
			(xy 337.545944 -243.967869) (xy 337.499928 -243.950417) (xy 337.457307 -243.92581) (xy 337.419186 -243.894685)
			(xy 337.386551 -243.857848) (xy 337.360248 -243.816252) (xy 337.340957 -243.770976) (xy 337.32918 -243.723192)
			(xy 337.32522 -243.674138) (xy 336.996532 -243.674138) (xy 336.996037 -243.698745) (xy 336.988142 -243.747322)
			(xy 336.972558 -243.794003) (xy 336.949687 -243.83758) (xy 336.920122 -243.876924) (xy 336.884629 -243.911016)
			(xy 336.844126 -243.938972) (xy 336.799664 -243.96007) (xy 336.752393 -243.973762) (xy 336.703538 -243.979694)
			(xy 336.654363 -243.977713) (xy 336.606144 -243.967869) (xy 336.560128 -243.950417) (xy 336.517507 -243.92581)
			(xy 336.479386 -243.894685) (xy 336.446751 -243.857848) (xy 336.420448 -243.816252) (xy 336.401157 -243.770976)
			(xy 336.38938 -243.723192) (xy 336.38542 -243.674138) (xy 336.056478 -243.674138) (xy 336.055983 -243.698745)
			(xy 336.048088 -243.747322) (xy 336.032504 -243.794003) (xy 336.009633 -243.83758) (xy 335.980068 -243.876924)
			(xy 335.944575 -243.911016) (xy 335.904072 -243.938972) (xy 335.85961 -243.96007) (xy 335.812339 -243.973762)
			(xy 335.763484 -243.979694) (xy 335.714309 -243.977713) (xy 335.66609 -243.967869) (xy 335.620074 -243.950417)
			(xy 335.577453 -243.92581) (xy 335.539332 -243.894685) (xy 335.506697 -243.857848) (xy 335.480394 -243.816252)
			(xy 335.461103 -243.770976) (xy 335.449326 -243.723192) (xy 335.445366 -243.674138) (xy 335.116424 -243.674138)
			(xy 335.115929 -243.698745) (xy 335.108034 -243.747322) (xy 335.09245 -243.794003) (xy 335.069579 -243.83758)
			(xy 335.040014 -243.876924) (xy 335.004521 -243.911016) (xy 334.964018 -243.938972) (xy 334.919556 -243.96007)
			(xy 334.872285 -243.973762) (xy 334.82343 -243.979694) (xy 334.774255 -243.977713) (xy 334.726036 -243.967869)
			(xy 334.68002 -243.950417) (xy 334.637399 -243.92581) (xy 334.599278 -243.894685) (xy 334.566643 -243.857848)
			(xy 334.54034 -243.816252) (xy 334.521049 -243.770976) (xy 334.509272 -243.723192) (xy 334.505312 -243.674138)
			(xy 334.17637 -243.674138) (xy 334.175875 -243.698745) (xy 334.16798 -243.747322) (xy 334.152396 -243.794003)
			(xy 334.129525 -243.83758) (xy 334.09996 -243.876924) (xy 334.064467 -243.911016) (xy 334.023964 -243.938972)
			(xy 333.979502 -243.96007) (xy 333.932231 -243.973762) (xy 333.883376 -243.979694) (xy 333.834201 -243.977713)
			(xy 333.785982 -243.967869) (xy 333.739966 -243.950417) (xy 333.697345 -243.92581) (xy 333.659224 -243.894685)
			(xy 333.626589 -243.857848) (xy 333.600286 -243.816252) (xy 333.580995 -243.770976) (xy 333.569218 -243.723192)
			(xy 333.565258 -243.674138) (xy 333.236316 -243.674138) (xy 333.235821 -243.698745) (xy 333.227926 -243.747322)
			(xy 333.212342 -243.794003) (xy 333.189471 -243.83758) (xy 333.159906 -243.876924) (xy 333.124413 -243.911016)
			(xy 333.08391 -243.938972) (xy 333.039448 -243.96007) (xy 332.992177 -243.973762) (xy 332.943322 -243.979694)
			(xy 332.894147 -243.977713) (xy 332.845928 -243.967869) (xy 332.799912 -243.950417) (xy 332.757291 -243.92581)
			(xy 332.71917 -243.894685) (xy 332.686535 -243.857848) (xy 332.660232 -243.816252) (xy 332.640941 -243.770976)
			(xy 332.629164 -243.723192) (xy 332.625204 -243.674138) (xy 332.296516 -243.674138) (xy 332.296021 -243.698745)
			(xy 332.288126 -243.747322) (xy 332.272542 -243.794003) (xy 332.249671 -243.83758) (xy 332.220106 -243.876924)
			(xy 332.184613 -243.911016) (xy 332.14411 -243.938972) (xy 332.099648 -243.96007) (xy 332.052377 -243.973762)
			(xy 332.003522 -243.979694) (xy 331.954347 -243.977713) (xy 331.906128 -243.967869) (xy 331.860112 -243.950417)
			(xy 331.817491 -243.92581) (xy 331.77937 -243.894685) (xy 331.746735 -243.857848) (xy 331.720432 -243.816252)
			(xy 331.701141 -243.770976) (xy 331.689364 -243.723192) (xy 331.685404 -243.674138) (xy 331.459332 -243.674138)
			(xy 331.459332 -244.080284) (xy 331.459807 -244.089641) (xy 331.466577 -244.107094) (xy 331.47254 -244.11432)
			(xy 331.517498 -244.16385) (xy 331.520812 -244.167316) (xy 331.528484 -244.173067) (xy 331.532738 -244.17528)
			(xy 331.540612 -244.17909) (xy 331.550264 -244.180106) (xy 331.550518 -244.180106) (xy 331.575384 -244.183017)
			(xy 331.623759 -244.1959) (xy 331.669385 -244.216501) (xy 331.711041 -244.244266) (xy 331.747611 -244.278453)
			(xy 331.778116 -244.318147) (xy 331.80174 -244.362284) (xy 331.817849 -244.409682) (xy 331.826012 -244.459074)
			(xy 331.826012 -244.484144) (xy 332.155304 -244.484144) (xy 332.159264 -244.43509) (xy 332.171041 -244.387306)
			(xy 332.190332 -244.34203) (xy 332.216635 -244.300434) (xy 332.24927 -244.263597) (xy 332.287391 -244.232472)
			(xy 332.330012 -244.207865) (xy 332.376028 -244.190413) (xy 332.424247 -244.180569) (xy 332.473422 -244.178588)
			(xy 332.522277 -244.18452) (xy 332.569548 -244.198212) (xy 332.61401 -244.21931) (xy 332.654513 -244.247266)
			(xy 332.690006 -244.281358) (xy 332.719571 -244.320702) (xy 332.742442 -244.364279) (xy 332.758026 -244.41096)
			(xy 332.765921 -244.459537) (xy 332.766416 -244.484144) (xy 333.095358 -244.484144) (xy 333.099318 -244.43509)
			(xy 333.111095 -244.387306) (xy 333.130386 -244.34203) (xy 333.156689 -244.300434) (xy 333.189324 -244.263597)
			(xy 333.227445 -244.232472) (xy 333.270066 -244.207865) (xy 333.316082 -244.190413) (xy 333.364301 -244.180569)
			(xy 333.413476 -244.178588) (xy 333.462331 -244.18452) (xy 333.509602 -244.198212) (xy 333.554064 -244.21931)
			(xy 333.594567 -244.247266) (xy 333.63006 -244.281358) (xy 333.659625 -244.320702) (xy 333.682496 -244.364279)
			(xy 333.69808 -244.41096) (xy 333.705975 -244.459537) (xy 333.70647 -244.484144) (xy 334.975212 -244.484144)
			(xy 334.979172 -244.43509) (xy 334.990949 -244.387306) (xy 335.01024 -244.34203) (xy 335.036543 -244.300434)
			(xy 335.069178 -244.263597) (xy 335.107299 -244.232472) (xy 335.14992 -244.207865) (xy 335.195936 -244.190413)
			(xy 335.244155 -244.180569) (xy 335.29333 -244.178588) (xy 335.342185 -244.18452) (xy 335.389456 -244.198212)
			(xy 335.433918 -244.21931) (xy 335.474421 -244.247266) (xy 335.509914 -244.281358) (xy 335.539479 -244.320702)
			(xy 335.56235 -244.364279) (xy 335.577934 -244.41096) (xy 335.585829 -244.459537) (xy 335.586324 -244.484144)
			(xy 335.915266 -244.484144) (xy 335.919226 -244.43509) (xy 335.931003 -244.387306) (xy 335.950294 -244.34203)
			(xy 335.976597 -244.300434) (xy 336.009232 -244.263597) (xy 336.047353 -244.232472) (xy 336.089974 -244.207865)
			(xy 336.13599 -244.190413) (xy 336.184209 -244.180569) (xy 336.233384 -244.178588) (xy 336.282239 -244.18452)
			(xy 336.32951 -244.198212) (xy 336.373972 -244.21931) (xy 336.414475 -244.247266) (xy 336.449968 -244.281358)
			(xy 336.479533 -244.320702) (xy 336.502404 -244.364279) (xy 336.517988 -244.41096) (xy 336.525883 -244.459537)
			(xy 336.526378 -244.484144) (xy 336.85532 -244.484144) (xy 336.85928 -244.43509) (xy 336.871057 -244.387306)
			(xy 336.890348 -244.34203) (xy 336.916651 -244.300434) (xy 336.949286 -244.263597) (xy 336.987407 -244.232472)
			(xy 337.030028 -244.207865) (xy 337.076044 -244.190413) (xy 337.124263 -244.180569) (xy 337.173438 -244.178588)
			(xy 337.222293 -244.18452) (xy 337.269564 -244.198212) (xy 337.314026 -244.21931) (xy 337.354529 -244.247266)
			(xy 337.390022 -244.281358) (xy 337.419587 -244.320702) (xy 337.442458 -244.364279) (xy 337.458042 -244.41096)
			(xy 337.465937 -244.459537) (xy 337.466432 -244.484144) (xy 337.795374 -244.484144) (xy 337.799334 -244.43509)
			(xy 337.811111 -244.387306) (xy 337.830402 -244.34203) (xy 337.856705 -244.300434) (xy 337.88934 -244.263597)
			(xy 337.927461 -244.232472) (xy 337.970082 -244.207865) (xy 338.016098 -244.190413) (xy 338.064317 -244.180569)
			(xy 338.113492 -244.178588) (xy 338.162347 -244.18452) (xy 338.209618 -244.198212) (xy 338.25408 -244.21931)
			(xy 338.294583 -244.247266) (xy 338.330076 -244.281358) (xy 338.359641 -244.320702) (xy 338.382512 -244.364279)
			(xy 338.398096 -244.41096) (xy 338.405991 -244.459537) (xy 338.406486 -244.484144) (xy 338.724743 -244.484144)
			(xy 338.728838 -244.433416) (xy 338.741017 -244.384002) (xy 338.760965 -244.337182) (xy 338.788166 -244.294168)
			(xy 338.821914 -244.256074) (xy 338.861336 -244.223887) (xy 338.90541 -244.198441) (xy 338.952996 -244.180394)
			(xy 339.00286 -244.170214) (xy 339.053712 -244.168165) (xy 339.104233 -244.174299) (xy 339.153117 -244.188459)
			(xy 339.199096 -244.210276) (xy 339.24098 -244.239186) (xy 339.277684 -244.274441) (xy 339.308257 -244.315127)
			(xy 339.331908 -244.36019) (xy 339.348024 -244.408464) (xy 339.356188 -244.458698) (xy 339.3567 -244.484144)
			(xy 339.664797 -244.484144) (xy 339.668892 -244.433416) (xy 339.681071 -244.384002) (xy 339.701019 -244.337182)
			(xy 339.72822 -244.294168) (xy 339.761968 -244.256074) (xy 339.80139 -244.223887) (xy 339.845464 -244.198441)
			(xy 339.89305 -244.180394) (xy 339.942914 -244.170214) (xy 339.993766 -244.168165) (xy 340.044287 -244.174299)
			(xy 340.093171 -244.188459) (xy 340.13915 -244.210276) (xy 340.181034 -244.239186) (xy 340.217738 -244.274441)
			(xy 340.248311 -244.315127) (xy 340.271962 -244.36019) (xy 340.288078 -244.408464) (xy 340.296242 -244.458698)
			(xy 340.296754 -244.484144) (xy 341.544905 -244.484144) (xy 341.549 -244.433416) (xy 341.561179 -244.384002)
			(xy 341.581127 -244.337182) (xy 341.608328 -244.294168) (xy 341.642076 -244.256074) (xy 341.681498 -244.223887)
			(xy 341.725572 -244.198441) (xy 341.773158 -244.180394) (xy 341.823022 -244.170214) (xy 341.873874 -244.168165)
			(xy 341.924395 -244.174299) (xy 341.973279 -244.188459) (xy 342.019258 -244.210276) (xy 342.061142 -244.239186)
			(xy 342.097846 -244.274441) (xy 342.128419 -244.315127) (xy 342.15207 -244.36019) (xy 342.168186 -244.408464)
			(xy 342.17635 -244.458698) (xy 342.176862 -244.484144) (xy 342.49539 -244.484144) (xy 342.49935 -244.43509)
			(xy 342.511127 -244.387306) (xy 342.530418 -244.34203) (xy 342.556721 -244.300434) (xy 342.589356 -244.263597)
			(xy 342.627477 -244.232472) (xy 342.670098 -244.207865) (xy 342.716114 -244.190413) (xy 342.764333 -244.180569)
			(xy 342.813508 -244.178588) (xy 342.862363 -244.18452) (xy 342.909634 -244.198212) (xy 342.954096 -244.21931)
			(xy 342.994599 -244.247266) (xy 343.030092 -244.281358) (xy 343.059657 -244.320702) (xy 343.082528 -244.364279)
			(xy 343.098112 -244.41096) (xy 343.106007 -244.459537) (xy 343.106502 -244.484144) (xy 343.424759 -244.484144)
			(xy 343.428854 -244.433416) (xy 343.441033 -244.384002) (xy 343.460981 -244.337182) (xy 343.488182 -244.294168)
			(xy 343.52193 -244.256074) (xy 343.561352 -244.223887) (xy 343.605426 -244.198441) (xy 343.653012 -244.180394)
			(xy 343.702876 -244.170214) (xy 343.753728 -244.168165) (xy 343.804249 -244.174299) (xy 343.853133 -244.188459)
			(xy 343.899112 -244.210276) (xy 343.940996 -244.239186) (xy 343.9777 -244.274441) (xy 344.008273 -244.315127)
			(xy 344.031924 -244.36019) (xy 344.04804 -244.408464) (xy 344.056204 -244.458698) (xy 344.056716 -244.484144)
			(xy 344.056204 -244.50959) (xy 344.04804 -244.559824) (xy 344.031924 -244.608098) (xy 344.008273 -244.653161)
			(xy 343.9777 -244.693847) (xy 343.940996 -244.729102) (xy 343.899112 -244.758012) (xy 343.853133 -244.779829)
			(xy 343.804249 -244.793989) (xy 343.753728 -244.800123) (xy 343.702876 -244.798074) (xy 343.653012 -244.787894)
			(xy 343.605426 -244.769847) (xy 343.561352 -244.744401) (xy 343.52193 -244.712214) (xy 343.488182 -244.67412)
			(xy 343.460981 -244.631106) (xy 343.441033 -244.584286) (xy 343.428854 -244.534872) (xy 343.424759 -244.484144)
			(xy 343.106502 -244.484144) (xy 343.106007 -244.508751) (xy 343.098112 -244.557328) (xy 343.082528 -244.604009)
			(xy 343.059657 -244.647586) (xy 343.030092 -244.68693) (xy 342.994599 -244.721022) (xy 342.954096 -244.748978)
			(xy 342.909634 -244.770076) (xy 342.862363 -244.783768) (xy 342.813508 -244.7897) (xy 342.764333 -244.787719)
			(xy 342.716114 -244.777875) (xy 342.670098 -244.760423) (xy 342.627477 -244.735816) (xy 342.589356 -244.704691)
			(xy 342.556721 -244.667854) (xy 342.530418 -244.626258) (xy 342.511127 -244.580982) (xy 342.49935 -244.533198)
			(xy 342.49539 -244.484144) (xy 342.176862 -244.484144) (xy 342.17635 -244.50959) (xy 342.168186 -244.559824)
			(xy 342.15207 -244.608098) (xy 342.128419 -244.653161) (xy 342.097846 -244.693847) (xy 342.061142 -244.729102)
			(xy 342.019258 -244.758012) (xy 341.973279 -244.779829) (xy 341.924395 -244.793989) (xy 341.873874 -244.800123)
			(xy 341.823022 -244.798074) (xy 341.773158 -244.787894) (xy 341.725572 -244.769847) (xy 341.681498 -244.744401)
			(xy 341.642076 -244.712214) (xy 341.608328 -244.67412) (xy 341.581127 -244.631106) (xy 341.561179 -244.584286)
			(xy 341.549 -244.534872) (xy 341.544905 -244.484144) (xy 340.296754 -244.484144) (xy 340.296242 -244.50959)
			(xy 340.288078 -244.559824) (xy 340.271962 -244.608098) (xy 340.248311 -244.653161) (xy 340.217738 -244.693847)
			(xy 340.181034 -244.729102) (xy 340.13915 -244.758012) (xy 340.093171 -244.779829) (xy 340.044287 -244.793989)
			(xy 339.993766 -244.800123) (xy 339.942914 -244.798074) (xy 339.89305 -244.787894) (xy 339.845464 -244.769847)
			(xy 339.80139 -244.744401) (xy 339.761968 -244.712214) (xy 339.72822 -244.67412) (xy 339.701019 -244.631106)
			(xy 339.681071 -244.584286) (xy 339.668892 -244.534872) (xy 339.664797 -244.484144) (xy 339.3567 -244.484144)
			(xy 339.356188 -244.50959) (xy 339.348024 -244.559824) (xy 339.331908 -244.608098) (xy 339.308257 -244.653161)
			(xy 339.277684 -244.693847) (xy 339.24098 -244.729102) (xy 339.199096 -244.758012) (xy 339.153117 -244.779829)
			(xy 339.104233 -244.793989) (xy 339.053712 -244.800123) (xy 339.00286 -244.798074) (xy 338.952996 -244.787894)
			(xy 338.90541 -244.769847) (xy 338.861336 -244.744401) (xy 338.821914 -244.712214) (xy 338.788166 -244.67412)
			(xy 338.760965 -244.631106) (xy 338.741017 -244.584286) (xy 338.728838 -244.534872) (xy 338.724743 -244.484144)
			(xy 338.406486 -244.484144) (xy 338.405991 -244.508751) (xy 338.398096 -244.557328) (xy 338.382512 -244.604009)
			(xy 338.359641 -244.647586) (xy 338.330076 -244.68693) (xy 338.294583 -244.721022) (xy 338.25408 -244.748978)
			(xy 338.209618 -244.770076) (xy 338.162347 -244.783768) (xy 338.113492 -244.7897) (xy 338.064317 -244.787719)
			(xy 338.016098 -244.777875) (xy 337.970082 -244.760423) (xy 337.927461 -244.735816) (xy 337.88934 -244.704691)
			(xy 337.856705 -244.667854) (xy 337.830402 -244.626258) (xy 337.811111 -244.580982) (xy 337.799334 -244.533198)
			(xy 337.795374 -244.484144) (xy 337.466432 -244.484144) (xy 337.465937 -244.508751) (xy 337.458042 -244.557328)
			(xy 337.442458 -244.604009) (xy 337.419587 -244.647586) (xy 337.390022 -244.68693) (xy 337.354529 -244.721022)
			(xy 337.314026 -244.748978) (xy 337.269564 -244.770076) (xy 337.222293 -244.783768) (xy 337.173438 -244.7897)
			(xy 337.124263 -244.787719) (xy 337.076044 -244.777875) (xy 337.030028 -244.760423) (xy 336.987407 -244.735816)
			(xy 336.949286 -244.704691) (xy 336.916651 -244.667854) (xy 336.890348 -244.626258) (xy 336.871057 -244.580982)
			(xy 336.85928 -244.533198) (xy 336.85532 -244.484144) (xy 336.526378 -244.484144) (xy 336.525883 -244.508751)
			(xy 336.517988 -244.557328) (xy 336.502404 -244.604009) (xy 336.479533 -244.647586) (xy 336.449968 -244.68693)
			(xy 336.414475 -244.721022) (xy 336.373972 -244.748978) (xy 336.32951 -244.770076) (xy 336.282239 -244.783768)
			(xy 336.233384 -244.7897) (xy 336.184209 -244.787719) (xy 336.13599 -244.777875) (xy 336.089974 -244.760423)
			(xy 336.047353 -244.735816) (xy 336.009232 -244.704691) (xy 335.976597 -244.667854) (xy 335.950294 -244.626258)
			(xy 335.931003 -244.580982) (xy 335.919226 -244.533198) (xy 335.915266 -244.484144) (xy 335.586324 -244.484144)
			(xy 335.585829 -244.508751) (xy 335.577934 -244.557328) (xy 335.56235 -244.604009) (xy 335.539479 -244.647586)
			(xy 335.509914 -244.68693) (xy 335.474421 -244.721022) (xy 335.433918 -244.748978) (xy 335.389456 -244.770076)
			(xy 335.342185 -244.783768) (xy 335.29333 -244.7897) (xy 335.244155 -244.787719) (xy 335.195936 -244.777875)
			(xy 335.14992 -244.760423) (xy 335.107299 -244.735816) (xy 335.069178 -244.704691) (xy 335.036543 -244.667854)
			(xy 335.01024 -244.626258) (xy 334.990949 -244.580982) (xy 334.979172 -244.533198) (xy 334.975212 -244.484144)
			(xy 333.70647 -244.484144) (xy 333.705975 -244.508751) (xy 333.69808 -244.557328) (xy 333.682496 -244.604009)
			(xy 333.659625 -244.647586) (xy 333.63006 -244.68693) (xy 333.594567 -244.721022) (xy 333.554064 -244.748978)
			(xy 333.509602 -244.770076) (xy 333.462331 -244.783768) (xy 333.413476 -244.7897) (xy 333.364301 -244.787719)
			(xy 333.316082 -244.777875) (xy 333.270066 -244.760423) (xy 333.227445 -244.735816) (xy 333.189324 -244.704691)
			(xy 333.156689 -244.667854) (xy 333.130386 -244.626258) (xy 333.111095 -244.580982) (xy 333.099318 -244.533198)
			(xy 333.095358 -244.484144) (xy 332.766416 -244.484144) (xy 332.765921 -244.508751) (xy 332.758026 -244.557328)
			(xy 332.742442 -244.604009) (xy 332.719571 -244.647586) (xy 332.690006 -244.68693) (xy 332.654513 -244.721022)
			(xy 332.61401 -244.748978) (xy 332.569548 -244.770076) (xy 332.522277 -244.783768) (xy 332.473422 -244.7897)
			(xy 332.424247 -244.787719) (xy 332.376028 -244.777875) (xy 332.330012 -244.760423) (xy 332.287391 -244.735816)
			(xy 332.24927 -244.704691) (xy 332.216635 -244.667854) (xy 332.190332 -244.626258) (xy 332.171041 -244.580982)
			(xy 332.159264 -244.533198) (xy 332.155304 -244.484144) (xy 331.826012 -244.484144) (xy 331.826012 -244.509135)
			(xy 331.817847 -244.558526) (xy 331.801736 -244.605924) (xy 331.778112 -244.65006) (xy 331.747605 -244.689753)
			(xy 331.711034 -244.723939) (xy 331.669378 -244.751703) (xy 331.623751 -244.772302) (xy 331.575376 -244.785185)
			(xy 331.550518 -244.788182) (xy 331.550264 -244.788182) (xy 331.540612 -244.789198) (xy 331.532738 -244.793008)
			(xy 331.528476 -244.795209) (xy 331.520799 -244.800958) (xy 331.517498 -244.804438) (xy 331.47254 -244.853968)
			(xy 331.46649 -244.861141) (xy 331.459715 -244.878627) (xy 331.459332 -244.888004) (xy 331.459332 -245.29415)
			(xy 331.685404 -245.29415) (xy 331.689364 -245.245096) (xy 331.701141 -245.197312) (xy 331.720432 -245.152036)
			(xy 331.746735 -245.11044) (xy 331.77937 -245.073603) (xy 331.817491 -245.042478) (xy 331.860112 -245.017871)
			(xy 331.906128 -245.000419) (xy 331.954347 -244.990575) (xy 332.003522 -244.988594) (xy 332.052377 -244.994526)
			(xy 332.099648 -245.008218) (xy 332.14411 -245.029316) (xy 332.184613 -245.057272) (xy 332.220106 -245.091364)
			(xy 332.249671 -245.130708) (xy 332.272542 -245.174285) (xy 332.288126 -245.220966) (xy 332.296021 -245.269543)
			(xy 332.296516 -245.29415) (xy 332.625204 -245.29415) (xy 332.629164 -245.245096) (xy 332.640941 -245.197312)
			(xy 332.660232 -245.152036) (xy 332.686535 -245.11044) (xy 332.71917 -245.073603) (xy 332.757291 -245.042478)
			(xy 332.799912 -245.017871) (xy 332.845928 -245.000419) (xy 332.894147 -244.990575) (xy 332.943322 -244.988594)
			(xy 332.992177 -244.994526) (xy 333.039448 -245.008218) (xy 333.08391 -245.029316) (xy 333.124413 -245.057272)
			(xy 333.159906 -245.091364) (xy 333.189471 -245.130708) (xy 333.212342 -245.174285) (xy 333.227926 -245.220966)
			(xy 333.235821 -245.269543) (xy 333.236316 -245.29415) (xy 333.565258 -245.29415) (xy 333.569218 -245.245096)
			(xy 333.580995 -245.197312) (xy 333.600286 -245.152036) (xy 333.626589 -245.11044) (xy 333.659224 -245.073603)
			(xy 333.697345 -245.042478) (xy 333.739966 -245.017871) (xy 333.785982 -245.000419) (xy 333.834201 -244.990575)
			(xy 333.883376 -244.988594) (xy 333.932231 -244.994526) (xy 333.979502 -245.008218) (xy 334.023964 -245.029316)
			(xy 334.064467 -245.057272) (xy 334.09996 -245.091364) (xy 334.129525 -245.130708) (xy 334.152396 -245.174285)
			(xy 334.16798 -245.220966) (xy 334.175875 -245.269543) (xy 334.17637 -245.29415) (xy 334.505312 -245.29415)
			(xy 334.509272 -245.245096) (xy 334.521049 -245.197312) (xy 334.54034 -245.152036) (xy 334.566643 -245.11044)
			(xy 334.599278 -245.073603) (xy 334.637399 -245.042478) (xy 334.68002 -245.017871) (xy 334.726036 -245.000419)
			(xy 334.774255 -244.990575) (xy 334.82343 -244.988594) (xy 334.872285 -244.994526) (xy 334.919556 -245.008218)
			(xy 334.964018 -245.029316) (xy 335.004521 -245.057272) (xy 335.040014 -245.091364) (xy 335.069579 -245.130708)
			(xy 335.09245 -245.174285) (xy 335.108034 -245.220966) (xy 335.115929 -245.269543) (xy 335.116424 -245.29415)
			(xy 335.445366 -245.29415) (xy 335.449326 -245.245096) (xy 335.461103 -245.197312) (xy 335.480394 -245.152036)
			(xy 335.506697 -245.11044) (xy 335.539332 -245.073603) (xy 335.577453 -245.042478) (xy 335.620074 -245.017871)
			(xy 335.66609 -245.000419) (xy 335.714309 -244.990575) (xy 335.763484 -244.988594) (xy 335.812339 -244.994526)
			(xy 335.85961 -245.008218) (xy 335.904072 -245.029316) (xy 335.944575 -245.057272) (xy 335.980068 -245.091364)
			(xy 336.009633 -245.130708) (xy 336.032504 -245.174285) (xy 336.048088 -245.220966) (xy 336.055983 -245.269543)
			(xy 336.056478 -245.29415) (xy 336.38542 -245.29415) (xy 336.38938 -245.245096) (xy 336.401157 -245.197312)
			(xy 336.420448 -245.152036) (xy 336.446751 -245.11044) (xy 336.479386 -245.073603) (xy 336.517507 -245.042478)
			(xy 336.560128 -245.017871) (xy 336.606144 -245.000419) (xy 336.654363 -244.990575) (xy 336.703538 -244.988594)
			(xy 336.752393 -244.994526) (xy 336.799664 -245.008218) (xy 336.844126 -245.029316) (xy 336.884629 -245.057272)
			(xy 336.920122 -245.091364) (xy 336.949687 -245.130708) (xy 336.972558 -245.174285) (xy 336.988142 -245.220966)
			(xy 336.996037 -245.269543) (xy 336.996532 -245.29415) (xy 337.32522 -245.29415) (xy 337.32918 -245.245096)
			(xy 337.340957 -245.197312) (xy 337.360248 -245.152036) (xy 337.386551 -245.11044) (xy 337.419186 -245.073603)
			(xy 337.457307 -245.042478) (xy 337.499928 -245.017871) (xy 337.545944 -245.000419) (xy 337.594163 -244.990575)
			(xy 337.643338 -244.988594) (xy 337.692193 -244.994526) (xy 337.739464 -245.008218) (xy 337.783926 -245.029316)
			(xy 337.824429 -245.057272) (xy 337.859922 -245.091364) (xy 337.889487 -245.130708) (xy 337.912358 -245.174285)
			(xy 337.927942 -245.220966) (xy 337.935837 -245.269543) (xy 337.936332 -245.29415) (xy 338.254843 -245.29415)
			(xy 338.258938 -245.243422) (xy 338.271117 -245.194008) (xy 338.291065 -245.147188) (xy 338.318266 -245.104174)
			(xy 338.352014 -245.06608) (xy 338.391436 -245.033893) (xy 338.43551 -245.008447) (xy 338.483096 -244.9904)
			(xy 338.53296 -244.98022) (xy 338.583812 -244.978171) (xy 338.634333 -244.984305) (xy 338.683217 -244.998465)
			(xy 338.729196 -245.020282) (xy 338.77108 -245.049192) (xy 338.807784 -245.084447) (xy 338.838357 -245.125133)
			(xy 338.862008 -245.170196) (xy 338.878124 -245.21847) (xy 338.886288 -245.268704) (xy 338.8868 -245.29415)
			(xy 339.205328 -245.29415) (xy 339.209288 -245.245096) (xy 339.221065 -245.197312) (xy 339.240356 -245.152036)
			(xy 339.266659 -245.11044) (xy 339.299294 -245.073603) (xy 339.337415 -245.042478) (xy 339.380036 -245.017871)
			(xy 339.426052 -245.000419) (xy 339.474271 -244.990575) (xy 339.523446 -244.988594) (xy 339.572301 -244.994526)
			(xy 339.619572 -245.008218) (xy 339.664034 -245.029316) (xy 339.704537 -245.057272) (xy 339.74003 -245.091364)
			(xy 339.769595 -245.130708) (xy 339.792466 -245.174285) (xy 339.80805 -245.220966) (xy 339.815945 -245.269543)
			(xy 339.81644 -245.29415) (xy 340.134951 -245.29415) (xy 340.139046 -245.243422) (xy 340.151225 -245.194008)
			(xy 340.171173 -245.147188) (xy 340.198374 -245.104174) (xy 340.232122 -245.06608) (xy 340.271544 -245.033893)
			(xy 340.315618 -245.008447) (xy 340.363204 -244.9904) (xy 340.413068 -244.98022) (xy 340.46392 -244.978171)
			(xy 340.514441 -244.984305) (xy 340.563325 -244.998465) (xy 340.609304 -245.020282) (xy 340.651188 -245.049192)
			(xy 340.687892 -245.084447) (xy 340.718465 -245.125133) (xy 340.742116 -245.170196) (xy 340.758232 -245.21847)
			(xy 340.766396 -245.268704) (xy 340.766908 -245.29415) (xy 341.085182 -245.29415) (xy 341.089142 -245.245096)
			(xy 341.100919 -245.197312) (xy 341.12021 -245.152036) (xy 341.146513 -245.11044) (xy 341.179148 -245.073603)
			(xy 341.217269 -245.042478) (xy 341.25989 -245.017871) (xy 341.305906 -245.000419) (xy 341.354125 -244.990575)
			(xy 341.4033 -244.988594) (xy 341.452155 -244.994526) (xy 341.499426 -245.008218) (xy 341.543888 -245.029316)
			(xy 341.584391 -245.057272) (xy 341.619884 -245.091364) (xy 341.649449 -245.130708) (xy 341.67232 -245.174285)
			(xy 341.687904 -245.220966) (xy 341.695799 -245.269543) (xy 341.696294 -245.29415) (xy 342.014805 -245.29415)
			(xy 342.0189 -245.243422) (xy 342.031079 -245.194008) (xy 342.051027 -245.147188) (xy 342.078228 -245.104174)
			(xy 342.111976 -245.06608) (xy 342.151398 -245.033893) (xy 342.195472 -245.008447) (xy 342.243058 -244.9904)
			(xy 342.292922 -244.98022) (xy 342.343774 -244.978171) (xy 342.394295 -244.984305) (xy 342.443179 -244.998465)
			(xy 342.489158 -245.020282) (xy 342.531042 -245.049192) (xy 342.567746 -245.084447) (xy 342.598319 -245.125133)
			(xy 342.62197 -245.170196) (xy 342.638086 -245.21847) (xy 342.64625 -245.268704) (xy 342.646762 -245.29415)
			(xy 342.954859 -245.29415) (xy 342.958954 -245.243422) (xy 342.971133 -245.194008) (xy 342.991081 -245.147188)
			(xy 343.018282 -245.104174) (xy 343.05203 -245.06608) (xy 343.091452 -245.033893) (xy 343.135526 -245.008447)
			(xy 343.183112 -244.9904) (xy 343.232976 -244.98022) (xy 343.283828 -244.978171) (xy 343.334349 -244.984305)
			(xy 343.383233 -244.998465) (xy 343.429212 -245.020282) (xy 343.471096 -245.049192) (xy 343.5078 -245.084447)
			(xy 343.538373 -245.125133) (xy 343.562024 -245.170196) (xy 343.57814 -245.21847) (xy 343.586304 -245.268704)
			(xy 343.586816 -245.29415) (xy 343.586304 -245.319596) (xy 343.57814 -245.36983) (xy 343.562024 -245.418104)
			(xy 343.538373 -245.463167) (xy 343.5078 -245.503853) (xy 343.471096 -245.539108) (xy 343.429212 -245.568018)
			(xy 343.383233 -245.589835) (xy 343.334349 -245.603995) (xy 343.283828 -245.610129) (xy 343.232976 -245.60808)
			(xy 343.183112 -245.5979) (xy 343.135526 -245.579853) (xy 343.091452 -245.554407) (xy 343.05203 -245.52222)
			(xy 343.018282 -245.484126) (xy 342.991081 -245.441112) (xy 342.971133 -245.394292) (xy 342.958954 -245.344878)
			(xy 342.954859 -245.29415) (xy 342.646762 -245.29415) (xy 342.64625 -245.319596) (xy 342.638086 -245.36983)
			(xy 342.62197 -245.418104) (xy 342.598319 -245.463167) (xy 342.567746 -245.503853) (xy 342.531042 -245.539108)
			(xy 342.489158 -245.568018) (xy 342.443179 -245.589835) (xy 342.394295 -245.603995) (xy 342.343774 -245.610129)
			(xy 342.292922 -245.60808) (xy 342.243058 -245.5979) (xy 342.195472 -245.579853) (xy 342.151398 -245.554407)
			(xy 342.111976 -245.52222) (xy 342.078228 -245.484126) (xy 342.051027 -245.441112) (xy 342.031079 -245.394292)
			(xy 342.0189 -245.344878) (xy 342.014805 -245.29415) (xy 341.696294 -245.29415) (xy 341.695799 -245.318757)
			(xy 341.687904 -245.367334) (xy 341.67232 -245.414015) (xy 341.649449 -245.457592) (xy 341.619884 -245.496936)
			(xy 341.584391 -245.531028) (xy 341.543888 -245.558984) (xy 341.499426 -245.580082) (xy 341.452155 -245.593774)
			(xy 341.4033 -245.599706) (xy 341.354125 -245.597725) (xy 341.305906 -245.587881) (xy 341.25989 -245.570429)
			(xy 341.217269 -245.545822) (xy 341.179148 -245.514697) (xy 341.146513 -245.47786) (xy 341.12021 -245.436264)
			(xy 341.100919 -245.390988) (xy 341.089142 -245.343204) (xy 341.085182 -245.29415) (xy 340.766908 -245.29415)
			(xy 340.766396 -245.319596) (xy 340.758232 -245.36983) (xy 340.742116 -245.418104) (xy 340.718465 -245.463167)
			(xy 340.687892 -245.503853) (xy 340.651188 -245.539108) (xy 340.609304 -245.568018) (xy 340.563325 -245.589835)
			(xy 340.514441 -245.603995) (xy 340.46392 -245.610129) (xy 340.413068 -245.60808) (xy 340.363204 -245.5979)
			(xy 340.315618 -245.579853) (xy 340.271544 -245.554407) (xy 340.232122 -245.52222) (xy 340.198374 -245.484126)
			(xy 340.171173 -245.441112) (xy 340.151225 -245.394292) (xy 340.139046 -245.344878) (xy 340.134951 -245.29415)
			(xy 339.81644 -245.29415) (xy 339.815945 -245.318757) (xy 339.80805 -245.367334) (xy 339.792466 -245.414015)
			(xy 339.769595 -245.457592) (xy 339.74003 -245.496936) (xy 339.704537 -245.531028) (xy 339.664034 -245.558984)
			(xy 339.619572 -245.580082) (xy 339.572301 -245.593774) (xy 339.523446 -245.599706) (xy 339.474271 -245.597725)
			(xy 339.426052 -245.587881) (xy 339.380036 -245.570429) (xy 339.337415 -245.545822) (xy 339.299294 -245.514697)
			(xy 339.266659 -245.47786) (xy 339.240356 -245.436264) (xy 339.221065 -245.390988) (xy 339.209288 -245.343204)
			(xy 339.205328 -245.29415) (xy 338.8868 -245.29415) (xy 338.886288 -245.319596) (xy 338.878124 -245.36983)
			(xy 338.862008 -245.418104) (xy 338.838357 -245.463167) (xy 338.807784 -245.503853) (xy 338.77108 -245.539108)
			(xy 338.729196 -245.568018) (xy 338.683217 -245.589835) (xy 338.634333 -245.603995) (xy 338.583812 -245.610129)
			(xy 338.53296 -245.60808) (xy 338.483096 -245.5979) (xy 338.43551 -245.579853) (xy 338.391436 -245.554407)
			(xy 338.352014 -245.52222) (xy 338.318266 -245.484126) (xy 338.291065 -245.441112) (xy 338.271117 -245.394292)
			(xy 338.258938 -245.344878) (xy 338.254843 -245.29415) (xy 337.936332 -245.29415) (xy 337.935837 -245.318757)
			(xy 337.927942 -245.367334) (xy 337.912358 -245.414015) (xy 337.889487 -245.457592) (xy 337.859922 -245.496936)
			(xy 337.824429 -245.531028) (xy 337.783926 -245.558984) (xy 337.739464 -245.580082) (xy 337.692193 -245.593774)
			(xy 337.643338 -245.599706) (xy 337.594163 -245.597725) (xy 337.545944 -245.587881) (xy 337.499928 -245.570429)
			(xy 337.457307 -245.545822) (xy 337.419186 -245.514697) (xy 337.386551 -245.47786) (xy 337.360248 -245.436264)
			(xy 337.340957 -245.390988) (xy 337.32918 -245.343204) (xy 337.32522 -245.29415) (xy 336.996532 -245.29415)
			(xy 336.996037 -245.318757) (xy 336.988142 -245.367334) (xy 336.972558 -245.414015) (xy 336.949687 -245.457592)
			(xy 336.920122 -245.496936) (xy 336.884629 -245.531028) (xy 336.844126 -245.558984) (xy 336.799664 -245.580082)
			(xy 336.752393 -245.593774) (xy 336.703538 -245.599706) (xy 336.654363 -245.597725) (xy 336.606144 -245.587881)
			(xy 336.560128 -245.570429) (xy 336.517507 -245.545822) (xy 336.479386 -245.514697) (xy 336.446751 -245.47786)
			(xy 336.420448 -245.436264) (xy 336.401157 -245.390988) (xy 336.38938 -245.343204) (xy 336.38542 -245.29415)
			(xy 336.056478 -245.29415) (xy 336.055983 -245.318757) (xy 336.048088 -245.367334) (xy 336.032504 -245.414015)
			(xy 336.009633 -245.457592) (xy 335.980068 -245.496936) (xy 335.944575 -245.531028) (xy 335.904072 -245.558984)
			(xy 335.85961 -245.580082) (xy 335.812339 -245.593774) (xy 335.763484 -245.599706) (xy 335.714309 -245.597725)
			(xy 335.66609 -245.587881) (xy 335.620074 -245.570429) (xy 335.577453 -245.545822) (xy 335.539332 -245.514697)
			(xy 335.506697 -245.47786) (xy 335.480394 -245.436264) (xy 335.461103 -245.390988) (xy 335.449326 -245.343204)
			(xy 335.445366 -245.29415) (xy 335.116424 -245.29415) (xy 335.115929 -245.318757) (xy 335.108034 -245.367334)
			(xy 335.09245 -245.414015) (xy 335.069579 -245.457592) (xy 335.040014 -245.496936) (xy 335.004521 -245.531028)
			(xy 334.964018 -245.558984) (xy 334.919556 -245.580082) (xy 334.872285 -245.593774) (xy 334.82343 -245.599706)
			(xy 334.774255 -245.597725) (xy 334.726036 -245.587881) (xy 334.68002 -245.570429) (xy 334.637399 -245.545822)
			(xy 334.599278 -245.514697) (xy 334.566643 -245.47786) (xy 334.54034 -245.436264) (xy 334.521049 -245.390988)
			(xy 334.509272 -245.343204) (xy 334.505312 -245.29415) (xy 334.17637 -245.29415) (xy 334.175875 -245.318757)
			(xy 334.16798 -245.367334) (xy 334.152396 -245.414015) (xy 334.129525 -245.457592) (xy 334.09996 -245.496936)
			(xy 334.064467 -245.531028) (xy 334.023964 -245.558984) (xy 333.979502 -245.580082) (xy 333.932231 -245.593774)
			(xy 333.883376 -245.599706) (xy 333.834201 -245.597725) (xy 333.785982 -245.587881) (xy 333.739966 -245.570429)
			(xy 333.697345 -245.545822) (xy 333.659224 -245.514697) (xy 333.626589 -245.47786) (xy 333.600286 -245.436264)
			(xy 333.580995 -245.390988) (xy 333.569218 -245.343204) (xy 333.565258 -245.29415) (xy 333.236316 -245.29415)
			(xy 333.235821 -245.318757) (xy 333.227926 -245.367334) (xy 333.212342 -245.414015) (xy 333.189471 -245.457592)
			(xy 333.159906 -245.496936) (xy 333.124413 -245.531028) (xy 333.08391 -245.558984) (xy 333.039448 -245.580082)
			(xy 332.992177 -245.593774) (xy 332.943322 -245.599706) (xy 332.894147 -245.597725) (xy 332.845928 -245.587881)
			(xy 332.799912 -245.570429) (xy 332.757291 -245.545822) (xy 332.71917 -245.514697) (xy 332.686535 -245.47786)
			(xy 332.660232 -245.436264) (xy 332.640941 -245.390988) (xy 332.629164 -245.343204) (xy 332.625204 -245.29415)
			(xy 332.296516 -245.29415) (xy 332.296021 -245.318757) (xy 332.288126 -245.367334) (xy 332.272542 -245.414015)
			(xy 332.249671 -245.457592) (xy 332.220106 -245.496936) (xy 332.184613 -245.531028) (xy 332.14411 -245.558984)
			(xy 332.099648 -245.580082) (xy 332.052377 -245.593774) (xy 332.003522 -245.599706) (xy 331.954347 -245.597725)
			(xy 331.906128 -245.587881) (xy 331.860112 -245.570429) (xy 331.817491 -245.545822) (xy 331.77937 -245.514697)
			(xy 331.746735 -245.47786) (xy 331.720432 -245.436264) (xy 331.701141 -245.390988) (xy 331.689364 -245.343204)
			(xy 331.685404 -245.29415) (xy 331.459332 -245.29415) (xy 331.459332 -245.700296) (xy 331.459809 -245.709652)
			(xy 331.466582 -245.727103) (xy 331.47254 -245.734332) (xy 331.517498 -245.783862) (xy 331.520808 -245.787333)
			(xy 331.528476 -245.793092) (xy 331.532738 -245.795292) (xy 331.540612 -245.799102) (xy 331.550264 -245.800118)
			(xy 331.550518 -245.800118) (xy 331.575391 -245.803029) (xy 331.62378 -245.815915) (xy 331.66942 -245.83652)
			(xy 331.711089 -245.864292) (xy 331.74767 -245.898488) (xy 331.778185 -245.938192) (xy 331.801817 -245.982341)
			(xy 331.817932 -246.029753) (xy 331.826099 -246.079158) (xy 331.826099 -246.104156) (xy 332.155304 -246.104156)
			(xy 332.159264 -246.055102) (xy 332.171041 -246.007318) (xy 332.190332 -245.962042) (xy 332.216635 -245.920446)
			(xy 332.24927 -245.883609) (xy 332.287391 -245.852484) (xy 332.330012 -245.827877) (xy 332.376028 -245.810425)
			(xy 332.424247 -245.800581) (xy 332.473422 -245.7986) (xy 332.522277 -245.804532) (xy 332.569548 -245.818224)
			(xy 332.61401 -245.839322) (xy 332.654513 -245.867278) (xy 332.690006 -245.90137) (xy 332.719571 -245.940714)
			(xy 332.742442 -245.984291) (xy 332.758026 -246.030972) (xy 332.765921 -246.079549) (xy 332.766416 -246.104156)
			(xy 333.095358 -246.104156) (xy 333.099318 -246.055102) (xy 333.111095 -246.007318) (xy 333.130386 -245.962042)
			(xy 333.156689 -245.920446) (xy 333.189324 -245.883609) (xy 333.227445 -245.852484) (xy 333.270066 -245.827877)
			(xy 333.316082 -245.810425) (xy 333.364301 -245.800581) (xy 333.413476 -245.7986) (xy 333.462331 -245.804532)
			(xy 333.509602 -245.818224) (xy 333.554064 -245.839322) (xy 333.594567 -245.867278) (xy 333.63006 -245.90137)
			(xy 333.659625 -245.940714) (xy 333.682496 -245.984291) (xy 333.69808 -246.030972) (xy 333.705975 -246.079549)
			(xy 333.70647 -246.104156) (xy 334.035412 -246.104156) (xy 334.039372 -246.055102) (xy 334.051149 -246.007318)
			(xy 334.07044 -245.962042) (xy 334.096743 -245.920446) (xy 334.129378 -245.883609) (xy 334.167499 -245.852484)
			(xy 334.21012 -245.827877) (xy 334.256136 -245.810425) (xy 334.304355 -245.800581) (xy 334.35353 -245.7986)
			(xy 334.402385 -245.804532) (xy 334.449656 -245.818224) (xy 334.494118 -245.839322) (xy 334.534621 -245.867278)
			(xy 334.570114 -245.90137) (xy 334.599679 -245.940714) (xy 334.62255 -245.984291) (xy 334.638134 -246.030972)
			(xy 334.646029 -246.079549) (xy 334.646524 -246.104156) (xy 334.975212 -246.104156) (xy 334.979172 -246.055102)
			(xy 334.990949 -246.007318) (xy 335.01024 -245.962042) (xy 335.036543 -245.920446) (xy 335.069178 -245.883609)
			(xy 335.107299 -245.852484) (xy 335.14992 -245.827877) (xy 335.195936 -245.810425) (xy 335.244155 -245.800581)
			(xy 335.29333 -245.7986) (xy 335.342185 -245.804532) (xy 335.389456 -245.818224) (xy 335.433918 -245.839322)
			(xy 335.474421 -245.867278) (xy 335.509914 -245.90137) (xy 335.539479 -245.940714) (xy 335.56235 -245.984291)
			(xy 335.577934 -246.030972) (xy 335.585829 -246.079549) (xy 335.586324 -246.104156) (xy 335.915266 -246.104156)
			(xy 335.919226 -246.055102) (xy 335.931003 -246.007318) (xy 335.950294 -245.962042) (xy 335.976597 -245.920446)
			(xy 336.009232 -245.883609) (xy 336.047353 -245.852484) (xy 336.089974 -245.827877) (xy 336.13599 -245.810425)
			(xy 336.184209 -245.800581) (xy 336.233384 -245.7986) (xy 336.282239 -245.804532) (xy 336.32951 -245.818224)
			(xy 336.373972 -245.839322) (xy 336.414475 -245.867278) (xy 336.449968 -245.90137) (xy 336.479533 -245.940714)
			(xy 336.502404 -245.984291) (xy 336.517988 -246.030972) (xy 336.525883 -246.079549) (xy 336.526378 -246.104156)
			(xy 336.85532 -246.104156) (xy 336.85928 -246.055102) (xy 336.871057 -246.007318) (xy 336.890348 -245.962042)
			(xy 336.916651 -245.920446) (xy 336.949286 -245.883609) (xy 336.987407 -245.852484) (xy 337.030028 -245.827877)
			(xy 337.076044 -245.810425) (xy 337.124263 -245.800581) (xy 337.173438 -245.7986) (xy 337.222293 -245.804532)
			(xy 337.269564 -245.818224) (xy 337.314026 -245.839322) (xy 337.354529 -245.867278) (xy 337.390022 -245.90137)
			(xy 337.419587 -245.940714) (xy 337.442458 -245.984291) (xy 337.458042 -246.030972) (xy 337.465937 -246.079549)
			(xy 337.466432 -246.104156) (xy 337.795374 -246.104156) (xy 337.799334 -246.055102) (xy 337.811111 -246.007318)
			(xy 337.830402 -245.962042) (xy 337.856705 -245.920446) (xy 337.88934 -245.883609) (xy 337.927461 -245.852484)
			(xy 337.970082 -245.827877) (xy 338.016098 -245.810425) (xy 338.064317 -245.800581) (xy 338.113492 -245.7986)
			(xy 338.162347 -245.804532) (xy 338.209618 -245.818224) (xy 338.25408 -245.839322) (xy 338.294583 -245.867278)
			(xy 338.330076 -245.90137) (xy 338.359641 -245.940714) (xy 338.382512 -245.984291) (xy 338.398096 -246.030972)
			(xy 338.405991 -246.079549) (xy 338.406486 -246.104156) (xy 338.724743 -246.104156) (xy 338.728838 -246.053428)
			(xy 338.741017 -246.004014) (xy 338.760965 -245.957194) (xy 338.788166 -245.91418) (xy 338.821914 -245.876086)
			(xy 338.861336 -245.843899) (xy 338.90541 -245.818453) (xy 338.952996 -245.800406) (xy 339.00286 -245.790226)
			(xy 339.053712 -245.788177) (xy 339.104233 -245.794311) (xy 339.153117 -245.808471) (xy 339.199096 -245.830288)
			(xy 339.24098 -245.859198) (xy 339.277684 -245.894453) (xy 339.308257 -245.935139) (xy 339.331908 -245.980202)
			(xy 339.348024 -246.028476) (xy 339.356188 -246.07871) (xy 339.3567 -246.104156) (xy 339.664797 -246.104156)
			(xy 339.668892 -246.053428) (xy 339.681071 -246.004014) (xy 339.701019 -245.957194) (xy 339.72822 -245.91418)
			(xy 339.761968 -245.876086) (xy 339.80139 -245.843899) (xy 339.845464 -245.818453) (xy 339.89305 -245.800406)
			(xy 339.942914 -245.790226) (xy 339.993766 -245.788177) (xy 340.044287 -245.794311) (xy 340.093171 -245.808471)
			(xy 340.13915 -245.830288) (xy 340.181034 -245.859198) (xy 340.217738 -245.894453) (xy 340.248311 -245.935139)
			(xy 340.271962 -245.980202) (xy 340.288078 -246.028476) (xy 340.296242 -246.07871) (xy 340.296754 -246.104156)
			(xy 340.615282 -246.104156) (xy 340.619242 -246.055102) (xy 340.631019 -246.007318) (xy 340.65031 -245.962042)
			(xy 340.676613 -245.920446) (xy 340.709248 -245.883609) (xy 340.747369 -245.852484) (xy 340.78999 -245.827877)
			(xy 340.836006 -245.810425) (xy 340.884225 -245.800581) (xy 340.9334 -245.7986) (xy 340.982255 -245.804532)
			(xy 341.029526 -245.818224) (xy 341.073988 -245.839322) (xy 341.114491 -245.867278) (xy 341.149984 -245.90137)
			(xy 341.179549 -245.940714) (xy 341.20242 -245.984291) (xy 341.218004 -246.030972) (xy 341.225899 -246.079549)
			(xy 341.226394 -246.104156) (xy 341.544905 -246.104156) (xy 341.549 -246.053428) (xy 341.561179 -246.004014)
			(xy 341.581127 -245.957194) (xy 341.608328 -245.91418) (xy 341.642076 -245.876086) (xy 341.681498 -245.843899)
			(xy 341.725572 -245.818453) (xy 341.773158 -245.800406) (xy 341.823022 -245.790226) (xy 341.873874 -245.788177)
			(xy 341.924395 -245.794311) (xy 341.973279 -245.808471) (xy 342.019258 -245.830288) (xy 342.061142 -245.859198)
			(xy 342.097846 -245.894453) (xy 342.128419 -245.935139) (xy 342.15207 -245.980202) (xy 342.168186 -246.028476)
			(xy 342.17635 -246.07871) (xy 342.176862 -246.104156) (xy 342.49539 -246.104156) (xy 342.49935 -246.055102)
			(xy 342.511127 -246.007318) (xy 342.530418 -245.962042) (xy 342.556721 -245.920446) (xy 342.589356 -245.883609)
			(xy 342.627477 -245.852484) (xy 342.670098 -245.827877) (xy 342.716114 -245.810425) (xy 342.764333 -245.800581)
			(xy 342.813508 -245.7986) (xy 342.862363 -245.804532) (xy 342.909634 -245.818224) (xy 342.954096 -245.839322)
			(xy 342.994599 -245.867278) (xy 343.030092 -245.90137) (xy 343.059657 -245.940714) (xy 343.082528 -245.984291)
			(xy 343.098112 -246.030972) (xy 343.106007 -246.079549) (xy 343.106502 -246.104156) (xy 343.424759 -246.104156)
			(xy 343.428854 -246.053428) (xy 343.441033 -246.004014) (xy 343.460981 -245.957194) (xy 343.488182 -245.91418)
			(xy 343.52193 -245.876086) (xy 343.561352 -245.843899) (xy 343.605426 -245.818453) (xy 343.653012 -245.800406)
			(xy 343.702876 -245.790226) (xy 343.753728 -245.788177) (xy 343.804249 -245.794311) (xy 343.853133 -245.808471)
			(xy 343.899112 -245.830288) (xy 343.940996 -245.859198) (xy 343.9777 -245.894453) (xy 344.008273 -245.935139)
			(xy 344.031924 -245.980202) (xy 344.04804 -246.028476) (xy 344.056204 -246.07871) (xy 344.056716 -246.104156)
			(xy 344.056204 -246.129602) (xy 344.04804 -246.179836) (xy 344.031924 -246.22811) (xy 344.008273 -246.273173)
			(xy 343.9777 -246.313859) (xy 343.940996 -246.349114) (xy 343.899112 -246.378024) (xy 343.853133 -246.399841)
			(xy 343.804249 -246.414001) (xy 343.753728 -246.420135) (xy 343.702876 -246.418086) (xy 343.653012 -246.407906)
			(xy 343.605426 -246.389859) (xy 343.561352 -246.364413) (xy 343.52193 -246.332226) (xy 343.488182 -246.294132)
			(xy 343.460981 -246.251118) (xy 343.441033 -246.204298) (xy 343.428854 -246.154884) (xy 343.424759 -246.104156)
			(xy 343.106502 -246.104156) (xy 343.106007 -246.128763) (xy 343.098112 -246.17734) (xy 343.082528 -246.224021)
			(xy 343.059657 -246.267598) (xy 343.030092 -246.306942) (xy 342.994599 -246.341034) (xy 342.954096 -246.36899)
			(xy 342.909634 -246.390088) (xy 342.862363 -246.40378) (xy 342.813508 -246.409712) (xy 342.764333 -246.407731)
			(xy 342.716114 -246.397887) (xy 342.670098 -246.380435) (xy 342.627477 -246.355828) (xy 342.589356 -246.324703)
			(xy 342.556721 -246.287866) (xy 342.530418 -246.24627) (xy 342.511127 -246.200994) (xy 342.49935 -246.15321)
			(xy 342.49539 -246.104156) (xy 342.176862 -246.104156) (xy 342.17635 -246.129602) (xy 342.168186 -246.179836)
			(xy 342.15207 -246.22811) (xy 342.128419 -246.273173) (xy 342.097846 -246.313859) (xy 342.061142 -246.349114)
			(xy 342.019258 -246.378024) (xy 341.973279 -246.399841) (xy 341.924395 -246.414001) (xy 341.873874 -246.420135)
			(xy 341.823022 -246.418086) (xy 341.773158 -246.407906) (xy 341.725572 -246.389859) (xy 341.681498 -246.364413)
			(xy 341.642076 -246.332226) (xy 341.608328 -246.294132) (xy 341.581127 -246.251118) (xy 341.561179 -246.204298)
			(xy 341.549 -246.154884) (xy 341.544905 -246.104156) (xy 341.226394 -246.104156) (xy 341.225899 -246.128763)
			(xy 341.218004 -246.17734) (xy 341.20242 -246.224021) (xy 341.179549 -246.267598) (xy 341.149984 -246.306942)
			(xy 341.114491 -246.341034) (xy 341.073988 -246.36899) (xy 341.029526 -246.390088) (xy 340.982255 -246.40378)
			(xy 340.9334 -246.409712) (xy 340.884225 -246.407731) (xy 340.836006 -246.397887) (xy 340.78999 -246.380435)
			(xy 340.747369 -246.355828) (xy 340.709248 -246.324703) (xy 340.676613 -246.287866) (xy 340.65031 -246.24627)
			(xy 340.631019 -246.200994) (xy 340.619242 -246.15321) (xy 340.615282 -246.104156) (xy 340.296754 -246.104156)
			(xy 340.296242 -246.129602) (xy 340.288078 -246.179836) (xy 340.271962 -246.22811) (xy 340.248311 -246.273173)
			(xy 340.217738 -246.313859) (xy 340.181034 -246.349114) (xy 340.13915 -246.378024) (xy 340.093171 -246.399841)
			(xy 340.044287 -246.414001) (xy 339.993766 -246.420135) (xy 339.942914 -246.418086) (xy 339.89305 -246.407906)
			(xy 339.845464 -246.389859) (xy 339.80139 -246.364413) (xy 339.761968 -246.332226) (xy 339.72822 -246.294132)
			(xy 339.701019 -246.251118) (xy 339.681071 -246.204298) (xy 339.668892 -246.154884) (xy 339.664797 -246.104156)
			(xy 339.3567 -246.104156) (xy 339.356188 -246.129602) (xy 339.348024 -246.179836) (xy 339.331908 -246.22811)
			(xy 339.308257 -246.273173) (xy 339.277684 -246.313859) (xy 339.24098 -246.349114) (xy 339.199096 -246.378024)
			(xy 339.153117 -246.399841) (xy 339.104233 -246.414001) (xy 339.053712 -246.420135) (xy 339.00286 -246.418086)
			(xy 338.952996 -246.407906) (xy 338.90541 -246.389859) (xy 338.861336 -246.364413) (xy 338.821914 -246.332226)
			(xy 338.788166 -246.294132) (xy 338.760965 -246.251118) (xy 338.741017 -246.204298) (xy 338.728838 -246.154884)
			(xy 338.724743 -246.104156) (xy 338.406486 -246.104156) (xy 338.405991 -246.128763) (xy 338.398096 -246.17734)
			(xy 338.382512 -246.224021) (xy 338.359641 -246.267598) (xy 338.330076 -246.306942) (xy 338.294583 -246.341034)
			(xy 338.25408 -246.36899) (xy 338.209618 -246.390088) (xy 338.162347 -246.40378) (xy 338.113492 -246.409712)
			(xy 338.064317 -246.407731) (xy 338.016098 -246.397887) (xy 337.970082 -246.380435) (xy 337.927461 -246.355828)
			(xy 337.88934 -246.324703) (xy 337.856705 -246.287866) (xy 337.830402 -246.24627) (xy 337.811111 -246.200994)
			(xy 337.799334 -246.15321) (xy 337.795374 -246.104156) (xy 337.466432 -246.104156) (xy 337.465937 -246.128763)
			(xy 337.458042 -246.17734) (xy 337.442458 -246.224021) (xy 337.419587 -246.267598) (xy 337.390022 -246.306942)
			(xy 337.354529 -246.341034) (xy 337.314026 -246.36899) (xy 337.269564 -246.390088) (xy 337.222293 -246.40378)
			(xy 337.173438 -246.409712) (xy 337.124263 -246.407731) (xy 337.076044 -246.397887) (xy 337.030028 -246.380435)
			(xy 336.987407 -246.355828) (xy 336.949286 -246.324703) (xy 336.916651 -246.287866) (xy 336.890348 -246.24627)
			(xy 336.871057 -246.200994) (xy 336.85928 -246.15321) (xy 336.85532 -246.104156) (xy 336.526378 -246.104156)
			(xy 336.525883 -246.128763) (xy 336.517988 -246.17734) (xy 336.502404 -246.224021) (xy 336.479533 -246.267598)
			(xy 336.449968 -246.306942) (xy 336.414475 -246.341034) (xy 336.373972 -246.36899) (xy 336.32951 -246.390088)
			(xy 336.282239 -246.40378) (xy 336.233384 -246.409712) (xy 336.184209 -246.407731) (xy 336.13599 -246.397887)
			(xy 336.089974 -246.380435) (xy 336.047353 -246.355828) (xy 336.009232 -246.324703) (xy 335.976597 -246.287866)
			(xy 335.950294 -246.24627) (xy 335.931003 -246.200994) (xy 335.919226 -246.15321) (xy 335.915266 -246.104156)
			(xy 335.586324 -246.104156) (xy 335.585829 -246.128763) (xy 335.577934 -246.17734) (xy 335.56235 -246.224021)
			(xy 335.539479 -246.267598) (xy 335.509914 -246.306942) (xy 335.474421 -246.341034) (xy 335.433918 -246.36899)
			(xy 335.389456 -246.390088) (xy 335.342185 -246.40378) (xy 335.29333 -246.409712) (xy 335.244155 -246.407731)
			(xy 335.195936 -246.397887) (xy 335.14992 -246.380435) (xy 335.107299 -246.355828) (xy 335.069178 -246.324703)
			(xy 335.036543 -246.287866) (xy 335.01024 -246.24627) (xy 334.990949 -246.200994) (xy 334.979172 -246.15321)
			(xy 334.975212 -246.104156) (xy 334.646524 -246.104156) (xy 334.646029 -246.128763) (xy 334.638134 -246.17734)
			(xy 334.62255 -246.224021) (xy 334.599679 -246.267598) (xy 334.570114 -246.306942) (xy 334.534621 -246.341034)
			(xy 334.494118 -246.36899) (xy 334.449656 -246.390088) (xy 334.402385 -246.40378) (xy 334.35353 -246.409712)
			(xy 334.304355 -246.407731) (xy 334.256136 -246.397887) (xy 334.21012 -246.380435) (xy 334.167499 -246.355828)
			(xy 334.129378 -246.324703) (xy 334.096743 -246.287866) (xy 334.07044 -246.24627) (xy 334.051149 -246.200994)
			(xy 334.039372 -246.15321) (xy 334.035412 -246.104156) (xy 333.70647 -246.104156) (xy 333.705975 -246.128763)
			(xy 333.69808 -246.17734) (xy 333.682496 -246.224021) (xy 333.659625 -246.267598) (xy 333.63006 -246.306942)
			(xy 333.594567 -246.341034) (xy 333.554064 -246.36899) (xy 333.509602 -246.390088) (xy 333.462331 -246.40378)
			(xy 333.413476 -246.409712) (xy 333.364301 -246.407731) (xy 333.316082 -246.397887) (xy 333.270066 -246.380435)
			(xy 333.227445 -246.355828) (xy 333.189324 -246.324703) (xy 333.156689 -246.287866) (xy 333.130386 -246.24627)
			(xy 333.111095 -246.200994) (xy 333.099318 -246.15321) (xy 333.095358 -246.104156) (xy 332.766416 -246.104156)
			(xy 332.765921 -246.128763) (xy 332.758026 -246.17734) (xy 332.742442 -246.224021) (xy 332.719571 -246.267598)
			(xy 332.690006 -246.306942) (xy 332.654513 -246.341034) (xy 332.61401 -246.36899) (xy 332.569548 -246.390088)
			(xy 332.522277 -246.40378) (xy 332.473422 -246.409712) (xy 332.424247 -246.407731) (xy 332.376028 -246.397887)
			(xy 332.330012 -246.380435) (xy 332.287391 -246.355828) (xy 332.24927 -246.324703) (xy 332.216635 -246.287866)
			(xy 332.190332 -246.24627) (xy 332.171041 -246.200994) (xy 332.159264 -246.15321) (xy 332.155304 -246.104156)
			(xy 331.826099 -246.104156) (xy 331.8261 -246.129234) (xy 331.817934 -246.178639) (xy 331.80182 -246.226051)
			(xy 331.77819 -246.270201) (xy 331.747676 -246.309905) (xy 331.711095 -246.344102) (xy 331.669428 -246.371876)
			(xy 331.623788 -246.392482) (xy 331.575399 -246.405369) (xy 331.550518 -246.408194) (xy 331.550264 -246.408194)
			(xy 331.540612 -246.40921) (xy 331.532738 -246.41302) (xy 331.528476 -246.415222) (xy 331.5208 -246.420971)
			(xy 331.517498 -246.42445) (xy 331.47254 -246.47398) (xy 331.466492 -246.481154) (xy 331.459721 -246.49864)
			(xy 331.459332 -246.508016) (xy 331.459332 -246.914162) (xy 331.685404 -246.914162) (xy 331.689364 -246.865108)
			(xy 331.701141 -246.817324) (xy 331.720432 -246.772048) (xy 331.746735 -246.730452) (xy 331.77937 -246.693615)
			(xy 331.817491 -246.66249) (xy 331.860112 -246.637883) (xy 331.906128 -246.620431) (xy 331.954347 -246.610587)
			(xy 332.003522 -246.608606) (xy 332.052377 -246.614538) (xy 332.099648 -246.62823) (xy 332.14411 -246.649328)
			(xy 332.184613 -246.677284) (xy 332.220106 -246.711376) (xy 332.249671 -246.75072) (xy 332.272542 -246.794297)
			(xy 332.288126 -246.840978) (xy 332.296021 -246.889555) (xy 332.296516 -246.914162) (xy 332.625204 -246.914162)
			(xy 332.629164 -246.865108) (xy 332.640941 -246.817324) (xy 332.660232 -246.772048) (xy 332.686535 -246.730452)
			(xy 332.71917 -246.693615) (xy 332.757291 -246.66249) (xy 332.799912 -246.637883) (xy 332.845928 -246.620431)
			(xy 332.894147 -246.610587) (xy 332.943322 -246.608606) (xy 332.992177 -246.614538) (xy 333.039448 -246.62823)
			(xy 333.08391 -246.649328) (xy 333.124413 -246.677284) (xy 333.159906 -246.711376) (xy 333.189471 -246.75072)
			(xy 333.212342 -246.794297) (xy 333.227926 -246.840978) (xy 333.235821 -246.889555) (xy 333.236316 -246.914162)
			(xy 333.565258 -246.914162) (xy 333.569218 -246.865108) (xy 333.580995 -246.817324) (xy 333.600286 -246.772048)
			(xy 333.626589 -246.730452) (xy 333.659224 -246.693615) (xy 333.697345 -246.66249) (xy 333.739966 -246.637883)
			(xy 333.785982 -246.620431) (xy 333.834201 -246.610587) (xy 333.883376 -246.608606) (xy 333.932231 -246.614538)
			(xy 333.979502 -246.62823) (xy 334.023964 -246.649328) (xy 334.064467 -246.677284) (xy 334.09996 -246.711376)
			(xy 334.129525 -246.75072) (xy 334.152396 -246.794297) (xy 334.16798 -246.840978) (xy 334.175875 -246.889555)
			(xy 334.17637 -246.914162) (xy 335.445366 -246.914162) (xy 335.449326 -246.865108) (xy 335.461103 -246.817324)
			(xy 335.480394 -246.772048) (xy 335.506697 -246.730452) (xy 335.539332 -246.693615) (xy 335.577453 -246.66249)
			(xy 335.620074 -246.637883) (xy 335.66609 -246.620431) (xy 335.714309 -246.610587) (xy 335.763484 -246.608606)
			(xy 335.812339 -246.614538) (xy 335.85961 -246.62823) (xy 335.904072 -246.649328) (xy 335.944575 -246.677284)
			(xy 335.980068 -246.711376) (xy 336.009633 -246.75072) (xy 336.032504 -246.794297) (xy 336.048088 -246.840978)
			(xy 336.055983 -246.889555) (xy 336.056478 -246.914162) (xy 336.38542 -246.914162) (xy 336.38938 -246.865108)
			(xy 336.401157 -246.817324) (xy 336.420448 -246.772048) (xy 336.446751 -246.730452) (xy 336.479386 -246.693615)
			(xy 336.517507 -246.66249) (xy 336.560128 -246.637883) (xy 336.606144 -246.620431) (xy 336.654363 -246.610587)
			(xy 336.703538 -246.608606) (xy 336.752393 -246.614538) (xy 336.799664 -246.62823) (xy 336.844126 -246.649328)
			(xy 336.884629 -246.677284) (xy 336.920122 -246.711376) (xy 336.949687 -246.75072) (xy 336.972558 -246.794297)
			(xy 336.988142 -246.840978) (xy 336.996037 -246.889555) (xy 336.996532 -246.914162) (xy 337.32522 -246.914162)
			(xy 337.32918 -246.865108) (xy 337.340957 -246.817324) (xy 337.360248 -246.772048) (xy 337.386551 -246.730452)
			(xy 337.419186 -246.693615) (xy 337.457307 -246.66249) (xy 337.499928 -246.637883) (xy 337.545944 -246.620431)
			(xy 337.594163 -246.610587) (xy 337.643338 -246.608606) (xy 337.692193 -246.614538) (xy 337.739464 -246.62823)
			(xy 337.783926 -246.649328) (xy 337.824429 -246.677284) (xy 337.859922 -246.711376) (xy 337.889487 -246.75072)
			(xy 337.912358 -246.794297) (xy 337.927942 -246.840978) (xy 337.935837 -246.889555) (xy 337.936332 -246.914162)
			(xy 338.254843 -246.914162) (xy 338.258938 -246.863434) (xy 338.271117 -246.81402) (xy 338.291065 -246.7672)
			(xy 338.318266 -246.724186) (xy 338.352014 -246.686092) (xy 338.391436 -246.653905) (xy 338.43551 -246.628459)
			(xy 338.483096 -246.610412) (xy 338.53296 -246.600232) (xy 338.583812 -246.598183) (xy 338.634333 -246.604317)
			(xy 338.683217 -246.618477) (xy 338.729196 -246.640294) (xy 338.77108 -246.669204) (xy 338.807784 -246.704459)
			(xy 338.838357 -246.745145) (xy 338.862008 -246.790208) (xy 338.878124 -246.838482) (xy 338.886288 -246.888716)
			(xy 338.8868 -246.914162) (xy 339.205328 -246.914162) (xy 339.209288 -246.865108) (xy 339.221065 -246.817324)
			(xy 339.240356 -246.772048) (xy 339.266659 -246.730452) (xy 339.299294 -246.693615) (xy 339.337415 -246.66249)
			(xy 339.380036 -246.637883) (xy 339.426052 -246.620431) (xy 339.474271 -246.610587) (xy 339.523446 -246.608606)
			(xy 339.572301 -246.614538) (xy 339.619572 -246.62823) (xy 339.664034 -246.649328) (xy 339.704537 -246.677284)
			(xy 339.74003 -246.711376) (xy 339.769595 -246.75072) (xy 339.792466 -246.794297) (xy 339.80805 -246.840978)
			(xy 339.815945 -246.889555) (xy 339.81644 -246.914162) (xy 340.134951 -246.914162) (xy 340.139046 -246.863434)
			(xy 340.151225 -246.81402) (xy 340.171173 -246.7672) (xy 340.198374 -246.724186) (xy 340.232122 -246.686092)
			(xy 340.271544 -246.653905) (xy 340.315618 -246.628459) (xy 340.363204 -246.610412) (xy 340.413068 -246.600232)
			(xy 340.46392 -246.598183) (xy 340.514441 -246.604317) (xy 340.563325 -246.618477) (xy 340.609304 -246.640294)
			(xy 340.651188 -246.669204) (xy 340.687892 -246.704459) (xy 340.718465 -246.745145) (xy 340.742116 -246.790208)
			(xy 340.758232 -246.838482) (xy 340.766396 -246.888716) (xy 340.766908 -246.914162) (xy 342.014805 -246.914162)
			(xy 342.0189 -246.863434) (xy 342.031079 -246.81402) (xy 342.051027 -246.7672) (xy 342.078228 -246.724186)
			(xy 342.111976 -246.686092) (xy 342.151398 -246.653905) (xy 342.195472 -246.628459) (xy 342.243058 -246.610412)
			(xy 342.292922 -246.600232) (xy 342.343774 -246.598183) (xy 342.394295 -246.604317) (xy 342.443179 -246.618477)
			(xy 342.489158 -246.640294) (xy 342.531042 -246.669204) (xy 342.567746 -246.704459) (xy 342.598319 -246.745145)
			(xy 342.62197 -246.790208) (xy 342.638086 -246.838482) (xy 342.64625 -246.888716) (xy 342.646762 -246.914162)
			(xy 342.954859 -246.914162) (xy 342.958954 -246.863434) (xy 342.971133 -246.81402) (xy 342.991081 -246.7672)
			(xy 343.018282 -246.724186) (xy 343.05203 -246.686092) (xy 343.091452 -246.653905) (xy 343.135526 -246.628459)
			(xy 343.183112 -246.610412) (xy 343.232976 -246.600232) (xy 343.283828 -246.598183) (xy 343.334349 -246.604317)
			(xy 343.383233 -246.618477) (xy 343.429212 -246.640294) (xy 343.471096 -246.669204) (xy 343.5078 -246.704459)
			(xy 343.538373 -246.745145) (xy 343.562024 -246.790208) (xy 343.57814 -246.838482) (xy 343.586304 -246.888716)
			(xy 343.586816 -246.914162) (xy 343.586304 -246.939608) (xy 343.57814 -246.989842) (xy 343.562024 -247.038116)
			(xy 343.538373 -247.083179) (xy 343.5078 -247.123865) (xy 343.471096 -247.15912) (xy 343.429212 -247.18803)
			(xy 343.383233 -247.209847) (xy 343.334349 -247.224007) (xy 343.283828 -247.230141) (xy 343.232976 -247.228092)
			(xy 343.183112 -247.217912) (xy 343.135526 -247.199865) (xy 343.091452 -247.174419) (xy 343.05203 -247.142232)
			(xy 343.018282 -247.104138) (xy 342.991081 -247.061124) (xy 342.971133 -247.014304) (xy 342.958954 -246.96489)
			(xy 342.954859 -246.914162) (xy 342.646762 -246.914162) (xy 342.64625 -246.939608) (xy 342.638086 -246.989842)
			(xy 342.62197 -247.038116) (xy 342.598319 -247.083179) (xy 342.567746 -247.123865) (xy 342.531042 -247.15912)
			(xy 342.489158 -247.18803) (xy 342.443179 -247.209847) (xy 342.394295 -247.224007) (xy 342.343774 -247.230141)
			(xy 342.292922 -247.228092) (xy 342.243058 -247.217912) (xy 342.195472 -247.199865) (xy 342.151398 -247.174419)
			(xy 342.111976 -247.142232) (xy 342.078228 -247.104138) (xy 342.051027 -247.061124) (xy 342.031079 -247.014304)
			(xy 342.0189 -246.96489) (xy 342.014805 -246.914162) (xy 340.766908 -246.914162) (xy 340.766396 -246.939608)
			(xy 340.758232 -246.989842) (xy 340.742116 -247.038116) (xy 340.718465 -247.083179) (xy 340.687892 -247.123865)
			(xy 340.651188 -247.15912) (xy 340.609304 -247.18803) (xy 340.563325 -247.209847) (xy 340.514441 -247.224007)
			(xy 340.46392 -247.230141) (xy 340.413068 -247.228092) (xy 340.363204 -247.217912) (xy 340.315618 -247.199865)
			(xy 340.271544 -247.174419) (xy 340.232122 -247.142232) (xy 340.198374 -247.104138) (xy 340.171173 -247.061124)
			(xy 340.151225 -247.014304) (xy 340.139046 -246.96489) (xy 340.134951 -246.914162) (xy 339.81644 -246.914162)
			(xy 339.815945 -246.938769) (xy 339.80805 -246.987346) (xy 339.792466 -247.034027) (xy 339.769595 -247.077604)
			(xy 339.74003 -247.116948) (xy 339.704537 -247.15104) (xy 339.664034 -247.178996) (xy 339.619572 -247.200094)
			(xy 339.572301 -247.213786) (xy 339.523446 -247.219718) (xy 339.474271 -247.217737) (xy 339.426052 -247.207893)
			(xy 339.380036 -247.190441) (xy 339.337415 -247.165834) (xy 339.299294 -247.134709) (xy 339.266659 -247.097872)
			(xy 339.240356 -247.056276) (xy 339.221065 -247.011) (xy 339.209288 -246.963216) (xy 339.205328 -246.914162)
			(xy 338.8868 -246.914162) (xy 338.886288 -246.939608) (xy 338.878124 -246.989842) (xy 338.862008 -247.038116)
			(xy 338.838357 -247.083179) (xy 338.807784 -247.123865) (xy 338.77108 -247.15912) (xy 338.729196 -247.18803)
			(xy 338.683217 -247.209847) (xy 338.634333 -247.224007) (xy 338.583812 -247.230141) (xy 338.53296 -247.228092)
			(xy 338.483096 -247.217912) (xy 338.43551 -247.199865) (xy 338.391436 -247.174419) (xy 338.352014 -247.142232)
			(xy 338.318266 -247.104138) (xy 338.291065 -247.061124) (xy 338.271117 -247.014304) (xy 338.258938 -246.96489)
			(xy 338.254843 -246.914162) (xy 337.936332 -246.914162) (xy 337.935837 -246.938769) (xy 337.927942 -246.987346)
			(xy 337.912358 -247.034027) (xy 337.889487 -247.077604) (xy 337.859922 -247.116948) (xy 337.824429 -247.15104)
			(xy 337.783926 -247.178996) (xy 337.739464 -247.200094) (xy 337.692193 -247.213786) (xy 337.643338 -247.219718)
			(xy 337.594163 -247.217737) (xy 337.545944 -247.207893) (xy 337.499928 -247.190441) (xy 337.457307 -247.165834)
			(xy 337.419186 -247.134709) (xy 337.386551 -247.097872) (xy 337.360248 -247.056276) (xy 337.340957 -247.011)
			(xy 337.32918 -246.963216) (xy 337.32522 -246.914162) (xy 336.996532 -246.914162) (xy 336.996037 -246.938769)
			(xy 336.988142 -246.987346) (xy 336.972558 -247.034027) (xy 336.949687 -247.077604) (xy 336.920122 -247.116948)
			(xy 336.884629 -247.15104) (xy 336.844126 -247.178996) (xy 336.799664 -247.200094) (xy 336.752393 -247.213786)
			(xy 336.703538 -247.219718) (xy 336.654363 -247.217737) (xy 336.606144 -247.207893) (xy 336.560128 -247.190441)
			(xy 336.517507 -247.165834) (xy 336.479386 -247.134709) (xy 336.446751 -247.097872) (xy 336.420448 -247.056276)
			(xy 336.401157 -247.011) (xy 336.38938 -246.963216) (xy 336.38542 -246.914162) (xy 336.056478 -246.914162)
			(xy 336.055983 -246.938769) (xy 336.048088 -246.987346) (xy 336.032504 -247.034027) (xy 336.009633 -247.077604)
			(xy 335.980068 -247.116948) (xy 335.944575 -247.15104) (xy 335.904072 -247.178996) (xy 335.85961 -247.200094)
			(xy 335.812339 -247.213786) (xy 335.763484 -247.219718) (xy 335.714309 -247.217737) (xy 335.66609 -247.207893)
			(xy 335.620074 -247.190441) (xy 335.577453 -247.165834) (xy 335.539332 -247.134709) (xy 335.506697 -247.097872)
			(xy 335.480394 -247.056276) (xy 335.461103 -247.011) (xy 335.449326 -246.963216) (xy 335.445366 -246.914162)
			(xy 334.17637 -246.914162) (xy 334.175875 -246.938769) (xy 334.16798 -246.987346) (xy 334.152396 -247.034027)
			(xy 334.129525 -247.077604) (xy 334.09996 -247.116948) (xy 334.064467 -247.15104) (xy 334.023964 -247.178996)
			(xy 333.979502 -247.200094) (xy 333.932231 -247.213786) (xy 333.883376 -247.219718) (xy 333.834201 -247.217737)
			(xy 333.785982 -247.207893) (xy 333.739966 -247.190441) (xy 333.697345 -247.165834) (xy 333.659224 -247.134709)
			(xy 333.626589 -247.097872) (xy 333.600286 -247.056276) (xy 333.580995 -247.011) (xy 333.569218 -246.963216)
			(xy 333.565258 -246.914162) (xy 333.236316 -246.914162) (xy 333.235821 -246.938769) (xy 333.227926 -246.987346)
			(xy 333.212342 -247.034027) (xy 333.189471 -247.077604) (xy 333.159906 -247.116948) (xy 333.124413 -247.15104)
			(xy 333.08391 -247.178996) (xy 333.039448 -247.200094) (xy 332.992177 -247.213786) (xy 332.943322 -247.219718)
			(xy 332.894147 -247.217737) (xy 332.845928 -247.207893) (xy 332.799912 -247.190441) (xy 332.757291 -247.165834)
			(xy 332.71917 -247.134709) (xy 332.686535 -247.097872) (xy 332.660232 -247.056276) (xy 332.640941 -247.011)
			(xy 332.629164 -246.963216) (xy 332.625204 -246.914162) (xy 332.296516 -246.914162) (xy 332.296021 -246.938769)
			(xy 332.288126 -246.987346) (xy 332.272542 -247.034027) (xy 332.249671 -247.077604) (xy 332.220106 -247.116948)
			(xy 332.184613 -247.15104) (xy 332.14411 -247.178996) (xy 332.099648 -247.200094) (xy 332.052377 -247.213786)
			(xy 332.003522 -247.219718) (xy 331.954347 -247.217737) (xy 331.906128 -247.207893) (xy 331.860112 -247.190441)
			(xy 331.817491 -247.165834) (xy 331.77937 -247.134709) (xy 331.746735 -247.097872) (xy 331.720432 -247.056276)
			(xy 331.701141 -247.011) (xy 331.689364 -246.963216) (xy 331.685404 -246.914162) (xy 331.459332 -246.914162)
			(xy 331.459332 -247.320308) (xy 331.459811 -247.329663) (xy 331.466587 -247.347111) (xy 331.47254 -247.354344)
			(xy 331.517498 -247.403874) (xy 331.520809 -247.407344) (xy 331.528477 -247.413103) (xy 331.532738 -247.415304)
			(xy 331.540612 -247.419114) (xy 331.550264 -247.42013) (xy 331.550518 -247.42013) (xy 331.57539 -247.423041)
			(xy 331.623777 -247.435927) (xy 331.669415 -247.456531) (xy 331.711082 -247.484302) (xy 331.747662 -247.518497)
			(xy 331.778176 -247.5582) (xy 331.801806 -247.602347) (xy 331.81792 -247.649757) (xy 331.826087 -247.69916)
			(xy 331.826087 -247.724168) (xy 332.155304 -247.724168) (xy 332.159264 -247.675114) (xy 332.171041 -247.62733)
			(xy 332.190332 -247.582054) (xy 332.216635 -247.540458) (xy 332.24927 -247.503621) (xy 332.287391 -247.472496)
			(xy 332.330012 -247.447889) (xy 332.376028 -247.430437) (xy 332.424247 -247.420593) (xy 332.473422 -247.418612)
			(xy 332.522277 -247.424544) (xy 332.569548 -247.438236) (xy 332.61401 -247.459334) (xy 332.654513 -247.48729)
			(xy 332.690006 -247.521382) (xy 332.719571 -247.560726) (xy 332.742442 -247.604303) (xy 332.758026 -247.650984)
			(xy 332.765921 -247.699561) (xy 332.766416 -247.724168) (xy 333.095358 -247.724168) (xy 333.099318 -247.675114)
			(xy 333.111095 -247.62733) (xy 333.130386 -247.582054) (xy 333.156689 -247.540458) (xy 333.189324 -247.503621)
			(xy 333.227445 -247.472496) (xy 333.270066 -247.447889) (xy 333.316082 -247.430437) (xy 333.364301 -247.420593)
			(xy 333.413476 -247.418612) (xy 333.462331 -247.424544) (xy 333.509602 -247.438236) (xy 333.554064 -247.459334)
			(xy 333.594567 -247.48729) (xy 333.63006 -247.521382) (xy 333.659625 -247.560726) (xy 333.682496 -247.604303)
			(xy 333.69808 -247.650984) (xy 333.705975 -247.699561) (xy 333.70647 -247.724168) (xy 334.035412 -247.724168)
			(xy 334.039372 -247.675114) (xy 334.051149 -247.62733) (xy 334.07044 -247.582054) (xy 334.096743 -247.540458)
			(xy 334.129378 -247.503621) (xy 334.167499 -247.472496) (xy 334.21012 -247.447889) (xy 334.256136 -247.430437)
			(xy 334.304355 -247.420593) (xy 334.35353 -247.418612) (xy 334.402385 -247.424544) (xy 334.449656 -247.438236)
			(xy 334.494118 -247.459334) (xy 334.534621 -247.48729) (xy 334.570114 -247.521382) (xy 334.599679 -247.560726)
			(xy 334.62255 -247.604303) (xy 334.638134 -247.650984) (xy 334.646029 -247.699561) (xy 334.646524 -247.724168)
			(xy 334.975212 -247.724168) (xy 334.979172 -247.675114) (xy 334.990949 -247.62733) (xy 335.01024 -247.582054)
			(xy 335.036543 -247.540458) (xy 335.069178 -247.503621) (xy 335.107299 -247.472496) (xy 335.14992 -247.447889)
			(xy 335.195936 -247.430437) (xy 335.244155 -247.420593) (xy 335.29333 -247.418612) (xy 335.342185 -247.424544)
			(xy 335.389456 -247.438236) (xy 335.433918 -247.459334) (xy 335.474421 -247.48729) (xy 335.509914 -247.521382)
			(xy 335.539479 -247.560726) (xy 335.56235 -247.604303) (xy 335.577934 -247.650984) (xy 335.585829 -247.699561)
			(xy 335.586324 -247.724168) (xy 335.915266 -247.724168) (xy 335.919226 -247.675114) (xy 335.931003 -247.62733)
			(xy 335.950294 -247.582054) (xy 335.976597 -247.540458) (xy 336.009232 -247.503621) (xy 336.047353 -247.472496)
			(xy 336.089974 -247.447889) (xy 336.13599 -247.430437) (xy 336.184209 -247.420593) (xy 336.233384 -247.418612)
			(xy 336.282239 -247.424544) (xy 336.32951 -247.438236) (xy 336.373972 -247.459334) (xy 336.414475 -247.48729)
			(xy 336.449968 -247.521382) (xy 336.479533 -247.560726) (xy 336.502404 -247.604303) (xy 336.517988 -247.650984)
			(xy 336.525883 -247.699561) (xy 336.526378 -247.724168) (xy 336.85532 -247.724168) (xy 336.85928 -247.675114)
			(xy 336.871057 -247.62733) (xy 336.890348 -247.582054) (xy 336.916651 -247.540458) (xy 336.949286 -247.503621)
			(xy 336.987407 -247.472496) (xy 337.030028 -247.447889) (xy 337.076044 -247.430437) (xy 337.124263 -247.420593)
			(xy 337.173438 -247.418612) (xy 337.222293 -247.424544) (xy 337.269564 -247.438236) (xy 337.314026 -247.459334)
			(xy 337.354529 -247.48729) (xy 337.390022 -247.521382) (xy 337.419587 -247.560726) (xy 337.442458 -247.604303)
			(xy 337.458042 -247.650984) (xy 337.465937 -247.699561) (xy 337.466432 -247.724168) (xy 337.795374 -247.724168)
			(xy 337.799334 -247.675114) (xy 337.811111 -247.62733) (xy 337.830402 -247.582054) (xy 337.856705 -247.540458)
			(xy 337.88934 -247.503621) (xy 337.927461 -247.472496) (xy 337.970082 -247.447889) (xy 338.016098 -247.430437)
			(xy 338.064317 -247.420593) (xy 338.113492 -247.418612) (xy 338.162347 -247.424544) (xy 338.209618 -247.438236)
			(xy 338.25408 -247.459334) (xy 338.294583 -247.48729) (xy 338.330076 -247.521382) (xy 338.359641 -247.560726)
			(xy 338.382512 -247.604303) (xy 338.398096 -247.650984) (xy 338.405991 -247.699561) (xy 338.406486 -247.724168)
			(xy 338.724743 -247.724168) (xy 338.728838 -247.67344) (xy 338.741017 -247.624026) (xy 338.760965 -247.577206)
			(xy 338.788166 -247.534192) (xy 338.821914 -247.496098) (xy 338.861336 -247.463911) (xy 338.90541 -247.438465)
			(xy 338.952996 -247.420418) (xy 339.00286 -247.410238) (xy 339.053712 -247.408189) (xy 339.104233 -247.414323)
			(xy 339.153117 -247.428483) (xy 339.199096 -247.4503) (xy 339.24098 -247.47921) (xy 339.277684 -247.514465)
			(xy 339.308257 -247.555151) (xy 339.331908 -247.600214) (xy 339.348024 -247.648488) (xy 339.356188 -247.698722)
			(xy 339.3567 -247.724168) (xy 339.664797 -247.724168) (xy 339.668892 -247.67344) (xy 339.681071 -247.624026)
			(xy 339.701019 -247.577206) (xy 339.72822 -247.534192) (xy 339.761968 -247.496098) (xy 339.80139 -247.463911)
			(xy 339.845464 -247.438465) (xy 339.89305 -247.420418) (xy 339.942914 -247.410238) (xy 339.993766 -247.408189)
			(xy 340.044287 -247.414323) (xy 340.093171 -247.428483) (xy 340.13915 -247.4503) (xy 340.181034 -247.47921)
			(xy 340.217738 -247.514465) (xy 340.248311 -247.555151) (xy 340.271962 -247.600214) (xy 340.288078 -247.648488)
			(xy 340.296242 -247.698722) (xy 340.296754 -247.724168) (xy 340.615282 -247.724168) (xy 340.619242 -247.675114)
			(xy 340.631019 -247.62733) (xy 340.65031 -247.582054) (xy 340.676613 -247.540458) (xy 340.709248 -247.503621)
			(xy 340.747369 -247.472496) (xy 340.78999 -247.447889) (xy 340.836006 -247.430437) (xy 340.884225 -247.420593)
			(xy 340.9334 -247.418612) (xy 340.982255 -247.424544) (xy 341.029526 -247.438236) (xy 341.073988 -247.459334)
			(xy 341.114491 -247.48729) (xy 341.149984 -247.521382) (xy 341.179549 -247.560726) (xy 341.20242 -247.604303)
			(xy 341.218004 -247.650984) (xy 341.225899 -247.699561) (xy 341.226394 -247.724168) (xy 341.544905 -247.724168)
			(xy 341.549 -247.67344) (xy 341.561179 -247.624026) (xy 341.581127 -247.577206) (xy 341.608328 -247.534192)
			(xy 341.642076 -247.496098) (xy 341.681498 -247.463911) (xy 341.725572 -247.438465) (xy 341.773158 -247.420418)
			(xy 341.823022 -247.410238) (xy 341.873874 -247.408189) (xy 341.924395 -247.414323) (xy 341.973279 -247.428483)
			(xy 342.019258 -247.4503) (xy 342.061142 -247.47921) (xy 342.097846 -247.514465) (xy 342.128419 -247.555151)
			(xy 342.15207 -247.600214) (xy 342.168186 -247.648488) (xy 342.17635 -247.698722) (xy 342.176862 -247.724168)
			(xy 342.49539 -247.724168) (xy 342.49935 -247.675114) (xy 342.511127 -247.62733) (xy 342.530418 -247.582054)
			(xy 342.556721 -247.540458) (xy 342.589356 -247.503621) (xy 342.627477 -247.472496) (xy 342.670098 -247.447889)
			(xy 342.716114 -247.430437) (xy 342.764333 -247.420593) (xy 342.813508 -247.418612) (xy 342.862363 -247.424544)
			(xy 342.909634 -247.438236) (xy 342.954096 -247.459334) (xy 342.994599 -247.48729) (xy 343.030092 -247.521382)
			(xy 343.059657 -247.560726) (xy 343.082528 -247.604303) (xy 343.098112 -247.650984) (xy 343.106007 -247.699561)
			(xy 343.106502 -247.724168) (xy 343.424759 -247.724168) (xy 343.428854 -247.67344) (xy 343.441033 -247.624026)
			(xy 343.460981 -247.577206) (xy 343.488182 -247.534192) (xy 343.52193 -247.496098) (xy 343.561352 -247.463911)
			(xy 343.605426 -247.438465) (xy 343.653012 -247.420418) (xy 343.702876 -247.410238) (xy 343.753728 -247.408189)
			(xy 343.804249 -247.414323) (xy 343.853133 -247.428483) (xy 343.899112 -247.4503) (xy 343.940996 -247.47921)
			(xy 343.9777 -247.514465) (xy 344.008273 -247.555151) (xy 344.031924 -247.600214) (xy 344.04804 -247.648488)
			(xy 344.056204 -247.698722) (xy 344.056716 -247.724168) (xy 344.056204 -247.749614) (xy 344.04804 -247.799848)
			(xy 344.031924 -247.848122) (xy 344.008273 -247.893185) (xy 343.9777 -247.933871) (xy 343.940996 -247.969126)
			(xy 343.899112 -247.998036) (xy 343.853133 -248.019853) (xy 343.804249 -248.034013) (xy 343.753728 -248.040147)
			(xy 343.702876 -248.038098) (xy 343.653012 -248.027918) (xy 343.605426 -248.009871) (xy 343.561352 -247.984425)
			(xy 343.52193 -247.952238) (xy 343.488182 -247.914144) (xy 343.460981 -247.87113) (xy 343.441033 -247.82431)
			(xy 343.428854 -247.774896) (xy 343.424759 -247.724168) (xy 343.106502 -247.724168) (xy 343.106007 -247.748775)
			(xy 343.098112 -247.797352) (xy 343.082528 -247.844033) (xy 343.059657 -247.88761) (xy 343.030092 -247.926954)
			(xy 342.994599 -247.961046) (xy 342.954096 -247.989002) (xy 342.909634 -248.0101) (xy 342.862363 -248.023792)
			(xy 342.813508 -248.029724) (xy 342.764333 -248.027743) (xy 342.716114 -248.017899) (xy 342.670098 -248.000447)
			(xy 342.627477 -247.97584) (xy 342.589356 -247.944715) (xy 342.556721 -247.907878) (xy 342.530418 -247.866282)
			(xy 342.511127 -247.821006) (xy 342.49935 -247.773222) (xy 342.49539 -247.724168) (xy 342.176862 -247.724168)
			(xy 342.17635 -247.749614) (xy 342.168186 -247.799848) (xy 342.15207 -247.848122) (xy 342.128419 -247.893185)
			(xy 342.097846 -247.933871) (xy 342.061142 -247.969126) (xy 342.019258 -247.998036) (xy 341.973279 -248.019853)
			(xy 341.924395 -248.034013) (xy 341.873874 -248.040147) (xy 341.823022 -248.038098) (xy 341.773158 -248.027918)
			(xy 341.725572 -248.009871) (xy 341.681498 -247.984425) (xy 341.642076 -247.952238) (xy 341.608328 -247.914144)
			(xy 341.581127 -247.87113) (xy 341.561179 -247.82431) (xy 341.549 -247.774896) (xy 341.544905 -247.724168)
			(xy 341.226394 -247.724168) (xy 341.225899 -247.748775) (xy 341.218004 -247.797352) (xy 341.20242 -247.844033)
			(xy 341.179549 -247.88761) (xy 341.149984 -247.926954) (xy 341.114491 -247.961046) (xy 341.073988 -247.989002)
			(xy 341.029526 -248.0101) (xy 340.982255 -248.023792) (xy 340.9334 -248.029724) (xy 340.884225 -248.027743)
			(xy 340.836006 -248.017899) (xy 340.78999 -248.000447) (xy 340.747369 -247.97584) (xy 340.709248 -247.944715)
			(xy 340.676613 -247.907878) (xy 340.65031 -247.866282) (xy 340.631019 -247.821006) (xy 340.619242 -247.773222)
			(xy 340.615282 -247.724168) (xy 340.296754 -247.724168) (xy 340.296242 -247.749614) (xy 340.288078 -247.799848)
			(xy 340.271962 -247.848122) (xy 340.248311 -247.893185) (xy 340.217738 -247.933871) (xy 340.181034 -247.969126)
			(xy 340.13915 -247.998036) (xy 340.093171 -248.019853) (xy 340.044287 -248.034013) (xy 339.993766 -248.040147)
			(xy 339.942914 -248.038098) (xy 339.89305 -248.027918) (xy 339.845464 -248.009871) (xy 339.80139 -247.984425)
			(xy 339.761968 -247.952238) (xy 339.72822 -247.914144) (xy 339.701019 -247.87113) (xy 339.681071 -247.82431)
			(xy 339.668892 -247.774896) (xy 339.664797 -247.724168) (xy 339.3567 -247.724168) (xy 339.356188 -247.749614)
			(xy 339.348024 -247.799848) (xy 339.331908 -247.848122) (xy 339.308257 -247.893185) (xy 339.277684 -247.933871)
			(xy 339.24098 -247.969126) (xy 339.199096 -247.998036) (xy 339.153117 -248.019853) (xy 339.104233 -248.034013)
			(xy 339.053712 -248.040147) (xy 339.00286 -248.038098) (xy 338.952996 -248.027918) (xy 338.90541 -248.009871)
			(xy 338.861336 -247.984425) (xy 338.821914 -247.952238) (xy 338.788166 -247.914144) (xy 338.760965 -247.87113)
			(xy 338.741017 -247.82431) (xy 338.728838 -247.774896) (xy 338.724743 -247.724168) (xy 338.406486 -247.724168)
			(xy 338.405991 -247.748775) (xy 338.398096 -247.797352) (xy 338.382512 -247.844033) (xy 338.359641 -247.88761)
			(xy 338.330076 -247.926954) (xy 338.294583 -247.961046) (xy 338.25408 -247.989002) (xy 338.209618 -248.0101)
			(xy 338.162347 -248.023792) (xy 338.113492 -248.029724) (xy 338.064317 -248.027743) (xy 338.016098 -248.017899)
			(xy 337.970082 -248.000447) (xy 337.927461 -247.97584) (xy 337.88934 -247.944715) (xy 337.856705 -247.907878)
			(xy 337.830402 -247.866282) (xy 337.811111 -247.821006) (xy 337.799334 -247.773222) (xy 337.795374 -247.724168)
			(xy 337.466432 -247.724168) (xy 337.465937 -247.748775) (xy 337.458042 -247.797352) (xy 337.442458 -247.844033)
			(xy 337.419587 -247.88761) (xy 337.390022 -247.926954) (xy 337.354529 -247.961046) (xy 337.314026 -247.989002)
			(xy 337.269564 -248.0101) (xy 337.222293 -248.023792) (xy 337.173438 -248.029724) (xy 337.124263 -248.027743)
			(xy 337.076044 -248.017899) (xy 337.030028 -248.000447) (xy 336.987407 -247.97584) (xy 336.949286 -247.944715)
			(xy 336.916651 -247.907878) (xy 336.890348 -247.866282) (xy 336.871057 -247.821006) (xy 336.85928 -247.773222)
			(xy 336.85532 -247.724168) (xy 336.526378 -247.724168) (xy 336.525883 -247.748775) (xy 336.517988 -247.797352)
			(xy 336.502404 -247.844033) (xy 336.479533 -247.88761) (xy 336.449968 -247.926954) (xy 336.414475 -247.961046)
			(xy 336.373972 -247.989002) (xy 336.32951 -248.0101) (xy 336.282239 -248.023792) (xy 336.233384 -248.029724)
			(xy 336.184209 -248.027743) (xy 336.13599 -248.017899) (xy 336.089974 -248.000447) (xy 336.047353 -247.97584)
			(xy 336.009232 -247.944715) (xy 335.976597 -247.907878) (xy 335.950294 -247.866282) (xy 335.931003 -247.821006)
			(xy 335.919226 -247.773222) (xy 335.915266 -247.724168) (xy 335.586324 -247.724168) (xy 335.585829 -247.748775)
			(xy 335.577934 -247.797352) (xy 335.56235 -247.844033) (xy 335.539479 -247.88761) (xy 335.509914 -247.926954)
			(xy 335.474421 -247.961046) (xy 335.433918 -247.989002) (xy 335.389456 -248.0101) (xy 335.342185 -248.023792)
			(xy 335.29333 -248.029724) (xy 335.244155 -248.027743) (xy 335.195936 -248.017899) (xy 335.14992 -248.000447)
			(xy 335.107299 -247.97584) (xy 335.069178 -247.944715) (xy 335.036543 -247.907878) (xy 335.01024 -247.866282)
			(xy 334.990949 -247.821006) (xy 334.979172 -247.773222) (xy 334.975212 -247.724168) (xy 334.646524 -247.724168)
			(xy 334.646029 -247.748775) (xy 334.638134 -247.797352) (xy 334.62255 -247.844033) (xy 334.599679 -247.88761)
			(xy 334.570114 -247.926954) (xy 334.534621 -247.961046) (xy 334.494118 -247.989002) (xy 334.449656 -248.0101)
			(xy 334.402385 -248.023792) (xy 334.35353 -248.029724) (xy 334.304355 -248.027743) (xy 334.256136 -248.017899)
			(xy 334.21012 -248.000447) (xy 334.167499 -247.97584) (xy 334.129378 -247.944715) (xy 334.096743 -247.907878)
			(xy 334.07044 -247.866282) (xy 334.051149 -247.821006) (xy 334.039372 -247.773222) (xy 334.035412 -247.724168)
			(xy 333.70647 -247.724168) (xy 333.705975 -247.748775) (xy 333.69808 -247.797352) (xy 333.682496 -247.844033)
			(xy 333.659625 -247.88761) (xy 333.63006 -247.926954) (xy 333.594567 -247.961046) (xy 333.554064 -247.989002)
			(xy 333.509602 -248.0101) (xy 333.462331 -248.023792) (xy 333.413476 -248.029724) (xy 333.364301 -248.027743)
			(xy 333.316082 -248.017899) (xy 333.270066 -248.000447) (xy 333.227445 -247.97584) (xy 333.189324 -247.944715)
			(xy 333.156689 -247.907878) (xy 333.130386 -247.866282) (xy 333.111095 -247.821006) (xy 333.099318 -247.773222)
			(xy 333.095358 -247.724168) (xy 332.766416 -247.724168) (xy 332.765921 -247.748775) (xy 332.758026 -247.797352)
			(xy 332.742442 -247.844033) (xy 332.719571 -247.88761) (xy 332.690006 -247.926954) (xy 332.654513 -247.961046)
			(xy 332.61401 -247.989002) (xy 332.569548 -248.0101) (xy 332.522277 -248.023792) (xy 332.473422 -248.029724)
			(xy 332.424247 -248.027743) (xy 332.376028 -248.017899) (xy 332.330012 -248.000447) (xy 332.287391 -247.97584)
			(xy 332.24927 -247.944715) (xy 332.216635 -247.907878) (xy 332.190332 -247.866282) (xy 332.171041 -247.821006)
			(xy 332.159264 -247.773222) (xy 332.155304 -247.724168) (xy 331.826087 -247.724168) (xy 331.826088 -247.749234)
			(xy 331.817922 -247.798637) (xy 331.801809 -247.846047) (xy 331.778179 -247.890195) (xy 331.747666 -247.929898)
			(xy 331.711087 -247.964094) (xy 331.669421 -247.991866) (xy 331.623783 -248.012471) (xy 331.575396 -248.025358)
			(xy 331.550518 -248.028206) (xy 331.550264 -248.028206) (xy 331.540612 -248.029222) (xy 331.532738 -248.033032)
			(xy 331.528477 -248.035234) (xy 331.520801 -248.040984) (xy 331.517498 -248.044462) (xy 331.47254 -248.093992)
			(xy 331.466478 -248.101162) (xy 331.459677 -248.118647) (xy 331.459332 -248.128028) (xy 331.459332 -248.534174)
			(xy 331.685404 -248.534174) (xy 331.689364 -248.48512) (xy 331.701141 -248.437336) (xy 331.720432 -248.39206)
			(xy 331.746735 -248.350464) (xy 331.77937 -248.313627) (xy 331.817491 -248.282502) (xy 331.860112 -248.257895)
			(xy 331.906128 -248.240443) (xy 331.954347 -248.230599) (xy 332.003522 -248.228618) (xy 332.052377 -248.23455)
			(xy 332.099648 -248.248242) (xy 332.14411 -248.26934) (xy 332.184613 -248.297296) (xy 332.220106 -248.331388)
			(xy 332.249671 -248.370732) (xy 332.272542 -248.414309) (xy 332.288126 -248.46099) (xy 332.296021 -248.509567)
			(xy 332.296516 -248.534174) (xy 332.625204 -248.534174) (xy 332.629164 -248.48512) (xy 332.640941 -248.437336)
			(xy 332.660232 -248.39206) (xy 332.686535 -248.350464) (xy 332.71917 -248.313627) (xy 332.757291 -248.282502)
			(xy 332.799912 -248.257895) (xy 332.845928 -248.240443) (xy 332.894147 -248.230599) (xy 332.943322 -248.228618)
			(xy 332.992177 -248.23455) (xy 333.039448 -248.248242) (xy 333.08391 -248.26934) (xy 333.124413 -248.297296)
			(xy 333.159906 -248.331388) (xy 333.189471 -248.370732) (xy 333.212342 -248.414309) (xy 333.227926 -248.46099)
			(xy 333.235821 -248.509567) (xy 333.236316 -248.534174) (xy 333.565258 -248.534174) (xy 333.569218 -248.48512)
			(xy 333.580995 -248.437336) (xy 333.600286 -248.39206) (xy 333.626589 -248.350464) (xy 333.659224 -248.313627)
			(xy 333.697345 -248.282502) (xy 333.739966 -248.257895) (xy 333.785982 -248.240443) (xy 333.834201 -248.230599)
			(xy 333.883376 -248.228618) (xy 333.932231 -248.23455) (xy 333.979502 -248.248242) (xy 334.023964 -248.26934)
			(xy 334.064467 -248.297296) (xy 334.09996 -248.331388) (xy 334.129525 -248.370732) (xy 334.152396 -248.414309)
			(xy 334.16798 -248.46099) (xy 334.175875 -248.509567) (xy 334.17637 -248.534174) (xy 334.505312 -248.534174)
			(xy 334.509272 -248.48512) (xy 334.521049 -248.437336) (xy 334.54034 -248.39206) (xy 334.566643 -248.350464)
			(xy 334.599278 -248.313627) (xy 334.637399 -248.282502) (xy 334.68002 -248.257895) (xy 334.726036 -248.240443)
			(xy 334.774255 -248.230599) (xy 334.82343 -248.228618) (xy 334.872285 -248.23455) (xy 334.919556 -248.248242)
			(xy 334.964018 -248.26934) (xy 335.004521 -248.297296) (xy 335.040014 -248.331388) (xy 335.069579 -248.370732)
			(xy 335.09245 -248.414309) (xy 335.108034 -248.46099) (xy 335.115929 -248.509567) (xy 335.116424 -248.534174)
			(xy 335.445366 -248.534174) (xy 335.449326 -248.48512) (xy 335.461103 -248.437336) (xy 335.480394 -248.39206)
			(xy 335.506697 -248.350464) (xy 335.539332 -248.313627) (xy 335.577453 -248.282502) (xy 335.620074 -248.257895)
			(xy 335.66609 -248.240443) (xy 335.714309 -248.230599) (xy 335.763484 -248.228618) (xy 335.812339 -248.23455)
			(xy 335.85961 -248.248242) (xy 335.904072 -248.26934) (xy 335.944575 -248.297296) (xy 335.980068 -248.331388)
			(xy 336.009633 -248.370732) (xy 336.032504 -248.414309) (xy 336.048088 -248.46099) (xy 336.055983 -248.509567)
			(xy 336.056478 -248.534174) (xy 336.38542 -248.534174) (xy 336.38938 -248.48512) (xy 336.401157 -248.437336)
			(xy 336.420448 -248.39206) (xy 336.446751 -248.350464) (xy 336.479386 -248.313627) (xy 336.517507 -248.282502)
			(xy 336.560128 -248.257895) (xy 336.606144 -248.240443) (xy 336.654363 -248.230599) (xy 336.703538 -248.228618)
			(xy 336.752393 -248.23455) (xy 336.799664 -248.248242) (xy 336.844126 -248.26934) (xy 336.884629 -248.297296)
			(xy 336.920122 -248.331388) (xy 336.949687 -248.370732) (xy 336.972558 -248.414309) (xy 336.988142 -248.46099)
			(xy 336.996037 -248.509567) (xy 336.996532 -248.534174) (xy 337.32522 -248.534174) (xy 337.32918 -248.48512)
			(xy 337.340957 -248.437336) (xy 337.360248 -248.39206) (xy 337.386551 -248.350464) (xy 337.419186 -248.313627)
			(xy 337.457307 -248.282502) (xy 337.499928 -248.257895) (xy 337.545944 -248.240443) (xy 337.594163 -248.230599)
			(xy 337.643338 -248.228618) (xy 337.692193 -248.23455) (xy 337.739464 -248.248242) (xy 337.783926 -248.26934)
			(xy 337.824429 -248.297296) (xy 337.859922 -248.331388) (xy 337.889487 -248.370732) (xy 337.912358 -248.414309)
			(xy 337.927942 -248.46099) (xy 337.935837 -248.509567) (xy 337.936332 -248.534174) (xy 338.254843 -248.534174)
			(xy 338.258938 -248.483446) (xy 338.271117 -248.434032) (xy 338.291065 -248.387212) (xy 338.318266 -248.344198)
			(xy 338.352014 -248.306104) (xy 338.391436 -248.273917) (xy 338.43551 -248.248471) (xy 338.483096 -248.230424)
			(xy 338.53296 -248.220244) (xy 338.583812 -248.218195) (xy 338.634333 -248.224329) (xy 338.683217 -248.238489)
			(xy 338.729196 -248.260306) (xy 338.77108 -248.289216) (xy 338.807784 -248.324471) (xy 338.838357 -248.365157)
			(xy 338.862008 -248.41022) (xy 338.878124 -248.458494) (xy 338.886288 -248.508728) (xy 338.8868 -248.534174)
			(xy 339.205328 -248.534174) (xy 339.209288 -248.48512) (xy 339.221065 -248.437336) (xy 339.240356 -248.39206)
			(xy 339.266659 -248.350464) (xy 339.299294 -248.313627) (xy 339.337415 -248.282502) (xy 339.380036 -248.257895)
			(xy 339.426052 -248.240443) (xy 339.474271 -248.230599) (xy 339.523446 -248.228618) (xy 339.572301 -248.23455)
			(xy 339.619572 -248.248242) (xy 339.664034 -248.26934) (xy 339.704537 -248.297296) (xy 339.74003 -248.331388)
			(xy 339.769595 -248.370732) (xy 339.792466 -248.414309) (xy 339.80805 -248.46099) (xy 339.815945 -248.509567)
			(xy 339.81644 -248.534174) (xy 340.134951 -248.534174) (xy 340.139046 -248.483446) (xy 340.151225 -248.434032)
			(xy 340.171173 -248.387212) (xy 340.198374 -248.344198) (xy 340.232122 -248.306104) (xy 340.271544 -248.273917)
			(xy 340.315618 -248.248471) (xy 340.363204 -248.230424) (xy 340.413068 -248.220244) (xy 340.46392 -248.218195)
			(xy 340.514441 -248.224329) (xy 340.563325 -248.238489) (xy 340.609304 -248.260306) (xy 340.651188 -248.289216)
			(xy 340.687892 -248.324471) (xy 340.718465 -248.365157) (xy 340.742116 -248.41022) (xy 340.758232 -248.458494)
			(xy 340.766396 -248.508728) (xy 340.766908 -248.534174) (xy 341.085182 -248.534174) (xy 341.089142 -248.48512)
			(xy 341.100919 -248.437336) (xy 341.12021 -248.39206) (xy 341.146513 -248.350464) (xy 341.179148 -248.313627)
			(xy 341.217269 -248.282502) (xy 341.25989 -248.257895) (xy 341.305906 -248.240443) (xy 341.354125 -248.230599)
			(xy 341.4033 -248.228618) (xy 341.452155 -248.23455) (xy 341.499426 -248.248242) (xy 341.543888 -248.26934)
			(xy 341.584391 -248.297296) (xy 341.619884 -248.331388) (xy 341.649449 -248.370732) (xy 341.67232 -248.414309)
			(xy 341.687904 -248.46099) (xy 341.695799 -248.509567) (xy 341.696294 -248.534174) (xy 342.014805 -248.534174)
			(xy 342.0189 -248.483446) (xy 342.031079 -248.434032) (xy 342.051027 -248.387212) (xy 342.078228 -248.344198)
			(xy 342.111976 -248.306104) (xy 342.151398 -248.273917) (xy 342.195472 -248.248471) (xy 342.243058 -248.230424)
			(xy 342.292922 -248.220244) (xy 342.343774 -248.218195) (xy 342.394295 -248.224329) (xy 342.443179 -248.238489)
			(xy 342.489158 -248.260306) (xy 342.531042 -248.289216) (xy 342.567746 -248.324471) (xy 342.598319 -248.365157)
			(xy 342.62197 -248.41022) (xy 342.638086 -248.458494) (xy 342.64625 -248.508728) (xy 342.646762 -248.534174)
			(xy 342.954859 -248.534174) (xy 342.958954 -248.483446) (xy 342.971133 -248.434032) (xy 342.991081 -248.387212)
			(xy 343.018282 -248.344198) (xy 343.05203 -248.306104) (xy 343.091452 -248.273917) (xy 343.135526 -248.248471)
			(xy 343.183112 -248.230424) (xy 343.232976 -248.220244) (xy 343.283828 -248.218195) (xy 343.334349 -248.224329)
			(xy 343.383233 -248.238489) (xy 343.429212 -248.260306) (xy 343.471096 -248.289216) (xy 343.5078 -248.324471)
			(xy 343.538373 -248.365157) (xy 343.562024 -248.41022) (xy 343.57814 -248.458494) (xy 343.586304 -248.508728)
			(xy 343.586816 -248.534174) (xy 343.586304 -248.55962) (xy 343.57814 -248.609854) (xy 343.562024 -248.658128)
			(xy 343.538373 -248.703191) (xy 343.5078 -248.743877) (xy 343.471096 -248.779132) (xy 343.429212 -248.808042)
			(xy 343.383233 -248.829859) (xy 343.334349 -248.844019) (xy 343.283828 -248.850153) (xy 343.232976 -248.848104)
			(xy 343.183112 -248.837924) (xy 343.135526 -248.819877) (xy 343.091452 -248.794431) (xy 343.05203 -248.762244)
			(xy 343.018282 -248.72415) (xy 342.991081 -248.681136) (xy 342.971133 -248.634316) (xy 342.958954 -248.584902)
			(xy 342.954859 -248.534174) (xy 342.646762 -248.534174) (xy 342.64625 -248.55962) (xy 342.638086 -248.609854)
			(xy 342.62197 -248.658128) (xy 342.598319 -248.703191) (xy 342.567746 -248.743877) (xy 342.531042 -248.779132)
			(xy 342.489158 -248.808042) (xy 342.443179 -248.829859) (xy 342.394295 -248.844019) (xy 342.343774 -248.850153)
			(xy 342.292922 -248.848104) (xy 342.243058 -248.837924) (xy 342.195472 -248.819877) (xy 342.151398 -248.794431)
			(xy 342.111976 -248.762244) (xy 342.078228 -248.72415) (xy 342.051027 -248.681136) (xy 342.031079 -248.634316)
			(xy 342.0189 -248.584902) (xy 342.014805 -248.534174) (xy 341.696294 -248.534174) (xy 341.695799 -248.558781)
			(xy 341.687904 -248.607358) (xy 341.67232 -248.654039) (xy 341.649449 -248.697616) (xy 341.619884 -248.73696)
			(xy 341.584391 -248.771052) (xy 341.543888 -248.799008) (xy 341.499426 -248.820106) (xy 341.452155 -248.833798)
			(xy 341.4033 -248.83973) (xy 341.354125 -248.837749) (xy 341.305906 -248.827905) (xy 341.25989 -248.810453)
			(xy 341.217269 -248.785846) (xy 341.179148 -248.754721) (xy 341.146513 -248.717884) (xy 341.12021 -248.676288)
			(xy 341.100919 -248.631012) (xy 341.089142 -248.583228) (xy 341.085182 -248.534174) (xy 340.766908 -248.534174)
			(xy 340.766396 -248.55962) (xy 340.758232 -248.609854) (xy 340.742116 -248.658128) (xy 340.718465 -248.703191)
			(xy 340.687892 -248.743877) (xy 340.651188 -248.779132) (xy 340.609304 -248.808042) (xy 340.563325 -248.829859)
			(xy 340.514441 -248.844019) (xy 340.46392 -248.850153) (xy 340.413068 -248.848104) (xy 340.363204 -248.837924)
			(xy 340.315618 -248.819877) (xy 340.271544 -248.794431) (xy 340.232122 -248.762244) (xy 340.198374 -248.72415)
			(xy 340.171173 -248.681136) (xy 340.151225 -248.634316) (xy 340.139046 -248.584902) (xy 340.134951 -248.534174)
			(xy 339.81644 -248.534174) (xy 339.815945 -248.558781) (xy 339.80805 -248.607358) (xy 339.792466 -248.654039)
			(xy 339.769595 -248.697616) (xy 339.74003 -248.73696) (xy 339.704537 -248.771052) (xy 339.664034 -248.799008)
			(xy 339.619572 -248.820106) (xy 339.572301 -248.833798) (xy 339.523446 -248.83973) (xy 339.474271 -248.837749)
			(xy 339.426052 -248.827905) (xy 339.380036 -248.810453) (xy 339.337415 -248.785846) (xy 339.299294 -248.754721)
			(xy 339.266659 -248.717884) (xy 339.240356 -248.676288) (xy 339.221065 -248.631012) (xy 339.209288 -248.583228)
			(xy 339.205328 -248.534174) (xy 338.8868 -248.534174) (xy 338.886288 -248.55962) (xy 338.878124 -248.609854)
			(xy 338.862008 -248.658128) (xy 338.838357 -248.703191) (xy 338.807784 -248.743877) (xy 338.77108 -248.779132)
			(xy 338.729196 -248.808042) (xy 338.683217 -248.829859) (xy 338.634333 -248.844019) (xy 338.583812 -248.850153)
			(xy 338.53296 -248.848104) (xy 338.483096 -248.837924) (xy 338.43551 -248.819877) (xy 338.391436 -248.794431)
			(xy 338.352014 -248.762244) (xy 338.318266 -248.72415) (xy 338.291065 -248.681136) (xy 338.271117 -248.634316)
			(xy 338.258938 -248.584902) (xy 338.254843 -248.534174) (xy 337.936332 -248.534174) (xy 337.935837 -248.558781)
			(xy 337.927942 -248.607358) (xy 337.912358 -248.654039) (xy 337.889487 -248.697616) (xy 337.859922 -248.73696)
			(xy 337.824429 -248.771052) (xy 337.783926 -248.799008) (xy 337.739464 -248.820106) (xy 337.692193 -248.833798)
			(xy 337.643338 -248.83973) (xy 337.594163 -248.837749) (xy 337.545944 -248.827905) (xy 337.499928 -248.810453)
			(xy 337.457307 -248.785846) (xy 337.419186 -248.754721) (xy 337.386551 -248.717884) (xy 337.360248 -248.676288)
			(xy 337.340957 -248.631012) (xy 337.32918 -248.583228) (xy 337.32522 -248.534174) (xy 336.996532 -248.534174)
			(xy 336.996037 -248.558781) (xy 336.988142 -248.607358) (xy 336.972558 -248.654039) (xy 336.949687 -248.697616)
			(xy 336.920122 -248.73696) (xy 336.884629 -248.771052) (xy 336.844126 -248.799008) (xy 336.799664 -248.820106)
			(xy 336.752393 -248.833798) (xy 336.703538 -248.83973) (xy 336.654363 -248.837749) (xy 336.606144 -248.827905)
			(xy 336.560128 -248.810453) (xy 336.517507 -248.785846) (xy 336.479386 -248.754721) (xy 336.446751 -248.717884)
			(xy 336.420448 -248.676288) (xy 336.401157 -248.631012) (xy 336.38938 -248.583228) (xy 336.38542 -248.534174)
			(xy 336.056478 -248.534174) (xy 336.055983 -248.558781) (xy 336.048088 -248.607358) (xy 336.032504 -248.654039)
			(xy 336.009633 -248.697616) (xy 335.980068 -248.73696) (xy 335.944575 -248.771052) (xy 335.904072 -248.799008)
			(xy 335.85961 -248.820106) (xy 335.812339 -248.833798) (xy 335.763484 -248.83973) (xy 335.714309 -248.837749)
			(xy 335.66609 -248.827905) (xy 335.620074 -248.810453) (xy 335.577453 -248.785846) (xy 335.539332 -248.754721)
			(xy 335.506697 -248.717884) (xy 335.480394 -248.676288) (xy 335.461103 -248.631012) (xy 335.449326 -248.583228)
			(xy 335.445366 -248.534174) (xy 335.116424 -248.534174) (xy 335.115929 -248.558781) (xy 335.108034 -248.607358)
			(xy 335.09245 -248.654039) (xy 335.069579 -248.697616) (xy 335.040014 -248.73696) (xy 335.004521 -248.771052)
			(xy 334.964018 -248.799008) (xy 334.919556 -248.820106) (xy 334.872285 -248.833798) (xy 334.82343 -248.83973)
			(xy 334.774255 -248.837749) (xy 334.726036 -248.827905) (xy 334.68002 -248.810453) (xy 334.637399 -248.785846)
			(xy 334.599278 -248.754721) (xy 334.566643 -248.717884) (xy 334.54034 -248.676288) (xy 334.521049 -248.631012)
			(xy 334.509272 -248.583228) (xy 334.505312 -248.534174) (xy 334.17637 -248.534174) (xy 334.175875 -248.558781)
			(xy 334.16798 -248.607358) (xy 334.152396 -248.654039) (xy 334.129525 -248.697616) (xy 334.09996 -248.73696)
			(xy 334.064467 -248.771052) (xy 334.023964 -248.799008) (xy 333.979502 -248.820106) (xy 333.932231 -248.833798)
			(xy 333.883376 -248.83973) (xy 333.834201 -248.837749) (xy 333.785982 -248.827905) (xy 333.739966 -248.810453)
			(xy 333.697345 -248.785846) (xy 333.659224 -248.754721) (xy 333.626589 -248.717884) (xy 333.600286 -248.676288)
			(xy 333.580995 -248.631012) (xy 333.569218 -248.583228) (xy 333.565258 -248.534174) (xy 333.236316 -248.534174)
			(xy 333.235821 -248.558781) (xy 333.227926 -248.607358) (xy 333.212342 -248.654039) (xy 333.189471 -248.697616)
			(xy 333.159906 -248.73696) (xy 333.124413 -248.771052) (xy 333.08391 -248.799008) (xy 333.039448 -248.820106)
			(xy 332.992177 -248.833798) (xy 332.943322 -248.83973) (xy 332.894147 -248.837749) (xy 332.845928 -248.827905)
			(xy 332.799912 -248.810453) (xy 332.757291 -248.785846) (xy 332.71917 -248.754721) (xy 332.686535 -248.717884)
			(xy 332.660232 -248.676288) (xy 332.640941 -248.631012) (xy 332.629164 -248.583228) (xy 332.625204 -248.534174)
			(xy 332.296516 -248.534174) (xy 332.296021 -248.558781) (xy 332.288126 -248.607358) (xy 332.272542 -248.654039)
			(xy 332.249671 -248.697616) (xy 332.220106 -248.73696) (xy 332.184613 -248.771052) (xy 332.14411 -248.799008)
			(xy 332.099648 -248.820106) (xy 332.052377 -248.833798) (xy 332.003522 -248.83973) (xy 331.954347 -248.837749)
			(xy 331.906128 -248.827905) (xy 331.860112 -248.810453) (xy 331.817491 -248.785846) (xy 331.77937 -248.754721)
			(xy 331.746735 -248.717884) (xy 331.720432 -248.676288) (xy 331.701141 -248.631012) (xy 331.689364 -248.583228)
			(xy 331.685404 -248.534174) (xy 331.459332 -248.534174) (xy 331.459332 -248.94032) (xy 331.459813 -248.949674)
			(xy 331.466592 -248.967119) (xy 331.47254 -248.974356) (xy 331.517498 -249.023886) (xy 331.520809 -249.027355)
			(xy 331.528478 -249.033113) (xy 331.532738 -249.035316) (xy 331.540612 -249.039126) (xy 331.550264 -249.040142)
			(xy 331.550518 -249.040142) (xy 331.575389 -249.043053) (xy 331.623774 -249.055938) (xy 331.669411 -249.076542)
			(xy 331.711076 -249.104313) (xy 331.747654 -249.138506) (xy 331.778166 -249.178207) (xy 331.801796 -249.222353)
			(xy 331.817909 -249.269761) (xy 331.826075 -249.319162) (xy 331.826075 -249.34418) (xy 332.155304 -249.34418)
			(xy 332.159264 -249.295126) (xy 332.171041 -249.247342) (xy 332.190332 -249.202066) (xy 332.216635 -249.16047)
			(xy 332.24927 -249.123633) (xy 332.287391 -249.092508) (xy 332.330012 -249.067901) (xy 332.376028 -249.050449)
			(xy 332.424247 -249.040605) (xy 332.473422 -249.038624) (xy 332.522277 -249.044556) (xy 332.569548 -249.058248)
			(xy 332.61401 -249.079346) (xy 332.654513 -249.107302) (xy 332.690006 -249.141394) (xy 332.719571 -249.180738)
			(xy 332.742442 -249.224315) (xy 332.758026 -249.270996) (xy 332.765921 -249.319573) (xy 332.766416 -249.34418)
			(xy 333.095358 -249.34418) (xy 333.099318 -249.295126) (xy 333.111095 -249.247342) (xy 333.130386 -249.202066)
			(xy 333.156689 -249.16047) (xy 333.189324 -249.123633) (xy 333.227445 -249.092508) (xy 333.270066 -249.067901)
			(xy 333.316082 -249.050449) (xy 333.364301 -249.040605) (xy 333.413476 -249.038624) (xy 333.462331 -249.044556)
			(xy 333.509602 -249.058248) (xy 333.554064 -249.079346) (xy 333.594567 -249.107302) (xy 333.63006 -249.141394)
			(xy 333.659625 -249.180738) (xy 333.682496 -249.224315) (xy 333.69808 -249.270996) (xy 333.705975 -249.319573)
			(xy 333.70647 -249.34418) (xy 334.975212 -249.34418) (xy 334.979172 -249.295126) (xy 334.990949 -249.247342)
			(xy 335.01024 -249.202066) (xy 335.036543 -249.16047) (xy 335.069178 -249.123633) (xy 335.107299 -249.092508)
			(xy 335.14992 -249.067901) (xy 335.195936 -249.050449) (xy 335.244155 -249.040605) (xy 335.29333 -249.038624)
			(xy 335.342185 -249.044556) (xy 335.389456 -249.058248) (xy 335.433918 -249.079346) (xy 335.474421 -249.107302)
			(xy 335.509914 -249.141394) (xy 335.539479 -249.180738) (xy 335.56235 -249.224315) (xy 335.577934 -249.270996)
			(xy 335.585829 -249.319573) (xy 335.586324 -249.34418) (xy 335.915266 -249.34418) (xy 335.919226 -249.295126)
			(xy 335.931003 -249.247342) (xy 335.950294 -249.202066) (xy 335.976597 -249.16047) (xy 336.009232 -249.123633)
			(xy 336.047353 -249.092508) (xy 336.089974 -249.067901) (xy 336.13599 -249.050449) (xy 336.184209 -249.040605)
			(xy 336.233384 -249.038624) (xy 336.282239 -249.044556) (xy 336.32951 -249.058248) (xy 336.373972 -249.079346)
			(xy 336.414475 -249.107302) (xy 336.449968 -249.141394) (xy 336.479533 -249.180738) (xy 336.502404 -249.224315)
			(xy 336.517988 -249.270996) (xy 336.525883 -249.319573) (xy 336.526378 -249.34418) (xy 336.85532 -249.34418)
			(xy 336.85928 -249.295126) (xy 336.871057 -249.247342) (xy 336.890348 -249.202066) (xy 336.916651 -249.16047)
			(xy 336.949286 -249.123633) (xy 336.987407 -249.092508) (xy 337.030028 -249.067901) (xy 337.076044 -249.050449)
			(xy 337.124263 -249.040605) (xy 337.173438 -249.038624) (xy 337.222293 -249.044556) (xy 337.269564 -249.058248)
			(xy 337.314026 -249.079346) (xy 337.354529 -249.107302) (xy 337.390022 -249.141394) (xy 337.419587 -249.180738)
			(xy 337.442458 -249.224315) (xy 337.458042 -249.270996) (xy 337.465937 -249.319573) (xy 337.466432 -249.34418)
			(xy 337.795374 -249.34418) (xy 337.799334 -249.295126) (xy 337.811111 -249.247342) (xy 337.830402 -249.202066)
			(xy 337.856705 -249.16047) (xy 337.88934 -249.123633) (xy 337.927461 -249.092508) (xy 337.970082 -249.067901)
			(xy 338.016098 -249.050449) (xy 338.064317 -249.040605) (xy 338.113492 -249.038624) (xy 338.162347 -249.044556)
			(xy 338.209618 -249.058248) (xy 338.25408 -249.079346) (xy 338.294583 -249.107302) (xy 338.330076 -249.141394)
			(xy 338.359641 -249.180738) (xy 338.382512 -249.224315) (xy 338.398096 -249.270996) (xy 338.405991 -249.319573)
			(xy 338.406486 -249.34418) (xy 338.735174 -249.34418) (xy 338.739134 -249.295126) (xy 338.750911 -249.247342)
			(xy 338.770202 -249.202066) (xy 338.796505 -249.16047) (xy 338.82914 -249.123633) (xy 338.867261 -249.092508)
			(xy 338.909882 -249.067901) (xy 338.955898 -249.050449) (xy 339.004117 -249.040605) (xy 339.053292 -249.038624)
			(xy 339.102147 -249.044556) (xy 339.149418 -249.058248) (xy 339.19388 -249.079346) (xy 339.234383 -249.107302)
			(xy 339.269876 -249.141394) (xy 339.299441 -249.180738) (xy 339.322312 -249.224315) (xy 339.337896 -249.270996)
			(xy 339.345791 -249.319573) (xy 339.346286 -249.34418) (xy 339.664797 -249.34418) (xy 339.668892 -249.293452)
			(xy 339.681071 -249.244038) (xy 339.701019 -249.197218) (xy 339.72822 -249.154204) (xy 339.761968 -249.11611)
			(xy 339.80139 -249.083923) (xy 339.845464 -249.058477) (xy 339.89305 -249.04043) (xy 339.942914 -249.03025)
			(xy 339.993766 -249.028201) (xy 340.044287 -249.034335) (xy 340.093171 -249.048495) (xy 340.13915 -249.070312)
			(xy 340.181034 -249.099222) (xy 340.217738 -249.134477) (xy 340.248311 -249.175163) (xy 340.271962 -249.220226)
			(xy 340.288078 -249.2685) (xy 340.296242 -249.318734) (xy 340.296754 -249.34418) (xy 341.555336 -249.34418)
			(xy 341.559296 -249.295126) (xy 341.571073 -249.247342) (xy 341.590364 -249.202066) (xy 341.616667 -249.16047)
			(xy 341.649302 -249.123633) (xy 341.687423 -249.092508) (xy 341.730044 -249.067901) (xy 341.77606 -249.050449)
			(xy 341.824279 -249.040605) (xy 341.873454 -249.038624) (xy 341.922309 -249.044556) (xy 341.96958 -249.058248)
			(xy 342.014042 -249.079346) (xy 342.054545 -249.107302) (xy 342.090038 -249.141394) (xy 342.119603 -249.180738)
			(xy 342.142474 -249.224315) (xy 342.158058 -249.270996) (xy 342.165953 -249.319573) (xy 342.166448 -249.34418)
			(xy 342.49539 -249.34418) (xy 342.49935 -249.295126) (xy 342.511127 -249.247342) (xy 342.530418 -249.202066)
			(xy 342.556721 -249.16047) (xy 342.589356 -249.123633) (xy 342.627477 -249.092508) (xy 342.670098 -249.067901)
			(xy 342.716114 -249.050449) (xy 342.764333 -249.040605) (xy 342.813508 -249.038624) (xy 342.862363 -249.044556)
			(xy 342.909634 -249.058248) (xy 342.954096 -249.079346) (xy 342.994599 -249.107302) (xy 343.030092 -249.141394)
			(xy 343.059657 -249.180738) (xy 343.082528 -249.224315) (xy 343.098112 -249.270996) (xy 343.106007 -249.319573)
			(xy 343.106502 -249.34418) (xy 343.106007 -249.368787) (xy 343.098112 -249.417364) (xy 343.082528 -249.464045)
			(xy 343.059657 -249.507622) (xy 343.030092 -249.546966) (xy 342.994599 -249.581058) (xy 342.954096 -249.609014)
			(xy 342.909634 -249.630112) (xy 342.862363 -249.643804) (xy 342.813508 -249.649736) (xy 342.764333 -249.647755)
			(xy 342.716114 -249.637911) (xy 342.670098 -249.620459) (xy 342.627477 -249.595852) (xy 342.589356 -249.564727)
			(xy 342.556721 -249.52789) (xy 342.530418 -249.486294) (xy 342.511127 -249.441018) (xy 342.49935 -249.393234)
			(xy 342.49539 -249.34418) (xy 342.166448 -249.34418) (xy 342.165953 -249.368787) (xy 342.158058 -249.417364)
			(xy 342.142474 -249.464045) (xy 342.119603 -249.507622) (xy 342.090038 -249.546966) (xy 342.054545 -249.581058)
			(xy 342.014042 -249.609014) (xy 341.96958 -249.630112) (xy 341.922309 -249.643804) (xy 341.873454 -249.649736)
			(xy 341.824279 -249.647755) (xy 341.77606 -249.637911) (xy 341.730044 -249.620459) (xy 341.687423 -249.595852)
			(xy 341.649302 -249.564727) (xy 341.616667 -249.52789) (xy 341.590364 -249.486294) (xy 341.571073 -249.441018)
			(xy 341.559296 -249.393234) (xy 341.555336 -249.34418) (xy 340.296754 -249.34418) (xy 340.296242 -249.369626)
			(xy 340.288078 -249.41986) (xy 340.271962 -249.468134) (xy 340.248311 -249.513197) (xy 340.217738 -249.553883)
			(xy 340.181034 -249.589138) (xy 340.13915 -249.618048) (xy 340.093171 -249.639865) (xy 340.044287 -249.654025)
			(xy 339.993766 -249.660159) (xy 339.942914 -249.65811) (xy 339.89305 -249.64793) (xy 339.845464 -249.629883)
			(xy 339.80139 -249.604437) (xy 339.761968 -249.57225) (xy 339.72822 -249.534156) (xy 339.701019 -249.491142)
			(xy 339.681071 -249.444322) (xy 339.668892 -249.394908) (xy 339.664797 -249.34418) (xy 339.346286 -249.34418)
			(xy 339.345791 -249.368787) (xy 339.337896 -249.417364) (xy 339.322312 -249.464045) (xy 339.299441 -249.507622)
			(xy 339.269876 -249.546966) (xy 339.234383 -249.581058) (xy 339.19388 -249.609014) (xy 339.149418 -249.630112)
			(xy 339.102147 -249.643804) (xy 339.053292 -249.649736) (xy 339.004117 -249.647755) (xy 338.955898 -249.637911)
			(xy 338.909882 -249.620459) (xy 338.867261 -249.595852) (xy 338.82914 -249.564727) (xy 338.796505 -249.52789)
			(xy 338.770202 -249.486294) (xy 338.750911 -249.441018) (xy 338.739134 -249.393234) (xy 338.735174 -249.34418)
			(xy 338.406486 -249.34418) (xy 338.405991 -249.368787) (xy 338.398096 -249.417364) (xy 338.382512 -249.464045)
			(xy 338.359641 -249.507622) (xy 338.330076 -249.546966) (xy 338.294583 -249.581058) (xy 338.25408 -249.609014)
			(xy 338.209618 -249.630112) (xy 338.162347 -249.643804) (xy 338.113492 -249.649736) (xy 338.064317 -249.647755)
			(xy 338.016098 -249.637911) (xy 337.970082 -249.620459) (xy 337.927461 -249.595852) (xy 337.88934 -249.564727)
			(xy 337.856705 -249.52789) (xy 337.830402 -249.486294) (xy 337.811111 -249.441018) (xy 337.799334 -249.393234)
			(xy 337.795374 -249.34418) (xy 337.466432 -249.34418) (xy 337.465937 -249.368787) (xy 337.458042 -249.417364)
			(xy 337.442458 -249.464045) (xy 337.419587 -249.507622) (xy 337.390022 -249.546966) (xy 337.354529 -249.581058)
			(xy 337.314026 -249.609014) (xy 337.269564 -249.630112) (xy 337.222293 -249.643804) (xy 337.173438 -249.649736)
			(xy 337.124263 -249.647755) (xy 337.076044 -249.637911) (xy 337.030028 -249.620459) (xy 336.987407 -249.595852)
			(xy 336.949286 -249.564727) (xy 336.916651 -249.52789) (xy 336.890348 -249.486294) (xy 336.871057 -249.441018)
			(xy 336.85928 -249.393234) (xy 336.85532 -249.34418) (xy 336.526378 -249.34418) (xy 336.525883 -249.368787)
			(xy 336.517988 -249.417364) (xy 336.502404 -249.464045) (xy 336.479533 -249.507622) (xy 336.449968 -249.546966)
			(xy 336.414475 -249.581058) (xy 336.373972 -249.609014) (xy 336.32951 -249.630112) (xy 336.282239 -249.643804)
			(xy 336.233384 -249.649736) (xy 336.184209 -249.647755) (xy 336.13599 -249.637911) (xy 336.089974 -249.620459)
			(xy 336.047353 -249.595852) (xy 336.009232 -249.564727) (xy 335.976597 -249.52789) (xy 335.950294 -249.486294)
			(xy 335.931003 -249.441018) (xy 335.919226 -249.393234) (xy 335.915266 -249.34418) (xy 335.586324 -249.34418)
			(xy 335.585829 -249.368787) (xy 335.577934 -249.417364) (xy 335.56235 -249.464045) (xy 335.539479 -249.507622)
			(xy 335.509914 -249.546966) (xy 335.474421 -249.581058) (xy 335.433918 -249.609014) (xy 335.389456 -249.630112)
			(xy 335.342185 -249.643804) (xy 335.29333 -249.649736) (xy 335.244155 -249.647755) (xy 335.195936 -249.637911)
			(xy 335.14992 -249.620459) (xy 335.107299 -249.595852) (xy 335.069178 -249.564727) (xy 335.036543 -249.52789)
			(xy 335.01024 -249.486294) (xy 334.990949 -249.441018) (xy 334.979172 -249.393234) (xy 334.975212 -249.34418)
			(xy 333.70647 -249.34418) (xy 333.705975 -249.368787) (xy 333.69808 -249.417364) (xy 333.682496 -249.464045)
			(xy 333.659625 -249.507622) (xy 333.63006 -249.546966) (xy 333.594567 -249.581058) (xy 333.554064 -249.609014)
			(xy 333.509602 -249.630112) (xy 333.462331 -249.643804) (xy 333.413476 -249.649736) (xy 333.364301 -249.647755)
			(xy 333.316082 -249.637911) (xy 333.270066 -249.620459) (xy 333.227445 -249.595852) (xy 333.189324 -249.564727)
			(xy 333.156689 -249.52789) (xy 333.130386 -249.486294) (xy 333.111095 -249.441018) (xy 333.099318 -249.393234)
			(xy 333.095358 -249.34418) (xy 332.766416 -249.34418) (xy 332.765921 -249.368787) (xy 332.758026 -249.417364)
			(xy 332.742442 -249.464045) (xy 332.719571 -249.507622) (xy 332.690006 -249.546966) (xy 332.654513 -249.581058)
			(xy 332.61401 -249.609014) (xy 332.569548 -249.630112) (xy 332.522277 -249.643804) (xy 332.473422 -249.649736)
			(xy 332.424247 -249.647755) (xy 332.376028 -249.637911) (xy 332.330012 -249.620459) (xy 332.287391 -249.595852)
			(xy 332.24927 -249.564727) (xy 332.216635 -249.52789) (xy 332.190332 -249.486294) (xy 332.171041 -249.441018)
			(xy 332.159264 -249.393234) (xy 332.155304 -249.34418) (xy 331.826075 -249.34418) (xy 331.826076 -249.369234)
			(xy 331.81791 -249.418635) (xy 331.801797 -249.466044) (xy 331.778169 -249.51019) (xy 331.747657 -249.549891)
			(xy 331.711079 -249.584085) (xy 331.669414 -249.611856) (xy 331.623778 -249.63246) (xy 331.575393 -249.645346)
			(xy 331.550518 -249.648218) (xy 331.550264 -249.648218) (xy 331.540612 -249.649234) (xy 331.532738 -249.653044)
			(xy 331.528477 -249.655246) (xy 331.520803 -249.660998) (xy 331.517498 -249.664474) (xy 331.47254 -249.714004)
			(xy 331.46648 -249.721174) (xy 331.459683 -249.73866) (xy 331.459332 -249.74804) (xy 331.459332 -250.154186)
			(xy 331.685404 -250.154186) (xy 331.689364 -250.105132) (xy 331.701141 -250.057348) (xy 331.720432 -250.012072)
			(xy 331.746735 -249.970476) (xy 331.77937 -249.933639) (xy 331.817491 -249.902514) (xy 331.860112 -249.877907)
			(xy 331.906128 -249.860455) (xy 331.954347 -249.850611) (xy 332.003522 -249.84863) (xy 332.052377 -249.854562)
			(xy 332.099648 -249.868254) (xy 332.14411 -249.889352) (xy 332.184613 -249.917308) (xy 332.220106 -249.9514)
			(xy 332.249671 -249.990744) (xy 332.272542 -250.034321) (xy 332.288126 -250.081002) (xy 332.296021 -250.129579)
			(xy 332.296516 -250.154186) (xy 332.625204 -250.154186) (xy 332.629164 -250.105132) (xy 332.640941 -250.057348)
			(xy 332.660232 -250.012072) (xy 332.686535 -249.970476) (xy 332.71917 -249.933639) (xy 332.757291 -249.902514)
			(xy 332.799912 -249.877907) (xy 332.845928 -249.860455) (xy 332.894147 -249.850611) (xy 332.943322 -249.84863)
			(xy 332.992177 -249.854562) (xy 333.039448 -249.868254) (xy 333.08391 -249.889352) (xy 333.124413 -249.917308)
			(xy 333.159906 -249.9514) (xy 333.189471 -249.990744) (xy 333.212342 -250.034321) (xy 333.227926 -250.081002)
			(xy 333.235821 -250.129579) (xy 333.236316 -250.154186) (xy 333.565258 -250.154186) (xy 333.569218 -250.105132)
			(xy 333.580995 -250.057348) (xy 333.600286 -250.012072) (xy 333.626589 -249.970476) (xy 333.659224 -249.933639)
			(xy 333.697345 -249.902514) (xy 333.739966 -249.877907) (xy 333.785982 -249.860455) (xy 333.834201 -249.850611)
			(xy 333.883376 -249.84863) (xy 333.932231 -249.854562) (xy 333.979502 -249.868254) (xy 334.023964 -249.889352)
			(xy 334.064467 -249.917308) (xy 334.09996 -249.9514) (xy 334.129525 -249.990744) (xy 334.152396 -250.034321)
			(xy 334.16798 -250.081002) (xy 334.175875 -250.129579) (xy 334.17637 -250.154186) (xy 334.505312 -250.154186)
			(xy 334.509272 -250.105132) (xy 334.521049 -250.057348) (xy 334.54034 -250.012072) (xy 334.566643 -249.970476)
			(xy 334.599278 -249.933639) (xy 334.637399 -249.902514) (xy 334.68002 -249.877907) (xy 334.726036 -249.860455)
			(xy 334.774255 -249.850611) (xy 334.82343 -249.84863) (xy 334.872285 -249.854562) (xy 334.919556 -249.868254)
			(xy 334.964018 -249.889352) (xy 335.004521 -249.917308) (xy 335.040014 -249.9514) (xy 335.069579 -249.990744)
			(xy 335.09245 -250.034321) (xy 335.108034 -250.081002) (xy 335.115929 -250.129579) (xy 335.116424 -250.154186)
			(xy 335.445366 -250.154186) (xy 335.449326 -250.105132) (xy 335.461103 -250.057348) (xy 335.480394 -250.012072)
			(xy 335.506697 -249.970476) (xy 335.539332 -249.933639) (xy 335.577453 -249.902514) (xy 335.620074 -249.877907)
			(xy 335.66609 -249.860455) (xy 335.714309 -249.850611) (xy 335.763484 -249.84863) (xy 335.812339 -249.854562)
			(xy 335.85961 -249.868254) (xy 335.904072 -249.889352) (xy 335.944575 -249.917308) (xy 335.980068 -249.9514)
			(xy 336.009633 -249.990744) (xy 336.032504 -250.034321) (xy 336.048088 -250.081002) (xy 336.055983 -250.129579)
			(xy 336.056478 -250.154186) (xy 336.38542 -250.154186) (xy 336.38938 -250.105132) (xy 336.401157 -250.057348)
			(xy 336.420448 -250.012072) (xy 336.446751 -249.970476) (xy 336.479386 -249.933639) (xy 336.517507 -249.902514)
			(xy 336.560128 -249.877907) (xy 336.606144 -249.860455) (xy 336.654363 -249.850611) (xy 336.703538 -249.84863)
			(xy 336.752393 -249.854562) (xy 336.799664 -249.868254) (xy 336.844126 -249.889352) (xy 336.884629 -249.917308)
			(xy 336.920122 -249.9514) (xy 336.949687 -249.990744) (xy 336.972558 -250.034321) (xy 336.988142 -250.081002)
			(xy 336.996037 -250.129579) (xy 336.996532 -250.154186) (xy 337.32522 -250.154186) (xy 337.32918 -250.105132)
			(xy 337.340957 -250.057348) (xy 337.360248 -250.012072) (xy 337.386551 -249.970476) (xy 337.419186 -249.933639)
			(xy 337.457307 -249.902514) (xy 337.499928 -249.877907) (xy 337.545944 -249.860455) (xy 337.594163 -249.850611)
			(xy 337.643338 -249.84863) (xy 337.692193 -249.854562) (xy 337.739464 -249.868254) (xy 337.783926 -249.889352)
			(xy 337.824429 -249.917308) (xy 337.859922 -249.9514) (xy 337.889487 -249.990744) (xy 337.912358 -250.034321)
			(xy 337.927942 -250.081002) (xy 337.935837 -250.129579) (xy 337.936332 -250.154186) (xy 338.265274 -250.154186)
			(xy 338.269234 -250.105132) (xy 338.281011 -250.057348) (xy 338.300302 -250.012072) (xy 338.326605 -249.970476)
			(xy 338.35924 -249.933639) (xy 338.397361 -249.902514) (xy 338.439982 -249.877907) (xy 338.485998 -249.860455)
			(xy 338.534217 -249.850611) (xy 338.583392 -249.84863) (xy 338.632247 -249.854562) (xy 338.679518 -249.868254)
			(xy 338.72398 -249.889352) (xy 338.764483 -249.917308) (xy 338.799976 -249.9514) (xy 338.829541 -249.990744)
			(xy 338.852412 -250.034321) (xy 338.867996 -250.081002) (xy 338.875891 -250.129579) (xy 338.876386 -250.154186)
			(xy 339.205328 -250.154186) (xy 339.209288 -250.105132) (xy 339.221065 -250.057348) (xy 339.240356 -250.012072)
			(xy 339.266659 -249.970476) (xy 339.299294 -249.933639) (xy 339.337415 -249.902514) (xy 339.380036 -249.877907)
			(xy 339.426052 -249.860455) (xy 339.474271 -249.850611) (xy 339.523446 -249.84863) (xy 339.572301 -249.854562)
			(xy 339.619572 -249.868254) (xy 339.664034 -249.889352) (xy 339.704537 -249.917308) (xy 339.74003 -249.9514)
			(xy 339.769595 -249.990744) (xy 339.792466 -250.034321) (xy 339.80805 -250.081002) (xy 339.815945 -250.129579)
			(xy 339.81644 -250.154186) (xy 340.134951 -250.154186) (xy 340.139046 -250.103458) (xy 340.151225 -250.054044)
			(xy 340.171173 -250.007224) (xy 340.198374 -249.96421) (xy 340.232122 -249.926116) (xy 340.271544 -249.893929)
			(xy 340.315618 -249.868483) (xy 340.363204 -249.850436) (xy 340.413068 -249.840256) (xy 340.46392 -249.838207)
			(xy 340.514441 -249.844341) (xy 340.563325 -249.858501) (xy 340.609304 -249.880318) (xy 340.651188 -249.909228)
			(xy 340.687892 -249.944483) (xy 340.718465 -249.985169) (xy 340.742116 -250.030232) (xy 340.758232 -250.078506)
			(xy 340.766396 -250.12874) (xy 340.766908 -250.154186) (xy 341.085182 -250.154186) (xy 341.089142 -250.105132)
			(xy 341.100919 -250.057348) (xy 341.12021 -250.012072) (xy 341.146513 -249.970476) (xy 341.179148 -249.933639)
			(xy 341.217269 -249.902514) (xy 341.25989 -249.877907) (xy 341.305906 -249.860455) (xy 341.354125 -249.850611)
			(xy 341.4033 -249.84863) (xy 341.452155 -249.854562) (xy 341.499426 -249.868254) (xy 341.543888 -249.889352)
			(xy 341.584391 -249.917308) (xy 341.619884 -249.9514) (xy 341.649449 -249.990744) (xy 341.67232 -250.034321)
			(xy 341.687904 -250.081002) (xy 341.695799 -250.129579) (xy 341.696294 -250.154186) (xy 342.025236 -250.154186)
			(xy 342.029196 -250.105132) (xy 342.040973 -250.057348) (xy 342.060264 -250.012072) (xy 342.086567 -249.970476)
			(xy 342.119202 -249.933639) (xy 342.157323 -249.902514) (xy 342.199944 -249.877907) (xy 342.24596 -249.860455)
			(xy 342.294179 -249.850611) (xy 342.343354 -249.84863) (xy 342.392209 -249.854562) (xy 342.43948 -249.868254)
			(xy 342.483942 -249.889352) (xy 342.524445 -249.917308) (xy 342.559938 -249.9514) (xy 342.589503 -249.990744)
			(xy 342.612374 -250.034321) (xy 342.627958 -250.081002) (xy 342.635853 -250.129579) (xy 342.636348 -250.154186)
			(xy 342.954859 -250.154186) (xy 342.958954 -250.103458) (xy 342.971133 -250.054044) (xy 342.991081 -250.007224)
			(xy 343.018282 -249.96421) (xy 343.05203 -249.926116) (xy 343.091452 -249.893929) (xy 343.135526 -249.868483)
			(xy 343.183112 -249.850436) (xy 343.232976 -249.840256) (xy 343.283828 -249.838207) (xy 343.334349 -249.844341)
			(xy 343.383233 -249.858501) (xy 343.429212 -249.880318) (xy 343.471096 -249.909228) (xy 343.5078 -249.944483)
			(xy 343.538373 -249.985169) (xy 343.562024 -250.030232) (xy 343.57814 -250.078506) (xy 343.586304 -250.12874)
			(xy 343.586816 -250.154186) (xy 343.586304 -250.179632) (xy 343.57814 -250.229866) (xy 343.562024 -250.27814)
			(xy 343.538373 -250.323203) (xy 343.5078 -250.363889) (xy 343.471096 -250.399144) (xy 343.429212 -250.428054)
			(xy 343.383233 -250.449871) (xy 343.334349 -250.464031) (xy 343.283828 -250.470165) (xy 343.232976 -250.468116)
			(xy 343.183112 -250.457936) (xy 343.135526 -250.439889) (xy 343.091452 -250.414443) (xy 343.05203 -250.382256)
			(xy 343.018282 -250.344162) (xy 342.991081 -250.301148) (xy 342.971133 -250.254328) (xy 342.958954 -250.204914)
			(xy 342.954859 -250.154186) (xy 342.636348 -250.154186) (xy 342.635853 -250.178793) (xy 342.627958 -250.22737)
			(xy 342.612374 -250.274051) (xy 342.589503 -250.317628) (xy 342.559938 -250.356972) (xy 342.524445 -250.391064)
			(xy 342.483942 -250.41902) (xy 342.43948 -250.440118) (xy 342.392209 -250.45381) (xy 342.343354 -250.459742)
			(xy 342.294179 -250.457761) (xy 342.24596 -250.447917) (xy 342.199944 -250.430465) (xy 342.157323 -250.405858)
			(xy 342.119202 -250.374733) (xy 342.086567 -250.337896) (xy 342.060264 -250.2963) (xy 342.040973 -250.251024)
			(xy 342.029196 -250.20324) (xy 342.025236 -250.154186) (xy 341.696294 -250.154186) (xy 341.695799 -250.178793)
			(xy 341.687904 -250.22737) (xy 341.67232 -250.274051) (xy 341.649449 -250.317628) (xy 341.619884 -250.356972)
			(xy 341.584391 -250.391064) (xy 341.543888 -250.41902) (xy 341.499426 -250.440118) (xy 341.452155 -250.45381)
			(xy 341.4033 -250.459742) (xy 341.354125 -250.457761) (xy 341.305906 -250.447917) (xy 341.25989 -250.430465)
			(xy 341.217269 -250.405858) (xy 341.179148 -250.374733) (xy 341.146513 -250.337896) (xy 341.12021 -250.2963)
			(xy 341.100919 -250.251024) (xy 341.089142 -250.20324) (xy 341.085182 -250.154186) (xy 340.766908 -250.154186)
			(xy 340.766396 -250.179632) (xy 340.758232 -250.229866) (xy 340.742116 -250.27814) (xy 340.718465 -250.323203)
			(xy 340.687892 -250.363889) (xy 340.651188 -250.399144) (xy 340.609304 -250.428054) (xy 340.563325 -250.449871)
			(xy 340.514441 -250.464031) (xy 340.46392 -250.470165) (xy 340.413068 -250.468116) (xy 340.363204 -250.457936)
			(xy 340.315618 -250.439889) (xy 340.271544 -250.414443) (xy 340.232122 -250.382256) (xy 340.198374 -250.344162)
			(xy 340.171173 -250.301148) (xy 340.151225 -250.254328) (xy 340.139046 -250.204914) (xy 340.134951 -250.154186)
			(xy 339.81644 -250.154186) (xy 339.815945 -250.178793) (xy 339.80805 -250.22737) (xy 339.792466 -250.274051)
			(xy 339.769595 -250.317628) (xy 339.74003 -250.356972) (xy 339.704537 -250.391064) (xy 339.664034 -250.41902)
			(xy 339.619572 -250.440118) (xy 339.572301 -250.45381) (xy 339.523446 -250.459742) (xy 339.474271 -250.457761)
			(xy 339.426052 -250.447917) (xy 339.380036 -250.430465) (xy 339.337415 -250.405858) (xy 339.299294 -250.374733)
			(xy 339.266659 -250.337896) (xy 339.240356 -250.2963) (xy 339.221065 -250.251024) (xy 339.209288 -250.20324)
			(xy 339.205328 -250.154186) (xy 338.876386 -250.154186) (xy 338.875891 -250.178793) (xy 338.867996 -250.22737)
			(xy 338.852412 -250.274051) (xy 338.829541 -250.317628) (xy 338.799976 -250.356972) (xy 338.764483 -250.391064)
			(xy 338.72398 -250.41902) (xy 338.679518 -250.440118) (xy 338.632247 -250.45381) (xy 338.583392 -250.459742)
			(xy 338.534217 -250.457761) (xy 338.485998 -250.447917) (xy 338.439982 -250.430465) (xy 338.397361 -250.405858)
			(xy 338.35924 -250.374733) (xy 338.326605 -250.337896) (xy 338.300302 -250.2963) (xy 338.281011 -250.251024)
			(xy 338.269234 -250.20324) (xy 338.265274 -250.154186) (xy 337.936332 -250.154186) (xy 337.935837 -250.178793)
			(xy 337.927942 -250.22737) (xy 337.912358 -250.274051) (xy 337.889487 -250.317628) (xy 337.859922 -250.356972)
			(xy 337.824429 -250.391064) (xy 337.783926 -250.41902) (xy 337.739464 -250.440118) (xy 337.692193 -250.45381)
			(xy 337.643338 -250.459742) (xy 337.594163 -250.457761) (xy 337.545944 -250.447917) (xy 337.499928 -250.430465)
			(xy 337.457307 -250.405858) (xy 337.419186 -250.374733) (xy 337.386551 -250.337896) (xy 337.360248 -250.2963)
			(xy 337.340957 -250.251024) (xy 337.32918 -250.20324) (xy 337.32522 -250.154186) (xy 336.996532 -250.154186)
			(xy 336.996037 -250.178793) (xy 336.988142 -250.22737) (xy 336.972558 -250.274051) (xy 336.949687 -250.317628)
			(xy 336.920122 -250.356972) (xy 336.884629 -250.391064) (xy 336.844126 -250.41902) (xy 336.799664 -250.440118)
			(xy 336.752393 -250.45381) (xy 336.703538 -250.459742) (xy 336.654363 -250.457761) (xy 336.606144 -250.447917)
			(xy 336.560128 -250.430465) (xy 336.517507 -250.405858) (xy 336.479386 -250.374733) (xy 336.446751 -250.337896)
			(xy 336.420448 -250.2963) (xy 336.401157 -250.251024) (xy 336.38938 -250.20324) (xy 336.38542 -250.154186)
			(xy 336.056478 -250.154186) (xy 336.055983 -250.178793) (xy 336.048088 -250.22737) (xy 336.032504 -250.274051)
			(xy 336.009633 -250.317628) (xy 335.980068 -250.356972) (xy 335.944575 -250.391064) (xy 335.904072 -250.41902)
			(xy 335.85961 -250.440118) (xy 335.812339 -250.45381) (xy 335.763484 -250.459742) (xy 335.714309 -250.457761)
			(xy 335.66609 -250.447917) (xy 335.620074 -250.430465) (xy 335.577453 -250.405858) (xy 335.539332 -250.374733)
			(xy 335.506697 -250.337896) (xy 335.480394 -250.2963) (xy 335.461103 -250.251024) (xy 335.449326 -250.20324)
			(xy 335.445366 -250.154186) (xy 335.116424 -250.154186) (xy 335.115929 -250.178793) (xy 335.108034 -250.22737)
			(xy 335.09245 -250.274051) (xy 335.069579 -250.317628) (xy 335.040014 -250.356972) (xy 335.004521 -250.391064)
			(xy 334.964018 -250.41902) (xy 334.919556 -250.440118) (xy 334.872285 -250.45381) (xy 334.82343 -250.459742)
			(xy 334.774255 -250.457761) (xy 334.726036 -250.447917) (xy 334.68002 -250.430465) (xy 334.637399 -250.405858)
			(xy 334.599278 -250.374733) (xy 334.566643 -250.337896) (xy 334.54034 -250.2963) (xy 334.521049 -250.251024)
			(xy 334.509272 -250.20324) (xy 334.505312 -250.154186) (xy 334.17637 -250.154186) (xy 334.175875 -250.178793)
			(xy 334.16798 -250.22737) (xy 334.152396 -250.274051) (xy 334.129525 -250.317628) (xy 334.09996 -250.356972)
			(xy 334.064467 -250.391064) (xy 334.023964 -250.41902) (xy 333.979502 -250.440118) (xy 333.932231 -250.45381)
			(xy 333.883376 -250.459742) (xy 333.834201 -250.457761) (xy 333.785982 -250.447917) (xy 333.739966 -250.430465)
			(xy 333.697345 -250.405858) (xy 333.659224 -250.374733) (xy 333.626589 -250.337896) (xy 333.600286 -250.2963)
			(xy 333.580995 -250.251024) (xy 333.569218 -250.20324) (xy 333.565258 -250.154186) (xy 333.236316 -250.154186)
			(xy 333.235821 -250.178793) (xy 333.227926 -250.22737) (xy 333.212342 -250.274051) (xy 333.189471 -250.317628)
			(xy 333.159906 -250.356972) (xy 333.124413 -250.391064) (xy 333.08391 -250.41902) (xy 333.039448 -250.440118)
			(xy 332.992177 -250.45381) (xy 332.943322 -250.459742) (xy 332.894147 -250.457761) (xy 332.845928 -250.447917)
			(xy 332.799912 -250.430465) (xy 332.757291 -250.405858) (xy 332.71917 -250.374733) (xy 332.686535 -250.337896)
			(xy 332.660232 -250.2963) (xy 332.640941 -250.251024) (xy 332.629164 -250.20324) (xy 332.625204 -250.154186)
			(xy 332.296516 -250.154186) (xy 332.296021 -250.178793) (xy 332.288126 -250.22737) (xy 332.272542 -250.274051)
			(xy 332.249671 -250.317628) (xy 332.220106 -250.356972) (xy 332.184613 -250.391064) (xy 332.14411 -250.41902)
			(xy 332.099648 -250.440118) (xy 332.052377 -250.45381) (xy 332.003522 -250.459742) (xy 331.954347 -250.457761)
			(xy 331.906128 -250.447917) (xy 331.860112 -250.430465) (xy 331.817491 -250.405858) (xy 331.77937 -250.374733)
			(xy 331.746735 -250.337896) (xy 331.720432 -250.2963) (xy 331.701141 -250.251024) (xy 331.689364 -250.20324)
			(xy 331.685404 -250.154186) (xy 331.459332 -250.154186) (xy 331.459332 -250.560332) (xy 331.459798 -250.569693)
			(xy 331.466555 -250.587158) (xy 331.47254 -250.594368) (xy 331.517498 -250.643898) (xy 331.52081 -250.647367)
			(xy 331.528479 -250.653123) (xy 331.532738 -250.655328) (xy 331.540612 -250.659138) (xy 331.550264 -250.660154)
			(xy 331.550518 -250.660154) (xy 331.575388 -250.663065) (xy 331.623772 -250.67595) (xy 331.669406 -250.696553)
			(xy 331.711069 -250.724323) (xy 331.747646 -250.758515) (xy 331.778157 -250.798215) (xy 331.801785 -250.842359)
			(xy 331.817898 -250.889765) (xy 331.826063 -250.939164) (xy 331.826063 -250.964192) (xy 332.155304 -250.964192)
			(xy 332.159264 -250.915138) (xy 332.171041 -250.867354) (xy 332.190332 -250.822078) (xy 332.216635 -250.780482)
			(xy 332.24927 -250.743645) (xy 332.287391 -250.71252) (xy 332.330012 -250.687913) (xy 332.376028 -250.670461)
			(xy 332.424247 -250.660617) (xy 332.473422 -250.658636) (xy 332.522277 -250.664568) (xy 332.569548 -250.67826)
			(xy 332.61401 -250.699358) (xy 332.654513 -250.727314) (xy 332.690006 -250.761406) (xy 332.719571 -250.80075)
			(xy 332.742442 -250.844327) (xy 332.758026 -250.891008) (xy 332.765921 -250.939585) (xy 332.766416 -250.964192)
			(xy 333.095358 -250.964192) (xy 333.099318 -250.915138) (xy 333.111095 -250.867354) (xy 333.130386 -250.822078)
			(xy 333.156689 -250.780482) (xy 333.189324 -250.743645) (xy 333.227445 -250.71252) (xy 333.270066 -250.687913)
			(xy 333.316082 -250.670461) (xy 333.364301 -250.660617) (xy 333.413476 -250.658636) (xy 333.462331 -250.664568)
			(xy 333.509602 -250.67826) (xy 333.554064 -250.699358) (xy 333.594567 -250.727314) (xy 333.63006 -250.761406)
			(xy 333.659625 -250.80075) (xy 333.682496 -250.844327) (xy 333.69808 -250.891008) (xy 333.705975 -250.939585)
			(xy 333.70647 -250.964192) (xy 334.035412 -250.964192) (xy 334.039372 -250.915138) (xy 334.051149 -250.867354)
			(xy 334.07044 -250.822078) (xy 334.096743 -250.780482) (xy 334.129378 -250.743645) (xy 334.167499 -250.71252)
			(xy 334.21012 -250.687913) (xy 334.256136 -250.670461) (xy 334.304355 -250.660617) (xy 334.35353 -250.658636)
			(xy 334.402385 -250.664568) (xy 334.449656 -250.67826) (xy 334.494118 -250.699358) (xy 334.534621 -250.727314)
			(xy 334.570114 -250.761406) (xy 334.599679 -250.80075) (xy 334.62255 -250.844327) (xy 334.638134 -250.891008)
			(xy 334.646029 -250.939585) (xy 334.646524 -250.964192) (xy 334.975212 -250.964192) (xy 334.979172 -250.915138)
			(xy 334.990949 -250.867354) (xy 335.01024 -250.822078) (xy 335.036543 -250.780482) (xy 335.069178 -250.743645)
			(xy 335.107299 -250.71252) (xy 335.14992 -250.687913) (xy 335.195936 -250.670461) (xy 335.244155 -250.660617)
			(xy 335.29333 -250.658636) (xy 335.342185 -250.664568) (xy 335.389456 -250.67826) (xy 335.433918 -250.699358)
			(xy 335.474421 -250.727314) (xy 335.509914 -250.761406) (xy 335.539479 -250.80075) (xy 335.56235 -250.844327)
			(xy 335.577934 -250.891008) (xy 335.585829 -250.939585) (xy 335.586324 -250.964192) (xy 335.915266 -250.964192)
			(xy 335.919226 -250.915138) (xy 335.931003 -250.867354) (xy 335.950294 -250.822078) (xy 335.976597 -250.780482)
			(xy 336.009232 -250.743645) (xy 336.047353 -250.71252) (xy 336.089974 -250.687913) (xy 336.13599 -250.670461)
			(xy 336.184209 -250.660617) (xy 336.233384 -250.658636) (xy 336.282239 -250.664568) (xy 336.32951 -250.67826)
			(xy 336.373972 -250.699358) (xy 336.414475 -250.727314) (xy 336.449968 -250.761406) (xy 336.479533 -250.80075)
			(xy 336.502404 -250.844327) (xy 336.517988 -250.891008) (xy 336.525883 -250.939585) (xy 336.526378 -250.964192)
			(xy 336.85532 -250.964192) (xy 336.85928 -250.915138) (xy 336.871057 -250.867354) (xy 336.890348 -250.822078)
			(xy 336.916651 -250.780482) (xy 336.949286 -250.743645) (xy 336.987407 -250.71252) (xy 337.030028 -250.687913)
			(xy 337.076044 -250.670461) (xy 337.124263 -250.660617) (xy 337.173438 -250.658636) (xy 337.222293 -250.664568)
			(xy 337.269564 -250.67826) (xy 337.314026 -250.699358) (xy 337.354529 -250.727314) (xy 337.390022 -250.761406)
			(xy 337.419587 -250.80075) (xy 337.442458 -250.844327) (xy 337.458042 -250.891008) (xy 337.465937 -250.939585)
			(xy 337.466432 -250.964192) (xy 337.795374 -250.964192) (xy 337.799334 -250.915138) (xy 337.811111 -250.867354)
			(xy 337.830402 -250.822078) (xy 337.856705 -250.780482) (xy 337.88934 -250.743645) (xy 337.927461 -250.71252)
			(xy 337.970082 -250.687913) (xy 338.016098 -250.670461) (xy 338.064317 -250.660617) (xy 338.113492 -250.658636)
			(xy 338.162347 -250.664568) (xy 338.209618 -250.67826) (xy 338.25408 -250.699358) (xy 338.294583 -250.727314)
			(xy 338.330076 -250.761406) (xy 338.359641 -250.80075) (xy 338.382512 -250.844327) (xy 338.398096 -250.891008)
			(xy 338.405991 -250.939585) (xy 338.406486 -250.964192) (xy 338.735428 -250.964192) (xy 338.739388 -250.915138)
			(xy 338.751165 -250.867354) (xy 338.770456 -250.822078) (xy 338.796759 -250.780482) (xy 338.829394 -250.743645)
			(xy 338.867515 -250.71252) (xy 338.910136 -250.687913) (xy 338.956152 -250.670461) (xy 339.004371 -250.660617)
			(xy 339.053546 -250.658636) (xy 339.102401 -250.664568) (xy 339.149672 -250.67826) (xy 339.194134 -250.699358)
			(xy 339.234637 -250.727314) (xy 339.27013 -250.761406) (xy 339.299695 -250.80075) (xy 339.322566 -250.844327)
			(xy 339.33815 -250.891008) (xy 339.346045 -250.939585) (xy 339.34654 -250.964192) (xy 339.664797 -250.964192)
			(xy 339.668892 -250.913464) (xy 339.681071 -250.86405) (xy 339.701019 -250.81723) (xy 339.72822 -250.774216)
			(xy 339.761968 -250.736122) (xy 339.80139 -250.703935) (xy 339.845464 -250.678489) (xy 339.89305 -250.660442)
			(xy 339.942914 -250.650262) (xy 339.993766 -250.648213) (xy 340.044287 -250.654347) (xy 340.093171 -250.668507)
			(xy 340.13915 -250.690324) (xy 340.181034 -250.719234) (xy 340.217738 -250.754489) (xy 340.248311 -250.795175)
			(xy 340.271962 -250.840238) (xy 340.288078 -250.888512) (xy 340.296242 -250.938746) (xy 340.296754 -250.964192)
			(xy 340.615282 -250.964192) (xy 340.619242 -250.915138) (xy 340.631019 -250.867354) (xy 340.65031 -250.822078)
			(xy 340.676613 -250.780482) (xy 340.709248 -250.743645) (xy 340.747369 -250.71252) (xy 340.78999 -250.687913)
			(xy 340.836006 -250.670461) (xy 340.884225 -250.660617) (xy 340.9334 -250.658636) (xy 340.982255 -250.664568)
			(xy 341.029526 -250.67826) (xy 341.073988 -250.699358) (xy 341.114491 -250.727314) (xy 341.149984 -250.761406)
			(xy 341.179549 -250.80075) (xy 341.20242 -250.844327) (xy 341.218004 -250.891008) (xy 341.225899 -250.939585)
			(xy 341.226394 -250.964192) (xy 341.555336 -250.964192) (xy 341.559296 -250.915138) (xy 341.571073 -250.867354)
			(xy 341.590364 -250.822078) (xy 341.616667 -250.780482) (xy 341.649302 -250.743645) (xy 341.687423 -250.71252)
			(xy 341.730044 -250.687913) (xy 341.77606 -250.670461) (xy 341.824279 -250.660617) (xy 341.873454 -250.658636)
			(xy 341.922309 -250.664568) (xy 341.96958 -250.67826) (xy 342.014042 -250.699358) (xy 342.054545 -250.727314)
			(xy 342.090038 -250.761406) (xy 342.119603 -250.80075) (xy 342.142474 -250.844327) (xy 342.158058 -250.891008)
			(xy 342.165953 -250.939585) (xy 342.166448 -250.964192) (xy 342.49539 -250.964192) (xy 342.49935 -250.915138)
			(xy 342.511127 -250.867354) (xy 342.530418 -250.822078) (xy 342.556721 -250.780482) (xy 342.589356 -250.743645)
			(xy 342.627477 -250.71252) (xy 342.670098 -250.687913) (xy 342.716114 -250.670461) (xy 342.764333 -250.660617)
			(xy 342.813508 -250.658636) (xy 342.862363 -250.664568) (xy 342.909634 -250.67826) (xy 342.954096 -250.699358)
			(xy 342.994599 -250.727314) (xy 343.030092 -250.761406) (xy 343.059657 -250.80075) (xy 343.082528 -250.844327)
			(xy 343.098112 -250.891008) (xy 343.106007 -250.939585) (xy 343.106502 -250.964192) (xy 343.106007 -250.988799)
			(xy 343.098112 -251.037376) (xy 343.082528 -251.084057) (xy 343.059657 -251.127634) (xy 343.030092 -251.166978)
			(xy 342.994599 -251.20107) (xy 342.954096 -251.229026) (xy 342.909634 -251.250124) (xy 342.862363 -251.263816)
			(xy 342.813508 -251.269748) (xy 342.764333 -251.267767) (xy 342.716114 -251.257923) (xy 342.670098 -251.240471)
			(xy 342.627477 -251.215864) (xy 342.589356 -251.184739) (xy 342.556721 -251.147902) (xy 342.530418 -251.106306)
			(xy 342.511127 -251.06103) (xy 342.49935 -251.013246) (xy 342.49539 -250.964192) (xy 342.166448 -250.964192)
			(xy 342.165953 -250.988799) (xy 342.158058 -251.037376) (xy 342.142474 -251.084057) (xy 342.119603 -251.127634)
			(xy 342.090038 -251.166978) (xy 342.054545 -251.20107) (xy 342.014042 -251.229026) (xy 341.96958 -251.250124)
			(xy 341.922309 -251.263816) (xy 341.873454 -251.269748) (xy 341.824279 -251.267767) (xy 341.77606 -251.257923)
			(xy 341.730044 -251.240471) (xy 341.687423 -251.215864) (xy 341.649302 -251.184739) (xy 341.616667 -251.147902)
			(xy 341.590364 -251.106306) (xy 341.571073 -251.06103) (xy 341.559296 -251.013246) (xy 341.555336 -250.964192)
			(xy 341.226394 -250.964192) (xy 341.225899 -250.988799) (xy 341.218004 -251.037376) (xy 341.20242 -251.084057)
			(xy 341.179549 -251.127634) (xy 341.149984 -251.166978) (xy 341.114491 -251.20107) (xy 341.073988 -251.229026)
			(xy 341.029526 -251.250124) (xy 340.982255 -251.263816) (xy 340.9334 -251.269748) (xy 340.884225 -251.267767)
			(xy 340.836006 -251.257923) (xy 340.78999 -251.240471) (xy 340.747369 -251.215864) (xy 340.709248 -251.184739)
			(xy 340.676613 -251.147902) (xy 340.65031 -251.106306) (xy 340.631019 -251.06103) (xy 340.619242 -251.013246)
			(xy 340.615282 -250.964192) (xy 340.296754 -250.964192) (xy 340.296242 -250.989638) (xy 340.288078 -251.039872)
			(xy 340.271962 -251.088146) (xy 340.248311 -251.133209) (xy 340.217738 -251.173895) (xy 340.181034 -251.20915)
			(xy 340.13915 -251.23806) (xy 340.093171 -251.259877) (xy 340.044287 -251.274037) (xy 339.993766 -251.280171)
			(xy 339.942914 -251.278122) (xy 339.89305 -251.267942) (xy 339.845464 -251.249895) (xy 339.80139 -251.224449)
			(xy 339.761968 -251.192262) (xy 339.72822 -251.154168) (xy 339.701019 -251.111154) (xy 339.681071 -251.064334)
			(xy 339.668892 -251.01492) (xy 339.664797 -250.964192) (xy 339.34654 -250.964192) (xy 339.346045 -250.988799)
			(xy 339.33815 -251.037376) (xy 339.322566 -251.084057) (xy 339.299695 -251.127634) (xy 339.27013 -251.166978)
			(xy 339.234637 -251.20107) (xy 339.194134 -251.229026) (xy 339.149672 -251.250124) (xy 339.102401 -251.263816)
			(xy 339.053546 -251.269748) (xy 339.004371 -251.267767) (xy 338.956152 -251.257923) (xy 338.910136 -251.240471)
			(xy 338.867515 -251.215864) (xy 338.829394 -251.184739) (xy 338.796759 -251.147902) (xy 338.770456 -251.106306)
			(xy 338.751165 -251.06103) (xy 338.739388 -251.013246) (xy 338.735428 -250.964192) (xy 338.406486 -250.964192)
			(xy 338.405991 -250.988799) (xy 338.398096 -251.037376) (xy 338.382512 -251.084057) (xy 338.359641 -251.127634)
			(xy 338.330076 -251.166978) (xy 338.294583 -251.20107) (xy 338.25408 -251.229026) (xy 338.209618 -251.250124)
			(xy 338.162347 -251.263816) (xy 338.113492 -251.269748) (xy 338.064317 -251.267767) (xy 338.016098 -251.257923)
			(xy 337.970082 -251.240471) (xy 337.927461 -251.215864) (xy 337.88934 -251.184739) (xy 337.856705 -251.147902)
			(xy 337.830402 -251.106306) (xy 337.811111 -251.06103) (xy 337.799334 -251.013246) (xy 337.795374 -250.964192)
			(xy 337.466432 -250.964192) (xy 337.465937 -250.988799) (xy 337.458042 -251.037376) (xy 337.442458 -251.084057)
			(xy 337.419587 -251.127634) (xy 337.390022 -251.166978) (xy 337.354529 -251.20107) (xy 337.314026 -251.229026)
			(xy 337.269564 -251.250124) (xy 337.222293 -251.263816) (xy 337.173438 -251.269748) (xy 337.124263 -251.267767)
			(xy 337.076044 -251.257923) (xy 337.030028 -251.240471) (xy 336.987407 -251.215864) (xy 336.949286 -251.184739)
			(xy 336.916651 -251.147902) (xy 336.890348 -251.106306) (xy 336.871057 -251.06103) (xy 336.85928 -251.013246)
			(xy 336.85532 -250.964192) (xy 336.526378 -250.964192) (xy 336.525883 -250.988799) (xy 336.517988 -251.037376)
			(xy 336.502404 -251.084057) (xy 336.479533 -251.127634) (xy 336.449968 -251.166978) (xy 336.414475 -251.20107)
			(xy 336.373972 -251.229026) (xy 336.32951 -251.250124) (xy 336.282239 -251.263816) (xy 336.233384 -251.269748)
			(xy 336.184209 -251.267767) (xy 336.13599 -251.257923) (xy 336.089974 -251.240471) (xy 336.047353 -251.215864)
			(xy 336.009232 -251.184739) (xy 335.976597 -251.147902) (xy 335.950294 -251.106306) (xy 335.931003 -251.06103)
			(xy 335.919226 -251.013246) (xy 335.915266 -250.964192) (xy 335.586324 -250.964192) (xy 335.585829 -250.988799)
			(xy 335.577934 -251.037376) (xy 335.56235 -251.084057) (xy 335.539479 -251.127634) (xy 335.509914 -251.166978)
			(xy 335.474421 -251.20107) (xy 335.433918 -251.229026) (xy 335.389456 -251.250124) (xy 335.342185 -251.263816)
			(xy 335.29333 -251.269748) (xy 335.244155 -251.267767) (xy 335.195936 -251.257923) (xy 335.14992 -251.240471)
			(xy 335.107299 -251.215864) (xy 335.069178 -251.184739) (xy 335.036543 -251.147902) (xy 335.01024 -251.106306)
			(xy 334.990949 -251.06103) (xy 334.979172 -251.013246) (xy 334.975212 -250.964192) (xy 334.646524 -250.964192)
			(xy 334.646029 -250.988799) (xy 334.638134 -251.037376) (xy 334.62255 -251.084057) (xy 334.599679 -251.127634)
			(xy 334.570114 -251.166978) (xy 334.534621 -251.20107) (xy 334.494118 -251.229026) (xy 334.449656 -251.250124)
			(xy 334.402385 -251.263816) (xy 334.35353 -251.269748) (xy 334.304355 -251.267767) (xy 334.256136 -251.257923)
			(xy 334.21012 -251.240471) (xy 334.167499 -251.215864) (xy 334.129378 -251.184739) (xy 334.096743 -251.147902)
			(xy 334.07044 -251.106306) (xy 334.051149 -251.06103) (xy 334.039372 -251.013246) (xy 334.035412 -250.964192)
			(xy 333.70647 -250.964192) (xy 333.705975 -250.988799) (xy 333.69808 -251.037376) (xy 333.682496 -251.084057)
			(xy 333.659625 -251.127634) (xy 333.63006 -251.166978) (xy 333.594567 -251.20107) (xy 333.554064 -251.229026)
			(xy 333.509602 -251.250124) (xy 333.462331 -251.263816) (xy 333.413476 -251.269748) (xy 333.364301 -251.267767)
			(xy 333.316082 -251.257923) (xy 333.270066 -251.240471) (xy 333.227445 -251.215864) (xy 333.189324 -251.184739)
			(xy 333.156689 -251.147902) (xy 333.130386 -251.106306) (xy 333.111095 -251.06103) (xy 333.099318 -251.013246)
			(xy 333.095358 -250.964192) (xy 332.766416 -250.964192) (xy 332.765921 -250.988799) (xy 332.758026 -251.037376)
			(xy 332.742442 -251.084057) (xy 332.719571 -251.127634) (xy 332.690006 -251.166978) (xy 332.654513 -251.20107)
			(xy 332.61401 -251.229026) (xy 332.569548 -251.250124) (xy 332.522277 -251.263816) (xy 332.473422 -251.269748)
			(xy 332.424247 -251.267767) (xy 332.376028 -251.257923) (xy 332.330012 -251.240471) (xy 332.287391 -251.215864)
			(xy 332.24927 -251.184739) (xy 332.216635 -251.147902) (xy 332.190332 -251.106306) (xy 332.171041 -251.06103)
			(xy 332.159264 -251.013246) (xy 332.155304 -250.964192) (xy 331.826063 -250.964192) (xy 331.826064 -250.989234)
			(xy 331.817898 -251.038634) (xy 331.801786 -251.08604) (xy 331.778158 -251.130184) (xy 331.747647 -251.169884)
			(xy 331.71107 -251.204076) (xy 331.669407 -251.231846) (xy 331.623773 -251.252449) (xy 331.57539 -251.265335)
			(xy 331.550518 -251.26823) (xy 331.550264 -251.26823) (xy 331.540612 -251.269246) (xy 331.532738 -251.273056)
			(xy 331.528477 -251.275259) (xy 331.520804 -251.281011) (xy 331.517498 -251.284486) (xy 331.47254 -251.334016)
			(xy 331.466482 -251.341187) (xy 331.459689 -251.358672) (xy 331.459332 -251.368052) (xy 331.459332 -251.774198)
			(xy 331.685404 -251.774198) (xy 331.689364 -251.725144) (xy 331.701141 -251.67736) (xy 331.720432 -251.632084)
			(xy 331.746735 -251.590488) (xy 331.77937 -251.553651) (xy 331.817491 -251.522526) (xy 331.860112 -251.497919)
			(xy 331.906128 -251.480467) (xy 331.954347 -251.470623) (xy 332.003522 -251.468642) (xy 332.052377 -251.474574)
			(xy 332.099648 -251.488266) (xy 332.14411 -251.509364) (xy 332.184613 -251.53732) (xy 332.220106 -251.571412)
			(xy 332.249671 -251.610756) (xy 332.272542 -251.654333) (xy 332.288126 -251.701014) (xy 332.296021 -251.749591)
			(xy 332.296516 -251.774198) (xy 332.625204 -251.774198) (xy 332.629164 -251.725144) (xy 332.640941 -251.67736)
			(xy 332.660232 -251.632084) (xy 332.686535 -251.590488) (xy 332.71917 -251.553651) (xy 332.757291 -251.522526)
			(xy 332.799912 -251.497919) (xy 332.845928 -251.480467) (xy 332.894147 -251.470623) (xy 332.943322 -251.468642)
			(xy 332.992177 -251.474574) (xy 333.039448 -251.488266) (xy 333.08391 -251.509364) (xy 333.124413 -251.53732)
			(xy 333.159906 -251.571412) (xy 333.189471 -251.610756) (xy 333.212342 -251.654333) (xy 333.227926 -251.701014)
			(xy 333.235821 -251.749591) (xy 333.236316 -251.774198) (xy 333.565258 -251.774198) (xy 333.569218 -251.725144)
			(xy 333.580995 -251.67736) (xy 333.600286 -251.632084) (xy 333.626589 -251.590488) (xy 333.659224 -251.553651)
			(xy 333.697345 -251.522526) (xy 333.739966 -251.497919) (xy 333.785982 -251.480467) (xy 333.834201 -251.470623)
			(xy 333.883376 -251.468642) (xy 333.932231 -251.474574) (xy 333.979502 -251.488266) (xy 334.023964 -251.509364)
			(xy 334.064467 -251.53732) (xy 334.09996 -251.571412) (xy 334.129525 -251.610756) (xy 334.152396 -251.654333)
			(xy 334.16798 -251.701014) (xy 334.175875 -251.749591) (xy 334.17637 -251.774198) (xy 335.445366 -251.774198)
			(xy 335.449326 -251.725144) (xy 335.461103 -251.67736) (xy 335.480394 -251.632084) (xy 335.506697 -251.590488)
			(xy 335.539332 -251.553651) (xy 335.577453 -251.522526) (xy 335.620074 -251.497919) (xy 335.66609 -251.480467)
			(xy 335.714309 -251.470623) (xy 335.763484 -251.468642) (xy 335.812339 -251.474574) (xy 335.85961 -251.488266)
			(xy 335.904072 -251.509364) (xy 335.944575 -251.53732) (xy 335.980068 -251.571412) (xy 336.009633 -251.610756)
			(xy 336.032504 -251.654333) (xy 336.048088 -251.701014) (xy 336.055983 -251.749591) (xy 336.056478 -251.774198)
			(xy 336.38542 -251.774198) (xy 336.38938 -251.725144) (xy 336.401157 -251.67736) (xy 336.420448 -251.632084)
			(xy 336.446751 -251.590488) (xy 336.479386 -251.553651) (xy 336.517507 -251.522526) (xy 336.560128 -251.497919)
			(xy 336.606144 -251.480467) (xy 336.654363 -251.470623) (xy 336.703538 -251.468642) (xy 336.752393 -251.474574)
			(xy 336.799664 -251.488266) (xy 336.844126 -251.509364) (xy 336.884629 -251.53732) (xy 336.920122 -251.571412)
			(xy 336.949687 -251.610756) (xy 336.972558 -251.654333) (xy 336.988142 -251.701014) (xy 336.996037 -251.749591)
			(xy 336.996532 -251.774198) (xy 337.32522 -251.774198) (xy 337.32918 -251.725144) (xy 337.340957 -251.67736)
			(xy 337.360248 -251.632084) (xy 337.386551 -251.590488) (xy 337.419186 -251.553651) (xy 337.457307 -251.522526)
			(xy 337.499928 -251.497919) (xy 337.545944 -251.480467) (xy 337.594163 -251.470623) (xy 337.643338 -251.468642)
			(xy 337.692193 -251.474574) (xy 337.739464 -251.488266) (xy 337.783926 -251.509364) (xy 337.824429 -251.53732)
			(xy 337.859922 -251.571412) (xy 337.889487 -251.610756) (xy 337.912358 -251.654333) (xy 337.927942 -251.701014)
			(xy 337.935837 -251.749591) (xy 337.936332 -251.774198) (xy 338.254843 -251.774198) (xy 338.258938 -251.72347)
			(xy 338.271117 -251.674056) (xy 338.291065 -251.627236) (xy 338.318266 -251.584222) (xy 338.352014 -251.546128)
			(xy 338.391436 -251.513941) (xy 338.43551 -251.488495) (xy 338.483096 -251.470448) (xy 338.53296 -251.460268)
			(xy 338.583812 -251.458219) (xy 338.634333 -251.464353) (xy 338.683217 -251.478513) (xy 338.729196 -251.50033)
			(xy 338.77108 -251.52924) (xy 338.807784 -251.564495) (xy 338.838357 -251.605181) (xy 338.862008 -251.650244)
			(xy 338.878124 -251.698518) (xy 338.886288 -251.748752) (xy 338.8868 -251.774198) (xy 339.205328 -251.774198)
			(xy 339.209288 -251.725144) (xy 339.221065 -251.67736) (xy 339.240356 -251.632084) (xy 339.266659 -251.590488)
			(xy 339.299294 -251.553651) (xy 339.337415 -251.522526) (xy 339.380036 -251.497919) (xy 339.426052 -251.480467)
			(xy 339.474271 -251.470623) (xy 339.523446 -251.468642) (xy 339.572301 -251.474574) (xy 339.619572 -251.488266)
			(xy 339.664034 -251.509364) (xy 339.704537 -251.53732) (xy 339.74003 -251.571412) (xy 339.769595 -251.610756)
			(xy 339.792466 -251.654333) (xy 339.80805 -251.701014) (xy 339.815945 -251.749591) (xy 339.81644 -251.774198)
			(xy 340.145382 -251.774198) (xy 340.149342 -251.725144) (xy 340.161119 -251.67736) (xy 340.18041 -251.632084)
			(xy 340.206713 -251.590488) (xy 340.239348 -251.553651) (xy 340.277469 -251.522526) (xy 340.32009 -251.497919)
			(xy 340.366106 -251.480467) (xy 340.414325 -251.470623) (xy 340.4635 -251.468642) (xy 340.512355 -251.474574)
			(xy 340.559626 -251.488266) (xy 340.604088 -251.509364) (xy 340.644591 -251.53732) (xy 340.680084 -251.571412)
			(xy 340.709649 -251.610756) (xy 340.73252 -251.654333) (xy 340.748104 -251.701014) (xy 340.755999 -251.749591)
			(xy 340.756494 -251.774198) (xy 342.014805 -251.774198) (xy 342.0189 -251.72347) (xy 342.031079 -251.674056)
			(xy 342.051027 -251.627236) (xy 342.078228 -251.584222) (xy 342.111976 -251.546128) (xy 342.151398 -251.513941)
			(xy 342.195472 -251.488495) (xy 342.243058 -251.470448) (xy 342.292922 -251.460268) (xy 342.343774 -251.458219)
			(xy 342.394295 -251.464353) (xy 342.443179 -251.478513) (xy 342.489158 -251.50033) (xy 342.531042 -251.52924)
			(xy 342.567746 -251.564495) (xy 342.598319 -251.605181) (xy 342.62197 -251.650244) (xy 342.638086 -251.698518)
			(xy 342.64625 -251.748752) (xy 342.646762 -251.774198) (xy 342.96529 -251.774198) (xy 342.96925 -251.725144)
			(xy 342.981027 -251.67736) (xy 343.000318 -251.632084) (xy 343.026621 -251.590488) (xy 343.059256 -251.553651)
			(xy 343.097377 -251.522526) (xy 343.139998 -251.497919) (xy 343.186014 -251.480467) (xy 343.234233 -251.470623)
			(xy 343.283408 -251.468642) (xy 343.332263 -251.474574) (xy 343.379534 -251.488266) (xy 343.423996 -251.509364)
			(xy 343.464499 -251.53732) (xy 343.499992 -251.571412) (xy 343.529557 -251.610756) (xy 343.552428 -251.654333)
			(xy 343.568012 -251.701014) (xy 343.575907 -251.749591) (xy 343.576402 -251.774198) (xy 343.575907 -251.798805)
			(xy 343.568012 -251.847382) (xy 343.552428 -251.894063) (xy 343.529557 -251.93764) (xy 343.499992 -251.976984)
			(xy 343.464499 -252.011076) (xy 343.423996 -252.039032) (xy 343.379534 -252.06013) (xy 343.332263 -252.073822)
			(xy 343.283408 -252.079754) (xy 343.234233 -252.077773) (xy 343.186014 -252.067929) (xy 343.139998 -252.050477)
			(xy 343.097377 -252.02587) (xy 343.059256 -251.994745) (xy 343.026621 -251.957908) (xy 343.000318 -251.916312)
			(xy 342.981027 -251.871036) (xy 342.96925 -251.823252) (xy 342.96529 -251.774198) (xy 342.646762 -251.774198)
			(xy 342.64625 -251.799644) (xy 342.638086 -251.849878) (xy 342.62197 -251.898152) (xy 342.598319 -251.943215)
			(xy 342.567746 -251.983901) (xy 342.531042 -252.019156) (xy 342.489158 -252.048066) (xy 342.443179 -252.069883)
			(xy 342.394295 -252.084043) (xy 342.343774 -252.090177) (xy 342.292922 -252.088128) (xy 342.243058 -252.077948)
			(xy 342.195472 -252.059901) (xy 342.151398 -252.034455) (xy 342.111976 -252.002268) (xy 342.078228 -251.964174)
			(xy 342.051027 -251.92116) (xy 342.031079 -251.87434) (xy 342.0189 -251.824926) (xy 342.014805 -251.774198)
			(xy 340.756494 -251.774198) (xy 340.755999 -251.798805) (xy 340.748104 -251.847382) (xy 340.73252 -251.894063)
			(xy 340.709649 -251.93764) (xy 340.680084 -251.976984) (xy 340.644591 -252.011076) (xy 340.604088 -252.039032)
			(xy 340.559626 -252.06013) (xy 340.512355 -252.073822) (xy 340.4635 -252.079754) (xy 340.414325 -252.077773)
			(xy 340.366106 -252.067929) (xy 340.32009 -252.050477) (xy 340.277469 -252.02587) (xy 340.239348 -251.994745)
			(xy 340.206713 -251.957908) (xy 340.18041 -251.916312) (xy 340.161119 -251.871036) (xy 340.149342 -251.823252)
			(xy 340.145382 -251.774198) (xy 339.81644 -251.774198) (xy 339.815945 -251.798805) (xy 339.80805 -251.847382)
			(xy 339.792466 -251.894063) (xy 339.769595 -251.93764) (xy 339.74003 -251.976984) (xy 339.704537 -252.011076)
			(xy 339.664034 -252.039032) (xy 339.619572 -252.06013) (xy 339.572301 -252.073822) (xy 339.523446 -252.079754)
			(xy 339.474271 -252.077773) (xy 339.426052 -252.067929) (xy 339.380036 -252.050477) (xy 339.337415 -252.02587)
			(xy 339.299294 -251.994745) (xy 339.266659 -251.957908) (xy 339.240356 -251.916312) (xy 339.221065 -251.871036)
			(xy 339.209288 -251.823252) (xy 339.205328 -251.774198) (xy 338.8868 -251.774198) (xy 338.886288 -251.799644)
			(xy 338.878124 -251.849878) (xy 338.862008 -251.898152) (xy 338.838357 -251.943215) (xy 338.807784 -251.983901)
			(xy 338.77108 -252.019156) (xy 338.729196 -252.048066) (xy 338.683217 -252.069883) (xy 338.634333 -252.084043)
			(xy 338.583812 -252.090177) (xy 338.53296 -252.088128) (xy 338.483096 -252.077948) (xy 338.43551 -252.059901)
			(xy 338.391436 -252.034455) (xy 338.352014 -252.002268) (xy 338.318266 -251.964174) (xy 338.291065 -251.92116)
			(xy 338.271117 -251.87434) (xy 338.258938 -251.824926) (xy 338.254843 -251.774198) (xy 337.936332 -251.774198)
			(xy 337.935837 -251.798805) (xy 337.927942 -251.847382) (xy 337.912358 -251.894063) (xy 337.889487 -251.93764)
			(xy 337.859922 -251.976984) (xy 337.824429 -252.011076) (xy 337.783926 -252.039032) (xy 337.739464 -252.06013)
			(xy 337.692193 -252.073822) (xy 337.643338 -252.079754) (xy 337.594163 -252.077773) (xy 337.545944 -252.067929)
			(xy 337.499928 -252.050477) (xy 337.457307 -252.02587) (xy 337.419186 -251.994745) (xy 337.386551 -251.957908)
			(xy 337.360248 -251.916312) (xy 337.340957 -251.871036) (xy 337.32918 -251.823252) (xy 337.32522 -251.774198)
			(xy 336.996532 -251.774198) (xy 336.996037 -251.798805) (xy 336.988142 -251.847382) (xy 336.972558 -251.894063)
			(xy 336.949687 -251.93764) (xy 336.920122 -251.976984) (xy 336.884629 -252.011076) (xy 336.844126 -252.039032)
			(xy 336.799664 -252.06013) (xy 336.752393 -252.073822) (xy 336.703538 -252.079754) (xy 336.654363 -252.077773)
			(xy 336.606144 -252.067929) (xy 336.560128 -252.050477) (xy 336.517507 -252.02587) (xy 336.479386 -251.994745)
			(xy 336.446751 -251.957908) (xy 336.420448 -251.916312) (xy 336.401157 -251.871036) (xy 336.38938 -251.823252)
			(xy 336.38542 -251.774198) (xy 336.056478 -251.774198) (xy 336.055983 -251.798805) (xy 336.048088 -251.847382)
			(xy 336.032504 -251.894063) (xy 336.009633 -251.93764) (xy 335.980068 -251.976984) (xy 335.944575 -252.011076)
			(xy 335.904072 -252.039032) (xy 335.85961 -252.06013) (xy 335.812339 -252.073822) (xy 335.763484 -252.079754)
			(xy 335.714309 -252.077773) (xy 335.66609 -252.067929) (xy 335.620074 -252.050477) (xy 335.577453 -252.02587)
			(xy 335.539332 -251.994745) (xy 335.506697 -251.957908) (xy 335.480394 -251.916312) (xy 335.461103 -251.871036)
			(xy 335.449326 -251.823252) (xy 335.445366 -251.774198) (xy 334.17637 -251.774198) (xy 334.175875 -251.798805)
			(xy 334.16798 -251.847382) (xy 334.152396 -251.894063) (xy 334.129525 -251.93764) (xy 334.09996 -251.976984)
			(xy 334.064467 -252.011076) (xy 334.023964 -252.039032) (xy 333.979502 -252.06013) (xy 333.932231 -252.073822)
			(xy 333.883376 -252.079754) (xy 333.834201 -252.077773) (xy 333.785982 -252.067929) (xy 333.739966 -252.050477)
			(xy 333.697345 -252.02587) (xy 333.659224 -251.994745) (xy 333.626589 -251.957908) (xy 333.600286 -251.916312)
			(xy 333.580995 -251.871036) (xy 333.569218 -251.823252) (xy 333.565258 -251.774198) (xy 333.236316 -251.774198)
			(xy 333.235821 -251.798805) (xy 333.227926 -251.847382) (xy 333.212342 -251.894063) (xy 333.189471 -251.93764)
			(xy 333.159906 -251.976984) (xy 333.124413 -252.011076) (xy 333.08391 -252.039032) (xy 333.039448 -252.06013)
			(xy 332.992177 -252.073822) (xy 332.943322 -252.079754) (xy 332.894147 -252.077773) (xy 332.845928 -252.067929)
			(xy 332.799912 -252.050477) (xy 332.757291 -252.02587) (xy 332.71917 -251.994745) (xy 332.686535 -251.957908)
			(xy 332.660232 -251.916312) (xy 332.640941 -251.871036) (xy 332.629164 -251.823252) (xy 332.625204 -251.774198)
			(xy 332.296516 -251.774198) (xy 332.296021 -251.798805) (xy 332.288126 -251.847382) (xy 332.272542 -251.894063)
			(xy 332.249671 -251.93764) (xy 332.220106 -251.976984) (xy 332.184613 -252.011076) (xy 332.14411 -252.039032)
			(xy 332.099648 -252.06013) (xy 332.052377 -252.073822) (xy 332.003522 -252.079754) (xy 331.954347 -252.077773)
			(xy 331.906128 -252.067929) (xy 331.860112 -252.050477) (xy 331.817491 -252.02587) (xy 331.77937 -251.994745)
			(xy 331.746735 -251.957908) (xy 331.720432 -251.916312) (xy 331.701141 -251.871036) (xy 331.689364 -251.823252)
			(xy 331.685404 -251.774198) (xy 331.459332 -251.774198) (xy 331.459332 -252.180344) (xy 331.4598 -252.189704)
			(xy 331.46656 -252.207166) (xy 331.47254 -252.21438) (xy 331.517498 -252.26391) (xy 331.52081 -252.267378)
			(xy 331.52848 -252.273133) (xy 331.532738 -252.27534) (xy 331.540612 -252.27915) (xy 331.550264 -252.280166)
			(xy 331.550518 -252.280166) (xy 331.575387 -252.283077) (xy 331.623769 -252.295962) (xy 331.669401 -252.316564)
			(xy 331.711063 -252.344333) (xy 331.747638 -252.378524) (xy 331.778148 -252.418222) (xy 331.801775 -252.462364)
			(xy 331.817886 -252.509769) (xy 331.826052 -252.559166) (xy 331.826052 -252.584204) (xy 332.155304 -252.584204)
			(xy 332.159264 -252.53515) (xy 332.171041 -252.487366) (xy 332.190332 -252.44209) (xy 332.216635 -252.400494)
			(xy 332.24927 -252.363657) (xy 332.287391 -252.332532) (xy 332.330012 -252.307925) (xy 332.376028 -252.290473)
			(xy 332.424247 -252.280629) (xy 332.473422 -252.278648) (xy 332.522277 -252.28458) (xy 332.569548 -252.298272)
			(xy 332.61401 -252.31937) (xy 332.654513 -252.347326) (xy 332.690006 -252.381418) (xy 332.719571 -252.420762)
			(xy 332.742442 -252.464339) (xy 332.758026 -252.51102) (xy 332.765921 -252.559597) (xy 332.766416 -252.584204)
			(xy 333.095358 -252.584204) (xy 333.099318 -252.53515) (xy 333.111095 -252.487366) (xy 333.130386 -252.44209)
			(xy 333.156689 -252.400494) (xy 333.189324 -252.363657) (xy 333.227445 -252.332532) (xy 333.270066 -252.307925)
			(xy 333.316082 -252.290473) (xy 333.364301 -252.280629) (xy 333.413476 -252.278648) (xy 333.462331 -252.28458)
			(xy 333.509602 -252.298272) (xy 333.554064 -252.31937) (xy 333.594567 -252.347326) (xy 333.63006 -252.381418)
			(xy 333.659625 -252.420762) (xy 333.682496 -252.464339) (xy 333.69808 -252.51102) (xy 333.705975 -252.559597)
			(xy 333.70647 -252.584204) (xy 334.035412 -252.584204) (xy 334.039372 -252.53515) (xy 334.051149 -252.487366)
			(xy 334.07044 -252.44209) (xy 334.096743 -252.400494) (xy 334.129378 -252.363657) (xy 334.167499 -252.332532)
			(xy 334.21012 -252.307925) (xy 334.256136 -252.290473) (xy 334.304355 -252.280629) (xy 334.35353 -252.278648)
			(xy 334.402385 -252.28458) (xy 334.449656 -252.298272) (xy 334.494118 -252.31937) (xy 334.534621 -252.347326)
			(xy 334.570114 -252.381418) (xy 334.599679 -252.420762) (xy 334.62255 -252.464339) (xy 334.638134 -252.51102)
			(xy 334.646029 -252.559597) (xy 334.646524 -252.584204) (xy 334.975212 -252.584204) (xy 334.979172 -252.53515)
			(xy 334.990949 -252.487366) (xy 335.01024 -252.44209) (xy 335.036543 -252.400494) (xy 335.069178 -252.363657)
			(xy 335.107299 -252.332532) (xy 335.14992 -252.307925) (xy 335.195936 -252.290473) (xy 335.244155 -252.280629)
			(xy 335.29333 -252.278648) (xy 335.342185 -252.28458) (xy 335.389456 -252.298272) (xy 335.433918 -252.31937)
			(xy 335.474421 -252.347326) (xy 335.509914 -252.381418) (xy 335.539479 -252.420762) (xy 335.56235 -252.464339)
			(xy 335.577934 -252.51102) (xy 335.585829 -252.559597) (xy 335.586324 -252.584204) (xy 335.915266 -252.584204)
			(xy 335.919226 -252.53515) (xy 335.931003 -252.487366) (xy 335.950294 -252.44209) (xy 335.976597 -252.400494)
			(xy 336.009232 -252.363657) (xy 336.047353 -252.332532) (xy 336.089974 -252.307925) (xy 336.13599 -252.290473)
			(xy 336.184209 -252.280629) (xy 336.233384 -252.278648) (xy 336.282239 -252.28458) (xy 336.32951 -252.298272)
			(xy 336.373972 -252.31937) (xy 336.414475 -252.347326) (xy 336.449968 -252.381418) (xy 336.479533 -252.420762)
			(xy 336.502404 -252.464339) (xy 336.517988 -252.51102) (xy 336.525883 -252.559597) (xy 336.526378 -252.584204)
			(xy 336.85532 -252.584204) (xy 336.85928 -252.53515) (xy 336.871057 -252.487366) (xy 336.890348 -252.44209)
			(xy 336.916651 -252.400494) (xy 336.949286 -252.363657) (xy 336.987407 -252.332532) (xy 337.030028 -252.307925)
			(xy 337.076044 -252.290473) (xy 337.124263 -252.280629) (xy 337.173438 -252.278648) (xy 337.222293 -252.28458)
			(xy 337.269564 -252.298272) (xy 337.314026 -252.31937) (xy 337.354529 -252.347326) (xy 337.390022 -252.381418)
			(xy 337.419587 -252.420762) (xy 337.442458 -252.464339) (xy 337.458042 -252.51102) (xy 337.465937 -252.559597)
			(xy 337.466432 -252.584204) (xy 337.795374 -252.584204) (xy 337.799334 -252.53515) (xy 337.811111 -252.487366)
			(xy 337.830402 -252.44209) (xy 337.856705 -252.400494) (xy 337.88934 -252.363657) (xy 337.927461 -252.332532)
			(xy 337.970082 -252.307925) (xy 338.016098 -252.290473) (xy 338.064317 -252.280629) (xy 338.113492 -252.278648)
			(xy 338.162347 -252.28458) (xy 338.209618 -252.298272) (xy 338.25408 -252.31937) (xy 338.294583 -252.347326)
			(xy 338.330076 -252.381418) (xy 338.359641 -252.420762) (xy 338.382512 -252.464339) (xy 338.398096 -252.51102)
			(xy 338.405991 -252.559597) (xy 338.406486 -252.584204) (xy 338.724743 -252.584204) (xy 338.728838 -252.533476)
			(xy 338.741017 -252.484062) (xy 338.760965 -252.437242) (xy 338.788166 -252.394228) (xy 338.821914 -252.356134)
			(xy 338.861336 -252.323947) (xy 338.90541 -252.298501) (xy 338.952996 -252.280454) (xy 339.00286 -252.270274)
			(xy 339.053712 -252.268225) (xy 339.104233 -252.274359) (xy 339.153117 -252.288519) (xy 339.199096 -252.310336)
			(xy 339.24098 -252.339246) (xy 339.277684 -252.374501) (xy 339.308257 -252.415187) (xy 339.331908 -252.46025)
			(xy 339.348024 -252.508524) (xy 339.356188 -252.558758) (xy 339.3567 -252.584204) (xy 339.664797 -252.584204)
			(xy 339.668892 -252.533476) (xy 339.681071 -252.484062) (xy 339.701019 -252.437242) (xy 339.72822 -252.394228)
			(xy 339.761968 -252.356134) (xy 339.80139 -252.323947) (xy 339.845464 -252.298501) (xy 339.89305 -252.280454)
			(xy 339.942914 -252.270274) (xy 339.993766 -252.268225) (xy 340.044287 -252.274359) (xy 340.093171 -252.288519)
			(xy 340.13915 -252.310336) (xy 340.181034 -252.339246) (xy 340.217738 -252.374501) (xy 340.248311 -252.415187)
			(xy 340.271962 -252.46025) (xy 340.288078 -252.508524) (xy 340.296242 -252.558758) (xy 340.296754 -252.584204)
			(xy 340.615282 -252.584204) (xy 340.619242 -252.53515) (xy 340.631019 -252.487366) (xy 340.65031 -252.44209)
			(xy 340.676613 -252.400494) (xy 340.709248 -252.363657) (xy 340.747369 -252.332532) (xy 340.78999 -252.307925)
			(xy 340.836006 -252.290473) (xy 340.884225 -252.280629) (xy 340.9334 -252.278648) (xy 340.982255 -252.28458)
			(xy 341.029526 -252.298272) (xy 341.073988 -252.31937) (xy 341.114491 -252.347326) (xy 341.149984 -252.381418)
			(xy 341.179549 -252.420762) (xy 341.20242 -252.464339) (xy 341.218004 -252.51102) (xy 341.225899 -252.559597)
			(xy 341.226394 -252.584204) (xy 341.544905 -252.584204) (xy 341.549 -252.533476) (xy 341.561179 -252.484062)
			(xy 341.581127 -252.437242) (xy 341.608328 -252.394228) (xy 341.642076 -252.356134) (xy 341.681498 -252.323947)
			(xy 341.725572 -252.298501) (xy 341.773158 -252.280454) (xy 341.823022 -252.270274) (xy 341.873874 -252.268225)
			(xy 341.924395 -252.274359) (xy 341.973279 -252.288519) (xy 342.019258 -252.310336) (xy 342.061142 -252.339246)
			(xy 342.097846 -252.374501) (xy 342.128419 -252.415187) (xy 342.15207 -252.46025) (xy 342.168186 -252.508524)
			(xy 342.17635 -252.558758) (xy 342.176862 -252.584204) (xy 342.49539 -252.584204) (xy 342.49935 -252.53515)
			(xy 342.511127 -252.487366) (xy 342.530418 -252.44209) (xy 342.556721 -252.400494) (xy 342.589356 -252.363657)
			(xy 342.627477 -252.332532) (xy 342.670098 -252.307925) (xy 342.716114 -252.290473) (xy 342.764333 -252.280629)
			(xy 342.813508 -252.278648) (xy 342.862363 -252.28458) (xy 342.909634 -252.298272) (xy 342.954096 -252.31937)
			(xy 342.994599 -252.347326) (xy 343.030092 -252.381418) (xy 343.059657 -252.420762) (xy 343.082528 -252.464339)
			(xy 343.098112 -252.51102) (xy 343.106007 -252.559597) (xy 343.106502 -252.584204) (xy 343.106007 -252.608811)
			(xy 343.098112 -252.657388) (xy 343.082528 -252.704069) (xy 343.059657 -252.747646) (xy 343.030092 -252.78699)
			(xy 342.994599 -252.821082) (xy 342.954096 -252.849038) (xy 342.909634 -252.870136) (xy 342.862363 -252.883828)
			(xy 342.813508 -252.88976) (xy 342.764333 -252.887779) (xy 342.716114 -252.877935) (xy 342.670098 -252.860483)
			(xy 342.627477 -252.835876) (xy 342.589356 -252.804751) (xy 342.556721 -252.767914) (xy 342.530418 -252.726318)
			(xy 342.511127 -252.681042) (xy 342.49935 -252.633258) (xy 342.49539 -252.584204) (xy 342.176862 -252.584204)
			(xy 342.17635 -252.60965) (xy 342.168186 -252.659884) (xy 342.15207 -252.708158) (xy 342.128419 -252.753221)
			(xy 342.097846 -252.793907) (xy 342.061142 -252.829162) (xy 342.019258 -252.858072) (xy 341.973279 -252.879889)
			(xy 341.924395 -252.894049) (xy 341.873874 -252.900183) (xy 341.823022 -252.898134) (xy 341.773158 -252.887954)
			(xy 341.725572 -252.869907) (xy 341.681498 -252.844461) (xy 341.642076 -252.812274) (xy 341.608328 -252.77418)
			(xy 341.581127 -252.731166) (xy 341.561179 -252.684346) (xy 341.549 -252.634932) (xy 341.544905 -252.584204)
			(xy 341.226394 -252.584204) (xy 341.225899 -252.608811) (xy 341.218004 -252.657388) (xy 341.20242 -252.704069)
			(xy 341.179549 -252.747646) (xy 341.149984 -252.78699) (xy 341.114491 -252.821082) (xy 341.073988 -252.849038)
			(xy 341.029526 -252.870136) (xy 340.982255 -252.883828) (xy 340.9334 -252.88976) (xy 340.884225 -252.887779)
			(xy 340.836006 -252.877935) (xy 340.78999 -252.860483) (xy 340.747369 -252.835876) (xy 340.709248 -252.804751)
			(xy 340.676613 -252.767914) (xy 340.65031 -252.726318) (xy 340.631019 -252.681042) (xy 340.619242 -252.633258)
			(xy 340.615282 -252.584204) (xy 340.296754 -252.584204) (xy 340.296242 -252.60965) (xy 340.288078 -252.659884)
			(xy 340.271962 -252.708158) (xy 340.248311 -252.753221) (xy 340.217738 -252.793907) (xy 340.181034 -252.829162)
			(xy 340.13915 -252.858072) (xy 340.093171 -252.879889) (xy 340.044287 -252.894049) (xy 339.993766 -252.900183)
			(xy 339.942914 -252.898134) (xy 339.89305 -252.887954) (xy 339.845464 -252.869907) (xy 339.80139 -252.844461)
			(xy 339.761968 -252.812274) (xy 339.72822 -252.77418) (xy 339.701019 -252.731166) (xy 339.681071 -252.684346)
			(xy 339.668892 -252.634932) (xy 339.664797 -252.584204) (xy 339.3567 -252.584204) (xy 339.356188 -252.60965)
			(xy 339.348024 -252.659884) (xy 339.331908 -252.708158) (xy 339.308257 -252.753221) (xy 339.277684 -252.793907)
			(xy 339.24098 -252.829162) (xy 339.199096 -252.858072) (xy 339.153117 -252.879889) (xy 339.104233 -252.894049)
			(xy 339.053712 -252.900183) (xy 339.00286 -252.898134) (xy 338.952996 -252.887954) (xy 338.90541 -252.869907)
			(xy 338.861336 -252.844461) (xy 338.821914 -252.812274) (xy 338.788166 -252.77418) (xy 338.760965 -252.731166)
			(xy 338.741017 -252.684346) (xy 338.728838 -252.634932) (xy 338.724743 -252.584204) (xy 338.406486 -252.584204)
			(xy 338.405991 -252.608811) (xy 338.398096 -252.657388) (xy 338.382512 -252.704069) (xy 338.359641 -252.747646)
			(xy 338.330076 -252.78699) (xy 338.294583 -252.821082) (xy 338.25408 -252.849038) (xy 338.209618 -252.870136)
			(xy 338.162347 -252.883828) (xy 338.113492 -252.88976) (xy 338.064317 -252.887779) (xy 338.016098 -252.877935)
			(xy 337.970082 -252.860483) (xy 337.927461 -252.835876) (xy 337.88934 -252.804751) (xy 337.856705 -252.767914)
			(xy 337.830402 -252.726318) (xy 337.811111 -252.681042) (xy 337.799334 -252.633258) (xy 337.795374 -252.584204)
			(xy 337.466432 -252.584204) (xy 337.465937 -252.608811) (xy 337.458042 -252.657388) (xy 337.442458 -252.704069)
			(xy 337.419587 -252.747646) (xy 337.390022 -252.78699) (xy 337.354529 -252.821082) (xy 337.314026 -252.849038)
			(xy 337.269564 -252.870136) (xy 337.222293 -252.883828) (xy 337.173438 -252.88976) (xy 337.124263 -252.887779)
			(xy 337.076044 -252.877935) (xy 337.030028 -252.860483) (xy 336.987407 -252.835876) (xy 336.949286 -252.804751)
			(xy 336.916651 -252.767914) (xy 336.890348 -252.726318) (xy 336.871057 -252.681042) (xy 336.85928 -252.633258)
			(xy 336.85532 -252.584204) (xy 336.526378 -252.584204) (xy 336.525883 -252.608811) (xy 336.517988 -252.657388)
			(xy 336.502404 -252.704069) (xy 336.479533 -252.747646) (xy 336.449968 -252.78699) (xy 336.414475 -252.821082)
			(xy 336.373972 -252.849038) (xy 336.32951 -252.870136) (xy 336.282239 -252.883828) (xy 336.233384 -252.88976)
			(xy 336.184209 -252.887779) (xy 336.13599 -252.877935) (xy 336.089974 -252.860483) (xy 336.047353 -252.835876)
			(xy 336.009232 -252.804751) (xy 335.976597 -252.767914) (xy 335.950294 -252.726318) (xy 335.931003 -252.681042)
			(xy 335.919226 -252.633258) (xy 335.915266 -252.584204) (xy 335.586324 -252.584204) (xy 335.585829 -252.608811)
			(xy 335.577934 -252.657388) (xy 335.56235 -252.704069) (xy 335.539479 -252.747646) (xy 335.509914 -252.78699)
			(xy 335.474421 -252.821082) (xy 335.433918 -252.849038) (xy 335.389456 -252.870136) (xy 335.342185 -252.883828)
			(xy 335.29333 -252.88976) (xy 335.244155 -252.887779) (xy 335.195936 -252.877935) (xy 335.14992 -252.860483)
			(xy 335.107299 -252.835876) (xy 335.069178 -252.804751) (xy 335.036543 -252.767914) (xy 335.01024 -252.726318)
			(xy 334.990949 -252.681042) (xy 334.979172 -252.633258) (xy 334.975212 -252.584204) (xy 334.646524 -252.584204)
			(xy 334.646029 -252.608811) (xy 334.638134 -252.657388) (xy 334.62255 -252.704069) (xy 334.599679 -252.747646)
			(xy 334.570114 -252.78699) (xy 334.534621 -252.821082) (xy 334.494118 -252.849038) (xy 334.449656 -252.870136)
			(xy 334.402385 -252.883828) (xy 334.35353 -252.88976) (xy 334.304355 -252.887779) (xy 334.256136 -252.877935)
			(xy 334.21012 -252.860483) (xy 334.167499 -252.835876) (xy 334.129378 -252.804751) (xy 334.096743 -252.767914)
			(xy 334.07044 -252.726318) (xy 334.051149 -252.681042) (xy 334.039372 -252.633258) (xy 334.035412 -252.584204)
			(xy 333.70647 -252.584204) (xy 333.705975 -252.608811) (xy 333.69808 -252.657388) (xy 333.682496 -252.704069)
			(xy 333.659625 -252.747646) (xy 333.63006 -252.78699) (xy 333.594567 -252.821082) (xy 333.554064 -252.849038)
			(xy 333.509602 -252.870136) (xy 333.462331 -252.883828) (xy 333.413476 -252.88976) (xy 333.364301 -252.887779)
			(xy 333.316082 -252.877935) (xy 333.270066 -252.860483) (xy 333.227445 -252.835876) (xy 333.189324 -252.804751)
			(xy 333.156689 -252.767914) (xy 333.130386 -252.726318) (xy 333.111095 -252.681042) (xy 333.099318 -252.633258)
			(xy 333.095358 -252.584204) (xy 332.766416 -252.584204) (xy 332.765921 -252.608811) (xy 332.758026 -252.657388)
			(xy 332.742442 -252.704069) (xy 332.719571 -252.747646) (xy 332.690006 -252.78699) (xy 332.654513 -252.821082)
			(xy 332.61401 -252.849038) (xy 332.569548 -252.870136) (xy 332.522277 -252.883828) (xy 332.473422 -252.88976)
			(xy 332.424247 -252.887779) (xy 332.376028 -252.877935) (xy 332.330012 -252.860483) (xy 332.287391 -252.835876)
			(xy 332.24927 -252.804751) (xy 332.216635 -252.767914) (xy 332.190332 -252.726318) (xy 332.171041 -252.681042)
			(xy 332.159264 -252.633258) (xy 332.155304 -252.584204) (xy 331.826052 -252.584204) (xy 331.826052 -252.609234)
			(xy 331.817886 -252.658632) (xy 331.801774 -252.706036) (xy 331.778147 -252.750179) (xy 331.747638 -252.789877)
			(xy 331.711062 -252.824068) (xy 331.6694 -252.851836) (xy 331.623768 -252.872439) (xy 331.575386 -252.885323)
			(xy 331.550518 -252.888242) (xy 331.550264 -252.888242) (xy 331.540612 -252.889258) (xy 331.532738 -252.893068)
			(xy 331.528475 -252.895268) (xy 331.520794 -252.901013) (xy 331.517498 -252.904498) (xy 331.47254 -252.954028)
			(xy 331.466484 -252.961199) (xy 331.459695 -252.978685) (xy 331.459332 -252.988064) (xy 331.459332 -253.39421)
			(xy 331.685404 -253.39421) (xy 331.689364 -253.345156) (xy 331.701141 -253.297372) (xy 331.720432 -253.252096)
			(xy 331.746735 -253.2105) (xy 331.77937 -253.173663) (xy 331.817491 -253.142538) (xy 331.860112 -253.117931)
			(xy 331.906128 -253.100479) (xy 331.954347 -253.090635) (xy 332.003522 -253.088654) (xy 332.052377 -253.094586)
			(xy 332.099648 -253.108278) (xy 332.14411 -253.129376) (xy 332.184613 -253.157332) (xy 332.220106 -253.191424)
			(xy 332.249671 -253.230768) (xy 332.272542 -253.274345) (xy 332.288126 -253.321026) (xy 332.296021 -253.369603)
			(xy 332.296516 -253.39421) (xy 332.625204 -253.39421) (xy 332.629164 -253.345156) (xy 332.640941 -253.297372)
			(xy 332.660232 -253.252096) (xy 332.686535 -253.2105) (xy 332.71917 -253.173663) (xy 332.757291 -253.142538)
			(xy 332.799912 -253.117931) (xy 332.845928 -253.100479) (xy 332.894147 -253.090635) (xy 332.943322 -253.088654)
			(xy 332.992177 -253.094586) (xy 333.039448 -253.108278) (xy 333.08391 -253.129376) (xy 333.124413 -253.157332)
			(xy 333.159906 -253.191424) (xy 333.189471 -253.230768) (xy 333.212342 -253.274345) (xy 333.227926 -253.321026)
			(xy 333.235821 -253.369603) (xy 333.236316 -253.39421) (xy 333.565258 -253.39421) (xy 333.569218 -253.345156)
			(xy 333.580995 -253.297372) (xy 333.600286 -253.252096) (xy 333.626589 -253.2105) (xy 333.659224 -253.173663)
			(xy 333.697345 -253.142538) (xy 333.739966 -253.117931) (xy 333.785982 -253.100479) (xy 333.834201 -253.090635)
			(xy 333.883376 -253.088654) (xy 333.932231 -253.094586) (xy 333.979502 -253.108278) (xy 334.023964 -253.129376)
			(xy 334.064467 -253.157332) (xy 334.09996 -253.191424) (xy 334.129525 -253.230768) (xy 334.152396 -253.274345)
			(xy 334.16798 -253.321026) (xy 334.175875 -253.369603) (xy 334.17637 -253.39421) (xy 334.505312 -253.39421)
			(xy 334.509272 -253.345156) (xy 334.521049 -253.297372) (xy 334.54034 -253.252096) (xy 334.566643 -253.2105)
			(xy 334.599278 -253.173663) (xy 334.637399 -253.142538) (xy 334.68002 -253.117931) (xy 334.726036 -253.100479)
			(xy 334.774255 -253.090635) (xy 334.82343 -253.088654) (xy 334.872285 -253.094586) (xy 334.919556 -253.108278)
			(xy 334.964018 -253.129376) (xy 335.004521 -253.157332) (xy 335.040014 -253.191424) (xy 335.069579 -253.230768)
			(xy 335.09245 -253.274345) (xy 335.108034 -253.321026) (xy 335.115929 -253.369603) (xy 335.116424 -253.39421)
			(xy 335.445366 -253.39421) (xy 335.449326 -253.345156) (xy 335.461103 -253.297372) (xy 335.480394 -253.252096)
			(xy 335.506697 -253.2105) (xy 335.539332 -253.173663) (xy 335.577453 -253.142538) (xy 335.620074 -253.117931)
			(xy 335.66609 -253.100479) (xy 335.714309 -253.090635) (xy 335.763484 -253.088654) (xy 335.812339 -253.094586)
			(xy 335.85961 -253.108278) (xy 335.904072 -253.129376) (xy 335.944575 -253.157332) (xy 335.980068 -253.191424)
			(xy 336.009633 -253.230768) (xy 336.032504 -253.274345) (xy 336.048088 -253.321026) (xy 336.055983 -253.369603)
			(xy 336.056478 -253.39421) (xy 336.38542 -253.39421) (xy 336.38938 -253.345156) (xy 336.401157 -253.297372)
			(xy 336.420448 -253.252096) (xy 336.446751 -253.2105) (xy 336.479386 -253.173663) (xy 336.517507 -253.142538)
			(xy 336.560128 -253.117931) (xy 336.606144 -253.100479) (xy 336.654363 -253.090635) (xy 336.703538 -253.088654)
			(xy 336.752393 -253.094586) (xy 336.799664 -253.108278) (xy 336.844126 -253.129376) (xy 336.884629 -253.157332)
			(xy 336.920122 -253.191424) (xy 336.949687 -253.230768) (xy 336.972558 -253.274345) (xy 336.988142 -253.321026)
			(xy 336.996037 -253.369603) (xy 336.996532 -253.39421) (xy 337.32522 -253.39421) (xy 337.32918 -253.345156)
			(xy 337.340957 -253.297372) (xy 337.360248 -253.252096) (xy 337.386551 -253.2105) (xy 337.419186 -253.173663)
			(xy 337.457307 -253.142538) (xy 337.499928 -253.117931) (xy 337.545944 -253.100479) (xy 337.594163 -253.090635)
			(xy 337.643338 -253.088654) (xy 337.692193 -253.094586) (xy 337.739464 -253.108278) (xy 337.783926 -253.129376)
			(xy 337.824429 -253.157332) (xy 337.859922 -253.191424) (xy 337.889487 -253.230768) (xy 337.912358 -253.274345)
			(xy 337.927942 -253.321026) (xy 337.935837 -253.369603) (xy 337.936332 -253.39421) (xy 338.254843 -253.39421)
			(xy 338.258938 -253.343482) (xy 338.271117 -253.294068) (xy 338.291065 -253.247248) (xy 338.318266 -253.204234)
			(xy 338.352014 -253.16614) (xy 338.391436 -253.133953) (xy 338.43551 -253.108507) (xy 338.483096 -253.09046)
			(xy 338.53296 -253.08028) (xy 338.583812 -253.078231) (xy 338.634333 -253.084365) (xy 338.683217 -253.098525)
			(xy 338.729196 -253.120342) (xy 338.77108 -253.149252) (xy 338.807784 -253.184507) (xy 338.838357 -253.225193)
			(xy 338.862008 -253.270256) (xy 338.878124 -253.31853) (xy 338.886288 -253.368764) (xy 338.8868 -253.39421)
			(xy 339.205328 -253.39421) (xy 339.209288 -253.345156) (xy 339.221065 -253.297372) (xy 339.240356 -253.252096)
			(xy 339.266659 -253.2105) (xy 339.299294 -253.173663) (xy 339.337415 -253.142538) (xy 339.380036 -253.117931)
			(xy 339.426052 -253.100479) (xy 339.474271 -253.090635) (xy 339.523446 -253.088654) (xy 339.572301 -253.094586)
			(xy 339.619572 -253.108278) (xy 339.664034 -253.129376) (xy 339.704537 -253.157332) (xy 339.74003 -253.191424)
			(xy 339.769595 -253.230768) (xy 339.792466 -253.274345) (xy 339.80805 -253.321026) (xy 339.815945 -253.369603)
			(xy 339.81644 -253.39421) (xy 340.134951 -253.39421) (xy 340.139046 -253.343482) (xy 340.151225 -253.294068)
			(xy 340.171173 -253.247248) (xy 340.198374 -253.204234) (xy 340.232122 -253.16614) (xy 340.271544 -253.133953)
			(xy 340.315618 -253.108507) (xy 340.363204 -253.09046) (xy 340.413068 -253.08028) (xy 340.46392 -253.078231)
			(xy 340.514441 -253.084365) (xy 340.563325 -253.098525) (xy 340.609304 -253.120342) (xy 340.651188 -253.149252)
			(xy 340.687892 -253.184507) (xy 340.718465 -253.225193) (xy 340.742116 -253.270256) (xy 340.758232 -253.31853)
			(xy 340.766396 -253.368764) (xy 340.766908 -253.39421) (xy 341.085182 -253.39421) (xy 341.089142 -253.345156)
			(xy 341.100919 -253.297372) (xy 341.12021 -253.252096) (xy 341.146513 -253.2105) (xy 341.179148 -253.173663)
			(xy 341.217269 -253.142538) (xy 341.25989 -253.117931) (xy 341.305906 -253.100479) (xy 341.354125 -253.090635)
			(xy 341.4033 -253.088654) (xy 341.452155 -253.094586) (xy 341.499426 -253.108278) (xy 341.543888 -253.129376)
			(xy 341.584391 -253.157332) (xy 341.619884 -253.191424) (xy 341.649449 -253.230768) (xy 341.67232 -253.274345)
			(xy 341.687904 -253.321026) (xy 341.695799 -253.369603) (xy 341.696294 -253.39421) (xy 342.014805 -253.39421)
			(xy 342.0189 -253.343482) (xy 342.031079 -253.294068) (xy 342.051027 -253.247248) (xy 342.078228 -253.204234)
			(xy 342.111976 -253.16614) (xy 342.151398 -253.133953) (xy 342.195472 -253.108507) (xy 342.243058 -253.09046)
			(xy 342.292922 -253.08028) (xy 342.343774 -253.078231) (xy 342.394295 -253.084365) (xy 342.443179 -253.098525)
			(xy 342.489158 -253.120342) (xy 342.531042 -253.149252) (xy 342.567746 -253.184507) (xy 342.598319 -253.225193)
			(xy 342.62197 -253.270256) (xy 342.638086 -253.31853) (xy 342.64625 -253.368764) (xy 342.646762 -253.39421)
			(xy 342.954859 -253.39421) (xy 342.958954 -253.343482) (xy 342.971133 -253.294068) (xy 342.991081 -253.247248)
			(xy 343.018282 -253.204234) (xy 343.05203 -253.16614) (xy 343.091452 -253.133953) (xy 343.135526 -253.108507)
			(xy 343.183112 -253.09046) (xy 343.232976 -253.08028) (xy 343.283828 -253.078231) (xy 343.334349 -253.084365)
			(xy 343.383233 -253.098525) (xy 343.429212 -253.120342) (xy 343.471096 -253.149252) (xy 343.5078 -253.184507)
			(xy 343.538373 -253.225193) (xy 343.562024 -253.270256) (xy 343.57814 -253.31853) (xy 343.586304 -253.368764)
			(xy 343.586816 -253.39421) (xy 343.586304 -253.419656) (xy 343.57814 -253.46989) (xy 343.562024 -253.518164)
			(xy 343.538373 -253.563227) (xy 343.5078 -253.603913) (xy 343.471096 -253.639168) (xy 343.429212 -253.668078)
			(xy 343.383233 -253.689895) (xy 343.334349 -253.704055) (xy 343.283828 -253.710189) (xy 343.232976 -253.70814)
			(xy 343.183112 -253.69796) (xy 343.135526 -253.679913) (xy 343.091452 -253.654467) (xy 343.05203 -253.62228)
			(xy 343.018282 -253.584186) (xy 342.991081 -253.541172) (xy 342.971133 -253.494352) (xy 342.958954 -253.444938)
			(xy 342.954859 -253.39421) (xy 342.646762 -253.39421) (xy 342.64625 -253.419656) (xy 342.638086 -253.46989)
			(xy 342.62197 -253.518164) (xy 342.598319 -253.563227) (xy 342.567746 -253.603913) (xy 342.531042 -253.639168)
			(xy 342.489158 -253.668078) (xy 342.443179 -253.689895) (xy 342.394295 -253.704055) (xy 342.343774 -253.710189)
			(xy 342.292922 -253.70814) (xy 342.243058 -253.69796) (xy 342.195472 -253.679913) (xy 342.151398 -253.654467)
			(xy 342.111976 -253.62228) (xy 342.078228 -253.584186) (xy 342.051027 -253.541172) (xy 342.031079 -253.494352)
			(xy 342.0189 -253.444938) (xy 342.014805 -253.39421) (xy 341.696294 -253.39421) (xy 341.695799 -253.418817)
			(xy 341.687904 -253.467394) (xy 341.67232 -253.514075) (xy 341.649449 -253.557652) (xy 341.619884 -253.596996)
			(xy 341.584391 -253.631088) (xy 341.543888 -253.659044) (xy 341.499426 -253.680142) (xy 341.452155 -253.693834)
			(xy 341.4033 -253.699766) (xy 341.354125 -253.697785) (xy 341.305906 -253.687941) (xy 341.25989 -253.670489)
			(xy 341.217269 -253.645882) (xy 341.179148 -253.614757) (xy 341.146513 -253.57792) (xy 341.12021 -253.536324)
			(xy 341.100919 -253.491048) (xy 341.089142 -253.443264) (xy 341.085182 -253.39421) (xy 340.766908 -253.39421)
			(xy 340.766396 -253.419656) (xy 340.758232 -253.46989) (xy 340.742116 -253.518164) (xy 340.718465 -253.563227)
			(xy 340.687892 -253.603913) (xy 340.651188 -253.639168) (xy 340.609304 -253.668078) (xy 340.563325 -253.689895)
			(xy 340.514441 -253.704055) (xy 340.46392 -253.710189) (xy 340.413068 -253.70814) (xy 340.363204 -253.69796)
			(xy 340.315618 -253.679913) (xy 340.271544 -253.654467) (xy 340.232122 -253.62228) (xy 340.198374 -253.584186)
			(xy 340.171173 -253.541172) (xy 340.151225 -253.494352) (xy 340.139046 -253.444938) (xy 340.134951 -253.39421)
			(xy 339.81644 -253.39421) (xy 339.815945 -253.418817) (xy 339.80805 -253.467394) (xy 339.792466 -253.514075)
			(xy 339.769595 -253.557652) (xy 339.74003 -253.596996) (xy 339.704537 -253.631088) (xy 339.664034 -253.659044)
			(xy 339.619572 -253.680142) (xy 339.572301 -253.693834) (xy 339.523446 -253.699766) (xy 339.474271 -253.697785)
			(xy 339.426052 -253.687941) (xy 339.380036 -253.670489) (xy 339.337415 -253.645882) (xy 339.299294 -253.614757)
			(xy 339.266659 -253.57792) (xy 339.240356 -253.536324) (xy 339.221065 -253.491048) (xy 339.209288 -253.443264)
			(xy 339.205328 -253.39421) (xy 338.8868 -253.39421) (xy 338.886288 -253.419656) (xy 338.878124 -253.46989)
			(xy 338.862008 -253.518164) (xy 338.838357 -253.563227) (xy 338.807784 -253.603913) (xy 338.77108 -253.639168)
			(xy 338.729196 -253.668078) (xy 338.683217 -253.689895) (xy 338.634333 -253.704055) (xy 338.583812 -253.710189)
			(xy 338.53296 -253.70814) (xy 338.483096 -253.69796) (xy 338.43551 -253.679913) (xy 338.391436 -253.654467)
			(xy 338.352014 -253.62228) (xy 338.318266 -253.584186) (xy 338.291065 -253.541172) (xy 338.271117 -253.494352)
			(xy 338.258938 -253.444938) (xy 338.254843 -253.39421) (xy 337.936332 -253.39421) (xy 337.935837 -253.418817)
			(xy 337.927942 -253.467394) (xy 337.912358 -253.514075) (xy 337.889487 -253.557652) (xy 337.859922 -253.596996)
			(xy 337.824429 -253.631088) (xy 337.783926 -253.659044) (xy 337.739464 -253.680142) (xy 337.692193 -253.693834)
			(xy 337.643338 -253.699766) (xy 337.594163 -253.697785) (xy 337.545944 -253.687941) (xy 337.499928 -253.670489)
			(xy 337.457307 -253.645882) (xy 337.419186 -253.614757) (xy 337.386551 -253.57792) (xy 337.360248 -253.536324)
			(xy 337.340957 -253.491048) (xy 337.32918 -253.443264) (xy 337.32522 -253.39421) (xy 336.996532 -253.39421)
			(xy 336.996037 -253.418817) (xy 336.988142 -253.467394) (xy 336.972558 -253.514075) (xy 336.949687 -253.557652)
			(xy 336.920122 -253.596996) (xy 336.884629 -253.631088) (xy 336.844126 -253.659044) (xy 336.799664 -253.680142)
			(xy 336.752393 -253.693834) (xy 336.703538 -253.699766) (xy 336.654363 -253.697785) (xy 336.606144 -253.687941)
			(xy 336.560128 -253.670489) (xy 336.517507 -253.645882) (xy 336.479386 -253.614757) (xy 336.446751 -253.57792)
			(xy 336.420448 -253.536324) (xy 336.401157 -253.491048) (xy 336.38938 -253.443264) (xy 336.38542 -253.39421)
			(xy 336.056478 -253.39421) (xy 336.055983 -253.418817) (xy 336.048088 -253.467394) (xy 336.032504 -253.514075)
			(xy 336.009633 -253.557652) (xy 335.980068 -253.596996) (xy 335.944575 -253.631088) (xy 335.904072 -253.659044)
			(xy 335.85961 -253.680142) (xy 335.812339 -253.693834) (xy 335.763484 -253.699766) (xy 335.714309 -253.697785)
			(xy 335.66609 -253.687941) (xy 335.620074 -253.670489) (xy 335.577453 -253.645882) (xy 335.539332 -253.614757)
			(xy 335.506697 -253.57792) (xy 335.480394 -253.536324) (xy 335.461103 -253.491048) (xy 335.449326 -253.443264)
			(xy 335.445366 -253.39421) (xy 335.116424 -253.39421) (xy 335.115929 -253.418817) (xy 335.108034 -253.467394)
			(xy 335.09245 -253.514075) (xy 335.069579 -253.557652) (xy 335.040014 -253.596996) (xy 335.004521 -253.631088)
			(xy 334.964018 -253.659044) (xy 334.919556 -253.680142) (xy 334.872285 -253.693834) (xy 334.82343 -253.699766)
			(xy 334.774255 -253.697785) (xy 334.726036 -253.687941) (xy 334.68002 -253.670489) (xy 334.637399 -253.645882)
			(xy 334.599278 -253.614757) (xy 334.566643 -253.57792) (xy 334.54034 -253.536324) (xy 334.521049 -253.491048)
			(xy 334.509272 -253.443264) (xy 334.505312 -253.39421) (xy 334.17637 -253.39421) (xy 334.175875 -253.418817)
			(xy 334.16798 -253.467394) (xy 334.152396 -253.514075) (xy 334.129525 -253.557652) (xy 334.09996 -253.596996)
			(xy 334.064467 -253.631088) (xy 334.023964 -253.659044) (xy 333.979502 -253.680142) (xy 333.932231 -253.693834)
			(xy 333.883376 -253.699766) (xy 333.834201 -253.697785) (xy 333.785982 -253.687941) (xy 333.739966 -253.670489)
			(xy 333.697345 -253.645882) (xy 333.659224 -253.614757) (xy 333.626589 -253.57792) (xy 333.600286 -253.536324)
			(xy 333.580995 -253.491048) (xy 333.569218 -253.443264) (xy 333.565258 -253.39421) (xy 333.236316 -253.39421)
			(xy 333.235821 -253.418817) (xy 333.227926 -253.467394) (xy 333.212342 -253.514075) (xy 333.189471 -253.557652)
			(xy 333.159906 -253.596996) (xy 333.124413 -253.631088) (xy 333.08391 -253.659044) (xy 333.039448 -253.680142)
			(xy 332.992177 -253.693834) (xy 332.943322 -253.699766) (xy 332.894147 -253.697785) (xy 332.845928 -253.687941)
			(xy 332.799912 -253.670489) (xy 332.757291 -253.645882) (xy 332.71917 -253.614757) (xy 332.686535 -253.57792)
			(xy 332.660232 -253.536324) (xy 332.640941 -253.491048) (xy 332.629164 -253.443264) (xy 332.625204 -253.39421)
			(xy 332.296516 -253.39421) (xy 332.296021 -253.418817) (xy 332.288126 -253.467394) (xy 332.272542 -253.514075)
			(xy 332.249671 -253.557652) (xy 332.220106 -253.596996) (xy 332.184613 -253.631088) (xy 332.14411 -253.659044)
			(xy 332.099648 -253.680142) (xy 332.052377 -253.693834) (xy 332.003522 -253.699766) (xy 331.954347 -253.697785)
			(xy 331.906128 -253.687941) (xy 331.860112 -253.670489) (xy 331.817491 -253.645882) (xy 331.77937 -253.614757)
			(xy 331.746735 -253.57792) (xy 331.720432 -253.536324) (xy 331.701141 -253.491048) (xy 331.689364 -253.443264)
			(xy 331.685404 -253.39421) (xy 331.459332 -253.39421) (xy 331.459332 -253.800356) (xy 331.459802 -253.809715)
			(xy 331.466565 -253.827175) (xy 331.47254 -253.834392) (xy 331.517498 -253.883922) (xy 331.520811 -253.887389)
			(xy 331.528481 -253.893143) (xy 331.532738 -253.895352) (xy 331.540612 -253.899162) (xy 331.550264 -253.900178)
			(xy 331.550518 -253.900178) (xy 331.575386 -253.903089) (xy 331.623766 -253.915973) (xy 331.669396 -253.936575)
			(xy 331.711056 -253.964343) (xy 331.74763 -253.998533) (xy 331.778138 -254.038229) (xy 331.801764 -254.08237)
			(xy 331.817875 -254.129773) (xy 331.82604 -254.179169) (xy 331.82604 -254.204216) (xy 332.155304 -254.204216)
			(xy 332.159264 -254.155162) (xy 332.171041 -254.107378) (xy 332.190332 -254.062102) (xy 332.216635 -254.020506)
			(xy 332.24927 -253.983669) (xy 332.287391 -253.952544) (xy 332.330012 -253.927937) (xy 332.376028 -253.910485)
			(xy 332.424247 -253.900641) (xy 332.473422 -253.89866) (xy 332.522277 -253.904592) (xy 332.569548 -253.918284)
			(xy 332.61401 -253.939382) (xy 332.654513 -253.967338) (xy 332.690006 -254.00143) (xy 332.719571 -254.040774)
			(xy 332.742442 -254.084351) (xy 332.758026 -254.131032) (xy 332.765921 -254.179609) (xy 332.766416 -254.204216)
			(xy 333.095358 -254.204216) (xy 333.099318 -254.155162) (xy 333.111095 -254.107378) (xy 333.130386 -254.062102)
			(xy 333.156689 -254.020506) (xy 333.189324 -253.983669) (xy 333.227445 -253.952544) (xy 333.270066 -253.927937)
			(xy 333.316082 -253.910485) (xy 333.364301 -253.900641) (xy 333.413476 -253.89866) (xy 333.462331 -253.904592)
			(xy 333.509602 -253.918284) (xy 333.554064 -253.939382) (xy 333.594567 -253.967338) (xy 333.63006 -254.00143)
			(xy 333.659625 -254.040774) (xy 333.682496 -254.084351) (xy 333.69808 -254.131032) (xy 333.705975 -254.179609)
			(xy 333.70647 -254.204216) (xy 334.975212 -254.204216) (xy 334.979172 -254.155162) (xy 334.990949 -254.107378)
			(xy 335.01024 -254.062102) (xy 335.036543 -254.020506) (xy 335.069178 -253.983669) (xy 335.107299 -253.952544)
			(xy 335.14992 -253.927937) (xy 335.195936 -253.910485) (xy 335.244155 -253.900641) (xy 335.29333 -253.89866)
			(xy 335.342185 -253.904592) (xy 335.389456 -253.918284) (xy 335.433918 -253.939382) (xy 335.474421 -253.967338)
			(xy 335.509914 -254.00143) (xy 335.539479 -254.040774) (xy 335.56235 -254.084351) (xy 335.577934 -254.131032)
			(xy 335.585829 -254.179609) (xy 335.586324 -254.204216) (xy 335.915266 -254.204216) (xy 335.919226 -254.155162)
			(xy 335.931003 -254.107378) (xy 335.950294 -254.062102) (xy 335.976597 -254.020506) (xy 336.009232 -253.983669)
			(xy 336.047353 -253.952544) (xy 336.089974 -253.927937) (xy 336.13599 -253.910485) (xy 336.184209 -253.900641)
			(xy 336.233384 -253.89866) (xy 336.282239 -253.904592) (xy 336.32951 -253.918284) (xy 336.373972 -253.939382)
			(xy 336.414475 -253.967338) (xy 336.449968 -254.00143) (xy 336.479533 -254.040774) (xy 336.502404 -254.084351)
			(xy 336.517988 -254.131032) (xy 336.525883 -254.179609) (xy 336.526378 -254.204216) (xy 336.85532 -254.204216)
			(xy 336.85928 -254.155162) (xy 336.871057 -254.107378) (xy 336.890348 -254.062102) (xy 336.916651 -254.020506)
			(xy 336.949286 -253.983669) (xy 336.987407 -253.952544) (xy 337.030028 -253.927937) (xy 337.076044 -253.910485)
			(xy 337.124263 -253.900641) (xy 337.173438 -253.89866) (xy 337.222293 -253.904592) (xy 337.269564 -253.918284)
			(xy 337.314026 -253.939382) (xy 337.354529 -253.967338) (xy 337.390022 -254.00143) (xy 337.419587 -254.040774)
			(xy 337.442458 -254.084351) (xy 337.458042 -254.131032) (xy 337.465937 -254.179609) (xy 337.466432 -254.204216)
			(xy 337.795374 -254.204216) (xy 337.799334 -254.155162) (xy 337.811111 -254.107378) (xy 337.830402 -254.062102)
			(xy 337.856705 -254.020506) (xy 337.88934 -253.983669) (xy 337.927461 -253.952544) (xy 337.970082 -253.927937)
			(xy 338.016098 -253.910485) (xy 338.064317 -253.900641) (xy 338.113492 -253.89866) (xy 338.162347 -253.904592)
			(xy 338.209618 -253.918284) (xy 338.25408 -253.939382) (xy 338.294583 -253.967338) (xy 338.330076 -254.00143)
			(xy 338.359641 -254.040774) (xy 338.382512 -254.084351) (xy 338.398096 -254.131032) (xy 338.405991 -254.179609)
			(xy 338.406486 -254.204216) (xy 338.724743 -254.204216) (xy 338.728838 -254.153488) (xy 338.741017 -254.104074)
			(xy 338.760965 -254.057254) (xy 338.788166 -254.01424) (xy 338.821914 -253.976146) (xy 338.861336 -253.943959)
			(xy 338.90541 -253.918513) (xy 338.952996 -253.900466) (xy 339.00286 -253.890286) (xy 339.053712 -253.888237)
			(xy 339.104233 -253.894371) (xy 339.153117 -253.908531) (xy 339.199096 -253.930348) (xy 339.24098 -253.959258)
			(xy 339.277684 -253.994513) (xy 339.308257 -254.035199) (xy 339.331908 -254.080262) (xy 339.348024 -254.128536)
			(xy 339.356188 -254.17877) (xy 339.3567 -254.204216) (xy 339.664797 -254.204216) (xy 339.668892 -254.153488)
			(xy 339.681071 -254.104074) (xy 339.701019 -254.057254) (xy 339.72822 -254.01424) (xy 339.761968 -253.976146)
			(xy 339.80139 -253.943959) (xy 339.845464 -253.918513) (xy 339.89305 -253.900466) (xy 339.942914 -253.890286)
			(xy 339.993766 -253.888237) (xy 340.044287 -253.894371) (xy 340.093171 -253.908531) (xy 340.13915 -253.930348)
			(xy 340.181034 -253.959258) (xy 340.217738 -253.994513) (xy 340.248311 -254.035199) (xy 340.271962 -254.080262)
			(xy 340.288078 -254.128536) (xy 340.296242 -254.17877) (xy 340.296754 -254.204216) (xy 341.544905 -254.204216)
			(xy 341.549 -254.153488) (xy 341.561179 -254.104074) (xy 341.581127 -254.057254) (xy 341.608328 -254.01424)
			(xy 341.642076 -253.976146) (xy 341.681498 -253.943959) (xy 341.725572 -253.918513) (xy 341.773158 -253.900466)
			(xy 341.823022 -253.890286) (xy 341.873874 -253.888237) (xy 341.924395 -253.894371) (xy 341.973279 -253.908531)
			(xy 342.019258 -253.930348) (xy 342.061142 -253.959258) (xy 342.097846 -253.994513) (xy 342.128419 -254.035199)
			(xy 342.15207 -254.080262) (xy 342.168186 -254.128536) (xy 342.17635 -254.17877) (xy 342.176862 -254.204216)
			(xy 342.49539 -254.204216) (xy 342.49935 -254.155162) (xy 342.511127 -254.107378) (xy 342.530418 -254.062102)
			(xy 342.556721 -254.020506) (xy 342.589356 -253.983669) (xy 342.627477 -253.952544) (xy 342.670098 -253.927937)
			(xy 342.716114 -253.910485) (xy 342.764333 -253.900641) (xy 342.813508 -253.89866) (xy 342.862363 -253.904592)
			(xy 342.909634 -253.918284) (xy 342.954096 -253.939382) (xy 342.994599 -253.967338) (xy 343.030092 -254.00143)
			(xy 343.059657 -254.040774) (xy 343.082528 -254.084351) (xy 343.098112 -254.131032) (xy 343.106007 -254.179609)
			(xy 343.106502 -254.204216) (xy 343.106007 -254.228823) (xy 343.098112 -254.2774) (xy 343.082528 -254.324081)
			(xy 343.059657 -254.367658) (xy 343.030092 -254.407002) (xy 342.994599 -254.441094) (xy 342.954096 -254.46905)
			(xy 342.909634 -254.490148) (xy 342.862363 -254.50384) (xy 342.813508 -254.509772) (xy 342.764333 -254.507791)
			(xy 342.716114 -254.497947) (xy 342.670098 -254.480495) (xy 342.627477 -254.455888) (xy 342.589356 -254.424763)
			(xy 342.556721 -254.387926) (xy 342.530418 -254.34633) (xy 342.511127 -254.301054) (xy 342.49935 -254.25327)
			(xy 342.49539 -254.204216) (xy 342.176862 -254.204216) (xy 342.17635 -254.229662) (xy 342.168186 -254.279896)
			(xy 342.15207 -254.32817) (xy 342.128419 -254.373233) (xy 342.097846 -254.413919) (xy 342.061142 -254.449174)
			(xy 342.019258 -254.478084) (xy 341.973279 -254.499901) (xy 341.924395 -254.514061) (xy 341.873874 -254.520195)
			(xy 341.823022 -254.518146) (xy 341.773158 -254.507966) (xy 341.725572 -254.489919) (xy 341.681498 -254.464473)
			(xy 341.642076 -254.432286) (xy 341.608328 -254.394192) (xy 341.581127 -254.351178) (xy 341.561179 -254.304358)
			(xy 341.549 -254.254944) (xy 341.544905 -254.204216) (xy 340.296754 -254.204216) (xy 340.296242 -254.229662)
			(xy 340.288078 -254.279896) (xy 340.271962 -254.32817) (xy 340.248311 -254.373233) (xy 340.217738 -254.413919)
			(xy 340.181034 -254.449174) (xy 340.13915 -254.478084) (xy 340.093171 -254.499901) (xy 340.044287 -254.514061)
			(xy 339.993766 -254.520195) (xy 339.942914 -254.518146) (xy 339.89305 -254.507966) (xy 339.845464 -254.489919)
			(xy 339.80139 -254.464473) (xy 339.761968 -254.432286) (xy 339.72822 -254.394192) (xy 339.701019 -254.351178)
			(xy 339.681071 -254.304358) (xy 339.668892 -254.254944) (xy 339.664797 -254.204216) (xy 339.3567 -254.204216)
			(xy 339.356188 -254.229662) (xy 339.348024 -254.279896) (xy 339.331908 -254.32817) (xy 339.308257 -254.373233)
			(xy 339.277684 -254.413919) (xy 339.24098 -254.449174) (xy 339.199096 -254.478084) (xy 339.153117 -254.499901)
			(xy 339.104233 -254.514061) (xy 339.053712 -254.520195) (xy 339.00286 -254.518146) (xy 338.952996 -254.507966)
			(xy 338.90541 -254.489919) (xy 338.861336 -254.464473) (xy 338.821914 -254.432286) (xy 338.788166 -254.394192)
			(xy 338.760965 -254.351178) (xy 338.741017 -254.304358) (xy 338.728838 -254.254944) (xy 338.724743 -254.204216)
			(xy 338.406486 -254.204216) (xy 338.405991 -254.228823) (xy 338.398096 -254.2774) (xy 338.382512 -254.324081)
			(xy 338.359641 -254.367658) (xy 338.330076 -254.407002) (xy 338.294583 -254.441094) (xy 338.25408 -254.46905)
			(xy 338.209618 -254.490148) (xy 338.162347 -254.50384) (xy 338.113492 -254.509772) (xy 338.064317 -254.507791)
			(xy 338.016098 -254.497947) (xy 337.970082 -254.480495) (xy 337.927461 -254.455888) (xy 337.88934 -254.424763)
			(xy 337.856705 -254.387926) (xy 337.830402 -254.34633) (xy 337.811111 -254.301054) (xy 337.799334 -254.25327)
			(xy 337.795374 -254.204216) (xy 337.466432 -254.204216) (xy 337.465937 -254.228823) (xy 337.458042 -254.2774)
			(xy 337.442458 -254.324081) (xy 337.419587 -254.367658) (xy 337.390022 -254.407002) (xy 337.354529 -254.441094)
			(xy 337.314026 -254.46905) (xy 337.269564 -254.490148) (xy 337.222293 -254.50384) (xy 337.173438 -254.509772)
			(xy 337.124263 -254.507791) (xy 337.076044 -254.497947) (xy 337.030028 -254.480495) (xy 336.987407 -254.455888)
			(xy 336.949286 -254.424763) (xy 336.916651 -254.387926) (xy 336.890348 -254.34633) (xy 336.871057 -254.301054)
			(xy 336.85928 -254.25327) (xy 336.85532 -254.204216) (xy 336.526378 -254.204216) (xy 336.525883 -254.228823)
			(xy 336.517988 -254.2774) (xy 336.502404 -254.324081) (xy 336.479533 -254.367658) (xy 336.449968 -254.407002)
			(xy 336.414475 -254.441094) (xy 336.373972 -254.46905) (xy 336.32951 -254.490148) (xy 336.282239 -254.50384)
			(xy 336.233384 -254.509772) (xy 336.184209 -254.507791) (xy 336.13599 -254.497947) (xy 336.089974 -254.480495)
			(xy 336.047353 -254.455888) (xy 336.009232 -254.424763) (xy 335.976597 -254.387926) (xy 335.950294 -254.34633)
			(xy 335.931003 -254.301054) (xy 335.919226 -254.25327) (xy 335.915266 -254.204216) (xy 335.586324 -254.204216)
			(xy 335.585829 -254.228823) (xy 335.577934 -254.2774) (xy 335.56235 -254.324081) (xy 335.539479 -254.367658)
			(xy 335.509914 -254.407002) (xy 335.474421 -254.441094) (xy 335.433918 -254.46905) (xy 335.389456 -254.490148)
			(xy 335.342185 -254.50384) (xy 335.29333 -254.509772) (xy 335.244155 -254.507791) (xy 335.195936 -254.497947)
			(xy 335.14992 -254.480495) (xy 335.107299 -254.455888) (xy 335.069178 -254.424763) (xy 335.036543 -254.387926)
			(xy 335.01024 -254.34633) (xy 334.990949 -254.301054) (xy 334.979172 -254.25327) (xy 334.975212 -254.204216)
			(xy 333.70647 -254.204216) (xy 333.705975 -254.228823) (xy 333.69808 -254.2774) (xy 333.682496 -254.324081)
			(xy 333.659625 -254.367658) (xy 333.63006 -254.407002) (xy 333.594567 -254.441094) (xy 333.554064 -254.46905)
			(xy 333.509602 -254.490148) (xy 333.462331 -254.50384) (xy 333.413476 -254.509772) (xy 333.364301 -254.507791)
			(xy 333.316082 -254.497947) (xy 333.270066 -254.480495) (xy 333.227445 -254.455888) (xy 333.189324 -254.424763)
			(xy 333.156689 -254.387926) (xy 333.130386 -254.34633) (xy 333.111095 -254.301054) (xy 333.099318 -254.25327)
			(xy 333.095358 -254.204216) (xy 332.766416 -254.204216) (xy 332.765921 -254.228823) (xy 332.758026 -254.2774)
			(xy 332.742442 -254.324081) (xy 332.719571 -254.367658) (xy 332.690006 -254.407002) (xy 332.654513 -254.441094)
			(xy 332.61401 -254.46905) (xy 332.569548 -254.490148) (xy 332.522277 -254.50384) (xy 332.473422 -254.509772)
			(xy 332.424247 -254.507791) (xy 332.376028 -254.497947) (xy 332.330012 -254.480495) (xy 332.287391 -254.455888)
			(xy 332.24927 -254.424763) (xy 332.216635 -254.387926) (xy 332.190332 -254.34633) (xy 332.171041 -254.301054)
			(xy 332.159264 -254.25327) (xy 332.155304 -254.204216) (xy 331.82604 -254.204216) (xy 331.82604 -254.229234)
			(xy 331.817874 -254.27863) (xy 331.801763 -254.326033) (xy 331.778137 -254.370173) (xy 331.747628 -254.40987)
			(xy 331.711054 -254.444059) (xy 331.669394 -254.471826) (xy 331.623763 -254.492428) (xy 331.575383 -254.505312)
			(xy 331.550518 -254.508254) (xy 331.550264 -254.508254) (xy 331.540612 -254.50927) (xy 331.532738 -254.51308)
			(xy 331.528475 -254.51528) (xy 331.520795 -254.521027) (xy 331.517498 -254.52451) (xy 331.47254 -254.57404)
			(xy 331.466485 -254.581212) (xy 331.459701 -254.598697) (xy 331.459332 -254.608076) (xy 331.459332 -255.014222)
			(xy 331.685404 -255.014222) (xy 331.689364 -254.965168) (xy 331.701141 -254.917384) (xy 331.720432 -254.872108)
			(xy 331.746735 -254.830512) (xy 331.77937 -254.793675) (xy 331.817491 -254.76255) (xy 331.860112 -254.737943)
			(xy 331.906128 -254.720491) (xy 331.954347 -254.710647) (xy 332.003522 -254.708666) (xy 332.052377 -254.714598)
			(xy 332.099648 -254.72829) (xy 332.14411 -254.749388) (xy 332.184613 -254.777344) (xy 332.220106 -254.811436)
			(xy 332.249671 -254.85078) (xy 332.272542 -254.894357) (xy 332.288126 -254.941038) (xy 332.296021 -254.989615)
			(xy 332.296516 -255.014222) (xy 332.625204 -255.014222) (xy 332.629164 -254.965168) (xy 332.640941 -254.917384)
			(xy 332.660232 -254.872108) (xy 332.686535 -254.830512) (xy 332.71917 -254.793675) (xy 332.757291 -254.76255)
			(xy 332.799912 -254.737943) (xy 332.845928 -254.720491) (xy 332.894147 -254.710647) (xy 332.943322 -254.708666)
			(xy 332.992177 -254.714598) (xy 333.039448 -254.72829) (xy 333.08391 -254.749388) (xy 333.124413 -254.777344)
			(xy 333.159906 -254.811436) (xy 333.189471 -254.85078) (xy 333.212342 -254.894357) (xy 333.227926 -254.941038)
			(xy 333.235821 -254.989615) (xy 333.236316 -255.014222) (xy 333.565258 -255.014222) (xy 333.569218 -254.965168)
			(xy 333.580995 -254.917384) (xy 333.600286 -254.872108) (xy 333.626589 -254.830512) (xy 333.659224 -254.793675)
			(xy 333.697345 -254.76255) (xy 333.739966 -254.737943) (xy 333.785982 -254.720491) (xy 333.834201 -254.710647)
			(xy 333.883376 -254.708666) (xy 333.932231 -254.714598) (xy 333.979502 -254.72829) (xy 334.023964 -254.749388)
			(xy 334.064467 -254.777344) (xy 334.09996 -254.811436) (xy 334.129525 -254.85078) (xy 334.152396 -254.894357)
			(xy 334.16798 -254.941038) (xy 334.175875 -254.989615) (xy 334.17637 -255.014222) (xy 334.505312 -255.014222)
			(xy 334.509272 -254.965168) (xy 334.521049 -254.917384) (xy 334.54034 -254.872108) (xy 334.566643 -254.830512)
			(xy 334.599278 -254.793675) (xy 334.637399 -254.76255) (xy 334.68002 -254.737943) (xy 334.726036 -254.720491)
			(xy 334.774255 -254.710647) (xy 334.82343 -254.708666) (xy 334.872285 -254.714598) (xy 334.919556 -254.72829)
			(xy 334.964018 -254.749388) (xy 335.004521 -254.777344) (xy 335.040014 -254.811436) (xy 335.069579 -254.85078)
			(xy 335.09245 -254.894357) (xy 335.108034 -254.941038) (xy 335.115929 -254.989615) (xy 335.116424 -255.014222)
			(xy 335.445366 -255.014222) (xy 335.449326 -254.965168) (xy 335.461103 -254.917384) (xy 335.480394 -254.872108)
			(xy 335.506697 -254.830512) (xy 335.539332 -254.793675) (xy 335.577453 -254.76255) (xy 335.620074 -254.737943)
			(xy 335.66609 -254.720491) (xy 335.714309 -254.710647) (xy 335.763484 -254.708666) (xy 335.812339 -254.714598)
			(xy 335.85961 -254.72829) (xy 335.904072 -254.749388) (xy 335.944575 -254.777344) (xy 335.980068 -254.811436)
			(xy 336.009633 -254.85078) (xy 336.032504 -254.894357) (xy 336.048088 -254.941038) (xy 336.055983 -254.989615)
			(xy 336.056478 -255.014222) (xy 336.38542 -255.014222) (xy 336.38938 -254.965168) (xy 336.401157 -254.917384)
			(xy 336.420448 -254.872108) (xy 336.446751 -254.830512) (xy 336.479386 -254.793675) (xy 336.517507 -254.76255)
			(xy 336.560128 -254.737943) (xy 336.606144 -254.720491) (xy 336.654363 -254.710647) (xy 336.703538 -254.708666)
			(xy 336.752393 -254.714598) (xy 336.799664 -254.72829) (xy 336.844126 -254.749388) (xy 336.884629 -254.777344)
			(xy 336.920122 -254.811436) (xy 336.949687 -254.85078) (xy 336.972558 -254.894357) (xy 336.988142 -254.941038)
			(xy 336.996037 -254.989615) (xy 336.996532 -255.014222) (xy 337.32522 -255.014222) (xy 337.32918 -254.965168)
			(xy 337.340957 -254.917384) (xy 337.360248 -254.872108) (xy 337.386551 -254.830512) (xy 337.419186 -254.793675)
			(xy 337.457307 -254.76255) (xy 337.499928 -254.737943) (xy 337.545944 -254.720491) (xy 337.594163 -254.710647)
			(xy 337.643338 -254.708666) (xy 337.692193 -254.714598) (xy 337.739464 -254.72829) (xy 337.783926 -254.749388)
			(xy 337.824429 -254.777344) (xy 337.859922 -254.811436) (xy 337.889487 -254.85078) (xy 337.912358 -254.894357)
			(xy 337.927942 -254.941038) (xy 337.935837 -254.989615) (xy 337.936332 -255.014222) (xy 338.254843 -255.014222)
			(xy 338.258938 -254.963494) (xy 338.271117 -254.91408) (xy 338.291065 -254.86726) (xy 338.318266 -254.824246)
			(xy 338.352014 -254.786152) (xy 338.391436 -254.753965) (xy 338.43551 -254.728519) (xy 338.483096 -254.710472)
			(xy 338.53296 -254.700292) (xy 338.583812 -254.698243) (xy 338.634333 -254.704377) (xy 338.683217 -254.718537)
			(xy 338.729196 -254.740354) (xy 338.77108 -254.769264) (xy 338.807784 -254.804519) (xy 338.838357 -254.845205)
			(xy 338.862008 -254.890268) (xy 338.878124 -254.938542) (xy 338.886288 -254.988776) (xy 338.8868 -255.014222)
			(xy 339.205328 -255.014222) (xy 339.209288 -254.965168) (xy 339.221065 -254.917384) (xy 339.240356 -254.872108)
			(xy 339.266659 -254.830512) (xy 339.299294 -254.793675) (xy 339.337415 -254.76255) (xy 339.380036 -254.737943)
			(xy 339.426052 -254.720491) (xy 339.474271 -254.710647) (xy 339.523446 -254.708666) (xy 339.572301 -254.714598)
			(xy 339.619572 -254.72829) (xy 339.664034 -254.749388) (xy 339.704537 -254.777344) (xy 339.74003 -254.811436)
			(xy 339.769595 -254.85078) (xy 339.792466 -254.894357) (xy 339.80805 -254.941038) (xy 339.815945 -254.989615)
			(xy 339.81644 -255.014222) (xy 340.134951 -255.014222) (xy 340.139046 -254.963494) (xy 340.151225 -254.91408)
			(xy 340.171173 -254.86726) (xy 340.198374 -254.824246) (xy 340.232122 -254.786152) (xy 340.271544 -254.753965)
			(xy 340.315618 -254.728519) (xy 340.363204 -254.710472) (xy 340.413068 -254.700292) (xy 340.46392 -254.698243)
			(xy 340.514441 -254.704377) (xy 340.563325 -254.718537) (xy 340.609304 -254.740354) (xy 340.651188 -254.769264)
			(xy 340.687892 -254.804519) (xy 340.718465 -254.845205) (xy 340.742116 -254.890268) (xy 340.758232 -254.938542)
			(xy 340.766396 -254.988776) (xy 340.766908 -255.014222) (xy 341.085182 -255.014222) (xy 341.089142 -254.965168)
			(xy 341.100919 -254.917384) (xy 341.12021 -254.872108) (xy 341.146513 -254.830512) (xy 341.179148 -254.793675)
			(xy 341.217269 -254.76255) (xy 341.25989 -254.737943) (xy 341.305906 -254.720491) (xy 341.354125 -254.710647)
			(xy 341.4033 -254.708666) (xy 341.452155 -254.714598) (xy 341.499426 -254.72829) (xy 341.543888 -254.749388)
			(xy 341.584391 -254.777344) (xy 341.619884 -254.811436) (xy 341.649449 -254.85078) (xy 341.67232 -254.894357)
			(xy 341.687904 -254.941038) (xy 341.695799 -254.989615) (xy 341.696294 -255.014222) (xy 342.014805 -255.014222)
			(xy 342.0189 -254.963494) (xy 342.031079 -254.91408) (xy 342.051027 -254.86726) (xy 342.078228 -254.824246)
			(xy 342.111976 -254.786152) (xy 342.151398 -254.753965) (xy 342.195472 -254.728519) (xy 342.243058 -254.710472)
			(xy 342.292922 -254.700292) (xy 342.343774 -254.698243) (xy 342.394295 -254.704377) (xy 342.443179 -254.718537)
			(xy 342.489158 -254.740354) (xy 342.531042 -254.769264) (xy 342.567746 -254.804519) (xy 342.598319 -254.845205)
			(xy 342.62197 -254.890268) (xy 342.638086 -254.938542) (xy 342.64625 -254.988776) (xy 342.646762 -255.014222)
			(xy 342.954859 -255.014222) (xy 342.958954 -254.963494) (xy 342.971133 -254.91408) (xy 342.991081 -254.86726)
			(xy 343.018282 -254.824246) (xy 343.05203 -254.786152) (xy 343.091452 -254.753965) (xy 343.135526 -254.728519)
			(xy 343.183112 -254.710472) (xy 343.232976 -254.700292) (xy 343.283828 -254.698243) (xy 343.334349 -254.704377)
			(xy 343.383233 -254.718537) (xy 343.429212 -254.740354) (xy 343.471096 -254.769264) (xy 343.5078 -254.804519)
			(xy 343.538373 -254.845205) (xy 343.562024 -254.890268) (xy 343.57814 -254.938542) (xy 343.586304 -254.988776)
			(xy 343.586816 -255.014222) (xy 343.586304 -255.039668) (xy 343.57814 -255.089902) (xy 343.562024 -255.138176)
			(xy 343.538373 -255.183239) (xy 343.5078 -255.223925) (xy 343.471096 -255.25918) (xy 343.429212 -255.28809)
			(xy 343.383233 -255.309907) (xy 343.334349 -255.324067) (xy 343.283828 -255.330201) (xy 343.232976 -255.328152)
			(xy 343.183112 -255.317972) (xy 343.135526 -255.299925) (xy 343.091452 -255.274479) (xy 343.05203 -255.242292)
			(xy 343.018282 -255.204198) (xy 342.991081 -255.161184) (xy 342.971133 -255.114364) (xy 342.958954 -255.06495)
			(xy 342.954859 -255.014222) (xy 342.646762 -255.014222) (xy 342.64625 -255.039668) (xy 342.638086 -255.089902)
			(xy 342.62197 -255.138176) (xy 342.598319 -255.183239) (xy 342.567746 -255.223925) (xy 342.531042 -255.25918)
			(xy 342.489158 -255.28809) (xy 342.443179 -255.309907) (xy 342.394295 -255.324067) (xy 342.343774 -255.330201)
			(xy 342.292922 -255.328152) (xy 342.243058 -255.317972) (xy 342.195472 -255.299925) (xy 342.151398 -255.274479)
			(xy 342.111976 -255.242292) (xy 342.078228 -255.204198) (xy 342.051027 -255.161184) (xy 342.031079 -255.114364)
			(xy 342.0189 -255.06495) (xy 342.014805 -255.014222) (xy 341.696294 -255.014222) (xy 341.695799 -255.038829)
			(xy 341.687904 -255.087406) (xy 341.67232 -255.134087) (xy 341.649449 -255.177664) (xy 341.619884 -255.217008)
			(xy 341.584391 -255.2511) (xy 341.543888 -255.279056) (xy 341.499426 -255.300154) (xy 341.452155 -255.313846)
			(xy 341.4033 -255.319778) (xy 341.354125 -255.317797) (xy 341.305906 -255.307953) (xy 341.25989 -255.290501)
			(xy 341.217269 -255.265894) (xy 341.179148 -255.234769) (xy 341.146513 -255.197932) (xy 341.12021 -255.156336)
			(xy 341.100919 -255.11106) (xy 341.089142 -255.063276) (xy 341.085182 -255.014222) (xy 340.766908 -255.014222)
			(xy 340.766396 -255.039668) (xy 340.758232 -255.089902) (xy 340.742116 -255.138176) (xy 340.718465 -255.183239)
			(xy 340.687892 -255.223925) (xy 340.651188 -255.25918) (xy 340.609304 -255.28809) (xy 340.563325 -255.309907)
			(xy 340.514441 -255.324067) (xy 340.46392 -255.330201) (xy 340.413068 -255.328152) (xy 340.363204 -255.317972)
			(xy 340.315618 -255.299925) (xy 340.271544 -255.274479) (xy 340.232122 -255.242292) (xy 340.198374 -255.204198)
			(xy 340.171173 -255.161184) (xy 340.151225 -255.114364) (xy 340.139046 -255.06495) (xy 340.134951 -255.014222)
			(xy 339.81644 -255.014222) (xy 339.815945 -255.038829) (xy 339.80805 -255.087406) (xy 339.792466 -255.134087)
			(xy 339.769595 -255.177664) (xy 339.74003 -255.217008) (xy 339.704537 -255.2511) (xy 339.664034 -255.279056)
			(xy 339.619572 -255.300154) (xy 339.572301 -255.313846) (xy 339.523446 -255.319778) (xy 339.474271 -255.317797)
			(xy 339.426052 -255.307953) (xy 339.380036 -255.290501) (xy 339.337415 -255.265894) (xy 339.299294 -255.234769)
			(xy 339.266659 -255.197932) (xy 339.240356 -255.156336) (xy 339.221065 -255.11106) (xy 339.209288 -255.063276)
			(xy 339.205328 -255.014222) (xy 338.8868 -255.014222) (xy 338.886288 -255.039668) (xy 338.878124 -255.089902)
			(xy 338.862008 -255.138176) (xy 338.838357 -255.183239) (xy 338.807784 -255.223925) (xy 338.77108 -255.25918)
			(xy 338.729196 -255.28809) (xy 338.683217 -255.309907) (xy 338.634333 -255.324067) (xy 338.583812 -255.330201)
			(xy 338.53296 -255.328152) (xy 338.483096 -255.317972) (xy 338.43551 -255.299925) (xy 338.391436 -255.274479)
			(xy 338.352014 -255.242292) (xy 338.318266 -255.204198) (xy 338.291065 -255.161184) (xy 338.271117 -255.114364)
			(xy 338.258938 -255.06495) (xy 338.254843 -255.014222) (xy 337.936332 -255.014222) (xy 337.935837 -255.038829)
			(xy 337.927942 -255.087406) (xy 337.912358 -255.134087) (xy 337.889487 -255.177664) (xy 337.859922 -255.217008)
			(xy 337.824429 -255.2511) (xy 337.783926 -255.279056) (xy 337.739464 -255.300154) (xy 337.692193 -255.313846)
			(xy 337.643338 -255.319778) (xy 337.594163 -255.317797) (xy 337.545944 -255.307953) (xy 337.499928 -255.290501)
			(xy 337.457307 -255.265894) (xy 337.419186 -255.234769) (xy 337.386551 -255.197932) (xy 337.360248 -255.156336)
			(xy 337.340957 -255.11106) (xy 337.32918 -255.063276) (xy 337.32522 -255.014222) (xy 336.996532 -255.014222)
			(xy 336.996037 -255.038829) (xy 336.988142 -255.087406) (xy 336.972558 -255.134087) (xy 336.949687 -255.177664)
			(xy 336.920122 -255.217008) (xy 336.884629 -255.2511) (xy 336.844126 -255.279056) (xy 336.799664 -255.300154)
			(xy 336.752393 -255.313846) (xy 336.703538 -255.319778) (xy 336.654363 -255.317797) (xy 336.606144 -255.307953)
			(xy 336.560128 -255.290501) (xy 336.517507 -255.265894) (xy 336.479386 -255.234769) (xy 336.446751 -255.197932)
			(xy 336.420448 -255.156336) (xy 336.401157 -255.11106) (xy 336.38938 -255.063276) (xy 336.38542 -255.014222)
			(xy 336.056478 -255.014222) (xy 336.055983 -255.038829) (xy 336.048088 -255.087406) (xy 336.032504 -255.134087)
			(xy 336.009633 -255.177664) (xy 335.980068 -255.217008) (xy 335.944575 -255.2511) (xy 335.904072 -255.279056)
			(xy 335.85961 -255.300154) (xy 335.812339 -255.313846) (xy 335.763484 -255.319778) (xy 335.714309 -255.317797)
			(xy 335.66609 -255.307953) (xy 335.620074 -255.290501) (xy 335.577453 -255.265894) (xy 335.539332 -255.234769)
			(xy 335.506697 -255.197932) (xy 335.480394 -255.156336) (xy 335.461103 -255.11106) (xy 335.449326 -255.063276)
			(xy 335.445366 -255.014222) (xy 335.116424 -255.014222) (xy 335.115929 -255.038829) (xy 335.108034 -255.087406)
			(xy 335.09245 -255.134087) (xy 335.069579 -255.177664) (xy 335.040014 -255.217008) (xy 335.004521 -255.2511)
			(xy 334.964018 -255.279056) (xy 334.919556 -255.300154) (xy 334.872285 -255.313846) (xy 334.82343 -255.319778)
			(xy 334.774255 -255.317797) (xy 334.726036 -255.307953) (xy 334.68002 -255.290501) (xy 334.637399 -255.265894)
			(xy 334.599278 -255.234769) (xy 334.566643 -255.197932) (xy 334.54034 -255.156336) (xy 334.521049 -255.11106)
			(xy 334.509272 -255.063276) (xy 334.505312 -255.014222) (xy 334.17637 -255.014222) (xy 334.175875 -255.038829)
			(xy 334.16798 -255.087406) (xy 334.152396 -255.134087) (xy 334.129525 -255.177664) (xy 334.09996 -255.217008)
			(xy 334.064467 -255.2511) (xy 334.023964 -255.279056) (xy 333.979502 -255.300154) (xy 333.932231 -255.313846)
			(xy 333.883376 -255.319778) (xy 333.834201 -255.317797) (xy 333.785982 -255.307953) (xy 333.739966 -255.290501)
			(xy 333.697345 -255.265894) (xy 333.659224 -255.234769) (xy 333.626589 -255.197932) (xy 333.600286 -255.156336)
			(xy 333.580995 -255.11106) (xy 333.569218 -255.063276) (xy 333.565258 -255.014222) (xy 333.236316 -255.014222)
			(xy 333.235821 -255.038829) (xy 333.227926 -255.087406) (xy 333.212342 -255.134087) (xy 333.189471 -255.177664)
			(xy 333.159906 -255.217008) (xy 333.124413 -255.2511) (xy 333.08391 -255.279056) (xy 333.039448 -255.300154)
			(xy 332.992177 -255.313846) (xy 332.943322 -255.319778) (xy 332.894147 -255.317797) (xy 332.845928 -255.307953)
			(xy 332.799912 -255.290501) (xy 332.757291 -255.265894) (xy 332.71917 -255.234769) (xy 332.686535 -255.197932)
			(xy 332.660232 -255.156336) (xy 332.640941 -255.11106) (xy 332.629164 -255.063276) (xy 332.625204 -255.014222)
			(xy 332.296516 -255.014222) (xy 332.296021 -255.038829) (xy 332.288126 -255.087406) (xy 332.272542 -255.134087)
			(xy 332.249671 -255.177664) (xy 332.220106 -255.217008) (xy 332.184613 -255.2511) (xy 332.14411 -255.279056)
			(xy 332.099648 -255.300154) (xy 332.052377 -255.313846) (xy 332.003522 -255.319778) (xy 331.954347 -255.317797)
			(xy 331.906128 -255.307953) (xy 331.860112 -255.290501) (xy 331.817491 -255.265894) (xy 331.77937 -255.234769)
			(xy 331.746735 -255.197932) (xy 331.720432 -255.156336) (xy 331.701141 -255.11106) (xy 331.689364 -255.063276)
			(xy 331.685404 -255.014222) (xy 331.459332 -255.014222) (xy 331.459332 -255.420368) (xy 331.459804 -255.429726)
			(xy 331.46657 -255.447183) (xy 331.47254 -255.454404) (xy 331.517498 -255.503934) (xy 331.520811 -255.507401)
			(xy 331.528482 -255.513153) (xy 331.532738 -255.515364) (xy 331.540612 -255.519174) (xy 331.550264 -255.52019)
			(xy 331.550518 -255.52019) (xy 331.575385 -255.523101) (xy 331.623763 -255.535985) (xy 331.669392 -255.556586)
			(xy 331.71105 -255.584353) (xy 331.747622 -255.618542) (xy 331.778129 -255.658237) (xy 331.801754 -255.702376)
			(xy 331.817864 -255.749777) (xy 331.826028 -255.799171) (xy 331.826028 -255.824228) (xy 332.155304 -255.824228)
			(xy 332.159264 -255.775174) (xy 332.171041 -255.72739) (xy 332.190332 -255.682114) (xy 332.216635 -255.640518)
			(xy 332.24927 -255.603681) (xy 332.287391 -255.572556) (xy 332.330012 -255.547949) (xy 332.376028 -255.530497)
			(xy 332.424247 -255.520653) (xy 332.473422 -255.518672) (xy 332.522277 -255.524604) (xy 332.569548 -255.538296)
			(xy 332.61401 -255.559394) (xy 332.654513 -255.58735) (xy 332.690006 -255.621442) (xy 332.719571 -255.660786)
			(xy 332.742442 -255.704363) (xy 332.758026 -255.751044) (xy 332.765921 -255.799621) (xy 332.766416 -255.824228)
			(xy 333.095358 -255.824228) (xy 333.099318 -255.775174) (xy 333.111095 -255.72739) (xy 333.130386 -255.682114)
			(xy 333.156689 -255.640518) (xy 333.189324 -255.603681) (xy 333.227445 -255.572556) (xy 333.270066 -255.547949)
			(xy 333.316082 -255.530497) (xy 333.364301 -255.520653) (xy 333.413476 -255.518672) (xy 333.462331 -255.524604)
			(xy 333.509602 -255.538296) (xy 333.554064 -255.559394) (xy 333.594567 -255.58735) (xy 333.63006 -255.621442)
			(xy 333.659625 -255.660786) (xy 333.682496 -255.704363) (xy 333.69808 -255.751044) (xy 333.705975 -255.799621)
			(xy 333.70647 -255.824228) (xy 334.035412 -255.824228) (xy 334.039372 -255.775174) (xy 334.051149 -255.72739)
			(xy 334.07044 -255.682114) (xy 334.096743 -255.640518) (xy 334.129378 -255.603681) (xy 334.167499 -255.572556)
			(xy 334.21012 -255.547949) (xy 334.256136 -255.530497) (xy 334.304355 -255.520653) (xy 334.35353 -255.518672)
			(xy 334.402385 -255.524604) (xy 334.449656 -255.538296) (xy 334.494118 -255.559394) (xy 334.534621 -255.58735)
			(xy 334.570114 -255.621442) (xy 334.599679 -255.660786) (xy 334.62255 -255.704363) (xy 334.638134 -255.751044)
			(xy 334.646029 -255.799621) (xy 334.646524 -255.824228) (xy 334.975212 -255.824228) (xy 334.979172 -255.775174)
			(xy 334.990949 -255.72739) (xy 335.01024 -255.682114) (xy 335.036543 -255.640518) (xy 335.069178 -255.603681)
			(xy 335.107299 -255.572556) (xy 335.14992 -255.547949) (xy 335.195936 -255.530497) (xy 335.244155 -255.520653)
			(xy 335.29333 -255.518672) (xy 335.342185 -255.524604) (xy 335.389456 -255.538296) (xy 335.433918 -255.559394)
			(xy 335.474421 -255.58735) (xy 335.509914 -255.621442) (xy 335.539479 -255.660786) (xy 335.56235 -255.704363)
			(xy 335.577934 -255.751044) (xy 335.585829 -255.799621) (xy 335.586324 -255.824228) (xy 335.915266 -255.824228)
			(xy 335.919226 -255.775174) (xy 335.931003 -255.72739) (xy 335.950294 -255.682114) (xy 335.976597 -255.640518)
			(xy 336.009232 -255.603681) (xy 336.047353 -255.572556) (xy 336.089974 -255.547949) (xy 336.13599 -255.530497)
			(xy 336.184209 -255.520653) (xy 336.233384 -255.518672) (xy 336.282239 -255.524604) (xy 336.32951 -255.538296)
			(xy 336.373972 -255.559394) (xy 336.414475 -255.58735) (xy 336.449968 -255.621442) (xy 336.479533 -255.660786)
			(xy 336.502404 -255.704363) (xy 336.517988 -255.751044) (xy 336.525883 -255.799621) (xy 336.526378 -255.824228)
			(xy 336.85532 -255.824228) (xy 336.85928 -255.775174) (xy 336.871057 -255.72739) (xy 336.890348 -255.682114)
			(xy 336.916651 -255.640518) (xy 336.949286 -255.603681) (xy 336.987407 -255.572556) (xy 337.030028 -255.547949)
			(xy 337.076044 -255.530497) (xy 337.124263 -255.520653) (xy 337.173438 -255.518672) (xy 337.222293 -255.524604)
			(xy 337.269564 -255.538296) (xy 337.314026 -255.559394) (xy 337.354529 -255.58735) (xy 337.390022 -255.621442)
			(xy 337.419587 -255.660786) (xy 337.442458 -255.704363) (xy 337.458042 -255.751044) (xy 337.465937 -255.799621)
			(xy 337.466432 -255.824228) (xy 337.795374 -255.824228) (xy 337.799334 -255.775174) (xy 337.811111 -255.72739)
			(xy 337.830402 -255.682114) (xy 337.856705 -255.640518) (xy 337.88934 -255.603681) (xy 337.927461 -255.572556)
			(xy 337.970082 -255.547949) (xy 338.016098 -255.530497) (xy 338.064317 -255.520653) (xy 338.113492 -255.518672)
			(xy 338.162347 -255.524604) (xy 338.209618 -255.538296) (xy 338.25408 -255.559394) (xy 338.294583 -255.58735)
			(xy 338.330076 -255.621442) (xy 338.359641 -255.660786) (xy 338.382512 -255.704363) (xy 338.398096 -255.751044)
			(xy 338.405991 -255.799621) (xy 338.406486 -255.824228) (xy 338.724743 -255.824228) (xy 338.728838 -255.7735)
			(xy 338.741017 -255.724086) (xy 338.760965 -255.677266) (xy 338.788166 -255.634252) (xy 338.821914 -255.596158)
			(xy 338.861336 -255.563971) (xy 338.90541 -255.538525) (xy 338.952996 -255.520478) (xy 339.00286 -255.510298)
			(xy 339.053712 -255.508249) (xy 339.104233 -255.514383) (xy 339.153117 -255.528543) (xy 339.199096 -255.55036)
			(xy 339.24098 -255.57927) (xy 339.277684 -255.614525) (xy 339.308257 -255.655211) (xy 339.331908 -255.700274)
			(xy 339.348024 -255.748548) (xy 339.356188 -255.798782) (xy 339.3567 -255.824228) (xy 339.664797 -255.824228)
			(xy 339.668892 -255.7735) (xy 339.681071 -255.724086) (xy 339.701019 -255.677266) (xy 339.72822 -255.634252)
			(xy 339.761968 -255.596158) (xy 339.80139 -255.563971) (xy 339.845464 -255.538525) (xy 339.89305 -255.520478)
			(xy 339.942914 -255.510298) (xy 339.993766 -255.508249) (xy 340.044287 -255.514383) (xy 340.093171 -255.528543)
			(xy 340.13915 -255.55036) (xy 340.181034 -255.57927) (xy 340.217738 -255.614525) (xy 340.248311 -255.655211)
			(xy 340.271962 -255.700274) (xy 340.288078 -255.748548) (xy 340.296242 -255.798782) (xy 340.296754 -255.824228)
			(xy 340.615282 -255.824228) (xy 340.619242 -255.775174) (xy 340.631019 -255.72739) (xy 340.65031 -255.682114)
			(xy 340.676613 -255.640518) (xy 340.709248 -255.603681) (xy 340.747369 -255.572556) (xy 340.78999 -255.547949)
			(xy 340.836006 -255.530497) (xy 340.884225 -255.520653) (xy 340.9334 -255.518672) (xy 340.982255 -255.524604)
			(xy 341.029526 -255.538296) (xy 341.073988 -255.559394) (xy 341.114491 -255.58735) (xy 341.149984 -255.621442)
			(xy 341.179549 -255.660786) (xy 341.20242 -255.704363) (xy 341.218004 -255.751044) (xy 341.225899 -255.799621)
			(xy 341.226394 -255.824228) (xy 341.544905 -255.824228) (xy 341.549 -255.7735) (xy 341.561179 -255.724086)
			(xy 341.581127 -255.677266) (xy 341.608328 -255.634252) (xy 341.642076 -255.596158) (xy 341.681498 -255.563971)
			(xy 341.725572 -255.538525) (xy 341.773158 -255.520478) (xy 341.823022 -255.510298) (xy 341.873874 -255.508249)
			(xy 341.924395 -255.514383) (xy 341.973279 -255.528543) (xy 342.019258 -255.55036) (xy 342.061142 -255.57927)
			(xy 342.097846 -255.614525) (xy 342.128419 -255.655211) (xy 342.15207 -255.700274) (xy 342.168186 -255.748548)
			(xy 342.17635 -255.798782) (xy 342.176862 -255.824228) (xy 342.49539 -255.824228) (xy 342.49935 -255.775174)
			(xy 342.511127 -255.72739) (xy 342.530418 -255.682114) (xy 342.556721 -255.640518) (xy 342.589356 -255.603681)
			(xy 342.627477 -255.572556) (xy 342.670098 -255.547949) (xy 342.716114 -255.530497) (xy 342.764333 -255.520653)
			(xy 342.813508 -255.518672) (xy 342.862363 -255.524604) (xy 342.909634 -255.538296) (xy 342.954096 -255.559394)
			(xy 342.994599 -255.58735) (xy 343.030092 -255.621442) (xy 343.059657 -255.660786) (xy 343.082528 -255.704363)
			(xy 343.098112 -255.751044) (xy 343.106007 -255.799621) (xy 343.106502 -255.824228) (xy 343.106007 -255.848835)
			(xy 343.098112 -255.897412) (xy 343.082528 -255.944093) (xy 343.059657 -255.98767) (xy 343.030092 -256.027014)
			(xy 342.994599 -256.061106) (xy 342.954096 -256.089062) (xy 342.909634 -256.11016) (xy 342.862363 -256.123852)
			(xy 342.813508 -256.129784) (xy 342.764333 -256.127803) (xy 342.716114 -256.117959) (xy 342.670098 -256.100507)
			(xy 342.627477 -256.0759) (xy 342.589356 -256.044775) (xy 342.556721 -256.007938) (xy 342.530418 -255.966342)
			(xy 342.511127 -255.921066) (xy 342.49935 -255.873282) (xy 342.49539 -255.824228) (xy 342.176862 -255.824228)
			(xy 342.17635 -255.849674) (xy 342.168186 -255.899908) (xy 342.15207 -255.948182) (xy 342.128419 -255.993245)
			(xy 342.097846 -256.033931) (xy 342.061142 -256.069186) (xy 342.019258 -256.098096) (xy 341.973279 -256.119913)
			(xy 341.924395 -256.134073) (xy 341.873874 -256.140207) (xy 341.823022 -256.138158) (xy 341.773158 -256.127978)
			(xy 341.725572 -256.109931) (xy 341.681498 -256.084485) (xy 341.642076 -256.052298) (xy 341.608328 -256.014204)
			(xy 341.581127 -255.97119) (xy 341.561179 -255.92437) (xy 341.549 -255.874956) (xy 341.544905 -255.824228)
			(xy 341.226394 -255.824228) (xy 341.225899 -255.848835) (xy 341.218004 -255.897412) (xy 341.20242 -255.944093)
			(xy 341.179549 -255.98767) (xy 341.149984 -256.027014) (xy 341.114491 -256.061106) (xy 341.073988 -256.089062)
			(xy 341.029526 -256.11016) (xy 340.982255 -256.123852) (xy 340.9334 -256.129784) (xy 340.884225 -256.127803)
			(xy 340.836006 -256.117959) (xy 340.78999 -256.100507) (xy 340.747369 -256.0759) (xy 340.709248 -256.044775)
			(xy 340.676613 -256.007938) (xy 340.65031 -255.966342) (xy 340.631019 -255.921066) (xy 340.619242 -255.873282)
			(xy 340.615282 -255.824228) (xy 340.296754 -255.824228) (xy 340.296242 -255.849674) (xy 340.288078 -255.899908)
			(xy 340.271962 -255.948182) (xy 340.248311 -255.993245) (xy 340.217738 -256.033931) (xy 340.181034 -256.069186)
			(xy 340.13915 -256.098096) (xy 340.093171 -256.119913) (xy 340.044287 -256.134073) (xy 339.993766 -256.140207)
			(xy 339.942914 -256.138158) (xy 339.89305 -256.127978) (xy 339.845464 -256.109931) (xy 339.80139 -256.084485)
			(xy 339.761968 -256.052298) (xy 339.72822 -256.014204) (xy 339.701019 -255.97119) (xy 339.681071 -255.92437)
			(xy 339.668892 -255.874956) (xy 339.664797 -255.824228) (xy 339.3567 -255.824228) (xy 339.356188 -255.849674)
			(xy 339.348024 -255.899908) (xy 339.331908 -255.948182) (xy 339.308257 -255.993245) (xy 339.277684 -256.033931)
			(xy 339.24098 -256.069186) (xy 339.199096 -256.098096) (xy 339.153117 -256.119913) (xy 339.104233 -256.134073)
			(xy 339.053712 -256.140207) (xy 339.00286 -256.138158) (xy 338.952996 -256.127978) (xy 338.90541 -256.109931)
			(xy 338.861336 -256.084485) (xy 338.821914 -256.052298) (xy 338.788166 -256.014204) (xy 338.760965 -255.97119)
			(xy 338.741017 -255.92437) (xy 338.728838 -255.874956) (xy 338.724743 -255.824228) (xy 338.406486 -255.824228)
			(xy 338.405991 -255.848835) (xy 338.398096 -255.897412) (xy 338.382512 -255.944093) (xy 338.359641 -255.98767)
			(xy 338.330076 -256.027014) (xy 338.294583 -256.061106) (xy 338.25408 -256.089062) (xy 338.209618 -256.11016)
			(xy 338.162347 -256.123852) (xy 338.113492 -256.129784) (xy 338.064317 -256.127803) (xy 338.016098 -256.117959)
			(xy 337.970082 -256.100507) (xy 337.927461 -256.0759) (xy 337.88934 -256.044775) (xy 337.856705 -256.007938)
			(xy 337.830402 -255.966342) (xy 337.811111 -255.921066) (xy 337.799334 -255.873282) (xy 337.795374 -255.824228)
			(xy 337.466432 -255.824228) (xy 337.465937 -255.848835) (xy 337.458042 -255.897412) (xy 337.442458 -255.944093)
			(xy 337.419587 -255.98767) (xy 337.390022 -256.027014) (xy 337.354529 -256.061106) (xy 337.314026 -256.089062)
			(xy 337.269564 -256.11016) (xy 337.222293 -256.123852) (xy 337.173438 -256.129784) (xy 337.124263 -256.127803)
			(xy 337.076044 -256.117959) (xy 337.030028 -256.100507) (xy 336.987407 -256.0759) (xy 336.949286 -256.044775)
			(xy 336.916651 -256.007938) (xy 336.890348 -255.966342) (xy 336.871057 -255.921066) (xy 336.85928 -255.873282)
			(xy 336.85532 -255.824228) (xy 336.526378 -255.824228) (xy 336.525883 -255.848835) (xy 336.517988 -255.897412)
			(xy 336.502404 -255.944093) (xy 336.479533 -255.98767) (xy 336.449968 -256.027014) (xy 336.414475 -256.061106)
			(xy 336.373972 -256.089062) (xy 336.32951 -256.11016) (xy 336.282239 -256.123852) (xy 336.233384 -256.129784)
			(xy 336.184209 -256.127803) (xy 336.13599 -256.117959) (xy 336.089974 -256.100507) (xy 336.047353 -256.0759)
			(xy 336.009232 -256.044775) (xy 335.976597 -256.007938) (xy 335.950294 -255.966342) (xy 335.931003 -255.921066)
			(xy 335.919226 -255.873282) (xy 335.915266 -255.824228) (xy 335.586324 -255.824228) (xy 335.585829 -255.848835)
			(xy 335.577934 -255.897412) (xy 335.56235 -255.944093) (xy 335.539479 -255.98767) (xy 335.509914 -256.027014)
			(xy 335.474421 -256.061106) (xy 335.433918 -256.089062) (xy 335.389456 -256.11016) (xy 335.342185 -256.123852)
			(xy 335.29333 -256.129784) (xy 335.244155 -256.127803) (xy 335.195936 -256.117959) (xy 335.14992 -256.100507)
			(xy 335.107299 -256.0759) (xy 335.069178 -256.044775) (xy 335.036543 -256.007938) (xy 335.01024 -255.966342)
			(xy 334.990949 -255.921066) (xy 334.979172 -255.873282) (xy 334.975212 -255.824228) (xy 334.646524 -255.824228)
			(xy 334.646029 -255.848835) (xy 334.638134 -255.897412) (xy 334.62255 -255.944093) (xy 334.599679 -255.98767)
			(xy 334.570114 -256.027014) (xy 334.534621 -256.061106) (xy 334.494118 -256.089062) (xy 334.449656 -256.11016)
			(xy 334.402385 -256.123852) (xy 334.35353 -256.129784) (xy 334.304355 -256.127803) (xy 334.256136 -256.117959)
			(xy 334.21012 -256.100507) (xy 334.167499 -256.0759) (xy 334.129378 -256.044775) (xy 334.096743 -256.007938)
			(xy 334.07044 -255.966342) (xy 334.051149 -255.921066) (xy 334.039372 -255.873282) (xy 334.035412 -255.824228)
			(xy 333.70647 -255.824228) (xy 333.705975 -255.848835) (xy 333.69808 -255.897412) (xy 333.682496 -255.944093)
			(xy 333.659625 -255.98767) (xy 333.63006 -256.027014) (xy 333.594567 -256.061106) (xy 333.554064 -256.089062)
			(xy 333.509602 -256.11016) (xy 333.462331 -256.123852) (xy 333.413476 -256.129784) (xy 333.364301 -256.127803)
			(xy 333.316082 -256.117959) (xy 333.270066 -256.100507) (xy 333.227445 -256.0759) (xy 333.189324 -256.044775)
			(xy 333.156689 -256.007938) (xy 333.130386 -255.966342) (xy 333.111095 -255.921066) (xy 333.099318 -255.873282)
			(xy 333.095358 -255.824228) (xy 332.766416 -255.824228) (xy 332.765921 -255.848835) (xy 332.758026 -255.897412)
			(xy 332.742442 -255.944093) (xy 332.719571 -255.98767) (xy 332.690006 -256.027014) (xy 332.654513 -256.061106)
			(xy 332.61401 -256.089062) (xy 332.569548 -256.11016) (xy 332.522277 -256.123852) (xy 332.473422 -256.129784)
			(xy 332.424247 -256.127803) (xy 332.376028 -256.117959) (xy 332.330012 -256.100507) (xy 332.287391 -256.0759)
			(xy 332.24927 -256.044775) (xy 332.216635 -256.007938) (xy 332.190332 -255.966342) (xy 332.171041 -255.921066)
			(xy 332.159264 -255.873282) (xy 332.155304 -255.824228) (xy 331.826028 -255.824228) (xy 331.826028 -255.849235)
			(xy 331.817863 -255.898628) (xy 331.801752 -255.946029) (xy 331.778126 -255.990168) (xy 331.747618 -256.029862)
			(xy 331.711046 -256.064051) (xy 331.669387 -256.091816) (xy 331.623758 -256.112417) (xy 331.57538 -256.1253)
			(xy 331.550518 -256.128266) (xy 331.550264 -256.128266) (xy 331.540612 -256.129282) (xy 331.532738 -256.133092)
			(xy 331.528476 -256.135293) (xy 331.520797 -256.14104) (xy 331.517498 -256.144522) (xy 331.47254 -256.194052)
			(xy 331.466487 -256.201224) (xy 331.459707 -256.21871) (xy 331.459332 -256.228088) (xy 331.459332 -256.634234)
			(xy 331.685404 -256.634234) (xy 331.689364 -256.58518) (xy 331.701141 -256.537396) (xy 331.720432 -256.49212)
			(xy 331.746735 -256.450524) (xy 331.77937 -256.413687) (xy 331.817491 -256.382562) (xy 331.860112 -256.357955)
			(xy 331.906128 -256.340503) (xy 331.954347 -256.330659) (xy 332.003522 -256.328678) (xy 332.052377 -256.33461)
			(xy 332.099648 -256.348302) (xy 332.14411 -256.3694) (xy 332.184613 -256.397356) (xy 332.220106 -256.431448)
			(xy 332.249671 -256.470792) (xy 332.272542 -256.514369) (xy 332.288126 -256.56105) (xy 332.296021 -256.609627)
			(xy 332.296516 -256.634234) (xy 332.625204 -256.634234) (xy 332.629164 -256.58518) (xy 332.640941 -256.537396)
			(xy 332.660232 -256.49212) (xy 332.686535 -256.450524) (xy 332.71917 -256.413687) (xy 332.757291 -256.382562)
			(xy 332.799912 -256.357955) (xy 332.845928 -256.340503) (xy 332.894147 -256.330659) (xy 332.943322 -256.328678)
			(xy 332.992177 -256.33461) (xy 333.039448 -256.348302) (xy 333.08391 -256.3694) (xy 333.124413 -256.397356)
			(xy 333.159906 -256.431448) (xy 333.189471 -256.470792) (xy 333.212342 -256.514369) (xy 333.227926 -256.56105)
			(xy 333.235821 -256.609627) (xy 333.236316 -256.634234) (xy 333.565258 -256.634234) (xy 333.569218 -256.58518)
			(xy 333.580995 -256.537396) (xy 333.600286 -256.49212) (xy 333.626589 -256.450524) (xy 333.659224 -256.413687)
			(xy 333.697345 -256.382562) (xy 333.739966 -256.357955) (xy 333.785982 -256.340503) (xy 333.834201 -256.330659)
			(xy 333.883376 -256.328678) (xy 333.932231 -256.33461) (xy 333.979502 -256.348302) (xy 334.023964 -256.3694)
			(xy 334.064467 -256.397356) (xy 334.09996 -256.431448) (xy 334.129525 -256.470792) (xy 334.152396 -256.514369)
			(xy 334.16798 -256.56105) (xy 334.175875 -256.609627) (xy 334.17637 -256.634234) (xy 334.505312 -256.634234)
			(xy 334.509272 -256.58518) (xy 334.521049 -256.537396) (xy 334.54034 -256.49212) (xy 334.566643 -256.450524)
			(xy 334.599278 -256.413687) (xy 334.637399 -256.382562) (xy 334.68002 -256.357955) (xy 334.726036 -256.340503)
			(xy 334.774255 -256.330659) (xy 334.82343 -256.328678) (xy 334.872285 -256.33461) (xy 334.919556 -256.348302)
			(xy 334.964018 -256.3694) (xy 335.004521 -256.397356) (xy 335.040014 -256.431448) (xy 335.069579 -256.470792)
			(xy 335.09245 -256.514369) (xy 335.108034 -256.56105) (xy 335.115929 -256.609627) (xy 335.116424 -256.634234)
			(xy 335.445366 -256.634234) (xy 335.449326 -256.58518) (xy 335.461103 -256.537396) (xy 335.480394 -256.49212)
			(xy 335.506697 -256.450524) (xy 335.539332 -256.413687) (xy 335.577453 -256.382562) (xy 335.620074 -256.357955)
			(xy 335.66609 -256.340503) (xy 335.714309 -256.330659) (xy 335.763484 -256.328678) (xy 335.812339 -256.33461)
			(xy 335.85961 -256.348302) (xy 335.904072 -256.3694) (xy 335.944575 -256.397356) (xy 335.980068 -256.431448)
			(xy 336.009633 -256.470792) (xy 336.032504 -256.514369) (xy 336.048088 -256.56105) (xy 336.055983 -256.609627)
			(xy 336.056478 -256.634234) (xy 336.38542 -256.634234) (xy 336.38938 -256.58518) (xy 336.401157 -256.537396)
			(xy 336.420448 -256.49212) (xy 336.446751 -256.450524) (xy 336.479386 -256.413687) (xy 336.517507 -256.382562)
			(xy 336.560128 -256.357955) (xy 336.606144 -256.340503) (xy 336.654363 -256.330659) (xy 336.703538 -256.328678)
			(xy 336.752393 -256.33461) (xy 336.799664 -256.348302) (xy 336.844126 -256.3694) (xy 336.884629 -256.397356)
			(xy 336.920122 -256.431448) (xy 336.949687 -256.470792) (xy 336.972558 -256.514369) (xy 336.988142 -256.56105)
			(xy 336.996037 -256.609627) (xy 336.996532 -256.634234) (xy 337.32522 -256.634234) (xy 337.32918 -256.58518)
			(xy 337.340957 -256.537396) (xy 337.360248 -256.49212) (xy 337.386551 -256.450524) (xy 337.419186 -256.413687)
			(xy 337.457307 -256.382562) (xy 337.499928 -256.357955) (xy 337.545944 -256.340503) (xy 337.594163 -256.330659)
			(xy 337.643338 -256.328678) (xy 337.692193 -256.33461) (xy 337.739464 -256.348302) (xy 337.783926 -256.3694)
			(xy 337.824429 -256.397356) (xy 337.859922 -256.431448) (xy 337.889487 -256.470792) (xy 337.912358 -256.514369)
			(xy 337.927942 -256.56105) (xy 337.935837 -256.609627) (xy 337.936332 -256.634234) (xy 338.254843 -256.634234)
			(xy 338.258938 -256.583506) (xy 338.271117 -256.534092) (xy 338.291065 -256.487272) (xy 338.318266 -256.444258)
			(xy 338.352014 -256.406164) (xy 338.391436 -256.373977) (xy 338.43551 -256.348531) (xy 338.483096 -256.330484)
			(xy 338.53296 -256.320304) (xy 338.583812 -256.318255) (xy 338.634333 -256.324389) (xy 338.683217 -256.338549)
			(xy 338.729196 -256.360366) (xy 338.77108 -256.389276) (xy 338.807784 -256.424531) (xy 338.838357 -256.465217)
			(xy 338.862008 -256.51028) (xy 338.878124 -256.558554) (xy 338.886288 -256.608788) (xy 338.8868 -256.634234)
			(xy 339.205328 -256.634234) (xy 339.209288 -256.58518) (xy 339.221065 -256.537396) (xy 339.240356 -256.49212)
			(xy 339.266659 -256.450524) (xy 339.299294 -256.413687) (xy 339.337415 -256.382562) (xy 339.380036 -256.357955)
			(xy 339.426052 -256.340503) (xy 339.474271 -256.330659) (xy 339.523446 -256.328678) (xy 339.572301 -256.33461)
			(xy 339.619572 -256.348302) (xy 339.664034 -256.3694) (xy 339.704537 -256.397356) (xy 339.74003 -256.431448)
			(xy 339.769595 -256.470792) (xy 339.792466 -256.514369) (xy 339.80805 -256.56105) (xy 339.815945 -256.609627)
			(xy 339.81644 -256.634234) (xy 340.145382 -256.634234) (xy 340.149342 -256.58518) (xy 340.161119 -256.537396)
			(xy 340.18041 -256.49212) (xy 340.206713 -256.450524) (xy 340.239348 -256.413687) (xy 340.277469 -256.382562)
			(xy 340.32009 -256.357955) (xy 340.366106 -256.340503) (xy 340.414325 -256.330659) (xy 340.4635 -256.328678)
			(xy 340.512355 -256.33461) (xy 340.559626 -256.348302) (xy 340.604088 -256.3694) (xy 340.644591 -256.397356)
			(xy 340.680084 -256.431448) (xy 340.709649 -256.470792) (xy 340.73252 -256.514369) (xy 340.748104 -256.56105)
			(xy 340.755999 -256.609627) (xy 340.756494 -256.634234) (xy 341.085182 -256.634234) (xy 341.089142 -256.58518)
			(xy 341.100919 -256.537396) (xy 341.12021 -256.49212) (xy 341.146513 -256.450524) (xy 341.179148 -256.413687)
			(xy 341.217269 -256.382562) (xy 341.25989 -256.357955) (xy 341.305906 -256.340503) (xy 341.354125 -256.330659)
			(xy 341.4033 -256.328678) (xy 341.452155 -256.33461) (xy 341.499426 -256.348302) (xy 341.543888 -256.3694)
			(xy 341.584391 -256.397356) (xy 341.619884 -256.431448) (xy 341.649449 -256.470792) (xy 341.67232 -256.514369)
			(xy 341.687904 -256.56105) (xy 341.695799 -256.609627) (xy 341.696294 -256.634234) (xy 342.014805 -256.634234)
			(xy 342.0189 -256.583506) (xy 342.031079 -256.534092) (xy 342.051027 -256.487272) (xy 342.078228 -256.444258)
			(xy 342.111976 -256.406164) (xy 342.151398 -256.373977) (xy 342.195472 -256.348531) (xy 342.243058 -256.330484)
			(xy 342.292922 -256.320304) (xy 342.343774 -256.318255) (xy 342.394295 -256.324389) (xy 342.443179 -256.338549)
			(xy 342.489158 -256.360366) (xy 342.531042 -256.389276) (xy 342.567746 -256.424531) (xy 342.598319 -256.465217)
			(xy 342.62197 -256.51028) (xy 342.638086 -256.558554) (xy 342.64625 -256.608788) (xy 342.646762 -256.634234)
			(xy 342.96529 -256.634234) (xy 342.96925 -256.58518) (xy 342.981027 -256.537396) (xy 343.000318 -256.49212)
			(xy 343.026621 -256.450524) (xy 343.059256 -256.413687) (xy 343.097377 -256.382562) (xy 343.139998 -256.357955)
			(xy 343.186014 -256.340503) (xy 343.234233 -256.330659) (xy 343.283408 -256.328678) (xy 343.332263 -256.33461)
			(xy 343.379534 -256.348302) (xy 343.423996 -256.3694) (xy 343.464499 -256.397356) (xy 343.499992 -256.431448)
			(xy 343.529557 -256.470792) (xy 343.552428 -256.514369) (xy 343.568012 -256.56105) (xy 343.575907 -256.609627)
			(xy 343.576402 -256.634234) (xy 343.575907 -256.658841) (xy 343.568012 -256.707418) (xy 343.552428 -256.754099)
			(xy 343.529557 -256.797676) (xy 343.499992 -256.83702) (xy 343.464499 -256.871112) (xy 343.423996 -256.899068)
			(xy 343.379534 -256.920166) (xy 343.332263 -256.933858) (xy 343.283408 -256.93979) (xy 343.234233 -256.937809)
			(xy 343.186014 -256.927965) (xy 343.139998 -256.910513) (xy 343.097377 -256.885906) (xy 343.059256 -256.854781)
			(xy 343.026621 -256.817944) (xy 343.000318 -256.776348) (xy 342.981027 -256.731072) (xy 342.96925 -256.683288)
			(xy 342.96529 -256.634234) (xy 342.646762 -256.634234) (xy 342.64625 -256.65968) (xy 342.638086 -256.709914)
			(xy 342.62197 -256.758188) (xy 342.598319 -256.803251) (xy 342.567746 -256.843937) (xy 342.531042 -256.879192)
			(xy 342.489158 -256.908102) (xy 342.443179 -256.929919) (xy 342.394295 -256.944079) (xy 342.343774 -256.950213)
			(xy 342.292922 -256.948164) (xy 342.243058 -256.937984) (xy 342.195472 -256.919937) (xy 342.151398 -256.894491)
			(xy 342.111976 -256.862304) (xy 342.078228 -256.82421) (xy 342.051027 -256.781196) (xy 342.031079 -256.734376)
			(xy 342.0189 -256.684962) (xy 342.014805 -256.634234) (xy 341.696294 -256.634234) (xy 341.695799 -256.658841)
			(xy 341.687904 -256.707418) (xy 341.67232 -256.754099) (xy 341.649449 -256.797676) (xy 341.619884 -256.83702)
			(xy 341.584391 -256.871112) (xy 341.543888 -256.899068) (xy 341.499426 -256.920166) (xy 341.452155 -256.933858)
			(xy 341.4033 -256.93979) (xy 341.354125 -256.937809) (xy 341.305906 -256.927965) (xy 341.25989 -256.910513)
			(xy 341.217269 -256.885906) (xy 341.179148 -256.854781) (xy 341.146513 -256.817944) (xy 341.12021 -256.776348)
			(xy 341.100919 -256.731072) (xy 341.089142 -256.683288) (xy 341.085182 -256.634234) (xy 340.756494 -256.634234)
			(xy 340.755999 -256.658841) (xy 340.748104 -256.707418) (xy 340.73252 -256.754099) (xy 340.709649 -256.797676)
			(xy 340.680084 -256.83702) (xy 340.644591 -256.871112) (xy 340.604088 -256.899068) (xy 340.559626 -256.920166)
			(xy 340.512355 -256.933858) (xy 340.4635 -256.93979) (xy 340.414325 -256.937809) (xy 340.366106 -256.927965)
			(xy 340.32009 -256.910513) (xy 340.277469 -256.885906) (xy 340.239348 -256.854781) (xy 340.206713 -256.817944)
			(xy 340.18041 -256.776348) (xy 340.161119 -256.731072) (xy 340.149342 -256.683288) (xy 340.145382 -256.634234)
			(xy 339.81644 -256.634234) (xy 339.815945 -256.658841) (xy 339.80805 -256.707418) (xy 339.792466 -256.754099)
			(xy 339.769595 -256.797676) (xy 339.74003 -256.83702) (xy 339.704537 -256.871112) (xy 339.664034 -256.899068)
			(xy 339.619572 -256.920166) (xy 339.572301 -256.933858) (xy 339.523446 -256.93979) (xy 339.474271 -256.937809)
			(xy 339.426052 -256.927965) (xy 339.380036 -256.910513) (xy 339.337415 -256.885906) (xy 339.299294 -256.854781)
			(xy 339.266659 -256.817944) (xy 339.240356 -256.776348) (xy 339.221065 -256.731072) (xy 339.209288 -256.683288)
			(xy 339.205328 -256.634234) (xy 338.8868 -256.634234) (xy 338.886288 -256.65968) (xy 338.878124 -256.709914)
			(xy 338.862008 -256.758188) (xy 338.838357 -256.803251) (xy 338.807784 -256.843937) (xy 338.77108 -256.879192)
			(xy 338.729196 -256.908102) (xy 338.683217 -256.929919) (xy 338.634333 -256.944079) (xy 338.583812 -256.950213)
			(xy 338.53296 -256.948164) (xy 338.483096 -256.937984) (xy 338.43551 -256.919937) (xy 338.391436 -256.894491)
			(xy 338.352014 -256.862304) (xy 338.318266 -256.82421) (xy 338.291065 -256.781196) (xy 338.271117 -256.734376)
			(xy 338.258938 -256.684962) (xy 338.254843 -256.634234) (xy 337.936332 -256.634234) (xy 337.935837 -256.658841)
			(xy 337.927942 -256.707418) (xy 337.912358 -256.754099) (xy 337.889487 -256.797676) (xy 337.859922 -256.83702)
			(xy 337.824429 -256.871112) (xy 337.783926 -256.899068) (xy 337.739464 -256.920166) (xy 337.692193 -256.933858)
			(xy 337.643338 -256.93979) (xy 337.594163 -256.937809) (xy 337.545944 -256.927965) (xy 337.499928 -256.910513)
			(xy 337.457307 -256.885906) (xy 337.419186 -256.854781) (xy 337.386551 -256.817944) (xy 337.360248 -256.776348)
			(xy 337.340957 -256.731072) (xy 337.32918 -256.683288) (xy 337.32522 -256.634234) (xy 336.996532 -256.634234)
			(xy 336.996037 -256.658841) (xy 336.988142 -256.707418) (xy 336.972558 -256.754099) (xy 336.949687 -256.797676)
			(xy 336.920122 -256.83702) (xy 336.884629 -256.871112) (xy 336.844126 -256.899068) (xy 336.799664 -256.920166)
			(xy 336.752393 -256.933858) (xy 336.703538 -256.93979) (xy 336.654363 -256.937809) (xy 336.606144 -256.927965)
			(xy 336.560128 -256.910513) (xy 336.517507 -256.885906) (xy 336.479386 -256.854781) (xy 336.446751 -256.817944)
			(xy 336.420448 -256.776348) (xy 336.401157 -256.731072) (xy 336.38938 -256.683288) (xy 336.38542 -256.634234)
			(xy 336.056478 -256.634234) (xy 336.055983 -256.658841) (xy 336.048088 -256.707418) (xy 336.032504 -256.754099)
			(xy 336.009633 -256.797676) (xy 335.980068 -256.83702) (xy 335.944575 -256.871112) (xy 335.904072 -256.899068)
			(xy 335.85961 -256.920166) (xy 335.812339 -256.933858) (xy 335.763484 -256.93979) (xy 335.714309 -256.937809)
			(xy 335.66609 -256.927965) (xy 335.620074 -256.910513) (xy 335.577453 -256.885906) (xy 335.539332 -256.854781)
			(xy 335.506697 -256.817944) (xy 335.480394 -256.776348) (xy 335.461103 -256.731072) (xy 335.449326 -256.683288)
			(xy 335.445366 -256.634234) (xy 335.116424 -256.634234) (xy 335.115929 -256.658841) (xy 335.108034 -256.707418)
			(xy 335.09245 -256.754099) (xy 335.069579 -256.797676) (xy 335.040014 -256.83702) (xy 335.004521 -256.871112)
			(xy 334.964018 -256.899068) (xy 334.919556 -256.920166) (xy 334.872285 -256.933858) (xy 334.82343 -256.93979)
			(xy 334.774255 -256.937809) (xy 334.726036 -256.927965) (xy 334.68002 -256.910513) (xy 334.637399 -256.885906)
			(xy 334.599278 -256.854781) (xy 334.566643 -256.817944) (xy 334.54034 -256.776348) (xy 334.521049 -256.731072)
			(xy 334.509272 -256.683288) (xy 334.505312 -256.634234) (xy 334.17637 -256.634234) (xy 334.175875 -256.658841)
			(xy 334.16798 -256.707418) (xy 334.152396 -256.754099) (xy 334.129525 -256.797676) (xy 334.09996 -256.83702)
			(xy 334.064467 -256.871112) (xy 334.023964 -256.899068) (xy 333.979502 -256.920166) (xy 333.932231 -256.933858)
			(xy 333.883376 -256.93979) (xy 333.834201 -256.937809) (xy 333.785982 -256.927965) (xy 333.739966 -256.910513)
			(xy 333.697345 -256.885906) (xy 333.659224 -256.854781) (xy 333.626589 -256.817944) (xy 333.600286 -256.776348)
			(xy 333.580995 -256.731072) (xy 333.569218 -256.683288) (xy 333.565258 -256.634234) (xy 333.236316 -256.634234)
			(xy 333.235821 -256.658841) (xy 333.227926 -256.707418) (xy 333.212342 -256.754099) (xy 333.189471 -256.797676)
			(xy 333.159906 -256.83702) (xy 333.124413 -256.871112) (xy 333.08391 -256.899068) (xy 333.039448 -256.920166)
			(xy 332.992177 -256.933858) (xy 332.943322 -256.93979) (xy 332.894147 -256.937809) (xy 332.845928 -256.927965)
			(xy 332.799912 -256.910513) (xy 332.757291 -256.885906) (xy 332.71917 -256.854781) (xy 332.686535 -256.817944)
			(xy 332.660232 -256.776348) (xy 332.640941 -256.731072) (xy 332.629164 -256.683288) (xy 332.625204 -256.634234)
			(xy 332.296516 -256.634234) (xy 332.296021 -256.658841) (xy 332.288126 -256.707418) (xy 332.272542 -256.754099)
			(xy 332.249671 -256.797676) (xy 332.220106 -256.83702) (xy 332.184613 -256.871112) (xy 332.14411 -256.899068)
			(xy 332.099648 -256.920166) (xy 332.052377 -256.933858) (xy 332.003522 -256.93979) (xy 331.954347 -256.937809)
			(xy 331.906128 -256.927965) (xy 331.860112 -256.910513) (xy 331.817491 -256.885906) (xy 331.77937 -256.854781)
			(xy 331.746735 -256.817944) (xy 331.720432 -256.776348) (xy 331.701141 -256.731072) (xy 331.689364 -256.683288)
			(xy 331.685404 -256.634234) (xy 331.459332 -256.634234) (xy 331.459332 -257.930142) (xy 346.651329 -257.930142)
			(xy 346.655359 -257.877644) (xy 346.667356 -257.826376) (xy 346.687039 -257.777541) (xy 346.713945 -257.732282)
			(xy 346.747445 -257.691661) (xy 346.786753 -257.65663) (xy 346.830948 -257.62801) (xy 346.878993 -257.606471)
			(xy 346.929764 -257.592519) (xy 346.982069 -257.586481) (xy 347.034683 -257.588498) (xy 347.086373 -257.598522)
			(xy 347.135926 -257.61632) (xy 347.182182 -257.641473) (xy 347.224056 -257.673392) (xy 347.260568 -257.71133)
			(xy 347.29086 -257.754396) (xy 347.314223 -257.801581) (xy 347.330109 -257.85178) (xy 347.338146 -257.903816)
			(xy 347.33865 -257.930142) (xy 348.551249 -257.930142) (xy 348.555279 -257.877644) (xy 348.567276 -257.826376)
			(xy 348.586959 -257.777541) (xy 348.613865 -257.732282) (xy 348.647365 -257.691661) (xy 348.686673 -257.65663)
			(xy 348.730868 -257.62801) (xy 348.778913 -257.606471) (xy 348.829684 -257.592519) (xy 348.881989 -257.586481)
			(xy 348.934603 -257.588498) (xy 348.986293 -257.598522) (xy 349.035846 -257.61632) (xy 349.082102 -257.641473)
			(xy 349.123976 -257.673392) (xy 349.160488 -257.71133) (xy 349.19078 -257.754396) (xy 349.214143 -257.801581)
			(xy 349.230029 -257.85178) (xy 349.238066 -257.903816) (xy 349.23857 -257.930142) (xy 350.451169 -257.930142)
			(xy 350.455199 -257.877644) (xy 350.467196 -257.826376) (xy 350.486879 -257.777541) (xy 350.513785 -257.732282)
			(xy 350.547285 -257.691661) (xy 350.586593 -257.65663) (xy 350.630788 -257.62801) (xy 350.678833 -257.606471)
			(xy 350.729604 -257.592519) (xy 350.781909 -257.586481) (xy 350.834523 -257.588498) (xy 350.886213 -257.598522)
			(xy 350.935766 -257.61632) (xy 350.982022 -257.641473) (xy 351.023896 -257.673392) (xy 351.060408 -257.71133)
			(xy 351.0907 -257.754396) (xy 351.114063 -257.801581) (xy 351.129949 -257.85178) (xy 351.137986 -257.903816)
			(xy 351.13849 -257.930142) (xy 351.137986 -257.956468) (xy 351.129949 -258.008504) (xy 351.114063 -258.058703)
			(xy 351.0907 -258.105888) (xy 351.060408 -258.148954) (xy 351.023896 -258.186892) (xy 350.982022 -258.218811)
			(xy 350.935766 -258.243964) (xy 350.886213 -258.261762) (xy 350.834523 -258.271786) (xy 350.781909 -258.273803)
			(xy 350.729604 -258.267765) (xy 350.678833 -258.253813) (xy 350.630788 -258.232274) (xy 350.586593 -258.203654)
			(xy 350.547285 -258.168623) (xy 350.513785 -258.128002) (xy 350.486879 -258.082743) (xy 350.467196 -258.033908)
			(xy 350.455199 -257.98264) (xy 350.451169 -257.930142) (xy 349.23857 -257.930142) (xy 349.238066 -257.956468)
			(xy 349.230029 -258.008504) (xy 349.214143 -258.058703) (xy 349.19078 -258.105888) (xy 349.160488 -258.148954)
			(xy 349.123976 -258.186892) (xy 349.082102 -258.218811) (xy 349.035846 -258.243964) (xy 348.986293 -258.261762)
			(xy 348.934603 -258.271786) (xy 348.881989 -258.273803) (xy 348.829684 -258.267765) (xy 348.778913 -258.253813)
			(xy 348.730868 -258.232274) (xy 348.686673 -258.203654) (xy 348.647365 -258.168623) (xy 348.613865 -258.128002)
			(xy 348.586959 -258.082743) (xy 348.567276 -258.033908) (xy 348.555279 -257.98264) (xy 348.551249 -257.930142)
			(xy 347.33865 -257.930142) (xy 347.338146 -257.956468) (xy 347.330109 -258.008504) (xy 347.314223 -258.058703)
			(xy 347.29086 -258.105888) (xy 347.260568 -258.148954) (xy 347.224056 -258.186892) (xy 347.182182 -258.218811)
			(xy 347.135926 -258.243964) (xy 347.086373 -258.261762) (xy 347.034683 -258.271786) (xy 346.982069 -258.273803)
			(xy 346.929764 -258.267765) (xy 346.878993 -258.253813) (xy 346.830948 -258.232274) (xy 346.786753 -258.203654)
			(xy 346.747445 -258.168623) (xy 346.713945 -258.128002) (xy 346.687039 -258.082743) (xy 346.667356 -258.033908)
			(xy 346.655359 -257.98264) (xy 346.651329 -257.930142) (xy 331.459332 -257.930142) (xy 331.459332 -258.379976)
			(xy 354.001327 -258.379976) (xy 354.005357 -258.327478) (xy 354.017354 -258.27621) (xy 354.037037 -258.227375)
			(xy 354.063943 -258.182116) (xy 354.097443 -258.141495) (xy 354.136751 -258.106464) (xy 354.180946 -258.077844)
			(xy 354.228991 -258.056305) (xy 354.279762 -258.042353) (xy 354.332067 -258.036315) (xy 354.384681 -258.038332)
			(xy 354.436371 -258.048356) (xy 354.485924 -258.066154) (xy 354.53218 -258.091307) (xy 354.574054 -258.123226)
			(xy 354.610566 -258.161164) (xy 354.640858 -258.20423) (xy 354.664221 -258.251415) (xy 354.680107 -258.301614)
			(xy 354.688144 -258.35365) (xy 354.688648 -258.379976) (xy 354.688144 -258.406302) (xy 354.680107 -258.458338)
			(xy 354.664221 -258.508537) (xy 354.640858 -258.555722) (xy 354.610566 -258.598788) (xy 354.574054 -258.636726)
			(xy 354.53218 -258.668645) (xy 354.485924 -258.693798) (xy 354.436371 -258.711596) (xy 354.384681 -258.72162)
			(xy 354.332067 -258.723637) (xy 354.279762 -258.717599) (xy 354.228991 -258.703647) (xy 354.180946 -258.682108)
			(xy 354.136751 -258.653488) (xy 354.097443 -258.618457) (xy 354.063943 -258.577836) (xy 354.037037 -258.532577)
			(xy 354.017354 -258.483742) (xy 354.005357 -258.432474) (xy 354.001327 -258.379976) (xy 331.459332 -258.379976)
			(xy 331.459332 -258.830064) (xy 346.651329 -258.830064) (xy 346.655359 -258.777566) (xy 346.667356 -258.726298)
			(xy 346.687039 -258.677463) (xy 346.713945 -258.632204) (xy 346.747445 -258.591583) (xy 346.786753 -258.556552)
			(xy 346.830948 -258.527932) (xy 346.878993 -258.506393) (xy 346.929764 -258.492441) (xy 346.982069 -258.486403)
			(xy 347.034683 -258.48842) (xy 347.086373 -258.498444) (xy 347.135926 -258.516242) (xy 347.182182 -258.541395)
			(xy 347.224056 -258.573314) (xy 347.260568 -258.611252) (xy 347.29086 -258.654318) (xy 347.314223 -258.701503)
			(xy 347.330109 -258.751702) (xy 347.338146 -258.803738) (xy 347.33865 -258.830064) (xy 348.551249 -258.830064)
			(xy 348.555279 -258.777566) (xy 348.567276 -258.726298) (xy 348.586959 -258.677463) (xy 348.613865 -258.632204)
			(xy 348.647365 -258.591583) (xy 348.686673 -258.556552) (xy 348.730868 -258.527932) (xy 348.778913 -258.506393)
			(xy 348.829684 -258.492441) (xy 348.881989 -258.486403) (xy 348.934603 -258.48842) (xy 348.986293 -258.498444)
			(xy 349.035846 -258.516242) (xy 349.082102 -258.541395) (xy 349.123976 -258.573314) (xy 349.160488 -258.611252)
			(xy 349.19078 -258.654318) (xy 349.214143 -258.701503) (xy 349.230029 -258.751702) (xy 349.238066 -258.803738)
			(xy 349.23857 -258.830064) (xy 350.451169 -258.830064) (xy 350.455199 -258.777566) (xy 350.467196 -258.726298)
			(xy 350.486879 -258.677463) (xy 350.513785 -258.632204) (xy 350.547285 -258.591583) (xy 350.586593 -258.556552)
			(xy 350.630788 -258.527932) (xy 350.678833 -258.506393) (xy 350.729604 -258.492441) (xy 350.781909 -258.486403)
			(xy 350.834523 -258.48842) (xy 350.886213 -258.498444) (xy 350.935766 -258.516242) (xy 350.982022 -258.541395)
			(xy 351.023896 -258.573314) (xy 351.060408 -258.611252) (xy 351.0907 -258.654318) (xy 351.114063 -258.701503)
			(xy 351.129949 -258.751702) (xy 351.137986 -258.803738) (xy 351.13849 -258.830064) (xy 351.137986 -258.85639)
			(xy 351.129949 -258.908426) (xy 351.114063 -258.958625) (xy 351.0907 -259.00581) (xy 351.060408 -259.048876)
			(xy 351.023896 -259.086814) (xy 350.982022 -259.118733) (xy 350.935766 -259.143886) (xy 350.886213 -259.161684)
			(xy 350.834523 -259.171708) (xy 350.781909 -259.173725) (xy 350.729604 -259.167687) (xy 350.678833 -259.153735)
			(xy 350.630788 -259.132196) (xy 350.586593 -259.103576) (xy 350.547285 -259.068545) (xy 350.513785 -259.027924)
			(xy 350.486879 -258.982665) (xy 350.467196 -258.93383) (xy 350.455199 -258.882562) (xy 350.451169 -258.830064)
			(xy 349.23857 -258.830064) (xy 349.238066 -258.85639) (xy 349.230029 -258.908426) (xy 349.214143 -258.958625)
			(xy 349.19078 -259.00581) (xy 349.160488 -259.048876) (xy 349.123976 -259.086814) (xy 349.082102 -259.118733)
			(xy 349.035846 -259.143886) (xy 348.986293 -259.161684) (xy 348.934603 -259.171708) (xy 348.881989 -259.173725)
			(xy 348.829684 -259.167687) (xy 348.778913 -259.153735) (xy 348.730868 -259.132196) (xy 348.686673 -259.103576)
			(xy 348.647365 -259.068545) (xy 348.613865 -259.027924) (xy 348.586959 -258.982665) (xy 348.567276 -258.93383)
			(xy 348.555279 -258.882562) (xy 348.551249 -258.830064) (xy 347.33865 -258.830064) (xy 347.338146 -258.85639)
			(xy 347.330109 -258.908426) (xy 347.314223 -258.958625) (xy 347.29086 -259.00581) (xy 347.260568 -259.048876)
			(xy 347.224056 -259.086814) (xy 347.182182 -259.118733) (xy 347.135926 -259.143886) (xy 347.086373 -259.161684)
			(xy 347.034683 -259.171708) (xy 346.982069 -259.173725) (xy 346.929764 -259.167687) (xy 346.878993 -259.153735)
			(xy 346.830948 -259.132196) (xy 346.786753 -259.103576) (xy 346.747445 -259.068545) (xy 346.713945 -259.027924)
			(xy 346.687039 -258.982665) (xy 346.667356 -258.93383) (xy 346.655359 -258.882562) (xy 346.651329 -258.830064)
			(xy 331.459332 -258.830064) (xy 331.459332 -259.33019) (xy 354.001327 -259.33019) (xy 354.005357 -259.277692)
			(xy 354.017354 -259.226424) (xy 354.037037 -259.177589) (xy 354.063943 -259.13233) (xy 354.097443 -259.091709)
			(xy 354.136751 -259.056678) (xy 354.180946 -259.028058) (xy 354.228991 -259.006519) (xy 354.279762 -258.992567)
			(xy 354.332067 -258.986529) (xy 354.384681 -258.988546) (xy 354.436371 -258.99857) (xy 354.485924 -259.016368)
			(xy 354.53218 -259.041521) (xy 354.574054 -259.07344) (xy 354.610566 -259.111378) (xy 354.640858 -259.154444)
			(xy 354.664221 -259.201629) (xy 354.680107 -259.251828) (xy 354.688144 -259.303864) (xy 354.688648 -259.33019)
			(xy 354.688144 -259.356516) (xy 354.680107 -259.408552) (xy 354.664221 -259.458751) (xy 354.640858 -259.505936)
			(xy 354.610566 -259.549002) (xy 354.574054 -259.58694) (xy 354.53218 -259.618859) (xy 354.485924 -259.644012)
			(xy 354.436371 -259.66181) (xy 354.384681 -259.671834) (xy 354.332067 -259.673851) (xy 354.279762 -259.667813)
			(xy 354.228991 -259.653861) (xy 354.180946 -259.632322) (xy 354.136751 -259.603702) (xy 354.097443 -259.568671)
			(xy 354.063943 -259.52805) (xy 354.037037 -259.482791) (xy 354.017354 -259.433956) (xy 354.005357 -259.382688)
			(xy 354.001327 -259.33019) (xy 331.459332 -259.33019) (xy 331.459332 -259.729986) (xy 346.651329 -259.729986)
			(xy 346.655359 -259.677488) (xy 346.667356 -259.62622) (xy 346.687039 -259.577385) (xy 346.713945 -259.532126)
			(xy 346.747445 -259.491505) (xy 346.786753 -259.456474) (xy 346.830948 -259.427854) (xy 346.878993 -259.406315)
			(xy 346.929764 -259.392363) (xy 346.982069 -259.386325) (xy 347.034683 -259.388342) (xy 347.086373 -259.398366)
			(xy 347.135926 -259.416164) (xy 347.182182 -259.441317) (xy 347.224056 -259.473236) (xy 347.260568 -259.511174)
			(xy 347.29086 -259.55424) (xy 347.314223 -259.601425) (xy 347.330109 -259.651624) (xy 347.338146 -259.70366)
			(xy 347.33865 -259.729986) (xy 348.551249 -259.729986) (xy 348.555279 -259.677488) (xy 348.567276 -259.62622)
			(xy 348.586959 -259.577385) (xy 348.613865 -259.532126) (xy 348.647365 -259.491505) (xy 348.686673 -259.456474)
			(xy 348.730868 -259.427854) (xy 348.778913 -259.406315) (xy 348.829684 -259.392363) (xy 348.881989 -259.386325)
			(xy 348.934603 -259.388342) (xy 348.986293 -259.398366) (xy 349.035846 -259.416164) (xy 349.082102 -259.441317)
			(xy 349.123976 -259.473236) (xy 349.160488 -259.511174) (xy 349.19078 -259.55424) (xy 349.214143 -259.601425)
			(xy 349.230029 -259.651624) (xy 349.238066 -259.70366) (xy 349.23857 -259.729986) (xy 350.451169 -259.729986)
			(xy 350.455199 -259.677488) (xy 350.467196 -259.62622) (xy 350.486879 -259.577385) (xy 350.513785 -259.532126)
			(xy 350.547285 -259.491505) (xy 350.586593 -259.456474) (xy 350.630788 -259.427854) (xy 350.678833 -259.406315)
			(xy 350.729604 -259.392363) (xy 350.781909 -259.386325) (xy 350.834523 -259.388342) (xy 350.886213 -259.398366)
			(xy 350.935766 -259.416164) (xy 350.982022 -259.441317) (xy 351.023896 -259.473236) (xy 351.060408 -259.511174)
			(xy 351.0907 -259.55424) (xy 351.114063 -259.601425) (xy 351.129949 -259.651624) (xy 351.137986 -259.70366)
			(xy 351.13849 -259.729986) (xy 351.137986 -259.756312) (xy 351.129949 -259.808348) (xy 351.114063 -259.858547)
			(xy 351.0907 -259.905732) (xy 351.060408 -259.948798) (xy 351.023896 -259.986736) (xy 350.982022 -260.018655)
			(xy 350.935766 -260.043808) (xy 350.886213 -260.061606) (xy 350.834523 -260.07163) (xy 350.781909 -260.073647)
			(xy 350.729604 -260.067609) (xy 350.678833 -260.053657) (xy 350.630788 -260.032118) (xy 350.586593 -260.003498)
			(xy 350.547285 -259.968467) (xy 350.513785 -259.927846) (xy 350.486879 -259.882587) (xy 350.467196 -259.833752)
			(xy 350.455199 -259.782484) (xy 350.451169 -259.729986) (xy 349.23857 -259.729986) (xy 349.238066 -259.756312)
			(xy 349.230029 -259.808348) (xy 349.214143 -259.858547) (xy 349.19078 -259.905732) (xy 349.160488 -259.948798)
			(xy 349.123976 -259.986736) (xy 349.082102 -260.018655) (xy 349.035846 -260.043808) (xy 348.986293 -260.061606)
			(xy 348.934603 -260.07163) (xy 348.881989 -260.073647) (xy 348.829684 -260.067609) (xy 348.778913 -260.053657)
			(xy 348.730868 -260.032118) (xy 348.686673 -260.003498) (xy 348.647365 -259.968467) (xy 348.613865 -259.927846)
			(xy 348.586959 -259.882587) (xy 348.567276 -259.833752) (xy 348.555279 -259.782484) (xy 348.551249 -259.729986)
			(xy 347.33865 -259.729986) (xy 347.338146 -259.756312) (xy 347.330109 -259.808348) (xy 347.314223 -259.858547)
			(xy 347.29086 -259.905732) (xy 347.260568 -259.948798) (xy 347.224056 -259.986736) (xy 347.182182 -260.018655)
			(xy 347.135926 -260.043808) (xy 347.086373 -260.061606) (xy 347.034683 -260.07163) (xy 346.982069 -260.073647)
			(xy 346.929764 -260.067609) (xy 346.878993 -260.053657) (xy 346.830948 -260.032118) (xy 346.786753 -260.003498)
			(xy 346.747445 -259.968467) (xy 346.713945 -259.927846) (xy 346.687039 -259.882587) (xy 346.667356 -259.833752)
			(xy 346.655359 -259.782484) (xy 346.651329 -259.729986) (xy 331.459332 -259.729986) (xy 331.459332 -260.807708)
			(xy 331.459577 -260.814658) (xy 331.463322 -260.828044) (xy 331.466698 -260.834124) (xy 331.47 -260.839204)
			(xy 331.480414 -260.848856) (xy 331.487526 -260.852412) (xy 331.508977 -260.863639) (xy 331.548343 -260.891825)
			(xy 331.582775 -260.925861) (xy 331.611414 -260.964897) (xy 331.633544 -261.007959) (xy 331.648613 -261.053969)
			(xy 331.656244 -261.101779) (xy 331.656245 -261.12597) (xy 331.985378 -261.12597) (xy 331.989338 -261.076916)
			(xy 332.001115 -261.029132) (xy 332.020406 -260.983856) (xy 332.046709 -260.94226) (xy 332.079344 -260.905423)
			(xy 332.117465 -260.874298) (xy 332.160086 -260.849691) (xy 332.206102 -260.832239) (xy 332.254321 -260.822395)
			(xy 332.303496 -260.820414) (xy 332.352351 -260.826346) (xy 332.399622 -260.840038) (xy 332.444084 -260.861136)
			(xy 332.484587 -260.889092) (xy 332.52008 -260.923184) (xy 332.549645 -260.962528) (xy 332.572516 -261.006105)
			(xy 332.5881 -261.052786) (xy 332.595995 -261.101363) (xy 332.59649 -261.12597) (xy 332.925178 -261.12597)
			(xy 332.929138 -261.076916) (xy 332.940915 -261.029132) (xy 332.960206 -260.983856) (xy 332.986509 -260.94226)
			(xy 333.019144 -260.905423) (xy 333.057265 -260.874298) (xy 333.099886 -260.849691) (xy 333.145902 -260.832239)
			(xy 333.194121 -260.822395) (xy 333.243296 -260.820414) (xy 333.292151 -260.826346) (xy 333.339422 -260.840038)
			(xy 333.383884 -260.861136) (xy 333.424387 -260.889092) (xy 333.45988 -260.923184) (xy 333.489445 -260.962528)
			(xy 333.512316 -261.006105) (xy 333.5279 -261.052786) (xy 333.535795 -261.101363) (xy 333.53629 -261.12597)
			(xy 333.865232 -261.12597) (xy 333.869192 -261.076916) (xy 333.880969 -261.029132) (xy 333.90026 -260.983856)
			(xy 333.926563 -260.94226) (xy 333.959198 -260.905423) (xy 333.997319 -260.874298) (xy 334.03994 -260.849691)
			(xy 334.085956 -260.832239) (xy 334.134175 -260.822395) (xy 334.18335 -260.820414) (xy 334.232205 -260.826346)
			(xy 334.279476 -260.840038) (xy 334.323938 -260.861136) (xy 334.364441 -260.889092) (xy 334.399934 -260.923184)
			(xy 334.429499 -260.962528) (xy 334.45237 -261.006105) (xy 334.467954 -261.052786) (xy 334.475849 -261.101363)
			(xy 334.476344 -261.12597) (xy 335.74534 -261.12597) (xy 335.7493 -261.076916) (xy 335.761077 -261.029132)
			(xy 335.780368 -260.983856) (xy 335.806671 -260.94226) (xy 335.839306 -260.905423) (xy 335.877427 -260.874298)
			(xy 335.920048 -260.849691) (xy 335.966064 -260.832239) (xy 336.014283 -260.822395) (xy 336.063458 -260.820414)
			(xy 336.112313 -260.826346) (xy 336.159584 -260.840038) (xy 336.204046 -260.861136) (xy 336.244549 -260.889092)
			(xy 336.280042 -260.923184) (xy 336.309607 -260.962528) (xy 336.332478 -261.006105) (xy 336.348062 -261.052786)
			(xy 336.355957 -261.101363) (xy 336.356452 -261.12597) (xy 336.685394 -261.12597) (xy 336.689354 -261.076916)
			(xy 336.701131 -261.029132) (xy 336.720422 -260.983856) (xy 336.746725 -260.94226) (xy 336.77936 -260.905423)
			(xy 336.817481 -260.874298) (xy 336.860102 -260.849691) (xy 336.906118 -260.832239) (xy 336.954337 -260.822395)
			(xy 337.003512 -260.820414) (xy 337.052367 -260.826346) (xy 337.099638 -260.840038) (xy 337.1441 -260.861136)
			(xy 337.184603 -260.889092) (xy 337.220096 -260.923184) (xy 337.249661 -260.962528) (xy 337.272532 -261.006105)
			(xy 337.288116 -261.052786) (xy 337.296011 -261.101363) (xy 337.296506 -261.12597) (xy 337.625194 -261.12597)
			(xy 337.629154 -261.076916) (xy 337.640931 -261.029132) (xy 337.660222 -260.983856) (xy 337.686525 -260.94226)
			(xy 337.71916 -260.905423) (xy 337.757281 -260.874298) (xy 337.799902 -260.849691) (xy 337.845918 -260.832239)
			(xy 337.894137 -260.822395) (xy 337.943312 -260.820414) (xy 337.992167 -260.826346) (xy 338.039438 -260.840038)
			(xy 338.0839 -260.861136) (xy 338.124403 -260.889092) (xy 338.159896 -260.923184) (xy 338.189461 -260.962528)
			(xy 338.212332 -261.006105) (xy 338.227916 -261.052786) (xy 338.235811 -261.101363) (xy 338.236306 -261.12597)
			(xy 338.565248 -261.12597) (xy 338.569208 -261.076916) (xy 338.580985 -261.029132) (xy 338.600276 -260.983856)
			(xy 338.626579 -260.94226) (xy 338.659214 -260.905423) (xy 338.697335 -260.874298) (xy 338.739956 -260.849691)
			(xy 338.785972 -260.832239) (xy 338.834191 -260.822395) (xy 338.883366 -260.820414) (xy 338.932221 -260.826346)
			(xy 338.979492 -260.840038) (xy 339.023954 -260.861136) (xy 339.064457 -260.889092) (xy 339.09995 -260.923184)
			(xy 339.129515 -260.962528) (xy 339.152386 -261.006105) (xy 339.16797 -261.052786) (xy 339.175865 -261.101363)
			(xy 339.17636 -261.12597) (xy 339.505302 -261.12597) (xy 339.509262 -261.076916) (xy 339.521039 -261.029132)
			(xy 339.54033 -260.983856) (xy 339.566633 -260.94226) (xy 339.599268 -260.905423) (xy 339.637389 -260.874298)
			(xy 339.68001 -260.849691) (xy 339.726026 -260.832239) (xy 339.774245 -260.822395) (xy 339.82342 -260.820414)
			(xy 339.872275 -260.826346) (xy 339.919546 -260.840038) (xy 339.964008 -260.861136) (xy 340.004511 -260.889092)
			(xy 340.040004 -260.923184) (xy 340.069569 -260.962528) (xy 340.09244 -261.006105) (xy 340.108024 -261.052786)
			(xy 340.115919 -261.101363) (xy 340.116414 -261.12597) (xy 340.445356 -261.12597) (xy 340.449316 -261.076916)
			(xy 340.461093 -261.029132) (xy 340.480384 -260.983856) (xy 340.506687 -260.94226) (xy 340.539322 -260.905423)
			(xy 340.577443 -260.874298) (xy 340.620064 -260.849691) (xy 340.66608 -260.832239) (xy 340.714299 -260.822395)
			(xy 340.763474 -260.820414) (xy 340.812329 -260.826346) (xy 340.8596 -260.840038) (xy 340.904062 -260.861136)
			(xy 340.944565 -260.889092) (xy 340.980058 -260.923184) (xy 341.009623 -260.962528) (xy 341.032494 -261.006105)
			(xy 341.048078 -261.052786) (xy 341.055973 -261.101363) (xy 341.056468 -261.12597) (xy 342.32521 -261.12597)
			(xy 342.32917 -261.076916) (xy 342.340947 -261.029132) (xy 342.360238 -260.983856) (xy 342.386541 -260.94226)
			(xy 342.419176 -260.905423) (xy 342.457297 -260.874298) (xy 342.499918 -260.849691) (xy 342.545934 -260.832239)
			(xy 342.594153 -260.822395) (xy 342.643328 -260.820414) (xy 342.692183 -260.826346) (xy 342.739454 -260.840038)
			(xy 342.783916 -260.861136) (xy 342.824419 -260.889092) (xy 342.859912 -260.923184) (xy 342.889477 -260.962528)
			(xy 342.912348 -261.006105) (xy 342.927932 -261.052786) (xy 342.935827 -261.101363) (xy 342.936322 -261.12597)
			(xy 343.265264 -261.12597) (xy 343.269224 -261.076916) (xy 343.281001 -261.029132) (xy 343.300292 -260.983856)
			(xy 343.326595 -260.94226) (xy 343.35923 -260.905423) (xy 343.397351 -260.874298) (xy 343.439972 -260.849691)
			(xy 343.485988 -260.832239) (xy 343.534207 -260.822395) (xy 343.583382 -260.820414) (xy 343.632237 -260.826346)
			(xy 343.679508 -260.840038) (xy 343.72397 -260.861136) (xy 343.764473 -260.889092) (xy 343.799966 -260.923184)
			(xy 343.829531 -260.962528) (xy 343.852402 -261.006105) (xy 343.867986 -261.052786) (xy 343.875881 -261.101363)
			(xy 343.876376 -261.12597) (xy 344.205318 -261.12597) (xy 344.209278 -261.076916) (xy 344.221055 -261.029132)
			(xy 344.240346 -260.983856) (xy 344.266649 -260.94226) (xy 344.299284 -260.905423) (xy 344.337405 -260.874298)
			(xy 344.380026 -260.849691) (xy 344.426042 -260.832239) (xy 344.474261 -260.822395) (xy 344.523436 -260.820414)
			(xy 344.572291 -260.826346) (xy 344.619562 -260.840038) (xy 344.664024 -260.861136) (xy 344.704527 -260.889092)
			(xy 344.74002 -260.923184) (xy 344.769585 -260.962528) (xy 344.792456 -261.006105) (xy 344.80804 -261.052786)
			(xy 344.815935 -261.101363) (xy 344.81643 -261.12597) (xy 346.085426 -261.12597) (xy 346.089386 -261.076916)
			(xy 346.101163 -261.029132) (xy 346.120454 -260.983856) (xy 346.146757 -260.94226) (xy 346.179392 -260.905423)
			(xy 346.217513 -260.874298) (xy 346.260134 -260.849691) (xy 346.30615 -260.832239) (xy 346.354369 -260.822395)
			(xy 346.403544 -260.820414) (xy 346.452399 -260.826346) (xy 346.49967 -260.840038) (xy 346.544132 -260.861136)
			(xy 346.584635 -260.889092) (xy 346.620128 -260.923184) (xy 346.649693 -260.962528) (xy 346.672564 -261.006105)
			(xy 346.688148 -261.052786) (xy 346.696043 -261.101363) (xy 346.696538 -261.12597) (xy 347.96528 -261.12597)
			(xy 347.96924 -261.076916) (xy 347.981017 -261.029132) (xy 348.000308 -260.983856) (xy 348.026611 -260.94226)
			(xy 348.059246 -260.905423) (xy 348.097367 -260.874298) (xy 348.139988 -260.849691) (xy 348.186004 -260.832239)
			(xy 348.234223 -260.822395) (xy 348.283398 -260.820414) (xy 348.332253 -260.826346) (xy 348.379524 -260.840038)
			(xy 348.423986 -260.861136) (xy 348.464489 -260.889092) (xy 348.499982 -260.923184) (xy 348.529547 -260.962528)
			(xy 348.552418 -261.006105) (xy 348.568002 -261.052786) (xy 348.575897 -261.101363) (xy 348.576392 -261.12597)
			(xy 348.905334 -261.12597) (xy 348.909294 -261.076916) (xy 348.921071 -261.029132) (xy 348.940362 -260.983856)
			(xy 348.966665 -260.94226) (xy 348.9993 -260.905423) (xy 349.037421 -260.874298) (xy 349.080042 -260.849691)
			(xy 349.126058 -260.832239) (xy 349.174277 -260.822395) (xy 349.223452 -260.820414) (xy 349.272307 -260.826346)
			(xy 349.319578 -260.840038) (xy 349.36404 -260.861136) (xy 349.404543 -260.889092) (xy 349.440036 -260.923184)
			(xy 349.469601 -260.962528) (xy 349.492472 -261.006105) (xy 349.508056 -261.052786) (xy 349.515951 -261.101363)
			(xy 349.516446 -261.12597) (xy 349.845388 -261.12597) (xy 349.849348 -261.076916) (xy 349.861125 -261.029132)
			(xy 349.880416 -260.983856) (xy 349.906719 -260.94226) (xy 349.939354 -260.905423) (xy 349.977475 -260.874298)
			(xy 350.020096 -260.849691) (xy 350.066112 -260.832239) (xy 350.114331 -260.822395) (xy 350.163506 -260.820414)
			(xy 350.212361 -260.826346) (xy 350.259632 -260.840038) (xy 350.304094 -260.861136) (xy 350.344597 -260.889092)
			(xy 350.38009 -260.923184) (xy 350.409655 -260.962528) (xy 350.432526 -261.006105) (xy 350.44811 -261.052786)
			(xy 350.456005 -261.101363) (xy 350.4565 -261.12597) (xy 350.456459 -261.128002) (xy 350.78214 -261.128002)
			(xy 350.7861 -261.078948) (xy 350.797877 -261.031164) (xy 350.817168 -260.985888) (xy 350.843471 -260.944292)
			(xy 350.876106 -260.907455) (xy 350.914227 -260.87633) (xy 350.956848 -260.851723) (xy 351.002864 -260.834271)
			(xy 351.051083 -260.824427) (xy 351.100258 -260.822446) (xy 351.149113 -260.828378) (xy 351.196384 -260.84207)
			(xy 351.240846 -260.863168) (xy 351.281349 -260.891124) (xy 351.316842 -260.925216) (xy 351.346407 -260.96456)
			(xy 351.369278 -261.008137) (xy 351.384862 -261.054818) (xy 351.392757 -261.103395) (xy 351.393252 -261.128002)
			(xy 351.722194 -261.128002) (xy 351.726154 -261.078948) (xy 351.737931 -261.031164) (xy 351.757222 -260.985888)
			(xy 351.783525 -260.944292) (xy 351.81616 -260.907455) (xy 351.854281 -260.87633) (xy 351.896902 -260.851723)
			(xy 351.942918 -260.834271) (xy 351.991137 -260.824427) (xy 352.040312 -260.822446) (xy 352.089167 -260.828378)
			(xy 352.136438 -260.84207) (xy 352.1809 -260.863168) (xy 352.221403 -260.891124) (xy 352.256896 -260.925216)
			(xy 352.286461 -260.96456) (xy 352.309332 -261.008137) (xy 352.324916 -261.054818) (xy 352.332811 -261.103395)
			(xy 352.333306 -261.128002) (xy 352.332811 -261.152609) (xy 352.324916 -261.201186) (xy 352.309332 -261.247867)
			(xy 352.286461 -261.291444) (xy 352.256896 -261.330788) (xy 352.221403 -261.36488) (xy 352.1809 -261.392836)
			(xy 352.136438 -261.413934) (xy 352.089167 -261.427626) (xy 352.040312 -261.433558) (xy 351.991137 -261.431577)
			(xy 351.942918 -261.421733) (xy 351.896902 -261.404281) (xy 351.854281 -261.379674) (xy 351.81616 -261.348549)
			(xy 351.783525 -261.311712) (xy 351.757222 -261.270116) (xy 351.737931 -261.22484) (xy 351.726154 -261.177056)
			(xy 351.722194 -261.128002) (xy 351.393252 -261.128002) (xy 351.392757 -261.152609) (xy 351.384862 -261.201186)
			(xy 351.369278 -261.247867) (xy 351.346407 -261.291444) (xy 351.316842 -261.330788) (xy 351.281349 -261.36488)
			(xy 351.240846 -261.392836) (xy 351.196384 -261.413934) (xy 351.149113 -261.427626) (xy 351.100258 -261.433558)
			(xy 351.051083 -261.431577) (xy 351.002864 -261.421733) (xy 350.956848 -261.404281) (xy 350.914227 -261.379674)
			(xy 350.876106 -261.348549) (xy 350.843471 -261.311712) (xy 350.817168 -261.270116) (xy 350.797877 -261.22484)
			(xy 350.7861 -261.177056) (xy 350.78214 -261.128002) (xy 350.456459 -261.128002) (xy 350.456005 -261.150577)
			(xy 350.44811 -261.199154) (xy 350.432526 -261.245835) (xy 350.409655 -261.289412) (xy 350.38009 -261.328756)
			(xy 350.344597 -261.362848) (xy 350.304094 -261.390804) (xy 350.259632 -261.411902) (xy 350.212361 -261.425594)
			(xy 350.163506 -261.431526) (xy 350.114331 -261.429545) (xy 350.066112 -261.419701) (xy 350.020096 -261.402249)
			(xy 349.977475 -261.377642) (xy 349.939354 -261.346517) (xy 349.906719 -261.30968) (xy 349.880416 -261.268084)
			(xy 349.861125 -261.222808) (xy 349.849348 -261.175024) (xy 349.845388 -261.12597) (xy 349.516446 -261.12597)
			(xy 349.515951 -261.150577) (xy 349.508056 -261.199154) (xy 349.492472 -261.245835) (xy 349.469601 -261.289412)
			(xy 349.440036 -261.328756) (xy 349.404543 -261.362848) (xy 349.36404 -261.390804) (xy 349.319578 -261.411902)
			(xy 349.272307 -261.425594) (xy 349.223452 -261.431526) (xy 349.174277 -261.429545) (xy 349.126058 -261.419701)
			(xy 349.080042 -261.402249) (xy 349.037421 -261.377642) (xy 348.9993 -261.346517) (xy 348.966665 -261.30968)
			(xy 348.940362 -261.268084) (xy 348.921071 -261.222808) (xy 348.909294 -261.175024) (xy 348.905334 -261.12597)
			(xy 348.576392 -261.12597) (xy 348.575897 -261.150577) (xy 348.568002 -261.199154) (xy 348.552418 -261.245835)
			(xy 348.529547 -261.289412) (xy 348.499982 -261.328756) (xy 348.464489 -261.362848) (xy 348.423986 -261.390804)
			(xy 348.379524 -261.411902) (xy 348.332253 -261.425594) (xy 348.283398 -261.431526) (xy 348.234223 -261.429545)
			(xy 348.186004 -261.419701) (xy 348.139988 -261.402249) (xy 348.097367 -261.377642) (xy 348.059246 -261.346517)
			(xy 348.026611 -261.30968) (xy 348.000308 -261.268084) (xy 347.981017 -261.222808) (xy 347.96924 -261.175024)
			(xy 347.96528 -261.12597) (xy 346.696538 -261.12597) (xy 346.696043 -261.150577) (xy 346.688148 -261.199154)
			(xy 346.672564 -261.245835) (xy 346.649693 -261.289412) (xy 346.620128 -261.328756) (xy 346.584635 -261.362848)
			(xy 346.544132 -261.390804) (xy 346.49967 -261.411902) (xy 346.452399 -261.425594) (xy 346.403544 -261.431526)
			(xy 346.354369 -261.429545) (xy 346.30615 -261.419701) (xy 346.260134 -261.402249) (xy 346.217513 -261.377642)
			(xy 346.179392 -261.346517) (xy 346.146757 -261.30968) (xy 346.120454 -261.268084) (xy 346.101163 -261.222808)
			(xy 346.089386 -261.175024) (xy 346.085426 -261.12597) (xy 344.81643 -261.12597) (xy 344.815935 -261.150577)
			(xy 344.80804 -261.199154) (xy 344.792456 -261.245835) (xy 344.769585 -261.289412) (xy 344.74002 -261.328756)
			(xy 344.704527 -261.362848) (xy 344.664024 -261.390804) (xy 344.619562 -261.411902) (xy 344.572291 -261.425594)
			(xy 344.523436 -261.431526) (xy 344.474261 -261.429545) (xy 344.426042 -261.419701) (xy 344.380026 -261.402249)
			(xy 344.337405 -261.377642) (xy 344.299284 -261.346517) (xy 344.266649 -261.30968) (xy 344.240346 -261.268084)
			(xy 344.221055 -261.222808) (xy 344.209278 -261.175024) (xy 344.205318 -261.12597) (xy 343.876376 -261.12597)
			(xy 343.875881 -261.150577) (xy 343.867986 -261.199154) (xy 343.852402 -261.245835) (xy 343.829531 -261.289412)
			(xy 343.799966 -261.328756) (xy 343.764473 -261.362848) (xy 343.72397 -261.390804) (xy 343.679508 -261.411902)
			(xy 343.632237 -261.425594) (xy 343.583382 -261.431526) (xy 343.534207 -261.429545) (xy 343.485988 -261.419701)
			(xy 343.439972 -261.402249) (xy 343.397351 -261.377642) (xy 343.35923 -261.346517) (xy 343.326595 -261.30968)
			(xy 343.300292 -261.268084) (xy 343.281001 -261.222808) (xy 343.269224 -261.175024) (xy 343.265264 -261.12597)
			(xy 342.936322 -261.12597) (xy 342.935827 -261.150577) (xy 342.927932 -261.199154) (xy 342.912348 -261.245835)
			(xy 342.889477 -261.289412) (xy 342.859912 -261.328756) (xy 342.824419 -261.362848) (xy 342.783916 -261.390804)
			(xy 342.739454 -261.411902) (xy 342.692183 -261.425594) (xy 342.643328 -261.431526) (xy 342.594153 -261.429545)
			(xy 342.545934 -261.419701) (xy 342.499918 -261.402249) (xy 342.457297 -261.377642) (xy 342.419176 -261.346517)
			(xy 342.386541 -261.30968) (xy 342.360238 -261.268084) (xy 342.340947 -261.222808) (xy 342.32917 -261.175024)
			(xy 342.32521 -261.12597) (xy 341.056468 -261.12597) (xy 341.055973 -261.150577) (xy 341.048078 -261.199154)
			(xy 341.032494 -261.245835) (xy 341.009623 -261.289412) (xy 340.980058 -261.328756) (xy 340.944565 -261.362848)
			(xy 340.904062 -261.390804) (xy 340.8596 -261.411902) (xy 340.812329 -261.425594) (xy 340.763474 -261.431526)
			(xy 340.714299 -261.429545) (xy 340.66608 -261.419701) (xy 340.620064 -261.402249) (xy 340.577443 -261.377642)
			(xy 340.539322 -261.346517) (xy 340.506687 -261.30968) (xy 340.480384 -261.268084) (xy 340.461093 -261.222808)
			(xy 340.449316 -261.175024) (xy 340.445356 -261.12597) (xy 340.116414 -261.12597) (xy 340.115919 -261.150577)
			(xy 340.108024 -261.199154) (xy 340.09244 -261.245835) (xy 340.069569 -261.289412) (xy 340.040004 -261.328756)
			(xy 340.004511 -261.362848) (xy 339.964008 -261.390804) (xy 339.919546 -261.411902) (xy 339.872275 -261.425594)
			(xy 339.82342 -261.431526) (xy 339.774245 -261.429545) (xy 339.726026 -261.419701) (xy 339.68001 -261.402249)
			(xy 339.637389 -261.377642) (xy 339.599268 -261.346517) (xy 339.566633 -261.30968) (xy 339.54033 -261.268084)
			(xy 339.521039 -261.222808) (xy 339.509262 -261.175024) (xy 339.505302 -261.12597) (xy 339.17636 -261.12597)
			(xy 339.175865 -261.150577) (xy 339.16797 -261.199154) (xy 339.152386 -261.245835) (xy 339.129515 -261.289412)
			(xy 339.09995 -261.328756) (xy 339.064457 -261.362848) (xy 339.023954 -261.390804) (xy 338.979492 -261.411902)
			(xy 338.932221 -261.425594) (xy 338.883366 -261.431526) (xy 338.834191 -261.429545) (xy 338.785972 -261.419701)
			(xy 338.739956 -261.402249) (xy 338.697335 -261.377642) (xy 338.659214 -261.346517) (xy 338.626579 -261.30968)
			(xy 338.600276 -261.268084) (xy 338.580985 -261.222808) (xy 338.569208 -261.175024) (xy 338.565248 -261.12597)
			(xy 338.236306 -261.12597) (xy 338.235811 -261.150577) (xy 338.227916 -261.199154) (xy 338.212332 -261.245835)
			(xy 338.189461 -261.289412) (xy 338.159896 -261.328756) (xy 338.124403 -261.362848) (xy 338.0839 -261.390804)
			(xy 338.039438 -261.411902) (xy 337.992167 -261.425594) (xy 337.943312 -261.431526) (xy 337.894137 -261.429545)
			(xy 337.845918 -261.419701) (xy 337.799902 -261.402249) (xy 337.757281 -261.377642) (xy 337.71916 -261.346517)
			(xy 337.686525 -261.30968) (xy 337.660222 -261.268084) (xy 337.640931 -261.222808) (xy 337.629154 -261.175024)
			(xy 337.625194 -261.12597) (xy 337.296506 -261.12597) (xy 337.296011 -261.150577) (xy 337.288116 -261.199154)
			(xy 337.272532 -261.245835) (xy 337.249661 -261.289412) (xy 337.220096 -261.328756) (xy 337.184603 -261.362848)
			(xy 337.1441 -261.390804) (xy 337.099638 -261.411902) (xy 337.052367 -261.425594) (xy 337.003512 -261.431526)
			(xy 336.954337 -261.429545) (xy 336.906118 -261.419701) (xy 336.860102 -261.402249) (xy 336.817481 -261.377642)
			(xy 336.77936 -261.346517) (xy 336.746725 -261.30968) (xy 336.720422 -261.268084) (xy 336.701131 -261.222808)
			(xy 336.689354 -261.175024) (xy 336.685394 -261.12597) (xy 336.356452 -261.12597) (xy 336.355957 -261.150577)
			(xy 336.348062 -261.199154) (xy 336.332478 -261.245835) (xy 336.309607 -261.289412) (xy 336.280042 -261.328756)
			(xy 336.244549 -261.362848) (xy 336.204046 -261.390804) (xy 336.159584 -261.411902) (xy 336.112313 -261.425594)
			(xy 336.063458 -261.431526) (xy 336.014283 -261.429545) (xy 335.966064 -261.419701) (xy 335.920048 -261.402249)
			(xy 335.877427 -261.377642) (xy 335.839306 -261.346517) (xy 335.806671 -261.30968) (xy 335.780368 -261.268084)
			(xy 335.761077 -261.222808) (xy 335.7493 -261.175024) (xy 335.74534 -261.12597) (xy 334.476344 -261.12597)
			(xy 334.475849 -261.150577) (xy 334.467954 -261.199154) (xy 334.45237 -261.245835) (xy 334.429499 -261.289412)
			(xy 334.399934 -261.328756) (xy 334.364441 -261.362848) (xy 334.323938 -261.390804) (xy 334.279476 -261.411902)
			(xy 334.232205 -261.425594) (xy 334.18335 -261.431526) (xy 334.134175 -261.429545) (xy 334.085956 -261.419701)
			(xy 334.03994 -261.402249) (xy 333.997319 -261.377642) (xy 333.959198 -261.346517) (xy 333.926563 -261.30968)
			(xy 333.90026 -261.268084) (xy 333.880969 -261.222808) (xy 333.869192 -261.175024) (xy 333.865232 -261.12597)
			(xy 333.53629 -261.12597) (xy 333.535795 -261.150577) (xy 333.5279 -261.199154) (xy 333.512316 -261.245835)
			(xy 333.489445 -261.289412) (xy 333.45988 -261.328756) (xy 333.424387 -261.362848) (xy 333.383884 -261.390804)
			(xy 333.339422 -261.411902) (xy 333.292151 -261.425594) (xy 333.243296 -261.431526) (xy 333.194121 -261.429545)
			(xy 333.145902 -261.419701) (xy 333.099886 -261.402249) (xy 333.057265 -261.377642) (xy 333.019144 -261.346517)
			(xy 332.986509 -261.30968) (xy 332.960206 -261.268084) (xy 332.940915 -261.222808) (xy 332.929138 -261.175024)
			(xy 332.925178 -261.12597) (xy 332.59649 -261.12597) (xy 332.595995 -261.150577) (xy 332.5881 -261.199154)
			(xy 332.572516 -261.245835) (xy 332.549645 -261.289412) (xy 332.52008 -261.328756) (xy 332.484587 -261.362848)
			(xy 332.444084 -261.390804) (xy 332.399622 -261.411902) (xy 332.352351 -261.425594) (xy 332.303496 -261.431526)
			(xy 332.254321 -261.429545) (xy 332.206102 -261.419701) (xy 332.160086 -261.402249) (xy 332.117465 -261.377642)
			(xy 332.079344 -261.346517) (xy 332.046709 -261.30968) (xy 332.020406 -261.268084) (xy 332.001115 -261.222808)
			(xy 331.989338 -261.175024) (xy 331.985378 -261.12597) (xy 331.656245 -261.12597) (xy 331.656246 -261.150194)
			(xy 331.648619 -261.198005) (xy 331.633555 -261.244017) (xy 331.611428 -261.28708) (xy 331.582792 -261.326119)
			(xy 331.548363 -261.360158) (xy 331.509 -261.388347) (xy 331.487526 -261.399528) (xy 331.486764 -261.399782)
			(xy 331.480506 -261.403183) (xy 331.470053 -261.412849) (xy 331.46619 -261.418832) (xy 331.463142 -261.423912)
			(xy 331.459332 -261.43712) (xy 331.459332 -261.626096) (xy 331.459797 -261.635473) (xy 331.466632 -261.652941)
			(xy 331.479309 -261.666766) (xy 331.487526 -261.671308) (xy 331.518006 -261.685532) (xy 331.566266 -261.707884)
			(xy 331.56955 -261.70938) (xy 331.576432 -261.711552) (xy 331.579982 -261.712202) (xy 331.584357 -261.712753)
			(xy 331.593171 -261.712496) (xy 331.597508 -261.711694) (xy 331.605382 -261.709662) (xy 331.62367 -261.702804)
			(xy 331.63002 -261.697724) (xy 331.6505 -261.682011) (xy 331.695637 -261.656976) (xy 331.744339 -261.639881)
			(xy 331.79522 -261.631212) (xy 331.821028 -261.630668) (xy 331.846284 -261.631192) (xy 331.896106 -261.63951)
			(xy 331.943879 -261.655914) (xy 331.988302 -261.679958) (xy 332.028161 -261.710985) (xy 332.06237 -261.748149)
			(xy 332.089996 -261.790437) (xy 332.110285 -261.836695) (xy 332.122684 -261.885661) (xy 332.126853 -261.935976)
			(xy 332.455278 -261.935976) (xy 332.459238 -261.886922) (xy 332.471015 -261.839138) (xy 332.490306 -261.793862)
			(xy 332.516609 -261.752266) (xy 332.549244 -261.715429) (xy 332.587365 -261.684304) (xy 332.629986 -261.659697)
			(xy 332.676002 -261.642245) (xy 332.724221 -261.632401) (xy 332.773396 -261.63042) (xy 332.822251 -261.636352)
			(xy 332.869522 -261.650044) (xy 332.913984 -261.671142) (xy 332.954487 -261.699098) (xy 332.98998 -261.73319)
			(xy 333.019545 -261.772534) (xy 333.042416 -261.816111) (xy 333.058 -261.862792) (xy 333.065895 -261.911369)
			(xy 333.06639 -261.935976) (xy 333.395332 -261.935976) (xy 333.399292 -261.886922) (xy 333.411069 -261.839138)
			(xy 333.43036 -261.793862) (xy 333.456663 -261.752266) (xy 333.489298 -261.715429) (xy 333.527419 -261.684304)
			(xy 333.57004 -261.659697) (xy 333.616056 -261.642245) (xy 333.664275 -261.632401) (xy 333.71345 -261.63042)
			(xy 333.762305 -261.636352) (xy 333.809576 -261.650044) (xy 333.854038 -261.671142) (xy 333.894541 -261.699098)
			(xy 333.930034 -261.73319) (xy 333.959599 -261.772534) (xy 333.98247 -261.816111) (xy 333.998054 -261.862792)
			(xy 334.005949 -261.911369) (xy 334.006444 -261.935976) (xy 334.335386 -261.935976) (xy 334.339346 -261.886922)
			(xy 334.351123 -261.839138) (xy 334.370414 -261.793862) (xy 334.396717 -261.752266) (xy 334.429352 -261.715429)
			(xy 334.467473 -261.684304) (xy 334.510094 -261.659697) (xy 334.55611 -261.642245) (xy 334.604329 -261.632401)
			(xy 334.653504 -261.63042) (xy 334.702359 -261.636352) (xy 334.74963 -261.650044) (xy 334.794092 -261.671142)
			(xy 334.834595 -261.699098) (xy 334.870088 -261.73319) (xy 334.899653 -261.772534) (xy 334.922524 -261.816111)
			(xy 334.938108 -261.862792) (xy 334.946003 -261.911369) (xy 334.946498 -261.935976) (xy 335.275186 -261.935976)
			(xy 335.279146 -261.886922) (xy 335.290923 -261.839138) (xy 335.310214 -261.793862) (xy 335.336517 -261.752266)
			(xy 335.369152 -261.715429) (xy 335.407273 -261.684304) (xy 335.449894 -261.659697) (xy 335.49591 -261.642245)
			(xy 335.544129 -261.632401) (xy 335.593304 -261.63042) (xy 335.642159 -261.636352) (xy 335.68943 -261.650044)
			(xy 335.733892 -261.671142) (xy 335.774395 -261.699098) (xy 335.809888 -261.73319) (xy 335.839453 -261.772534)
			(xy 335.862324 -261.816111) (xy 335.877908 -261.862792) (xy 335.885803 -261.911369) (xy 335.886298 -261.935976)
			(xy 336.21524 -261.935976) (xy 336.2192 -261.886922) (xy 336.230977 -261.839138) (xy 336.250268 -261.793862)
			(xy 336.276571 -261.752266) (xy 336.309206 -261.715429) (xy 336.347327 -261.684304) (xy 336.389948 -261.659697)
			(xy 336.435964 -261.642245) (xy 336.484183 -261.632401) (xy 336.533358 -261.63042) (xy 336.582213 -261.636352)
			(xy 336.629484 -261.650044) (xy 336.673946 -261.671142) (xy 336.714449 -261.699098) (xy 336.749942 -261.73319)
			(xy 336.779507 -261.772534) (xy 336.802378 -261.816111) (xy 336.817962 -261.862792) (xy 336.825857 -261.911369)
			(xy 336.826352 -261.935976) (xy 337.155294 -261.935976) (xy 337.159254 -261.886922) (xy 337.171031 -261.839138)
			(xy 337.190322 -261.793862) (xy 337.216625 -261.752266) (xy 337.24926 -261.715429) (xy 337.287381 -261.684304)
			(xy 337.330002 -261.659697) (xy 337.376018 -261.642245) (xy 337.424237 -261.632401) (xy 337.473412 -261.63042)
			(xy 337.522267 -261.636352) (xy 337.569538 -261.650044) (xy 337.614 -261.671142) (xy 337.654503 -261.699098)
			(xy 337.689996 -261.73319) (xy 337.719561 -261.772534) (xy 337.742432 -261.816111) (xy 337.758016 -261.862792)
			(xy 337.765911 -261.911369) (xy 337.766406 -261.935976) (xy 338.095348 -261.935976) (xy 338.099308 -261.886922)
			(xy 338.111085 -261.839138) (xy 338.130376 -261.793862) (xy 338.156679 -261.752266) (xy 338.189314 -261.715429)
			(xy 338.227435 -261.684304) (xy 338.270056 -261.659697) (xy 338.316072 -261.642245) (xy 338.364291 -261.632401)
			(xy 338.413466 -261.63042) (xy 338.462321 -261.636352) (xy 338.509592 -261.650044) (xy 338.554054 -261.671142)
			(xy 338.594557 -261.699098) (xy 338.63005 -261.73319) (xy 338.659615 -261.772534) (xy 338.682486 -261.816111)
			(xy 338.69807 -261.862792) (xy 338.705965 -261.911369) (xy 338.70646 -261.935976) (xy 339.035402 -261.935976)
			(xy 339.039362 -261.886922) (xy 339.051139 -261.839138) (xy 339.07043 -261.793862) (xy 339.096733 -261.752266)
			(xy 339.129368 -261.715429) (xy 339.167489 -261.684304) (xy 339.21011 -261.659697) (xy 339.256126 -261.642245)
			(xy 339.304345 -261.632401) (xy 339.35352 -261.63042) (xy 339.402375 -261.636352) (xy 339.449646 -261.650044)
			(xy 339.494108 -261.671142) (xy 339.534611 -261.699098) (xy 339.570104 -261.73319) (xy 339.599669 -261.772534)
			(xy 339.62254 -261.816111) (xy 339.638124 -261.862792) (xy 339.646019 -261.911369) (xy 339.646514 -261.935976)
			(xy 339.964771 -261.935976) (xy 339.968866 -261.885248) (xy 339.981045 -261.835834) (xy 340.000993 -261.789014)
			(xy 340.028194 -261.746) (xy 340.061942 -261.707906) (xy 340.101364 -261.675719) (xy 340.145438 -261.650273)
			(xy 340.193024 -261.632226) (xy 340.242888 -261.622046) (xy 340.29374 -261.619997) (xy 340.344261 -261.626131)
			(xy 340.393145 -261.640291) (xy 340.439124 -261.662108) (xy 340.481008 -261.691018) (xy 340.517712 -261.726273)
			(xy 340.548285 -261.766959) (xy 340.571936 -261.812022) (xy 340.588052 -261.860296) (xy 340.596216 -261.91053)
			(xy 340.596728 -261.935976) (xy 340.915256 -261.935976) (xy 340.919216 -261.886922) (xy 340.930993 -261.839138)
			(xy 340.950284 -261.793862) (xy 340.976587 -261.752266) (xy 341.009222 -261.715429) (xy 341.047343 -261.684304)
			(xy 341.089964 -261.659697) (xy 341.13598 -261.642245) (xy 341.184199 -261.632401) (xy 341.233374 -261.63042)
			(xy 341.282229 -261.636352) (xy 341.3295 -261.650044) (xy 341.373962 -261.671142) (xy 341.414465 -261.699098)
			(xy 341.449958 -261.73319) (xy 341.479523 -261.772534) (xy 341.502394 -261.816111) (xy 341.517978 -261.862792)
			(xy 341.525873 -261.911369) (xy 341.526368 -261.935976) (xy 341.85531 -261.935976) (xy 341.85927 -261.886922)
			(xy 341.871047 -261.839138) (xy 341.890338 -261.793862) (xy 341.916641 -261.752266) (xy 341.949276 -261.715429)
			(xy 341.987397 -261.684304) (xy 342.030018 -261.659697) (xy 342.076034 -261.642245) (xy 342.124253 -261.632401)
			(xy 342.173428 -261.63042) (xy 342.222283 -261.636352) (xy 342.269554 -261.650044) (xy 342.314016 -261.671142)
			(xy 342.354519 -261.699098) (xy 342.390012 -261.73319) (xy 342.419577 -261.772534) (xy 342.442448 -261.816111)
			(xy 342.458032 -261.862792) (xy 342.465927 -261.911369) (xy 342.466422 -261.935976) (xy 342.795364 -261.935976)
			(xy 342.799324 -261.886922) (xy 342.811101 -261.839138) (xy 342.830392 -261.793862) (xy 342.856695 -261.752266)
			(xy 342.88933 -261.715429) (xy 342.927451 -261.684304) (xy 342.970072 -261.659697) (xy 343.016088 -261.642245)
			(xy 343.064307 -261.632401) (xy 343.113482 -261.63042) (xy 343.162337 -261.636352) (xy 343.209608 -261.650044)
			(xy 343.25407 -261.671142) (xy 343.294573 -261.699098) (xy 343.330066 -261.73319) (xy 343.359631 -261.772534)
			(xy 343.382502 -261.816111) (xy 343.398086 -261.862792) (xy 343.405981 -261.911369) (xy 343.406476 -261.935976)
			(xy 343.724987 -261.935976) (xy 343.729082 -261.885248) (xy 343.741261 -261.835834) (xy 343.761209 -261.789014)
			(xy 343.78841 -261.746) (xy 343.822158 -261.707906) (xy 343.86158 -261.675719) (xy 343.905654 -261.650273)
			(xy 343.95324 -261.632226) (xy 344.003104 -261.622046) (xy 344.053956 -261.619997) (xy 344.104477 -261.626131)
			(xy 344.153361 -261.640291) (xy 344.19934 -261.662108) (xy 344.241224 -261.691018) (xy 344.277928 -261.726273)
			(xy 344.308501 -261.766959) (xy 344.332152 -261.812022) (xy 344.348268 -261.860296) (xy 344.356432 -261.91053)
			(xy 344.356944 -261.935976) (xy 345.615272 -261.935976) (xy 345.619232 -261.886922) (xy 345.631009 -261.839138)
			(xy 345.6503 -261.793862) (xy 345.676603 -261.752266) (xy 345.709238 -261.715429) (xy 345.747359 -261.684304)
			(xy 345.78998 -261.659697) (xy 345.835996 -261.642245) (xy 345.884215 -261.632401) (xy 345.93339 -261.63042)
			(xy 345.982245 -261.636352) (xy 346.029516 -261.650044) (xy 346.073978 -261.671142) (xy 346.114481 -261.699098)
			(xy 346.149974 -261.73319) (xy 346.179539 -261.772534) (xy 346.20241 -261.816111) (xy 346.217994 -261.862792)
			(xy 346.225889 -261.911369) (xy 346.226384 -261.935976) (xy 347.49538 -261.935976) (xy 347.49934 -261.886922)
			(xy 347.511117 -261.839138) (xy 347.530408 -261.793862) (xy 347.556711 -261.752266) (xy 347.589346 -261.715429)
			(xy 347.627467 -261.684304) (xy 347.670088 -261.659697) (xy 347.716104 -261.642245) (xy 347.764323 -261.632401)
			(xy 347.813498 -261.63042) (xy 347.862353 -261.636352) (xy 347.909624 -261.650044) (xy 347.954086 -261.671142)
			(xy 347.994589 -261.699098) (xy 348.030082 -261.73319) (xy 348.059647 -261.772534) (xy 348.082518 -261.816111)
			(xy 348.098102 -261.862792) (xy 348.105997 -261.911369) (xy 348.106492 -261.935976) (xy 349.375234 -261.935976)
			(xy 349.379194 -261.886922) (xy 349.390971 -261.839138) (xy 349.410262 -261.793862) (xy 349.436565 -261.752266)
			(xy 349.4692 -261.715429) (xy 349.507321 -261.684304) (xy 349.549942 -261.659697) (xy 349.595958 -261.642245)
			(xy 349.644177 -261.632401) (xy 349.693352 -261.63042) (xy 349.742207 -261.636352) (xy 349.789478 -261.650044)
			(xy 349.83394 -261.671142) (xy 349.874443 -261.699098) (xy 349.909936 -261.73319) (xy 349.939501 -261.772534)
			(xy 349.962372 -261.816111) (xy 349.977956 -261.862792) (xy 349.985851 -261.911369) (xy 349.986346 -261.935976)
			(xy 349.985851 -261.960583) (xy 349.977956 -262.00916) (xy 349.962372 -262.055841) (xy 349.939501 -262.099418)
			(xy 349.909936 -262.138762) (xy 349.874443 -262.172854) (xy 349.83394 -262.20081) (xy 349.789478 -262.221908)
			(xy 349.742207 -262.2356) (xy 349.693352 -262.241532) (xy 349.644177 -262.239551) (xy 349.595958 -262.229707)
			(xy 349.549942 -262.212255) (xy 349.507321 -262.187648) (xy 349.4692 -262.156523) (xy 349.436565 -262.119686)
			(xy 349.410262 -262.07809) (xy 349.390971 -262.032814) (xy 349.379194 -261.98503) (xy 349.375234 -261.935976)
			(xy 348.106492 -261.935976) (xy 348.105997 -261.960583) (xy 348.098102 -262.00916) (xy 348.082518 -262.055841)
			(xy 348.059647 -262.099418) (xy 348.030082 -262.138762) (xy 347.994589 -262.172854) (xy 347.954086 -262.20081)
			(xy 347.909624 -262.221908) (xy 347.862353 -262.2356) (xy 347.813498 -262.241532) (xy 347.764323 -262.239551)
			(xy 347.716104 -262.229707) (xy 347.670088 -262.212255) (xy 347.627467 -262.187648) (xy 347.589346 -262.156523)
			(xy 347.556711 -262.119686) (xy 347.530408 -262.07809) (xy 347.511117 -262.032814) (xy 347.49934 -261.98503)
			(xy 347.49538 -261.935976) (xy 346.226384 -261.935976) (xy 346.225889 -261.960583) (xy 346.217994 -262.00916)
			(xy 346.20241 -262.055841) (xy 346.179539 -262.099418) (xy 346.149974 -262.138762) (xy 346.114481 -262.172854)
			(xy 346.073978 -262.20081) (xy 346.029516 -262.221908) (xy 345.982245 -262.2356) (xy 345.93339 -262.241532)
			(xy 345.884215 -262.239551) (xy 345.835996 -262.229707) (xy 345.78998 -262.212255) (xy 345.747359 -262.187648)
			(xy 345.709238 -262.156523) (xy 345.676603 -262.119686) (xy 345.6503 -262.07809) (xy 345.631009 -262.032814)
			(xy 345.619232 -261.98503) (xy 345.615272 -261.935976) (xy 344.356944 -261.935976) (xy 344.356432 -261.961422)
			(xy 344.348268 -262.011656) (xy 344.332152 -262.05993) (xy 344.308501 -262.104993) (xy 344.277928 -262.145679)
			(xy 344.241224 -262.180934) (xy 344.19934 -262.209844) (xy 344.153361 -262.231661) (xy 344.104477 -262.245821)
			(xy 344.053956 -262.251955) (xy 344.003104 -262.249906) (xy 343.95324 -262.239726) (xy 343.905654 -262.221679)
			(xy 343.86158 -262.196233) (xy 343.822158 -262.164046) (xy 343.78841 -262.125952) (xy 343.761209 -262.082938)
			(xy 343.741261 -262.036118) (xy 343.729082 -261.986704) (xy 343.724987 -261.935976) (xy 343.406476 -261.935976)
			(xy 343.405981 -261.960583) (xy 343.398086 -262.00916) (xy 343.382502 -262.055841) (xy 343.359631 -262.099418)
			(xy 343.330066 -262.138762) (xy 343.294573 -262.172854) (xy 343.25407 -262.20081) (xy 343.209608 -262.221908)
			(xy 343.162337 -262.2356) (xy 343.113482 -262.241532) (xy 343.064307 -262.239551) (xy 343.016088 -262.229707)
			(xy 342.970072 -262.212255) (xy 342.927451 -262.187648) (xy 342.88933 -262.156523) (xy 342.856695 -262.119686)
			(xy 342.830392 -262.07809) (xy 342.811101 -262.032814) (xy 342.799324 -261.98503) (xy 342.795364 -261.935976)
			(xy 342.466422 -261.935976) (xy 342.465927 -261.960583) (xy 342.458032 -262.00916) (xy 342.442448 -262.055841)
			(xy 342.419577 -262.099418) (xy 342.390012 -262.138762) (xy 342.354519 -262.172854) (xy 342.314016 -262.20081)
			(xy 342.269554 -262.221908) (xy 342.222283 -262.2356) (xy 342.173428 -262.241532) (xy 342.124253 -262.239551)
			(xy 342.076034 -262.229707) (xy 342.030018 -262.212255) (xy 341.987397 -262.187648) (xy 341.949276 -262.156523)
			(xy 341.916641 -262.119686) (xy 341.890338 -262.07809) (xy 341.871047 -262.032814) (xy 341.85927 -261.98503)
			(xy 341.85531 -261.935976) (xy 341.526368 -261.935976) (xy 341.525873 -261.960583) (xy 341.517978 -262.00916)
			(xy 341.502394 -262.055841) (xy 341.479523 -262.099418) (xy 341.449958 -262.138762) (xy 341.414465 -262.172854)
			(xy 341.373962 -262.20081) (xy 341.3295 -262.221908) (xy 341.282229 -262.2356) (xy 341.233374 -262.241532)
			(xy 341.184199 -262.239551) (xy 341.13598 -262.229707) (xy 341.089964 -262.212255) (xy 341.047343 -262.187648)
			(xy 341.009222 -262.156523) (xy 340.976587 -262.119686) (xy 340.950284 -262.07809) (xy 340.930993 -262.032814)
			(xy 340.919216 -261.98503) (xy 340.915256 -261.935976) (xy 340.596728 -261.935976) (xy 340.596216 -261.961422)
			(xy 340.588052 -262.011656) (xy 340.571936 -262.05993) (xy 340.548285 -262.104993) (xy 340.517712 -262.145679)
			(xy 340.481008 -262.180934) (xy 340.439124 -262.209844) (xy 340.393145 -262.231661) (xy 340.344261 -262.245821)
			(xy 340.29374 -262.251955) (xy 340.242888 -262.249906) (xy 340.193024 -262.239726) (xy 340.145438 -262.221679)
			(xy 340.101364 -262.196233) (xy 340.061942 -262.164046) (xy 340.028194 -262.125952) (xy 340.000993 -262.082938)
			(xy 339.981045 -262.036118) (xy 339.968866 -261.986704) (xy 339.964771 -261.935976) (xy 339.646514 -261.935976)
			(xy 339.646019 -261.960583) (xy 339.638124 -262.00916) (xy 339.62254 -262.055841) (xy 339.599669 -262.099418)
			(xy 339.570104 -262.138762) (xy 339.534611 -262.172854) (xy 339.494108 -262.20081) (xy 339.449646 -262.221908)
			(xy 339.402375 -262.2356) (xy 339.35352 -262.241532) (xy 339.304345 -262.239551) (xy 339.256126 -262.229707)
			(xy 339.21011 -262.212255) (xy 339.167489 -262.187648) (xy 339.129368 -262.156523) (xy 339.096733 -262.119686)
			(xy 339.07043 -262.07809) (xy 339.051139 -262.032814) (xy 339.039362 -261.98503) (xy 339.035402 -261.935976)
			(xy 338.70646 -261.935976) (xy 338.705965 -261.960583) (xy 338.69807 -262.00916) (xy 338.682486 -262.055841)
			(xy 338.659615 -262.099418) (xy 338.63005 -262.138762) (xy 338.594557 -262.172854) (xy 338.554054 -262.20081)
			(xy 338.509592 -262.221908) (xy 338.462321 -262.2356) (xy 338.413466 -262.241532) (xy 338.364291 -262.239551)
			(xy 338.316072 -262.229707) (xy 338.270056 -262.212255) (xy 338.227435 -262.187648) (xy 338.189314 -262.156523)
			(xy 338.156679 -262.119686) (xy 338.130376 -262.07809) (xy 338.111085 -262.032814) (xy 338.099308 -261.98503)
			(xy 338.095348 -261.935976) (xy 337.766406 -261.935976) (xy 337.765911 -261.960583) (xy 337.758016 -262.00916)
			(xy 337.742432 -262.055841) (xy 337.719561 -262.099418) (xy 337.689996 -262.138762) (xy 337.654503 -262.172854)
			(xy 337.614 -262.20081) (xy 337.569538 -262.221908) (xy 337.522267 -262.2356) (xy 337.473412 -262.241532)
			(xy 337.424237 -262.239551) (xy 337.376018 -262.229707) (xy 337.330002 -262.212255) (xy 337.287381 -262.187648)
			(xy 337.24926 -262.156523) (xy 337.216625 -262.119686) (xy 337.190322 -262.07809) (xy 337.171031 -262.032814)
			(xy 337.159254 -261.98503) (xy 337.155294 -261.935976) (xy 336.826352 -261.935976) (xy 336.825857 -261.960583)
			(xy 336.817962 -262.00916) (xy 336.802378 -262.055841) (xy 336.779507 -262.099418) (xy 336.749942 -262.138762)
			(xy 336.714449 -262.172854) (xy 336.673946 -262.20081) (xy 336.629484 -262.221908) (xy 336.582213 -262.2356)
			(xy 336.533358 -262.241532) (xy 336.484183 -262.239551) (xy 336.435964 -262.229707) (xy 336.389948 -262.212255)
			(xy 336.347327 -262.187648) (xy 336.309206 -262.156523) (xy 336.276571 -262.119686) (xy 336.250268 -262.07809)
			(xy 336.230977 -262.032814) (xy 336.2192 -261.98503) (xy 336.21524 -261.935976) (xy 335.886298 -261.935976)
			(xy 335.885803 -261.960583) (xy 335.877908 -262.00916) (xy 335.862324 -262.055841) (xy 335.839453 -262.099418)
			(xy 335.809888 -262.138762) (xy 335.774395 -262.172854) (xy 335.733892 -262.20081) (xy 335.68943 -262.221908)
			(xy 335.642159 -262.2356) (xy 335.593304 -262.241532) (xy 335.544129 -262.239551) (xy 335.49591 -262.229707)
			(xy 335.449894 -262.212255) (xy 335.407273 -262.187648) (xy 335.369152 -262.156523) (xy 335.336517 -262.119686)
			(xy 335.310214 -262.07809) (xy 335.290923 -262.032814) (xy 335.279146 -261.98503) (xy 335.275186 -261.935976)
			(xy 334.946498 -261.935976) (xy 334.946003 -261.960583) (xy 334.938108 -262.00916) (xy 334.922524 -262.055841)
			(xy 334.899653 -262.099418) (xy 334.870088 -262.138762) (xy 334.834595 -262.172854) (xy 334.794092 -262.20081)
			(xy 334.74963 -262.221908) (xy 334.702359 -262.2356) (xy 334.653504 -262.241532) (xy 334.604329 -262.239551)
			(xy 334.55611 -262.229707) (xy 334.510094 -262.212255) (xy 334.467473 -262.187648) (xy 334.429352 -262.156523)
			(xy 334.396717 -262.119686) (xy 334.370414 -262.07809) (xy 334.351123 -262.032814) (xy 334.339346 -261.98503)
			(xy 334.335386 -261.935976) (xy 334.006444 -261.935976) (xy 334.005949 -261.960583) (xy 333.998054 -262.00916)
			(xy 333.98247 -262.055841) (xy 333.959599 -262.099418) (xy 333.930034 -262.138762) (xy 333.894541 -262.172854)
			(xy 333.854038 -262.20081) (xy 333.809576 -262.221908) (xy 333.762305 -262.2356) (xy 333.71345 -262.241532)
			(xy 333.664275 -262.239551) (xy 333.616056 -262.229707) (xy 333.57004 -262.212255) (xy 333.527419 -262.187648)
			(xy 333.489298 -262.156523) (xy 333.456663 -262.119686) (xy 333.43036 -262.07809) (xy 333.411069 -262.032814)
			(xy 333.399292 -261.98503) (xy 333.395332 -261.935976) (xy 333.06639 -261.935976) (xy 333.065895 -261.960583)
			(xy 333.058 -262.00916) (xy 333.042416 -262.055841) (xy 333.019545 -262.099418) (xy 332.98998 -262.138762)
			(xy 332.954487 -262.172854) (xy 332.913984 -262.20081) (xy 332.869522 -262.221908) (xy 332.822251 -262.2356)
			(xy 332.773396 -262.241532) (xy 332.724221 -262.239551) (xy 332.676002 -262.229707) (xy 332.629986 -262.212255)
			(xy 332.587365 -262.187648) (xy 332.549244 -262.156523) (xy 332.516609 -262.119686) (xy 332.490306 -262.07809)
			(xy 332.471015 -262.032814) (xy 332.459238 -261.98503) (xy 332.455278 -261.935976) (xy 332.126853 -261.935976)
			(xy 332.126855 -261.936) (xy 332.122684 -261.986339) (xy 332.110285 -262.035305) (xy 332.089996 -262.081563)
			(xy 332.06237 -262.123851) (xy 332.028161 -262.161015) (xy 331.988302 -262.192042) (xy 331.943879 -262.216086)
			(xy 331.896106 -262.23249) (xy 331.846284 -262.240808) (xy 331.821028 -262.241284) (xy 331.808265 -262.241144)
			(xy 331.782832 -262.238979) (xy 331.770228 -262.236966) (xy 331.743541 -262.231884) (xy 331.692411 -262.213546)
			(xy 331.645336 -262.186442) (xy 331.624178 -262.169402) (xy 331.61859 -262.16483) (xy 331.605636 -262.158988)
			(xy 331.59827 -262.157972) (xy 331.591061 -262.157291) (xy 331.576754 -262.159489) (xy 331.570076 -262.16229)
			(xy 331.487018 -262.200644) (xy 331.479149 -262.205085) (xy 331.466926 -262.218375) (xy 331.460051 -262.235071)
			(xy 331.459332 -262.244078) (xy 331.459332 -262.42772) (xy 331.459565 -262.434673) (xy 331.463291 -262.448071)
			(xy 331.466698 -262.454136) (xy 331.47 -262.459216) (xy 331.480414 -262.468868) (xy 331.487526 -262.472424)
			(xy 331.508977 -262.483651) (xy 331.54834 -262.511837) (xy 331.58277 -262.545872) (xy 331.611408 -262.584907)
			(xy 331.633536 -262.627968) (xy 331.648604 -262.673977) (xy 331.656234 -262.721785) (xy 331.656234 -262.745982)
			(xy 331.985378 -262.745982) (xy 331.989338 -262.696928) (xy 332.001115 -262.649144) (xy 332.020406 -262.603868)
			(xy 332.046709 -262.562272) (xy 332.079344 -262.525435) (xy 332.117465 -262.49431) (xy 332.160086 -262.469703)
			(xy 332.206102 -262.452251) (xy 332.254321 -262.442407) (xy 332.303496 -262.440426) (xy 332.352351 -262.446358)
			(xy 332.399622 -262.46005) (xy 332.444084 -262.481148) (xy 332.484587 -262.509104) (xy 332.52008 -262.543196)
			(xy 332.549645 -262.58254) (xy 332.572516 -262.626117) (xy 332.5881 -262.672798) (xy 332.595995 -262.721375)
			(xy 332.59649 -262.745982) (xy 332.925178 -262.745982) (xy 332.929138 -262.696928) (xy 332.940915 -262.649144)
			(xy 332.960206 -262.603868) (xy 332.986509 -262.562272) (xy 333.019144 -262.525435) (xy 333.057265 -262.49431)
			(xy 333.099886 -262.469703) (xy 333.145902 -262.452251) (xy 333.194121 -262.442407) (xy 333.243296 -262.440426)
			(xy 333.292151 -262.446358) (xy 333.339422 -262.46005) (xy 333.383884 -262.481148) (xy 333.424387 -262.509104)
			(xy 333.45988 -262.543196) (xy 333.489445 -262.58254) (xy 333.512316 -262.626117) (xy 333.5279 -262.672798)
			(xy 333.535795 -262.721375) (xy 333.53629 -262.745982) (xy 333.865232 -262.745982) (xy 333.869192 -262.696928)
			(xy 333.880969 -262.649144) (xy 333.90026 -262.603868) (xy 333.926563 -262.562272) (xy 333.959198 -262.525435)
			(xy 333.997319 -262.49431) (xy 334.03994 -262.469703) (xy 334.085956 -262.452251) (xy 334.134175 -262.442407)
			(xy 334.18335 -262.440426) (xy 334.232205 -262.446358) (xy 334.279476 -262.46005) (xy 334.323938 -262.481148)
			(xy 334.364441 -262.509104) (xy 334.399934 -262.543196) (xy 334.429499 -262.58254) (xy 334.45237 -262.626117)
			(xy 334.467954 -262.672798) (xy 334.475849 -262.721375) (xy 334.476344 -262.745982) (xy 334.805286 -262.745982)
			(xy 334.809246 -262.696928) (xy 334.821023 -262.649144) (xy 334.840314 -262.603868) (xy 334.866617 -262.562272)
			(xy 334.899252 -262.525435) (xy 334.937373 -262.49431) (xy 334.979994 -262.469703) (xy 335.02601 -262.452251)
			(xy 335.074229 -262.442407) (xy 335.123404 -262.440426) (xy 335.172259 -262.446358) (xy 335.21953 -262.46005)
			(xy 335.263992 -262.481148) (xy 335.304495 -262.509104) (xy 335.339988 -262.543196) (xy 335.369553 -262.58254)
			(xy 335.392424 -262.626117) (xy 335.408008 -262.672798) (xy 335.415903 -262.721375) (xy 335.416398 -262.745982)
			(xy 335.74534 -262.745982) (xy 335.7493 -262.696928) (xy 335.761077 -262.649144) (xy 335.780368 -262.603868)
			(xy 335.806671 -262.562272) (xy 335.839306 -262.525435) (xy 335.877427 -262.49431) (xy 335.920048 -262.469703)
			(xy 335.966064 -262.452251) (xy 336.014283 -262.442407) (xy 336.063458 -262.440426) (xy 336.112313 -262.446358)
			(xy 336.159584 -262.46005) (xy 336.204046 -262.481148) (xy 336.244549 -262.509104) (xy 336.280042 -262.543196)
			(xy 336.309607 -262.58254) (xy 336.332478 -262.626117) (xy 336.348062 -262.672798) (xy 336.355957 -262.721375)
			(xy 336.356452 -262.745982) (xy 336.685394 -262.745982) (xy 336.689354 -262.696928) (xy 336.701131 -262.649144)
			(xy 336.720422 -262.603868) (xy 336.746725 -262.562272) (xy 336.77936 -262.525435) (xy 336.817481 -262.49431)
			(xy 336.860102 -262.469703) (xy 336.906118 -262.452251) (xy 336.954337 -262.442407) (xy 337.003512 -262.440426)
			(xy 337.052367 -262.446358) (xy 337.099638 -262.46005) (xy 337.1441 -262.481148) (xy 337.184603 -262.509104)
			(xy 337.220096 -262.543196) (xy 337.249661 -262.58254) (xy 337.272532 -262.626117) (xy 337.288116 -262.672798)
			(xy 337.296011 -262.721375) (xy 337.296506 -262.745982) (xy 337.625194 -262.745982) (xy 337.629154 -262.696928)
			(xy 337.640931 -262.649144) (xy 337.660222 -262.603868) (xy 337.686525 -262.562272) (xy 337.71916 -262.525435)
			(xy 337.757281 -262.49431) (xy 337.799902 -262.469703) (xy 337.845918 -262.452251) (xy 337.894137 -262.442407)
			(xy 337.943312 -262.440426) (xy 337.992167 -262.446358) (xy 338.039438 -262.46005) (xy 338.0839 -262.481148)
			(xy 338.124403 -262.509104) (xy 338.159896 -262.543196) (xy 338.189461 -262.58254) (xy 338.212332 -262.626117)
			(xy 338.227916 -262.672798) (xy 338.235811 -262.721375) (xy 338.236306 -262.745982) (xy 338.554817 -262.745982)
			(xy 338.558912 -262.695254) (xy 338.571091 -262.64584) (xy 338.591039 -262.59902) (xy 338.61824 -262.556006)
			(xy 338.651988 -262.517912) (xy 338.69141 -262.485725) (xy 338.735484 -262.460279) (xy 338.78307 -262.442232)
			(xy 338.832934 -262.432052) (xy 338.883786 -262.430003) (xy 338.934307 -262.436137) (xy 338.983191 -262.450297)
			(xy 339.02917 -262.472114) (xy 339.071054 -262.501024) (xy 339.107758 -262.536279) (xy 339.138331 -262.576965)
			(xy 339.161982 -262.622028) (xy 339.178098 -262.670302) (xy 339.186262 -262.720536) (xy 339.186774 -262.745982)
			(xy 339.505302 -262.745982) (xy 339.509262 -262.696928) (xy 339.521039 -262.649144) (xy 339.54033 -262.603868)
			(xy 339.566633 -262.562272) (xy 339.599268 -262.525435) (xy 339.637389 -262.49431) (xy 339.68001 -262.469703)
			(xy 339.726026 -262.452251) (xy 339.774245 -262.442407) (xy 339.82342 -262.440426) (xy 339.872275 -262.446358)
			(xy 339.919546 -262.46005) (xy 339.964008 -262.481148) (xy 340.004511 -262.509104) (xy 340.040004 -262.543196)
			(xy 340.069569 -262.58254) (xy 340.09244 -262.626117) (xy 340.108024 -262.672798) (xy 340.115919 -262.721375)
			(xy 340.116414 -262.745982) (xy 340.434925 -262.745982) (xy 340.43902 -262.695254) (xy 340.451199 -262.64584)
			(xy 340.471147 -262.59902) (xy 340.498348 -262.556006) (xy 340.532096 -262.517912) (xy 340.571518 -262.485725)
			(xy 340.615592 -262.460279) (xy 340.663178 -262.442232) (xy 340.713042 -262.432052) (xy 340.763894 -262.430003)
			(xy 340.814415 -262.436137) (xy 340.863299 -262.450297) (xy 340.909278 -262.472114) (xy 340.951162 -262.501024)
			(xy 340.987866 -262.536279) (xy 341.018439 -262.576965) (xy 341.04209 -262.622028) (xy 341.058206 -262.670302)
			(xy 341.06637 -262.720536) (xy 341.066882 -262.745982) (xy 341.38541 -262.745982) (xy 341.38937 -262.696928)
			(xy 341.401147 -262.649144) (xy 341.420438 -262.603868) (xy 341.446741 -262.562272) (xy 341.479376 -262.525435)
			(xy 341.517497 -262.49431) (xy 341.560118 -262.469703) (xy 341.606134 -262.452251) (xy 341.654353 -262.442407)
			(xy 341.703528 -262.440426) (xy 341.752383 -262.446358) (xy 341.799654 -262.46005) (xy 341.844116 -262.481148)
			(xy 341.884619 -262.509104) (xy 341.920112 -262.543196) (xy 341.949677 -262.58254) (xy 341.972548 -262.626117)
			(xy 341.988132 -262.672798) (xy 341.996027 -262.721375) (xy 341.996522 -262.745982) (xy 342.314779 -262.745982)
			(xy 342.318874 -262.695254) (xy 342.331053 -262.64584) (xy 342.351001 -262.59902) (xy 342.378202 -262.556006)
			(xy 342.41195 -262.517912) (xy 342.451372 -262.485725) (xy 342.495446 -262.460279) (xy 342.543032 -262.442232)
			(xy 342.592896 -262.432052) (xy 342.643748 -262.430003) (xy 342.694269 -262.436137) (xy 342.743153 -262.450297)
			(xy 342.789132 -262.472114) (xy 342.831016 -262.501024) (xy 342.86772 -262.536279) (xy 342.898293 -262.576965)
			(xy 342.921944 -262.622028) (xy 342.93806 -262.670302) (xy 342.946224 -262.720536) (xy 342.946736 -262.745982)
			(xy 343.254833 -262.745982) (xy 343.258928 -262.695254) (xy 343.271107 -262.64584) (xy 343.291055 -262.59902)
			(xy 343.318256 -262.556006) (xy 343.352004 -262.517912) (xy 343.391426 -262.485725) (xy 343.4355 -262.460279)
			(xy 343.483086 -262.442232) (xy 343.53295 -262.432052) (xy 343.583802 -262.430003) (xy 343.634323 -262.436137)
			(xy 343.683207 -262.450297) (xy 343.729186 -262.472114) (xy 343.77107 -262.501024) (xy 343.807774 -262.536279)
			(xy 343.838347 -262.576965) (xy 343.861998 -262.622028) (xy 343.878114 -262.670302) (xy 343.886278 -262.720536)
			(xy 343.88679 -262.745982) (xy 344.205318 -262.745982) (xy 344.209278 -262.696928) (xy 344.221055 -262.649144)
			(xy 344.240346 -262.603868) (xy 344.266649 -262.562272) (xy 344.299284 -262.525435) (xy 344.337405 -262.49431)
			(xy 344.380026 -262.469703) (xy 344.426042 -262.452251) (xy 344.474261 -262.442407) (xy 344.523436 -262.440426)
			(xy 344.572291 -262.446358) (xy 344.619562 -262.46005) (xy 344.664024 -262.481148) (xy 344.704527 -262.509104)
			(xy 344.74002 -262.543196) (xy 344.769585 -262.58254) (xy 344.792456 -262.626117) (xy 344.80804 -262.672798)
			(xy 344.815935 -262.721375) (xy 344.81643 -262.745982) (xy 346.085426 -262.745982) (xy 346.089386 -262.696928)
			(xy 346.101163 -262.649144) (xy 346.120454 -262.603868) (xy 346.146757 -262.562272) (xy 346.179392 -262.525435)
			(xy 346.217513 -262.49431) (xy 346.260134 -262.469703) (xy 346.30615 -262.452251) (xy 346.354369 -262.442407)
			(xy 346.403544 -262.440426) (xy 346.452399 -262.446358) (xy 346.49967 -262.46005) (xy 346.544132 -262.481148)
			(xy 346.584635 -262.509104) (xy 346.620128 -262.543196) (xy 346.649693 -262.58254) (xy 346.672564 -262.626117)
			(xy 346.688148 -262.672798) (xy 346.696043 -262.721375) (xy 346.696538 -262.745982) (xy 347.96528 -262.745982)
			(xy 347.96924 -262.696928) (xy 347.981017 -262.649144) (xy 348.000308 -262.603868) (xy 348.026611 -262.562272)
			(xy 348.059246 -262.525435) (xy 348.097367 -262.49431) (xy 348.139988 -262.469703) (xy 348.186004 -262.452251)
			(xy 348.234223 -262.442407) (xy 348.283398 -262.440426) (xy 348.332253 -262.446358) (xy 348.379524 -262.46005)
			(xy 348.423986 -262.481148) (xy 348.464489 -262.509104) (xy 348.499982 -262.543196) (xy 348.529547 -262.58254)
			(xy 348.552418 -262.626117) (xy 348.568002 -262.672798) (xy 348.575897 -262.721375) (xy 348.576392 -262.745982)
			(xy 348.905334 -262.745982) (xy 348.909294 -262.696928) (xy 348.921071 -262.649144) (xy 348.940362 -262.603868)
			(xy 348.966665 -262.562272) (xy 348.9993 -262.525435) (xy 349.037421 -262.49431) (xy 349.080042 -262.469703)
			(xy 349.126058 -262.452251) (xy 349.174277 -262.442407) (xy 349.223452 -262.440426) (xy 349.272307 -262.446358)
			(xy 349.319578 -262.46005) (xy 349.36404 -262.481148) (xy 349.404543 -262.509104) (xy 349.440036 -262.543196)
			(xy 349.469601 -262.58254) (xy 349.492472 -262.626117) (xy 349.508056 -262.672798) (xy 349.515951 -262.721375)
			(xy 349.516446 -262.745982) (xy 349.515951 -262.770589) (xy 349.508056 -262.819166) (xy 349.492472 -262.865847)
			(xy 349.469601 -262.909424) (xy 349.440036 -262.948768) (xy 349.404543 -262.98286) (xy 349.36404 -263.010816)
			(xy 349.319578 -263.031914) (xy 349.272307 -263.045606) (xy 349.223452 -263.051538) (xy 349.174277 -263.049557)
			(xy 349.126058 -263.039713) (xy 349.080042 -263.022261) (xy 349.037421 -262.997654) (xy 348.9993 -262.966529)
			(xy 348.966665 -262.929692) (xy 348.940362 -262.888096) (xy 348.921071 -262.84282) (xy 348.909294 -262.795036)
			(xy 348.905334 -262.745982) (xy 348.576392 -262.745982) (xy 348.575897 -262.770589) (xy 348.568002 -262.819166)
			(xy 348.552418 -262.865847) (xy 348.529547 -262.909424) (xy 348.499982 -262.948768) (xy 348.464489 -262.98286)
			(xy 348.423986 -263.010816) (xy 348.379524 -263.031914) (xy 348.332253 -263.045606) (xy 348.283398 -263.051538)
			(xy 348.234223 -263.049557) (xy 348.186004 -263.039713) (xy 348.139988 -263.022261) (xy 348.097367 -262.997654)
			(xy 348.059246 -262.966529) (xy 348.026611 -262.929692) (xy 348.000308 -262.888096) (xy 347.981017 -262.84282)
			(xy 347.96924 -262.795036) (xy 347.96528 -262.745982) (xy 346.696538 -262.745982) (xy 346.696043 -262.770589)
			(xy 346.688148 -262.819166) (xy 346.672564 -262.865847) (xy 346.649693 -262.909424) (xy 346.620128 -262.948768)
			(xy 346.584635 -262.98286) (xy 346.544132 -263.010816) (xy 346.49967 -263.031914) (xy 346.452399 -263.045606)
			(xy 346.403544 -263.051538) (xy 346.354369 -263.049557) (xy 346.30615 -263.039713) (xy 346.260134 -263.022261)
			(xy 346.217513 -262.997654) (xy 346.179392 -262.966529) (xy 346.146757 -262.929692) (xy 346.120454 -262.888096)
			(xy 346.101163 -262.84282) (xy 346.089386 -262.795036) (xy 346.085426 -262.745982) (xy 344.81643 -262.745982)
			(xy 344.815935 -262.770589) (xy 344.80804 -262.819166) (xy 344.792456 -262.865847) (xy 344.769585 -262.909424)
			(xy 344.74002 -262.948768) (xy 344.704527 -262.98286) (xy 344.664024 -263.010816) (xy 344.619562 -263.031914)
			(xy 344.572291 -263.045606) (xy 344.523436 -263.051538) (xy 344.474261 -263.049557) (xy 344.426042 -263.039713)
			(xy 344.380026 -263.022261) (xy 344.337405 -262.997654) (xy 344.299284 -262.966529) (xy 344.266649 -262.929692)
			(xy 344.240346 -262.888096) (xy 344.221055 -262.84282) (xy 344.209278 -262.795036) (xy 344.205318 -262.745982)
			(xy 343.88679 -262.745982) (xy 343.886278 -262.771428) (xy 343.878114 -262.821662) (xy 343.861998 -262.869936)
			(xy 343.838347 -262.914999) (xy 343.807774 -262.955685) (xy 343.77107 -262.99094) (xy 343.729186 -263.01985)
			(xy 343.683207 -263.041667) (xy 343.634323 -263.055827) (xy 343.583802 -263.061961) (xy 343.53295 -263.059912)
			(xy 343.483086 -263.049732) (xy 343.4355 -263.031685) (xy 343.391426 -263.006239) (xy 343.352004 -262.974052)
			(xy 343.318256 -262.935958) (xy 343.291055 -262.892944) (xy 343.271107 -262.846124) (xy 343.258928 -262.79671)
			(xy 343.254833 -262.745982) (xy 342.946736 -262.745982) (xy 342.946224 -262.771428) (xy 342.93806 -262.821662)
			(xy 342.921944 -262.869936) (xy 342.898293 -262.914999) (xy 342.86772 -262.955685) (xy 342.831016 -262.99094)
			(xy 342.789132 -263.01985) (xy 342.743153 -263.041667) (xy 342.694269 -263.055827) (xy 342.643748 -263.061961)
			(xy 342.592896 -263.059912) (xy 342.543032 -263.049732) (xy 342.495446 -263.031685) (xy 342.451372 -263.006239)
			(xy 342.41195 -262.974052) (xy 342.378202 -262.935958) (xy 342.351001 -262.892944) (xy 342.331053 -262.846124)
			(xy 342.318874 -262.79671) (xy 342.314779 -262.745982) (xy 341.996522 -262.745982) (xy 341.996027 -262.770589)
			(xy 341.988132 -262.819166) (xy 341.972548 -262.865847) (xy 341.949677 -262.909424) (xy 341.920112 -262.948768)
			(xy 341.884619 -262.98286) (xy 341.844116 -263.010816) (xy 341.799654 -263.031914) (xy 341.752383 -263.045606)
			(xy 341.703528 -263.051538) (xy 341.654353 -263.049557) (xy 341.606134 -263.039713) (xy 341.560118 -263.022261)
			(xy 341.517497 -262.997654) (xy 341.479376 -262.966529) (xy 341.446741 -262.929692) (xy 341.420438 -262.888096)
			(xy 341.401147 -262.84282) (xy 341.38937 -262.795036) (xy 341.38541 -262.745982) (xy 341.066882 -262.745982)
			(xy 341.06637 -262.771428) (xy 341.058206 -262.821662) (xy 341.04209 -262.869936) (xy 341.018439 -262.914999)
			(xy 340.987866 -262.955685) (xy 340.951162 -262.99094) (xy 340.909278 -263.01985) (xy 340.863299 -263.041667)
			(xy 340.814415 -263.055827) (xy 340.763894 -263.061961) (xy 340.713042 -263.059912) (xy 340.663178 -263.049732)
			(xy 340.615592 -263.031685) (xy 340.571518 -263.006239) (xy 340.532096 -262.974052) (xy 340.498348 -262.935958)
			(xy 340.471147 -262.892944) (xy 340.451199 -262.846124) (xy 340.43902 -262.79671) (xy 340.434925 -262.745982)
			(xy 340.116414 -262.745982) (xy 340.115919 -262.770589) (xy 340.108024 -262.819166) (xy 340.09244 -262.865847)
			(xy 340.069569 -262.909424) (xy 340.040004 -262.948768) (xy 340.004511 -262.98286) (xy 339.964008 -263.010816)
			(xy 339.919546 -263.031914) (xy 339.872275 -263.045606) (xy 339.82342 -263.051538) (xy 339.774245 -263.049557)
			(xy 339.726026 -263.039713) (xy 339.68001 -263.022261) (xy 339.637389 -262.997654) (xy 339.599268 -262.966529)
			(xy 339.566633 -262.929692) (xy 339.54033 -262.888096) (xy 339.521039 -262.84282) (xy 339.509262 -262.795036)
			(xy 339.505302 -262.745982) (xy 339.186774 -262.745982) (xy 339.186262 -262.771428) (xy 339.178098 -262.821662)
			(xy 339.161982 -262.869936) (xy 339.138331 -262.914999) (xy 339.107758 -262.955685) (xy 339.071054 -262.99094)
			(xy 339.02917 -263.01985) (xy 338.983191 -263.041667) (xy 338.934307 -263.055827) (xy 338.883786 -263.061961)
			(xy 338.832934 -263.059912) (xy 338.78307 -263.049732) (xy 338.735484 -263.031685) (xy 338.69141 -263.006239)
			(xy 338.651988 -262.974052) (xy 338.61824 -262.935958) (xy 338.591039 -262.892944) (xy 338.571091 -262.846124)
			(xy 338.558912 -262.79671) (xy 338.554817 -262.745982) (xy 338.236306 -262.745982) (xy 338.235811 -262.770589)
			(xy 338.227916 -262.819166) (xy 338.212332 -262.865847) (xy 338.189461 -262.909424) (xy 338.159896 -262.948768)
			(xy 338.124403 -262.98286) (xy 338.0839 -263.010816) (xy 338.039438 -263.031914) (xy 337.992167 -263.045606)
			(xy 337.943312 -263.051538) (xy 337.894137 -263.049557) (xy 337.845918 -263.039713) (xy 337.799902 -263.022261)
			(xy 337.757281 -262.997654) (xy 337.71916 -262.966529) (xy 337.686525 -262.929692) (xy 337.660222 -262.888096)
			(xy 337.640931 -262.84282) (xy 337.629154 -262.795036) (xy 337.625194 -262.745982) (xy 337.296506 -262.745982)
			(xy 337.296011 -262.770589) (xy 337.288116 -262.819166) (xy 337.272532 -262.865847) (xy 337.249661 -262.909424)
			(xy 337.220096 -262.948768) (xy 337.184603 -262.98286) (xy 337.1441 -263.010816) (xy 337.099638 -263.031914)
			(xy 337.052367 -263.045606) (xy 337.003512 -263.051538) (xy 336.954337 -263.049557) (xy 336.906118 -263.039713)
			(xy 336.860102 -263.022261) (xy 336.817481 -262.997654) (xy 336.77936 -262.966529) (xy 336.746725 -262.929692)
			(xy 336.720422 -262.888096) (xy 336.701131 -262.84282) (xy 336.689354 -262.795036) (xy 336.685394 -262.745982)
			(xy 336.356452 -262.745982) (xy 336.355957 -262.770589) (xy 336.348062 -262.819166) (xy 336.332478 -262.865847)
			(xy 336.309607 -262.909424) (xy 336.280042 -262.948768) (xy 336.244549 -262.98286) (xy 336.204046 -263.010816)
			(xy 336.159584 -263.031914) (xy 336.112313 -263.045606) (xy 336.063458 -263.051538) (xy 336.014283 -263.049557)
			(xy 335.966064 -263.039713) (xy 335.920048 -263.022261) (xy 335.877427 -262.997654) (xy 335.839306 -262.966529)
			(xy 335.806671 -262.929692) (xy 335.780368 -262.888096) (xy 335.761077 -262.84282) (xy 335.7493 -262.795036)
			(xy 335.74534 -262.745982) (xy 335.416398 -262.745982) (xy 335.415903 -262.770589) (xy 335.408008 -262.819166)
			(xy 335.392424 -262.865847) (xy 335.369553 -262.909424) (xy 335.339988 -262.948768) (xy 335.304495 -262.98286)
			(xy 335.263992 -263.010816) (xy 335.21953 -263.031914) (xy 335.172259 -263.045606) (xy 335.123404 -263.051538)
			(xy 335.074229 -263.049557) (xy 335.02601 -263.039713) (xy 334.979994 -263.022261) (xy 334.937373 -262.997654)
			(xy 334.899252 -262.966529) (xy 334.866617 -262.929692) (xy 334.840314 -262.888096) (xy 334.821023 -262.84282)
			(xy 334.809246 -262.795036) (xy 334.805286 -262.745982) (xy 334.476344 -262.745982) (xy 334.475849 -262.770589)
			(xy 334.467954 -262.819166) (xy 334.45237 -262.865847) (xy 334.429499 -262.909424) (xy 334.399934 -262.948768)
			(xy 334.364441 -262.98286) (xy 334.323938 -263.010816) (xy 334.279476 -263.031914) (xy 334.232205 -263.045606)
			(xy 334.18335 -263.051538) (xy 334.134175 -263.049557) (xy 334.085956 -263.039713) (xy 334.03994 -263.022261)
			(xy 333.997319 -262.997654) (xy 333.959198 -262.966529) (xy 333.926563 -262.929692) (xy 333.90026 -262.888096)
			(xy 333.880969 -262.84282) (xy 333.869192 -262.795036) (xy 333.865232 -262.745982) (xy 333.53629 -262.745982)
			(xy 333.535795 -262.770589) (xy 333.5279 -262.819166) (xy 333.512316 -262.865847) (xy 333.489445 -262.909424)
			(xy 333.45988 -262.948768) (xy 333.424387 -262.98286) (xy 333.383884 -263.010816) (xy 333.339422 -263.031914)
			(xy 333.292151 -263.045606) (xy 333.243296 -263.051538) (xy 333.194121 -263.049557) (xy 333.145902 -263.039713)
			(xy 333.099886 -263.022261) (xy 333.057265 -262.997654) (xy 333.019144 -262.966529) (xy 332.986509 -262.929692)
			(xy 332.960206 -262.888096) (xy 332.940915 -262.84282) (xy 332.929138 -262.795036) (xy 332.925178 -262.745982)
			(xy 332.59649 -262.745982) (xy 332.595995 -262.770589) (xy 332.5881 -262.819166) (xy 332.572516 -262.865847)
			(xy 332.549645 -262.909424) (xy 332.52008 -262.948768) (xy 332.484587 -262.98286) (xy 332.444084 -263.010816)
			(xy 332.399622 -263.031914) (xy 332.352351 -263.045606) (xy 332.303496 -263.051538) (xy 332.254321 -263.049557)
			(xy 332.206102 -263.039713) (xy 332.160086 -263.022261) (xy 332.117465 -262.997654) (xy 332.079344 -262.966529)
			(xy 332.046709 -262.929692) (xy 332.020406 -262.888096) (xy 332.001115 -262.84282) (xy 331.989338 -262.795036)
			(xy 331.985378 -262.745982) (xy 331.656234 -262.745982) (xy 331.656235 -262.770199) (xy 331.648608 -262.818008)
			(xy 331.633543 -262.864018) (xy 331.611416 -262.907079) (xy 331.582781 -262.946116) (xy 331.548352 -262.980153)
			(xy 331.50899 -263.00834) (xy 331.487526 -263.01954) (xy 331.486764 -263.019794) (xy 331.480507 -263.023196)
			(xy 331.470056 -263.032863) (xy 331.46619 -263.038844) (xy 331.463142 -263.043924) (xy 331.459332 -263.057132)
			(xy 331.459332 -263.246108) (xy 331.459799 -263.255484) (xy 331.466637 -263.272948) (xy 331.479314 -263.28677)
			(xy 331.487526 -263.29132) (xy 331.518006 -263.305544) (xy 331.566266 -263.327896) (xy 331.56955 -263.329392)
			(xy 331.576433 -263.331563) (xy 331.579982 -263.332214) (xy 331.584357 -263.332765) (xy 331.593171 -263.332508)
			(xy 331.597508 -263.331706) (xy 331.605382 -263.329674) (xy 331.62367 -263.322816) (xy 331.63002 -263.317736)
			(xy 331.6505 -263.302023) (xy 331.695636 -263.276986) (xy 331.744338 -263.259891) (xy 331.79522 -263.251222)
			(xy 331.821028 -263.25068) (xy 331.846283 -263.251204) (xy 331.896103 -263.259522) (xy 331.943875 -263.275925)
			(xy 331.988295 -263.299968) (xy 332.028153 -263.330994) (xy 332.06236 -263.368157) (xy 332.089985 -263.410443)
			(xy 332.110274 -263.456699) (xy 332.122672 -263.505663) (xy 332.126842 -263.555988) (xy 332.455278 -263.555988)
			(xy 332.459238 -263.506934) (xy 332.471015 -263.45915) (xy 332.490306 -263.413874) (xy 332.516609 -263.372278)
			(xy 332.549244 -263.335441) (xy 332.587365 -263.304316) (xy 332.629986 -263.279709) (xy 332.676002 -263.262257)
			(xy 332.724221 -263.252413) (xy 332.773396 -263.250432) (xy 332.822251 -263.256364) (xy 332.869522 -263.270056)
			(xy 332.913984 -263.291154) (xy 332.954487 -263.31911) (xy 332.98998 -263.353202) (xy 333.019545 -263.392546)
			(xy 333.042416 -263.436123) (xy 333.058 -263.482804) (xy 333.065895 -263.531381) (xy 333.06639 -263.555988)
			(xy 333.395332 -263.555988) (xy 333.399292 -263.506934) (xy 333.411069 -263.45915) (xy 333.43036 -263.413874)
			(xy 333.456663 -263.372278) (xy 333.489298 -263.335441) (xy 333.527419 -263.304316) (xy 333.57004 -263.279709)
			(xy 333.616056 -263.262257) (xy 333.664275 -263.252413) (xy 333.71345 -263.250432) (xy 333.762305 -263.256364)
			(xy 333.809576 -263.270056) (xy 333.854038 -263.291154) (xy 333.894541 -263.31911) (xy 333.930034 -263.353202)
			(xy 333.959599 -263.392546) (xy 333.98247 -263.436123) (xy 333.998054 -263.482804) (xy 334.005949 -263.531381)
			(xy 334.006444 -263.555988) (xy 335.275186 -263.555988) (xy 335.279146 -263.506934) (xy 335.290923 -263.45915)
			(xy 335.310214 -263.413874) (xy 335.336517 -263.372278) (xy 335.369152 -263.335441) (xy 335.407273 -263.304316)
			(xy 335.449894 -263.279709) (xy 335.49591 -263.262257) (xy 335.544129 -263.252413) (xy 335.593304 -263.250432)
			(xy 335.642159 -263.256364) (xy 335.68943 -263.270056) (xy 335.733892 -263.291154) (xy 335.774395 -263.31911)
			(xy 335.809888 -263.353202) (xy 335.839453 -263.392546) (xy 335.862324 -263.436123) (xy 335.877908 -263.482804)
			(xy 335.885803 -263.531381) (xy 335.886298 -263.555988) (xy 336.21524 -263.555988) (xy 336.2192 -263.506934)
			(xy 336.230977 -263.45915) (xy 336.250268 -263.413874) (xy 336.276571 -263.372278) (xy 336.309206 -263.335441)
			(xy 336.347327 -263.304316) (xy 336.389948 -263.279709) (xy 336.435964 -263.262257) (xy 336.484183 -263.252413)
			(xy 336.533358 -263.250432) (xy 336.582213 -263.256364) (xy 336.629484 -263.270056) (xy 336.673946 -263.291154)
			(xy 336.714449 -263.31911) (xy 336.749942 -263.353202) (xy 336.779507 -263.392546) (xy 336.802378 -263.436123)
			(xy 336.817962 -263.482804) (xy 336.825857 -263.531381) (xy 336.826352 -263.555988) (xy 337.155294 -263.555988)
			(xy 337.159254 -263.506934) (xy 337.171031 -263.45915) (xy 337.190322 -263.413874) (xy 337.216625 -263.372278)
			(xy 337.24926 -263.335441) (xy 337.287381 -263.304316) (xy 337.330002 -263.279709) (xy 337.376018 -263.262257)
			(xy 337.424237 -263.252413) (xy 337.473412 -263.250432) (xy 337.522267 -263.256364) (xy 337.569538 -263.270056)
			(xy 337.614 -263.291154) (xy 337.654503 -263.31911) (xy 337.689996 -263.353202) (xy 337.719561 -263.392546)
			(xy 337.742432 -263.436123) (xy 337.758016 -263.482804) (xy 337.765911 -263.531381) (xy 337.766406 -263.555988)
			(xy 338.095348 -263.555988) (xy 338.099308 -263.506934) (xy 338.111085 -263.45915) (xy 338.130376 -263.413874)
			(xy 338.156679 -263.372278) (xy 338.189314 -263.335441) (xy 338.227435 -263.304316) (xy 338.270056 -263.279709)
			(xy 338.316072 -263.262257) (xy 338.364291 -263.252413) (xy 338.413466 -263.250432) (xy 338.462321 -263.256364)
			(xy 338.509592 -263.270056) (xy 338.554054 -263.291154) (xy 338.594557 -263.31911) (xy 338.63005 -263.353202)
			(xy 338.659615 -263.392546) (xy 338.682486 -263.436123) (xy 338.69807 -263.482804) (xy 338.705965 -263.531381)
			(xy 338.70646 -263.555988) (xy 339.024971 -263.555988) (xy 339.029066 -263.50526) (xy 339.041245 -263.455846)
			(xy 339.061193 -263.409026) (xy 339.088394 -263.366012) (xy 339.122142 -263.327918) (xy 339.161564 -263.295731)
			(xy 339.205638 -263.270285) (xy 339.253224 -263.252238) (xy 339.303088 -263.242058) (xy 339.35394 -263.240009)
			(xy 339.404461 -263.246143) (xy 339.453345 -263.260303) (xy 339.499324 -263.28212) (xy 339.541208 -263.31103)
			(xy 339.577912 -263.346285) (xy 339.608485 -263.386971) (xy 339.632136 -263.432034) (xy 339.648252 -263.480308)
			(xy 339.656416 -263.530542) (xy 339.656928 -263.555988) (xy 339.964771 -263.555988) (xy 339.968866 -263.50526)
			(xy 339.981045 -263.455846) (xy 340.000993 -263.409026) (xy 340.028194 -263.366012) (xy 340.061942 -263.327918)
			(xy 340.101364 -263.295731) (xy 340.145438 -263.270285) (xy 340.193024 -263.252238) (xy 340.242888 -263.242058)
			(xy 340.29374 -263.240009) (xy 340.344261 -263.246143) (xy 340.393145 -263.260303) (xy 340.439124 -263.28212)
			(xy 340.481008 -263.31103) (xy 340.517712 -263.346285) (xy 340.548285 -263.386971) (xy 340.571936 -263.432034)
			(xy 340.588052 -263.480308) (xy 340.596216 -263.530542) (xy 340.596728 -263.555988) (xy 341.844879 -263.555988)
			(xy 341.848974 -263.50526) (xy 341.861153 -263.455846) (xy 341.881101 -263.409026) (xy 341.908302 -263.366012)
			(xy 341.94205 -263.327918) (xy 341.981472 -263.295731) (xy 342.025546 -263.270285) (xy 342.073132 -263.252238)
			(xy 342.122996 -263.242058) (xy 342.173848 -263.240009) (xy 342.224369 -263.246143) (xy 342.273253 -263.260303)
			(xy 342.319232 -263.28212) (xy 342.361116 -263.31103) (xy 342.39782 -263.346285) (xy 342.428393 -263.386971)
			(xy 342.452044 -263.432034) (xy 342.46816 -263.480308) (xy 342.476324 -263.530542) (xy 342.476836 -263.555988)
			(xy 342.795364 -263.555988) (xy 342.799324 -263.506934) (xy 342.811101 -263.45915) (xy 342.830392 -263.413874)
			(xy 342.856695 -263.372278) (xy 342.88933 -263.335441) (xy 342.927451 -263.304316) (xy 342.970072 -263.279709)
			(xy 343.016088 -263.262257) (xy 343.064307 -263.252413) (xy 343.113482 -263.250432) (xy 343.162337 -263.256364)
			(xy 343.209608 -263.270056) (xy 343.25407 -263.291154) (xy 343.294573 -263.31911) (xy 343.330066 -263.353202)
			(xy 343.359631 -263.392546) (xy 343.382502 -263.436123) (xy 343.398086 -263.482804) (xy 343.405981 -263.531381)
			(xy 343.406476 -263.555988) (xy 343.724987 -263.555988) (xy 343.729082 -263.50526) (xy 343.741261 -263.455846)
			(xy 343.761209 -263.409026) (xy 343.78841 -263.366012) (xy 343.822158 -263.327918) (xy 343.86158 -263.295731)
			(xy 343.905654 -263.270285) (xy 343.95324 -263.252238) (xy 344.003104 -263.242058) (xy 344.053956 -263.240009)
			(xy 344.104477 -263.246143) (xy 344.153361 -263.260303) (xy 344.19934 -263.28212) (xy 344.241224 -263.31103)
			(xy 344.277928 -263.346285) (xy 344.308501 -263.386971) (xy 344.332152 -263.432034) (xy 344.348268 -263.480308)
			(xy 344.356432 -263.530542) (xy 344.356944 -263.555988) (xy 345.615272 -263.555988) (xy 345.619232 -263.506934)
			(xy 345.631009 -263.45915) (xy 345.6503 -263.413874) (xy 345.676603 -263.372278) (xy 345.709238 -263.335441)
			(xy 345.747359 -263.304316) (xy 345.78998 -263.279709) (xy 345.835996 -263.262257) (xy 345.884215 -263.252413)
			(xy 345.93339 -263.250432) (xy 345.982245 -263.256364) (xy 346.029516 -263.270056) (xy 346.073978 -263.291154)
			(xy 346.114481 -263.31911) (xy 346.149974 -263.353202) (xy 346.179539 -263.392546) (xy 346.20241 -263.436123)
			(xy 346.217994 -263.482804) (xy 346.225889 -263.531381) (xy 346.226384 -263.555988) (xy 347.49538 -263.555988)
			(xy 347.49934 -263.506934) (xy 347.511117 -263.45915) (xy 347.530408 -263.413874) (xy 347.556711 -263.372278)
			(xy 347.589346 -263.335441) (xy 347.627467 -263.304316) (xy 347.670088 -263.279709) (xy 347.716104 -263.262257)
			(xy 347.764323 -263.252413) (xy 347.813498 -263.250432) (xy 347.862353 -263.256364) (xy 347.909624 -263.270056)
			(xy 347.954086 -263.291154) (xy 347.994589 -263.31911) (xy 348.030082 -263.353202) (xy 348.059647 -263.392546)
			(xy 348.082518 -263.436123) (xy 348.098102 -263.482804) (xy 348.105997 -263.531381) (xy 348.106492 -263.555988)
			(xy 348.105997 -263.580595) (xy 348.098102 -263.629172) (xy 348.082518 -263.675853) (xy 348.059647 -263.71943)
			(xy 348.030082 -263.758774) (xy 347.994589 -263.792866) (xy 347.954086 -263.820822) (xy 347.909624 -263.84192)
			(xy 347.862353 -263.855612) (xy 347.813498 -263.861544) (xy 347.764323 -263.859563) (xy 347.716104 -263.849719)
			(xy 347.670088 -263.832267) (xy 347.627467 -263.80766) (xy 347.589346 -263.776535) (xy 347.556711 -263.739698)
			(xy 347.530408 -263.698102) (xy 347.511117 -263.652826) (xy 347.49934 -263.605042) (xy 347.49538 -263.555988)
			(xy 346.226384 -263.555988) (xy 346.225889 -263.580595) (xy 346.217994 -263.629172) (xy 346.20241 -263.675853)
			(xy 346.179539 -263.71943) (xy 346.149974 -263.758774) (xy 346.114481 -263.792866) (xy 346.073978 -263.820822)
			(xy 346.029516 -263.84192) (xy 345.982245 -263.855612) (xy 345.93339 -263.861544) (xy 345.884215 -263.859563)
			(xy 345.835996 -263.849719) (xy 345.78998 -263.832267) (xy 345.747359 -263.80766) (xy 345.709238 -263.776535)
			(xy 345.676603 -263.739698) (xy 345.6503 -263.698102) (xy 345.631009 -263.652826) (xy 345.619232 -263.605042)
			(xy 345.615272 -263.555988) (xy 344.356944 -263.555988) (xy 344.356432 -263.581434) (xy 344.348268 -263.631668)
			(xy 344.332152 -263.679942) (xy 344.308501 -263.725005) (xy 344.277928 -263.765691) (xy 344.241224 -263.800946)
			(xy 344.19934 -263.829856) (xy 344.153361 -263.851673) (xy 344.104477 -263.865833) (xy 344.053956 -263.871967)
			(xy 344.003104 -263.869918) (xy 343.95324 -263.859738) (xy 343.905654 -263.841691) (xy 343.86158 -263.816245)
			(xy 343.822158 -263.784058) (xy 343.78841 -263.745964) (xy 343.761209 -263.70295) (xy 343.741261 -263.65613)
			(xy 343.729082 -263.606716) (xy 343.724987 -263.555988) (xy 343.406476 -263.555988) (xy 343.405981 -263.580595)
			(xy 343.398086 -263.629172) (xy 343.382502 -263.675853) (xy 343.359631 -263.71943) (xy 343.330066 -263.758774)
			(xy 343.294573 -263.792866) (xy 343.25407 -263.820822) (xy 343.209608 -263.84192) (xy 343.162337 -263.855612)
			(xy 343.113482 -263.861544) (xy 343.064307 -263.859563) (xy 343.016088 -263.849719) (xy 342.970072 -263.832267)
			(xy 342.927451 -263.80766) (xy 342.88933 -263.776535) (xy 342.856695 -263.739698) (xy 342.830392 -263.698102)
			(xy 342.811101 -263.652826) (xy 342.799324 -263.605042) (xy 342.795364 -263.555988) (xy 342.476836 -263.555988)
			(xy 342.476324 -263.581434) (xy 342.46816 -263.631668) (xy 342.452044 -263.679942) (xy 342.428393 -263.725005)
			(xy 342.39782 -263.765691) (xy 342.361116 -263.800946) (xy 342.319232 -263.829856) (xy 342.273253 -263.851673)
			(xy 342.224369 -263.865833) (xy 342.173848 -263.871967) (xy 342.122996 -263.869918) (xy 342.073132 -263.859738)
			(xy 342.025546 -263.841691) (xy 341.981472 -263.816245) (xy 341.94205 -263.784058) (xy 341.908302 -263.745964)
			(xy 341.881101 -263.70295) (xy 341.861153 -263.65613) (xy 341.848974 -263.606716) (xy 341.844879 -263.555988)
			(xy 340.596728 -263.555988) (xy 340.596216 -263.581434) (xy 340.588052 -263.631668) (xy 340.571936 -263.679942)
			(xy 340.548285 -263.725005) (xy 340.517712 -263.765691) (xy 340.481008 -263.800946) (xy 340.439124 -263.829856)
			(xy 340.393145 -263.851673) (xy 340.344261 -263.865833) (xy 340.29374 -263.871967) (xy 340.242888 -263.869918)
			(xy 340.193024 -263.859738) (xy 340.145438 -263.841691) (xy 340.101364 -263.816245) (xy 340.061942 -263.784058)
			(xy 340.028194 -263.745964) (xy 340.000993 -263.70295) (xy 339.981045 -263.65613) (xy 339.968866 -263.606716)
			(xy 339.964771 -263.555988) (xy 339.656928 -263.555988) (xy 339.656416 -263.581434) (xy 339.648252 -263.631668)
			(xy 339.632136 -263.679942) (xy 339.608485 -263.725005) (xy 339.577912 -263.765691) (xy 339.541208 -263.800946)
			(xy 339.499324 -263.829856) (xy 339.453345 -263.851673) (xy 339.404461 -263.865833) (xy 339.35394 -263.871967)
			(xy 339.303088 -263.869918) (xy 339.253224 -263.859738) (xy 339.205638 -263.841691) (xy 339.161564 -263.816245)
			(xy 339.122142 -263.784058) (xy 339.088394 -263.745964) (xy 339.061193 -263.70295) (xy 339.041245 -263.65613)
			(xy 339.029066 -263.606716) (xy 339.024971 -263.555988) (xy 338.70646 -263.555988) (xy 338.705965 -263.580595)
			(xy 338.69807 -263.629172) (xy 338.682486 -263.675853) (xy 338.659615 -263.71943) (xy 338.63005 -263.758774)
			(xy 338.594557 -263.792866) (xy 338.554054 -263.820822) (xy 338.509592 -263.84192) (xy 338.462321 -263.855612)
			(xy 338.413466 -263.861544) (xy 338.364291 -263.859563) (xy 338.316072 -263.849719) (xy 338.270056 -263.832267)
			(xy 338.227435 -263.80766) (xy 338.189314 -263.776535) (xy 338.156679 -263.739698) (xy 338.130376 -263.698102)
			(xy 338.111085 -263.652826) (xy 338.099308 -263.605042) (xy 338.095348 -263.555988) (xy 337.766406 -263.555988)
			(xy 337.765911 -263.580595) (xy 337.758016 -263.629172) (xy 337.742432 -263.675853) (xy 337.719561 -263.71943)
			(xy 337.689996 -263.758774) (xy 337.654503 -263.792866) (xy 337.614 -263.820822) (xy 337.569538 -263.84192)
			(xy 337.522267 -263.855612) (xy 337.473412 -263.861544) (xy 337.424237 -263.859563) (xy 337.376018 -263.849719)
			(xy 337.330002 -263.832267) (xy 337.287381 -263.80766) (xy 337.24926 -263.776535) (xy 337.216625 -263.739698)
			(xy 337.190322 -263.698102) (xy 337.171031 -263.652826) (xy 337.159254 -263.605042) (xy 337.155294 -263.555988)
			(xy 336.826352 -263.555988) (xy 336.825857 -263.580595) (xy 336.817962 -263.629172) (xy 336.802378 -263.675853)
			(xy 336.779507 -263.71943) (xy 336.749942 -263.758774) (xy 336.714449 -263.792866) (xy 336.673946 -263.820822)
			(xy 336.629484 -263.84192) (xy 336.582213 -263.855612) (xy 336.533358 -263.861544) (xy 336.484183 -263.859563)
			(xy 336.435964 -263.849719) (xy 336.389948 -263.832267) (xy 336.347327 -263.80766) (xy 336.309206 -263.776535)
			(xy 336.276571 -263.739698) (xy 336.250268 -263.698102) (xy 336.230977 -263.652826) (xy 336.2192 -263.605042)
			(xy 336.21524 -263.555988) (xy 335.886298 -263.555988) (xy 335.885803 -263.580595) (xy 335.877908 -263.629172)
			(xy 335.862324 -263.675853) (xy 335.839453 -263.71943) (xy 335.809888 -263.758774) (xy 335.774395 -263.792866)
			(xy 335.733892 -263.820822) (xy 335.68943 -263.84192) (xy 335.642159 -263.855612) (xy 335.593304 -263.861544)
			(xy 335.544129 -263.859563) (xy 335.49591 -263.849719) (xy 335.449894 -263.832267) (xy 335.407273 -263.80766)
			(xy 335.369152 -263.776535) (xy 335.336517 -263.739698) (xy 335.310214 -263.698102) (xy 335.290923 -263.652826)
			(xy 335.279146 -263.605042) (xy 335.275186 -263.555988) (xy 334.006444 -263.555988) (xy 334.005949 -263.580595)
			(xy 333.998054 -263.629172) (xy 333.98247 -263.675853) (xy 333.959599 -263.71943) (xy 333.930034 -263.758774)
			(xy 333.894541 -263.792866) (xy 333.854038 -263.820822) (xy 333.809576 -263.84192) (xy 333.762305 -263.855612)
			(xy 333.71345 -263.861544) (xy 333.664275 -263.859563) (xy 333.616056 -263.849719) (xy 333.57004 -263.832267)
			(xy 333.527419 -263.80766) (xy 333.489298 -263.776535) (xy 333.456663 -263.739698) (xy 333.43036 -263.698102)
			(xy 333.411069 -263.652826) (xy 333.399292 -263.605042) (xy 333.395332 -263.555988) (xy 333.06639 -263.555988)
			(xy 333.065895 -263.580595) (xy 333.058 -263.629172) (xy 333.042416 -263.675853) (xy 333.019545 -263.71943)
			(xy 332.98998 -263.758774) (xy 332.954487 -263.792866) (xy 332.913984 -263.820822) (xy 332.869522 -263.84192)
			(xy 332.822251 -263.855612) (xy 332.773396 -263.861544) (xy 332.724221 -263.859563) (xy 332.676002 -263.849719)
			(xy 332.629986 -263.832267) (xy 332.587365 -263.80766) (xy 332.549244 -263.776535) (xy 332.516609 -263.739698)
			(xy 332.490306 -263.698102) (xy 332.471015 -263.652826) (xy 332.459238 -263.605042) (xy 332.455278 -263.555988)
			(xy 332.126842 -263.555988) (xy 332.126843 -263.556) (xy 332.122672 -263.606337) (xy 332.110274 -263.655301)
			(xy 332.089985 -263.701557) (xy 332.06236 -263.743843) (xy 332.028153 -263.781006) (xy 331.988295 -263.812032)
			(xy 331.943875 -263.836075) (xy 331.896103 -263.852478) (xy 331.846283 -263.860796) (xy 331.821028 -263.861296)
			(xy 331.808265 -263.861156) (xy 331.782832 -263.858991) (xy 331.770228 -263.856978) (xy 331.743541 -263.851896)
			(xy 331.69241 -263.833559) (xy 331.645335 -263.806456) (xy 331.624178 -263.789414) (xy 331.61859 -263.784842)
			(xy 331.605636 -263.779) (xy 331.59827 -263.777984) (xy 331.591061 -263.777302) (xy 331.576754 -263.779501)
			(xy 331.570076 -263.782302) (xy 331.487018 -263.820656) (xy 331.479151 -263.825097) (xy 331.466931 -263.838388)
			(xy 331.460059 -263.855084) (xy 331.459332 -263.86409) (xy 331.459332 -264.047732) (xy 331.459567 -264.054685)
			(xy 331.463295 -264.068081) (xy 331.466698 -264.074148) (xy 331.47 -264.079228) (xy 331.480414 -264.08888)
			(xy 331.487526 -264.092436) (xy 331.508976 -264.103663) (xy 331.548337 -264.131848) (xy 331.582766 -264.165883)
			(xy 331.611401 -264.204918) (xy 331.633529 -264.247977) (xy 331.648595 -264.293984) (xy 331.656223 -264.341791)
			(xy 331.656223 -264.365994) (xy 331.985378 -264.365994) (xy 331.989338 -264.31694) (xy 332.001115 -264.269156)
			(xy 332.020406 -264.22388) (xy 332.046709 -264.182284) (xy 332.079344 -264.145447) (xy 332.117465 -264.114322)
			(xy 332.160086 -264.089715) (xy 332.206102 -264.072263) (xy 332.254321 -264.062419) (xy 332.303496 -264.060438)
			(xy 332.352351 -264.06637) (xy 332.399622 -264.080062) (xy 332.444084 -264.10116) (xy 332.484587 -264.129116)
			(xy 332.52008 -264.163208) (xy 332.549645 -264.202552) (xy 332.572516 -264.246129) (xy 332.5881 -264.29281)
			(xy 332.595995 -264.341387) (xy 332.59649 -264.365994) (xy 332.925178 -264.365994) (xy 332.929138 -264.31694)
			(xy 332.940915 -264.269156) (xy 332.960206 -264.22388) (xy 332.986509 -264.182284) (xy 333.019144 -264.145447)
			(xy 333.057265 -264.114322) (xy 333.099886 -264.089715) (xy 333.145902 -264.072263) (xy 333.194121 -264.062419)
			(xy 333.243296 -264.060438) (xy 333.292151 -264.06637) (xy 333.339422 -264.080062) (xy 333.383884 -264.10116)
			(xy 333.424387 -264.129116) (xy 333.45988 -264.163208) (xy 333.489445 -264.202552) (xy 333.512316 -264.246129)
			(xy 333.5279 -264.29281) (xy 333.535795 -264.341387) (xy 333.53629 -264.365994) (xy 333.865232 -264.365994)
			(xy 333.869192 -264.31694) (xy 333.880969 -264.269156) (xy 333.90026 -264.22388) (xy 333.926563 -264.182284)
			(xy 333.959198 -264.145447) (xy 333.997319 -264.114322) (xy 334.03994 -264.089715) (xy 334.085956 -264.072263)
			(xy 334.134175 -264.062419) (xy 334.18335 -264.060438) (xy 334.232205 -264.06637) (xy 334.279476 -264.080062)
			(xy 334.323938 -264.10116) (xy 334.364441 -264.129116) (xy 334.399934 -264.163208) (xy 334.429499 -264.202552)
			(xy 334.45237 -264.246129) (xy 334.467954 -264.29281) (xy 334.475849 -264.341387) (xy 334.476344 -264.365994)
			(xy 334.805286 -264.365994) (xy 334.809246 -264.31694) (xy 334.821023 -264.269156) (xy 334.840314 -264.22388)
			(xy 334.866617 -264.182284) (xy 334.899252 -264.145447) (xy 334.937373 -264.114322) (xy 334.979994 -264.089715)
			(xy 335.02601 -264.072263) (xy 335.074229 -264.062419) (xy 335.123404 -264.060438) (xy 335.172259 -264.06637)
			(xy 335.21953 -264.080062) (xy 335.263992 -264.10116) (xy 335.304495 -264.129116) (xy 335.339988 -264.163208)
			(xy 335.369553 -264.202552) (xy 335.392424 -264.246129) (xy 335.408008 -264.29281) (xy 335.415903 -264.341387)
			(xy 335.416398 -264.365994) (xy 335.74534 -264.365994) (xy 335.7493 -264.31694) (xy 335.761077 -264.269156)
			(xy 335.780368 -264.22388) (xy 335.806671 -264.182284) (xy 335.839306 -264.145447) (xy 335.877427 -264.114322)
			(xy 335.920048 -264.089715) (xy 335.966064 -264.072263) (xy 336.014283 -264.062419) (xy 336.063458 -264.060438)
			(xy 336.112313 -264.06637) (xy 336.159584 -264.080062) (xy 336.204046 -264.10116) (xy 336.244549 -264.129116)
			(xy 336.280042 -264.163208) (xy 336.309607 -264.202552) (xy 336.332478 -264.246129) (xy 336.348062 -264.29281)
			(xy 336.355957 -264.341387) (xy 336.356452 -264.365994) (xy 336.685394 -264.365994) (xy 336.689354 -264.31694)
			(xy 336.701131 -264.269156) (xy 336.720422 -264.22388) (xy 336.746725 -264.182284) (xy 336.77936 -264.145447)
			(xy 336.817481 -264.114322) (xy 336.860102 -264.089715) (xy 336.906118 -264.072263) (xy 336.954337 -264.062419)
			(xy 337.003512 -264.060438) (xy 337.052367 -264.06637) (xy 337.099638 -264.080062) (xy 337.1441 -264.10116)
			(xy 337.184603 -264.129116) (xy 337.220096 -264.163208) (xy 337.249661 -264.202552) (xy 337.272532 -264.246129)
			(xy 337.288116 -264.29281) (xy 337.296011 -264.341387) (xy 337.296506 -264.365994) (xy 337.625194 -264.365994)
			(xy 337.629154 -264.31694) (xy 337.640931 -264.269156) (xy 337.660222 -264.22388) (xy 337.686525 -264.182284)
			(xy 337.71916 -264.145447) (xy 337.757281 -264.114322) (xy 337.799902 -264.089715) (xy 337.845918 -264.072263)
			(xy 337.894137 -264.062419) (xy 337.943312 -264.060438) (xy 337.992167 -264.06637) (xy 338.039438 -264.080062)
			(xy 338.0839 -264.10116) (xy 338.124403 -264.129116) (xy 338.159896 -264.163208) (xy 338.189461 -264.202552)
			(xy 338.212332 -264.246129) (xy 338.227916 -264.29281) (xy 338.235811 -264.341387) (xy 338.236306 -264.365994)
			(xy 338.554817 -264.365994) (xy 338.558912 -264.315266) (xy 338.571091 -264.265852) (xy 338.591039 -264.219032)
			(xy 338.61824 -264.176018) (xy 338.651988 -264.137924) (xy 338.69141 -264.105737) (xy 338.735484 -264.080291)
			(xy 338.78307 -264.062244) (xy 338.832934 -264.052064) (xy 338.883786 -264.050015) (xy 338.934307 -264.056149)
			(xy 338.983191 -264.070309) (xy 339.02917 -264.092126) (xy 339.071054 -264.121036) (xy 339.107758 -264.156291)
			(xy 339.138331 -264.196977) (xy 339.161982 -264.24204) (xy 339.178098 -264.290314) (xy 339.186262 -264.340548)
			(xy 339.186774 -264.365994) (xy 339.505302 -264.365994) (xy 339.509262 -264.31694) (xy 339.521039 -264.269156)
			(xy 339.54033 -264.22388) (xy 339.566633 -264.182284) (xy 339.599268 -264.145447) (xy 339.637389 -264.114322)
			(xy 339.68001 -264.089715) (xy 339.726026 -264.072263) (xy 339.774245 -264.062419) (xy 339.82342 -264.060438)
			(xy 339.872275 -264.06637) (xy 339.919546 -264.080062) (xy 339.964008 -264.10116) (xy 340.004511 -264.129116)
			(xy 340.040004 -264.163208) (xy 340.069569 -264.202552) (xy 340.09244 -264.246129) (xy 340.108024 -264.29281)
			(xy 340.115919 -264.341387) (xy 340.116414 -264.365994) (xy 340.434925 -264.365994) (xy 340.43902 -264.315266)
			(xy 340.451199 -264.265852) (xy 340.471147 -264.219032) (xy 340.498348 -264.176018) (xy 340.532096 -264.137924)
			(xy 340.571518 -264.105737) (xy 340.615592 -264.080291) (xy 340.663178 -264.062244) (xy 340.713042 -264.052064)
			(xy 340.763894 -264.050015) (xy 340.814415 -264.056149) (xy 340.863299 -264.070309) (xy 340.909278 -264.092126)
			(xy 340.951162 -264.121036) (xy 340.987866 -264.156291) (xy 341.018439 -264.196977) (xy 341.04209 -264.24204)
			(xy 341.058206 -264.290314) (xy 341.06637 -264.340548) (xy 341.066882 -264.365994) (xy 341.38541 -264.365994)
			(xy 341.38937 -264.31694) (xy 341.401147 -264.269156) (xy 341.420438 -264.22388) (xy 341.446741 -264.182284)
			(xy 341.479376 -264.145447) (xy 341.517497 -264.114322) (xy 341.560118 -264.089715) (xy 341.606134 -264.072263)
			(xy 341.654353 -264.062419) (xy 341.703528 -264.060438) (xy 341.752383 -264.06637) (xy 341.799654 -264.080062)
			(xy 341.844116 -264.10116) (xy 341.884619 -264.129116) (xy 341.920112 -264.163208) (xy 341.949677 -264.202552)
			(xy 341.972548 -264.246129) (xy 341.988132 -264.29281) (xy 341.996027 -264.341387) (xy 341.996522 -264.365994)
			(xy 342.314779 -264.365994) (xy 342.318874 -264.315266) (xy 342.331053 -264.265852) (xy 342.351001 -264.219032)
			(xy 342.378202 -264.176018) (xy 342.41195 -264.137924) (xy 342.451372 -264.105737) (xy 342.495446 -264.080291)
			(xy 342.543032 -264.062244) (xy 342.592896 -264.052064) (xy 342.643748 -264.050015) (xy 342.694269 -264.056149)
			(xy 342.743153 -264.070309) (xy 342.789132 -264.092126) (xy 342.831016 -264.121036) (xy 342.86772 -264.156291)
			(xy 342.898293 -264.196977) (xy 342.921944 -264.24204) (xy 342.93806 -264.290314) (xy 342.946224 -264.340548)
			(xy 342.946736 -264.365994) (xy 343.254833 -264.365994) (xy 343.258928 -264.315266) (xy 343.271107 -264.265852)
			(xy 343.291055 -264.219032) (xy 343.318256 -264.176018) (xy 343.352004 -264.137924) (xy 343.391426 -264.105737)
			(xy 343.4355 -264.080291) (xy 343.483086 -264.062244) (xy 343.53295 -264.052064) (xy 343.583802 -264.050015)
			(xy 343.634323 -264.056149) (xy 343.683207 -264.070309) (xy 343.729186 -264.092126) (xy 343.77107 -264.121036)
			(xy 343.807774 -264.156291) (xy 343.838347 -264.196977) (xy 343.861998 -264.24204) (xy 343.878114 -264.290314)
			(xy 343.886278 -264.340548) (xy 343.88679 -264.365994) (xy 344.205318 -264.365994) (xy 344.209278 -264.31694)
			(xy 344.221055 -264.269156) (xy 344.240346 -264.22388) (xy 344.266649 -264.182284) (xy 344.299284 -264.145447)
			(xy 344.337405 -264.114322) (xy 344.380026 -264.089715) (xy 344.426042 -264.072263) (xy 344.474261 -264.062419)
			(xy 344.523436 -264.060438) (xy 344.572291 -264.06637) (xy 344.619562 -264.080062) (xy 344.664024 -264.10116)
			(xy 344.704527 -264.129116) (xy 344.74002 -264.163208) (xy 344.769585 -264.202552) (xy 344.792456 -264.246129)
			(xy 344.80804 -264.29281) (xy 344.815935 -264.341387) (xy 344.81643 -264.365994) (xy 346.085426 -264.365994)
			(xy 346.089386 -264.31694) (xy 346.101163 -264.269156) (xy 346.120454 -264.22388) (xy 346.146757 -264.182284)
			(xy 346.179392 -264.145447) (xy 346.217513 -264.114322) (xy 346.260134 -264.089715) (xy 346.30615 -264.072263)
			(xy 346.354369 -264.062419) (xy 346.403544 -264.060438) (xy 346.452399 -264.06637) (xy 346.49967 -264.080062)
			(xy 346.544132 -264.10116) (xy 346.584635 -264.129116) (xy 346.620128 -264.163208) (xy 346.649693 -264.202552)
			(xy 346.672564 -264.246129) (xy 346.688148 -264.29281) (xy 346.696043 -264.341387) (xy 346.696538 -264.365994)
			(xy 347.96528 -264.365994) (xy 347.96924 -264.31694) (xy 347.981017 -264.269156) (xy 348.000308 -264.22388)
			(xy 348.026611 -264.182284) (xy 348.059246 -264.145447) (xy 348.097367 -264.114322) (xy 348.139988 -264.089715)
			(xy 348.186004 -264.072263) (xy 348.234223 -264.062419) (xy 348.283398 -264.060438) (xy 348.332253 -264.06637)
			(xy 348.379524 -264.080062) (xy 348.423986 -264.10116) (xy 348.464489 -264.129116) (xy 348.499982 -264.163208)
			(xy 348.529547 -264.202552) (xy 348.552418 -264.246129) (xy 348.568002 -264.29281) (xy 348.575897 -264.341387)
			(xy 348.576392 -264.365994) (xy 348.575897 -264.390601) (xy 348.568002 -264.439178) (xy 348.552418 -264.485859)
			(xy 348.529547 -264.529436) (xy 348.499982 -264.56878) (xy 348.464489 -264.602872) (xy 348.423986 -264.630828)
			(xy 348.379524 -264.651926) (xy 348.332253 -264.665618) (xy 348.283398 -264.67155) (xy 348.234223 -264.669569)
			(xy 348.186004 -264.659725) (xy 348.139988 -264.642273) (xy 348.097367 -264.617666) (xy 348.059246 -264.586541)
			(xy 348.026611 -264.549704) (xy 348.000308 -264.508108) (xy 347.981017 -264.462832) (xy 347.96924 -264.415048)
			(xy 347.96528 -264.365994) (xy 346.696538 -264.365994) (xy 346.696043 -264.390601) (xy 346.688148 -264.439178)
			(xy 346.672564 -264.485859) (xy 346.649693 -264.529436) (xy 346.620128 -264.56878) (xy 346.584635 -264.602872)
			(xy 346.544132 -264.630828) (xy 346.49967 -264.651926) (xy 346.452399 -264.665618) (xy 346.403544 -264.67155)
			(xy 346.354369 -264.669569) (xy 346.30615 -264.659725) (xy 346.260134 -264.642273) (xy 346.217513 -264.617666)
			(xy 346.179392 -264.586541) (xy 346.146757 -264.549704) (xy 346.120454 -264.508108) (xy 346.101163 -264.462832)
			(xy 346.089386 -264.415048) (xy 346.085426 -264.365994) (xy 344.81643 -264.365994) (xy 344.815935 -264.390601)
			(xy 344.80804 -264.439178) (xy 344.792456 -264.485859) (xy 344.769585 -264.529436) (xy 344.74002 -264.56878)
			(xy 344.704527 -264.602872) (xy 344.664024 -264.630828) (xy 344.619562 -264.651926) (xy 344.572291 -264.665618)
			(xy 344.523436 -264.67155) (xy 344.474261 -264.669569) (xy 344.426042 -264.659725) (xy 344.380026 -264.642273)
			(xy 344.337405 -264.617666) (xy 344.299284 -264.586541) (xy 344.266649 -264.549704) (xy 344.240346 -264.508108)
			(xy 344.221055 -264.462832) (xy 344.209278 -264.415048) (xy 344.205318 -264.365994) (xy 343.88679 -264.365994)
			(xy 343.886278 -264.39144) (xy 343.878114 -264.441674) (xy 343.861998 -264.489948) (xy 343.838347 -264.535011)
			(xy 343.807774 -264.575697) (xy 343.77107 -264.610952) (xy 343.729186 -264.639862) (xy 343.683207 -264.661679)
			(xy 343.634323 -264.675839) (xy 343.583802 -264.681973) (xy 343.53295 -264.679924) (xy 343.483086 -264.669744)
			(xy 343.4355 -264.651697) (xy 343.391426 -264.626251) (xy 343.352004 -264.594064) (xy 343.318256 -264.55597)
			(xy 343.291055 -264.512956) (xy 343.271107 -264.466136) (xy 343.258928 -264.416722) (xy 343.254833 -264.365994)
			(xy 342.946736 -264.365994) (xy 342.946224 -264.39144) (xy 342.93806 -264.441674) (xy 342.921944 -264.489948)
			(xy 342.898293 -264.535011) (xy 342.86772 -264.575697) (xy 342.831016 -264.610952) (xy 342.789132 -264.639862)
			(xy 342.743153 -264.661679) (xy 342.694269 -264.675839) (xy 342.643748 -264.681973) (xy 342.592896 -264.679924)
			(xy 342.543032 -264.669744) (xy 342.495446 -264.651697) (xy 342.451372 -264.626251) (xy 342.41195 -264.594064)
			(xy 342.378202 -264.55597) (xy 342.351001 -264.512956) (xy 342.331053 -264.466136) (xy 342.318874 -264.416722)
			(xy 342.314779 -264.365994) (xy 341.996522 -264.365994) (xy 341.996027 -264.390601) (xy 341.988132 -264.439178)
			(xy 341.972548 -264.485859) (xy 341.949677 -264.529436) (xy 341.920112 -264.56878) (xy 341.884619 -264.602872)
			(xy 341.844116 -264.630828) (xy 341.799654 -264.651926) (xy 341.752383 -264.665618) (xy 341.703528 -264.67155)
			(xy 341.654353 -264.669569) (xy 341.606134 -264.659725) (xy 341.560118 -264.642273) (xy 341.517497 -264.617666)
			(xy 341.479376 -264.586541) (xy 341.446741 -264.549704) (xy 341.420438 -264.508108) (xy 341.401147 -264.462832)
			(xy 341.38937 -264.415048) (xy 341.38541 -264.365994) (xy 341.066882 -264.365994) (xy 341.06637 -264.39144)
			(xy 341.058206 -264.441674) (xy 341.04209 -264.489948) (xy 341.018439 -264.535011) (xy 340.987866 -264.575697)
			(xy 340.951162 -264.610952) (xy 340.909278 -264.639862) (xy 340.863299 -264.661679) (xy 340.814415 -264.675839)
			(xy 340.763894 -264.681973) (xy 340.713042 -264.679924) (xy 340.663178 -264.669744) (xy 340.615592 -264.651697)
			(xy 340.571518 -264.626251) (xy 340.532096 -264.594064) (xy 340.498348 -264.55597) (xy 340.471147 -264.512956)
			(xy 340.451199 -264.466136) (xy 340.43902 -264.416722) (xy 340.434925 -264.365994) (xy 340.116414 -264.365994)
			(xy 340.115919 -264.390601) (xy 340.108024 -264.439178) (xy 340.09244 -264.485859) (xy 340.069569 -264.529436)
			(xy 340.040004 -264.56878) (xy 340.004511 -264.602872) (xy 339.964008 -264.630828) (xy 339.919546 -264.651926)
			(xy 339.872275 -264.665618) (xy 339.82342 -264.67155) (xy 339.774245 -264.669569) (xy 339.726026 -264.659725)
			(xy 339.68001 -264.642273) (xy 339.637389 -264.617666) (xy 339.599268 -264.586541) (xy 339.566633 -264.549704)
			(xy 339.54033 -264.508108) (xy 339.521039 -264.462832) (xy 339.509262 -264.415048) (xy 339.505302 -264.365994)
			(xy 339.186774 -264.365994) (xy 339.186262 -264.39144) (xy 339.178098 -264.441674) (xy 339.161982 -264.489948)
			(xy 339.138331 -264.535011) (xy 339.107758 -264.575697) (xy 339.071054 -264.610952) (xy 339.02917 -264.639862)
			(xy 338.983191 -264.661679) (xy 338.934307 -264.675839) (xy 338.883786 -264.681973) (xy 338.832934 -264.679924)
			(xy 338.78307 -264.669744) (xy 338.735484 -264.651697) (xy 338.69141 -264.626251) (xy 338.651988 -264.594064)
			(xy 338.61824 -264.55597) (xy 338.591039 -264.512956) (xy 338.571091 -264.466136) (xy 338.558912 -264.416722)
			(xy 338.554817 -264.365994) (xy 338.236306 -264.365994) (xy 338.235811 -264.390601) (xy 338.227916 -264.439178)
			(xy 338.212332 -264.485859) (xy 338.189461 -264.529436) (xy 338.159896 -264.56878) (xy 338.124403 -264.602872)
			(xy 338.0839 -264.630828) (xy 338.039438 -264.651926) (xy 337.992167 -264.665618) (xy 337.943312 -264.67155)
			(xy 337.894137 -264.669569) (xy 337.845918 -264.659725) (xy 337.799902 -264.642273) (xy 337.757281 -264.617666)
			(xy 337.71916 -264.586541) (xy 337.686525 -264.549704) (xy 337.660222 -264.508108) (xy 337.640931 -264.462832)
			(xy 337.629154 -264.415048) (xy 337.625194 -264.365994) (xy 337.296506 -264.365994) (xy 337.296011 -264.390601)
			(xy 337.288116 -264.439178) (xy 337.272532 -264.485859) (xy 337.249661 -264.529436) (xy 337.220096 -264.56878)
			(xy 337.184603 -264.602872) (xy 337.1441 -264.630828) (xy 337.099638 -264.651926) (xy 337.052367 -264.665618)
			(xy 337.003512 -264.67155) (xy 336.954337 -264.669569) (xy 336.906118 -264.659725) (xy 336.860102 -264.642273)
			(xy 336.817481 -264.617666) (xy 336.77936 -264.586541) (xy 336.746725 -264.549704) (xy 336.720422 -264.508108)
			(xy 336.701131 -264.462832) (xy 336.689354 -264.415048) (xy 336.685394 -264.365994) (xy 336.356452 -264.365994)
			(xy 336.355957 -264.390601) (xy 336.348062 -264.439178) (xy 336.332478 -264.485859) (xy 336.309607 -264.529436)
			(xy 336.280042 -264.56878) (xy 336.244549 -264.602872) (xy 336.204046 -264.630828) (xy 336.159584 -264.651926)
			(xy 336.112313 -264.665618) (xy 336.063458 -264.67155) (xy 336.014283 -264.669569) (xy 335.966064 -264.659725)
			(xy 335.920048 -264.642273) (xy 335.877427 -264.617666) (xy 335.839306 -264.586541) (xy 335.806671 -264.549704)
			(xy 335.780368 -264.508108) (xy 335.761077 -264.462832) (xy 335.7493 -264.415048) (xy 335.74534 -264.365994)
			(xy 335.416398 -264.365994) (xy 335.415903 -264.390601) (xy 335.408008 -264.439178) (xy 335.392424 -264.485859)
			(xy 335.369553 -264.529436) (xy 335.339988 -264.56878) (xy 335.304495 -264.602872) (xy 335.263992 -264.630828)
			(xy 335.21953 -264.651926) (xy 335.172259 -264.665618) (xy 335.123404 -264.67155) (xy 335.074229 -264.669569)
			(xy 335.02601 -264.659725) (xy 334.979994 -264.642273) (xy 334.937373 -264.617666) (xy 334.899252 -264.586541)
			(xy 334.866617 -264.549704) (xy 334.840314 -264.508108) (xy 334.821023 -264.462832) (xy 334.809246 -264.415048)
			(xy 334.805286 -264.365994) (xy 334.476344 -264.365994) (xy 334.475849 -264.390601) (xy 334.467954 -264.439178)
			(xy 334.45237 -264.485859) (xy 334.429499 -264.529436) (xy 334.399934 -264.56878) (xy 334.364441 -264.602872)
			(xy 334.323938 -264.630828) (xy 334.279476 -264.651926) (xy 334.232205 -264.665618) (xy 334.18335 -264.67155)
			(xy 334.134175 -264.669569) (xy 334.085956 -264.659725) (xy 334.03994 -264.642273) (xy 333.997319 -264.617666)
			(xy 333.959198 -264.586541) (xy 333.926563 -264.549704) (xy 333.90026 -264.508108) (xy 333.880969 -264.462832)
			(xy 333.869192 -264.415048) (xy 333.865232 -264.365994) (xy 333.53629 -264.365994) (xy 333.535795 -264.390601)
			(xy 333.5279 -264.439178) (xy 333.512316 -264.485859) (xy 333.489445 -264.529436) (xy 333.45988 -264.56878)
			(xy 333.424387 -264.602872) (xy 333.383884 -264.630828) (xy 333.339422 -264.651926) (xy 333.292151 -264.665618)
			(xy 333.243296 -264.67155) (xy 333.194121 -264.669569) (xy 333.145902 -264.659725) (xy 333.099886 -264.642273)
			(xy 333.057265 -264.617666) (xy 333.019144 -264.586541) (xy 332.986509 -264.549704) (xy 332.960206 -264.508108)
			(xy 332.940915 -264.462832) (xy 332.929138 -264.415048) (xy 332.925178 -264.365994) (xy 332.59649 -264.365994)
			(xy 332.595995 -264.390601) (xy 332.5881 -264.439178) (xy 332.572516 -264.485859) (xy 332.549645 -264.529436)
			(xy 332.52008 -264.56878) (xy 332.484587 -264.602872) (xy 332.444084 -264.630828) (xy 332.399622 -264.651926)
			(xy 332.352351 -264.665618) (xy 332.303496 -264.67155) (xy 332.254321 -264.669569) (xy 332.206102 -264.659725)
			(xy 332.160086 -264.642273) (xy 332.117465 -264.617666) (xy 332.079344 -264.586541) (xy 332.046709 -264.549704)
			(xy 332.020406 -264.508108) (xy 332.001115 -264.462832) (xy 331.989338 -264.415048) (xy 331.985378 -264.365994)
			(xy 331.656223 -264.365994) (xy 331.656224 -264.390203) (xy 331.648596 -264.43801) (xy 331.633531 -264.484018)
			(xy 331.611404 -264.527078) (xy 331.582769 -264.566113) (xy 331.548341 -264.600148) (xy 331.50898 -264.628334)
			(xy 331.487526 -264.639552) (xy 331.486764 -264.639806) (xy 331.480507 -264.643209) (xy 331.470058 -264.652876)
			(xy 331.46619 -264.658856) (xy 331.463142 -264.663936) (xy 331.459332 -264.677144) (xy 331.459332 -264.86612)
			(xy 331.459801 -264.875495) (xy 331.466641 -264.892956) (xy 331.47932 -264.906774) (xy 331.487526 -264.911332)
			(xy 331.518006 -264.925556) (xy 331.566266 -264.947908) (xy 331.56955 -264.949403) (xy 331.576433 -264.951574)
			(xy 331.579982 -264.952226) (xy 331.584357 -264.952778) (xy 331.593171 -264.95252) (xy 331.597508 -264.951718)
			(xy 331.605382 -264.949686) (xy 331.62367 -264.942828) (xy 331.63002 -264.937748) (xy 331.6505 -264.922034)
			(xy 331.695636 -264.896997) (xy 331.744338 -264.8799) (xy 331.79522 -264.871231) (xy 331.821028 -264.870692)
			(xy 331.846282 -264.871216) (xy 331.8961 -264.879533) (xy 331.94387 -264.895936) (xy 331.988289 -264.919978)
			(xy 332.028145 -264.951003) (xy 332.062351 -264.988164) (xy 332.089975 -265.030448) (xy 332.110262 -265.076702)
			(xy 332.12266 -265.125665) (xy 332.126831 -265.176) (xy 332.455278 -265.176) (xy 332.459238 -265.126946)
			(xy 332.471015 -265.079162) (xy 332.490306 -265.033886) (xy 332.516609 -264.99229) (xy 332.549244 -264.955453)
			(xy 332.587365 -264.924328) (xy 332.629986 -264.899721) (xy 332.676002 -264.882269) (xy 332.724221 -264.872425)
			(xy 332.773396 -264.870444) (xy 332.822251 -264.876376) (xy 332.869522 -264.890068) (xy 332.913984 -264.911166)
			(xy 332.954487 -264.939122) (xy 332.98998 -264.973214) (xy 333.019545 -265.012558) (xy 333.042416 -265.056135)
			(xy 333.058 -265.102816) (xy 333.065895 -265.151393) (xy 333.06639 -265.176) (xy 333.395332 -265.176)
			(xy 333.399292 -265.126946) (xy 333.411069 -265.079162) (xy 333.43036 -265.033886) (xy 333.456663 -264.99229)
			(xy 333.489298 -264.955453) (xy 333.527419 -264.924328) (xy 333.57004 -264.899721) (xy 333.616056 -264.882269)
			(xy 333.664275 -264.872425) (xy 333.71345 -264.870444) (xy 333.762305 -264.876376) (xy 333.809576 -264.890068)
			(xy 333.854038 -264.911166) (xy 333.894541 -264.939122) (xy 333.930034 -264.973214) (xy 333.959599 -265.012558)
			(xy 333.98247 -265.056135) (xy 333.998054 -265.102816) (xy 334.005949 -265.151393) (xy 334.006444 -265.176)
			(xy 334.335386 -265.176) (xy 334.339346 -265.126946) (xy 334.351123 -265.079162) (xy 334.370414 -265.033886)
			(xy 334.396717 -264.99229) (xy 334.429352 -264.955453) (xy 334.467473 -264.924328) (xy 334.510094 -264.899721)
			(xy 334.55611 -264.882269) (xy 334.604329 -264.872425) (xy 334.653504 -264.870444) (xy 334.702359 -264.876376)
			(xy 334.74963 -264.890068) (xy 334.794092 -264.911166) (xy 334.834595 -264.939122) (xy 334.870088 -264.973214)
			(xy 334.899653 -265.012558) (xy 334.922524 -265.056135) (xy 334.938108 -265.102816) (xy 334.946003 -265.151393)
			(xy 334.946498 -265.176) (xy 335.275186 -265.176) (xy 335.279146 -265.126946) (xy 335.290923 -265.079162)
			(xy 335.310214 -265.033886) (xy 335.336517 -264.99229) (xy 335.369152 -264.955453) (xy 335.407273 -264.924328)
			(xy 335.449894 -264.899721) (xy 335.49591 -264.882269) (xy 335.544129 -264.872425) (xy 335.593304 -264.870444)
			(xy 335.642159 -264.876376) (xy 335.68943 -264.890068) (xy 335.733892 -264.911166) (xy 335.774395 -264.939122)
			(xy 335.809888 -264.973214) (xy 335.839453 -265.012558) (xy 335.862324 -265.056135) (xy 335.877908 -265.102816)
			(xy 335.885803 -265.151393) (xy 335.886298 -265.176) (xy 336.21524 -265.176) (xy 336.2192 -265.126946)
			(xy 336.230977 -265.079162) (xy 336.250268 -265.033886) (xy 336.276571 -264.99229) (xy 336.309206 -264.955453)
			(xy 336.347327 -264.924328) (xy 336.389948 -264.899721) (xy 336.435964 -264.882269) (xy 336.484183 -264.872425)
			(xy 336.533358 -264.870444) (xy 336.582213 -264.876376) (xy 336.629484 -264.890068) (xy 336.673946 -264.911166)
			(xy 336.714449 -264.939122) (xy 336.749942 -264.973214) (xy 336.779507 -265.012558) (xy 336.802378 -265.056135)
			(xy 336.817962 -265.102816) (xy 336.825857 -265.151393) (xy 336.826352 -265.176) (xy 337.155294 -265.176)
			(xy 337.159254 -265.126946) (xy 337.171031 -265.079162) (xy 337.190322 -265.033886) (xy 337.216625 -264.99229)
			(xy 337.24926 -264.955453) (xy 337.287381 -264.924328) (xy 337.330002 -264.899721) (xy 337.376018 -264.882269)
			(xy 337.424237 -264.872425) (xy 337.473412 -264.870444) (xy 337.522267 -264.876376) (xy 337.569538 -264.890068)
			(xy 337.614 -264.911166) (xy 337.654503 -264.939122) (xy 337.689996 -264.973214) (xy 337.719561 -265.012558)
			(xy 337.742432 -265.056135) (xy 337.758016 -265.102816) (xy 337.765911 -265.151393) (xy 337.766406 -265.176)
			(xy 338.095348 -265.176) (xy 338.099308 -265.126946) (xy 338.111085 -265.079162) (xy 338.130376 -265.033886)
			(xy 338.156679 -264.99229) (xy 338.189314 -264.955453) (xy 338.227435 -264.924328) (xy 338.270056 -264.899721)
			(xy 338.316072 -264.882269) (xy 338.364291 -264.872425) (xy 338.413466 -264.870444) (xy 338.462321 -264.876376)
			(xy 338.509592 -264.890068) (xy 338.554054 -264.911166) (xy 338.594557 -264.939122) (xy 338.63005 -264.973214)
			(xy 338.659615 -265.012558) (xy 338.682486 -265.056135) (xy 338.69807 -265.102816) (xy 338.705965 -265.151393)
			(xy 338.70646 -265.176) (xy 339.024971 -265.176) (xy 339.029066 -265.125272) (xy 339.041245 -265.075858)
			(xy 339.061193 -265.029038) (xy 339.088394 -264.986024) (xy 339.122142 -264.94793) (xy 339.161564 -264.915743)
			(xy 339.205638 -264.890297) (xy 339.253224 -264.87225) (xy 339.303088 -264.86207) (xy 339.35394 -264.860021)
			(xy 339.404461 -264.866155) (xy 339.453345 -264.880315) (xy 339.499324 -264.902132) (xy 339.541208 -264.931042)
			(xy 339.577912 -264.966297) (xy 339.608485 -265.006983) (xy 339.632136 -265.052046) (xy 339.648252 -265.10032)
			(xy 339.656416 -265.150554) (xy 339.656928 -265.176) (xy 339.975202 -265.176) (xy 339.979162 -265.126946)
			(xy 339.990939 -265.079162) (xy 340.01023 -265.033886) (xy 340.036533 -264.99229) (xy 340.069168 -264.955453)
			(xy 340.107289 -264.924328) (xy 340.14991 -264.899721) (xy 340.195926 -264.882269) (xy 340.244145 -264.872425)
			(xy 340.29332 -264.870444) (xy 340.342175 -264.876376) (xy 340.389446 -264.890068) (xy 340.433908 -264.911166)
			(xy 340.474411 -264.939122) (xy 340.509904 -264.973214) (xy 340.539469 -265.012558) (xy 340.56234 -265.056135)
			(xy 340.577924 -265.102816) (xy 340.585819 -265.151393) (xy 340.586314 -265.176) (xy 340.915256 -265.176)
			(xy 340.919216 -265.126946) (xy 340.930993 -265.079162) (xy 340.950284 -265.033886) (xy 340.976587 -264.99229)
			(xy 341.009222 -264.955453) (xy 341.047343 -264.924328) (xy 341.089964 -264.899721) (xy 341.13598 -264.882269)
			(xy 341.184199 -264.872425) (xy 341.233374 -264.870444) (xy 341.282229 -264.876376) (xy 341.3295 -264.890068)
			(xy 341.373962 -264.911166) (xy 341.414465 -264.939122) (xy 341.449958 -264.973214) (xy 341.479523 -265.012558)
			(xy 341.502394 -265.056135) (xy 341.517978 -265.102816) (xy 341.525873 -265.151393) (xy 341.526368 -265.176)
			(xy 341.844879 -265.176) (xy 341.848974 -265.125272) (xy 341.861153 -265.075858) (xy 341.881101 -265.029038)
			(xy 341.908302 -264.986024) (xy 341.94205 -264.94793) (xy 341.981472 -264.915743) (xy 342.025546 -264.890297)
			(xy 342.073132 -264.87225) (xy 342.122996 -264.86207) (xy 342.173848 -264.860021) (xy 342.224369 -264.866155)
			(xy 342.273253 -264.880315) (xy 342.319232 -264.902132) (xy 342.361116 -264.931042) (xy 342.39782 -264.966297)
			(xy 342.428393 -265.006983) (xy 342.452044 -265.052046) (xy 342.46816 -265.10032) (xy 342.476324 -265.150554)
			(xy 342.476836 -265.176) (xy 342.795364 -265.176) (xy 342.799324 -265.126946) (xy 342.811101 -265.079162)
			(xy 342.830392 -265.033886) (xy 342.856695 -264.99229) (xy 342.88933 -264.955453) (xy 342.927451 -264.924328)
			(xy 342.970072 -264.899721) (xy 343.016088 -264.882269) (xy 343.064307 -264.872425) (xy 343.113482 -264.870444)
			(xy 343.162337 -264.876376) (xy 343.209608 -264.890068) (xy 343.25407 -264.911166) (xy 343.294573 -264.939122)
			(xy 343.330066 -264.973214) (xy 343.359631 -265.012558) (xy 343.382502 -265.056135) (xy 343.398086 -265.102816)
			(xy 343.405981 -265.151393) (xy 343.406476 -265.176) (xy 343.735418 -265.176) (xy 343.739378 -265.126946)
			(xy 343.751155 -265.079162) (xy 343.770446 -265.033886) (xy 343.796749 -264.99229) (xy 343.829384 -264.955453)
			(xy 343.867505 -264.924328) (xy 343.910126 -264.899721) (xy 343.956142 -264.882269) (xy 344.004361 -264.872425)
			(xy 344.053536 -264.870444) (xy 344.102391 -264.876376) (xy 344.149662 -264.890068) (xy 344.194124 -264.911166)
			(xy 344.234627 -264.939122) (xy 344.27012 -264.973214) (xy 344.299685 -265.012558) (xy 344.322556 -265.056135)
			(xy 344.33814 -265.102816) (xy 344.346035 -265.151393) (xy 344.34653 -265.176) (xy 345.615272 -265.176)
			(xy 345.619232 -265.126946) (xy 345.631009 -265.079162) (xy 345.6503 -265.033886) (xy 345.676603 -264.99229)
			(xy 345.709238 -264.955453) (xy 345.747359 -264.924328) (xy 345.78998 -264.899721) (xy 345.835996 -264.882269)
			(xy 345.884215 -264.872425) (xy 345.93339 -264.870444) (xy 345.982245 -264.876376) (xy 346.029516 -264.890068)
			(xy 346.073978 -264.911166) (xy 346.114481 -264.939122) (xy 346.149974 -264.973214) (xy 346.179539 -265.012558)
			(xy 346.20241 -265.056135) (xy 346.217994 -265.102816) (xy 346.225889 -265.151393) (xy 346.226384 -265.176)
			(xy 347.49538 -265.176) (xy 347.49934 -265.126946) (xy 347.511117 -265.079162) (xy 347.530408 -265.033886)
			(xy 347.556711 -264.99229) (xy 347.589346 -264.955453) (xy 347.627467 -264.924328) (xy 347.670088 -264.899721)
			(xy 347.716104 -264.882269) (xy 347.764323 -264.872425) (xy 347.813498 -264.870444) (xy 347.862353 -264.876376)
			(xy 347.909624 -264.890068) (xy 347.954086 -264.911166) (xy 347.994589 -264.939122) (xy 348.030082 -264.973214)
			(xy 348.059647 -265.012558) (xy 348.082518 -265.056135) (xy 348.098102 -265.102816) (xy 348.105997 -265.151393)
			(xy 348.106492 -265.176) (xy 348.105997 -265.200607) (xy 348.098102 -265.249184) (xy 348.082518 -265.295865)
			(xy 348.059647 -265.339442) (xy 348.030082 -265.378786) (xy 347.994589 -265.412878) (xy 347.954086 -265.440834)
			(xy 347.909624 -265.461932) (xy 347.862353 -265.475624) (xy 347.813498 -265.481556) (xy 347.764323 -265.479575)
			(xy 347.716104 -265.469731) (xy 347.670088 -265.452279) (xy 347.627467 -265.427672) (xy 347.589346 -265.396547)
			(xy 347.556711 -265.35971) (xy 347.530408 -265.318114) (xy 347.511117 -265.272838) (xy 347.49934 -265.225054)
			(xy 347.49538 -265.176) (xy 346.226384 -265.176) (xy 346.225889 -265.200607) (xy 346.217994 -265.249184)
			(xy 346.20241 -265.295865) (xy 346.179539 -265.339442) (xy 346.149974 -265.378786) (xy 346.114481 -265.412878)
			(xy 346.073978 -265.440834) (xy 346.029516 -265.461932) (xy 345.982245 -265.475624) (xy 345.93339 -265.481556)
			(xy 345.884215 -265.479575) (xy 345.835996 -265.469731) (xy 345.78998 -265.452279) (xy 345.747359 -265.427672)
			(xy 345.709238 -265.396547) (xy 345.676603 -265.35971) (xy 345.6503 -265.318114) (xy 345.631009 -265.272838)
			(xy 345.619232 -265.225054) (xy 345.615272 -265.176) (xy 344.34653 -265.176) (xy 344.346035 -265.200607)
			(xy 344.33814 -265.249184) (xy 344.322556 -265.295865) (xy 344.299685 -265.339442) (xy 344.27012 -265.378786)
			(xy 344.234627 -265.412878) (xy 344.194124 -265.440834) (xy 344.149662 -265.461932) (xy 344.102391 -265.475624)
			(xy 344.053536 -265.481556) (xy 344.004361 -265.479575) (xy 343.956142 -265.469731) (xy 343.910126 -265.452279)
			(xy 343.867505 -265.427672) (xy 343.829384 -265.396547) (xy 343.796749 -265.35971) (xy 343.770446 -265.318114)
			(xy 343.751155 -265.272838) (xy 343.739378 -265.225054) (xy 343.735418 -265.176) (xy 343.406476 -265.176)
			(xy 343.405981 -265.200607) (xy 343.398086 -265.249184) (xy 343.382502 -265.295865) (xy 343.359631 -265.339442)
			(xy 343.330066 -265.378786) (xy 343.294573 -265.412878) (xy 343.25407 -265.440834) (xy 343.209608 -265.461932)
			(xy 343.162337 -265.475624) (xy 343.113482 -265.481556) (xy 343.064307 -265.479575) (xy 343.016088 -265.469731)
			(xy 342.970072 -265.452279) (xy 342.927451 -265.427672) (xy 342.88933 -265.396547) (xy 342.856695 -265.35971)
			(xy 342.830392 -265.318114) (xy 342.811101 -265.272838) (xy 342.799324 -265.225054) (xy 342.795364 -265.176)
			(xy 342.476836 -265.176) (xy 342.476324 -265.201446) (xy 342.46816 -265.25168) (xy 342.452044 -265.299954)
			(xy 342.428393 -265.345017) (xy 342.39782 -265.385703) (xy 342.361116 -265.420958) (xy 342.319232 -265.449868)
			(xy 342.273253 -265.471685) (xy 342.224369 -265.485845) (xy 342.173848 -265.491979) (xy 342.122996 -265.48993)
			(xy 342.073132 -265.47975) (xy 342.025546 -265.461703) (xy 341.981472 -265.436257) (xy 341.94205 -265.40407)
			(xy 341.908302 -265.365976) (xy 341.881101 -265.322962) (xy 341.861153 -265.276142) (xy 341.848974 -265.226728)
			(xy 341.844879 -265.176) (xy 341.526368 -265.176) (xy 341.525873 -265.200607) (xy 341.517978 -265.249184)
			(xy 341.502394 -265.295865) (xy 341.479523 -265.339442) (xy 341.449958 -265.378786) (xy 341.414465 -265.412878)
			(xy 341.373962 -265.440834) (xy 341.3295 -265.461932) (xy 341.282229 -265.475624) (xy 341.233374 -265.481556)
			(xy 341.184199 -265.479575) (xy 341.13598 -265.469731) (xy 341.089964 -265.452279) (xy 341.047343 -265.427672)
			(xy 341.009222 -265.396547) (xy 340.976587 -265.35971) (xy 340.950284 -265.318114) (xy 340.930993 -265.272838)
			(xy 340.919216 -265.225054) (xy 340.915256 -265.176) (xy 340.586314 -265.176) (xy 340.585819 -265.200607)
			(xy 340.577924 -265.249184) (xy 340.56234 -265.295865) (xy 340.539469 -265.339442) (xy 340.509904 -265.378786)
			(xy 340.474411 -265.412878) (xy 340.433908 -265.440834) (xy 340.389446 -265.461932) (xy 340.342175 -265.475624)
			(xy 340.29332 -265.481556) (xy 340.244145 -265.479575) (xy 340.195926 -265.469731) (xy 340.14991 -265.452279)
			(xy 340.107289 -265.427672) (xy 340.069168 -265.396547) (xy 340.036533 -265.35971) (xy 340.01023 -265.318114)
			(xy 339.990939 -265.272838) (xy 339.979162 -265.225054) (xy 339.975202 -265.176) (xy 339.656928 -265.176)
			(xy 339.656416 -265.201446) (xy 339.648252 -265.25168) (xy 339.632136 -265.299954) (xy 339.608485 -265.345017)
			(xy 339.577912 -265.385703) (xy 339.541208 -265.420958) (xy 339.499324 -265.449868) (xy 339.453345 -265.471685)
			(xy 339.404461 -265.485845) (xy 339.35394 -265.491979) (xy 339.303088 -265.48993) (xy 339.253224 -265.47975)
			(xy 339.205638 -265.461703) (xy 339.161564 -265.436257) (xy 339.122142 -265.40407) (xy 339.088394 -265.365976)
			(xy 339.061193 -265.322962) (xy 339.041245 -265.276142) (xy 339.029066 -265.226728) (xy 339.024971 -265.176)
			(xy 338.70646 -265.176) (xy 338.705965 -265.200607) (xy 338.69807 -265.249184) (xy 338.682486 -265.295865)
			(xy 338.659615 -265.339442) (xy 338.63005 -265.378786) (xy 338.594557 -265.412878) (xy 338.554054 -265.440834)
			(xy 338.509592 -265.461932) (xy 338.462321 -265.475624) (xy 338.413466 -265.481556) (xy 338.364291 -265.479575)
			(xy 338.316072 -265.469731) (xy 338.270056 -265.452279) (xy 338.227435 -265.427672) (xy 338.189314 -265.396547)
			(xy 338.156679 -265.35971) (xy 338.130376 -265.318114) (xy 338.111085 -265.272838) (xy 338.099308 -265.225054)
			(xy 338.095348 -265.176) (xy 337.766406 -265.176) (xy 337.765911 -265.200607) (xy 337.758016 -265.249184)
			(xy 337.742432 -265.295865) (xy 337.719561 -265.339442) (xy 337.689996 -265.378786) (xy 337.654503 -265.412878)
			(xy 337.614 -265.440834) (xy 337.569538 -265.461932) (xy 337.522267 -265.475624) (xy 337.473412 -265.481556)
			(xy 337.424237 -265.479575) (xy 337.376018 -265.469731) (xy 337.330002 -265.452279) (xy 337.287381 -265.427672)
			(xy 337.24926 -265.396547) (xy 337.216625 -265.35971) (xy 337.190322 -265.318114) (xy 337.171031 -265.272838)
			(xy 337.159254 -265.225054) (xy 337.155294 -265.176) (xy 336.826352 -265.176) (xy 336.825857 -265.200607)
			(xy 336.817962 -265.249184) (xy 336.802378 -265.295865) (xy 336.779507 -265.339442) (xy 336.749942 -265.378786)
			(xy 336.714449 -265.412878) (xy 336.673946 -265.440834) (xy 336.629484 -265.461932) (xy 336.582213 -265.475624)
			(xy 336.533358 -265.481556) (xy 336.484183 -265.479575) (xy 336.435964 -265.469731) (xy 336.389948 -265.452279)
			(xy 336.347327 -265.427672) (xy 336.309206 -265.396547) (xy 336.276571 -265.35971) (xy 336.250268 -265.318114)
			(xy 336.230977 -265.272838) (xy 336.2192 -265.225054) (xy 336.21524 -265.176) (xy 335.886298 -265.176)
			(xy 335.885803 -265.200607) (xy 335.877908 -265.249184) (xy 335.862324 -265.295865) (xy 335.839453 -265.339442)
			(xy 335.809888 -265.378786) (xy 335.774395 -265.412878) (xy 335.733892 -265.440834) (xy 335.68943 -265.461932)
			(xy 335.642159 -265.475624) (xy 335.593304 -265.481556) (xy 335.544129 -265.479575) (xy 335.49591 -265.469731)
			(xy 335.449894 -265.452279) (xy 335.407273 -265.427672) (xy 335.369152 -265.396547) (xy 335.336517 -265.35971)
			(xy 335.310214 -265.318114) (xy 335.290923 -265.272838) (xy 335.279146 -265.225054) (xy 335.275186 -265.176)
			(xy 334.946498 -265.176) (xy 334.946003 -265.200607) (xy 334.938108 -265.249184) (xy 334.922524 -265.295865)
			(xy 334.899653 -265.339442) (xy 334.870088 -265.378786) (xy 334.834595 -265.412878) (xy 334.794092 -265.440834)
			(xy 334.74963 -265.461932) (xy 334.702359 -265.475624) (xy 334.653504 -265.481556) (xy 334.604329 -265.479575)
			(xy 334.55611 -265.469731) (xy 334.510094 -265.452279) (xy 334.467473 -265.427672) (xy 334.429352 -265.396547)
			(xy 334.396717 -265.35971) (xy 334.370414 -265.318114) (xy 334.351123 -265.272838) (xy 334.339346 -265.225054)
			(xy 334.335386 -265.176) (xy 334.006444 -265.176) (xy 334.005949 -265.200607) (xy 333.998054 -265.249184)
			(xy 333.98247 -265.295865) (xy 333.959599 -265.339442) (xy 333.930034 -265.378786) (xy 333.894541 -265.412878)
			(xy 333.854038 -265.440834) (xy 333.809576 -265.461932) (xy 333.762305 -265.475624) (xy 333.71345 -265.481556)
			(xy 333.664275 -265.479575) (xy 333.616056 -265.469731) (xy 333.57004 -265.452279) (xy 333.527419 -265.427672)
			(xy 333.489298 -265.396547) (xy 333.456663 -265.35971) (xy 333.43036 -265.318114) (xy 333.411069 -265.272838)
			(xy 333.399292 -265.225054) (xy 333.395332 -265.176) (xy 333.06639 -265.176) (xy 333.065895 -265.200607)
			(xy 333.058 -265.249184) (xy 333.042416 -265.295865) (xy 333.019545 -265.339442) (xy 332.98998 -265.378786)
			(xy 332.954487 -265.412878) (xy 332.913984 -265.440834) (xy 332.869522 -265.461932) (xy 332.822251 -265.475624)
			(xy 332.773396 -265.481556) (xy 332.724221 -265.479575) (xy 332.676002 -265.469731) (xy 332.629986 -265.452279)
			(xy 332.587365 -265.427672) (xy 332.549244 -265.396547) (xy 332.516609 -265.35971) (xy 332.490306 -265.318114)
			(xy 332.471015 -265.272838) (xy 332.459238 -265.225054) (xy 332.455278 -265.176) (xy 332.126831 -265.176)
			(xy 332.12266 -265.226335) (xy 332.110262 -265.275298) (xy 332.089975 -265.321552) (xy 332.062351 -265.363836)
			(xy 332.028145 -265.400997) (xy 331.988289 -265.432022) (xy 331.94387 -265.456064) (xy 331.8961 -265.472467)
			(xy 331.846282 -265.480784) (xy 331.821028 -265.481308) (xy 331.808265 -265.481168) (xy 331.782832 -265.479003)
			(xy 331.770228 -265.47699) (xy 331.743541 -265.471909) (xy 331.69241 -265.453571) (xy 331.645334 -265.426469)
			(xy 331.624178 -265.409426) (xy 331.61859 -265.404854) (xy 331.605636 -265.399012) (xy 331.59827 -265.397996)
			(xy 331.591061 -265.397314) (xy 331.576755 -265.399514) (xy 331.570076 -265.402314) (xy 331.487018 -265.440668)
			(xy 331.479152 -265.44511) (xy 331.466935 -265.458401) (xy 331.460067 -265.475097) (xy 331.459332 -265.484102)
			(xy 331.459332 -265.667744) (xy 331.459568 -265.674696) (xy 331.463299 -265.688091) (xy 331.466698 -265.69416)
			(xy 331.47 -265.69924) (xy 331.480414 -265.708892) (xy 331.487526 -265.712448) (xy 331.508975 -265.723675)
			(xy 331.548334 -265.75186) (xy 331.582761 -265.785894) (xy 331.611395 -265.824928) (xy 331.633521 -265.867986)
			(xy 331.648586 -265.913992) (xy 331.656213 -265.961798) (xy 331.656213 -265.986006) (xy 331.985378 -265.986006)
			(xy 331.989338 -265.936952) (xy 332.001115 -265.889168) (xy 332.020406 -265.843892) (xy 332.046709 -265.802296)
			(xy 332.079344 -265.765459) (xy 332.117465 -265.734334) (xy 332.160086 -265.709727) (xy 332.206102 -265.692275)
			(xy 332.254321 -265.682431) (xy 332.303496 -265.68045) (xy 332.352351 -265.686382) (xy 332.399622 -265.700074)
			(xy 332.444084 -265.721172) (xy 332.484587 -265.749128) (xy 332.52008 -265.78322) (xy 332.549645 -265.822564)
			(xy 332.572516 -265.866141) (xy 332.5881 -265.912822) (xy 332.595995 -265.961399) (xy 332.59649 -265.986006)
			(xy 332.925178 -265.986006) (xy 332.929138 -265.936952) (xy 332.940915 -265.889168) (xy 332.960206 -265.843892)
			(xy 332.986509 -265.802296) (xy 333.019144 -265.765459) (xy 333.057265 -265.734334) (xy 333.099886 -265.709727)
			(xy 333.145902 -265.692275) (xy 333.194121 -265.682431) (xy 333.243296 -265.68045) (xy 333.292151 -265.686382)
			(xy 333.339422 -265.700074) (xy 333.383884 -265.721172) (xy 333.424387 -265.749128) (xy 333.45988 -265.78322)
			(xy 333.489445 -265.822564) (xy 333.512316 -265.866141) (xy 333.5279 -265.912822) (xy 333.535795 -265.961399)
			(xy 333.53629 -265.986006) (xy 333.865232 -265.986006) (xy 333.869192 -265.936952) (xy 333.880969 -265.889168)
			(xy 333.90026 -265.843892) (xy 333.926563 -265.802296) (xy 333.959198 -265.765459) (xy 333.997319 -265.734334)
			(xy 334.03994 -265.709727) (xy 334.085956 -265.692275) (xy 334.134175 -265.682431) (xy 334.18335 -265.68045)
			(xy 334.232205 -265.686382) (xy 334.279476 -265.700074) (xy 334.323938 -265.721172) (xy 334.364441 -265.749128)
			(xy 334.399934 -265.78322) (xy 334.429499 -265.822564) (xy 334.45237 -265.866141) (xy 334.467954 -265.912822)
			(xy 334.475849 -265.961399) (xy 334.476344 -265.986006) (xy 335.74534 -265.986006) (xy 335.7493 -265.936952)
			(xy 335.761077 -265.889168) (xy 335.780368 -265.843892) (xy 335.806671 -265.802296) (xy 335.839306 -265.765459)
			(xy 335.877427 -265.734334) (xy 335.920048 -265.709727) (xy 335.966064 -265.692275) (xy 336.014283 -265.682431)
			(xy 336.063458 -265.68045) (xy 336.112313 -265.686382) (xy 336.159584 -265.700074) (xy 336.204046 -265.721172)
			(xy 336.244549 -265.749128) (xy 336.280042 -265.78322) (xy 336.309607 -265.822564) (xy 336.332478 -265.866141)
			(xy 336.348062 -265.912822) (xy 336.355957 -265.961399) (xy 336.356452 -265.986006) (xy 336.685394 -265.986006)
			(xy 336.689354 -265.936952) (xy 336.701131 -265.889168) (xy 336.720422 -265.843892) (xy 336.746725 -265.802296)
			(xy 336.77936 -265.765459) (xy 336.817481 -265.734334) (xy 336.860102 -265.709727) (xy 336.906118 -265.692275)
			(xy 336.954337 -265.682431) (xy 337.003512 -265.68045) (xy 337.052367 -265.686382) (xy 337.099638 -265.700074)
			(xy 337.1441 -265.721172) (xy 337.184603 -265.749128) (xy 337.220096 -265.78322) (xy 337.249661 -265.822564)
			(xy 337.272532 -265.866141) (xy 337.288116 -265.912822) (xy 337.296011 -265.961399) (xy 337.296506 -265.986006)
			(xy 337.625194 -265.986006) (xy 337.629154 -265.936952) (xy 337.640931 -265.889168) (xy 337.660222 -265.843892)
			(xy 337.686525 -265.802296) (xy 337.71916 -265.765459) (xy 337.757281 -265.734334) (xy 337.799902 -265.709727)
			(xy 337.845918 -265.692275) (xy 337.894137 -265.682431) (xy 337.943312 -265.68045) (xy 337.992167 -265.686382)
			(xy 338.039438 -265.700074) (xy 338.0839 -265.721172) (xy 338.124403 -265.749128) (xy 338.159896 -265.78322)
			(xy 338.189461 -265.822564) (xy 338.212332 -265.866141) (xy 338.227916 -265.912822) (xy 338.235811 -265.961399)
			(xy 338.236306 -265.986006) (xy 338.565248 -265.986006) (xy 338.569208 -265.936952) (xy 338.580985 -265.889168)
			(xy 338.600276 -265.843892) (xy 338.626579 -265.802296) (xy 338.659214 -265.765459) (xy 338.697335 -265.734334)
			(xy 338.739956 -265.709727) (xy 338.785972 -265.692275) (xy 338.834191 -265.682431) (xy 338.883366 -265.68045)
			(xy 338.932221 -265.686382) (xy 338.979492 -265.700074) (xy 339.023954 -265.721172) (xy 339.064457 -265.749128)
			(xy 339.09995 -265.78322) (xy 339.129515 -265.822564) (xy 339.152386 -265.866141) (xy 339.16797 -265.912822)
			(xy 339.175865 -265.961399) (xy 339.17636 -265.986006) (xy 339.505302 -265.986006) (xy 339.509262 -265.936952)
			(xy 339.521039 -265.889168) (xy 339.54033 -265.843892) (xy 339.566633 -265.802296) (xy 339.599268 -265.765459)
			(xy 339.637389 -265.734334) (xy 339.68001 -265.709727) (xy 339.726026 -265.692275) (xy 339.774245 -265.682431)
			(xy 339.82342 -265.68045) (xy 339.872275 -265.686382) (xy 339.919546 -265.700074) (xy 339.964008 -265.721172)
			(xy 340.004511 -265.749128) (xy 340.040004 -265.78322) (xy 340.069569 -265.822564) (xy 340.09244 -265.866141)
			(xy 340.108024 -265.912822) (xy 340.115919 -265.961399) (xy 340.116414 -265.986006) (xy 340.434925 -265.986006)
			(xy 340.43902 -265.935278) (xy 340.451199 -265.885864) (xy 340.471147 -265.839044) (xy 340.498348 -265.79603)
			(xy 340.532096 -265.757936) (xy 340.571518 -265.725749) (xy 340.615592 -265.700303) (xy 340.663178 -265.682256)
			(xy 340.713042 -265.672076) (xy 340.763894 -265.670027) (xy 340.814415 -265.676161) (xy 340.863299 -265.690321)
			(xy 340.909278 -265.712138) (xy 340.951162 -265.741048) (xy 340.987866 -265.776303) (xy 341.018439 -265.816989)
			(xy 341.04209 -265.862052) (xy 341.058206 -265.910326) (xy 341.06637 -265.96056) (xy 341.066882 -265.986006)
			(xy 342.32521 -265.986006) (xy 342.32917 -265.936952) (xy 342.340947 -265.889168) (xy 342.360238 -265.843892)
			(xy 342.386541 -265.802296) (xy 342.419176 -265.765459) (xy 342.457297 -265.734334) (xy 342.499918 -265.709727)
			(xy 342.545934 -265.692275) (xy 342.594153 -265.682431) (xy 342.643328 -265.68045) (xy 342.692183 -265.686382)
			(xy 342.739454 -265.700074) (xy 342.783916 -265.721172) (xy 342.824419 -265.749128) (xy 342.859912 -265.78322)
			(xy 342.889477 -265.822564) (xy 342.912348 -265.866141) (xy 342.927932 -265.912822) (xy 342.935827 -265.961399)
			(xy 342.936322 -265.986006) (xy 343.254833 -265.986006) (xy 343.258928 -265.935278) (xy 343.271107 -265.885864)
			(xy 343.291055 -265.839044) (xy 343.318256 -265.79603) (xy 343.352004 -265.757936) (xy 343.391426 -265.725749)
			(xy 343.4355 -265.700303) (xy 343.483086 -265.682256) (xy 343.53295 -265.672076) (xy 343.583802 -265.670027)
			(xy 343.634323 -265.676161) (xy 343.683207 -265.690321) (xy 343.729186 -265.712138) (xy 343.77107 -265.741048)
			(xy 343.807774 -265.776303) (xy 343.838347 -265.816989) (xy 343.861998 -265.862052) (xy 343.878114 -265.910326)
			(xy 343.886278 -265.96056) (xy 343.88679 -265.986006) (xy 344.205318 -265.986006) (xy 344.209278 -265.936952)
			(xy 344.221055 -265.889168) (xy 344.240346 -265.843892) (xy 344.266649 -265.802296) (xy 344.299284 -265.765459)
			(xy 344.337405 -265.734334) (xy 344.380026 -265.709727) (xy 344.426042 -265.692275) (xy 344.474261 -265.682431)
			(xy 344.523436 -265.68045) (xy 344.572291 -265.686382) (xy 344.619562 -265.700074) (xy 344.664024 -265.721172)
			(xy 344.704527 -265.749128) (xy 344.74002 -265.78322) (xy 344.769585 -265.822564) (xy 344.792456 -265.866141)
			(xy 344.80804 -265.912822) (xy 344.815935 -265.961399) (xy 344.81643 -265.986006) (xy 346.085426 -265.986006)
			(xy 346.089386 -265.936952) (xy 346.101163 -265.889168) (xy 346.120454 -265.843892) (xy 346.146757 -265.802296)
			(xy 346.179392 -265.765459) (xy 346.217513 -265.734334) (xy 346.260134 -265.709727) (xy 346.30615 -265.692275)
			(xy 346.354369 -265.682431) (xy 346.403544 -265.68045) (xy 346.452399 -265.686382) (xy 346.49967 -265.700074)
			(xy 346.544132 -265.721172) (xy 346.584635 -265.749128) (xy 346.620128 -265.78322) (xy 346.649693 -265.822564)
			(xy 346.672564 -265.866141) (xy 346.688148 -265.912822) (xy 346.696043 -265.961399) (xy 346.696538 -265.986006)
			(xy 346.696043 -266.010613) (xy 346.688148 -266.05919) (xy 346.672564 -266.105871) (xy 346.649693 -266.149448)
			(xy 346.620128 -266.188792) (xy 346.584635 -266.222884) (xy 346.544132 -266.25084) (xy 346.49967 -266.271938)
			(xy 346.452399 -266.28563) (xy 346.403544 -266.291562) (xy 346.354369 -266.289581) (xy 346.30615 -266.279737)
			(xy 346.260134 -266.262285) (xy 346.217513 -266.237678) (xy 346.179392 -266.206553) (xy 346.146757 -266.169716)
			(xy 346.120454 -266.12812) (xy 346.101163 -266.082844) (xy 346.089386 -266.03506) (xy 346.085426 -265.986006)
			(xy 344.81643 -265.986006) (xy 344.815935 -266.010613) (xy 344.80804 -266.05919) (xy 344.792456 -266.105871)
			(xy 344.769585 -266.149448) (xy 344.74002 -266.188792) (xy 344.704527 -266.222884) (xy 344.664024 -266.25084)
			(xy 344.619562 -266.271938) (xy 344.572291 -266.28563) (xy 344.523436 -266.291562) (xy 344.474261 -266.289581)
			(xy 344.426042 -266.279737) (xy 344.380026 -266.262285) (xy 344.337405 -266.237678) (xy 344.299284 -266.206553)
			(xy 344.266649 -266.169716) (xy 344.240346 -266.12812) (xy 344.221055 -266.082844) (xy 344.209278 -266.03506)
			(xy 344.205318 -265.986006) (xy 343.88679 -265.986006) (xy 343.886278 -266.011452) (xy 343.878114 -266.061686)
			(xy 343.861998 -266.10996) (xy 343.838347 -266.155023) (xy 343.807774 -266.195709) (xy 343.77107 -266.230964)
			(xy 343.729186 -266.259874) (xy 343.683207 -266.281691) (xy 343.634323 -266.295851) (xy 343.583802 -266.301985)
			(xy 343.53295 -266.299936) (xy 343.483086 -266.289756) (xy 343.4355 -266.271709) (xy 343.391426 -266.246263)
			(xy 343.352004 -266.214076) (xy 343.318256 -266.175982) (xy 343.291055 -266.132968) (xy 343.271107 -266.086148)
			(xy 343.258928 -266.036734) (xy 343.254833 -265.986006) (xy 342.936322 -265.986006) (xy 342.935827 -266.010613)
			(xy 342.927932 -266.05919) (xy 342.912348 -266.105871) (xy 342.889477 -266.149448) (xy 342.859912 -266.188792)
			(xy 342.824419 -266.222884) (xy 342.783916 -266.25084) (xy 342.739454 -266.271938) (xy 342.692183 -266.28563)
			(xy 342.643328 -266.291562) (xy 342.594153 -266.289581) (xy 342.545934 -266.279737) (xy 342.499918 -266.262285)
			(xy 342.457297 -266.237678) (xy 342.419176 -266.206553) (xy 342.386541 -266.169716) (xy 342.360238 -266.12812)
			(xy 342.340947 -266.082844) (xy 342.32917 -266.03506) (xy 342.32521 -265.986006) (xy 341.066882 -265.986006)
			(xy 341.06637 -266.011452) (xy 341.058206 -266.061686) (xy 341.04209 -266.10996) (xy 341.018439 -266.155023)
			(xy 340.987866 -266.195709) (xy 340.951162 -266.230964) (xy 340.909278 -266.259874) (xy 340.863299 -266.281691)
			(xy 340.814415 -266.295851) (xy 340.763894 -266.301985) (xy 340.713042 -266.299936) (xy 340.663178 -266.289756)
			(xy 340.615592 -266.271709) (xy 340.571518 -266.246263) (xy 340.532096 -266.214076) (xy 340.498348 -266.175982)
			(xy 340.471147 -266.132968) (xy 340.451199 -266.086148) (xy 340.43902 -266.036734) (xy 340.434925 -265.986006)
			(xy 340.116414 -265.986006) (xy 340.115919 -266.010613) (xy 340.108024 -266.05919) (xy 340.09244 -266.105871)
			(xy 340.069569 -266.149448) (xy 340.040004 -266.188792) (xy 340.004511 -266.222884) (xy 339.964008 -266.25084)
			(xy 339.919546 -266.271938) (xy 339.872275 -266.28563) (xy 339.82342 -266.291562) (xy 339.774245 -266.289581)
			(xy 339.726026 -266.279737) (xy 339.68001 -266.262285) (xy 339.637389 -266.237678) (xy 339.599268 -266.206553)
			(xy 339.566633 -266.169716) (xy 339.54033 -266.12812) (xy 339.521039 -266.082844) (xy 339.509262 -266.03506)
			(xy 339.505302 -265.986006) (xy 339.17636 -265.986006) (xy 339.175865 -266.010613) (xy 339.16797 -266.05919)
			(xy 339.152386 -266.105871) (xy 339.129515 -266.149448) (xy 339.09995 -266.188792) (xy 339.064457 -266.222884)
			(xy 339.023954 -266.25084) (xy 338.979492 -266.271938) (xy 338.932221 -266.28563) (xy 338.883366 -266.291562)
			(xy 338.834191 -266.289581) (xy 338.785972 -266.279737) (xy 338.739956 -266.262285) (xy 338.697335 -266.237678)
			(xy 338.659214 -266.206553) (xy 338.626579 -266.169716) (xy 338.600276 -266.12812) (xy 338.580985 -266.082844)
			(xy 338.569208 -266.03506) (xy 338.565248 -265.986006) (xy 338.236306 -265.986006) (xy 338.235811 -266.010613)
			(xy 338.227916 -266.05919) (xy 338.212332 -266.105871) (xy 338.189461 -266.149448) (xy 338.159896 -266.188792)
			(xy 338.124403 -266.222884) (xy 338.0839 -266.25084) (xy 338.039438 -266.271938) (xy 337.992167 -266.28563)
			(xy 337.943312 -266.291562) (xy 337.894137 -266.289581) (xy 337.845918 -266.279737) (xy 337.799902 -266.262285)
			(xy 337.757281 -266.237678) (xy 337.71916 -266.206553) (xy 337.686525 -266.169716) (xy 337.660222 -266.12812)
			(xy 337.640931 -266.082844) (xy 337.629154 -266.03506) (xy 337.625194 -265.986006) (xy 337.296506 -265.986006)
			(xy 337.296011 -266.010613) (xy 337.288116 -266.05919) (xy 337.272532 -266.105871) (xy 337.249661 -266.149448)
			(xy 337.220096 -266.188792) (xy 337.184603 -266.222884) (xy 337.1441 -266.25084) (xy 337.099638 -266.271938)
			(xy 337.052367 -266.28563) (xy 337.003512 -266.291562) (xy 336.954337 -266.289581) (xy 336.906118 -266.279737)
			(xy 336.860102 -266.262285) (xy 336.817481 -266.237678) (xy 336.77936 -266.206553) (xy 336.746725 -266.169716)
			(xy 336.720422 -266.12812) (xy 336.701131 -266.082844) (xy 336.689354 -266.03506) (xy 336.685394 -265.986006)
			(xy 336.356452 -265.986006) (xy 336.355957 -266.010613) (xy 336.348062 -266.05919) (xy 336.332478 -266.105871)
			(xy 336.309607 -266.149448) (xy 336.280042 -266.188792) (xy 336.244549 -266.222884) (xy 336.204046 -266.25084)
			(xy 336.159584 -266.271938) (xy 336.112313 -266.28563) (xy 336.063458 -266.291562) (xy 336.014283 -266.289581)
			(xy 335.966064 -266.279737) (xy 335.920048 -266.262285) (xy 335.877427 -266.237678) (xy 335.839306 -266.206553)
			(xy 335.806671 -266.169716) (xy 335.780368 -266.12812) (xy 335.761077 -266.082844) (xy 335.7493 -266.03506)
			(xy 335.74534 -265.986006) (xy 334.476344 -265.986006) (xy 334.475849 -266.010613) (xy 334.467954 -266.05919)
			(xy 334.45237 -266.105871) (xy 334.429499 -266.149448) (xy 334.399934 -266.188792) (xy 334.364441 -266.222884)
			(xy 334.323938 -266.25084) (xy 334.279476 -266.271938) (xy 334.232205 -266.28563) (xy 334.18335 -266.291562)
			(xy 334.134175 -266.289581) (xy 334.085956 -266.279737) (xy 334.03994 -266.262285) (xy 333.997319 -266.237678)
			(xy 333.959198 -266.206553) (xy 333.926563 -266.169716) (xy 333.90026 -266.12812) (xy 333.880969 -266.082844)
			(xy 333.869192 -266.03506) (xy 333.865232 -265.986006) (xy 333.53629 -265.986006) (xy 333.535795 -266.010613)
			(xy 333.5279 -266.05919) (xy 333.512316 -266.105871) (xy 333.489445 -266.149448) (xy 333.45988 -266.188792)
			(xy 333.424387 -266.222884) (xy 333.383884 -266.25084) (xy 333.339422 -266.271938) (xy 333.292151 -266.28563)
			(xy 333.243296 -266.291562) (xy 333.194121 -266.289581) (xy 333.145902 -266.279737) (xy 333.099886 -266.262285)
			(xy 333.057265 -266.237678) (xy 333.019144 -266.206553) (xy 332.986509 -266.169716) (xy 332.960206 -266.12812)
			(xy 332.940915 -266.082844) (xy 332.929138 -266.03506) (xy 332.925178 -265.986006) (xy 332.59649 -265.986006)
			(xy 332.595995 -266.010613) (xy 332.5881 -266.05919) (xy 332.572516 -266.105871) (xy 332.549645 -266.149448)
			(xy 332.52008 -266.188792) (xy 332.484587 -266.222884) (xy 332.444084 -266.25084) (xy 332.399622 -266.271938)
			(xy 332.352351 -266.28563) (xy 332.303496 -266.291562) (xy 332.254321 -266.289581) (xy 332.206102 -266.279737)
			(xy 332.160086 -266.262285) (xy 332.117465 -266.237678) (xy 332.079344 -266.206553) (xy 332.046709 -266.169716)
			(xy 332.020406 -266.12812) (xy 332.001115 -266.082844) (xy 331.989338 -266.03506) (xy 331.985378 -265.986006)
			(xy 331.656213 -265.986006) (xy 331.656213 -266.010208) (xy 331.648584 -266.058013) (xy 331.633519 -266.104019)
			(xy 331.611392 -266.147077) (xy 331.582757 -266.18611) (xy 331.54833 -266.220144) (xy 331.50897 -266.248327)
			(xy 331.487526 -266.259564) (xy 331.486764 -266.259818) (xy 331.480508 -266.263221) (xy 331.470061 -266.27289)
			(xy 331.46619 -266.278868) (xy 331.463142 -266.283948) (xy 331.459332 -266.297156) (xy 331.459332 -266.486132)
			(xy 331.459803 -266.495505) (xy 331.466646 -266.512963) (xy 331.479325 -266.526778) (xy 331.487526 -266.531344)
			(xy 331.518006 -266.545568) (xy 331.566266 -266.56792) (xy 331.569551 -266.569415) (xy 331.576433 -266.571585)
			(xy 331.579982 -266.572238) (xy 331.584357 -266.57279) (xy 331.593171 -266.572532) (xy 331.597508 -266.57173)
			(xy 331.605382 -266.569698) (xy 331.62367 -266.56284) (xy 331.63002 -266.55776) (xy 331.650501 -266.54205)
			(xy 331.695639 -266.51702) (xy 331.744341 -266.499929) (xy 331.795221 -266.491262) (xy 331.821028 -266.490704)
			(xy 331.846281 -266.491228) (xy 331.896097 -266.499545) (xy 331.943865 -266.515947) (xy 331.988282 -266.539988)
			(xy 332.028136 -266.571012) (xy 332.062341 -266.608171) (xy 332.089964 -266.650454) (xy 332.110251 -266.696706)
			(xy 332.122649 -266.745667) (xy 332.126819 -266.796) (xy 332.126818 -266.796012) (xy 332.455278 -266.796012)
			(xy 332.459238 -266.746958) (xy 332.471015 -266.699174) (xy 332.490306 -266.653898) (xy 332.516609 -266.612302)
			(xy 332.549244 -266.575465) (xy 332.587365 -266.54434) (xy 332.629986 -266.519733) (xy 332.676002 -266.502281)
			(xy 332.724221 -266.492437) (xy 332.773396 -266.490456) (xy 332.822251 -266.496388) (xy 332.869522 -266.51008)
			(xy 332.913984 -266.531178) (xy 332.954487 -266.559134) (xy 332.98998 -266.593226) (xy 333.019545 -266.63257)
			(xy 333.042416 -266.676147) (xy 333.058 -266.722828) (xy 333.065895 -266.771405) (xy 333.06639 -266.796012)
			(xy 333.395332 -266.796012) (xy 333.399292 -266.746958) (xy 333.411069 -266.699174) (xy 333.43036 -266.653898)
			(xy 333.456663 -266.612302) (xy 333.489298 -266.575465) (xy 333.527419 -266.54434) (xy 333.57004 -266.519733)
			(xy 333.616056 -266.502281) (xy 333.664275 -266.492437) (xy 333.71345 -266.490456) (xy 333.762305 -266.496388)
			(xy 333.809576 -266.51008) (xy 333.854038 -266.531178) (xy 333.894541 -266.559134) (xy 333.930034 -266.593226)
			(xy 333.959599 -266.63257) (xy 333.98247 -266.676147) (xy 333.998054 -266.722828) (xy 334.005949 -266.771405)
			(xy 334.006444 -266.796012) (xy 334.335386 -266.796012) (xy 334.339346 -266.746958) (xy 334.351123 -266.699174)
			(xy 334.370414 -266.653898) (xy 334.396717 -266.612302) (xy 334.429352 -266.575465) (xy 334.467473 -266.54434)
			(xy 334.510094 -266.519733) (xy 334.55611 -266.502281) (xy 334.604329 -266.492437) (xy 334.653504 -266.490456)
			(xy 334.702359 -266.496388) (xy 334.74963 -266.51008) (xy 334.794092 -266.531178) (xy 334.834595 -266.559134)
			(xy 334.870088 -266.593226) (xy 334.899653 -266.63257) (xy 334.922524 -266.676147) (xy 334.938108 -266.722828)
			(xy 334.946003 -266.771405) (xy 334.946498 -266.796012) (xy 335.275186 -266.796012) (xy 335.279146 -266.746958)
			(xy 335.290923 -266.699174) (xy 335.310214 -266.653898) (xy 335.336517 -266.612302) (xy 335.369152 -266.575465)
			(xy 335.407273 -266.54434) (xy 335.449894 -266.519733) (xy 335.49591 -266.502281) (xy 335.544129 -266.492437)
			(xy 335.593304 -266.490456) (xy 335.642159 -266.496388) (xy 335.68943 -266.51008) (xy 335.733892 -266.531178)
			(xy 335.774395 -266.559134) (xy 335.809888 -266.593226) (xy 335.839453 -266.63257) (xy 335.862324 -266.676147)
			(xy 335.877908 -266.722828) (xy 335.885803 -266.771405) (xy 335.886298 -266.796012) (xy 336.21524 -266.796012)
			(xy 336.2192 -266.746958) (xy 336.230977 -266.699174) (xy 336.250268 -266.653898) (xy 336.276571 -266.612302)
			(xy 336.309206 -266.575465) (xy 336.347327 -266.54434) (xy 336.389948 -266.519733) (xy 336.435964 -266.502281)
			(xy 336.484183 -266.492437) (xy 336.533358 -266.490456) (xy 336.582213 -266.496388) (xy 336.629484 -266.51008)
			(xy 336.673946 -266.531178) (xy 336.714449 -266.559134) (xy 336.749942 -266.593226) (xy 336.779507 -266.63257)
			(xy 336.802378 -266.676147) (xy 336.817962 -266.722828) (xy 336.825857 -266.771405) (xy 336.826352 -266.796012)
			(xy 337.155294 -266.796012) (xy 337.159254 -266.746958) (xy 337.171031 -266.699174) (xy 337.190322 -266.653898)
			(xy 337.216625 -266.612302) (xy 337.24926 -266.575465) (xy 337.287381 -266.54434) (xy 337.330002 -266.519733)
			(xy 337.376018 -266.502281) (xy 337.424237 -266.492437) (xy 337.473412 -266.490456) (xy 337.522267 -266.496388)
			(xy 337.569538 -266.51008) (xy 337.614 -266.531178) (xy 337.654503 -266.559134) (xy 337.689996 -266.593226)
			(xy 337.719561 -266.63257) (xy 337.742432 -266.676147) (xy 337.758016 -266.722828) (xy 337.765911 -266.771405)
			(xy 337.766406 -266.796012) (xy 338.095348 -266.796012) (xy 338.099308 -266.746958) (xy 338.111085 -266.699174)
			(xy 338.130376 -266.653898) (xy 338.156679 -266.612302) (xy 338.189314 -266.575465) (xy 338.227435 -266.54434)
			(xy 338.270056 -266.519733) (xy 338.316072 -266.502281) (xy 338.364291 -266.492437) (xy 338.413466 -266.490456)
			(xy 338.462321 -266.496388) (xy 338.509592 -266.51008) (xy 338.554054 -266.531178) (xy 338.594557 -266.559134)
			(xy 338.63005 -266.593226) (xy 338.659615 -266.63257) (xy 338.682486 -266.676147) (xy 338.69807 -266.722828)
			(xy 338.705965 -266.771405) (xy 338.70646 -266.796012) (xy 339.024971 -266.796012) (xy 339.029066 -266.745284)
			(xy 339.041245 -266.69587) (xy 339.061193 -266.64905) (xy 339.088394 -266.606036) (xy 339.122142 -266.567942)
			(xy 339.161564 -266.535755) (xy 339.205638 -266.510309) (xy 339.253224 -266.492262) (xy 339.303088 -266.482082)
			(xy 339.35394 -266.480033) (xy 339.404461 -266.486167) (xy 339.453345 -266.500327) (xy 339.499324 -266.522144)
			(xy 339.541208 -266.551054) (xy 339.577912 -266.586309) (xy 339.608485 -266.626995) (xy 339.632136 -266.672058)
			(xy 339.648252 -266.720332) (xy 339.656416 -266.770566) (xy 339.656928 -266.796012) (xy 339.964771 -266.796012)
			(xy 339.968866 -266.745284) (xy 339.981045 -266.69587) (xy 340.000993 -266.64905) (xy 340.028194 -266.606036)
			(xy 340.061942 -266.567942) (xy 340.101364 -266.535755) (xy 340.145438 -266.510309) (xy 340.193024 -266.492262)
			(xy 340.242888 -266.482082) (xy 340.29374 -266.480033) (xy 340.344261 -266.486167) (xy 340.393145 -266.500327)
			(xy 340.439124 -266.522144) (xy 340.481008 -266.551054) (xy 340.517712 -266.586309) (xy 340.548285 -266.626995)
			(xy 340.571936 -266.672058) (xy 340.588052 -266.720332) (xy 340.596216 -266.770566) (xy 340.596728 -266.796012)
			(xy 340.915256 -266.796012) (xy 340.919216 -266.746958) (xy 340.930993 -266.699174) (xy 340.950284 -266.653898)
			(xy 340.976587 -266.612302) (xy 341.009222 -266.575465) (xy 341.047343 -266.54434) (xy 341.089964 -266.519733)
			(xy 341.13598 -266.502281) (xy 341.184199 -266.492437) (xy 341.233374 -266.490456) (xy 341.282229 -266.496388)
			(xy 341.3295 -266.51008) (xy 341.373962 -266.531178) (xy 341.414465 -266.559134) (xy 341.449958 -266.593226)
			(xy 341.479523 -266.63257) (xy 341.502394 -266.676147) (xy 341.517978 -266.722828) (xy 341.525873 -266.771405)
			(xy 341.526368 -266.796012) (xy 341.844879 -266.796012) (xy 341.848974 -266.745284) (xy 341.861153 -266.69587)
			(xy 341.881101 -266.64905) (xy 341.908302 -266.606036) (xy 341.94205 -266.567942) (xy 341.981472 -266.535755)
			(xy 342.025546 -266.510309) (xy 342.073132 -266.492262) (xy 342.122996 -266.482082) (xy 342.173848 -266.480033)
			(xy 342.224369 -266.486167) (xy 342.273253 -266.500327) (xy 342.319232 -266.522144) (xy 342.361116 -266.551054)
			(xy 342.39782 -266.586309) (xy 342.428393 -266.626995) (xy 342.452044 -266.672058) (xy 342.46816 -266.720332)
			(xy 342.476324 -266.770566) (xy 342.476836 -266.796012) (xy 342.795364 -266.796012) (xy 342.799324 -266.746958)
			(xy 342.811101 -266.699174) (xy 342.830392 -266.653898) (xy 342.856695 -266.612302) (xy 342.88933 -266.575465)
			(xy 342.927451 -266.54434) (xy 342.970072 -266.519733) (xy 343.016088 -266.502281) (xy 343.064307 -266.492437)
			(xy 343.113482 -266.490456) (xy 343.162337 -266.496388) (xy 343.209608 -266.51008) (xy 343.25407 -266.531178)
			(xy 343.294573 -266.559134) (xy 343.330066 -266.593226) (xy 343.359631 -266.63257) (xy 343.382502 -266.676147)
			(xy 343.398086 -266.722828) (xy 343.405981 -266.771405) (xy 343.406476 -266.796012) (xy 343.724987 -266.796012)
			(xy 343.729082 -266.745284) (xy 343.741261 -266.69587) (xy 343.761209 -266.64905) (xy 343.78841 -266.606036)
			(xy 343.822158 -266.567942) (xy 343.86158 -266.535755) (xy 343.905654 -266.510309) (xy 343.95324 -266.492262)
			(xy 344.003104 -266.482082) (xy 344.053956 -266.480033) (xy 344.104477 -266.486167) (xy 344.153361 -266.500327)
			(xy 344.19934 -266.522144) (xy 344.241224 -266.551054) (xy 344.277928 -266.586309) (xy 344.308501 -266.626995)
			(xy 344.332152 -266.672058) (xy 344.348268 -266.720332) (xy 344.356432 -266.770566) (xy 344.356944 -266.796012)
			(xy 345.615272 -266.796012) (xy 345.619232 -266.746958) (xy 345.631009 -266.699174) (xy 345.6503 -266.653898)
			(xy 345.676603 -266.612302) (xy 345.709238 -266.575465) (xy 345.747359 -266.54434) (xy 345.78998 -266.519733)
			(xy 345.835996 -266.502281) (xy 345.884215 -266.492437) (xy 345.93339 -266.490456) (xy 345.982245 -266.496388)
			(xy 346.029516 -266.51008) (xy 346.073978 -266.531178) (xy 346.114481 -266.559134) (xy 346.149974 -266.593226)
			(xy 346.179539 -266.63257) (xy 346.20241 -266.676147) (xy 346.217994 -266.722828) (xy 346.225889 -266.771405)
			(xy 346.226384 -266.796012) (xy 346.555326 -266.796012) (xy 346.559286 -266.746958) (xy 346.571063 -266.699174)
			(xy 346.590354 -266.653898) (xy 346.616657 -266.612302) (xy 346.649292 -266.575465) (xy 346.687413 -266.54434)
			(xy 346.730034 -266.519733) (xy 346.77605 -266.502281) (xy 346.824269 -266.492437) (xy 346.873444 -266.490456)
			(xy 346.922299 -266.496388) (xy 346.96957 -266.51008) (xy 347.014032 -266.531178) (xy 347.054535 -266.559134)
			(xy 347.090028 -266.593226) (xy 347.119593 -266.63257) (xy 347.142464 -266.676147) (xy 347.158048 -266.722828)
			(xy 347.165943 -266.771405) (xy 347.166438 -266.796012) (xy 347.165943 -266.820619) (xy 347.158048 -266.869196)
			(xy 347.142464 -266.915877) (xy 347.119593 -266.959454) (xy 347.090028 -266.998798) (xy 347.054535 -267.03289)
			(xy 347.014032 -267.060846) (xy 346.96957 -267.081944) (xy 346.922299 -267.095636) (xy 346.873444 -267.101568)
			(xy 346.824269 -267.099587) (xy 346.77605 -267.089743) (xy 346.730034 -267.072291) (xy 346.687413 -267.047684)
			(xy 346.649292 -267.016559) (xy 346.616657 -266.979722) (xy 346.590354 -266.938126) (xy 346.571063 -266.89285)
			(xy 346.559286 -266.845066) (xy 346.555326 -266.796012) (xy 346.226384 -266.796012) (xy 346.225889 -266.820619)
			(xy 346.217994 -266.869196) (xy 346.20241 -266.915877) (xy 346.179539 -266.959454) (xy 346.149974 -266.998798)
			(xy 346.114481 -267.03289) (xy 346.073978 -267.060846) (xy 346.029516 -267.081944) (xy 345.982245 -267.095636)
			(xy 345.93339 -267.101568) (xy 345.884215 -267.099587) (xy 345.835996 -267.089743) (xy 345.78998 -267.072291)
			(xy 345.747359 -267.047684) (xy 345.709238 -267.016559) (xy 345.676603 -266.979722) (xy 345.6503 -266.938126)
			(xy 345.631009 -266.89285) (xy 345.619232 -266.845066) (xy 345.615272 -266.796012) (xy 344.356944 -266.796012)
			(xy 344.356432 -266.821458) (xy 344.348268 -266.871692) (xy 344.332152 -266.919966) (xy 344.308501 -266.965029)
			(xy 344.277928 -267.005715) (xy 344.241224 -267.04097) (xy 344.19934 -267.06988) (xy 344.153361 -267.091697)
			(xy 344.104477 -267.105857) (xy 344.053956 -267.111991) (xy 344.003104 -267.109942) (xy 343.95324 -267.099762)
			(xy 343.905654 -267.081715) (xy 343.86158 -267.056269) (xy 343.822158 -267.024082) (xy 343.78841 -266.985988)
			(xy 343.761209 -266.942974) (xy 343.741261 -266.896154) (xy 343.729082 -266.84674) (xy 343.724987 -266.796012)
			(xy 343.406476 -266.796012) (xy 343.405981 -266.820619) (xy 343.398086 -266.869196) (xy 343.382502 -266.915877)
			(xy 343.359631 -266.959454) (xy 343.330066 -266.998798) (xy 343.294573 -267.03289) (xy 343.25407 -267.060846)
			(xy 343.209608 -267.081944) (xy 343.162337 -267.095636) (xy 343.113482 -267.101568) (xy 343.064307 -267.099587)
			(xy 343.016088 -267.089743) (xy 342.970072 -267.072291) (xy 342.927451 -267.047684) (xy 342.88933 -267.016559)
			(xy 342.856695 -266.979722) (xy 342.830392 -266.938126) (xy 342.811101 -266.89285) (xy 342.799324 -266.845066)
			(xy 342.795364 -266.796012) (xy 342.476836 -266.796012) (xy 342.476324 -266.821458) (xy 342.46816 -266.871692)
			(xy 342.452044 -266.919966) (xy 342.428393 -266.965029) (xy 342.39782 -267.005715) (xy 342.361116 -267.04097)
			(xy 342.319232 -267.06988) (xy 342.273253 -267.091697) (xy 342.224369 -267.105857) (xy 342.173848 -267.111991)
			(xy 342.122996 -267.109942) (xy 342.073132 -267.099762) (xy 342.025546 -267.081715) (xy 341.981472 -267.056269)
			(xy 341.94205 -267.024082) (xy 341.908302 -266.985988) (xy 341.881101 -266.942974) (xy 341.861153 -266.896154)
			(xy 341.848974 -266.84674) (xy 341.844879 -266.796012) (xy 341.526368 -266.796012) (xy 341.525873 -266.820619)
			(xy 341.517978 -266.869196) (xy 341.502394 -266.915877) (xy 341.479523 -266.959454) (xy 341.449958 -266.998798)
			(xy 341.414465 -267.03289) (xy 341.373962 -267.060846) (xy 341.3295 -267.081944) (xy 341.282229 -267.095636)
			(xy 341.233374 -267.101568) (xy 341.184199 -267.099587) (xy 341.13598 -267.089743) (xy 341.089964 -267.072291)
			(xy 341.047343 -267.047684) (xy 341.009222 -267.016559) (xy 340.976587 -266.979722) (xy 340.950284 -266.938126)
			(xy 340.930993 -266.89285) (xy 340.919216 -266.845066) (xy 340.915256 -266.796012) (xy 340.596728 -266.796012)
			(xy 340.596216 -266.821458) (xy 340.588052 -266.871692) (xy 340.571936 -266.919966) (xy 340.548285 -266.965029)
			(xy 340.517712 -267.005715) (xy 340.481008 -267.04097) (xy 340.439124 -267.06988) (xy 340.393145 -267.091697)
			(xy 340.344261 -267.105857) (xy 340.29374 -267.111991) (xy 340.242888 -267.109942) (xy 340.193024 -267.099762)
			(xy 340.145438 -267.081715) (xy 340.101364 -267.056269) (xy 340.061942 -267.024082) (xy 340.028194 -266.985988)
			(xy 340.000993 -266.942974) (xy 339.981045 -266.896154) (xy 339.968866 -266.84674) (xy 339.964771 -266.796012)
			(xy 339.656928 -266.796012) (xy 339.656416 -266.821458) (xy 339.648252 -266.871692) (xy 339.632136 -266.919966)
			(xy 339.608485 -266.965029) (xy 339.577912 -267.005715) (xy 339.541208 -267.04097) (xy 339.499324 -267.06988)
			(xy 339.453345 -267.091697) (xy 339.404461 -267.105857) (xy 339.35394 -267.111991) (xy 339.303088 -267.109942)
			(xy 339.253224 -267.099762) (xy 339.205638 -267.081715) (xy 339.161564 -267.056269) (xy 339.122142 -267.024082)
			(xy 339.088394 -266.985988) (xy 339.061193 -266.942974) (xy 339.041245 -266.896154) (xy 339.029066 -266.84674)
			(xy 339.024971 -266.796012) (xy 338.70646 -266.796012) (xy 338.705965 -266.820619) (xy 338.69807 -266.869196)
			(xy 338.682486 -266.915877) (xy 338.659615 -266.959454) (xy 338.63005 -266.998798) (xy 338.594557 -267.03289)
			(xy 338.554054 -267.060846) (xy 338.509592 -267.081944) (xy 338.462321 -267.095636) (xy 338.413466 -267.101568)
			(xy 338.364291 -267.099587) (xy 338.316072 -267.089743) (xy 338.270056 -267.072291) (xy 338.227435 -267.047684)
			(xy 338.189314 -267.016559) (xy 338.156679 -266.979722) (xy 338.130376 -266.938126) (xy 338.111085 -266.89285)
			(xy 338.099308 -266.845066) (xy 338.095348 -266.796012) (xy 337.766406 -266.796012) (xy 337.765911 -266.820619)
			(xy 337.758016 -266.869196) (xy 337.742432 -266.915877) (xy 337.719561 -266.959454) (xy 337.689996 -266.998798)
			(xy 337.654503 -267.03289) (xy 337.614 -267.060846) (xy 337.569538 -267.081944) (xy 337.522267 -267.095636)
			(xy 337.473412 -267.101568) (xy 337.424237 -267.099587) (xy 337.376018 -267.089743) (xy 337.330002 -267.072291)
			(xy 337.287381 -267.047684) (xy 337.24926 -267.016559) (xy 337.216625 -266.979722) (xy 337.190322 -266.938126)
			(xy 337.171031 -266.89285) (xy 337.159254 -266.845066) (xy 337.155294 -266.796012) (xy 336.826352 -266.796012)
			(xy 336.825857 -266.820619) (xy 336.817962 -266.869196) (xy 336.802378 -266.915877) (xy 336.779507 -266.959454)
			(xy 336.749942 -266.998798) (xy 336.714449 -267.03289) (xy 336.673946 -267.060846) (xy 336.629484 -267.081944)
			(xy 336.582213 -267.095636) (xy 336.533358 -267.101568) (xy 336.484183 -267.099587) (xy 336.435964 -267.089743)
			(xy 336.389948 -267.072291) (xy 336.347327 -267.047684) (xy 336.309206 -267.016559) (xy 336.276571 -266.979722)
			(xy 336.250268 -266.938126) (xy 336.230977 -266.89285) (xy 336.2192 -266.845066) (xy 336.21524 -266.796012)
			(xy 335.886298 -266.796012) (xy 335.885803 -266.820619) (xy 335.877908 -266.869196) (xy 335.862324 -266.915877)
			(xy 335.839453 -266.959454) (xy 335.809888 -266.998798) (xy 335.774395 -267.03289) (xy 335.733892 -267.060846)
			(xy 335.68943 -267.081944) (xy 335.642159 -267.095636) (xy 335.593304 -267.101568) (xy 335.544129 -267.099587)
			(xy 335.49591 -267.089743) (xy 335.449894 -267.072291) (xy 335.407273 -267.047684) (xy 335.369152 -267.016559)
			(xy 335.336517 -266.979722) (xy 335.310214 -266.938126) (xy 335.290923 -266.89285) (xy 335.279146 -266.845066)
			(xy 335.275186 -266.796012) (xy 334.946498 -266.796012) (xy 334.946003 -266.820619) (xy 334.938108 -266.869196)
			(xy 334.922524 -266.915877) (xy 334.899653 -266.959454) (xy 334.870088 -266.998798) (xy 334.834595 -267.03289)
			(xy 334.794092 -267.060846) (xy 334.74963 -267.081944) (xy 334.702359 -267.095636) (xy 334.653504 -267.101568)
			(xy 334.604329 -267.099587) (xy 334.55611 -267.089743) (xy 334.510094 -267.072291) (xy 334.467473 -267.047684)
			(xy 334.429352 -267.016559) (xy 334.396717 -266.979722) (xy 334.370414 -266.938126) (xy 334.351123 -266.89285)
			(xy 334.339346 -266.845066) (xy 334.335386 -266.796012) (xy 334.006444 -266.796012) (xy 334.005949 -266.820619)
			(xy 333.998054 -266.869196) (xy 333.98247 -266.915877) (xy 333.959599 -266.959454) (xy 333.930034 -266.998798)
			(xy 333.894541 -267.03289) (xy 333.854038 -267.060846) (xy 333.809576 -267.081944) (xy 333.762305 -267.095636)
			(xy 333.71345 -267.101568) (xy 333.664275 -267.099587) (xy 333.616056 -267.089743) (xy 333.57004 -267.072291)
			(xy 333.527419 -267.047684) (xy 333.489298 -267.016559) (xy 333.456663 -266.979722) (xy 333.43036 -266.938126)
			(xy 333.411069 -266.89285) (xy 333.399292 -266.845066) (xy 333.395332 -266.796012) (xy 333.06639 -266.796012)
			(xy 333.065895 -266.820619) (xy 333.058 -266.869196) (xy 333.042416 -266.915877) (xy 333.019545 -266.959454)
			(xy 332.98998 -266.998798) (xy 332.954487 -267.03289) (xy 332.913984 -267.060846) (xy 332.869522 -267.081944)
			(xy 332.822251 -267.095636) (xy 332.773396 -267.101568) (xy 332.724221 -267.099587) (xy 332.676002 -267.089743)
			(xy 332.629986 -267.072291) (xy 332.587365 -267.047684) (xy 332.549244 -267.016559) (xy 332.516609 -266.979722)
			(xy 332.490306 -266.938126) (xy 332.471015 -266.89285) (xy 332.459238 -266.845066) (xy 332.455278 -266.796012)
			(xy 332.126818 -266.796012) (xy 332.122649 -266.846333) (xy 332.110251 -266.895294) (xy 332.089964 -266.941546)
			(xy 332.062341 -266.983829) (xy 332.028136 -267.020988) (xy 331.988282 -267.052012) (xy 331.943865 -267.076053)
			(xy 331.896097 -267.092455) (xy 331.846281 -267.100772) (xy 331.821028 -267.10132) (xy 331.808265 -267.10118)
			(xy 331.782832 -267.099015) (xy 331.770228 -267.097002) (xy 331.743541 -267.091921) (xy 331.692409 -267.073584)
			(xy 331.645333 -267.046483) (xy 331.624178 -267.029438) (xy 331.61859 -267.024866) (xy 331.605636 -267.019024)
			(xy 331.59827 -267.018008) (xy 331.591061 -267.017326) (xy 331.576755 -267.019526) (xy 331.570076 -267.022326)
			(xy 331.487018 -267.06068) (xy 331.479153 -267.065122) (xy 331.466939 -267.078414) (xy 331.460075 -267.09511)
			(xy 331.459332 -267.104114) (xy 331.459332 -267.287756) (xy 331.45957 -267.294708) (xy 331.463303 -267.308101)
			(xy 331.466698 -267.314172) (xy 331.47 -267.319252) (xy 331.480414 -267.328904) (xy 331.487526 -267.33246)
			(xy 331.508974 -267.343687) (xy 331.548331 -267.371872) (xy 331.582756 -267.405905) (xy 331.611389 -267.444938)
			(xy 331.633513 -267.487995) (xy 331.648576 -267.534) (xy 331.656203 -267.581804) (xy 331.656202 -267.606018)
			(xy 331.985378 -267.606018) (xy 331.989338 -267.556964) (xy 332.001115 -267.50918) (xy 332.020406 -267.463904)
			(xy 332.046709 -267.422308) (xy 332.079344 -267.385471) (xy 332.117465 -267.354346) (xy 332.160086 -267.329739)
			(xy 332.206102 -267.312287) (xy 332.254321 -267.302443) (xy 332.303496 -267.300462) (xy 332.352351 -267.306394)
			(xy 332.399622 -267.320086) (xy 332.444084 -267.341184) (xy 332.484587 -267.36914) (xy 332.52008 -267.403232)
			(xy 332.549645 -267.442576) (xy 332.572516 -267.486153) (xy 332.5881 -267.532834) (xy 332.595995 -267.581411)
			(xy 332.59649 -267.606018) (xy 332.925178 -267.606018) (xy 332.929138 -267.556964) (xy 332.940915 -267.50918)
			(xy 332.960206 -267.463904) (xy 332.986509 -267.422308) (xy 333.019144 -267.385471) (xy 333.057265 -267.354346)
			(xy 333.099886 -267.329739) (xy 333.145902 -267.312287) (xy 333.194121 -267.302443) (xy 333.243296 -267.300462)
			(xy 333.292151 -267.306394) (xy 333.339422 -267.320086) (xy 333.383884 -267.341184) (xy 333.424387 -267.36914)
			(xy 333.45988 -267.403232) (xy 333.489445 -267.442576) (xy 333.512316 -267.486153) (xy 333.5279 -267.532834)
			(xy 333.535795 -267.581411) (xy 333.53629 -267.606018) (xy 333.865232 -267.606018) (xy 333.869192 -267.556964)
			(xy 333.880969 -267.50918) (xy 333.90026 -267.463904) (xy 333.926563 -267.422308) (xy 333.959198 -267.385471)
			(xy 333.997319 -267.354346) (xy 334.03994 -267.329739) (xy 334.085956 -267.312287) (xy 334.134175 -267.302443)
			(xy 334.18335 -267.300462) (xy 334.232205 -267.306394) (xy 334.279476 -267.320086) (xy 334.323938 -267.341184)
			(xy 334.364441 -267.36914) (xy 334.399934 -267.403232) (xy 334.429499 -267.442576) (xy 334.45237 -267.486153)
			(xy 334.467954 -267.532834) (xy 334.475849 -267.581411) (xy 334.476344 -267.606018) (xy 334.805286 -267.606018)
			(xy 334.809246 -267.556964) (xy 334.821023 -267.50918) (xy 334.840314 -267.463904) (xy 334.866617 -267.422308)
			(xy 334.899252 -267.385471) (xy 334.937373 -267.354346) (xy 334.979994 -267.329739) (xy 335.02601 -267.312287)
			(xy 335.074229 -267.302443) (xy 335.123404 -267.300462) (xy 335.172259 -267.306394) (xy 335.21953 -267.320086)
			(xy 335.263992 -267.341184) (xy 335.304495 -267.36914) (xy 335.339988 -267.403232) (xy 335.369553 -267.442576)
			(xy 335.392424 -267.486153) (xy 335.408008 -267.532834) (xy 335.415903 -267.581411) (xy 335.416398 -267.606018)
			(xy 335.74534 -267.606018) (xy 335.7493 -267.556964) (xy 335.761077 -267.50918) (xy 335.780368 -267.463904)
			(xy 335.806671 -267.422308) (xy 335.839306 -267.385471) (xy 335.877427 -267.354346) (xy 335.920048 -267.329739)
			(xy 335.966064 -267.312287) (xy 336.014283 -267.302443) (xy 336.063458 -267.300462) (xy 336.112313 -267.306394)
			(xy 336.159584 -267.320086) (xy 336.204046 -267.341184) (xy 336.244549 -267.36914) (xy 336.280042 -267.403232)
			(xy 336.309607 -267.442576) (xy 336.332478 -267.486153) (xy 336.348062 -267.532834) (xy 336.355957 -267.581411)
			(xy 336.356452 -267.606018) (xy 336.685394 -267.606018) (xy 336.689354 -267.556964) (xy 336.701131 -267.50918)
			(xy 336.720422 -267.463904) (xy 336.746725 -267.422308) (xy 336.77936 -267.385471) (xy 336.817481 -267.354346)
			(xy 336.860102 -267.329739) (xy 336.906118 -267.312287) (xy 336.954337 -267.302443) (xy 337.003512 -267.300462)
			(xy 337.052367 -267.306394) (xy 337.099638 -267.320086) (xy 337.1441 -267.341184) (xy 337.184603 -267.36914)
			(xy 337.220096 -267.403232) (xy 337.249661 -267.442576) (xy 337.272532 -267.486153) (xy 337.288116 -267.532834)
			(xy 337.296011 -267.581411) (xy 337.296506 -267.606018) (xy 337.625194 -267.606018) (xy 337.629154 -267.556964)
			(xy 337.640931 -267.50918) (xy 337.660222 -267.463904) (xy 337.686525 -267.422308) (xy 337.71916 -267.385471)
			(xy 337.757281 -267.354346) (xy 337.799902 -267.329739) (xy 337.845918 -267.312287) (xy 337.894137 -267.302443)
			(xy 337.943312 -267.300462) (xy 337.992167 -267.306394) (xy 338.039438 -267.320086) (xy 338.0839 -267.341184)
			(xy 338.124403 -267.36914) (xy 338.159896 -267.403232) (xy 338.189461 -267.442576) (xy 338.212332 -267.486153)
			(xy 338.227916 -267.532834) (xy 338.235811 -267.581411) (xy 338.236306 -267.606018) (xy 338.554817 -267.606018)
			(xy 338.558912 -267.55529) (xy 338.571091 -267.505876) (xy 338.591039 -267.459056) (xy 338.61824 -267.416042)
			(xy 338.651988 -267.377948) (xy 338.69141 -267.345761) (xy 338.735484 -267.320315) (xy 338.78307 -267.302268)
			(xy 338.832934 -267.292088) (xy 338.883786 -267.290039) (xy 338.934307 -267.296173) (xy 338.983191 -267.310333)
			(xy 339.02917 -267.33215) (xy 339.071054 -267.36106) (xy 339.107758 -267.396315) (xy 339.138331 -267.437001)
			(xy 339.161982 -267.482064) (xy 339.178098 -267.530338) (xy 339.186262 -267.580572) (xy 339.186774 -267.606018)
			(xy 339.505302 -267.606018) (xy 339.509262 -267.556964) (xy 339.521039 -267.50918) (xy 339.54033 -267.463904)
			(xy 339.566633 -267.422308) (xy 339.599268 -267.385471) (xy 339.637389 -267.354346) (xy 339.68001 -267.329739)
			(xy 339.726026 -267.312287) (xy 339.774245 -267.302443) (xy 339.82342 -267.300462) (xy 339.872275 -267.306394)
			(xy 339.919546 -267.320086) (xy 339.964008 -267.341184) (xy 340.004511 -267.36914) (xy 340.040004 -267.403232)
			(xy 340.069569 -267.442576) (xy 340.09244 -267.486153) (xy 340.108024 -267.532834) (xy 340.115919 -267.581411)
			(xy 340.116414 -267.606018) (xy 340.445356 -267.606018) (xy 340.449316 -267.556964) (xy 340.461093 -267.50918)
			(xy 340.480384 -267.463904) (xy 340.506687 -267.422308) (xy 340.539322 -267.385471) (xy 340.577443 -267.354346)
			(xy 340.620064 -267.329739) (xy 340.66608 -267.312287) (xy 340.714299 -267.302443) (xy 340.763474 -267.300462)
			(xy 340.812329 -267.306394) (xy 340.8596 -267.320086) (xy 340.904062 -267.341184) (xy 340.944565 -267.36914)
			(xy 340.980058 -267.403232) (xy 341.009623 -267.442576) (xy 341.032494 -267.486153) (xy 341.048078 -267.532834)
			(xy 341.055973 -267.581411) (xy 341.056468 -267.606018) (xy 341.38541 -267.606018) (xy 341.38937 -267.556964)
			(xy 341.401147 -267.50918) (xy 341.420438 -267.463904) (xy 341.446741 -267.422308) (xy 341.479376 -267.385471)
			(xy 341.517497 -267.354346) (xy 341.560118 -267.329739) (xy 341.606134 -267.312287) (xy 341.654353 -267.302443)
			(xy 341.703528 -267.300462) (xy 341.752383 -267.306394) (xy 341.799654 -267.320086) (xy 341.844116 -267.341184)
			(xy 341.884619 -267.36914) (xy 341.920112 -267.403232) (xy 341.949677 -267.442576) (xy 341.972548 -267.486153)
			(xy 341.988132 -267.532834) (xy 341.996027 -267.581411) (xy 341.996522 -267.606018) (xy 342.314779 -267.606018)
			(xy 342.318874 -267.55529) (xy 342.331053 -267.505876) (xy 342.351001 -267.459056) (xy 342.378202 -267.416042)
			(xy 342.41195 -267.377948) (xy 342.451372 -267.345761) (xy 342.495446 -267.320315) (xy 342.543032 -267.302268)
			(xy 342.592896 -267.292088) (xy 342.643748 -267.290039) (xy 342.694269 -267.296173) (xy 342.743153 -267.310333)
			(xy 342.789132 -267.33215) (xy 342.831016 -267.36106) (xy 342.86772 -267.396315) (xy 342.898293 -267.437001)
			(xy 342.921944 -267.482064) (xy 342.93806 -267.530338) (xy 342.946224 -267.580572) (xy 342.946736 -267.606018)
			(xy 343.265264 -267.606018) (xy 343.269224 -267.556964) (xy 343.281001 -267.50918) (xy 343.300292 -267.463904)
			(xy 343.326595 -267.422308) (xy 343.35923 -267.385471) (xy 343.397351 -267.354346) (xy 343.439972 -267.329739)
			(xy 343.485988 -267.312287) (xy 343.534207 -267.302443) (xy 343.583382 -267.300462) (xy 343.632237 -267.306394)
			(xy 343.679508 -267.320086) (xy 343.72397 -267.341184) (xy 343.764473 -267.36914) (xy 343.799966 -267.403232)
			(xy 343.829531 -267.442576) (xy 343.852402 -267.486153) (xy 343.867986 -267.532834) (xy 343.875881 -267.581411)
			(xy 343.876376 -267.606018) (xy 343.875881 -267.630625) (xy 343.867986 -267.679202) (xy 343.852402 -267.725883)
			(xy 343.829531 -267.76946) (xy 343.799966 -267.808804) (xy 343.764473 -267.842896) (xy 343.72397 -267.870852)
			(xy 343.679508 -267.89195) (xy 343.632237 -267.905642) (xy 343.583382 -267.911574) (xy 343.534207 -267.909593)
			(xy 343.485988 -267.899749) (xy 343.439972 -267.882297) (xy 343.397351 -267.85769) (xy 343.35923 -267.826565)
			(xy 343.326595 -267.789728) (xy 343.300292 -267.748132) (xy 343.281001 -267.702856) (xy 343.269224 -267.655072)
			(xy 343.265264 -267.606018) (xy 342.946736 -267.606018) (xy 342.946224 -267.631464) (xy 342.93806 -267.681698)
			(xy 342.921944 -267.729972) (xy 342.898293 -267.775035) (xy 342.86772 -267.815721) (xy 342.831016 -267.850976)
			(xy 342.789132 -267.879886) (xy 342.743153 -267.901703) (xy 342.694269 -267.915863) (xy 342.643748 -267.921997)
			(xy 342.592896 -267.919948) (xy 342.543032 -267.909768) (xy 342.495446 -267.891721) (xy 342.451372 -267.866275)
			(xy 342.41195 -267.834088) (xy 342.378202 -267.795994) (xy 342.351001 -267.75298) (xy 342.331053 -267.70616)
			(xy 342.318874 -267.656746) (xy 342.314779 -267.606018) (xy 341.996522 -267.606018) (xy 341.996027 -267.630625)
			(xy 341.988132 -267.679202) (xy 341.972548 -267.725883) (xy 341.949677 -267.76946) (xy 341.920112 -267.808804)
			(xy 341.884619 -267.842896) (xy 341.844116 -267.870852) (xy 341.799654 -267.89195) (xy 341.752383 -267.905642)
			(xy 341.703528 -267.911574) (xy 341.654353 -267.909593) (xy 341.606134 -267.899749) (xy 341.560118 -267.882297)
			(xy 341.517497 -267.85769) (xy 341.479376 -267.826565) (xy 341.446741 -267.789728) (xy 341.420438 -267.748132)
			(xy 341.401147 -267.702856) (xy 341.38937 -267.655072) (xy 341.38541 -267.606018) (xy 341.056468 -267.606018)
			(xy 341.055973 -267.630625) (xy 341.048078 -267.679202) (xy 341.032494 -267.725883) (xy 341.009623 -267.76946)
			(xy 340.980058 -267.808804) (xy 340.944565 -267.842896) (xy 340.904062 -267.870852) (xy 340.8596 -267.89195)
			(xy 340.812329 -267.905642) (xy 340.763474 -267.911574) (xy 340.714299 -267.909593) (xy 340.66608 -267.899749)
			(xy 340.620064 -267.882297) (xy 340.577443 -267.85769) (xy 340.539322 -267.826565) (xy 340.506687 -267.789728)
			(xy 340.480384 -267.748132) (xy 340.461093 -267.702856) (xy 340.449316 -267.655072) (xy 340.445356 -267.606018)
			(xy 340.116414 -267.606018) (xy 340.115919 -267.630625) (xy 340.108024 -267.679202) (xy 340.09244 -267.725883)
			(xy 340.069569 -267.76946) (xy 340.040004 -267.808804) (xy 340.004511 -267.842896) (xy 339.964008 -267.870852)
			(xy 339.919546 -267.89195) (xy 339.872275 -267.905642) (xy 339.82342 -267.911574) (xy 339.774245 -267.909593)
			(xy 339.726026 -267.899749) (xy 339.68001 -267.882297) (xy 339.637389 -267.85769) (xy 339.599268 -267.826565)
			(xy 339.566633 -267.789728) (xy 339.54033 -267.748132) (xy 339.521039 -267.702856) (xy 339.509262 -267.655072)
			(xy 339.505302 -267.606018) (xy 339.186774 -267.606018) (xy 339.186262 -267.631464) (xy 339.178098 -267.681698)
			(xy 339.161982 -267.729972) (xy 339.138331 -267.775035) (xy 339.107758 -267.815721) (xy 339.071054 -267.850976)
			(xy 339.02917 -267.879886) (xy 338.983191 -267.901703) (xy 338.934307 -267.915863) (xy 338.883786 -267.921997)
			(xy 338.832934 -267.919948) (xy 338.78307 -267.909768) (xy 338.735484 -267.891721) (xy 338.69141 -267.866275)
			(xy 338.651988 -267.834088) (xy 338.61824 -267.795994) (xy 338.591039 -267.75298) (xy 338.571091 -267.70616)
			(xy 338.558912 -267.656746) (xy 338.554817 -267.606018) (xy 338.236306 -267.606018) (xy 338.235811 -267.630625)
			(xy 338.227916 -267.679202) (xy 338.212332 -267.725883) (xy 338.189461 -267.76946) (xy 338.159896 -267.808804)
			(xy 338.124403 -267.842896) (xy 338.0839 -267.870852) (xy 338.039438 -267.89195) (xy 337.992167 -267.905642)
			(xy 337.943312 -267.911574) (xy 337.894137 -267.909593) (xy 337.845918 -267.899749) (xy 337.799902 -267.882297)
			(xy 337.757281 -267.85769) (xy 337.71916 -267.826565) (xy 337.686525 -267.789728) (xy 337.660222 -267.748132)
			(xy 337.640931 -267.702856) (xy 337.629154 -267.655072) (xy 337.625194 -267.606018) (xy 337.296506 -267.606018)
			(xy 337.296011 -267.630625) (xy 337.288116 -267.679202) (xy 337.272532 -267.725883) (xy 337.249661 -267.76946)
			(xy 337.220096 -267.808804) (xy 337.184603 -267.842896) (xy 337.1441 -267.870852) (xy 337.099638 -267.89195)
			(xy 337.052367 -267.905642) (xy 337.003512 -267.911574) (xy 336.954337 -267.909593) (xy 336.906118 -267.899749)
			(xy 336.860102 -267.882297) (xy 336.817481 -267.85769) (xy 336.77936 -267.826565) (xy 336.746725 -267.789728)
			(xy 336.720422 -267.748132) (xy 336.701131 -267.702856) (xy 336.689354 -267.655072) (xy 336.685394 -267.606018)
			(xy 336.356452 -267.606018) (xy 336.355957 -267.630625) (xy 336.348062 -267.679202) (xy 336.332478 -267.725883)
			(xy 336.309607 -267.76946) (xy 336.280042 -267.808804) (xy 336.244549 -267.842896) (xy 336.204046 -267.870852)
			(xy 336.159584 -267.89195) (xy 336.112313 -267.905642) (xy 336.063458 -267.911574) (xy 336.014283 -267.909593)
			(xy 335.966064 -267.899749) (xy 335.920048 -267.882297) (xy 335.877427 -267.85769) (xy 335.839306 -267.826565)
			(xy 335.806671 -267.789728) (xy 335.780368 -267.748132) (xy 335.761077 -267.702856) (xy 335.7493 -267.655072)
			(xy 335.74534 -267.606018) (xy 335.416398 -267.606018) (xy 335.415903 -267.630625) (xy 335.408008 -267.679202)
			(xy 335.392424 -267.725883) (xy 335.369553 -267.76946) (xy 335.339988 -267.808804) (xy 335.304495 -267.842896)
			(xy 335.263992 -267.870852) (xy 335.21953 -267.89195) (xy 335.172259 -267.905642) (xy 335.123404 -267.911574)
			(xy 335.074229 -267.909593) (xy 335.02601 -267.899749) (xy 334.979994 -267.882297) (xy 334.937373 -267.85769)
			(xy 334.899252 -267.826565) (xy 334.866617 -267.789728) (xy 334.840314 -267.748132) (xy 334.821023 -267.702856)
			(xy 334.809246 -267.655072) (xy 334.805286 -267.606018) (xy 334.476344 -267.606018) (xy 334.475849 -267.630625)
			(xy 334.467954 -267.679202) (xy 334.45237 -267.725883) (xy 334.429499 -267.76946) (xy 334.399934 -267.808804)
			(xy 334.364441 -267.842896) (xy 334.323938 -267.870852) (xy 334.279476 -267.89195) (xy 334.232205 -267.905642)
			(xy 334.18335 -267.911574) (xy 334.134175 -267.909593) (xy 334.085956 -267.899749) (xy 334.03994 -267.882297)
			(xy 333.997319 -267.85769) (xy 333.959198 -267.826565) (xy 333.926563 -267.789728) (xy 333.90026 -267.748132)
			(xy 333.880969 -267.702856) (xy 333.869192 -267.655072) (xy 333.865232 -267.606018) (xy 333.53629 -267.606018)
			(xy 333.535795 -267.630625) (xy 333.5279 -267.679202) (xy 333.512316 -267.725883) (xy 333.489445 -267.76946)
			(xy 333.45988 -267.808804) (xy 333.424387 -267.842896) (xy 333.383884 -267.870852) (xy 333.339422 -267.89195)
			(xy 333.292151 -267.905642) (xy 333.243296 -267.911574) (xy 333.194121 -267.909593) (xy 333.145902 -267.899749)
			(xy 333.099886 -267.882297) (xy 333.057265 -267.85769) (xy 333.019144 -267.826565) (xy 332.986509 -267.789728)
			(xy 332.960206 -267.748132) (xy 332.940915 -267.702856) (xy 332.929138 -267.655072) (xy 332.925178 -267.606018)
			(xy 332.59649 -267.606018) (xy 332.595995 -267.630625) (xy 332.5881 -267.679202) (xy 332.572516 -267.725883)
			(xy 332.549645 -267.76946) (xy 332.52008 -267.808804) (xy 332.484587 -267.842896) (xy 332.444084 -267.870852)
			(xy 332.399622 -267.89195) (xy 332.352351 -267.905642) (xy 332.303496 -267.911574) (xy 332.254321 -267.909593)
			(xy 332.206102 -267.899749) (xy 332.160086 -267.882297) (xy 332.117465 -267.85769) (xy 332.079344 -267.826565)
			(xy 332.046709 -267.789728) (xy 332.020406 -267.748132) (xy 332.001115 -267.702856) (xy 331.989338 -267.655072)
			(xy 331.985378 -267.606018) (xy 331.656202 -267.606018) (xy 331.656202 -267.630212) (xy 331.648573 -267.678016)
			(xy 331.633507 -267.72402) (xy 331.61138 -267.767076) (xy 331.582746 -267.806107) (xy 331.548319 -267.840139)
			(xy 331.50896 -267.868321) (xy 331.487526 -267.879576) (xy 331.486764 -267.87983) (xy 331.480509 -267.883234)
			(xy 331.470063 -267.892904) (xy 331.46619 -267.89888) (xy 331.463142 -267.90396) (xy 331.459332 -267.917168)
			(xy 331.459332 -268.106144) (xy 331.459805 -268.115516) (xy 331.466651 -268.132971) (xy 331.47933 -268.146782)
			(xy 331.487526 -268.151356) (xy 331.518006 -268.16558) (xy 331.566266 -268.187932) (xy 331.56955 -268.189429)
			(xy 331.576432 -268.191603) (xy 331.579982 -268.19225) (xy 331.584357 -268.192802) (xy 331.593171 -268.192544)
			(xy 331.597508 -268.191742) (xy 331.605382 -268.18971) (xy 331.62367 -268.182852) (xy 331.63002 -268.177772)
			(xy 331.650501 -268.162062) (xy 331.695639 -268.13703) (xy 331.74434 -268.119938) (xy 331.795221 -268.111272)
			(xy 331.821028 -268.110716) (xy 331.84628 -268.11124) (xy 331.896094 -268.119556) (xy 331.94386 -268.135958)
			(xy 331.988275 -268.159998) (xy 332.028128 -268.19102) (xy 332.062332 -268.228179) (xy 332.089953 -268.27046)
			(xy 332.110239 -268.31671) (xy 332.122637 -268.365669) (xy 332.126807 -268.416) (xy 332.126805 -268.416024)
			(xy 332.455278 -268.416024) (xy 332.459238 -268.36697) (xy 332.471015 -268.319186) (xy 332.490306 -268.27391)
			(xy 332.516609 -268.232314) (xy 332.549244 -268.195477) (xy 332.587365 -268.164352) (xy 332.629986 -268.139745)
			(xy 332.676002 -268.122293) (xy 332.724221 -268.112449) (xy 332.773396 -268.110468) (xy 332.822251 -268.1164)
			(xy 332.869522 -268.130092) (xy 332.913984 -268.15119) (xy 332.954487 -268.179146) (xy 332.98998 -268.213238)
			(xy 333.019545 -268.252582) (xy 333.042416 -268.296159) (xy 333.058 -268.34284) (xy 333.065895 -268.391417)
			(xy 333.06639 -268.416024) (xy 333.395332 -268.416024) (xy 333.399292 -268.36697) (xy 333.411069 -268.319186)
			(xy 333.43036 -268.27391) (xy 333.456663 -268.232314) (xy 333.489298 -268.195477) (xy 333.527419 -268.164352)
			(xy 333.57004 -268.139745) (xy 333.616056 -268.122293) (xy 333.664275 -268.112449) (xy 333.71345 -268.110468)
			(xy 333.762305 -268.1164) (xy 333.809576 -268.130092) (xy 333.854038 -268.15119) (xy 333.894541 -268.179146)
			(xy 333.930034 -268.213238) (xy 333.959599 -268.252582) (xy 333.98247 -268.296159) (xy 333.998054 -268.34284)
			(xy 334.005949 -268.391417) (xy 334.006444 -268.416024) (xy 335.275186 -268.416024) (xy 335.279146 -268.36697)
			(xy 335.290923 -268.319186) (xy 335.310214 -268.27391) (xy 335.336517 -268.232314) (xy 335.369152 -268.195477)
			(xy 335.407273 -268.164352) (xy 335.449894 -268.139745) (xy 335.49591 -268.122293) (xy 335.544129 -268.112449)
			(xy 335.593304 -268.110468) (xy 335.642159 -268.1164) (xy 335.68943 -268.130092) (xy 335.733892 -268.15119)
			(xy 335.774395 -268.179146) (xy 335.809888 -268.213238) (xy 335.839453 -268.252582) (xy 335.862324 -268.296159)
			(xy 335.877908 -268.34284) (xy 335.885803 -268.391417) (xy 335.886298 -268.416024) (xy 336.21524 -268.416024)
			(xy 336.2192 -268.36697) (xy 336.230977 -268.319186) (xy 336.250268 -268.27391) (xy 336.276571 -268.232314)
			(xy 336.309206 -268.195477) (xy 336.347327 -268.164352) (xy 336.389948 -268.139745) (xy 336.435964 -268.122293)
			(xy 336.484183 -268.112449) (xy 336.533358 -268.110468) (xy 336.582213 -268.1164) (xy 336.629484 -268.130092)
			(xy 336.673946 -268.15119) (xy 336.714449 -268.179146) (xy 336.749942 -268.213238) (xy 336.779507 -268.252582)
			(xy 336.802378 -268.296159) (xy 336.817962 -268.34284) (xy 336.825857 -268.391417) (xy 336.826352 -268.416024)
			(xy 337.155294 -268.416024) (xy 337.159254 -268.36697) (xy 337.171031 -268.319186) (xy 337.190322 -268.27391)
			(xy 337.216625 -268.232314) (xy 337.24926 -268.195477) (xy 337.287381 -268.164352) (xy 337.330002 -268.139745)
			(xy 337.376018 -268.122293) (xy 337.424237 -268.112449) (xy 337.473412 -268.110468) (xy 337.522267 -268.1164)
			(xy 337.569538 -268.130092) (xy 337.614 -268.15119) (xy 337.654503 -268.179146) (xy 337.689996 -268.213238)
			(xy 337.719561 -268.252582) (xy 337.742432 -268.296159) (xy 337.758016 -268.34284) (xy 337.765911 -268.391417)
			(xy 337.766406 -268.416024) (xy 338.095348 -268.416024) (xy 338.099308 -268.36697) (xy 338.111085 -268.319186)
			(xy 338.130376 -268.27391) (xy 338.156679 -268.232314) (xy 338.189314 -268.195477) (xy 338.227435 -268.164352)
			(xy 338.270056 -268.139745) (xy 338.316072 -268.122293) (xy 338.364291 -268.112449) (xy 338.413466 -268.110468)
			(xy 338.462321 -268.1164) (xy 338.509592 -268.130092) (xy 338.554054 -268.15119) (xy 338.594557 -268.179146)
			(xy 338.63005 -268.213238) (xy 338.659615 -268.252582) (xy 338.682486 -268.296159) (xy 338.69807 -268.34284)
			(xy 338.705965 -268.391417) (xy 338.70646 -268.416024) (xy 339.035402 -268.416024) (xy 339.039362 -268.36697)
			(xy 339.051139 -268.319186) (xy 339.07043 -268.27391) (xy 339.096733 -268.232314) (xy 339.129368 -268.195477)
			(xy 339.167489 -268.164352) (xy 339.21011 -268.139745) (xy 339.256126 -268.122293) (xy 339.304345 -268.112449)
			(xy 339.35352 -268.110468) (xy 339.402375 -268.1164) (xy 339.449646 -268.130092) (xy 339.494108 -268.15119)
			(xy 339.534611 -268.179146) (xy 339.570104 -268.213238) (xy 339.599669 -268.252582) (xy 339.62254 -268.296159)
			(xy 339.638124 -268.34284) (xy 339.646019 -268.391417) (xy 339.646514 -268.416024) (xy 339.975202 -268.416024)
			(xy 339.979162 -268.36697) (xy 339.990939 -268.319186) (xy 340.01023 -268.27391) (xy 340.036533 -268.232314)
			(xy 340.069168 -268.195477) (xy 340.107289 -268.164352) (xy 340.14991 -268.139745) (xy 340.195926 -268.122293)
			(xy 340.244145 -268.112449) (xy 340.29332 -268.110468) (xy 340.342175 -268.1164) (xy 340.389446 -268.130092)
			(xy 340.433908 -268.15119) (xy 340.474411 -268.179146) (xy 340.509904 -268.213238) (xy 340.539469 -268.252582)
			(xy 340.56234 -268.296159) (xy 340.577924 -268.34284) (xy 340.585819 -268.391417) (xy 340.586314 -268.416024)
			(xy 341.85531 -268.416024) (xy 341.85927 -268.36697) (xy 341.871047 -268.319186) (xy 341.890338 -268.27391)
			(xy 341.916641 -268.232314) (xy 341.949276 -268.195477) (xy 341.987397 -268.164352) (xy 342.030018 -268.139745)
			(xy 342.076034 -268.122293) (xy 342.124253 -268.112449) (xy 342.173428 -268.110468) (xy 342.222283 -268.1164)
			(xy 342.269554 -268.130092) (xy 342.314016 -268.15119) (xy 342.354519 -268.179146) (xy 342.390012 -268.213238)
			(xy 342.419577 -268.252582) (xy 342.442448 -268.296159) (xy 342.458032 -268.34284) (xy 342.465927 -268.391417)
			(xy 342.466422 -268.416024) (xy 342.795364 -268.416024) (xy 342.799324 -268.36697) (xy 342.811101 -268.319186)
			(xy 342.830392 -268.27391) (xy 342.856695 -268.232314) (xy 342.88933 -268.195477) (xy 342.927451 -268.164352)
			(xy 342.970072 -268.139745) (xy 343.016088 -268.122293) (xy 343.064307 -268.112449) (xy 343.113482 -268.110468)
			(xy 343.162337 -268.1164) (xy 343.209608 -268.130092) (xy 343.25407 -268.15119) (xy 343.294573 -268.179146)
			(xy 343.330066 -268.213238) (xy 343.359631 -268.252582) (xy 343.382502 -268.296159) (xy 343.398086 -268.34284)
			(xy 343.405981 -268.391417) (xy 343.406476 -268.416024) (xy 343.405981 -268.440631) (xy 343.398086 -268.489208)
			(xy 343.382502 -268.535889) (xy 343.359631 -268.579466) (xy 343.330066 -268.61881) (xy 343.294573 -268.652902)
			(xy 343.25407 -268.680858) (xy 343.209608 -268.701956) (xy 343.162337 -268.715648) (xy 343.113482 -268.72158)
			(xy 343.064307 -268.719599) (xy 343.016088 -268.709755) (xy 342.970072 -268.692303) (xy 342.927451 -268.667696)
			(xy 342.88933 -268.636571) (xy 342.856695 -268.599734) (xy 342.830392 -268.558138) (xy 342.811101 -268.512862)
			(xy 342.799324 -268.465078) (xy 342.795364 -268.416024) (xy 342.466422 -268.416024) (xy 342.465927 -268.440631)
			(xy 342.458032 -268.489208) (xy 342.442448 -268.535889) (xy 342.419577 -268.579466) (xy 342.390012 -268.61881)
			(xy 342.354519 -268.652902) (xy 342.314016 -268.680858) (xy 342.269554 -268.701956) (xy 342.222283 -268.715648)
			(xy 342.173428 -268.72158) (xy 342.124253 -268.719599) (xy 342.076034 -268.709755) (xy 342.030018 -268.692303)
			(xy 341.987397 -268.667696) (xy 341.949276 -268.636571) (xy 341.916641 -268.599734) (xy 341.890338 -268.558138)
			(xy 341.871047 -268.512862) (xy 341.85927 -268.465078) (xy 341.85531 -268.416024) (xy 340.586314 -268.416024)
			(xy 340.585819 -268.440631) (xy 340.577924 -268.489208) (xy 340.56234 -268.535889) (xy 340.539469 -268.579466)
			(xy 340.509904 -268.61881) (xy 340.474411 -268.652902) (xy 340.433908 -268.680858) (xy 340.389446 -268.701956)
			(xy 340.342175 -268.715648) (xy 340.29332 -268.72158) (xy 340.244145 -268.719599) (xy 340.195926 -268.709755)
			(xy 340.14991 -268.692303) (xy 340.107289 -268.667696) (xy 340.069168 -268.636571) (xy 340.036533 -268.599734)
			(xy 340.01023 -268.558138) (xy 339.990939 -268.512862) (xy 339.979162 -268.465078) (xy 339.975202 -268.416024)
			(xy 339.646514 -268.416024) (xy 339.646019 -268.440631) (xy 339.638124 -268.489208) (xy 339.62254 -268.535889)
			(xy 339.599669 -268.579466) (xy 339.570104 -268.61881) (xy 339.534611 -268.652902) (xy 339.494108 -268.680858)
			(xy 339.449646 -268.701956) (xy 339.402375 -268.715648) (xy 339.35352 -268.72158) (xy 339.304345 -268.719599)
			(xy 339.256126 -268.709755) (xy 339.21011 -268.692303) (xy 339.167489 -268.667696) (xy 339.129368 -268.636571)
			(xy 339.096733 -268.599734) (xy 339.07043 -268.558138) (xy 339.051139 -268.512862) (xy 339.039362 -268.465078)
			(xy 339.035402 -268.416024) (xy 338.70646 -268.416024) (xy 338.705965 -268.440631) (xy 338.69807 -268.489208)
			(xy 338.682486 -268.535889) (xy 338.659615 -268.579466) (xy 338.63005 -268.61881) (xy 338.594557 -268.652902)
			(xy 338.554054 -268.680858) (xy 338.509592 -268.701956) (xy 338.462321 -268.715648) (xy 338.413466 -268.72158)
			(xy 338.364291 -268.719599) (xy 338.316072 -268.709755) (xy 338.270056 -268.692303) (xy 338.227435 -268.667696)
			(xy 338.189314 -268.636571) (xy 338.156679 -268.599734) (xy 338.130376 -268.558138) (xy 338.111085 -268.512862)
			(xy 338.099308 -268.465078) (xy 338.095348 -268.416024) (xy 337.766406 -268.416024) (xy 337.765911 -268.440631)
			(xy 337.758016 -268.489208) (xy 337.742432 -268.535889) (xy 337.719561 -268.579466) (xy 337.689996 -268.61881)
			(xy 337.654503 -268.652902) (xy 337.614 -268.680858) (xy 337.569538 -268.701956) (xy 337.522267 -268.715648)
			(xy 337.473412 -268.72158) (xy 337.424237 -268.719599) (xy 337.376018 -268.709755) (xy 337.330002 -268.692303)
			(xy 337.287381 -268.667696) (xy 337.24926 -268.636571) (xy 337.216625 -268.599734) (xy 337.190322 -268.558138)
			(xy 337.171031 -268.512862) (xy 337.159254 -268.465078) (xy 337.155294 -268.416024) (xy 336.826352 -268.416024)
			(xy 336.825857 -268.440631) (xy 336.817962 -268.489208) (xy 336.802378 -268.535889) (xy 336.779507 -268.579466)
			(xy 336.749942 -268.61881) (xy 336.714449 -268.652902) (xy 336.673946 -268.680858) (xy 336.629484 -268.701956)
			(xy 336.582213 -268.715648) (xy 336.533358 -268.72158) (xy 336.484183 -268.719599) (xy 336.435964 -268.709755)
			(xy 336.389948 -268.692303) (xy 336.347327 -268.667696) (xy 336.309206 -268.636571) (xy 336.276571 -268.599734)
			(xy 336.250268 -268.558138) (xy 336.230977 -268.512862) (xy 336.2192 -268.465078) (xy 336.21524 -268.416024)
			(xy 335.886298 -268.416024) (xy 335.885803 -268.440631) (xy 335.877908 -268.489208) (xy 335.862324 -268.535889)
			(xy 335.839453 -268.579466) (xy 335.809888 -268.61881) (xy 335.774395 -268.652902) (xy 335.733892 -268.680858)
			(xy 335.68943 -268.701956) (xy 335.642159 -268.715648) (xy 335.593304 -268.72158) (xy 335.544129 -268.719599)
			(xy 335.49591 -268.709755) (xy 335.449894 -268.692303) (xy 335.407273 -268.667696) (xy 335.369152 -268.636571)
			(xy 335.336517 -268.599734) (xy 335.310214 -268.558138) (xy 335.290923 -268.512862) (xy 335.279146 -268.465078)
			(xy 335.275186 -268.416024) (xy 334.006444 -268.416024) (xy 334.005949 -268.440631) (xy 333.998054 -268.489208)
			(xy 333.98247 -268.535889) (xy 333.959599 -268.579466) (xy 333.930034 -268.61881) (xy 333.894541 -268.652902)
			(xy 333.854038 -268.680858) (xy 333.809576 -268.701956) (xy 333.762305 -268.715648) (xy 333.71345 -268.72158)
			(xy 333.664275 -268.719599) (xy 333.616056 -268.709755) (xy 333.57004 -268.692303) (xy 333.527419 -268.667696)
			(xy 333.489298 -268.636571) (xy 333.456663 -268.599734) (xy 333.43036 -268.558138) (xy 333.411069 -268.512862)
			(xy 333.399292 -268.465078) (xy 333.395332 -268.416024) (xy 333.06639 -268.416024) (xy 333.065895 -268.440631)
			(xy 333.058 -268.489208) (xy 333.042416 -268.535889) (xy 333.019545 -268.579466) (xy 332.98998 -268.61881)
			(xy 332.954487 -268.652902) (xy 332.913984 -268.680858) (xy 332.869522 -268.701956) (xy 332.822251 -268.715648)
			(xy 332.773396 -268.72158) (xy 332.724221 -268.719599) (xy 332.676002 -268.709755) (xy 332.629986 -268.692303)
			(xy 332.587365 -268.667696) (xy 332.549244 -268.636571) (xy 332.516609 -268.599734) (xy 332.490306 -268.558138)
			(xy 332.471015 -268.512862) (xy 332.459238 -268.465078) (xy 332.455278 -268.416024) (xy 332.126805 -268.416024)
			(xy 332.122637 -268.466331) (xy 332.110239 -268.51529) (xy 332.089953 -268.56154) (xy 332.062332 -268.603821)
			(xy 332.028128 -268.64098) (xy 331.988275 -268.672002) (xy 331.94386 -268.696042) (xy 331.896094 -268.712444)
			(xy 331.84628 -268.72076) (xy 331.821028 -268.721332) (xy 331.794269 -268.72078) (xy 331.741569 -268.711462)
			(xy 331.691298 -268.693107) (xy 331.644993 -268.666275) (xy 331.624178 -268.64945) (xy 331.61859 -268.644878)
			(xy 331.605636 -268.639036) (xy 331.598524 -268.63802) (xy 331.591313 -268.637331) (xy 331.577 -268.639514)
			(xy 331.57033 -268.642338) (xy 331.531722 -268.660118) (xy 331.486764 -268.680946) (xy 331.478718 -268.685548)
			(xy 331.466363 -268.699345) (xy 331.459751 -268.716644) (xy 331.459332 -268.725904) (xy 331.459332 -268.907768)
			(xy 331.459571 -268.914719) (xy 331.463308 -268.928111) (xy 331.466698 -268.934184) (xy 331.47 -268.939264)
			(xy 331.480414 -268.948916) (xy 331.487526 -268.952472) (xy 331.508973 -268.963699) (xy 331.548329 -268.991883)
			(xy 331.582752 -269.025916) (xy 331.611382 -269.064948) (xy 331.633505 -269.108004) (xy 331.648567 -269.154008)
			(xy 331.656193 -269.20181) (xy 331.656191 -269.22603) (xy 331.985378 -269.22603) (xy 331.989338 -269.176976)
			(xy 332.001115 -269.129192) (xy 332.020406 -269.083916) (xy 332.046709 -269.04232) (xy 332.079344 -269.005483)
			(xy 332.117465 -268.974358) (xy 332.160086 -268.949751) (xy 332.206102 -268.932299) (xy 332.254321 -268.922455)
			(xy 332.303496 -268.920474) (xy 332.352351 -268.926406) (xy 332.399622 -268.940098) (xy 332.444084 -268.961196)
			(xy 332.484587 -268.989152) (xy 332.52008 -269.023244) (xy 332.549645 -269.062588) (xy 332.572516 -269.106165)
			(xy 332.5881 -269.152846) (xy 332.595995 -269.201423) (xy 332.59649 -269.22603) (xy 332.925178 -269.22603)
			(xy 332.929138 -269.176976) (xy 332.940915 -269.129192) (xy 332.960206 -269.083916) (xy 332.986509 -269.04232)
			(xy 333.019144 -269.005483) (xy 333.057265 -268.974358) (xy 333.099886 -268.949751) (xy 333.145902 -268.932299)
			(xy 333.194121 -268.922455) (xy 333.243296 -268.920474) (xy 333.292151 -268.926406) (xy 333.339422 -268.940098)
			(xy 333.383884 -268.961196) (xy 333.424387 -268.989152) (xy 333.45988 -269.023244) (xy 333.489445 -269.062588)
			(xy 333.512316 -269.106165) (xy 333.5279 -269.152846) (xy 333.535795 -269.201423) (xy 333.53629 -269.22603)
			(xy 333.865232 -269.22603) (xy 333.869192 -269.176976) (xy 333.880969 -269.129192) (xy 333.90026 -269.083916)
			(xy 333.926563 -269.04232) (xy 333.959198 -269.005483) (xy 333.997319 -268.974358) (xy 334.03994 -268.949751)
			(xy 334.085956 -268.932299) (xy 334.134175 -268.922455) (xy 334.18335 -268.920474) (xy 334.232205 -268.926406)
			(xy 334.279476 -268.940098) (xy 334.323938 -268.961196) (xy 334.364441 -268.989152) (xy 334.399934 -269.023244)
			(xy 334.429499 -269.062588) (xy 334.45237 -269.106165) (xy 334.467954 -269.152846) (xy 334.475849 -269.201423)
			(xy 334.476344 -269.22603) (xy 334.805286 -269.22603) (xy 334.809246 -269.176976) (xy 334.821023 -269.129192)
			(xy 334.840314 -269.083916) (xy 334.866617 -269.04232) (xy 334.899252 -269.005483) (xy 334.937373 -268.974358)
			(xy 334.979994 -268.949751) (xy 335.02601 -268.932299) (xy 335.074229 -268.922455) (xy 335.123404 -268.920474)
			(xy 335.172259 -268.926406) (xy 335.21953 -268.940098) (xy 335.263992 -268.961196) (xy 335.304495 -268.989152)
			(xy 335.339988 -269.023244) (xy 335.369553 -269.062588) (xy 335.392424 -269.106165) (xy 335.408008 -269.152846)
			(xy 335.415903 -269.201423) (xy 335.416398 -269.22603) (xy 335.74534 -269.22603) (xy 335.7493 -269.176976)
			(xy 335.761077 -269.129192) (xy 335.780368 -269.083916) (xy 335.806671 -269.04232) (xy 335.839306 -269.005483)
			(xy 335.877427 -268.974358) (xy 335.920048 -268.949751) (xy 335.966064 -268.932299) (xy 336.014283 -268.922455)
			(xy 336.063458 -268.920474) (xy 336.112313 -268.926406) (xy 336.159584 -268.940098) (xy 336.204046 -268.961196)
			(xy 336.244549 -268.989152) (xy 336.280042 -269.023244) (xy 336.309607 -269.062588) (xy 336.332478 -269.106165)
			(xy 336.348062 -269.152846) (xy 336.355957 -269.201423) (xy 336.356452 -269.22603) (xy 336.685394 -269.22603)
			(xy 336.689354 -269.176976) (xy 336.701131 -269.129192) (xy 336.720422 -269.083916) (xy 336.746725 -269.04232)
			(xy 336.77936 -269.005483) (xy 336.817481 -268.974358) (xy 336.860102 -268.949751) (xy 336.906118 -268.932299)
			(xy 336.954337 -268.922455) (xy 337.003512 -268.920474) (xy 337.052367 -268.926406) (xy 337.099638 -268.940098)
			(xy 337.1441 -268.961196) (xy 337.184603 -268.989152) (xy 337.220096 -269.023244) (xy 337.249661 -269.062588)
			(xy 337.272532 -269.106165) (xy 337.288116 -269.152846) (xy 337.296011 -269.201423) (xy 337.296506 -269.22603)
			(xy 337.625194 -269.22603) (xy 337.629154 -269.176976) (xy 337.640931 -269.129192) (xy 337.660222 -269.083916)
			(xy 337.686525 -269.04232) (xy 337.71916 -269.005483) (xy 337.757281 -268.974358) (xy 337.799902 -268.949751)
			(xy 337.845918 -268.932299) (xy 337.894137 -268.922455) (xy 337.943312 -268.920474) (xy 337.992167 -268.926406)
			(xy 338.039438 -268.940098) (xy 338.0839 -268.961196) (xy 338.124403 -268.989152) (xy 338.159896 -269.023244)
			(xy 338.189461 -269.062588) (xy 338.212332 -269.106165) (xy 338.227916 -269.152846) (xy 338.235811 -269.201423)
			(xy 338.236306 -269.22603) (xy 338.554817 -269.22603) (xy 338.558912 -269.175302) (xy 338.571091 -269.125888)
			(xy 338.591039 -269.079068) (xy 338.61824 -269.036054) (xy 338.651988 -268.99796) (xy 338.69141 -268.965773)
			(xy 338.735484 -268.940327) (xy 338.78307 -268.92228) (xy 338.832934 -268.9121) (xy 338.883786 -268.910051)
			(xy 338.934307 -268.916185) (xy 338.983191 -268.930345) (xy 339.02917 -268.952162) (xy 339.071054 -268.981072)
			(xy 339.107758 -269.016327) (xy 339.138331 -269.057013) (xy 339.161982 -269.102076) (xy 339.178098 -269.15035)
			(xy 339.186262 -269.200584) (xy 339.186774 -269.22603) (xy 339.505302 -269.22603) (xy 339.509262 -269.176976)
			(xy 339.521039 -269.129192) (xy 339.54033 -269.083916) (xy 339.566633 -269.04232) (xy 339.599268 -269.005483)
			(xy 339.637389 -268.974358) (xy 339.68001 -268.949751) (xy 339.726026 -268.932299) (xy 339.774245 -268.922455)
			(xy 339.82342 -268.920474) (xy 339.872275 -268.926406) (xy 339.919546 -268.940098) (xy 339.964008 -268.961196)
			(xy 340.004511 -268.989152) (xy 340.040004 -269.023244) (xy 340.069569 -269.062588) (xy 340.09244 -269.106165)
			(xy 340.108024 -269.152846) (xy 340.115919 -269.201423) (xy 340.116414 -269.22603) (xy 340.445356 -269.22603)
			(xy 340.449316 -269.176976) (xy 340.461093 -269.129192) (xy 340.480384 -269.083916) (xy 340.506687 -269.04232)
			(xy 340.539322 -269.005483) (xy 340.577443 -268.974358) (xy 340.620064 -268.949751) (xy 340.66608 -268.932299)
			(xy 340.714299 -268.922455) (xy 340.763474 -268.920474) (xy 340.812329 -268.926406) (xy 340.8596 -268.940098)
			(xy 340.904062 -268.961196) (xy 340.944565 -268.989152) (xy 340.980058 -269.023244) (xy 341.009623 -269.062588)
			(xy 341.032494 -269.106165) (xy 341.048078 -269.152846) (xy 341.055973 -269.201423) (xy 341.056468 -269.22603)
			(xy 341.38541 -269.22603) (xy 341.38937 -269.176976) (xy 341.401147 -269.129192) (xy 341.420438 -269.083916)
			(xy 341.446741 -269.04232) (xy 341.479376 -269.005483) (xy 341.517497 -268.974358) (xy 341.560118 -268.949751)
			(xy 341.606134 -268.932299) (xy 341.654353 -268.922455) (xy 341.703528 -268.920474) (xy 341.752383 -268.926406)
			(xy 341.799654 -268.940098) (xy 341.844116 -268.961196) (xy 341.884619 -268.989152) (xy 341.920112 -269.023244)
			(xy 341.949677 -269.062588) (xy 341.972548 -269.106165) (xy 341.988132 -269.152846) (xy 341.996027 -269.201423)
			(xy 341.996522 -269.22603) (xy 342.314779 -269.22603) (xy 342.318874 -269.175302) (xy 342.331053 -269.125888)
			(xy 342.351001 -269.079068) (xy 342.378202 -269.036054) (xy 342.41195 -268.99796) (xy 342.451372 -268.965773)
			(xy 342.495446 -268.940327) (xy 342.543032 -268.92228) (xy 342.592896 -268.9121) (xy 342.643748 -268.910051)
			(xy 342.694269 -268.916185) (xy 342.743153 -268.930345) (xy 342.789132 -268.952162) (xy 342.831016 -268.981072)
			(xy 342.86772 -269.016327) (xy 342.898293 -269.057013) (xy 342.921944 -269.102076) (xy 342.93806 -269.15035)
			(xy 342.946224 -269.200584) (xy 342.946736 -269.22603) (xy 343.265264 -269.22603) (xy 343.269224 -269.176976)
			(xy 343.281001 -269.129192) (xy 343.300292 -269.083916) (xy 343.326595 -269.04232) (xy 343.35923 -269.005483)
			(xy 343.397351 -268.974358) (xy 343.439972 -268.949751) (xy 343.485988 -268.932299) (xy 343.534207 -268.922455)
			(xy 343.583382 -268.920474) (xy 343.632237 -268.926406) (xy 343.679508 -268.940098) (xy 343.72397 -268.961196)
			(xy 343.764473 -268.989152) (xy 343.799966 -269.023244) (xy 343.829531 -269.062588) (xy 343.852402 -269.106165)
			(xy 343.867986 -269.152846) (xy 343.875881 -269.201423) (xy 343.876376 -269.22603) (xy 343.875881 -269.250637)
			(xy 343.867986 -269.299214) (xy 343.852402 -269.345895) (xy 343.829531 -269.389472) (xy 343.799966 -269.428816)
			(xy 343.764473 -269.462908) (xy 343.72397 -269.490864) (xy 343.679508 -269.511962) (xy 343.632237 -269.525654)
			(xy 343.583382 -269.531586) (xy 343.534207 -269.529605) (xy 343.485988 -269.519761) (xy 343.439972 -269.502309)
			(xy 343.397351 -269.477702) (xy 343.35923 -269.446577) (xy 343.326595 -269.40974) (xy 343.300292 -269.368144)
			(xy 343.281001 -269.322868) (xy 343.269224 -269.275084) (xy 343.265264 -269.22603) (xy 342.946736 -269.22603)
			(xy 342.946224 -269.251476) (xy 342.93806 -269.30171) (xy 342.921944 -269.349984) (xy 342.898293 -269.395047)
			(xy 342.86772 -269.435733) (xy 342.831016 -269.470988) (xy 342.789132 -269.499898) (xy 342.743153 -269.521715)
			(xy 342.694269 -269.535875) (xy 342.643748 -269.542009) (xy 342.592896 -269.53996) (xy 342.543032 -269.52978)
			(xy 342.495446 -269.511733) (xy 342.451372 -269.486287) (xy 342.41195 -269.4541) (xy 342.378202 -269.416006)
			(xy 342.351001 -269.372992) (xy 342.331053 -269.326172) (xy 342.318874 -269.276758) (xy 342.314779 -269.22603)
			(xy 341.996522 -269.22603) (xy 341.996027 -269.250637) (xy 341.988132 -269.299214) (xy 341.972548 -269.345895)
			(xy 341.949677 -269.389472) (xy 341.920112 -269.428816) (xy 341.884619 -269.462908) (xy 341.844116 -269.490864)
			(xy 341.799654 -269.511962) (xy 341.752383 -269.525654) (xy 341.703528 -269.531586) (xy 341.654353 -269.529605)
			(xy 341.606134 -269.519761) (xy 341.560118 -269.502309) (xy 341.517497 -269.477702) (xy 341.479376 -269.446577)
			(xy 341.446741 -269.40974) (xy 341.420438 -269.368144) (xy 341.401147 -269.322868) (xy 341.38937 -269.275084)
			(xy 341.38541 -269.22603) (xy 341.056468 -269.22603) (xy 341.055973 -269.250637) (xy 341.048078 -269.299214)
			(xy 341.032494 -269.345895) (xy 341.009623 -269.389472) (xy 340.980058 -269.428816) (xy 340.944565 -269.462908)
			(xy 340.904062 -269.490864) (xy 340.8596 -269.511962) (xy 340.812329 -269.525654) (xy 340.763474 -269.531586)
			(xy 340.714299 -269.529605) (xy 340.66608 -269.519761) (xy 340.620064 -269.502309) (xy 340.577443 -269.477702)
			(xy 340.539322 -269.446577) (xy 340.506687 -269.40974) (xy 340.480384 -269.368144) (xy 340.461093 -269.322868)
			(xy 340.449316 -269.275084) (xy 340.445356 -269.22603) (xy 340.116414 -269.22603) (xy 340.115919 -269.250637)
			(xy 340.108024 -269.299214) (xy 340.09244 -269.345895) (xy 340.069569 -269.389472) (xy 340.040004 -269.428816)
			(xy 340.004511 -269.462908) (xy 339.964008 -269.490864) (xy 339.919546 -269.511962) (xy 339.872275 -269.525654)
			(xy 339.82342 -269.531586) (xy 339.774245 -269.529605) (xy 339.726026 -269.519761) (xy 339.68001 -269.502309)
			(xy 339.637389 -269.477702) (xy 339.599268 -269.446577) (xy 339.566633 -269.40974) (xy 339.54033 -269.368144)
			(xy 339.521039 -269.322868) (xy 339.509262 -269.275084) (xy 339.505302 -269.22603) (xy 339.186774 -269.22603)
			(xy 339.186262 -269.251476) (xy 339.178098 -269.30171) (xy 339.161982 -269.349984) (xy 339.138331 -269.395047)
			(xy 339.107758 -269.435733) (xy 339.071054 -269.470988) (xy 339.02917 -269.499898) (xy 338.983191 -269.521715)
			(xy 338.934307 -269.535875) (xy 338.883786 -269.542009) (xy 338.832934 -269.53996) (xy 338.78307 -269.52978)
			(xy 338.735484 -269.511733) (xy 338.69141 -269.486287) (xy 338.651988 -269.4541) (xy 338.61824 -269.416006)
			(xy 338.591039 -269.372992) (xy 338.571091 -269.326172) (xy 338.558912 -269.276758) (xy 338.554817 -269.22603)
			(xy 338.236306 -269.22603) (xy 338.235811 -269.250637) (xy 338.227916 -269.299214) (xy 338.212332 -269.345895)
			(xy 338.189461 -269.389472) (xy 338.159896 -269.428816) (xy 338.124403 -269.462908) (xy 338.0839 -269.490864)
			(xy 338.039438 -269.511962) (xy 337.992167 -269.525654) (xy 337.943312 -269.531586) (xy 337.894137 -269.529605)
			(xy 337.845918 -269.519761) (xy 337.799902 -269.502309) (xy 337.757281 -269.477702) (xy 337.71916 -269.446577)
			(xy 337.686525 -269.40974) (xy 337.660222 -269.368144) (xy 337.640931 -269.322868) (xy 337.629154 -269.275084)
			(xy 337.625194 -269.22603) (xy 337.296506 -269.22603) (xy 337.296011 -269.250637) (xy 337.288116 -269.299214)
			(xy 337.272532 -269.345895) (xy 337.249661 -269.389472) (xy 337.220096 -269.428816) (xy 337.184603 -269.462908)
			(xy 337.1441 -269.490864) (xy 337.099638 -269.511962) (xy 337.052367 -269.525654) (xy 337.003512 -269.531586)
			(xy 336.954337 -269.529605) (xy 336.906118 -269.519761) (xy 336.860102 -269.502309) (xy 336.817481 -269.477702)
			(xy 336.77936 -269.446577) (xy 336.746725 -269.40974) (xy 336.720422 -269.368144) (xy 336.701131 -269.322868)
			(xy 336.689354 -269.275084) (xy 336.685394 -269.22603) (xy 336.356452 -269.22603) (xy 336.355957 -269.250637)
			(xy 336.348062 -269.299214) (xy 336.332478 -269.345895) (xy 336.309607 -269.389472) (xy 336.280042 -269.428816)
			(xy 336.244549 -269.462908) (xy 336.204046 -269.490864) (xy 336.159584 -269.511962) (xy 336.112313 -269.525654)
			(xy 336.063458 -269.531586) (xy 336.014283 -269.529605) (xy 335.966064 -269.519761) (xy 335.920048 -269.502309)
			(xy 335.877427 -269.477702) (xy 335.839306 -269.446577) (xy 335.806671 -269.40974) (xy 335.780368 -269.368144)
			(xy 335.761077 -269.322868) (xy 335.7493 -269.275084) (xy 335.74534 -269.22603) (xy 335.416398 -269.22603)
			(xy 335.415903 -269.250637) (xy 335.408008 -269.299214) (xy 335.392424 -269.345895) (xy 335.369553 -269.389472)
			(xy 335.339988 -269.428816) (xy 335.304495 -269.462908) (xy 335.263992 -269.490864) (xy 335.21953 -269.511962)
			(xy 335.172259 -269.525654) (xy 335.123404 -269.531586) (xy 335.074229 -269.529605) (xy 335.02601 -269.519761)
			(xy 334.979994 -269.502309) (xy 334.937373 -269.477702) (xy 334.899252 -269.446577) (xy 334.866617 -269.40974)
			(xy 334.840314 -269.368144) (xy 334.821023 -269.322868) (xy 334.809246 -269.275084) (xy 334.805286 -269.22603)
			(xy 334.476344 -269.22603) (xy 334.475849 -269.250637) (xy 334.467954 -269.299214) (xy 334.45237 -269.345895)
			(xy 334.429499 -269.389472) (xy 334.399934 -269.428816) (xy 334.364441 -269.462908) (xy 334.323938 -269.490864)
			(xy 334.279476 -269.511962) (xy 334.232205 -269.525654) (xy 334.18335 -269.531586) (xy 334.134175 -269.529605)
			(xy 334.085956 -269.519761) (xy 334.03994 -269.502309) (xy 333.997319 -269.477702) (xy 333.959198 -269.446577)
			(xy 333.926563 -269.40974) (xy 333.90026 -269.368144) (xy 333.880969 -269.322868) (xy 333.869192 -269.275084)
			(xy 333.865232 -269.22603) (xy 333.53629 -269.22603) (xy 333.535795 -269.250637) (xy 333.5279 -269.299214)
			(xy 333.512316 -269.345895) (xy 333.489445 -269.389472) (xy 333.45988 -269.428816) (xy 333.424387 -269.462908)
			(xy 333.383884 -269.490864) (xy 333.339422 -269.511962) (xy 333.292151 -269.525654) (xy 333.243296 -269.531586)
			(xy 333.194121 -269.529605) (xy 333.145902 -269.519761) (xy 333.099886 -269.502309) (xy 333.057265 -269.477702)
			(xy 333.019144 -269.446577) (xy 332.986509 -269.40974) (xy 332.960206 -269.368144) (xy 332.940915 -269.322868)
			(xy 332.929138 -269.275084) (xy 332.925178 -269.22603) (xy 332.59649 -269.22603) (xy 332.595995 -269.250637)
			(xy 332.5881 -269.299214) (xy 332.572516 -269.345895) (xy 332.549645 -269.389472) (xy 332.52008 -269.428816)
			(xy 332.484587 -269.462908) (xy 332.444084 -269.490864) (xy 332.399622 -269.511962) (xy 332.352351 -269.525654)
			(xy 332.303496 -269.531586) (xy 332.254321 -269.529605) (xy 332.206102 -269.519761) (xy 332.160086 -269.502309)
			(xy 332.117465 -269.477702) (xy 332.079344 -269.446577) (xy 332.046709 -269.40974) (xy 332.020406 -269.368144)
			(xy 332.001115 -269.322868) (xy 331.989338 -269.275084) (xy 331.985378 -269.22603) (xy 331.656191 -269.22603)
			(xy 331.65619 -269.250217) (xy 331.648561 -269.298018) (xy 331.633495 -269.344021) (xy 331.611368 -269.387075)
			(xy 331.582734 -269.426104) (xy 331.548308 -269.460134) (xy 331.50895 -269.488315) (xy 331.487526 -269.499588)
			(xy 331.486764 -269.499842) (xy 331.480509 -269.503246) (xy 331.470066 -269.512918) (xy 331.46619 -269.518892)
			(xy 331.463142 -269.523972) (xy 331.459332 -269.53718) (xy 331.459332 -269.726156) (xy 331.459807 -269.735527)
			(xy 331.466655 -269.752978) (xy 331.479335 -269.766786) (xy 331.487526 -269.771368) (xy 331.518006 -269.785592)
			(xy 331.566266 -269.807944) (xy 331.56955 -269.809441) (xy 331.576432 -269.811614) (xy 331.579982 -269.812262)
			(xy 331.584357 -269.812814) (xy 331.593171 -269.812556) (xy 331.597508 -269.811754) (xy 331.605382 -269.809722)
			(xy 331.62367 -269.802864) (xy 331.63002 -269.797784) (xy 331.650501 -269.782073) (xy 331.695638 -269.757041)
			(xy 331.74434 -269.739948) (xy 331.795221 -269.731281) (xy 331.821028 -269.730728) (xy 331.846279 -269.731252)
			(xy 331.896091 -269.739568) (xy 331.943855 -269.755969) (xy 331.988269 -269.780008) (xy 332.02812 -269.811029)
			(xy 332.062322 -269.848186) (xy 332.089943 -269.890465) (xy 332.110228 -269.936714) (xy 332.122625 -269.985671)
			(xy 332.126795 -270.036) (xy 332.126792 -270.036036) (xy 332.455278 -270.036036) (xy 332.459238 -269.986982)
			(xy 332.471015 -269.939198) (xy 332.490306 -269.893922) (xy 332.516609 -269.852326) (xy 332.549244 -269.815489)
			(xy 332.587365 -269.784364) (xy 332.629986 -269.759757) (xy 332.676002 -269.742305) (xy 332.724221 -269.732461)
			(xy 332.773396 -269.73048) (xy 332.822251 -269.736412) (xy 332.869522 -269.750104) (xy 332.913984 -269.771202)
			(xy 332.954487 -269.799158) (xy 332.98998 -269.83325) (xy 333.019545 -269.872594) (xy 333.042416 -269.916171)
			(xy 333.058 -269.962852) (xy 333.065895 -270.011429) (xy 333.06639 -270.036036) (xy 333.395332 -270.036036)
			(xy 333.399292 -269.986982) (xy 333.411069 -269.939198) (xy 333.43036 -269.893922) (xy 333.456663 -269.852326)
			(xy 333.489298 -269.815489) (xy 333.527419 -269.784364) (xy 333.57004 -269.759757) (xy 333.616056 -269.742305)
			(xy 333.664275 -269.732461) (xy 333.71345 -269.73048) (xy 333.762305 -269.736412) (xy 333.809576 -269.750104)
			(xy 333.854038 -269.771202) (xy 333.894541 -269.799158) (xy 333.930034 -269.83325) (xy 333.959599 -269.872594)
			(xy 333.98247 -269.916171) (xy 333.998054 -269.962852) (xy 334.005949 -270.011429) (xy 334.006444 -270.036036)
			(xy 334.335386 -270.036036) (xy 334.339346 -269.986982) (xy 334.351123 -269.939198) (xy 334.370414 -269.893922)
			(xy 334.396717 -269.852326) (xy 334.429352 -269.815489) (xy 334.467473 -269.784364) (xy 334.510094 -269.759757)
			(xy 334.55611 -269.742305) (xy 334.604329 -269.732461) (xy 334.653504 -269.73048) (xy 334.702359 -269.736412)
			(xy 334.74963 -269.750104) (xy 334.794092 -269.771202) (xy 334.834595 -269.799158) (xy 334.870088 -269.83325)
			(xy 334.899653 -269.872594) (xy 334.922524 -269.916171) (xy 334.938108 -269.962852) (xy 334.946003 -270.011429)
			(xy 334.946498 -270.036036) (xy 335.275186 -270.036036) (xy 335.279146 -269.986982) (xy 335.290923 -269.939198)
			(xy 335.310214 -269.893922) (xy 335.336517 -269.852326) (xy 335.369152 -269.815489) (xy 335.407273 -269.784364)
			(xy 335.449894 -269.759757) (xy 335.49591 -269.742305) (xy 335.544129 -269.732461) (xy 335.593304 -269.73048)
			(xy 335.642159 -269.736412) (xy 335.68943 -269.750104) (xy 335.733892 -269.771202) (xy 335.774395 -269.799158)
			(xy 335.809888 -269.83325) (xy 335.839453 -269.872594) (xy 335.862324 -269.916171) (xy 335.877908 -269.962852)
			(xy 335.885803 -270.011429) (xy 335.886298 -270.036036) (xy 336.21524 -270.036036) (xy 336.2192 -269.986982)
			(xy 336.230977 -269.939198) (xy 336.250268 -269.893922) (xy 336.276571 -269.852326) (xy 336.309206 -269.815489)
			(xy 336.347327 -269.784364) (xy 336.389948 -269.759757) (xy 336.435964 -269.742305) (xy 336.484183 -269.732461)
			(xy 336.533358 -269.73048) (xy 336.582213 -269.736412) (xy 336.629484 -269.750104) (xy 336.673946 -269.771202)
			(xy 336.714449 -269.799158) (xy 336.749942 -269.83325) (xy 336.779507 -269.872594) (xy 336.802378 -269.916171)
			(xy 336.817962 -269.962852) (xy 336.825857 -270.011429) (xy 336.826352 -270.036036) (xy 337.155294 -270.036036)
			(xy 337.159254 -269.986982) (xy 337.171031 -269.939198) (xy 337.190322 -269.893922) (xy 337.216625 -269.852326)
			(xy 337.24926 -269.815489) (xy 337.287381 -269.784364) (xy 337.330002 -269.759757) (xy 337.376018 -269.742305)
			(xy 337.424237 -269.732461) (xy 337.473412 -269.73048) (xy 337.522267 -269.736412) (xy 337.569538 -269.750104)
			(xy 337.614 -269.771202) (xy 337.654503 -269.799158) (xy 337.689996 -269.83325) (xy 337.719561 -269.872594)
			(xy 337.742432 -269.916171) (xy 337.758016 -269.962852) (xy 337.765911 -270.011429) (xy 337.766406 -270.036036)
			(xy 338.095348 -270.036036) (xy 338.099308 -269.986982) (xy 338.111085 -269.939198) (xy 338.130376 -269.893922)
			(xy 338.156679 -269.852326) (xy 338.189314 -269.815489) (xy 338.227435 -269.784364) (xy 338.270056 -269.759757)
			(xy 338.316072 -269.742305) (xy 338.364291 -269.732461) (xy 338.413466 -269.73048) (xy 338.462321 -269.736412)
			(xy 338.509592 -269.750104) (xy 338.554054 -269.771202) (xy 338.594557 -269.799158) (xy 338.63005 -269.83325)
			(xy 338.659615 -269.872594) (xy 338.682486 -269.916171) (xy 338.69807 -269.962852) (xy 338.705965 -270.011429)
			(xy 338.70646 -270.036036) (xy 339.024971 -270.036036) (xy 339.029066 -269.985308) (xy 339.041245 -269.935894)
			(xy 339.061193 -269.889074) (xy 339.088394 -269.84606) (xy 339.122142 -269.807966) (xy 339.161564 -269.775779)
			(xy 339.205638 -269.750333) (xy 339.253224 -269.732286) (xy 339.303088 -269.722106) (xy 339.35394 -269.720057)
			(xy 339.404461 -269.726191) (xy 339.453345 -269.740351) (xy 339.499324 -269.762168) (xy 339.541208 -269.791078)
			(xy 339.577912 -269.826333) (xy 339.608485 -269.867019) (xy 339.632136 -269.912082) (xy 339.648252 -269.960356)
			(xy 339.656416 -270.01059) (xy 339.656928 -270.036036) (xy 339.964771 -270.036036) (xy 339.968866 -269.985308)
			(xy 339.981045 -269.935894) (xy 340.000993 -269.889074) (xy 340.028194 -269.84606) (xy 340.061942 -269.807966)
			(xy 340.101364 -269.775779) (xy 340.145438 -269.750333) (xy 340.193024 -269.732286) (xy 340.242888 -269.722106)
			(xy 340.29374 -269.720057) (xy 340.344261 -269.726191) (xy 340.393145 -269.740351) (xy 340.439124 -269.762168)
			(xy 340.481008 -269.791078) (xy 340.517712 -269.826333) (xy 340.548285 -269.867019) (xy 340.571936 -269.912082)
			(xy 340.588052 -269.960356) (xy 340.596216 -270.01059) (xy 340.596728 -270.036036) (xy 340.915256 -270.036036)
			(xy 340.919216 -269.986982) (xy 340.930993 -269.939198) (xy 340.950284 -269.893922) (xy 340.976587 -269.852326)
			(xy 341.009222 -269.815489) (xy 341.047343 -269.784364) (xy 341.089964 -269.759757) (xy 341.13598 -269.742305)
			(xy 341.184199 -269.732461) (xy 341.233374 -269.73048) (xy 341.282229 -269.736412) (xy 341.3295 -269.750104)
			(xy 341.373962 -269.771202) (xy 341.414465 -269.799158) (xy 341.449958 -269.83325) (xy 341.479523 -269.872594)
			(xy 341.502394 -269.916171) (xy 341.517978 -269.962852) (xy 341.525873 -270.011429) (xy 341.526368 -270.036036)
			(xy 341.844879 -270.036036) (xy 341.848974 -269.985308) (xy 341.861153 -269.935894) (xy 341.881101 -269.889074)
			(xy 341.908302 -269.84606) (xy 341.94205 -269.807966) (xy 341.981472 -269.775779) (xy 342.025546 -269.750333)
			(xy 342.073132 -269.732286) (xy 342.122996 -269.722106) (xy 342.173848 -269.720057) (xy 342.224369 -269.726191)
			(xy 342.273253 -269.740351) (xy 342.319232 -269.762168) (xy 342.361116 -269.791078) (xy 342.39782 -269.826333)
			(xy 342.428393 -269.867019) (xy 342.452044 -269.912082) (xy 342.46816 -269.960356) (xy 342.476324 -270.01059)
			(xy 342.476836 -270.036036) (xy 342.795364 -270.036036) (xy 342.799324 -269.986982) (xy 342.811101 -269.939198)
			(xy 342.830392 -269.893922) (xy 342.856695 -269.852326) (xy 342.88933 -269.815489) (xy 342.927451 -269.784364)
			(xy 342.970072 -269.759757) (xy 343.016088 -269.742305) (xy 343.064307 -269.732461) (xy 343.113482 -269.73048)
			(xy 343.162337 -269.736412) (xy 343.209608 -269.750104) (xy 343.25407 -269.771202) (xy 343.294573 -269.799158)
			(xy 343.330066 -269.83325) (xy 343.359631 -269.872594) (xy 343.382502 -269.916171) (xy 343.398086 -269.962852)
			(xy 343.405981 -270.011429) (xy 343.406476 -270.036036) (xy 343.405981 -270.060643) (xy 343.398086 -270.10922)
			(xy 343.382502 -270.155901) (xy 343.359631 -270.199478) (xy 343.330066 -270.238822) (xy 343.294573 -270.272914)
			(xy 343.25407 -270.30087) (xy 343.209608 -270.321968) (xy 343.162337 -270.33566) (xy 343.113482 -270.341592)
			(xy 343.064307 -270.339611) (xy 343.016088 -270.329767) (xy 342.970072 -270.312315) (xy 342.927451 -270.287708)
			(xy 342.88933 -270.256583) (xy 342.856695 -270.219746) (xy 342.830392 -270.17815) (xy 342.811101 -270.132874)
			(xy 342.799324 -270.08509) (xy 342.795364 -270.036036) (xy 342.476836 -270.036036) (xy 342.476324 -270.061482)
			(xy 342.46816 -270.111716) (xy 342.452044 -270.15999) (xy 342.428393 -270.205053) (xy 342.39782 -270.245739)
			(xy 342.361116 -270.280994) (xy 342.319232 -270.309904) (xy 342.273253 -270.331721) (xy 342.224369 -270.345881)
			(xy 342.173848 -270.352015) (xy 342.122996 -270.349966) (xy 342.073132 -270.339786) (xy 342.025546 -270.321739)
			(xy 341.981472 -270.296293) (xy 341.94205 -270.264106) (xy 341.908302 -270.226012) (xy 341.881101 -270.182998)
			(xy 341.861153 -270.136178) (xy 341.848974 -270.086764) (xy 341.844879 -270.036036) (xy 341.526368 -270.036036)
			(xy 341.525873 -270.060643) (xy 341.517978 -270.10922) (xy 341.502394 -270.155901) (xy 341.479523 -270.199478)
			(xy 341.449958 -270.238822) (xy 341.414465 -270.272914) (xy 341.373962 -270.30087) (xy 341.3295 -270.321968)
			(xy 341.282229 -270.33566) (xy 341.233374 -270.341592) (xy 341.184199 -270.339611) (xy 341.13598 -270.329767)
			(xy 341.089964 -270.312315) (xy 341.047343 -270.287708) (xy 341.009222 -270.256583) (xy 340.976587 -270.219746)
			(xy 340.950284 -270.17815) (xy 340.930993 -270.132874) (xy 340.919216 -270.08509) (xy 340.915256 -270.036036)
			(xy 340.596728 -270.036036) (xy 340.596216 -270.061482) (xy 340.588052 -270.111716) (xy 340.571936 -270.15999)
			(xy 340.548285 -270.205053) (xy 340.517712 -270.245739) (xy 340.481008 -270.280994) (xy 340.439124 -270.309904)
			(xy 340.393145 -270.331721) (xy 340.344261 -270.345881) (xy 340.29374 -270.352015) (xy 340.242888 -270.349966)
			(xy 340.193024 -270.339786) (xy 340.145438 -270.321739) (xy 340.101364 -270.296293) (xy 340.061942 -270.264106)
			(xy 340.028194 -270.226012) (xy 340.000993 -270.182998) (xy 339.981045 -270.136178) (xy 339.968866 -270.086764)
			(xy 339.964771 -270.036036) (xy 339.656928 -270.036036) (xy 339.656416 -270.061482) (xy 339.648252 -270.111716)
			(xy 339.632136 -270.15999) (xy 339.608485 -270.205053) (xy 339.577912 -270.245739) (xy 339.541208 -270.280994)
			(xy 339.499324 -270.309904) (xy 339.453345 -270.331721) (xy 339.404461 -270.345881) (xy 339.35394 -270.352015)
			(xy 339.303088 -270.349966) (xy 339.253224 -270.339786) (xy 339.205638 -270.321739) (xy 339.161564 -270.296293)
			(xy 339.122142 -270.264106) (xy 339.088394 -270.226012) (xy 339.061193 -270.182998) (xy 339.041245 -270.136178)
			(xy 339.029066 -270.086764) (xy 339.024971 -270.036036) (xy 338.70646 -270.036036) (xy 338.705965 -270.060643)
			(xy 338.69807 -270.10922) (xy 338.682486 -270.155901) (xy 338.659615 -270.199478) (xy 338.63005 -270.238822)
			(xy 338.594557 -270.272914) (xy 338.554054 -270.30087) (xy 338.509592 -270.321968) (xy 338.462321 -270.33566)
			(xy 338.413466 -270.341592) (xy 338.364291 -270.339611) (xy 338.316072 -270.329767) (xy 338.270056 -270.312315)
			(xy 338.227435 -270.287708) (xy 338.189314 -270.256583) (xy 338.156679 -270.219746) (xy 338.130376 -270.17815)
			(xy 338.111085 -270.132874) (xy 338.099308 -270.08509) (xy 338.095348 -270.036036) (xy 337.766406 -270.036036)
			(xy 337.765911 -270.060643) (xy 337.758016 -270.10922) (xy 337.742432 -270.155901) (xy 337.719561 -270.199478)
			(xy 337.689996 -270.238822) (xy 337.654503 -270.272914) (xy 337.614 -270.30087) (xy 337.569538 -270.321968)
			(xy 337.522267 -270.33566) (xy 337.473412 -270.341592) (xy 337.424237 -270.339611) (xy 337.376018 -270.329767)
			(xy 337.330002 -270.312315) (xy 337.287381 -270.287708) (xy 337.24926 -270.256583) (xy 337.216625 -270.219746)
			(xy 337.190322 -270.17815) (xy 337.171031 -270.132874) (xy 337.159254 -270.08509) (xy 337.155294 -270.036036)
			(xy 336.826352 -270.036036) (xy 336.825857 -270.060643) (xy 336.817962 -270.10922) (xy 336.802378 -270.155901)
			(xy 336.779507 -270.199478) (xy 336.749942 -270.238822) (xy 336.714449 -270.272914) (xy 336.673946 -270.30087)
			(xy 336.629484 -270.321968) (xy 336.582213 -270.33566) (xy 336.533358 -270.341592) (xy 336.484183 -270.339611)
			(xy 336.435964 -270.329767) (xy 336.389948 -270.312315) (xy 336.347327 -270.287708) (xy 336.309206 -270.256583)
			(xy 336.276571 -270.219746) (xy 336.250268 -270.17815) (xy 336.230977 -270.132874) (xy 336.2192 -270.08509)
			(xy 336.21524 -270.036036) (xy 335.886298 -270.036036) (xy 335.885803 -270.060643) (xy 335.877908 -270.10922)
			(xy 335.862324 -270.155901) (xy 335.839453 -270.199478) (xy 335.809888 -270.238822) (xy 335.774395 -270.272914)
			(xy 335.733892 -270.30087) (xy 335.68943 -270.321968) (xy 335.642159 -270.33566) (xy 335.593304 -270.341592)
			(xy 335.544129 -270.339611) (xy 335.49591 -270.329767) (xy 335.449894 -270.312315) (xy 335.407273 -270.287708)
			(xy 335.369152 -270.256583) (xy 335.336517 -270.219746) (xy 335.310214 -270.17815) (xy 335.290923 -270.132874)
			(xy 335.279146 -270.08509) (xy 335.275186 -270.036036) (xy 334.946498 -270.036036) (xy 334.946003 -270.060643)
			(xy 334.938108 -270.10922) (xy 334.922524 -270.155901) (xy 334.899653 -270.199478) (xy 334.870088 -270.238822)
			(xy 334.834595 -270.272914) (xy 334.794092 -270.30087) (xy 334.74963 -270.321968) (xy 334.702359 -270.33566)
			(xy 334.653504 -270.341592) (xy 334.604329 -270.339611) (xy 334.55611 -270.329767) (xy 334.510094 -270.312315)
			(xy 334.467473 -270.287708) (xy 334.429352 -270.256583) (xy 334.396717 -270.219746) (xy 334.370414 -270.17815)
			(xy 334.351123 -270.132874) (xy 334.339346 -270.08509) (xy 334.335386 -270.036036) (xy 334.006444 -270.036036)
			(xy 334.005949 -270.060643) (xy 333.998054 -270.10922) (xy 333.98247 -270.155901) (xy 333.959599 -270.199478)
			(xy 333.930034 -270.238822) (xy 333.894541 -270.272914) (xy 333.854038 -270.30087) (xy 333.809576 -270.321968)
			(xy 333.762305 -270.33566) (xy 333.71345 -270.341592) (xy 333.664275 -270.339611) (xy 333.616056 -270.329767)
			(xy 333.57004 -270.312315) (xy 333.527419 -270.287708) (xy 333.489298 -270.256583) (xy 333.456663 -270.219746)
			(xy 333.43036 -270.17815) (xy 333.411069 -270.132874) (xy 333.399292 -270.08509) (xy 333.395332 -270.036036)
			(xy 333.06639 -270.036036) (xy 333.065895 -270.060643) (xy 333.058 -270.10922) (xy 333.042416 -270.155901)
			(xy 333.019545 -270.199478) (xy 332.98998 -270.238822) (xy 332.954487 -270.272914) (xy 332.913984 -270.30087)
			(xy 332.869522 -270.321968) (xy 332.822251 -270.33566) (xy 332.773396 -270.341592) (xy 332.724221 -270.339611)
			(xy 332.676002 -270.329767) (xy 332.629986 -270.312315) (xy 332.587365 -270.287708) (xy 332.549244 -270.256583)
			(xy 332.516609 -270.219746) (xy 332.490306 -270.17815) (xy 332.471015 -270.132874) (xy 332.459238 -270.08509)
			(xy 332.455278 -270.036036) (xy 332.126792 -270.036036) (xy 332.122625 -270.086329) (xy 332.110228 -270.135286)
			(xy 332.089943 -270.181535) (xy 332.062322 -270.223814) (xy 332.02812 -270.260971) (xy 331.988269 -270.291992)
			(xy 331.943855 -270.316031) (xy 331.896091 -270.332432) (xy 331.846279 -270.340748) (xy 331.821028 -270.341344)
			(xy 331.808265 -270.341204) (xy 331.782832 -270.339039) (xy 331.770228 -270.337026) (xy 331.74354 -270.331946)
			(xy 331.692408 -270.31361) (xy 331.64533 -270.28651) (xy 331.624178 -270.269462) (xy 331.61859 -270.26489)
			(xy 331.605636 -270.259048) (xy 331.59827 -270.258032) (xy 331.591061 -270.257351) (xy 331.576754 -270.259548)
			(xy 331.570076 -270.26235) (xy 331.487018 -270.300704) (xy 331.479145 -270.305143) (xy 331.466912 -270.31843)
			(xy 331.460023 -270.335127) (xy 331.459332 -270.344138) (xy 331.459332 -270.52778) (xy 331.459573 -270.534731)
			(xy 331.463312 -270.548121) (xy 331.466698 -270.554196) (xy 331.47 -270.559276) (xy 331.480414 -270.568928)
			(xy 331.487526 -270.572484) (xy 331.508972 -270.583711) (xy 331.548326 -270.611895) (xy 331.582747 -270.645927)
			(xy 331.611376 -270.684958) (xy 331.633497 -270.728013) (xy 331.648558 -270.774015) (xy 331.656182 -270.821816)
			(xy 331.65618 -270.846042) (xy 331.985378 -270.846042) (xy 331.989338 -270.796988) (xy 332.001115 -270.749204)
			(xy 332.020406 -270.703928) (xy 332.046709 -270.662332) (xy 332.079344 -270.625495) (xy 332.117465 -270.59437)
			(xy 332.160086 -270.569763) (xy 332.206102 -270.552311) (xy 332.254321 -270.542467) (xy 332.303496 -270.540486)
			(xy 332.352351 -270.546418) (xy 332.399622 -270.56011) (xy 332.444084 -270.581208) (xy 332.484587 -270.609164)
			(xy 332.52008 -270.643256) (xy 332.549645 -270.6826) (xy 332.572516 -270.726177) (xy 332.5881 -270.772858)
			(xy 332.595995 -270.821435) (xy 332.59649 -270.846042) (xy 332.925178 -270.846042) (xy 332.929138 -270.796988)
			(xy 332.940915 -270.749204) (xy 332.960206 -270.703928) (xy 332.986509 -270.662332) (xy 333.019144 -270.625495)
			(xy 333.057265 -270.59437) (xy 333.099886 -270.569763) (xy 333.145902 -270.552311) (xy 333.194121 -270.542467)
			(xy 333.243296 -270.540486) (xy 333.292151 -270.546418) (xy 333.339422 -270.56011) (xy 333.383884 -270.581208)
			(xy 333.424387 -270.609164) (xy 333.45988 -270.643256) (xy 333.489445 -270.6826) (xy 333.512316 -270.726177)
			(xy 333.5279 -270.772858) (xy 333.535795 -270.821435) (xy 333.53629 -270.846042) (xy 333.865232 -270.846042)
			(xy 333.869192 -270.796988) (xy 333.880969 -270.749204) (xy 333.90026 -270.703928) (xy 333.926563 -270.662332)
			(xy 333.959198 -270.625495) (xy 333.997319 -270.59437) (xy 334.03994 -270.569763) (xy 334.085956 -270.552311)
			(xy 334.134175 -270.542467) (xy 334.18335 -270.540486) (xy 334.232205 -270.546418) (xy 334.279476 -270.56011)
			(xy 334.323938 -270.581208) (xy 334.364441 -270.609164) (xy 334.399934 -270.643256) (xy 334.429499 -270.6826)
			(xy 334.45237 -270.726177) (xy 334.467954 -270.772858) (xy 334.475849 -270.821435) (xy 334.476344 -270.846042)
			(xy 335.74534 -270.846042) (xy 335.7493 -270.796988) (xy 335.761077 -270.749204) (xy 335.780368 -270.703928)
			(xy 335.806671 -270.662332) (xy 335.839306 -270.625495) (xy 335.877427 -270.59437) (xy 335.920048 -270.569763)
			(xy 335.966064 -270.552311) (xy 336.014283 -270.542467) (xy 336.063458 -270.540486) (xy 336.112313 -270.546418)
			(xy 336.159584 -270.56011) (xy 336.204046 -270.581208) (xy 336.244549 -270.609164) (xy 336.280042 -270.643256)
			(xy 336.309607 -270.6826) (xy 336.332478 -270.726177) (xy 336.348062 -270.772858) (xy 336.355957 -270.821435)
			(xy 336.356452 -270.846042) (xy 336.685394 -270.846042) (xy 336.689354 -270.796988) (xy 336.701131 -270.749204)
			(xy 336.720422 -270.703928) (xy 336.746725 -270.662332) (xy 336.77936 -270.625495) (xy 336.817481 -270.59437)
			(xy 336.860102 -270.569763) (xy 336.906118 -270.552311) (xy 336.954337 -270.542467) (xy 337.003512 -270.540486)
			(xy 337.052367 -270.546418) (xy 337.099638 -270.56011) (xy 337.1441 -270.581208) (xy 337.184603 -270.609164)
			(xy 337.220096 -270.643256) (xy 337.249661 -270.6826) (xy 337.272532 -270.726177) (xy 337.288116 -270.772858)
			(xy 337.296011 -270.821435) (xy 337.296506 -270.846042) (xy 337.625194 -270.846042) (xy 337.629154 -270.796988)
			(xy 337.640931 -270.749204) (xy 337.660222 -270.703928) (xy 337.686525 -270.662332) (xy 337.71916 -270.625495)
			(xy 337.757281 -270.59437) (xy 337.799902 -270.569763) (xy 337.845918 -270.552311) (xy 337.894137 -270.542467)
			(xy 337.943312 -270.540486) (xy 337.992167 -270.546418) (xy 338.039438 -270.56011) (xy 338.0839 -270.581208)
			(xy 338.124403 -270.609164) (xy 338.159896 -270.643256) (xy 338.189461 -270.6826) (xy 338.212332 -270.726177)
			(xy 338.227916 -270.772858) (xy 338.235811 -270.821435) (xy 338.236306 -270.846042) (xy 338.554817 -270.846042)
			(xy 338.558912 -270.795314) (xy 338.571091 -270.7459) (xy 338.591039 -270.69908) (xy 338.61824 -270.656066)
			(xy 338.651988 -270.617972) (xy 338.69141 -270.585785) (xy 338.735484 -270.560339) (xy 338.78307 -270.542292)
			(xy 338.832934 -270.532112) (xy 338.883786 -270.530063) (xy 338.934307 -270.536197) (xy 338.983191 -270.550357)
			(xy 339.02917 -270.572174) (xy 339.071054 -270.601084) (xy 339.107758 -270.636339) (xy 339.138331 -270.677025)
			(xy 339.161982 -270.722088) (xy 339.178098 -270.770362) (xy 339.186262 -270.820596) (xy 339.186774 -270.846042)
			(xy 339.505302 -270.846042) (xy 339.509262 -270.796988) (xy 339.521039 -270.749204) (xy 339.54033 -270.703928)
			(xy 339.566633 -270.662332) (xy 339.599268 -270.625495) (xy 339.637389 -270.59437) (xy 339.68001 -270.569763)
			(xy 339.726026 -270.552311) (xy 339.774245 -270.542467) (xy 339.82342 -270.540486) (xy 339.872275 -270.546418)
			(xy 339.919546 -270.56011) (xy 339.964008 -270.581208) (xy 340.004511 -270.609164) (xy 340.040004 -270.643256)
			(xy 340.069569 -270.6826) (xy 340.09244 -270.726177) (xy 340.108024 -270.772858) (xy 340.115919 -270.821435)
			(xy 340.116414 -270.846042) (xy 340.434925 -270.846042) (xy 340.43902 -270.795314) (xy 340.451199 -270.7459)
			(xy 340.471147 -270.69908) (xy 340.498348 -270.656066) (xy 340.532096 -270.617972) (xy 340.571518 -270.585785)
			(xy 340.615592 -270.560339) (xy 340.663178 -270.542292) (xy 340.713042 -270.532112) (xy 340.763894 -270.530063)
			(xy 340.814415 -270.536197) (xy 340.863299 -270.550357) (xy 340.909278 -270.572174) (xy 340.951162 -270.601084)
			(xy 340.987866 -270.636339) (xy 341.018439 -270.677025) (xy 341.04209 -270.722088) (xy 341.058206 -270.770362)
			(xy 341.06637 -270.820596) (xy 341.066882 -270.846042) (xy 342.314779 -270.846042) (xy 342.318874 -270.795314)
			(xy 342.331053 -270.7459) (xy 342.351001 -270.69908) (xy 342.378202 -270.656066) (xy 342.41195 -270.617972)
			(xy 342.451372 -270.585785) (xy 342.495446 -270.560339) (xy 342.543032 -270.542292) (xy 342.592896 -270.532112)
			(xy 342.643748 -270.530063) (xy 342.694269 -270.536197) (xy 342.743153 -270.550357) (xy 342.789132 -270.572174)
			(xy 342.831016 -270.601084) (xy 342.86772 -270.636339) (xy 342.898293 -270.677025) (xy 342.921944 -270.722088)
			(xy 342.93806 -270.770362) (xy 342.946224 -270.820596) (xy 342.946736 -270.846042) (xy 342.946224 -270.871488)
			(xy 342.93806 -270.921722) (xy 342.921944 -270.969996) (xy 342.898293 -271.015059) (xy 342.86772 -271.055745)
			(xy 342.831016 -271.091) (xy 342.789132 -271.11991) (xy 342.743153 -271.141727) (xy 342.694269 -271.155887)
			(xy 342.643748 -271.162021) (xy 342.592896 -271.159972) (xy 342.543032 -271.149792) (xy 342.495446 -271.131745)
			(xy 342.451372 -271.106299) (xy 342.41195 -271.074112) (xy 342.378202 -271.036018) (xy 342.351001 -270.993004)
			(xy 342.331053 -270.946184) (xy 342.318874 -270.89677) (xy 342.314779 -270.846042) (xy 341.066882 -270.846042)
			(xy 341.06637 -270.871488) (xy 341.058206 -270.921722) (xy 341.04209 -270.969996) (xy 341.018439 -271.015059)
			(xy 340.987866 -271.055745) (xy 340.951162 -271.091) (xy 340.909278 -271.11991) (xy 340.863299 -271.141727)
			(xy 340.814415 -271.155887) (xy 340.763894 -271.162021) (xy 340.713042 -271.159972) (xy 340.663178 -271.149792)
			(xy 340.615592 -271.131745) (xy 340.571518 -271.106299) (xy 340.532096 -271.074112) (xy 340.498348 -271.036018)
			(xy 340.471147 -270.993004) (xy 340.451199 -270.946184) (xy 340.43902 -270.89677) (xy 340.434925 -270.846042)
			(xy 340.116414 -270.846042) (xy 340.115919 -270.870649) (xy 340.108024 -270.919226) (xy 340.09244 -270.965907)
			(xy 340.069569 -271.009484) (xy 340.040004 -271.048828) (xy 340.004511 -271.08292) (xy 339.964008 -271.110876)
			(xy 339.919546 -271.131974) (xy 339.872275 -271.145666) (xy 339.82342 -271.151598) (xy 339.774245 -271.149617)
			(xy 339.726026 -271.139773) (xy 339.68001 -271.122321) (xy 339.637389 -271.097714) (xy 339.599268 -271.066589)
			(xy 339.566633 -271.029752) (xy 339.54033 -270.988156) (xy 339.521039 -270.94288) (xy 339.509262 -270.895096)
			(xy 339.505302 -270.846042) (xy 339.186774 -270.846042) (xy 339.186262 -270.871488) (xy 339.178098 -270.921722)
			(xy 339.161982 -270.969996) (xy 339.138331 -271.015059) (xy 339.107758 -271.055745) (xy 339.071054 -271.091)
			(xy 339.02917 -271.11991) (xy 338.983191 -271.141727) (xy 338.934307 -271.155887) (xy 338.883786 -271.162021)
			(xy 338.832934 -271.159972) (xy 338.78307 -271.149792) (xy 338.735484 -271.131745) (xy 338.69141 -271.106299)
			(xy 338.651988 -271.074112) (xy 338.61824 -271.036018) (xy 338.591039 -270.993004) (xy 338.571091 -270.946184)
			(xy 338.558912 -270.89677) (xy 338.554817 -270.846042) (xy 338.236306 -270.846042) (xy 338.235811 -270.870649)
			(xy 338.227916 -270.919226) (xy 338.212332 -270.965907) (xy 338.189461 -271.009484) (xy 338.159896 -271.048828)
			(xy 338.124403 -271.08292) (xy 338.0839 -271.110876) (xy 338.039438 -271.131974) (xy 337.992167 -271.145666)
			(xy 337.943312 -271.151598) (xy 337.894137 -271.149617) (xy 337.845918 -271.139773) (xy 337.799902 -271.122321)
			(xy 337.757281 -271.097714) (xy 337.71916 -271.066589) (xy 337.686525 -271.029752) (xy 337.660222 -270.988156)
			(xy 337.640931 -270.94288) (xy 337.629154 -270.895096) (xy 337.625194 -270.846042) (xy 337.296506 -270.846042)
			(xy 337.296011 -270.870649) (xy 337.288116 -270.919226) (xy 337.272532 -270.965907) (xy 337.249661 -271.009484)
			(xy 337.220096 -271.048828) (xy 337.184603 -271.08292) (xy 337.1441 -271.110876) (xy 337.099638 -271.131974)
			(xy 337.052367 -271.145666) (xy 337.003512 -271.151598) (xy 336.954337 -271.149617) (xy 336.906118 -271.139773)
			(xy 336.860102 -271.122321) (xy 336.817481 -271.097714) (xy 336.77936 -271.066589) (xy 336.746725 -271.029752)
			(xy 336.720422 -270.988156) (xy 336.701131 -270.94288) (xy 336.689354 -270.895096) (xy 336.685394 -270.846042)
			(xy 336.356452 -270.846042) (xy 336.355957 -270.870649) (xy 336.348062 -270.919226) (xy 336.332478 -270.965907)
			(xy 336.309607 -271.009484) (xy 336.280042 -271.048828) (xy 336.244549 -271.08292) (xy 336.204046 -271.110876)
			(xy 336.159584 -271.131974) (xy 336.112313 -271.145666) (xy 336.063458 -271.151598) (xy 336.014283 -271.149617)
			(xy 335.966064 -271.139773) (xy 335.920048 -271.122321) (xy 335.877427 -271.097714) (xy 335.839306 -271.066589)
			(xy 335.806671 -271.029752) (xy 335.780368 -270.988156) (xy 335.761077 -270.94288) (xy 335.7493 -270.895096)
			(xy 335.74534 -270.846042) (xy 334.476344 -270.846042) (xy 334.475849 -270.870649) (xy 334.467954 -270.919226)
			(xy 334.45237 -270.965907) (xy 334.429499 -271.009484) (xy 334.399934 -271.048828) (xy 334.364441 -271.08292)
			(xy 334.323938 -271.110876) (xy 334.279476 -271.131974) (xy 334.232205 -271.145666) (xy 334.18335 -271.151598)
			(xy 334.134175 -271.149617) (xy 334.085956 -271.139773) (xy 334.03994 -271.122321) (xy 333.997319 -271.097714)
			(xy 333.959198 -271.066589) (xy 333.926563 -271.029752) (xy 333.90026 -270.988156) (xy 333.880969 -270.94288)
			(xy 333.869192 -270.895096) (xy 333.865232 -270.846042) (xy 333.53629 -270.846042) (xy 333.535795 -270.870649)
			(xy 333.5279 -270.919226) (xy 333.512316 -270.965907) (xy 333.489445 -271.009484) (xy 333.45988 -271.048828)
			(xy 333.424387 -271.08292) (xy 333.383884 -271.110876) (xy 333.339422 -271.131974) (xy 333.292151 -271.145666)
			(xy 333.243296 -271.151598) (xy 333.194121 -271.149617) (xy 333.145902 -271.139773) (xy 333.099886 -271.122321)
			(xy 333.057265 -271.097714) (xy 333.019144 -271.066589) (xy 332.986509 -271.029752) (xy 332.960206 -270.988156)
			(xy 332.940915 -270.94288) (xy 332.929138 -270.895096) (xy 332.925178 -270.846042) (xy 332.59649 -270.846042)
			(xy 332.595995 -270.870649) (xy 332.5881 -270.919226) (xy 332.572516 -270.965907) (xy 332.549645 -271.009484)
			(xy 332.52008 -271.048828) (xy 332.484587 -271.08292) (xy 332.444084 -271.110876) (xy 332.399622 -271.131974)
			(xy 332.352351 -271.145666) (xy 332.303496 -271.151598) (xy 332.254321 -271.149617) (xy 332.206102 -271.139773)
			(xy 332.160086 -271.122321) (xy 332.117465 -271.097714) (xy 332.079344 -271.066589) (xy 332.046709 -271.029752)
			(xy 332.020406 -270.988156) (xy 332.001115 -270.94288) (xy 331.989338 -270.895096) (xy 331.985378 -270.846042)
			(xy 331.65618 -270.846042) (xy 331.656179 -270.870221) (xy 331.648549 -270.918021) (xy 331.633483 -270.964022)
			(xy 331.611356 -271.007073) (xy 331.582723 -271.046101) (xy 331.548297 -271.080129) (xy 331.50894 -271.108308)
			(xy 331.487526 -271.1196) (xy 331.486764 -271.119854) (xy 331.480504 -271.123254) (xy 331.470047 -271.132916)
			(xy 331.46619 -271.138904) (xy 331.463142 -271.143984) (xy 331.459332 -271.157192) (xy 331.459332 -271.346168)
			(xy 331.459809 -271.355538) (xy 331.46666 -271.372985) (xy 331.47934 -271.38679) (xy 331.487526 -271.39138)
			(xy 331.518006 -271.405604) (xy 331.566266 -271.427956) (xy 331.56955 -271.429453) (xy 331.576432 -271.431626)
			(xy 331.579982 -271.432274) (xy 331.584357 -271.432826) (xy 331.593171 -271.432568) (xy 331.597508 -271.431766)
			(xy 331.605382 -271.429734) (xy 331.62367 -271.422876) (xy 331.63002 -271.417796) (xy 331.650501 -271.402085)
			(xy 331.695638 -271.377051) (xy 331.744339 -271.359958) (xy 331.795221 -271.35129) (xy 331.821028 -271.35074)
			(xy 331.846278 -271.351264) (xy 331.896088 -271.35958) (xy 331.943851 -271.37598) (xy 331.988262 -271.400018)
			(xy 332.028112 -271.431038) (xy 332.062313 -271.468194) (xy 332.089932 -271.510471) (xy 332.110217 -271.556718)
			(xy 332.122613 -271.605673) (xy 332.126783 -271.656) (xy 332.126779 -271.656048) (xy 332.455278 -271.656048)
			(xy 332.459238 -271.606994) (xy 332.471015 -271.55921) (xy 332.490306 -271.513934) (xy 332.516609 -271.472338)
			(xy 332.549244 -271.435501) (xy 332.587365 -271.404376) (xy 332.629986 -271.379769) (xy 332.676002 -271.362317)
			(xy 332.724221 -271.352473) (xy 332.773396 -271.350492) (xy 332.822251 -271.356424) (xy 332.869522 -271.370116)
			(xy 332.913984 -271.391214) (xy 332.954487 -271.41917) (xy 332.98998 -271.453262) (xy 333.019545 -271.492606)
			(xy 333.042416 -271.536183) (xy 333.058 -271.582864) (xy 333.065895 -271.631441) (xy 333.06639 -271.656048)
			(xy 333.395332 -271.656048) (xy 333.399292 -271.606994) (xy 333.411069 -271.55921) (xy 333.43036 -271.513934)
			(xy 333.456663 -271.472338) (xy 333.489298 -271.435501) (xy 333.527419 -271.404376) (xy 333.57004 -271.379769)
			(xy 333.616056 -271.362317) (xy 333.664275 -271.352473) (xy 333.71345 -271.350492) (xy 333.762305 -271.356424)
			(xy 333.809576 -271.370116) (xy 333.854038 -271.391214) (xy 333.894541 -271.41917) (xy 333.930034 -271.453262)
			(xy 333.959599 -271.492606) (xy 333.98247 -271.536183) (xy 333.998054 -271.582864) (xy 334.005949 -271.631441)
			(xy 334.006444 -271.656048) (xy 334.335386 -271.656048) (xy 334.339346 -271.606994) (xy 334.351123 -271.55921)
			(xy 334.370414 -271.513934) (xy 334.396717 -271.472338) (xy 334.429352 -271.435501) (xy 334.467473 -271.404376)
			(xy 334.510094 -271.379769) (xy 334.55611 -271.362317) (xy 334.604329 -271.352473) (xy 334.653504 -271.350492)
			(xy 334.702359 -271.356424) (xy 334.74963 -271.370116) (xy 334.794092 -271.391214) (xy 334.834595 -271.41917)
			(xy 334.870088 -271.453262) (xy 334.899653 -271.492606) (xy 334.922524 -271.536183) (xy 334.938108 -271.582864)
			(xy 334.946003 -271.631441) (xy 334.946498 -271.656048) (xy 335.275186 -271.656048) (xy 335.279146 -271.606994)
			(xy 335.290923 -271.55921) (xy 335.310214 -271.513934) (xy 335.336517 -271.472338) (xy 335.369152 -271.435501)
			(xy 335.407273 -271.404376) (xy 335.449894 -271.379769) (xy 335.49591 -271.362317) (xy 335.544129 -271.352473)
			(xy 335.593304 -271.350492) (xy 335.642159 -271.356424) (xy 335.68943 -271.370116) (xy 335.733892 -271.391214)
			(xy 335.774395 -271.41917) (xy 335.809888 -271.453262) (xy 335.839453 -271.492606) (xy 335.862324 -271.536183)
			(xy 335.877908 -271.582864) (xy 335.885803 -271.631441) (xy 335.886298 -271.656048) (xy 336.21524 -271.656048)
			(xy 336.2192 -271.606994) (xy 336.230977 -271.55921) (xy 336.250268 -271.513934) (xy 336.276571 -271.472338)
			(xy 336.309206 -271.435501) (xy 336.347327 -271.404376) (xy 336.389948 -271.379769) (xy 336.435964 -271.362317)
			(xy 336.484183 -271.352473) (xy 336.533358 -271.350492) (xy 336.582213 -271.356424) (xy 336.629484 -271.370116)
			(xy 336.673946 -271.391214) (xy 336.714449 -271.41917) (xy 336.749942 -271.453262) (xy 336.779507 -271.492606)
			(xy 336.802378 -271.536183) (xy 336.817962 -271.582864) (xy 336.825857 -271.631441) (xy 336.826352 -271.656048)
			(xy 337.155294 -271.656048) (xy 337.159254 -271.606994) (xy 337.171031 -271.55921) (xy 337.190322 -271.513934)
			(xy 337.216625 -271.472338) (xy 337.24926 -271.435501) (xy 337.287381 -271.404376) (xy 337.330002 -271.379769)
			(xy 337.376018 -271.362317) (xy 337.424237 -271.352473) (xy 337.473412 -271.350492) (xy 337.522267 -271.356424)
			(xy 337.569538 -271.370116) (xy 337.614 -271.391214) (xy 337.654503 -271.41917) (xy 337.689996 -271.453262)
			(xy 337.719561 -271.492606) (xy 337.742432 -271.536183) (xy 337.758016 -271.582864) (xy 337.765911 -271.631441)
			(xy 337.766406 -271.656048) (xy 338.095348 -271.656048) (xy 338.099308 -271.606994) (xy 338.111085 -271.55921)
			(xy 338.130376 -271.513934) (xy 338.156679 -271.472338) (xy 338.189314 -271.435501) (xy 338.227435 -271.404376)
			(xy 338.270056 -271.379769) (xy 338.316072 -271.362317) (xy 338.364291 -271.352473) (xy 338.413466 -271.350492)
			(xy 338.462321 -271.356424) (xy 338.509592 -271.370116) (xy 338.554054 -271.391214) (xy 338.594557 -271.41917)
			(xy 338.63005 -271.453262) (xy 338.659615 -271.492606) (xy 338.682486 -271.536183) (xy 338.69807 -271.582864)
			(xy 338.705965 -271.631441) (xy 338.70646 -271.656048) (xy 339.024971 -271.656048) (xy 339.029066 -271.60532)
			(xy 339.041245 -271.555906) (xy 339.061193 -271.509086) (xy 339.088394 -271.466072) (xy 339.122142 -271.427978)
			(xy 339.161564 -271.395791) (xy 339.205638 -271.370345) (xy 339.253224 -271.352298) (xy 339.303088 -271.342118)
			(xy 339.35394 -271.340069) (xy 339.404461 -271.346203) (xy 339.453345 -271.360363) (xy 339.499324 -271.38218)
			(xy 339.541208 -271.41109) (xy 339.577912 -271.446345) (xy 339.608485 -271.487031) (xy 339.632136 -271.532094)
			(xy 339.648252 -271.580368) (xy 339.656416 -271.630602) (xy 339.656928 -271.656048) (xy 339.964771 -271.656048)
			(xy 339.968866 -271.60532) (xy 339.981045 -271.555906) (xy 340.000993 -271.509086) (xy 340.028194 -271.466072)
			(xy 340.061942 -271.427978) (xy 340.101364 -271.395791) (xy 340.145438 -271.370345) (xy 340.193024 -271.352298)
			(xy 340.242888 -271.342118) (xy 340.29374 -271.340069) (xy 340.344261 -271.346203) (xy 340.393145 -271.360363)
			(xy 340.439124 -271.38218) (xy 340.481008 -271.41109) (xy 340.517712 -271.446345) (xy 340.548285 -271.487031)
			(xy 340.571936 -271.532094) (xy 340.588052 -271.580368) (xy 340.596216 -271.630602) (xy 340.596728 -271.656048)
			(xy 340.915256 -271.656048) (xy 340.919216 -271.606994) (xy 340.930993 -271.55921) (xy 340.950284 -271.513934)
			(xy 340.976587 -271.472338) (xy 341.009222 -271.435501) (xy 341.047343 -271.404376) (xy 341.089964 -271.379769)
			(xy 341.13598 -271.362317) (xy 341.184199 -271.352473) (xy 341.233374 -271.350492) (xy 341.282229 -271.356424)
			(xy 341.3295 -271.370116) (xy 341.373962 -271.391214) (xy 341.414465 -271.41917) (xy 341.449958 -271.453262)
			(xy 341.479523 -271.492606) (xy 341.502394 -271.536183) (xy 341.517978 -271.582864) (xy 341.525873 -271.631441)
			(xy 341.526368 -271.656048) (xy 341.844879 -271.656048) (xy 341.848974 -271.60532) (xy 341.861153 -271.555906)
			(xy 341.881101 -271.509086) (xy 341.908302 -271.466072) (xy 341.94205 -271.427978) (xy 341.981472 -271.395791)
			(xy 342.025546 -271.370345) (xy 342.073132 -271.352298) (xy 342.122996 -271.342118) (xy 342.173848 -271.340069)
			(xy 342.224369 -271.346203) (xy 342.273253 -271.360363) (xy 342.319232 -271.38218) (xy 342.361116 -271.41109)
			(xy 342.39782 -271.446345) (xy 342.428393 -271.487031) (xy 342.452044 -271.532094) (xy 342.46816 -271.580368)
			(xy 342.476324 -271.630602) (xy 342.476836 -271.656048) (xy 342.476324 -271.681494) (xy 342.46816 -271.731728)
			(xy 342.452044 -271.780002) (xy 342.428393 -271.825065) (xy 342.39782 -271.865751) (xy 342.361116 -271.901006)
			(xy 342.319232 -271.929916) (xy 342.273253 -271.951733) (xy 342.224369 -271.965893) (xy 342.173848 -271.972027)
			(xy 342.122996 -271.969978) (xy 342.073132 -271.959798) (xy 342.025546 -271.941751) (xy 341.981472 -271.916305)
			(xy 341.94205 -271.884118) (xy 341.908302 -271.846024) (xy 341.881101 -271.80301) (xy 341.861153 -271.75619)
			(xy 341.848974 -271.706776) (xy 341.844879 -271.656048) (xy 341.526368 -271.656048) (xy 341.525873 -271.680655)
			(xy 341.517978 -271.729232) (xy 341.502394 -271.775913) (xy 341.479523 -271.81949) (xy 341.449958 -271.858834)
			(xy 341.414465 -271.892926) (xy 341.373962 -271.920882) (xy 341.3295 -271.94198) (xy 341.282229 -271.955672)
			(xy 341.233374 -271.961604) (xy 341.184199 -271.959623) (xy 341.13598 -271.949779) (xy 341.089964 -271.932327)
			(xy 341.047343 -271.90772) (xy 341.009222 -271.876595) (xy 340.976587 -271.839758) (xy 340.950284 -271.798162)
			(xy 340.930993 -271.752886) (xy 340.919216 -271.705102) (xy 340.915256 -271.656048) (xy 340.596728 -271.656048)
			(xy 340.596216 -271.681494) (xy 340.588052 -271.731728) (xy 340.571936 -271.780002) (xy 340.548285 -271.825065)
			(xy 340.517712 -271.865751) (xy 340.481008 -271.901006) (xy 340.439124 -271.929916) (xy 340.393145 -271.951733)
			(xy 340.344261 -271.965893) (xy 340.29374 -271.972027) (xy 340.242888 -271.969978) (xy 340.193024 -271.959798)
			(xy 340.145438 -271.941751) (xy 340.101364 -271.916305) (xy 340.061942 -271.884118) (xy 340.028194 -271.846024)
			(xy 340.000993 -271.80301) (xy 339.981045 -271.75619) (xy 339.968866 -271.706776) (xy 339.964771 -271.656048)
			(xy 339.656928 -271.656048) (xy 339.656416 -271.681494) (xy 339.648252 -271.731728) (xy 339.632136 -271.780002)
			(xy 339.608485 -271.825065) (xy 339.577912 -271.865751) (xy 339.541208 -271.901006) (xy 339.499324 -271.929916)
			(xy 339.453345 -271.951733) (xy 339.404461 -271.965893) (xy 339.35394 -271.972027) (xy 339.303088 -271.969978)
			(xy 339.253224 -271.959798) (xy 339.205638 -271.941751) (xy 339.161564 -271.916305) (xy 339.122142 -271.884118)
			(xy 339.088394 -271.846024) (xy 339.061193 -271.80301) (xy 339.041245 -271.75619) (xy 339.029066 -271.706776)
			(xy 339.024971 -271.656048) (xy 338.70646 -271.656048) (xy 338.705965 -271.680655) (xy 338.69807 -271.729232)
			(xy 338.682486 -271.775913) (xy 338.659615 -271.81949) (xy 338.63005 -271.858834) (xy 338.594557 -271.892926)
			(xy 338.554054 -271.920882) (xy 338.509592 -271.94198) (xy 338.462321 -271.955672) (xy 338.413466 -271.961604)
			(xy 338.364291 -271.959623) (xy 338.316072 -271.949779) (xy 338.270056 -271.932327) (xy 338.227435 -271.90772)
			(xy 338.189314 -271.876595) (xy 338.156679 -271.839758) (xy 338.130376 -271.798162) (xy 338.111085 -271.752886)
			(xy 338.099308 -271.705102) (xy 338.095348 -271.656048) (xy 337.766406 -271.656048) (xy 337.765911 -271.680655)
			(xy 337.758016 -271.729232) (xy 337.742432 -271.775913) (xy 337.719561 -271.81949) (xy 337.689996 -271.858834)
			(xy 337.654503 -271.892926) (xy 337.614 -271.920882) (xy 337.569538 -271.94198) (xy 337.522267 -271.955672)
			(xy 337.473412 -271.961604) (xy 337.424237 -271.959623) (xy 337.376018 -271.949779) (xy 337.330002 -271.932327)
			(xy 337.287381 -271.90772) (xy 337.24926 -271.876595) (xy 337.216625 -271.839758) (xy 337.190322 -271.798162)
			(xy 337.171031 -271.752886) (xy 337.159254 -271.705102) (xy 337.155294 -271.656048) (xy 336.826352 -271.656048)
			(xy 336.825857 -271.680655) (xy 336.817962 -271.729232) (xy 336.802378 -271.775913) (xy 336.779507 -271.81949)
			(xy 336.749942 -271.858834) (xy 336.714449 -271.892926) (xy 336.673946 -271.920882) (xy 336.629484 -271.94198)
			(xy 336.582213 -271.955672) (xy 336.533358 -271.961604) (xy 336.484183 -271.959623) (xy 336.435964 -271.949779)
			(xy 336.389948 -271.932327) (xy 336.347327 -271.90772) (xy 336.309206 -271.876595) (xy 336.276571 -271.839758)
			(xy 336.250268 -271.798162) (xy 336.230977 -271.752886) (xy 336.2192 -271.705102) (xy 336.21524 -271.656048)
			(xy 335.886298 -271.656048) (xy 335.885803 -271.680655) (xy 335.877908 -271.729232) (xy 335.862324 -271.775913)
			(xy 335.839453 -271.81949) (xy 335.809888 -271.858834) (xy 335.774395 -271.892926) (xy 335.733892 -271.920882)
			(xy 335.68943 -271.94198) (xy 335.642159 -271.955672) (xy 335.593304 -271.961604) (xy 335.544129 -271.959623)
			(xy 335.49591 -271.949779) (xy 335.449894 -271.932327) (xy 335.407273 -271.90772) (xy 335.369152 -271.876595)
			(xy 335.336517 -271.839758) (xy 335.310214 -271.798162) (xy 335.290923 -271.752886) (xy 335.279146 -271.705102)
			(xy 335.275186 -271.656048) (xy 334.946498 -271.656048) (xy 334.946003 -271.680655) (xy 334.938108 -271.729232)
			(xy 334.922524 -271.775913) (xy 334.899653 -271.81949) (xy 334.870088 -271.858834) (xy 334.834595 -271.892926)
			(xy 334.794092 -271.920882) (xy 334.74963 -271.94198) (xy 334.702359 -271.955672) (xy 334.653504 -271.961604)
			(xy 334.604329 -271.959623) (xy 334.55611 -271.949779) (xy 334.510094 -271.932327) (xy 334.467473 -271.90772)
			(xy 334.429352 -271.876595) (xy 334.396717 -271.839758) (xy 334.370414 -271.798162) (xy 334.351123 -271.752886)
			(xy 334.339346 -271.705102) (xy 334.335386 -271.656048) (xy 334.006444 -271.656048) (xy 334.005949 -271.680655)
			(xy 333.998054 -271.729232) (xy 333.98247 -271.775913) (xy 333.959599 -271.81949) (xy 333.930034 -271.858834)
			(xy 333.894541 -271.892926) (xy 333.854038 -271.920882) (xy 333.809576 -271.94198) (xy 333.762305 -271.955672)
			(xy 333.71345 -271.961604) (xy 333.664275 -271.959623) (xy 333.616056 -271.949779) (xy 333.57004 -271.932327)
			(xy 333.527419 -271.90772) (xy 333.489298 -271.876595) (xy 333.456663 -271.839758) (xy 333.43036 -271.798162)
			(xy 333.411069 -271.752886) (xy 333.399292 -271.705102) (xy 333.395332 -271.656048) (xy 333.06639 -271.656048)
			(xy 333.065895 -271.680655) (xy 333.058 -271.729232) (xy 333.042416 -271.775913) (xy 333.019545 -271.81949)
			(xy 332.98998 -271.858834) (xy 332.954487 -271.892926) (xy 332.913984 -271.920882) (xy 332.869522 -271.94198)
			(xy 332.822251 -271.955672) (xy 332.773396 -271.961604) (xy 332.724221 -271.959623) (xy 332.676002 -271.949779)
			(xy 332.629986 -271.932327) (xy 332.587365 -271.90772) (xy 332.549244 -271.876595) (xy 332.516609 -271.839758)
			(xy 332.490306 -271.798162) (xy 332.471015 -271.752886) (xy 332.459238 -271.705102) (xy 332.455278 -271.656048)
			(xy 332.126779 -271.656048) (xy 332.122613 -271.706327) (xy 332.110217 -271.755282) (xy 332.089932 -271.801529)
			(xy 332.062313 -271.843806) (xy 332.028112 -271.880962) (xy 331.988262 -271.911982) (xy 331.943851 -271.93602)
			(xy 331.896088 -271.95242) (xy 331.846278 -271.960736) (xy 331.821028 -271.961356) (xy 331.808265 -271.961216)
			(xy 331.782832 -271.959051) (xy 331.770228 -271.957038) (xy 331.74354 -271.951958) (xy 331.692407 -271.933623)
			(xy 331.645329 -271.906524) (xy 331.624178 -271.889474) (xy 331.61859 -271.884902) (xy 331.605636 -271.87906)
			(xy 331.59827 -271.878044) (xy 331.591061 -271.877363) (xy 331.576754 -271.87956) (xy 331.570076 -271.882362)
			(xy 331.487018 -271.920716) (xy 331.479146 -271.925155) (xy 331.466916 -271.938444) (xy 331.460031 -271.95514)
			(xy 331.459332 -271.96415) (xy 331.459332 -272.147792) (xy 331.459575 -272.154742) (xy 331.463316 -272.168131)
			(xy 331.466698 -272.174208) (xy 331.47 -272.179288) (xy 331.480414 -272.18894) (xy 331.487526 -272.192496)
			(xy 331.508979 -272.203723) (xy 331.548346 -272.231909) (xy 331.582781 -272.265946) (xy 331.611422 -272.304984)
			(xy 331.633555 -272.348046) (xy 331.648625 -272.394059) (xy 331.656258 -272.441871) (xy 331.656259 -272.466054)
			(xy 331.985378 -272.466054) (xy 331.989338 -272.417) (xy 332.001115 -272.369216) (xy 332.020406 -272.32394)
			(xy 332.046709 -272.282344) (xy 332.079344 -272.245507) (xy 332.117465 -272.214382) (xy 332.160086 -272.189775)
			(xy 332.206102 -272.172323) (xy 332.254321 -272.162479) (xy 332.303496 -272.160498) (xy 332.352351 -272.16643)
			(xy 332.399622 -272.180122) (xy 332.444084 -272.20122) (xy 332.484587 -272.229176) (xy 332.52008 -272.263268)
			(xy 332.549645 -272.302612) (xy 332.572516 -272.346189) (xy 332.5881 -272.39287) (xy 332.595995 -272.441447)
			(xy 332.59649 -272.466054) (xy 332.925178 -272.466054) (xy 332.929138 -272.417) (xy 332.940915 -272.369216)
			(xy 332.960206 -272.32394) (xy 332.986509 -272.282344) (xy 333.019144 -272.245507) (xy 333.057265 -272.214382)
			(xy 333.099886 -272.189775) (xy 333.145902 -272.172323) (xy 333.194121 -272.162479) (xy 333.243296 -272.160498)
			(xy 333.292151 -272.16643) (xy 333.339422 -272.180122) (xy 333.383884 -272.20122) (xy 333.424387 -272.229176)
			(xy 333.45988 -272.263268) (xy 333.489445 -272.302612) (xy 333.512316 -272.346189) (xy 333.5279 -272.39287)
			(xy 333.535795 -272.441447) (xy 333.53629 -272.466054) (xy 333.865232 -272.466054) (xy 333.869192 -272.417)
			(xy 333.880969 -272.369216) (xy 333.90026 -272.32394) (xy 333.926563 -272.282344) (xy 333.959198 -272.245507)
			(xy 333.997319 -272.214382) (xy 334.03994 -272.189775) (xy 334.085956 -272.172323) (xy 334.134175 -272.162479)
			(xy 334.18335 -272.160498) (xy 334.232205 -272.16643) (xy 334.279476 -272.180122) (xy 334.323938 -272.20122)
			(xy 334.364441 -272.229176) (xy 334.399934 -272.263268) (xy 334.429499 -272.302612) (xy 334.45237 -272.346189)
			(xy 334.467954 -272.39287) (xy 334.475849 -272.441447) (xy 334.476344 -272.466054) (xy 334.805286 -272.466054)
			(xy 334.809246 -272.417) (xy 334.821023 -272.369216) (xy 334.840314 -272.32394) (xy 334.866617 -272.282344)
			(xy 334.899252 -272.245507) (xy 334.937373 -272.214382) (xy 334.979994 -272.189775) (xy 335.02601 -272.172323)
			(xy 335.074229 -272.162479) (xy 335.123404 -272.160498) (xy 335.172259 -272.16643) (xy 335.21953 -272.180122)
			(xy 335.263992 -272.20122) (xy 335.304495 -272.229176) (xy 335.339988 -272.263268) (xy 335.369553 -272.302612)
			(xy 335.392424 -272.346189) (xy 335.408008 -272.39287) (xy 335.415903 -272.441447) (xy 335.416398 -272.466054)
			(xy 335.74534 -272.466054) (xy 335.7493 -272.417) (xy 335.761077 -272.369216) (xy 335.780368 -272.32394)
			(xy 335.806671 -272.282344) (xy 335.839306 -272.245507) (xy 335.877427 -272.214382) (xy 335.920048 -272.189775)
			(xy 335.966064 -272.172323) (xy 336.014283 -272.162479) (xy 336.063458 -272.160498) (xy 336.112313 -272.16643)
			(xy 336.159584 -272.180122) (xy 336.204046 -272.20122) (xy 336.244549 -272.229176) (xy 336.280042 -272.263268)
			(xy 336.309607 -272.302612) (xy 336.332478 -272.346189) (xy 336.348062 -272.39287) (xy 336.355957 -272.441447)
			(xy 336.356452 -272.466054) (xy 336.685394 -272.466054) (xy 336.689354 -272.417) (xy 336.701131 -272.369216)
			(xy 336.720422 -272.32394) (xy 336.746725 -272.282344) (xy 336.77936 -272.245507) (xy 336.817481 -272.214382)
			(xy 336.860102 -272.189775) (xy 336.906118 -272.172323) (xy 336.954337 -272.162479) (xy 337.003512 -272.160498)
			(xy 337.052367 -272.16643) (xy 337.099638 -272.180122) (xy 337.1441 -272.20122) (xy 337.184603 -272.229176)
			(xy 337.220096 -272.263268) (xy 337.249661 -272.302612) (xy 337.272532 -272.346189) (xy 337.288116 -272.39287)
			(xy 337.296011 -272.441447) (xy 337.296506 -272.466054) (xy 337.625194 -272.466054) (xy 337.629154 -272.417)
			(xy 337.640931 -272.369216) (xy 337.660222 -272.32394) (xy 337.686525 -272.282344) (xy 337.71916 -272.245507)
			(xy 337.757281 -272.214382) (xy 337.799902 -272.189775) (xy 337.845918 -272.172323) (xy 337.894137 -272.162479)
			(xy 337.943312 -272.160498) (xy 337.992167 -272.16643) (xy 338.039438 -272.180122) (xy 338.0839 -272.20122)
			(xy 338.124403 -272.229176) (xy 338.159896 -272.263268) (xy 338.189461 -272.302612) (xy 338.212332 -272.346189)
			(xy 338.227916 -272.39287) (xy 338.235811 -272.441447) (xy 338.236306 -272.466054) (xy 338.554817 -272.466054)
			(xy 338.558912 -272.415326) (xy 338.571091 -272.365912) (xy 338.591039 -272.319092) (xy 338.61824 -272.276078)
			(xy 338.651988 -272.237984) (xy 338.69141 -272.205797) (xy 338.735484 -272.180351) (xy 338.78307 -272.162304)
			(xy 338.832934 -272.152124) (xy 338.883786 -272.150075) (xy 338.934307 -272.156209) (xy 338.983191 -272.170369)
			(xy 339.02917 -272.192186) (xy 339.071054 -272.221096) (xy 339.107758 -272.256351) (xy 339.138331 -272.297037)
			(xy 339.161982 -272.3421) (xy 339.178098 -272.390374) (xy 339.186262 -272.440608) (xy 339.186774 -272.466054)
			(xy 339.505302 -272.466054) (xy 339.509262 -272.417) (xy 339.521039 -272.369216) (xy 339.54033 -272.32394)
			(xy 339.566633 -272.282344) (xy 339.599268 -272.245507) (xy 339.637389 -272.214382) (xy 339.68001 -272.189775)
			(xy 339.726026 -272.172323) (xy 339.774245 -272.162479) (xy 339.82342 -272.160498) (xy 339.872275 -272.16643)
			(xy 339.919546 -272.180122) (xy 339.964008 -272.20122) (xy 340.004511 -272.229176) (xy 340.040004 -272.263268)
			(xy 340.069569 -272.302612) (xy 340.09244 -272.346189) (xy 340.108024 -272.39287) (xy 340.115919 -272.441447)
			(xy 340.116414 -272.466054) (xy 340.434925 -272.466054) (xy 340.43902 -272.415326) (xy 340.451199 -272.365912)
			(xy 340.471147 -272.319092) (xy 340.498348 -272.276078) (xy 340.532096 -272.237984) (xy 340.571518 -272.205797)
			(xy 340.615592 -272.180351) (xy 340.663178 -272.162304) (xy 340.713042 -272.152124) (xy 340.763894 -272.150075)
			(xy 340.814415 -272.156209) (xy 340.863299 -272.170369) (xy 340.909278 -272.192186) (xy 340.951162 -272.221096)
			(xy 340.987866 -272.256351) (xy 341.018439 -272.297037) (xy 341.04209 -272.3421) (xy 341.058206 -272.390374)
			(xy 341.06637 -272.440608) (xy 341.066882 -272.466054) (xy 341.38541 -272.466054) (xy 341.38937 -272.417)
			(xy 341.401147 -272.369216) (xy 341.420438 -272.32394) (xy 341.446741 -272.282344) (xy 341.479376 -272.245507)
			(xy 341.517497 -272.214382) (xy 341.560118 -272.189775) (xy 341.606134 -272.172323) (xy 341.654353 -272.162479)
			(xy 341.703528 -272.160498) (xy 341.752383 -272.16643) (xy 341.799654 -272.180122) (xy 341.844116 -272.20122)
			(xy 341.884619 -272.229176) (xy 341.920112 -272.263268) (xy 341.949677 -272.302612) (xy 341.972548 -272.346189)
			(xy 341.988132 -272.39287) (xy 341.996027 -272.441447) (xy 341.996522 -272.466054) (xy 341.996027 -272.490661)
			(xy 341.988132 -272.539238) (xy 341.972548 -272.585919) (xy 341.949677 -272.629496) (xy 341.920112 -272.66884)
			(xy 341.884619 -272.702932) (xy 341.844116 -272.730888) (xy 341.799654 -272.751986) (xy 341.752383 -272.765678)
			(xy 341.703528 -272.77161) (xy 341.654353 -272.769629) (xy 341.606134 -272.759785) (xy 341.560118 -272.742333)
			(xy 341.517497 -272.717726) (xy 341.479376 -272.686601) (xy 341.446741 -272.649764) (xy 341.420438 -272.608168)
			(xy 341.401147 -272.562892) (xy 341.38937 -272.515108) (xy 341.38541 -272.466054) (xy 341.066882 -272.466054)
			(xy 341.06637 -272.4915) (xy 341.058206 -272.541734) (xy 341.04209 -272.590008) (xy 341.018439 -272.635071)
			(xy 340.987866 -272.675757) (xy 340.951162 -272.711012) (xy 340.909278 -272.739922) (xy 340.863299 -272.761739)
			(xy 340.814415 -272.775899) (xy 340.763894 -272.782033) (xy 340.713042 -272.779984) (xy 340.663178 -272.769804)
			(xy 340.615592 -272.751757) (xy 340.571518 -272.726311) (xy 340.532096 -272.694124) (xy 340.498348 -272.65603)
			(xy 340.471147 -272.613016) (xy 340.451199 -272.566196) (xy 340.43902 -272.516782) (xy 340.434925 -272.466054)
			(xy 340.116414 -272.466054) (xy 340.115919 -272.490661) (xy 340.108024 -272.539238) (xy 340.09244 -272.585919)
			(xy 340.069569 -272.629496) (xy 340.040004 -272.66884) (xy 340.004511 -272.702932) (xy 339.964008 -272.730888)
			(xy 339.919546 -272.751986) (xy 339.872275 -272.765678) (xy 339.82342 -272.77161) (xy 339.774245 -272.769629)
			(xy 339.726026 -272.759785) (xy 339.68001 -272.742333) (xy 339.637389 -272.717726) (xy 339.599268 -272.686601)
			(xy 339.566633 -272.649764) (xy 339.54033 -272.608168) (xy 339.521039 -272.562892) (xy 339.509262 -272.515108)
			(xy 339.505302 -272.466054) (xy 339.186774 -272.466054) (xy 339.186262 -272.4915) (xy 339.178098 -272.541734)
			(xy 339.161982 -272.590008) (xy 339.138331 -272.635071) (xy 339.107758 -272.675757) (xy 339.071054 -272.711012)
			(xy 339.02917 -272.739922) (xy 338.983191 -272.761739) (xy 338.934307 -272.775899) (xy 338.883786 -272.782033)
			(xy 338.832934 -272.779984) (xy 338.78307 -272.769804) (xy 338.735484 -272.751757) (xy 338.69141 -272.726311)
			(xy 338.651988 -272.694124) (xy 338.61824 -272.65603) (xy 338.591039 -272.613016) (xy 338.571091 -272.566196)
			(xy 338.558912 -272.516782) (xy 338.554817 -272.466054) (xy 338.236306 -272.466054) (xy 338.235811 -272.490661)
			(xy 338.227916 -272.539238) (xy 338.212332 -272.585919) (xy 338.189461 -272.629496) (xy 338.159896 -272.66884)
			(xy 338.124403 -272.702932) (xy 338.0839 -272.730888) (xy 338.039438 -272.751986) (xy 337.992167 -272.765678)
			(xy 337.943312 -272.77161) (xy 337.894137 -272.769629) (xy 337.845918 -272.759785) (xy 337.799902 -272.742333)
			(xy 337.757281 -272.717726) (xy 337.71916 -272.686601) (xy 337.686525 -272.649764) (xy 337.660222 -272.608168)
			(xy 337.640931 -272.562892) (xy 337.629154 -272.515108) (xy 337.625194 -272.466054) (xy 337.296506 -272.466054)
			(xy 337.296011 -272.490661) (xy 337.288116 -272.539238) (xy 337.272532 -272.585919) (xy 337.249661 -272.629496)
			(xy 337.220096 -272.66884) (xy 337.184603 -272.702932) (xy 337.1441 -272.730888) (xy 337.099638 -272.751986)
			(xy 337.052367 -272.765678) (xy 337.003512 -272.77161) (xy 336.954337 -272.769629) (xy 336.906118 -272.759785)
			(xy 336.860102 -272.742333) (xy 336.817481 -272.717726) (xy 336.77936 -272.686601) (xy 336.746725 -272.649764)
			(xy 336.720422 -272.608168) (xy 336.701131 -272.562892) (xy 336.689354 -272.515108) (xy 336.685394 -272.466054)
			(xy 336.356452 -272.466054) (xy 336.355957 -272.490661) (xy 336.348062 -272.539238) (xy 336.332478 -272.585919)
			(xy 336.309607 -272.629496) (xy 336.280042 -272.66884) (xy 336.244549 -272.702932) (xy 336.204046 -272.730888)
			(xy 336.159584 -272.751986) (xy 336.112313 -272.765678) (xy 336.063458 -272.77161) (xy 336.014283 -272.769629)
			(xy 335.966064 -272.759785) (xy 335.920048 -272.742333) (xy 335.877427 -272.717726) (xy 335.839306 -272.686601)
			(xy 335.806671 -272.649764) (xy 335.780368 -272.608168) (xy 335.761077 -272.562892) (xy 335.7493 -272.515108)
			(xy 335.74534 -272.466054) (xy 335.416398 -272.466054) (xy 335.415903 -272.490661) (xy 335.408008 -272.539238)
			(xy 335.392424 -272.585919) (xy 335.369553 -272.629496) (xy 335.339988 -272.66884) (xy 335.304495 -272.702932)
			(xy 335.263992 -272.730888) (xy 335.21953 -272.751986) (xy 335.172259 -272.765678) (xy 335.123404 -272.77161)
			(xy 335.074229 -272.769629) (xy 335.02601 -272.759785) (xy 334.979994 -272.742333) (xy 334.937373 -272.717726)
			(xy 334.899252 -272.686601) (xy 334.866617 -272.649764) (xy 334.840314 -272.608168) (xy 334.821023 -272.562892)
			(xy 334.809246 -272.515108) (xy 334.805286 -272.466054) (xy 334.476344 -272.466054) (xy 334.475849 -272.490661)
			(xy 334.467954 -272.539238) (xy 334.45237 -272.585919) (xy 334.429499 -272.629496) (xy 334.399934 -272.66884)
			(xy 334.364441 -272.702932) (xy 334.323938 -272.730888) (xy 334.279476 -272.751986) (xy 334.232205 -272.765678)
			(xy 334.18335 -272.77161) (xy 334.134175 -272.769629) (xy 334.085956 -272.759785) (xy 334.03994 -272.742333)
			(xy 333.997319 -272.717726) (xy 333.959198 -272.686601) (xy 333.926563 -272.649764) (xy 333.90026 -272.608168)
			(xy 333.880969 -272.562892) (xy 333.869192 -272.515108) (xy 333.865232 -272.466054) (xy 333.53629 -272.466054)
			(xy 333.535795 -272.490661) (xy 333.5279 -272.539238) (xy 333.512316 -272.585919) (xy 333.489445 -272.629496)
			(xy 333.45988 -272.66884) (xy 333.424387 -272.702932) (xy 333.383884 -272.730888) (xy 333.339422 -272.751986)
			(xy 333.292151 -272.765678) (xy 333.243296 -272.77161) (xy 333.194121 -272.769629) (xy 333.145902 -272.759785)
			(xy 333.099886 -272.742333) (xy 333.057265 -272.717726) (xy 333.019144 -272.686601) (xy 332.986509 -272.649764)
			(xy 332.960206 -272.608168) (xy 332.940915 -272.562892) (xy 332.929138 -272.515108) (xy 332.925178 -272.466054)
			(xy 332.59649 -272.466054) (xy 332.595995 -272.490661) (xy 332.5881 -272.539238) (xy 332.572516 -272.585919)
			(xy 332.549645 -272.629496) (xy 332.52008 -272.66884) (xy 332.484587 -272.702932) (xy 332.444084 -272.730888)
			(xy 332.399622 -272.751986) (xy 332.352351 -272.765678) (xy 332.303496 -272.77161) (xy 332.254321 -272.769629)
			(xy 332.206102 -272.759785) (xy 332.160086 -272.742333) (xy 332.117465 -272.717726) (xy 332.079344 -272.686601)
			(xy 332.046709 -272.649764) (xy 332.020406 -272.608168) (xy 332.001115 -272.562892) (xy 331.989338 -272.515108)
			(xy 331.985378 -272.466054) (xy 331.656259 -272.466054) (xy 331.656261 -272.490288) (xy 331.648635 -272.538101)
			(xy 331.633571 -272.584116) (xy 331.611444 -272.627181) (xy 331.582808 -272.666223) (xy 331.548378 -272.700264)
			(xy 331.509014 -272.728455) (xy 331.487526 -272.739612) (xy 331.486764 -272.739866) (xy 331.480505 -272.743267)
			(xy 331.47005 -272.75293) (xy 331.46619 -272.758916) (xy 331.463142 -272.763996) (xy 331.459332 -272.777204)
			(xy 331.459332 -272.96618) (xy 331.459795 -272.975559) (xy 331.466626 -272.993031) (xy 331.479302 -273.006861)
			(xy 331.487526 -273.011392) (xy 331.518006 -273.025616) (xy 331.566266 -273.047968) (xy 331.56955 -273.049464)
			(xy 331.576432 -273.051637) (xy 331.579982 -273.052286) (xy 331.584357 -273.052837) (xy 331.593171 -273.05258)
			(xy 331.597508 -273.051778) (xy 331.605382 -273.049746) (xy 331.62367 -273.042888) (xy 331.63002 -273.037808)
			(xy 331.6505 -273.022096) (xy 331.695637 -272.997062) (xy 331.744339 -272.979968) (xy 331.795221 -272.9713)
			(xy 331.821028 -272.970752) (xy 331.846285 -272.971276) (xy 331.89611 -272.979594) (xy 331.943886 -272.996)
			(xy 331.98831 -273.020045) (xy 332.028172 -273.051073) (xy 332.062382 -273.088239) (xy 332.09001 -273.130529)
			(xy 332.1103 -273.176789) (xy 332.1227 -273.225758) (xy 332.126868 -273.27606) (xy 332.455278 -273.27606)
			(xy 332.459238 -273.227006) (xy 332.471015 -273.179222) (xy 332.490306 -273.133946) (xy 332.516609 -273.09235)
			(xy 332.549244 -273.055513) (xy 332.587365 -273.024388) (xy 332.629986 -272.999781) (xy 332.676002 -272.982329)
			(xy 332.724221 -272.972485) (xy 332.773396 -272.970504) (xy 332.822251 -272.976436) (xy 332.869522 -272.990128)
			(xy 332.913984 -273.011226) (xy 332.954487 -273.039182) (xy 332.98998 -273.073274) (xy 333.019545 -273.112618)
			(xy 333.042416 -273.156195) (xy 333.058 -273.202876) (xy 333.065895 -273.251453) (xy 333.06639 -273.27606)
			(xy 333.395332 -273.27606) (xy 333.399292 -273.227006) (xy 333.411069 -273.179222) (xy 333.43036 -273.133946)
			(xy 333.456663 -273.09235) (xy 333.489298 -273.055513) (xy 333.527419 -273.024388) (xy 333.57004 -272.999781)
			(xy 333.616056 -272.982329) (xy 333.664275 -272.972485) (xy 333.71345 -272.970504) (xy 333.762305 -272.976436)
			(xy 333.809576 -272.990128) (xy 333.854038 -273.011226) (xy 333.894541 -273.039182) (xy 333.930034 -273.073274)
			(xy 333.959599 -273.112618) (xy 333.98247 -273.156195) (xy 333.998054 -273.202876) (xy 334.005949 -273.251453)
			(xy 334.006444 -273.27606) (xy 335.275186 -273.27606) (xy 335.279146 -273.227006) (xy 335.290923 -273.179222)
			(xy 335.310214 -273.133946) (xy 335.336517 -273.09235) (xy 335.369152 -273.055513) (xy 335.407273 -273.024388)
			(xy 335.449894 -272.999781) (xy 335.49591 -272.982329) (xy 335.544129 -272.972485) (xy 335.593304 -272.970504)
			(xy 335.642159 -272.976436) (xy 335.68943 -272.990128) (xy 335.733892 -273.011226) (xy 335.774395 -273.039182)
			(xy 335.809888 -273.073274) (xy 335.839453 -273.112618) (xy 335.862324 -273.156195) (xy 335.877908 -273.202876)
			(xy 335.885803 -273.251453) (xy 335.886298 -273.27606) (xy 336.21524 -273.27606) (xy 336.2192 -273.227006)
			(xy 336.230977 -273.179222) (xy 336.250268 -273.133946) (xy 336.276571 -273.09235) (xy 336.309206 -273.055513)
			(xy 336.347327 -273.024388) (xy 336.389948 -272.999781) (xy 336.435964 -272.982329) (xy 336.484183 -272.972485)
			(xy 336.533358 -272.970504) (xy 336.582213 -272.976436) (xy 336.629484 -272.990128) (xy 336.673946 -273.011226)
			(xy 336.714449 -273.039182) (xy 336.749942 -273.073274) (xy 336.779507 -273.112618) (xy 336.802378 -273.156195)
			(xy 336.817962 -273.202876) (xy 336.825857 -273.251453) (xy 336.826352 -273.27606) (xy 337.155294 -273.27606)
			(xy 337.159254 -273.227006) (xy 337.171031 -273.179222) (xy 337.190322 -273.133946) (xy 337.216625 -273.09235)
			(xy 337.24926 -273.055513) (xy 337.287381 -273.024388) (xy 337.330002 -272.999781) (xy 337.376018 -272.982329)
			(xy 337.424237 -272.972485) (xy 337.473412 -272.970504) (xy 337.522267 -272.976436) (xy 337.569538 -272.990128)
			(xy 337.614 -273.011226) (xy 337.654503 -273.039182) (xy 337.689996 -273.073274) (xy 337.719561 -273.112618)
			(xy 337.742432 -273.156195) (xy 337.758016 -273.202876) (xy 337.765911 -273.251453) (xy 337.766406 -273.27606)
			(xy 338.095348 -273.27606) (xy 338.099308 -273.227006) (xy 338.111085 -273.179222) (xy 338.130376 -273.133946)
			(xy 338.156679 -273.09235) (xy 338.189314 -273.055513) (xy 338.227435 -273.024388) (xy 338.270056 -272.999781)
			(xy 338.316072 -272.982329) (xy 338.364291 -272.972485) (xy 338.413466 -272.970504) (xy 338.462321 -272.976436)
			(xy 338.509592 -272.990128) (xy 338.554054 -273.011226) (xy 338.594557 -273.039182) (xy 338.63005 -273.073274)
			(xy 338.659615 -273.112618) (xy 338.682486 -273.156195) (xy 338.69807 -273.202876) (xy 338.705965 -273.251453)
			(xy 338.70646 -273.27606) (xy 339.024971 -273.27606) (xy 339.029066 -273.225332) (xy 339.041245 -273.175918)
			(xy 339.061193 -273.129098) (xy 339.088394 -273.086084) (xy 339.122142 -273.04799) (xy 339.161564 -273.015803)
			(xy 339.205638 -272.990357) (xy 339.253224 -272.97231) (xy 339.303088 -272.96213) (xy 339.35394 -272.960081)
			(xy 339.404461 -272.966215) (xy 339.453345 -272.980375) (xy 339.499324 -273.002192) (xy 339.541208 -273.031102)
			(xy 339.577912 -273.066357) (xy 339.608485 -273.107043) (xy 339.632136 -273.152106) (xy 339.648252 -273.20038)
			(xy 339.656416 -273.250614) (xy 339.656928 -273.27606) (xy 339.964771 -273.27606) (xy 339.968866 -273.225332)
			(xy 339.981045 -273.175918) (xy 340.000993 -273.129098) (xy 340.028194 -273.086084) (xy 340.061942 -273.04799)
			(xy 340.101364 -273.015803) (xy 340.145438 -272.990357) (xy 340.193024 -272.97231) (xy 340.242888 -272.96213)
			(xy 340.29374 -272.960081) (xy 340.344261 -272.966215) (xy 340.393145 -272.980375) (xy 340.439124 -273.002192)
			(xy 340.481008 -273.031102) (xy 340.517712 -273.066357) (xy 340.548285 -273.107043) (xy 340.571936 -273.152106)
			(xy 340.588052 -273.20038) (xy 340.596216 -273.250614) (xy 340.596728 -273.27606) (xy 340.596216 -273.301506)
			(xy 340.588052 -273.35174) (xy 340.571936 -273.400014) (xy 340.548285 -273.445077) (xy 340.517712 -273.485763)
			(xy 340.481008 -273.521018) (xy 340.439124 -273.549928) (xy 340.393145 -273.571745) (xy 340.344261 -273.585905)
			(xy 340.29374 -273.592039) (xy 340.242888 -273.58999) (xy 340.193024 -273.57981) (xy 340.145438 -273.561763)
			(xy 340.101364 -273.536317) (xy 340.061942 -273.50413) (xy 340.028194 -273.466036) (xy 340.000993 -273.423022)
			(xy 339.981045 -273.376202) (xy 339.968866 -273.326788) (xy 339.964771 -273.27606) (xy 339.656928 -273.27606)
			(xy 339.656416 -273.301506) (xy 339.648252 -273.35174) (xy 339.632136 -273.400014) (xy 339.608485 -273.445077)
			(xy 339.577912 -273.485763) (xy 339.541208 -273.521018) (xy 339.499324 -273.549928) (xy 339.453345 -273.571745)
			(xy 339.404461 -273.585905) (xy 339.35394 -273.592039) (xy 339.303088 -273.58999) (xy 339.253224 -273.57981)
			(xy 339.205638 -273.561763) (xy 339.161564 -273.536317) (xy 339.122142 -273.50413) (xy 339.088394 -273.466036)
			(xy 339.061193 -273.423022) (xy 339.041245 -273.376202) (xy 339.029066 -273.326788) (xy 339.024971 -273.27606)
			(xy 338.70646 -273.27606) (xy 338.705965 -273.300667) (xy 338.69807 -273.349244) (xy 338.682486 -273.395925)
			(xy 338.659615 -273.439502) (xy 338.63005 -273.478846) (xy 338.594557 -273.512938) (xy 338.554054 -273.540894)
			(xy 338.509592 -273.561992) (xy 338.462321 -273.575684) (xy 338.413466 -273.581616) (xy 338.364291 -273.579635)
			(xy 338.316072 -273.569791) (xy 338.270056 -273.552339) (xy 338.227435 -273.527732) (xy 338.189314 -273.496607)
			(xy 338.156679 -273.45977) (xy 338.130376 -273.418174) (xy 338.111085 -273.372898) (xy 338.099308 -273.325114)
			(xy 338.095348 -273.27606) (xy 337.766406 -273.27606) (xy 337.765911 -273.300667) (xy 337.758016 -273.349244)
			(xy 337.742432 -273.395925) (xy 337.719561 -273.439502) (xy 337.689996 -273.478846) (xy 337.654503 -273.512938)
			(xy 337.614 -273.540894) (xy 337.569538 -273.561992) (xy 337.522267 -273.575684) (xy 337.473412 -273.581616)
			(xy 337.424237 -273.579635) (xy 337.376018 -273.569791) (xy 337.330002 -273.552339) (xy 337.287381 -273.527732)
			(xy 337.24926 -273.496607) (xy 337.216625 -273.45977) (xy 337.190322 -273.418174) (xy 337.171031 -273.372898)
			(xy 337.159254 -273.325114) (xy 337.155294 -273.27606) (xy 336.826352 -273.27606) (xy 336.825857 -273.300667)
			(xy 336.817962 -273.349244) (xy 336.802378 -273.395925) (xy 336.779507 -273.439502) (xy 336.749942 -273.478846)
			(xy 336.714449 -273.512938) (xy 336.673946 -273.540894) (xy 336.629484 -273.561992) (xy 336.582213 -273.575684)
			(xy 336.533358 -273.581616) (xy 336.484183 -273.579635) (xy 336.435964 -273.569791) (xy 336.389948 -273.552339)
			(xy 336.347327 -273.527732) (xy 336.309206 -273.496607) (xy 336.276571 -273.45977) (xy 336.250268 -273.418174)
			(xy 336.230977 -273.372898) (xy 336.2192 -273.325114) (xy 336.21524 -273.27606) (xy 335.886298 -273.27606)
			(xy 335.885803 -273.300667) (xy 335.877908 -273.349244) (xy 335.862324 -273.395925) (xy 335.839453 -273.439502)
			(xy 335.809888 -273.478846) (xy 335.774395 -273.512938) (xy 335.733892 -273.540894) (xy 335.68943 -273.561992)
			(xy 335.642159 -273.575684) (xy 335.593304 -273.581616) (xy 335.544129 -273.579635) (xy 335.49591 -273.569791)
			(xy 335.449894 -273.552339) (xy 335.407273 -273.527732) (xy 335.369152 -273.496607) (xy 335.336517 -273.45977)
			(xy 335.310214 -273.418174) (xy 335.290923 -273.372898) (xy 335.279146 -273.325114) (xy 335.275186 -273.27606)
			(xy 334.006444 -273.27606) (xy 334.005949 -273.300667) (xy 333.998054 -273.349244) (xy 333.98247 -273.395925)
			(xy 333.959599 -273.439502) (xy 333.930034 -273.478846) (xy 333.894541 -273.512938) (xy 333.854038 -273.540894)
			(xy 333.809576 -273.561992) (xy 333.762305 -273.575684) (xy 333.71345 -273.581616) (xy 333.664275 -273.579635)
			(xy 333.616056 -273.569791) (xy 333.57004 -273.552339) (xy 333.527419 -273.527732) (xy 333.489298 -273.496607)
			(xy 333.456663 -273.45977) (xy 333.43036 -273.418174) (xy 333.411069 -273.372898) (xy 333.399292 -273.325114)
			(xy 333.395332 -273.27606) (xy 333.06639 -273.27606) (xy 333.065895 -273.300667) (xy 333.058 -273.349244)
			(xy 333.042416 -273.395925) (xy 333.019545 -273.439502) (xy 332.98998 -273.478846) (xy 332.954487 -273.512938)
			(xy 332.913984 -273.540894) (xy 332.869522 -273.561992) (xy 332.822251 -273.575684) (xy 332.773396 -273.581616)
			(xy 332.724221 -273.579635) (xy 332.676002 -273.569791) (xy 332.629986 -273.552339) (xy 332.587365 -273.527732)
			(xy 332.549244 -273.496607) (xy 332.516609 -273.45977) (xy 332.490306 -273.418174) (xy 332.471015 -273.372898)
			(xy 332.459238 -273.325114) (xy 332.455278 -273.27606) (xy 332.126868 -273.27606) (xy 332.126871 -273.2761)
			(xy 332.1227 -273.326442) (xy 332.1103 -273.375411) (xy 332.09001 -273.421671) (xy 332.062382 -273.463961)
			(xy 332.028172 -273.501127) (xy 331.98831 -273.532155) (xy 331.943886 -273.5562) (xy 331.89611 -273.572606)
			(xy 331.846285 -273.580924) (xy 331.821028 -273.581368) (xy 331.808265 -273.581228) (xy 331.782832 -273.579063)
			(xy 331.770228 -273.57705) (xy 331.74354 -273.57197) (xy 331.692407 -273.553636) (xy 331.645327 -273.526537)
			(xy 331.624178 -273.509486) (xy 331.61859 -273.504914) (xy 331.605636 -273.499072) (xy 331.59827 -273.498056)
			(xy 331.591061 -273.497375) (xy 331.576754 -273.499572) (xy 331.570076 -273.502374) (xy 331.487018 -273.540728)
			(xy 331.479148 -273.545168) (xy 331.466921 -273.558457) (xy 331.46004 -273.575153) (xy 331.459332 -273.584162)
			(xy 331.459332 -273.767804) (xy 331.459576 -273.774754) (xy 331.46332 -273.788141) (xy 331.466698 -273.79422)
			(xy 331.47 -273.7993) (xy 331.480414 -273.808952) (xy 331.487526 -273.812508) (xy 331.508978 -273.823735)
			(xy 331.548344 -273.851921) (xy 331.582776 -273.885957) (xy 331.611416 -273.924994) (xy 331.633547 -273.968055)
			(xy 331.648616 -274.014066) (xy 331.656247 -274.061877) (xy 331.656248 -274.086066) (xy 331.985378 -274.086066)
			(xy 331.989338 -274.037012) (xy 332.001115 -273.989228) (xy 332.020406 -273.943952) (xy 332.046709 -273.902356)
			(xy 332.079344 -273.865519) (xy 332.117465 -273.834394) (xy 332.160086 -273.809787) (xy 332.206102 -273.792335)
			(xy 332.254321 -273.782491) (xy 332.303496 -273.78051) (xy 332.352351 -273.786442) (xy 332.399622 -273.800134)
			(xy 332.444084 -273.821232) (xy 332.484587 -273.849188) (xy 332.52008 -273.88328) (xy 332.549645 -273.922624)
			(xy 332.572516 -273.966201) (xy 332.5881 -274.012882) (xy 332.595995 -274.061459) (xy 332.59649 -274.086066)
			(xy 332.925178 -274.086066) (xy 332.929138 -274.037012) (xy 332.940915 -273.989228) (xy 332.960206 -273.943952)
			(xy 332.986509 -273.902356) (xy 333.019144 -273.865519) (xy 333.057265 -273.834394) (xy 333.099886 -273.809787)
			(xy 333.145902 -273.792335) (xy 333.194121 -273.782491) (xy 333.243296 -273.78051) (xy 333.292151 -273.786442)
			(xy 333.339422 -273.800134) (xy 333.383884 -273.821232) (xy 333.424387 -273.849188) (xy 333.45988 -273.88328)
			(xy 333.489445 -273.922624) (xy 333.512316 -273.966201) (xy 333.5279 -274.012882) (xy 333.535795 -274.061459)
			(xy 333.53629 -274.086066) (xy 333.865232 -274.086066) (xy 333.869192 -274.037012) (xy 333.880969 -273.989228)
			(xy 333.90026 -273.943952) (xy 333.926563 -273.902356) (xy 333.959198 -273.865519) (xy 333.997319 -273.834394)
			(xy 334.03994 -273.809787) (xy 334.085956 -273.792335) (xy 334.134175 -273.782491) (xy 334.18335 -273.78051)
			(xy 334.232205 -273.786442) (xy 334.279476 -273.800134) (xy 334.323938 -273.821232) (xy 334.364441 -273.849188)
			(xy 334.399934 -273.88328) (xy 334.429499 -273.922624) (xy 334.45237 -273.966201) (xy 334.467954 -274.012882)
			(xy 334.475849 -274.061459) (xy 334.476344 -274.086066) (xy 334.805286 -274.086066) (xy 334.809246 -274.037012)
			(xy 334.821023 -273.989228) (xy 334.840314 -273.943952) (xy 334.866617 -273.902356) (xy 334.899252 -273.865519)
			(xy 334.937373 -273.834394) (xy 334.979994 -273.809787) (xy 335.02601 -273.792335) (xy 335.074229 -273.782491)
			(xy 335.123404 -273.78051) (xy 335.172259 -273.786442) (xy 335.21953 -273.800134) (xy 335.263992 -273.821232)
			(xy 335.304495 -273.849188) (xy 335.339988 -273.88328) (xy 335.369553 -273.922624) (xy 335.392424 -273.966201)
			(xy 335.408008 -274.012882) (xy 335.415903 -274.061459) (xy 335.416398 -274.086066) (xy 335.74534 -274.086066)
			(xy 335.7493 -274.037012) (xy 335.761077 -273.989228) (xy 335.780368 -273.943952) (xy 335.806671 -273.902356)
			(xy 335.839306 -273.865519) (xy 335.877427 -273.834394) (xy 335.920048 -273.809787) (xy 335.966064 -273.792335)
			(xy 336.014283 -273.782491) (xy 336.063458 -273.78051) (xy 336.112313 -273.786442) (xy 336.159584 -273.800134)
			(xy 336.204046 -273.821232) (xy 336.244549 -273.849188) (xy 336.280042 -273.88328) (xy 336.309607 -273.922624)
			(xy 336.332478 -273.966201) (xy 336.348062 -274.012882) (xy 336.355957 -274.061459) (xy 336.356452 -274.086066)
			(xy 336.685394 -274.086066) (xy 336.689354 -274.037012) (xy 336.701131 -273.989228) (xy 336.720422 -273.943952)
			(xy 336.746725 -273.902356) (xy 336.77936 -273.865519) (xy 336.817481 -273.834394) (xy 336.860102 -273.809787)
			(xy 336.906118 -273.792335) (xy 336.954337 -273.782491) (xy 337.003512 -273.78051) (xy 337.052367 -273.786442)
			(xy 337.099638 -273.800134) (xy 337.1441 -273.821232) (xy 337.184603 -273.849188) (xy 337.220096 -273.88328)
			(xy 337.249661 -273.922624) (xy 337.272532 -273.966201) (xy 337.288116 -274.012882) (xy 337.296011 -274.061459)
			(xy 337.296506 -274.086066) (xy 337.625194 -274.086066) (xy 337.629154 -274.037012) (xy 337.640931 -273.989228)
			(xy 337.660222 -273.943952) (xy 337.686525 -273.902356) (xy 337.71916 -273.865519) (xy 337.757281 -273.834394)
			(xy 337.799902 -273.809787) (xy 337.845918 -273.792335) (xy 337.894137 -273.782491) (xy 337.943312 -273.78051)
			(xy 337.992167 -273.786442) (xy 338.039438 -273.800134) (xy 338.0839 -273.821232) (xy 338.124403 -273.849188)
			(xy 338.159896 -273.88328) (xy 338.189461 -273.922624) (xy 338.212332 -273.966201) (xy 338.227916 -274.012882)
			(xy 338.235811 -274.061459) (xy 338.236306 -274.086066) (xy 338.554817 -274.086066) (xy 338.558912 -274.035338)
			(xy 338.571091 -273.985924) (xy 338.591039 -273.939104) (xy 338.61824 -273.89609) (xy 338.651988 -273.857996)
			(xy 338.69141 -273.825809) (xy 338.735484 -273.800363) (xy 338.78307 -273.782316) (xy 338.832934 -273.772136)
			(xy 338.883786 -273.770087) (xy 338.934307 -273.776221) (xy 338.983191 -273.790381) (xy 339.02917 -273.812198)
			(xy 339.071054 -273.841108) (xy 339.107758 -273.876363) (xy 339.138331 -273.917049) (xy 339.161982 -273.962112)
			(xy 339.178098 -274.010386) (xy 339.186262 -274.06062) (xy 339.186774 -274.086066) (xy 339.505302 -274.086066)
			(xy 339.509262 -274.037012) (xy 339.521039 -273.989228) (xy 339.54033 -273.943952) (xy 339.566633 -273.902356)
			(xy 339.599268 -273.865519) (xy 339.637389 -273.834394) (xy 339.68001 -273.809787) (xy 339.726026 -273.792335)
			(xy 339.774245 -273.782491) (xy 339.82342 -273.78051) (xy 339.872275 -273.786442) (xy 339.919546 -273.800134)
			(xy 339.964008 -273.821232) (xy 340.004511 -273.849188) (xy 340.040004 -273.88328) (xy 340.069569 -273.922624)
			(xy 340.09244 -273.966201) (xy 340.108024 -274.012882) (xy 340.115919 -274.061459) (xy 340.116414 -274.086066)
			(xy 340.115919 -274.110673) (xy 340.108024 -274.15925) (xy 340.09244 -274.205931) (xy 340.069569 -274.249508)
			(xy 340.040004 -274.288852) (xy 340.004511 -274.322944) (xy 339.964008 -274.3509) (xy 339.919546 -274.371998)
			(xy 339.872275 -274.38569) (xy 339.82342 -274.391622) (xy 339.774245 -274.389641) (xy 339.726026 -274.379797)
			(xy 339.68001 -274.362345) (xy 339.637389 -274.337738) (xy 339.599268 -274.306613) (xy 339.566633 -274.269776)
			(xy 339.54033 -274.22818) (xy 339.521039 -274.182904) (xy 339.509262 -274.13512) (xy 339.505302 -274.086066)
			(xy 339.186774 -274.086066) (xy 339.186262 -274.111512) (xy 339.178098 -274.161746) (xy 339.161982 -274.21002)
			(xy 339.138331 -274.255083) (xy 339.107758 -274.295769) (xy 339.071054 -274.331024) (xy 339.02917 -274.359934)
			(xy 338.983191 -274.381751) (xy 338.934307 -274.395911) (xy 338.883786 -274.402045) (xy 338.832934 -274.399996)
			(xy 338.78307 -274.389816) (xy 338.735484 -274.371769) (xy 338.69141 -274.346323) (xy 338.651988 -274.314136)
			(xy 338.61824 -274.276042) (xy 338.591039 -274.233028) (xy 338.571091 -274.186208) (xy 338.558912 -274.136794)
			(xy 338.554817 -274.086066) (xy 338.236306 -274.086066) (xy 338.235811 -274.110673) (xy 338.227916 -274.15925)
			(xy 338.212332 -274.205931) (xy 338.189461 -274.249508) (xy 338.159896 -274.288852) (xy 338.124403 -274.322944)
			(xy 338.0839 -274.3509) (xy 338.039438 -274.371998) (xy 337.992167 -274.38569) (xy 337.943312 -274.391622)
			(xy 337.894137 -274.389641) (xy 337.845918 -274.379797) (xy 337.799902 -274.362345) (xy 337.757281 -274.337738)
			(xy 337.71916 -274.306613) (xy 337.686525 -274.269776) (xy 337.660222 -274.22818) (xy 337.640931 -274.182904)
			(xy 337.629154 -274.13512) (xy 337.625194 -274.086066) (xy 337.296506 -274.086066) (xy 337.296011 -274.110673)
			(xy 337.288116 -274.15925) (xy 337.272532 -274.205931) (xy 337.249661 -274.249508) (xy 337.220096 -274.288852)
			(xy 337.184603 -274.322944) (xy 337.1441 -274.3509) (xy 337.099638 -274.371998) (xy 337.052367 -274.38569)
			(xy 337.003512 -274.391622) (xy 336.954337 -274.389641) (xy 336.906118 -274.379797) (xy 336.860102 -274.362345)
			(xy 336.817481 -274.337738) (xy 336.77936 -274.306613) (xy 336.746725 -274.269776) (xy 336.720422 -274.22818)
			(xy 336.701131 -274.182904) (xy 336.689354 -274.13512) (xy 336.685394 -274.086066) (xy 336.356452 -274.086066)
			(xy 336.355957 -274.110673) (xy 336.348062 -274.15925) (xy 336.332478 -274.205931) (xy 336.309607 -274.249508)
			(xy 336.280042 -274.288852) (xy 336.244549 -274.322944) (xy 336.204046 -274.3509) (xy 336.159584 -274.371998)
			(xy 336.112313 -274.38569) (xy 336.063458 -274.391622) (xy 336.014283 -274.389641) (xy 335.966064 -274.379797)
			(xy 335.920048 -274.362345) (xy 335.877427 -274.337738) (xy 335.839306 -274.306613) (xy 335.806671 -274.269776)
			(xy 335.780368 -274.22818) (xy 335.761077 -274.182904) (xy 335.7493 -274.13512) (xy 335.74534 -274.086066)
			(xy 335.416398 -274.086066) (xy 335.415903 -274.110673) (xy 335.408008 -274.15925) (xy 335.392424 -274.205931)
			(xy 335.369553 -274.249508) (xy 335.339988 -274.288852) (xy 335.304495 -274.322944) (xy 335.263992 -274.3509)
			(xy 335.21953 -274.371998) (xy 335.172259 -274.38569) (xy 335.123404 -274.391622) (xy 335.074229 -274.389641)
			(xy 335.02601 -274.379797) (xy 334.979994 -274.362345) (xy 334.937373 -274.337738) (xy 334.899252 -274.306613)
			(xy 334.866617 -274.269776) (xy 334.840314 -274.22818) (xy 334.821023 -274.182904) (xy 334.809246 -274.13512)
			(xy 334.805286 -274.086066) (xy 334.476344 -274.086066) (xy 334.475849 -274.110673) (xy 334.467954 -274.15925)
			(xy 334.45237 -274.205931) (xy 334.429499 -274.249508) (xy 334.399934 -274.288852) (xy 334.364441 -274.322944)
			(xy 334.323938 -274.3509) (xy 334.279476 -274.371998) (xy 334.232205 -274.38569) (xy 334.18335 -274.391622)
			(xy 334.134175 -274.389641) (xy 334.085956 -274.379797) (xy 334.03994 -274.362345) (xy 333.997319 -274.337738)
			(xy 333.959198 -274.306613) (xy 333.926563 -274.269776) (xy 333.90026 -274.22818) (xy 333.880969 -274.182904)
			(xy 333.869192 -274.13512) (xy 333.865232 -274.086066) (xy 333.53629 -274.086066) (xy 333.535795 -274.110673)
			(xy 333.5279 -274.15925) (xy 333.512316 -274.205931) (xy 333.489445 -274.249508) (xy 333.45988 -274.288852)
			(xy 333.424387 -274.322944) (xy 333.383884 -274.3509) (xy 333.339422 -274.371998) (xy 333.292151 -274.38569)
			(xy 333.243296 -274.391622) (xy 333.194121 -274.389641) (xy 333.145902 -274.379797) (xy 333.099886 -274.362345)
			(xy 333.057265 -274.337738) (xy 333.019144 -274.306613) (xy 332.986509 -274.269776) (xy 332.960206 -274.22818)
			(xy 332.940915 -274.182904) (xy 332.929138 -274.13512) (xy 332.925178 -274.086066) (xy 332.59649 -274.086066)
			(xy 332.595995 -274.110673) (xy 332.5881 -274.15925) (xy 332.572516 -274.205931) (xy 332.549645 -274.249508)
			(xy 332.52008 -274.288852) (xy 332.484587 -274.322944) (xy 332.444084 -274.3509) (xy 332.399622 -274.371998)
			(xy 332.352351 -274.38569) (xy 332.303496 -274.391622) (xy 332.254321 -274.389641) (xy 332.206102 -274.379797)
			(xy 332.160086 -274.362345) (xy 332.117465 -274.337738) (xy 332.079344 -274.306613) (xy 332.046709 -274.269776)
			(xy 332.020406 -274.22818) (xy 332.001115 -274.182904) (xy 331.989338 -274.13512) (xy 331.985378 -274.086066)
			(xy 331.656248 -274.086066) (xy 331.65625 -274.110293) (xy 331.648623 -274.158104) (xy 331.633559 -274.204116)
			(xy 331.611432 -274.24718) (xy 331.582796 -274.28622) (xy 331.548367 -274.320259) (xy 331.509004 -274.348449)
			(xy 331.487526 -274.359624) (xy 331.486764 -274.359878) (xy 331.480506 -274.363279) (xy 331.470052 -274.372944)
			(xy 331.46619 -274.378928) (xy 331.463142 -274.384008) (xy 331.459332 -274.397216) (xy 331.459332 -274.586192)
			(xy 331.459797 -274.595569) (xy 331.466631 -274.613038) (xy 331.479308 -274.626865) (xy 331.487526 -274.631404)
			(xy 331.518006 -274.645628) (xy 331.566266 -274.66798) (xy 331.56955 -274.669476) (xy 331.576432 -274.671648)
			(xy 331.579982 -274.672298) (xy 331.584357 -274.672849) (xy 331.593171 -274.672592) (xy 331.597508 -274.67179)
			(xy 331.605382 -274.669758) (xy 331.62367 -274.6629) (xy 331.63002 -274.65782) (xy 331.6505 -274.642108)
			(xy 331.695637 -274.617072) (xy 331.744339 -274.599977) (xy 331.795221 -274.591309) (xy 331.821028 -274.590764)
			(xy 331.846284 -274.591288) (xy 331.896107 -274.599606) (xy 331.943881 -274.616011) (xy 331.988304 -274.640055)
			(xy 332.028164 -274.671082) (xy 332.062373 -274.708247) (xy 332.089999 -274.750535) (xy 332.110289 -274.796793)
			(xy 332.122688 -274.84576) (xy 332.126857 -274.896072) (xy 332.455278 -274.896072) (xy 332.459238 -274.847018)
			(xy 332.471015 -274.799234) (xy 332.490306 -274.753958) (xy 332.516609 -274.712362) (xy 332.549244 -274.675525)
			(xy 332.587365 -274.6444) (xy 332.629986 -274.619793) (xy 332.676002 -274.602341) (xy 332.724221 -274.592497)
			(xy 332.773396 -274.590516) (xy 332.822251 -274.596448) (xy 332.869522 -274.61014) (xy 332.913984 -274.631238)
			(xy 332.954487 -274.659194) (xy 332.98998 -274.693286) (xy 333.019545 -274.73263) (xy 333.042416 -274.776207)
			(xy 333.058 -274.822888) (xy 333.065895 -274.871465) (xy 333.06639 -274.896072) (xy 333.395332 -274.896072)
			(xy 333.399292 -274.847018) (xy 333.411069 -274.799234) (xy 333.43036 -274.753958) (xy 333.456663 -274.712362)
			(xy 333.489298 -274.675525) (xy 333.527419 -274.6444) (xy 333.57004 -274.619793) (xy 333.616056 -274.602341)
			(xy 333.664275 -274.592497) (xy 333.71345 -274.590516) (xy 333.762305 -274.596448) (xy 333.809576 -274.61014)
			(xy 333.854038 -274.631238) (xy 333.894541 -274.659194) (xy 333.930034 -274.693286) (xy 333.959599 -274.73263)
			(xy 333.98247 -274.776207) (xy 333.998054 -274.822888) (xy 334.005949 -274.871465) (xy 334.006444 -274.896072)
			(xy 334.335386 -274.896072) (xy 334.339346 -274.847018) (xy 334.351123 -274.799234) (xy 334.370414 -274.753958)
			(xy 334.396717 -274.712362) (xy 334.429352 -274.675525) (xy 334.467473 -274.6444) (xy 334.510094 -274.619793)
			(xy 334.55611 -274.602341) (xy 334.604329 -274.592497) (xy 334.653504 -274.590516) (xy 334.702359 -274.596448)
			(xy 334.74963 -274.61014) (xy 334.794092 -274.631238) (xy 334.834595 -274.659194) (xy 334.870088 -274.693286)
			(xy 334.899653 -274.73263) (xy 334.922524 -274.776207) (xy 334.938108 -274.822888) (xy 334.946003 -274.871465)
			(xy 334.946498 -274.896072) (xy 335.275186 -274.896072) (xy 335.279146 -274.847018) (xy 335.290923 -274.799234)
			(xy 335.310214 -274.753958) (xy 335.336517 -274.712362) (xy 335.369152 -274.675525) (xy 335.407273 -274.6444)
			(xy 335.449894 -274.619793) (xy 335.49591 -274.602341) (xy 335.544129 -274.592497) (xy 335.593304 -274.590516)
			(xy 335.642159 -274.596448) (xy 335.68943 -274.61014) (xy 335.733892 -274.631238) (xy 335.774395 -274.659194)
			(xy 335.809888 -274.693286) (xy 335.839453 -274.73263) (xy 335.862324 -274.776207) (xy 335.877908 -274.822888)
			(xy 335.885803 -274.871465) (xy 335.886298 -274.896072) (xy 336.21524 -274.896072) (xy 336.2192 -274.847018)
			(xy 336.230977 -274.799234) (xy 336.250268 -274.753958) (xy 336.276571 -274.712362) (xy 336.309206 -274.675525)
			(xy 336.347327 -274.6444) (xy 336.389948 -274.619793) (xy 336.435964 -274.602341) (xy 336.484183 -274.592497)
			(xy 336.533358 -274.590516) (xy 336.582213 -274.596448) (xy 336.629484 -274.61014) (xy 336.673946 -274.631238)
			(xy 336.714449 -274.659194) (xy 336.749942 -274.693286) (xy 336.779507 -274.73263) (xy 336.802378 -274.776207)
			(xy 336.817962 -274.822888) (xy 336.825857 -274.871465) (xy 336.826352 -274.896072) (xy 337.155294 -274.896072)
			(xy 337.159254 -274.847018) (xy 337.171031 -274.799234) (xy 337.190322 -274.753958) (xy 337.216625 -274.712362)
			(xy 337.24926 -274.675525) (xy 337.287381 -274.6444) (xy 337.330002 -274.619793) (xy 337.376018 -274.602341)
			(xy 337.424237 -274.592497) (xy 337.473412 -274.590516) (xy 337.522267 -274.596448) (xy 337.569538 -274.61014)
			(xy 337.614 -274.631238) (xy 337.654503 -274.659194) (xy 337.689996 -274.693286) (xy 337.719561 -274.73263)
			(xy 337.742432 -274.776207) (xy 337.758016 -274.822888) (xy 337.765911 -274.871465) (xy 337.766406 -274.896072)
			(xy 338.095348 -274.896072) (xy 338.099308 -274.847018) (xy 338.111085 -274.799234) (xy 338.130376 -274.753958)
			(xy 338.156679 -274.712362) (xy 338.189314 -274.675525) (xy 338.227435 -274.6444) (xy 338.270056 -274.619793)
			(xy 338.316072 -274.602341) (xy 338.364291 -274.592497) (xy 338.413466 -274.590516) (xy 338.462321 -274.596448)
			(xy 338.509592 -274.61014) (xy 338.554054 -274.631238) (xy 338.594557 -274.659194) (xy 338.63005 -274.693286)
			(xy 338.659615 -274.73263) (xy 338.682486 -274.776207) (xy 338.69807 -274.822888) (xy 338.705965 -274.871465)
			(xy 338.70646 -274.896072) (xy 339.024971 -274.896072) (xy 339.029066 -274.845344) (xy 339.041245 -274.79593)
			(xy 339.061193 -274.74911) (xy 339.088394 -274.706096) (xy 339.122142 -274.668002) (xy 339.161564 -274.635815)
			(xy 339.205638 -274.610369) (xy 339.253224 -274.592322) (xy 339.303088 -274.582142) (xy 339.35394 -274.580093)
			(xy 339.404461 -274.586227) (xy 339.453345 -274.600387) (xy 339.499324 -274.622204) (xy 339.541208 -274.651114)
			(xy 339.577912 -274.686369) (xy 339.608485 -274.727055) (xy 339.632136 -274.772118) (xy 339.648252 -274.820392)
			(xy 339.656416 -274.870626) (xy 339.656928 -274.896072) (xy 339.656416 -274.921518) (xy 339.648252 -274.971752)
			(xy 339.632136 -275.020026) (xy 339.608485 -275.065089) (xy 339.577912 -275.105775) (xy 339.541208 -275.14103)
			(xy 339.499324 -275.16994) (xy 339.453345 -275.191757) (xy 339.404461 -275.205917) (xy 339.35394 -275.212051)
			(xy 339.303088 -275.210002) (xy 339.253224 -275.199822) (xy 339.205638 -275.181775) (xy 339.161564 -275.156329)
			(xy 339.122142 -275.124142) (xy 339.088394 -275.086048) (xy 339.061193 -275.043034) (xy 339.041245 -274.996214)
			(xy 339.029066 -274.9468) (xy 339.024971 -274.896072) (xy 338.70646 -274.896072) (xy 338.705965 -274.920679)
			(xy 338.69807 -274.969256) (xy 338.682486 -275.015937) (xy 338.659615 -275.059514) (xy 338.63005 -275.098858)
			(xy 338.594557 -275.13295) (xy 338.554054 -275.160906) (xy 338.509592 -275.182004) (xy 338.462321 -275.195696)
			(xy 338.413466 -275.201628) (xy 338.364291 -275.199647) (xy 338.316072 -275.189803) (xy 338.270056 -275.172351)
			(xy 338.227435 -275.147744) (xy 338.189314 -275.116619) (xy 338.156679 -275.079782) (xy 338.130376 -275.038186)
			(xy 338.111085 -274.99291) (xy 338.099308 -274.945126) (xy 338.095348 -274.896072) (xy 337.766406 -274.896072)
			(xy 337.765911 -274.920679) (xy 337.758016 -274.969256) (xy 337.742432 -275.015937) (xy 337.719561 -275.059514)
			(xy 337.689996 -275.098858) (xy 337.654503 -275.13295) (xy 337.614 -275.160906) (xy 337.569538 -275.182004)
			(xy 337.522267 -275.195696) (xy 337.473412 -275.201628) (xy 337.424237 -275.199647) (xy 337.376018 -275.189803)
			(xy 337.330002 -275.172351) (xy 337.287381 -275.147744) (xy 337.24926 -275.116619) (xy 337.216625 -275.079782)
			(xy 337.190322 -275.038186) (xy 337.171031 -274.99291) (xy 337.159254 -274.945126) (xy 337.155294 -274.896072)
			(xy 336.826352 -274.896072) (xy 336.825857 -274.920679) (xy 336.817962 -274.969256) (xy 336.802378 -275.015937)
			(xy 336.779507 -275.059514) (xy 336.749942 -275.098858) (xy 336.714449 -275.13295) (xy 336.673946 -275.160906)
			(xy 336.629484 -275.182004) (xy 336.582213 -275.195696) (xy 336.533358 -275.201628) (xy 336.484183 -275.199647)
			(xy 336.435964 -275.189803) (xy 336.389948 -275.172351) (xy 336.347327 -275.147744) (xy 336.309206 -275.116619)
			(xy 336.276571 -275.079782) (xy 336.250268 -275.038186) (xy 336.230977 -274.99291) (xy 336.2192 -274.945126)
			(xy 336.21524 -274.896072) (xy 335.886298 -274.896072) (xy 335.885803 -274.920679) (xy 335.877908 -274.969256)
			(xy 335.862324 -275.015937) (xy 335.839453 -275.059514) (xy 335.809888 -275.098858) (xy 335.774395 -275.13295)
			(xy 335.733892 -275.160906) (xy 335.68943 -275.182004) (xy 335.642159 -275.195696) (xy 335.593304 -275.201628)
			(xy 335.544129 -275.199647) (xy 335.49591 -275.189803) (xy 335.449894 -275.172351) (xy 335.407273 -275.147744)
			(xy 335.369152 -275.116619) (xy 335.336517 -275.079782) (xy 335.310214 -275.038186) (xy 335.290923 -274.99291)
			(xy 335.279146 -274.945126) (xy 335.275186 -274.896072) (xy 334.946498 -274.896072) (xy 334.946003 -274.920679)
			(xy 334.938108 -274.969256) (xy 334.922524 -275.015937) (xy 334.899653 -275.059514) (xy 334.870088 -275.098858)
			(xy 334.834595 -275.13295) (xy 334.794092 -275.160906) (xy 334.74963 -275.182004) (xy 334.702359 -275.195696)
			(xy 334.653504 -275.201628) (xy 334.604329 -275.199647) (xy 334.55611 -275.189803) (xy 334.510094 -275.172351)
			(xy 334.467473 -275.147744) (xy 334.429352 -275.116619) (xy 334.396717 -275.079782) (xy 334.370414 -275.038186)
			(xy 334.351123 -274.99291) (xy 334.339346 -274.945126) (xy 334.335386 -274.896072) (xy 334.006444 -274.896072)
			(xy 334.005949 -274.920679) (xy 333.998054 -274.969256) (xy 333.98247 -275.015937) (xy 333.959599 -275.059514)
			(xy 333.930034 -275.098858) (xy 333.894541 -275.13295) (xy 333.854038 -275.160906) (xy 333.809576 -275.182004)
			(xy 333.762305 -275.195696) (xy 333.71345 -275.201628) (xy 333.664275 -275.199647) (xy 333.616056 -275.189803)
			(xy 333.57004 -275.172351) (xy 333.527419 -275.147744) (xy 333.489298 -275.116619) (xy 333.456663 -275.079782)
			(xy 333.43036 -275.038186) (xy 333.411069 -274.99291) (xy 333.399292 -274.945126) (xy 333.395332 -274.896072)
			(xy 333.06639 -274.896072) (xy 333.065895 -274.920679) (xy 333.058 -274.969256) (xy 333.042416 -275.015937)
			(xy 333.019545 -275.059514) (xy 332.98998 -275.098858) (xy 332.954487 -275.13295) (xy 332.913984 -275.160906)
			(xy 332.869522 -275.182004) (xy 332.822251 -275.195696) (xy 332.773396 -275.201628) (xy 332.724221 -275.199647)
			(xy 332.676002 -275.189803) (xy 332.629986 -275.172351) (xy 332.587365 -275.147744) (xy 332.549244 -275.116619)
			(xy 332.516609 -275.079782) (xy 332.490306 -275.038186) (xy 332.471015 -274.99291) (xy 332.459238 -274.945126)
			(xy 332.455278 -274.896072) (xy 332.126857 -274.896072) (xy 332.126859 -274.8961) (xy 332.122688 -274.94644)
			(xy 332.110289 -274.995407) (xy 332.089999 -275.041665) (xy 332.062373 -275.083953) (xy 332.028164 -275.121118)
			(xy 331.988304 -275.152145) (xy 331.943881 -275.176189) (xy 331.896107 -275.192594) (xy 331.846284 -275.200912)
			(xy 331.821028 -275.20138) (xy 331.808265 -275.20124) (xy 331.782832 -275.199075) (xy 331.770228 -275.197062)
			(xy 331.743541 -275.19198) (xy 331.692411 -275.173642) (xy 331.645337 -275.146537) (xy 331.624178 -275.129498)
			(xy 331.61859 -275.124926) (xy 331.605636 -275.119084) (xy 331.59827 -275.118068) (xy 331.591061 -275.117387)
			(xy 331.576754 -275.119585) (xy 331.570076 -275.122386) (xy 331.487018 -275.16074) (xy 331.479149 -275.16518)
			(xy 331.466925 -275.17847) (xy 331.460048 -275.195166) (xy 331.459332 -275.204174) (xy 331.459332 -275.387816)
			(xy 331.459578 -275.394765) (xy 331.463325 -275.40815) (xy 331.466698 -275.414232) (xy 331.47 -275.419312)
			(xy 331.480414 -275.428964) (xy 331.487526 -275.43252) (xy 331.508977 -275.443747) (xy 331.548341 -275.471933)
			(xy 331.582772 -275.505968) (xy 331.61141 -275.545004) (xy 331.633539 -275.588065) (xy 331.648607 -275.634074)
			(xy 331.656237 -275.681883) (xy 331.656238 -275.706078) (xy 331.985378 -275.706078) (xy 331.989338 -275.657024)
			(xy 332.001115 -275.60924) (xy 332.020406 -275.563964) (xy 332.046709 -275.522368) (xy 332.079344 -275.485531)
			(xy 332.117465 -275.454406) (xy 332.160086 -275.429799) (xy 332.206102 -275.412347) (xy 332.254321 -275.402503)
			(xy 332.303496 -275.400522) (xy 332.352351 -275.406454) (xy 332.399622 -275.420146) (xy 332.444084 -275.441244)
			(xy 332.484587 -275.4692) (xy 332.52008 -275.503292) (xy 332.549645 -275.542636) (xy 332.572516 -275.586213)
			(xy 332.5881 -275.632894) (xy 332.595995 -275.681471) (xy 332.59649 -275.706078) (xy 332.925178 -275.706078)
			(xy 332.929138 -275.657024) (xy 332.940915 -275.60924) (xy 332.960206 -275.563964) (xy 332.986509 -275.522368)
			(xy 333.019144 -275.485531) (xy 333.057265 -275.454406) (xy 333.099886 -275.429799) (xy 333.145902 -275.412347)
			(xy 333.194121 -275.402503) (xy 333.243296 -275.400522) (xy 333.292151 -275.406454) (xy 333.339422 -275.420146)
			(xy 333.383884 -275.441244) (xy 333.424387 -275.4692) (xy 333.45988 -275.503292) (xy 333.489445 -275.542636)
			(xy 333.512316 -275.586213) (xy 333.5279 -275.632894) (xy 333.535795 -275.681471) (xy 333.53629 -275.706078)
			(xy 333.865232 -275.706078) (xy 333.869192 -275.657024) (xy 333.880969 -275.60924) (xy 333.90026 -275.563964)
			(xy 333.926563 -275.522368) (xy 333.959198 -275.485531) (xy 333.997319 -275.454406) (xy 334.03994 -275.429799)
			(xy 334.085956 -275.412347) (xy 334.134175 -275.402503) (xy 334.18335 -275.400522) (xy 334.232205 -275.406454)
			(xy 334.279476 -275.420146) (xy 334.323938 -275.441244) (xy 334.364441 -275.4692) (xy 334.399934 -275.503292)
			(xy 334.429499 -275.542636) (xy 334.45237 -275.586213) (xy 334.467954 -275.632894) (xy 334.475849 -275.681471)
			(xy 334.476344 -275.706078) (xy 335.74534 -275.706078) (xy 335.7493 -275.657024) (xy 335.761077 -275.60924)
			(xy 335.780368 -275.563964) (xy 335.806671 -275.522368) (xy 335.839306 -275.485531) (xy 335.877427 -275.454406)
			(xy 335.920048 -275.429799) (xy 335.966064 -275.412347) (xy 336.014283 -275.402503) (xy 336.063458 -275.400522)
			(xy 336.112313 -275.406454) (xy 336.159584 -275.420146) (xy 336.204046 -275.441244) (xy 336.244549 -275.4692)
			(xy 336.280042 -275.503292) (xy 336.309607 -275.542636) (xy 336.332478 -275.586213) (xy 336.348062 -275.632894)
			(xy 336.355957 -275.681471) (xy 336.356452 -275.706078) (xy 336.685394 -275.706078) (xy 336.689354 -275.657024)
			(xy 336.701131 -275.60924) (xy 336.720422 -275.563964) (xy 336.746725 -275.522368) (xy 336.77936 -275.485531)
			(xy 336.817481 -275.454406) (xy 336.860102 -275.429799) (xy 336.906118 -275.412347) (xy 336.954337 -275.402503)
			(xy 337.003512 -275.400522) (xy 337.052367 -275.406454) (xy 337.099638 -275.420146) (xy 337.1441 -275.441244)
			(xy 337.184603 -275.4692) (xy 337.220096 -275.503292) (xy 337.249661 -275.542636) (xy 337.272532 -275.586213)
			(xy 337.288116 -275.632894) (xy 337.296011 -275.681471) (xy 337.296506 -275.706078) (xy 337.625194 -275.706078)
			(xy 337.629154 -275.657024) (xy 337.640931 -275.60924) (xy 337.660222 -275.563964) (xy 337.686525 -275.522368)
			(xy 337.71916 -275.485531) (xy 337.757281 -275.454406) (xy 337.799902 -275.429799) (xy 337.845918 -275.412347)
			(xy 337.894137 -275.402503) (xy 337.943312 -275.400522) (xy 337.992167 -275.406454) (xy 338.039438 -275.420146)
			(xy 338.0839 -275.441244) (xy 338.124403 -275.4692) (xy 338.159896 -275.503292) (xy 338.189461 -275.542636)
			(xy 338.212332 -275.586213) (xy 338.227916 -275.632894) (xy 338.235811 -275.681471) (xy 338.236306 -275.706078)
			(xy 338.554817 -275.706078) (xy 338.558912 -275.65535) (xy 338.571091 -275.605936) (xy 338.591039 -275.559116)
			(xy 338.61824 -275.516102) (xy 338.651988 -275.478008) (xy 338.69141 -275.445821) (xy 338.735484 -275.420375)
			(xy 338.78307 -275.402328) (xy 338.832934 -275.392148) (xy 338.883786 -275.390099) (xy 338.934307 -275.396233)
			(xy 338.983191 -275.410393) (xy 339.02917 -275.43221) (xy 339.071054 -275.46112) (xy 339.107758 -275.496375)
			(xy 339.138331 -275.537061) (xy 339.161982 -275.582124) (xy 339.178098 -275.630398) (xy 339.186262 -275.680632)
			(xy 339.186774 -275.706078) (xy 339.186262 -275.731524) (xy 339.178098 -275.781758) (xy 339.161982 -275.830032)
			(xy 339.138331 -275.875095) (xy 339.107758 -275.915781) (xy 339.071054 -275.951036) (xy 339.02917 -275.979946)
			(xy 338.983191 -276.001763) (xy 338.934307 -276.015923) (xy 338.883786 -276.022057) (xy 338.832934 -276.020008)
			(xy 338.78307 -276.009828) (xy 338.735484 -275.991781) (xy 338.69141 -275.966335) (xy 338.651988 -275.934148)
			(xy 338.61824 -275.896054) (xy 338.591039 -275.85304) (xy 338.571091 -275.80622) (xy 338.558912 -275.756806)
			(xy 338.554817 -275.706078) (xy 338.236306 -275.706078) (xy 338.235811 -275.730685) (xy 338.227916 -275.779262)
			(xy 338.212332 -275.825943) (xy 338.189461 -275.86952) (xy 338.159896 -275.908864) (xy 338.124403 -275.942956)
			(xy 338.0839 -275.970912) (xy 338.039438 -275.99201) (xy 337.992167 -276.005702) (xy 337.943312 -276.011634)
			(xy 337.894137 -276.009653) (xy 337.845918 -275.999809) (xy 337.799902 -275.982357) (xy 337.757281 -275.95775)
			(xy 337.71916 -275.926625) (xy 337.686525 -275.889788) (xy 337.660222 -275.848192) (xy 337.640931 -275.802916)
			(xy 337.629154 -275.755132) (xy 337.625194 -275.706078) (xy 337.296506 -275.706078) (xy 337.296011 -275.730685)
			(xy 337.288116 -275.779262) (xy 337.272532 -275.825943) (xy 337.249661 -275.86952) (xy 337.220096 -275.908864)
			(xy 337.184603 -275.942956) (xy 337.1441 -275.970912) (xy 337.099638 -275.99201) (xy 337.052367 -276.005702)
			(xy 337.003512 -276.011634) (xy 336.954337 -276.009653) (xy 336.906118 -275.999809) (xy 336.860102 -275.982357)
			(xy 336.817481 -275.95775) (xy 336.77936 -275.926625) (xy 336.746725 -275.889788) (xy 336.720422 -275.848192)
			(xy 336.701131 -275.802916) (xy 336.689354 -275.755132) (xy 336.685394 -275.706078) (xy 336.356452 -275.706078)
			(xy 336.355957 -275.730685) (xy 336.348062 -275.779262) (xy 336.332478 -275.825943) (xy 336.309607 -275.86952)
			(xy 336.280042 -275.908864) (xy 336.244549 -275.942956) (xy 336.204046 -275.970912) (xy 336.159584 -275.99201)
			(xy 336.112313 -276.005702) (xy 336.063458 -276.011634) (xy 336.014283 -276.009653) (xy 335.966064 -275.999809)
			(xy 335.920048 -275.982357) (xy 335.877427 -275.95775) (xy 335.839306 -275.926625) (xy 335.806671 -275.889788)
			(xy 335.780368 -275.848192) (xy 335.761077 -275.802916) (xy 335.7493 -275.755132) (xy 335.74534 -275.706078)
			(xy 334.476344 -275.706078) (xy 334.475849 -275.730685) (xy 334.467954 -275.779262) (xy 334.45237 -275.825943)
			(xy 334.429499 -275.86952) (xy 334.399934 -275.908864) (xy 334.364441 -275.942956) (xy 334.323938 -275.970912)
			(xy 334.279476 -275.99201) (xy 334.232205 -276.005702) (xy 334.18335 -276.011634) (xy 334.134175 -276.009653)
			(xy 334.085956 -275.999809) (xy 334.03994 -275.982357) (xy 333.997319 -275.95775) (xy 333.959198 -275.926625)
			(xy 333.926563 -275.889788) (xy 333.90026 -275.848192) (xy 333.880969 -275.802916) (xy 333.869192 -275.755132)
			(xy 333.865232 -275.706078) (xy 333.53629 -275.706078) (xy 333.535795 -275.730685) (xy 333.5279 -275.779262)
			(xy 333.512316 -275.825943) (xy 333.489445 -275.86952) (xy 333.45988 -275.908864) (xy 333.424387 -275.942956)
			(xy 333.383884 -275.970912) (xy 333.339422 -275.99201) (xy 333.292151 -276.005702) (xy 333.243296 -276.011634)
			(xy 333.194121 -276.009653) (xy 333.145902 -275.999809) (xy 333.099886 -275.982357) (xy 333.057265 -275.95775)
			(xy 333.019144 -275.926625) (xy 332.986509 -275.889788) (xy 332.960206 -275.848192) (xy 332.940915 -275.802916)
			(xy 332.929138 -275.755132) (xy 332.925178 -275.706078) (xy 332.59649 -275.706078) (xy 332.595995 -275.730685)
			(xy 332.5881 -275.779262) (xy 332.572516 -275.825943) (xy 332.549645 -275.86952) (xy 332.52008 -275.908864)
			(xy 332.484587 -275.942956) (xy 332.444084 -275.970912) (xy 332.399622 -275.99201) (xy 332.352351 -276.005702)
			(xy 332.303496 -276.011634) (xy 332.254321 -276.009653) (xy 332.206102 -275.999809) (xy 332.160086 -275.982357)
			(xy 332.117465 -275.95775) (xy 332.079344 -275.926625) (xy 332.046709 -275.889788) (xy 332.020406 -275.848192)
			(xy 332.001115 -275.802916) (xy 331.989338 -275.755132) (xy 331.985378 -275.706078) (xy 331.656238 -275.706078)
			(xy 331.656239 -275.730297) (xy 331.648612 -275.778107) (xy 331.633547 -275.824117) (xy 331.61142 -275.867179)
			(xy 331.582785 -275.906217) (xy 331.548356 -275.940255) (xy 331.508994 -275.968442) (xy 331.487526 -275.979636)
			(xy 331.486764 -275.97989) (xy 331.480506 -275.983292) (xy 331.470055 -275.992958) (xy 331.46619 -275.99894)
			(xy 331.463142 -276.00402) (xy 331.459332 -276.017228) (xy 331.459332 -276.206204) (xy 331.459799 -276.21558)
			(xy 331.466635 -276.233046) (xy 331.479313 -276.246869) (xy 331.487526 -276.251416) (xy 331.518006 -276.26564)
			(xy 331.566266 -276.287992) (xy 331.56955 -276.289488) (xy 331.576432 -276.291659) (xy 331.579982 -276.29231)
			(xy 331.584357 -276.292861) (xy 331.593171 -276.292604) (xy 331.597508 -276.291802) (xy 331.605382 -276.28977)
			(xy 331.62367 -276.282912) (xy 331.63002 -276.277832) (xy 331.6505 -276.262119) (xy 331.695636 -276.237083)
			(xy 331.744338 -276.219987) (xy 331.79522 -276.211319) (xy 331.821028 -276.210776) (xy 331.846283 -276.2113)
			(xy 331.896104 -276.219618) (xy 331.943876 -276.236022) (xy 331.988297 -276.260065) (xy 332.028155 -276.291091)
			(xy 332.062364 -276.328254) (xy 332.089989 -276.370541) (xy 332.110277 -276.416797) (xy 332.122676 -276.465762)
			(xy 332.126846 -276.516084) (xy 332.455278 -276.516084) (xy 332.459238 -276.46703) (xy 332.471015 -276.419246)
			(xy 332.490306 -276.37397) (xy 332.516609 -276.332374) (xy 332.549244 -276.295537) (xy 332.587365 -276.264412)
			(xy 332.629986 -276.239805) (xy 332.676002 -276.222353) (xy 332.724221 -276.212509) (xy 332.773396 -276.210528)
			(xy 332.822251 -276.21646) (xy 332.869522 -276.230152) (xy 332.913984 -276.25125) (xy 332.954487 -276.279206)
			(xy 332.98998 -276.313298) (xy 333.019545 -276.352642) (xy 333.042416 -276.396219) (xy 333.058 -276.4429)
			(xy 333.065895 -276.491477) (xy 333.06639 -276.516084) (xy 333.395332 -276.516084) (xy 333.399292 -276.46703)
			(xy 333.411069 -276.419246) (xy 333.43036 -276.37397) (xy 333.456663 -276.332374) (xy 333.489298 -276.295537)
			(xy 333.527419 -276.264412) (xy 333.57004 -276.239805) (xy 333.616056 -276.222353) (xy 333.664275 -276.212509)
			(xy 333.71345 -276.210528) (xy 333.762305 -276.21646) (xy 333.809576 -276.230152) (xy 333.854038 -276.25125)
			(xy 333.894541 -276.279206) (xy 333.930034 -276.313298) (xy 333.959599 -276.352642) (xy 333.98247 -276.396219)
			(xy 333.998054 -276.4429) (xy 334.005949 -276.491477) (xy 334.006444 -276.516084) (xy 334.335386 -276.516084)
			(xy 334.339346 -276.46703) (xy 334.351123 -276.419246) (xy 334.370414 -276.37397) (xy 334.396717 -276.332374)
			(xy 334.429352 -276.295537) (xy 334.467473 -276.264412) (xy 334.510094 -276.239805) (xy 334.55611 -276.222353)
			(xy 334.604329 -276.212509) (xy 334.653504 -276.210528) (xy 334.702359 -276.21646) (xy 334.74963 -276.230152)
			(xy 334.794092 -276.25125) (xy 334.834595 -276.279206) (xy 334.870088 -276.313298) (xy 334.899653 -276.352642)
			(xy 334.922524 -276.396219) (xy 334.938108 -276.4429) (xy 334.946003 -276.491477) (xy 334.946498 -276.516084)
			(xy 335.275186 -276.516084) (xy 335.279146 -276.46703) (xy 335.290923 -276.419246) (xy 335.310214 -276.37397)
			(xy 335.336517 -276.332374) (xy 335.369152 -276.295537) (xy 335.407273 -276.264412) (xy 335.449894 -276.239805)
			(xy 335.49591 -276.222353) (xy 335.544129 -276.212509) (xy 335.593304 -276.210528) (xy 335.642159 -276.21646)
			(xy 335.68943 -276.230152) (xy 335.733892 -276.25125) (xy 335.774395 -276.279206) (xy 335.809888 -276.313298)
			(xy 335.839453 -276.352642) (xy 335.862324 -276.396219) (xy 335.877908 -276.4429) (xy 335.885803 -276.491477)
			(xy 335.886298 -276.516084) (xy 336.21524 -276.516084) (xy 336.2192 -276.46703) (xy 336.230977 -276.419246)
			(xy 336.250268 -276.37397) (xy 336.276571 -276.332374) (xy 336.309206 -276.295537) (xy 336.347327 -276.264412)
			(xy 336.389948 -276.239805) (xy 336.435964 -276.222353) (xy 336.484183 -276.212509) (xy 336.533358 -276.210528)
			(xy 336.582213 -276.21646) (xy 336.629484 -276.230152) (xy 336.673946 -276.25125) (xy 336.714449 -276.279206)
			(xy 336.749942 -276.313298) (xy 336.779507 -276.352642) (xy 336.802378 -276.396219) (xy 336.817962 -276.4429)
			(xy 336.825857 -276.491477) (xy 336.826352 -276.516084) (xy 337.155294 -276.516084) (xy 337.159254 -276.46703)
			(xy 337.171031 -276.419246) (xy 337.190322 -276.37397) (xy 337.216625 -276.332374) (xy 337.24926 -276.295537)
			(xy 337.287381 -276.264412) (xy 337.330002 -276.239805) (xy 337.376018 -276.222353) (xy 337.424237 -276.212509)
			(xy 337.473412 -276.210528) (xy 337.522267 -276.21646) (xy 337.569538 -276.230152) (xy 337.614 -276.25125)
			(xy 337.654503 -276.279206) (xy 337.689996 -276.313298) (xy 337.719561 -276.352642) (xy 337.742432 -276.396219)
			(xy 337.758016 -276.4429) (xy 337.765911 -276.491477) (xy 337.766406 -276.516084) (xy 338.095348 -276.516084)
			(xy 338.099308 -276.46703) (xy 338.111085 -276.419246) (xy 338.130376 -276.37397) (xy 338.156679 -276.332374)
			(xy 338.189314 -276.295537) (xy 338.227435 -276.264412) (xy 338.270056 -276.239805) (xy 338.316072 -276.222353)
			(xy 338.364291 -276.212509) (xy 338.413466 -276.210528) (xy 338.462321 -276.21646) (xy 338.509592 -276.230152)
			(xy 338.554054 -276.25125) (xy 338.594557 -276.279206) (xy 338.63005 -276.313298) (xy 338.659615 -276.352642)
			(xy 338.682486 -276.396219) (xy 338.69807 -276.4429) (xy 338.705965 -276.491477) (xy 338.70646 -276.516084)
			(xy 338.705965 -276.540691) (xy 338.69807 -276.589268) (xy 338.682486 -276.635949) (xy 338.659615 -276.679526)
			(xy 338.63005 -276.71887) (xy 338.594557 -276.752962) (xy 338.554054 -276.780918) (xy 338.509592 -276.802016)
			(xy 338.462321 -276.815708) (xy 338.413466 -276.82164) (xy 338.364291 -276.819659) (xy 338.316072 -276.809815)
			(xy 338.270056 -276.792363) (xy 338.227435 -276.767756) (xy 338.189314 -276.736631) (xy 338.156679 -276.699794)
			(xy 338.130376 -276.658198) (xy 338.111085 -276.612922) (xy 338.099308 -276.565138) (xy 338.095348 -276.516084)
			(xy 337.766406 -276.516084) (xy 337.765911 -276.540691) (xy 337.758016 -276.589268) (xy 337.742432 -276.635949)
			(xy 337.719561 -276.679526) (xy 337.689996 -276.71887) (xy 337.654503 -276.752962) (xy 337.614 -276.780918)
			(xy 337.569538 -276.802016) (xy 337.522267 -276.815708) (xy 337.473412 -276.82164) (xy 337.424237 -276.819659)
			(xy 337.376018 -276.809815) (xy 337.330002 -276.792363) (xy 337.287381 -276.767756) (xy 337.24926 -276.736631)
			(xy 337.216625 -276.699794) (xy 337.190322 -276.658198) (xy 337.171031 -276.612922) (xy 337.159254 -276.565138)
			(xy 337.155294 -276.516084) (xy 336.826352 -276.516084) (xy 336.825857 -276.540691) (xy 336.817962 -276.589268)
			(xy 336.802378 -276.635949) (xy 336.779507 -276.679526) (xy 336.749942 -276.71887) (xy 336.714449 -276.752962)
			(xy 336.673946 -276.780918) (xy 336.629484 -276.802016) (xy 336.582213 -276.815708) (xy 336.533358 -276.82164)
			(xy 336.484183 -276.819659) (xy 336.435964 -276.809815) (xy 336.389948 -276.792363) (xy 336.347327 -276.767756)
			(xy 336.309206 -276.736631) (xy 336.276571 -276.699794) (xy 336.250268 -276.658198) (xy 336.230977 -276.612922)
			(xy 336.2192 -276.565138) (xy 336.21524 -276.516084) (xy 335.886298 -276.516084) (xy 335.885803 -276.540691)
			(xy 335.877908 -276.589268) (xy 335.862324 -276.635949) (xy 335.839453 -276.679526) (xy 335.809888 -276.71887)
			(xy 335.774395 -276.752962) (xy 335.733892 -276.780918) (xy 335.68943 -276.802016) (xy 335.642159 -276.815708)
			(xy 335.593304 -276.82164) (xy 335.544129 -276.819659) (xy 335.49591 -276.809815) (xy 335.449894 -276.792363)
			(xy 335.407273 -276.767756) (xy 335.369152 -276.736631) (xy 335.336517 -276.699794) (xy 335.310214 -276.658198)
			(xy 335.290923 -276.612922) (xy 335.279146 -276.565138) (xy 335.275186 -276.516084) (xy 334.946498 -276.516084)
			(xy 334.946003 -276.540691) (xy 334.938108 -276.589268) (xy 334.922524 -276.635949) (xy 334.899653 -276.679526)
			(xy 334.870088 -276.71887) (xy 334.834595 -276.752962) (xy 334.794092 -276.780918) (xy 334.74963 -276.802016)
			(xy 334.702359 -276.815708) (xy 334.653504 -276.82164) (xy 334.604329 -276.819659) (xy 334.55611 -276.809815)
			(xy 334.510094 -276.792363) (xy 334.467473 -276.767756) (xy 334.429352 -276.736631) (xy 334.396717 -276.699794)
			(xy 334.370414 -276.658198) (xy 334.351123 -276.612922) (xy 334.339346 -276.565138) (xy 334.335386 -276.516084)
			(xy 334.006444 -276.516084) (xy 334.005949 -276.540691) (xy 333.998054 -276.589268) (xy 333.98247 -276.635949)
			(xy 333.959599 -276.679526) (xy 333.930034 -276.71887) (xy 333.894541 -276.752962) (xy 333.854038 -276.780918)
			(xy 333.809576 -276.802016) (xy 333.762305 -276.815708) (xy 333.71345 -276.82164) (xy 333.664275 -276.819659)
			(xy 333.616056 -276.809815) (xy 333.57004 -276.792363) (xy 333.527419 -276.767756) (xy 333.489298 -276.736631)
			(xy 333.456663 -276.699794) (xy 333.43036 -276.658198) (xy 333.411069 -276.612922) (xy 333.399292 -276.565138)
			(xy 333.395332 -276.516084) (xy 333.06639 -276.516084) (xy 333.065895 -276.540691) (xy 333.058 -276.589268)
			(xy 333.042416 -276.635949) (xy 333.019545 -276.679526) (xy 332.98998 -276.71887) (xy 332.954487 -276.752962)
			(xy 332.913984 -276.780918) (xy 332.869522 -276.802016) (xy 332.822251 -276.815708) (xy 332.773396 -276.82164)
			(xy 332.724221 -276.819659) (xy 332.676002 -276.809815) (xy 332.629986 -276.792363) (xy 332.587365 -276.767756)
			(xy 332.549244 -276.736631) (xy 332.516609 -276.699794) (xy 332.490306 -276.658198) (xy 332.471015 -276.612922)
			(xy 332.459238 -276.565138) (xy 332.455278 -276.516084) (xy 332.126846 -276.516084) (xy 332.126847 -276.5161)
			(xy 332.122676 -276.566438) (xy 332.110277 -276.615403) (xy 332.089989 -276.661659) (xy 332.062364 -276.703946)
			(xy 332.028155 -276.741109) (xy 331.988297 -276.772135) (xy 331.943876 -276.796178) (xy 331.896104 -276.812582)
			(xy 331.846283 -276.8209) (xy 331.821028 -276.821392) (xy 331.808265 -276.821252) (xy 331.782832 -276.819086)
			(xy 331.770228 -276.817074) (xy 331.743541 -276.811992) (xy 331.69241 -276.793654) (xy 331.645335 -276.766551)
			(xy 331.624178 -276.74951) (xy 331.61859 -276.744938) (xy 331.605636 -276.739096) (xy 331.59827 -276.73808)
			(xy 331.591061 -276.737398) (xy 331.576754 -276.739597) (xy 331.570076 -276.742398) (xy 331.487018 -276.780752)
			(xy 331.47915 -276.785193) (xy 331.466929 -276.798483) (xy 331.460056 -276.815179) (xy 331.459332 -276.824186)
			(xy 331.459332 -277.007828) (xy 331.459566 -277.014781) (xy 331.463293 -277.028178) (xy 331.466698 -277.034244)
			(xy 331.47 -277.039324) (xy 331.480414 -277.048976) (xy 331.487526 -277.052532) (xy 331.508976 -277.063759)
			(xy 331.548338 -277.091944) (xy 331.582767 -277.125979) (xy 331.611403 -277.165014) (xy 331.633531 -277.208074)
			(xy 331.648598 -277.254082) (xy 331.656227 -277.301889) (xy 331.656227 -277.32609) (xy 331.985378 -277.32609)
			(xy 331.989338 -277.277036) (xy 332.001115 -277.229252) (xy 332.020406 -277.183976) (xy 332.046709 -277.14238)
			(xy 332.079344 -277.105543) (xy 332.117465 -277.074418) (xy 332.160086 -277.049811) (xy 332.206102 -277.032359)
			(xy 332.254321 -277.022515) (xy 332.303496 -277.020534) (xy 332.352351 -277.026466) (xy 332.399622 -277.040158)
			(xy 332.444084 -277.061256) (xy 332.484587 -277.089212) (xy 332.52008 -277.123304) (xy 332.549645 -277.162648)
			(xy 332.572516 -277.206225) (xy 332.5881 -277.252906) (xy 332.595995 -277.301483) (xy 332.59649 -277.32609)
			(xy 332.925178 -277.32609) (xy 332.929138 -277.277036) (xy 332.940915 -277.229252) (xy 332.960206 -277.183976)
			(xy 332.986509 -277.14238) (xy 333.019144 -277.105543) (xy 333.057265 -277.074418) (xy 333.099886 -277.049811)
			(xy 333.145902 -277.032359) (xy 333.194121 -277.022515) (xy 333.243296 -277.020534) (xy 333.292151 -277.026466)
			(xy 333.339422 -277.040158) (xy 333.383884 -277.061256) (xy 333.424387 -277.089212) (xy 333.45988 -277.123304)
			(xy 333.489445 -277.162648) (xy 333.512316 -277.206225) (xy 333.5279 -277.252906) (xy 333.535795 -277.301483)
			(xy 333.53629 -277.32609) (xy 333.865232 -277.32609) (xy 333.869192 -277.277036) (xy 333.880969 -277.229252)
			(xy 333.90026 -277.183976) (xy 333.926563 -277.14238) (xy 333.959198 -277.105543) (xy 333.997319 -277.074418)
			(xy 334.03994 -277.049811) (xy 334.085956 -277.032359) (xy 334.134175 -277.022515) (xy 334.18335 -277.020534)
			(xy 334.232205 -277.026466) (xy 334.279476 -277.040158) (xy 334.323938 -277.061256) (xy 334.364441 -277.089212)
			(xy 334.399934 -277.123304) (xy 334.429499 -277.162648) (xy 334.45237 -277.206225) (xy 334.467954 -277.252906)
			(xy 334.475849 -277.301483) (xy 334.476344 -277.32609) (xy 334.805286 -277.32609) (xy 334.809246 -277.277036)
			(xy 334.821023 -277.229252) (xy 334.840314 -277.183976) (xy 334.866617 -277.14238) (xy 334.899252 -277.105543)
			(xy 334.937373 -277.074418) (xy 334.979994 -277.049811) (xy 335.02601 -277.032359) (xy 335.074229 -277.022515)
			(xy 335.123404 -277.020534) (xy 335.172259 -277.026466) (xy 335.21953 -277.040158) (xy 335.263992 -277.061256)
			(xy 335.304495 -277.089212) (xy 335.339988 -277.123304) (xy 335.369553 -277.162648) (xy 335.392424 -277.206225)
			(xy 335.408008 -277.252906) (xy 335.415903 -277.301483) (xy 335.416398 -277.32609) (xy 335.74534 -277.32609)
			(xy 335.7493 -277.277036) (xy 335.761077 -277.229252) (xy 335.780368 -277.183976) (xy 335.806671 -277.14238)
			(xy 335.839306 -277.105543) (xy 335.877427 -277.074418) (xy 335.920048 -277.049811) (xy 335.966064 -277.032359)
			(xy 336.014283 -277.022515) (xy 336.063458 -277.020534) (xy 336.112313 -277.026466) (xy 336.159584 -277.040158)
			(xy 336.204046 -277.061256) (xy 336.244549 -277.089212) (xy 336.280042 -277.123304) (xy 336.309607 -277.162648)
			(xy 336.332478 -277.206225) (xy 336.348062 -277.252906) (xy 336.355957 -277.301483) (xy 336.356452 -277.32609)
			(xy 336.685394 -277.32609) (xy 336.689354 -277.277036) (xy 336.701131 -277.229252) (xy 336.720422 -277.183976)
			(xy 336.746725 -277.14238) (xy 336.77936 -277.105543) (xy 336.817481 -277.074418) (xy 336.860102 -277.049811)
			(xy 336.906118 -277.032359) (xy 336.954337 -277.022515) (xy 337.003512 -277.020534) (xy 337.052367 -277.026466)
			(xy 337.099638 -277.040158) (xy 337.1441 -277.061256) (xy 337.184603 -277.089212) (xy 337.220096 -277.123304)
			(xy 337.249661 -277.162648) (xy 337.272532 -277.206225) (xy 337.288116 -277.252906) (xy 337.296011 -277.301483)
			(xy 337.296506 -277.32609) (xy 337.625194 -277.32609) (xy 337.629154 -277.277036) (xy 337.640931 -277.229252)
			(xy 337.660222 -277.183976) (xy 337.686525 -277.14238) (xy 337.71916 -277.105543) (xy 337.757281 -277.074418)
			(xy 337.799902 -277.049811) (xy 337.845918 -277.032359) (xy 337.894137 -277.022515) (xy 337.943312 -277.020534)
			(xy 337.992167 -277.026466) (xy 338.039438 -277.040158) (xy 338.0839 -277.061256) (xy 338.124403 -277.089212)
			(xy 338.159896 -277.123304) (xy 338.189461 -277.162648) (xy 338.212332 -277.206225) (xy 338.227916 -277.252906)
			(xy 338.235811 -277.301483) (xy 338.236306 -277.32609) (xy 338.235811 -277.350697) (xy 338.227916 -277.399274)
			(xy 338.212332 -277.445955) (xy 338.189461 -277.489532) (xy 338.159896 -277.528876) (xy 338.124403 -277.562968)
			(xy 338.0839 -277.590924) (xy 338.039438 -277.612022) (xy 337.992167 -277.625714) (xy 337.943312 -277.631646)
			(xy 337.894137 -277.629665) (xy 337.845918 -277.619821) (xy 337.799902 -277.602369) (xy 337.757281 -277.577762)
			(xy 337.71916 -277.546637) (xy 337.686525 -277.5098) (xy 337.660222 -277.468204) (xy 337.640931 -277.422928)
			(xy 337.629154 -277.375144) (xy 337.625194 -277.32609) (xy 337.296506 -277.32609) (xy 337.296011 -277.350697)
			(xy 337.288116 -277.399274) (xy 337.272532 -277.445955) (xy 337.249661 -277.489532) (xy 337.220096 -277.528876)
			(xy 337.184603 -277.562968) (xy 337.1441 -277.590924) (xy 337.099638 -277.612022) (xy 337.052367 -277.625714)
			(xy 337.003512 -277.631646) (xy 336.954337 -277.629665) (xy 336.906118 -277.619821) (xy 336.860102 -277.602369)
			(xy 336.817481 -277.577762) (xy 336.77936 -277.546637) (xy 336.746725 -277.5098) (xy 336.720422 -277.468204)
			(xy 336.701131 -277.422928) (xy 336.689354 -277.375144) (xy 336.685394 -277.32609) (xy 336.356452 -277.32609)
			(xy 336.355957 -277.350697) (xy 336.348062 -277.399274) (xy 336.332478 -277.445955) (xy 336.309607 -277.489532)
			(xy 336.280042 -277.528876) (xy 336.244549 -277.562968) (xy 336.204046 -277.590924) (xy 336.159584 -277.612022)
			(xy 336.112313 -277.625714) (xy 336.063458 -277.631646) (xy 336.014283 -277.629665) (xy 335.966064 -277.619821)
			(xy 335.920048 -277.602369) (xy 335.877427 -277.577762) (xy 335.839306 -277.546637) (xy 335.806671 -277.5098)
			(xy 335.780368 -277.468204) (xy 335.761077 -277.422928) (xy 335.7493 -277.375144) (xy 335.74534 -277.32609)
			(xy 335.416398 -277.32609) (xy 335.415903 -277.350697) (xy 335.408008 -277.399274) (xy 335.392424 -277.445955)
			(xy 335.369553 -277.489532) (xy 335.339988 -277.528876) (xy 335.304495 -277.562968) (xy 335.263992 -277.590924)
			(xy 335.21953 -277.612022) (xy 335.172259 -277.625714) (xy 335.123404 -277.631646) (xy 335.074229 -277.629665)
			(xy 335.02601 -277.619821) (xy 334.979994 -277.602369) (xy 334.937373 -277.577762) (xy 334.899252 -277.546637)
			(xy 334.866617 -277.5098) (xy 334.840314 -277.468204) (xy 334.821023 -277.422928) (xy 334.809246 -277.375144)
			(xy 334.805286 -277.32609) (xy 334.476344 -277.32609) (xy 334.475849 -277.350697) (xy 334.467954 -277.399274)
			(xy 334.45237 -277.445955) (xy 334.429499 -277.489532) (xy 334.399934 -277.528876) (xy 334.364441 -277.562968)
			(xy 334.323938 -277.590924) (xy 334.279476 -277.612022) (xy 334.232205 -277.625714) (xy 334.18335 -277.631646)
			(xy 334.134175 -277.629665) (xy 334.085956 -277.619821) (xy 334.03994 -277.602369) (xy 333.997319 -277.577762)
			(xy 333.959198 -277.546637) (xy 333.926563 -277.5098) (xy 333.90026 -277.468204) (xy 333.880969 -277.422928)
			(xy 333.869192 -277.375144) (xy 333.865232 -277.32609) (xy 333.53629 -277.32609) (xy 333.535795 -277.350697)
			(xy 333.5279 -277.399274) (xy 333.512316 -277.445955) (xy 333.489445 -277.489532) (xy 333.45988 -277.528876)
			(xy 333.424387 -277.562968) (xy 333.383884 -277.590924) (xy 333.339422 -277.612022) (xy 333.292151 -277.625714)
			(xy 333.243296 -277.631646) (xy 333.194121 -277.629665) (xy 333.145902 -277.619821) (xy 333.099886 -277.602369)
			(xy 333.057265 -277.577762) (xy 333.019144 -277.546637) (xy 332.986509 -277.5098) (xy 332.960206 -277.468204)
			(xy 332.940915 -277.422928) (xy 332.929138 -277.375144) (xy 332.925178 -277.32609) (xy 332.59649 -277.32609)
			(xy 332.595995 -277.350697) (xy 332.5881 -277.399274) (xy 332.572516 -277.445955) (xy 332.549645 -277.489532)
			(xy 332.52008 -277.528876) (xy 332.484587 -277.562968) (xy 332.444084 -277.590924) (xy 332.399622 -277.612022)
			(xy 332.352351 -277.625714) (xy 332.303496 -277.631646) (xy 332.254321 -277.629665) (xy 332.206102 -277.619821)
			(xy 332.160086 -277.602369) (xy 332.117465 -277.577762) (xy 332.079344 -277.546637) (xy 332.046709 -277.5098)
			(xy 332.020406 -277.468204) (xy 332.001115 -277.422928) (xy 331.989338 -277.375144) (xy 331.985378 -277.32609)
			(xy 331.656227 -277.32609) (xy 331.656228 -277.350302) (xy 331.6486 -277.398109) (xy 331.633535 -277.444118)
			(xy 331.611408 -277.487178) (xy 331.582773 -277.526214) (xy 331.548345 -277.56025) (xy 331.508984 -277.588436)
			(xy 331.487526 -277.599648) (xy 331.486764 -277.599902) (xy 331.480507 -277.603304) (xy 331.470057 -277.612972)
			(xy 331.46619 -277.618952) (xy 331.463142 -277.624032) (xy 331.459332 -277.63724) (xy 331.459332 -277.826216)
			(xy 331.459801 -277.835591) (xy 331.46664 -277.853053) (xy 331.479318 -277.866873) (xy 331.487526 -277.871428)
			(xy 331.518006 -277.885652) (xy 331.566266 -277.908004) (xy 331.56955 -277.909499) (xy 331.576433 -277.91167)
			(xy 331.579982 -277.912322) (xy 331.584357 -277.912874) (xy 331.593171 -277.912616) (xy 331.597508 -277.911814)
			(xy 331.605382 -277.909782) (xy 331.62367 -277.902924) (xy 331.63002 -277.897844) (xy 331.6505 -277.882131)
			(xy 331.695636 -277.857093) (xy 331.744338 -277.839997) (xy 331.79522 -277.831328) (xy 331.821028 -277.830788)
			(xy 331.846282 -277.831312) (xy 331.896101 -277.839629) (xy 331.943871 -277.856033) (xy 331.988291 -277.880075)
			(xy 332.028147 -277.9111) (xy 332.062354 -277.948262) (xy 332.089978 -277.990546) (xy 332.110266 -278.036801)
			(xy 332.122664 -278.085764) (xy 332.126835 -278.136096) (xy 332.455278 -278.136096) (xy 332.459238 -278.087042)
			(xy 332.471015 -278.039258) (xy 332.490306 -277.993982) (xy 332.516609 -277.952386) (xy 332.549244 -277.915549)
			(xy 332.587365 -277.884424) (xy 332.629986 -277.859817) (xy 332.676002 -277.842365) (xy 332.724221 -277.832521)
			(xy 332.773396 -277.83054) (xy 332.822251 -277.836472) (xy 332.869522 -277.850164) (xy 332.913984 -277.871262)
			(xy 332.954487 -277.899218) (xy 332.98998 -277.93331) (xy 333.019545 -277.972654) (xy 333.042416 -278.016231)
			(xy 333.058 -278.062912) (xy 333.065895 -278.111489) (xy 333.06639 -278.136096) (xy 333.395332 -278.136096)
			(xy 333.399292 -278.087042) (xy 333.411069 -278.039258) (xy 333.43036 -277.993982) (xy 333.456663 -277.952386)
			(xy 333.489298 -277.915549) (xy 333.527419 -277.884424) (xy 333.57004 -277.859817) (xy 333.616056 -277.842365)
			(xy 333.664275 -277.832521) (xy 333.71345 -277.83054) (xy 333.762305 -277.836472) (xy 333.809576 -277.850164)
			(xy 333.854038 -277.871262) (xy 333.894541 -277.899218) (xy 333.930034 -277.93331) (xy 333.959599 -277.972654)
			(xy 333.98247 -278.016231) (xy 333.998054 -278.062912) (xy 334.005949 -278.111489) (xy 334.006444 -278.136096)
			(xy 335.275186 -278.136096) (xy 335.279146 -278.087042) (xy 335.290923 -278.039258) (xy 335.310214 -277.993982)
			(xy 335.336517 -277.952386) (xy 335.369152 -277.915549) (xy 335.407273 -277.884424) (xy 335.449894 -277.859817)
			(xy 335.49591 -277.842365) (xy 335.544129 -277.832521) (xy 335.593304 -277.83054) (xy 335.642159 -277.836472)
			(xy 335.68943 -277.850164) (xy 335.733892 -277.871262) (xy 335.774395 -277.899218) (xy 335.809888 -277.93331)
			(xy 335.839453 -277.972654) (xy 335.862324 -278.016231) (xy 335.877908 -278.062912) (xy 335.885803 -278.111489)
			(xy 335.886298 -278.136096) (xy 336.21524 -278.136096) (xy 336.2192 -278.087042) (xy 336.230977 -278.039258)
			(xy 336.250268 -277.993982) (xy 336.276571 -277.952386) (xy 336.309206 -277.915549) (xy 336.347327 -277.884424)
			(xy 336.389948 -277.859817) (xy 336.435964 -277.842365) (xy 336.484183 -277.832521) (xy 336.533358 -277.83054)
			(xy 336.582213 -277.836472) (xy 336.629484 -277.850164) (xy 336.673946 -277.871262) (xy 336.714449 -277.899218)
			(xy 336.749942 -277.93331) (xy 336.779507 -277.972654) (xy 336.802378 -278.016231) (xy 336.817962 -278.062912)
			(xy 336.825857 -278.111489) (xy 336.826352 -278.136096) (xy 337.155294 -278.136096) (xy 337.159254 -278.087042)
			(xy 337.171031 -278.039258) (xy 337.190322 -277.993982) (xy 337.216625 -277.952386) (xy 337.24926 -277.915549)
			(xy 337.287381 -277.884424) (xy 337.330002 -277.859817) (xy 337.376018 -277.842365) (xy 337.424237 -277.832521)
			(xy 337.473412 -277.83054) (xy 337.522267 -277.836472) (xy 337.569538 -277.850164) (xy 337.614 -277.871262)
			(xy 337.654503 -277.899218) (xy 337.689996 -277.93331) (xy 337.719561 -277.972654) (xy 337.742432 -278.016231)
			(xy 337.758016 -278.062912) (xy 337.765911 -278.111489) (xy 337.766406 -278.136096) (xy 338.095348 -278.136096)
			(xy 338.099308 -278.087042) (xy 338.111085 -278.039258) (xy 338.130376 -277.993982) (xy 338.156679 -277.952386)
			(xy 338.189314 -277.915549) (xy 338.227435 -277.884424) (xy 338.270056 -277.859817) (xy 338.316072 -277.842365)
			(xy 338.364291 -277.832521) (xy 338.413466 -277.83054) (xy 338.462321 -277.836472) (xy 338.509592 -277.850164)
			(xy 338.554054 -277.871262) (xy 338.594557 -277.899218) (xy 338.63005 -277.93331) (xy 338.659615 -277.972654)
			(xy 338.682486 -278.016231) (xy 338.69807 -278.062912) (xy 338.705965 -278.111489) (xy 338.70646 -278.136096)
			(xy 338.705965 -278.160703) (xy 338.69807 -278.20928) (xy 338.682486 -278.255961) (xy 338.659615 -278.299538)
			(xy 338.63005 -278.338882) (xy 338.594557 -278.372974) (xy 338.554054 -278.40093) (xy 338.509592 -278.422028)
			(xy 338.462321 -278.43572) (xy 338.413466 -278.441652) (xy 338.364291 -278.439671) (xy 338.316072 -278.429827)
			(xy 338.270056 -278.412375) (xy 338.227435 -278.387768) (xy 338.189314 -278.356643) (xy 338.156679 -278.319806)
			(xy 338.130376 -278.27821) (xy 338.111085 -278.232934) (xy 338.099308 -278.18515) (xy 338.095348 -278.136096)
			(xy 337.766406 -278.136096) (xy 337.765911 -278.160703) (xy 337.758016 -278.20928) (xy 337.742432 -278.255961)
			(xy 337.719561 -278.299538) (xy 337.689996 -278.338882) (xy 337.654503 -278.372974) (xy 337.614 -278.40093)
			(xy 337.569538 -278.422028) (xy 337.522267 -278.43572) (xy 337.473412 -278.441652) (xy 337.424237 -278.439671)
			(xy 337.376018 -278.429827) (xy 337.330002 -278.412375) (xy 337.287381 -278.387768) (xy 337.24926 -278.356643)
			(xy 337.216625 -278.319806) (xy 337.190322 -278.27821) (xy 337.171031 -278.232934) (xy 337.159254 -278.18515)
			(xy 337.155294 -278.136096) (xy 336.826352 -278.136096) (xy 336.825857 -278.160703) (xy 336.817962 -278.20928)
			(xy 336.802378 -278.255961) (xy 336.779507 -278.299538) (xy 336.749942 -278.338882) (xy 336.714449 -278.372974)
			(xy 336.673946 -278.40093) (xy 336.629484 -278.422028) (xy 336.582213 -278.43572) (xy 336.533358 -278.441652)
			(xy 336.484183 -278.439671) (xy 336.435964 -278.429827) (xy 336.389948 -278.412375) (xy 336.347327 -278.387768)
			(xy 336.309206 -278.356643) (xy 336.276571 -278.319806) (xy 336.250268 -278.27821) (xy 336.230977 -278.232934)
			(xy 336.2192 -278.18515) (xy 336.21524 -278.136096) (xy 335.886298 -278.136096) (xy 335.885803 -278.160703)
			(xy 335.877908 -278.20928) (xy 335.862324 -278.255961) (xy 335.839453 -278.299538) (xy 335.809888 -278.338882)
			(xy 335.774395 -278.372974) (xy 335.733892 -278.40093) (xy 335.68943 -278.422028) (xy 335.642159 -278.43572)
			(xy 335.593304 -278.441652) (xy 335.544129 -278.439671) (xy 335.49591 -278.429827) (xy 335.449894 -278.412375)
			(xy 335.407273 -278.387768) (xy 335.369152 -278.356643) (xy 335.336517 -278.319806) (xy 335.310214 -278.27821)
			(xy 335.290923 -278.232934) (xy 335.279146 -278.18515) (xy 335.275186 -278.136096) (xy 334.006444 -278.136096)
			(xy 334.005949 -278.160703) (xy 333.998054 -278.20928) (xy 333.98247 -278.255961) (xy 333.959599 -278.299538)
			(xy 333.930034 -278.338882) (xy 333.894541 -278.372974) (xy 333.854038 -278.40093) (xy 333.809576 -278.422028)
			(xy 333.762305 -278.43572) (xy 333.71345 -278.441652) (xy 333.664275 -278.439671) (xy 333.616056 -278.429827)
			(xy 333.57004 -278.412375) (xy 333.527419 -278.387768) (xy 333.489298 -278.356643) (xy 333.456663 -278.319806)
			(xy 333.43036 -278.27821) (xy 333.411069 -278.232934) (xy 333.399292 -278.18515) (xy 333.395332 -278.136096)
			(xy 333.06639 -278.136096) (xy 333.065895 -278.160703) (xy 333.058 -278.20928) (xy 333.042416 -278.255961)
			(xy 333.019545 -278.299538) (xy 332.98998 -278.338882) (xy 332.954487 -278.372974) (xy 332.913984 -278.40093)
			(xy 332.869522 -278.422028) (xy 332.822251 -278.43572) (xy 332.773396 -278.441652) (xy 332.724221 -278.439671)
			(xy 332.676002 -278.429827) (xy 332.629986 -278.412375) (xy 332.587365 -278.387768) (xy 332.549244 -278.356643)
			(xy 332.516609 -278.319806) (xy 332.490306 -278.27821) (xy 332.471015 -278.232934) (xy 332.459238 -278.18515)
			(xy 332.455278 -278.136096) (xy 332.126835 -278.136096) (xy 332.126835 -278.1361) (xy 332.122664 -278.186436)
			(xy 332.110266 -278.235399) (xy 332.089978 -278.281654) (xy 332.062354 -278.323938) (xy 332.028147 -278.3611)
			(xy 331.988291 -278.392125) (xy 331.943871 -278.416167) (xy 331.896101 -278.432571) (xy 331.846282 -278.440888)
			(xy 331.821028 -278.441404) (xy 331.808265 -278.441264) (xy 331.782832 -278.439099) (xy 331.770228 -278.437086)
			(xy 331.743541 -278.432004) (xy 331.69241 -278.413667) (xy 331.645334 -278.386565) (xy 331.624178 -278.369522)
			(xy 331.61859 -278.36495) (xy 331.605636 -278.359108) (xy 331.59827 -278.358092) (xy 331.591061 -278.35741)
			(xy 331.576755 -278.35961) (xy 331.570076 -278.36241) (xy 331.487018 -278.400764) (xy 331.479151 -278.405205)
			(xy 331.466933 -278.418497) (xy 331.460064 -278.435192) (xy 331.459332 -278.444198) (xy 331.459332 -278.62784)
			(xy 331.459568 -278.634792) (xy 331.463298 -278.648188) (xy 331.466698 -278.654256) (xy 331.47 -278.659336)
			(xy 331.480414 -278.668988) (xy 331.487526 -278.672544) (xy 331.508975 -278.683771) (xy 331.548335 -278.711956)
			(xy 331.582762 -278.74599) (xy 331.611397 -278.785024) (xy 331.633523 -278.828083) (xy 331.648589 -278.87409)
			(xy 331.656217 -278.921896) (xy 331.656216 -278.946102) (xy 331.985378 -278.946102) (xy 331.989338 -278.897048)
			(xy 332.001115 -278.849264) (xy 332.020406 -278.803988) (xy 332.046709 -278.762392) (xy 332.079344 -278.725555)
			(xy 332.117465 -278.69443) (xy 332.160086 -278.669823) (xy 332.206102 -278.652371) (xy 332.254321 -278.642527)
			(xy 332.303496 -278.640546) (xy 332.352351 -278.646478) (xy 332.399622 -278.66017) (xy 332.444084 -278.681268)
			(xy 332.484587 -278.709224) (xy 332.52008 -278.743316) (xy 332.549645 -278.78266) (xy 332.572516 -278.826237)
			(xy 332.5881 -278.872918) (xy 332.595995 -278.921495) (xy 332.59649 -278.946102) (xy 332.925178 -278.946102)
			(xy 332.929138 -278.897048) (xy 332.940915 -278.849264) (xy 332.960206 -278.803988) (xy 332.986509 -278.762392)
			(xy 333.019144 -278.725555) (xy 333.057265 -278.69443) (xy 333.099886 -278.669823) (xy 333.145902 -278.652371)
			(xy 333.194121 -278.642527) (xy 333.243296 -278.640546) (xy 333.292151 -278.646478) (xy 333.339422 -278.66017)
			(xy 333.383884 -278.681268) (xy 333.424387 -278.709224) (xy 333.45988 -278.743316) (xy 333.489445 -278.78266)
			(xy 333.512316 -278.826237) (xy 333.5279 -278.872918) (xy 333.535795 -278.921495) (xy 333.53629 -278.946102)
			(xy 333.865232 -278.946102) (xy 333.869192 -278.897048) (xy 333.880969 -278.849264) (xy 333.90026 -278.803988)
			(xy 333.926563 -278.762392) (xy 333.959198 -278.725555) (xy 333.997319 -278.69443) (xy 334.03994 -278.669823)
			(xy 334.085956 -278.652371) (xy 334.134175 -278.642527) (xy 334.18335 -278.640546) (xy 334.232205 -278.646478)
			(xy 334.279476 -278.66017) (xy 334.323938 -278.681268) (xy 334.364441 -278.709224) (xy 334.399934 -278.743316)
			(xy 334.429499 -278.78266) (xy 334.45237 -278.826237) (xy 334.467954 -278.872918) (xy 334.475849 -278.921495)
			(xy 334.476344 -278.946102) (xy 334.805286 -278.946102) (xy 334.809246 -278.897048) (xy 334.821023 -278.849264)
			(xy 334.840314 -278.803988) (xy 334.866617 -278.762392) (xy 334.899252 -278.725555) (xy 334.937373 -278.69443)
			(xy 334.979994 -278.669823) (xy 335.02601 -278.652371) (xy 335.074229 -278.642527) (xy 335.123404 -278.640546)
			(xy 335.172259 -278.646478) (xy 335.21953 -278.66017) (xy 335.263992 -278.681268) (xy 335.304495 -278.709224)
			(xy 335.339988 -278.743316) (xy 335.369553 -278.78266) (xy 335.392424 -278.826237) (xy 335.408008 -278.872918)
			(xy 335.415903 -278.921495) (xy 335.416398 -278.946102) (xy 335.74534 -278.946102) (xy 335.7493 -278.897048)
			(xy 335.761077 -278.849264) (xy 335.780368 -278.803988) (xy 335.806671 -278.762392) (xy 335.839306 -278.725555)
			(xy 335.877427 -278.69443) (xy 335.920048 -278.669823) (xy 335.966064 -278.652371) (xy 336.014283 -278.642527)
			(xy 336.063458 -278.640546) (xy 336.112313 -278.646478) (xy 336.159584 -278.66017) (xy 336.204046 -278.681268)
			(xy 336.244549 -278.709224) (xy 336.280042 -278.743316) (xy 336.309607 -278.78266) (xy 336.332478 -278.826237)
			(xy 336.348062 -278.872918) (xy 336.355957 -278.921495) (xy 336.356452 -278.946102) (xy 336.685394 -278.946102)
			(xy 336.689354 -278.897048) (xy 336.701131 -278.849264) (xy 336.720422 -278.803988) (xy 336.746725 -278.762392)
			(xy 336.77936 -278.725555) (xy 336.817481 -278.69443) (xy 336.860102 -278.669823) (xy 336.906118 -278.652371)
			(xy 336.954337 -278.642527) (xy 337.003512 -278.640546) (xy 337.052367 -278.646478) (xy 337.099638 -278.66017)
			(xy 337.1441 -278.681268) (xy 337.184603 -278.709224) (xy 337.220096 -278.743316) (xy 337.249661 -278.78266)
			(xy 337.272532 -278.826237) (xy 337.288116 -278.872918) (xy 337.296011 -278.921495) (xy 337.296506 -278.946102)
			(xy 337.625194 -278.946102) (xy 337.629154 -278.897048) (xy 337.640931 -278.849264) (xy 337.660222 -278.803988)
			(xy 337.686525 -278.762392) (xy 337.71916 -278.725555) (xy 337.757281 -278.69443) (xy 337.799902 -278.669823)
			(xy 337.845918 -278.652371) (xy 337.894137 -278.642527) (xy 337.943312 -278.640546) (xy 337.992167 -278.646478)
			(xy 338.039438 -278.66017) (xy 338.0839 -278.681268) (xy 338.124403 -278.709224) (xy 338.159896 -278.743316)
			(xy 338.189461 -278.78266) (xy 338.212332 -278.826237) (xy 338.227916 -278.872918) (xy 338.235811 -278.921495)
			(xy 338.236306 -278.946102) (xy 338.235811 -278.970709) (xy 338.227916 -279.019286) (xy 338.212332 -279.065967)
			(xy 338.189461 -279.109544) (xy 338.159896 -279.148888) (xy 338.124403 -279.18298) (xy 338.0839 -279.210936)
			(xy 338.039438 -279.232034) (xy 337.992167 -279.245726) (xy 337.943312 -279.251658) (xy 337.894137 -279.249677)
			(xy 337.845918 -279.239833) (xy 337.799902 -279.222381) (xy 337.757281 -279.197774) (xy 337.71916 -279.166649)
			(xy 337.686525 -279.129812) (xy 337.660222 -279.088216) (xy 337.640931 -279.04294) (xy 337.629154 -278.995156)
			(xy 337.625194 -278.946102) (xy 337.296506 -278.946102) (xy 337.296011 -278.970709) (xy 337.288116 -279.019286)
			(xy 337.272532 -279.065967) (xy 337.249661 -279.109544) (xy 337.220096 -279.148888) (xy 337.184603 -279.18298)
			(xy 337.1441 -279.210936) (xy 337.099638 -279.232034) (xy 337.052367 -279.245726) (xy 337.003512 -279.251658)
			(xy 336.954337 -279.249677) (xy 336.906118 -279.239833) (xy 336.860102 -279.222381) (xy 336.817481 -279.197774)
			(xy 336.77936 -279.166649) (xy 336.746725 -279.129812) (xy 336.720422 -279.088216) (xy 336.701131 -279.04294)
			(xy 336.689354 -278.995156) (xy 336.685394 -278.946102) (xy 336.356452 -278.946102) (xy 336.355957 -278.970709)
			(xy 336.348062 -279.019286) (xy 336.332478 -279.065967) (xy 336.309607 -279.109544) (xy 336.280042 -279.148888)
			(xy 336.244549 -279.18298) (xy 336.204046 -279.210936) (xy 336.159584 -279.232034) (xy 336.112313 -279.245726)
			(xy 336.063458 -279.251658) (xy 336.014283 -279.249677) (xy 335.966064 -279.239833) (xy 335.920048 -279.222381)
			(xy 335.877427 -279.197774) (xy 335.839306 -279.166649) (xy 335.806671 -279.129812) (xy 335.780368 -279.088216)
			(xy 335.761077 -279.04294) (xy 335.7493 -278.995156) (xy 335.74534 -278.946102) (xy 335.416398 -278.946102)
			(xy 335.415903 -278.970709) (xy 335.408008 -279.019286) (xy 335.392424 -279.065967) (xy 335.369553 -279.109544)
			(xy 335.339988 -279.148888) (xy 335.304495 -279.18298) (xy 335.263992 -279.210936) (xy 335.21953 -279.232034)
			(xy 335.172259 -279.245726) (xy 335.123404 -279.251658) (xy 335.074229 -279.249677) (xy 335.02601 -279.239833)
			(xy 334.979994 -279.222381) (xy 334.937373 -279.197774) (xy 334.899252 -279.166649) (xy 334.866617 -279.129812)
			(xy 334.840314 -279.088216) (xy 334.821023 -279.04294) (xy 334.809246 -278.995156) (xy 334.805286 -278.946102)
			(xy 334.476344 -278.946102) (xy 334.475849 -278.970709) (xy 334.467954 -279.019286) (xy 334.45237 -279.065967)
			(xy 334.429499 -279.109544) (xy 334.399934 -279.148888) (xy 334.364441 -279.18298) (xy 334.323938 -279.210936)
			(xy 334.279476 -279.232034) (xy 334.232205 -279.245726) (xy 334.18335 -279.251658) (xy 334.134175 -279.249677)
			(xy 334.085956 -279.239833) (xy 334.03994 -279.222381) (xy 333.997319 -279.197774) (xy 333.959198 -279.166649)
			(xy 333.926563 -279.129812) (xy 333.90026 -279.088216) (xy 333.880969 -279.04294) (xy 333.869192 -278.995156)
			(xy 333.865232 -278.946102) (xy 333.53629 -278.946102) (xy 333.535795 -278.970709) (xy 333.5279 -279.019286)
			(xy 333.512316 -279.065967) (xy 333.489445 -279.109544) (xy 333.45988 -279.148888) (xy 333.424387 -279.18298)
			(xy 333.383884 -279.210936) (xy 333.339422 -279.232034) (xy 333.292151 -279.245726) (xy 333.243296 -279.251658)
			(xy 333.194121 -279.249677) (xy 333.145902 -279.239833) (xy 333.099886 -279.222381) (xy 333.057265 -279.197774)
			(xy 333.019144 -279.166649) (xy 332.986509 -279.129812) (xy 332.960206 -279.088216) (xy 332.940915 -279.04294)
			(xy 332.929138 -278.995156) (xy 332.925178 -278.946102) (xy 332.59649 -278.946102) (xy 332.595995 -278.970709)
			(xy 332.5881 -279.019286) (xy 332.572516 -279.065967) (xy 332.549645 -279.109544) (xy 332.52008 -279.148888)
			(xy 332.484587 -279.18298) (xy 332.444084 -279.210936) (xy 332.399622 -279.232034) (xy 332.352351 -279.245726)
			(xy 332.303496 -279.251658) (xy 332.254321 -279.249677) (xy 332.206102 -279.239833) (xy 332.160086 -279.222381)
			(xy 332.117465 -279.197774) (xy 332.079344 -279.166649) (xy 332.046709 -279.129812) (xy 332.020406 -279.088216)
			(xy 332.001115 -279.04294) (xy 331.989338 -278.995156) (xy 331.985378 -278.946102) (xy 331.656216 -278.946102)
			(xy 331.656216 -278.970306) (xy 331.648588 -279.018112) (xy 331.633523 -279.064119) (xy 331.611396 -279.107177)
			(xy 331.582761 -279.146211) (xy 331.548334 -279.180245) (xy 331.508973 -279.20843) (xy 331.487526 -279.21966)
			(xy 331.486764 -279.219914) (xy 331.480508 -279.223317) (xy 331.47006 -279.232986) (xy 331.46619 -279.238964)
			(xy 331.463142 -279.244044) (xy 331.459332 -279.257252) (xy 331.459332 -279.446228) (xy 331.459803 -279.455602)
			(xy 331.466645 -279.473061) (xy 331.479323 -279.486877) (xy 331.487526 -279.49144) (xy 331.518006 -279.505664)
			(xy 331.566266 -279.528016) (xy 331.56955 -279.529511) (xy 331.576433 -279.531681) (xy 331.579982 -279.532334)
			(xy 331.584357 -279.532886) (xy 331.593171 -279.532628) (xy 331.597508 -279.531826) (xy 331.605382 -279.529794)
			(xy 331.62367 -279.522936) (xy 331.63002 -279.517856) (xy 331.650501 -279.502147) (xy 331.695639 -279.477117)
			(xy 331.744341 -279.460025) (xy 331.795221 -279.451359) (xy 331.821028 -279.4508) (xy 331.846281 -279.451324)
			(xy 331.896098 -279.459641) (xy 331.943867 -279.476044) (xy 331.988284 -279.500085) (xy 332.028139 -279.531109)
			(xy 332.062345 -279.568269) (xy 332.089968 -279.610552) (xy 332.110255 -279.656805) (xy 332.122652 -279.705766)
			(xy 332.126823 -279.7561) (xy 332.126822 -279.756108) (xy 332.455278 -279.756108) (xy 332.459238 -279.707054)
			(xy 332.471015 -279.65927) (xy 332.490306 -279.613994) (xy 332.516609 -279.572398) (xy 332.549244 -279.535561)
			(xy 332.587365 -279.504436) (xy 332.629986 -279.479829) (xy 332.676002 -279.462377) (xy 332.724221 -279.452533)
			(xy 332.773396 -279.450552) (xy 332.822251 -279.456484) (xy 332.869522 -279.470176) (xy 332.913984 -279.491274)
			(xy 332.954487 -279.51923) (xy 332.98998 -279.553322) (xy 333.019545 -279.592666) (xy 333.042416 -279.636243)
			(xy 333.058 -279.682924) (xy 333.065895 -279.731501) (xy 333.06639 -279.756108) (xy 333.395332 -279.756108)
			(xy 333.399292 -279.707054) (xy 333.411069 -279.65927) (xy 333.43036 -279.613994) (xy 333.456663 -279.572398)
			(xy 333.489298 -279.535561) (xy 333.527419 -279.504436) (xy 333.57004 -279.479829) (xy 333.616056 -279.462377)
			(xy 333.664275 -279.452533) (xy 333.71345 -279.450552) (xy 333.762305 -279.456484) (xy 333.809576 -279.470176)
			(xy 333.854038 -279.491274) (xy 333.894541 -279.51923) (xy 333.930034 -279.553322) (xy 333.959599 -279.592666)
			(xy 333.98247 -279.636243) (xy 333.998054 -279.682924) (xy 334.005949 -279.731501) (xy 334.006444 -279.756108)
			(xy 334.335386 -279.756108) (xy 334.339346 -279.707054) (xy 334.351123 -279.65927) (xy 334.370414 -279.613994)
			(xy 334.396717 -279.572398) (xy 334.429352 -279.535561) (xy 334.467473 -279.504436) (xy 334.510094 -279.479829)
			(xy 334.55611 -279.462377) (xy 334.604329 -279.452533) (xy 334.653504 -279.450552) (xy 334.702359 -279.456484)
			(xy 334.74963 -279.470176) (xy 334.794092 -279.491274) (xy 334.834595 -279.51923) (xy 334.870088 -279.553322)
			(xy 334.899653 -279.592666) (xy 334.922524 -279.636243) (xy 334.938108 -279.682924) (xy 334.946003 -279.731501)
			(xy 334.946498 -279.756108) (xy 335.275186 -279.756108) (xy 335.279146 -279.707054) (xy 335.290923 -279.65927)
			(xy 335.310214 -279.613994) (xy 335.336517 -279.572398) (xy 335.369152 -279.535561) (xy 335.407273 -279.504436)
			(xy 335.449894 -279.479829) (xy 335.49591 -279.462377) (xy 335.544129 -279.452533) (xy 335.593304 -279.450552)
			(xy 335.642159 -279.456484) (xy 335.68943 -279.470176) (xy 335.733892 -279.491274) (xy 335.774395 -279.51923)
			(xy 335.809888 -279.553322) (xy 335.839453 -279.592666) (xy 335.862324 -279.636243) (xy 335.877908 -279.682924)
			(xy 335.885803 -279.731501) (xy 335.886298 -279.756108) (xy 336.21524 -279.756108) (xy 336.2192 -279.707054)
			(xy 336.230977 -279.65927) (xy 336.250268 -279.613994) (xy 336.276571 -279.572398) (xy 336.309206 -279.535561)
			(xy 336.347327 -279.504436) (xy 336.389948 -279.479829) (xy 336.435964 -279.462377) (xy 336.484183 -279.452533)
			(xy 336.533358 -279.450552) (xy 336.582213 -279.456484) (xy 336.629484 -279.470176) (xy 336.673946 -279.491274)
			(xy 336.714449 -279.51923) (xy 336.749942 -279.553322) (xy 336.779507 -279.592666) (xy 336.802378 -279.636243)
			(xy 336.817962 -279.682924) (xy 336.825857 -279.731501) (xy 336.826352 -279.756108) (xy 337.155294 -279.756108)
			(xy 337.159254 -279.707054) (xy 337.171031 -279.65927) (xy 337.190322 -279.613994) (xy 337.216625 -279.572398)
			(xy 337.24926 -279.535561) (xy 337.287381 -279.504436) (xy 337.330002 -279.479829) (xy 337.376018 -279.462377)
			(xy 337.424237 -279.452533) (xy 337.473412 -279.450552) (xy 337.522267 -279.456484) (xy 337.569538 -279.470176)
			(xy 337.614 -279.491274) (xy 337.654503 -279.51923) (xy 337.689996 -279.553322) (xy 337.719561 -279.592666)
			(xy 337.742432 -279.636243) (xy 337.758016 -279.682924) (xy 337.765911 -279.731501) (xy 337.766406 -279.756108)
			(xy 338.095348 -279.756108) (xy 338.099308 -279.707054) (xy 338.111085 -279.65927) (xy 338.130376 -279.613994)
			(xy 338.156679 -279.572398) (xy 338.189314 -279.535561) (xy 338.227435 -279.504436) (xy 338.270056 -279.479829)
			(xy 338.316072 -279.462377) (xy 338.364291 -279.452533) (xy 338.413466 -279.450552) (xy 338.462321 -279.456484)
			(xy 338.509592 -279.470176) (xy 338.554054 -279.491274) (xy 338.594557 -279.51923) (xy 338.63005 -279.553322)
			(xy 338.659615 -279.592666) (xy 338.682486 -279.636243) (xy 338.69807 -279.682924) (xy 338.705965 -279.731501)
			(xy 338.70646 -279.756108) (xy 338.705965 -279.780715) (xy 338.69807 -279.829292) (xy 338.682486 -279.875973)
			(xy 338.659615 -279.91955) (xy 338.63005 -279.958894) (xy 338.594557 -279.992986) (xy 338.554054 -280.020942)
			(xy 338.509592 -280.04204) (xy 338.462321 -280.055732) (xy 338.413466 -280.061664) (xy 338.364291 -280.059683)
			(xy 338.316072 -280.049839) (xy 338.270056 -280.032387) (xy 338.227435 -280.00778) (xy 338.189314 -279.976655)
			(xy 338.156679 -279.939818) (xy 338.130376 -279.898222) (xy 338.111085 -279.852946) (xy 338.099308 -279.805162)
			(xy 338.095348 -279.756108) (xy 337.766406 -279.756108) (xy 337.765911 -279.780715) (xy 337.758016 -279.829292)
			(xy 337.742432 -279.875973) (xy 337.719561 -279.91955) (xy 337.689996 -279.958894) (xy 337.654503 -279.992986)
			(xy 337.614 -280.020942) (xy 337.569538 -280.04204) (xy 337.522267 -280.055732) (xy 337.473412 -280.061664)
			(xy 337.424237 -280.059683) (xy 337.376018 -280.049839) (xy 337.330002 -280.032387) (xy 337.287381 -280.00778)
			(xy 337.24926 -279.976655) (xy 337.216625 -279.939818) (xy 337.190322 -279.898222) (xy 337.171031 -279.852946)
			(xy 337.159254 -279.805162) (xy 337.155294 -279.756108) (xy 336.826352 -279.756108) (xy 336.825857 -279.780715)
			(xy 336.817962 -279.829292) (xy 336.802378 -279.875973) (xy 336.779507 -279.91955) (xy 336.749942 -279.958894)
			(xy 336.714449 -279.992986) (xy 336.673946 -280.020942) (xy 336.629484 -280.04204) (xy 336.582213 -280.055732)
			(xy 336.533358 -280.061664) (xy 336.484183 -280.059683) (xy 336.435964 -280.049839) (xy 336.389948 -280.032387)
			(xy 336.347327 -280.00778) (xy 336.309206 -279.976655) (xy 336.276571 -279.939818) (xy 336.250268 -279.898222)
			(xy 336.230977 -279.852946) (xy 336.2192 -279.805162) (xy 336.21524 -279.756108) (xy 335.886298 -279.756108)
			(xy 335.885803 -279.780715) (xy 335.877908 -279.829292) (xy 335.862324 -279.875973) (xy 335.839453 -279.91955)
			(xy 335.809888 -279.958894) (xy 335.774395 -279.992986) (xy 335.733892 -280.020942) (xy 335.68943 -280.04204)
			(xy 335.642159 -280.055732) (xy 335.593304 -280.061664) (xy 335.544129 -280.059683) (xy 335.49591 -280.049839)
			(xy 335.449894 -280.032387) (xy 335.407273 -280.00778) (xy 335.369152 -279.976655) (xy 335.336517 -279.939818)
			(xy 335.310214 -279.898222) (xy 335.290923 -279.852946) (xy 335.279146 -279.805162) (xy 335.275186 -279.756108)
			(xy 334.946498 -279.756108) (xy 334.946003 -279.780715) (xy 334.938108 -279.829292) (xy 334.922524 -279.875973)
			(xy 334.899653 -279.91955) (xy 334.870088 -279.958894) (xy 334.834595 -279.992986) (xy 334.794092 -280.020942)
			(xy 334.74963 -280.04204) (xy 334.702359 -280.055732) (xy 334.653504 -280.061664) (xy 334.604329 -280.059683)
			(xy 334.55611 -280.049839) (xy 334.510094 -280.032387) (xy 334.467473 -280.00778) (xy 334.429352 -279.976655)
			(xy 334.396717 -279.939818) (xy 334.370414 -279.898222) (xy 334.351123 -279.852946) (xy 334.339346 -279.805162)
			(xy 334.335386 -279.756108) (xy 334.006444 -279.756108) (xy 334.005949 -279.780715) (xy 333.998054 -279.829292)
			(xy 333.98247 -279.875973) (xy 333.959599 -279.91955) (xy 333.930034 -279.958894) (xy 333.894541 -279.992986)
			(xy 333.854038 -280.020942) (xy 333.809576 -280.04204) (xy 333.762305 -280.055732) (xy 333.71345 -280.061664)
			(xy 333.664275 -280.059683) (xy 333.616056 -280.049839) (xy 333.57004 -280.032387) (xy 333.527419 -280.00778)
			(xy 333.489298 -279.976655) (xy 333.456663 -279.939818) (xy 333.43036 -279.898222) (xy 333.411069 -279.852946)
			(xy 333.399292 -279.805162) (xy 333.395332 -279.756108) (xy 333.06639 -279.756108) (xy 333.065895 -279.780715)
			(xy 333.058 -279.829292) (xy 333.042416 -279.875973) (xy 333.019545 -279.91955) (xy 332.98998 -279.958894)
			(xy 332.954487 -279.992986) (xy 332.913984 -280.020942) (xy 332.869522 -280.04204) (xy 332.822251 -280.055732)
			(xy 332.773396 -280.061664) (xy 332.724221 -280.059683) (xy 332.676002 -280.049839) (xy 332.629986 -280.032387)
			(xy 332.587365 -280.00778) (xy 332.549244 -279.976655) (xy 332.516609 -279.939818) (xy 332.490306 -279.898222)
			(xy 332.471015 -279.852946) (xy 332.459238 -279.805162) (xy 332.455278 -279.756108) (xy 332.126822 -279.756108)
			(xy 332.122652 -279.806434) (xy 332.110255 -279.855395) (xy 332.089968 -279.901648) (xy 332.062345 -279.943931)
			(xy 332.028139 -279.981091) (xy 331.988284 -280.012115) (xy 331.943867 -280.036156) (xy 331.896098 -280.052559)
			(xy 331.846281 -280.060876) (xy 331.821028 -280.061416) (xy 331.808265 -280.061276) (xy 331.782832 -280.059111)
			(xy 331.770228 -280.057098) (xy 331.743541 -280.052017) (xy 331.692409 -280.03368) (xy 331.645333 -280.006578)
			(xy 331.624178 -279.989534) (xy 331.61859 -279.984962) (xy 331.605636 -279.97912) (xy 331.59827 -279.978104)
			(xy 331.591061 -279.977422) (xy 331.576755 -279.979622) (xy 331.570076 -279.982422) (xy 331.487018 -280.020776)
			(xy 331.479153 -280.025218) (xy 331.466938 -280.03851) (xy 331.460072 -280.055205) (xy 331.459332 -280.06421)
			(xy 331.459332 -280.247852) (xy 331.459569 -280.254804) (xy 331.463302 -280.268198) (xy 331.466698 -280.274268)
			(xy 331.47 -280.279348) (xy 331.480414 -280.289) (xy 331.487526 -280.292556) (xy 331.508974 -280.303783)
			(xy 331.548332 -280.331968) (xy 331.582758 -280.366002) (xy 331.611391 -280.405035) (xy 331.633516 -280.448092)
			(xy 331.64858 -280.494097) (xy 331.656206 -280.541902) (xy 331.656205 -280.566114) (xy 331.985378 -280.566114)
			(xy 331.989338 -280.51706) (xy 332.001115 -280.469276) (xy 332.020406 -280.424) (xy 332.046709 -280.382404)
			(xy 332.079344 -280.345567) (xy 332.117465 -280.314442) (xy 332.160086 -280.289835) (xy 332.206102 -280.272383)
			(xy 332.254321 -280.262539) (xy 332.303496 -280.260558) (xy 332.352351 -280.26649) (xy 332.399622 -280.280182)
			(xy 332.444084 -280.30128) (xy 332.484587 -280.329236) (xy 332.52008 -280.363328) (xy 332.549645 -280.402672)
			(xy 332.572516 -280.446249) (xy 332.5881 -280.49293) (xy 332.595995 -280.541507) (xy 332.59649 -280.566114)
			(xy 332.925178 -280.566114) (xy 332.929138 -280.51706) (xy 332.940915 -280.469276) (xy 332.960206 -280.424)
			(xy 332.986509 -280.382404) (xy 333.019144 -280.345567) (xy 333.057265 -280.314442) (xy 333.099886 -280.289835)
			(xy 333.145902 -280.272383) (xy 333.194121 -280.262539) (xy 333.243296 -280.260558) (xy 333.292151 -280.26649)
			(xy 333.339422 -280.280182) (xy 333.383884 -280.30128) (xy 333.424387 -280.329236) (xy 333.45988 -280.363328)
			(xy 333.489445 -280.402672) (xy 333.512316 -280.446249) (xy 333.5279 -280.49293) (xy 333.535795 -280.541507)
			(xy 333.53629 -280.566114) (xy 333.865232 -280.566114) (xy 333.869192 -280.51706) (xy 333.880969 -280.469276)
			(xy 333.90026 -280.424) (xy 333.926563 -280.382404) (xy 333.959198 -280.345567) (xy 333.997319 -280.314442)
			(xy 334.03994 -280.289835) (xy 334.085956 -280.272383) (xy 334.134175 -280.262539) (xy 334.18335 -280.260558)
			(xy 334.232205 -280.26649) (xy 334.279476 -280.280182) (xy 334.323938 -280.30128) (xy 334.364441 -280.329236)
			(xy 334.399934 -280.363328) (xy 334.429499 -280.402672) (xy 334.45237 -280.446249) (xy 334.467954 -280.49293)
			(xy 334.475849 -280.541507) (xy 334.476344 -280.566114) (xy 335.74534 -280.566114) (xy 335.7493 -280.51706)
			(xy 335.761077 -280.469276) (xy 335.780368 -280.424) (xy 335.806671 -280.382404) (xy 335.839306 -280.345567)
			(xy 335.877427 -280.314442) (xy 335.920048 -280.289835) (xy 335.966064 -280.272383) (xy 336.014283 -280.262539)
			(xy 336.063458 -280.260558) (xy 336.112313 -280.26649) (xy 336.159584 -280.280182) (xy 336.204046 -280.30128)
			(xy 336.244549 -280.329236) (xy 336.280042 -280.363328) (xy 336.309607 -280.402672) (xy 336.332478 -280.446249)
			(xy 336.348062 -280.49293) (xy 336.355957 -280.541507) (xy 336.356452 -280.566114) (xy 336.685394 -280.566114)
			(xy 336.689354 -280.51706) (xy 336.701131 -280.469276) (xy 336.720422 -280.424) (xy 336.746725 -280.382404)
			(xy 336.77936 -280.345567) (xy 336.817481 -280.314442) (xy 336.860102 -280.289835) (xy 336.906118 -280.272383)
			(xy 336.954337 -280.262539) (xy 337.003512 -280.260558) (xy 337.052367 -280.26649) (xy 337.099638 -280.280182)
			(xy 337.1441 -280.30128) (xy 337.184603 -280.329236) (xy 337.220096 -280.363328) (xy 337.249661 -280.402672)
			(xy 337.272532 -280.446249) (xy 337.288116 -280.49293) (xy 337.296011 -280.541507) (xy 337.296506 -280.566114)
			(xy 337.625194 -280.566114) (xy 337.629154 -280.51706) (xy 337.640931 -280.469276) (xy 337.660222 -280.424)
			(xy 337.686525 -280.382404) (xy 337.71916 -280.345567) (xy 337.757281 -280.314442) (xy 337.799902 -280.289835)
			(xy 337.845918 -280.272383) (xy 337.894137 -280.262539) (xy 337.943312 -280.260558) (xy 337.992167 -280.26649)
			(xy 338.039438 -280.280182) (xy 338.0839 -280.30128) (xy 338.124403 -280.329236) (xy 338.159896 -280.363328)
			(xy 338.189461 -280.402672) (xy 338.212332 -280.446249) (xy 338.227916 -280.49293) (xy 338.235811 -280.541507)
			(xy 338.236306 -280.566114) (xy 338.235811 -280.590721) (xy 338.227916 -280.639298) (xy 338.212332 -280.685979)
			(xy 338.189461 -280.729556) (xy 338.159896 -280.7689) (xy 338.124403 -280.802992) (xy 338.0839 -280.830948)
			(xy 338.039438 -280.852046) (xy 337.992167 -280.865738) (xy 337.943312 -280.87167) (xy 337.894137 -280.869689)
			(xy 337.845918 -280.859845) (xy 337.799902 -280.842393) (xy 337.757281 -280.817786) (xy 337.71916 -280.786661)
			(xy 337.686525 -280.749824) (xy 337.660222 -280.708228) (xy 337.640931 -280.662952) (xy 337.629154 -280.615168)
			(xy 337.625194 -280.566114) (xy 337.296506 -280.566114) (xy 337.296011 -280.590721) (xy 337.288116 -280.639298)
			(xy 337.272532 -280.685979) (xy 337.249661 -280.729556) (xy 337.220096 -280.7689) (xy 337.184603 -280.802992)
			(xy 337.1441 -280.830948) (xy 337.099638 -280.852046) (xy 337.052367 -280.865738) (xy 337.003512 -280.87167)
			(xy 336.954337 -280.869689) (xy 336.906118 -280.859845) (xy 336.860102 -280.842393) (xy 336.817481 -280.817786)
			(xy 336.77936 -280.786661) (xy 336.746725 -280.749824) (xy 336.720422 -280.708228) (xy 336.701131 -280.662952)
			(xy 336.689354 -280.615168) (xy 336.685394 -280.566114) (xy 336.356452 -280.566114) (xy 336.355957 -280.590721)
			(xy 336.348062 -280.639298) (xy 336.332478 -280.685979) (xy 336.309607 -280.729556) (xy 336.280042 -280.7689)
			(xy 336.244549 -280.802992) (xy 336.204046 -280.830948) (xy 336.159584 -280.852046) (xy 336.112313 -280.865738)
			(xy 336.063458 -280.87167) (xy 336.014283 -280.869689) (xy 335.966064 -280.859845) (xy 335.920048 -280.842393)
			(xy 335.877427 -280.817786) (xy 335.839306 -280.786661) (xy 335.806671 -280.749824) (xy 335.780368 -280.708228)
			(xy 335.761077 -280.662952) (xy 335.7493 -280.615168) (xy 335.74534 -280.566114) (xy 334.476344 -280.566114)
			(xy 334.475849 -280.590721) (xy 334.467954 -280.639298) (xy 334.45237 -280.685979) (xy 334.429499 -280.729556)
			(xy 334.399934 -280.7689) (xy 334.364441 -280.802992) (xy 334.323938 -280.830948) (xy 334.279476 -280.852046)
			(xy 334.232205 -280.865738) (xy 334.18335 -280.87167) (xy 334.134175 -280.869689) (xy 334.085956 -280.859845)
			(xy 334.03994 -280.842393) (xy 333.997319 -280.817786) (xy 333.959198 -280.786661) (xy 333.926563 -280.749824)
			(xy 333.90026 -280.708228) (xy 333.880969 -280.662952) (xy 333.869192 -280.615168) (xy 333.865232 -280.566114)
			(xy 333.53629 -280.566114) (xy 333.535795 -280.590721) (xy 333.5279 -280.639298) (xy 333.512316 -280.685979)
			(xy 333.489445 -280.729556) (xy 333.45988 -280.7689) (xy 333.424387 -280.802992) (xy 333.383884 -280.830948)
			(xy 333.339422 -280.852046) (xy 333.292151 -280.865738) (xy 333.243296 -280.87167) (xy 333.194121 -280.869689)
			(xy 333.145902 -280.859845) (xy 333.099886 -280.842393) (xy 333.057265 -280.817786) (xy 333.019144 -280.786661)
			(xy 332.986509 -280.749824) (xy 332.960206 -280.708228) (xy 332.940915 -280.662952) (xy 332.929138 -280.615168)
			(xy 332.925178 -280.566114) (xy 332.59649 -280.566114) (xy 332.595995 -280.590721) (xy 332.5881 -280.639298)
			(xy 332.572516 -280.685979) (xy 332.549645 -280.729556) (xy 332.52008 -280.7689) (xy 332.484587 -280.802992)
			(xy 332.444084 -280.830948) (xy 332.399622 -280.852046) (xy 332.352351 -280.865738) (xy 332.303496 -280.87167)
			(xy 332.254321 -280.869689) (xy 332.206102 -280.859845) (xy 332.160086 -280.842393) (xy 332.117465 -280.817786)
			(xy 332.079344 -280.786661) (xy 332.046709 -280.749824) (xy 332.020406 -280.708228) (xy 332.001115 -280.662952)
			(xy 331.989338 -280.615168) (xy 331.985378 -280.566114) (xy 331.656205 -280.566114) (xy 331.656205 -280.590311)
			(xy 331.648577 -280.638115) (xy 331.633511 -280.68412) (xy 331.611384 -280.727176) (xy 331.58275 -280.766208)
			(xy 331.548323 -280.80024) (xy 331.508963 -280.828423) (xy 331.487526 -280.839672) (xy 331.486764 -280.839926)
			(xy 331.480508 -280.84333) (xy 331.470063 -280.853) (xy 331.46619 -280.858976) (xy 331.463142 -280.864056)
			(xy 331.459332 -280.877264) (xy 331.459332 -281.06624) (xy 331.459805 -281.075613) (xy 331.466649 -281.093068)
			(xy 331.479328 -281.106881) (xy 331.487526 -281.111452) (xy 331.518006 -281.125676) (xy 331.566266 -281.148028)
			(xy 331.56955 -281.149525) (xy 331.576432 -281.151699) (xy 331.579982 -281.152346) (xy 331.584357 -281.152898)
			(xy 331.593171 -281.15264) (xy 331.597508 -281.151838) (xy 331.605382 -281.149806) (xy 331.62367 -281.142948)
			(xy 331.63002 -281.137868) (xy 331.650501 -281.122158) (xy 331.695639 -281.097127) (xy 331.74434 -281.080035)
			(xy 331.795221 -281.071368) (xy 331.821028 -281.070812) (xy 331.84628 -281.071336) (xy 331.896095 -281.079653)
			(xy 331.943862 -281.096055) (xy 331.988278 -281.120095) (xy 332.028131 -281.151118) (xy 332.062335 -281.188276)
			(xy 332.089957 -281.230558) (xy 332.110243 -281.276809) (xy 332.122641 -281.325768) (xy 332.126811 -281.3761)
			(xy 332.126809 -281.37612) (xy 332.455278 -281.37612) (xy 332.459238 -281.327066) (xy 332.471015 -281.279282)
			(xy 332.490306 -281.234006) (xy 332.516609 -281.19241) (xy 332.549244 -281.155573) (xy 332.587365 -281.124448)
			(xy 332.629986 -281.099841) (xy 332.676002 -281.082389) (xy 332.724221 -281.072545) (xy 332.773396 -281.070564)
			(xy 332.822251 -281.076496) (xy 332.869522 -281.090188) (xy 332.913984 -281.111286) (xy 332.954487 -281.139242)
			(xy 332.98998 -281.173334) (xy 333.019545 -281.212678) (xy 333.042416 -281.256255) (xy 333.058 -281.302936)
			(xy 333.065895 -281.351513) (xy 333.06639 -281.37612) (xy 333.395332 -281.37612) (xy 333.399292 -281.327066)
			(xy 333.411069 -281.279282) (xy 333.43036 -281.234006) (xy 333.456663 -281.19241) (xy 333.489298 -281.155573)
			(xy 333.527419 -281.124448) (xy 333.57004 -281.099841) (xy 333.616056 -281.082389) (xy 333.664275 -281.072545)
			(xy 333.71345 -281.070564) (xy 333.762305 -281.076496) (xy 333.809576 -281.090188) (xy 333.854038 -281.111286)
			(xy 333.894541 -281.139242) (xy 333.930034 -281.173334) (xy 333.959599 -281.212678) (xy 333.98247 -281.256255)
			(xy 333.998054 -281.302936) (xy 334.005949 -281.351513) (xy 334.006444 -281.37612) (xy 334.335386 -281.37612)
			(xy 334.339346 -281.327066) (xy 334.351123 -281.279282) (xy 334.370414 -281.234006) (xy 334.396717 -281.19241)
			(xy 334.429352 -281.155573) (xy 334.467473 -281.124448) (xy 334.510094 -281.099841) (xy 334.55611 -281.082389)
			(xy 334.604329 -281.072545) (xy 334.653504 -281.070564) (xy 334.702359 -281.076496) (xy 334.74963 -281.090188)
			(xy 334.794092 -281.111286) (xy 334.834595 -281.139242) (xy 334.870088 -281.173334) (xy 334.899653 -281.212678)
			(xy 334.922524 -281.256255) (xy 334.938108 -281.302936) (xy 334.946003 -281.351513) (xy 334.946498 -281.37612)
			(xy 335.275186 -281.37612) (xy 335.279146 -281.327066) (xy 335.290923 -281.279282) (xy 335.310214 -281.234006)
			(xy 335.336517 -281.19241) (xy 335.369152 -281.155573) (xy 335.407273 -281.124448) (xy 335.449894 -281.099841)
			(xy 335.49591 -281.082389) (xy 335.544129 -281.072545) (xy 335.593304 -281.070564) (xy 335.642159 -281.076496)
			(xy 335.68943 -281.090188) (xy 335.733892 -281.111286) (xy 335.774395 -281.139242) (xy 335.809888 -281.173334)
			(xy 335.839453 -281.212678) (xy 335.862324 -281.256255) (xy 335.877908 -281.302936) (xy 335.885803 -281.351513)
			(xy 335.886298 -281.37612) (xy 336.21524 -281.37612) (xy 336.2192 -281.327066) (xy 336.230977 -281.279282)
			(xy 336.250268 -281.234006) (xy 336.276571 -281.19241) (xy 336.309206 -281.155573) (xy 336.347327 -281.124448)
			(xy 336.389948 -281.099841) (xy 336.435964 -281.082389) (xy 336.484183 -281.072545) (xy 336.533358 -281.070564)
			(xy 336.582213 -281.076496) (xy 336.629484 -281.090188) (xy 336.673946 -281.111286) (xy 336.714449 -281.139242)
			(xy 336.749942 -281.173334) (xy 336.779507 -281.212678) (xy 336.802378 -281.256255) (xy 336.817962 -281.302936)
			(xy 336.825857 -281.351513) (xy 336.826352 -281.37612) (xy 337.155294 -281.37612) (xy 337.159254 -281.327066)
			(xy 337.171031 -281.279282) (xy 337.190322 -281.234006) (xy 337.216625 -281.19241) (xy 337.24926 -281.155573)
			(xy 337.287381 -281.124448) (xy 337.330002 -281.099841) (xy 337.376018 -281.082389) (xy 337.424237 -281.072545)
			(xy 337.473412 -281.070564) (xy 337.522267 -281.076496) (xy 337.569538 -281.090188) (xy 337.614 -281.111286)
			(xy 337.654503 -281.139242) (xy 337.689996 -281.173334) (xy 337.719561 -281.212678) (xy 337.742432 -281.256255)
			(xy 337.758016 -281.302936) (xy 337.765911 -281.351513) (xy 337.766406 -281.37612) (xy 338.095348 -281.37612)
			(xy 338.099308 -281.327066) (xy 338.111085 -281.279282) (xy 338.130376 -281.234006) (xy 338.156679 -281.19241)
			(xy 338.189314 -281.155573) (xy 338.227435 -281.124448) (xy 338.270056 -281.099841) (xy 338.316072 -281.082389)
			(xy 338.364291 -281.072545) (xy 338.413466 -281.070564) (xy 338.462321 -281.076496) (xy 338.509592 -281.090188)
			(xy 338.554054 -281.111286) (xy 338.594557 -281.139242) (xy 338.63005 -281.173334) (xy 338.659615 -281.212678)
			(xy 338.682486 -281.256255) (xy 338.69807 -281.302936) (xy 338.705965 -281.351513) (xy 338.70646 -281.37612)
			(xy 338.705965 -281.400727) (xy 338.69807 -281.449304) (xy 338.682486 -281.495985) (xy 338.659615 -281.539562)
			(xy 338.63005 -281.578906) (xy 338.594557 -281.612998) (xy 338.554054 -281.640954) (xy 338.509592 -281.662052)
			(xy 338.462321 -281.675744) (xy 338.413466 -281.681676) (xy 338.364291 -281.679695) (xy 338.316072 -281.669851)
			(xy 338.270056 -281.652399) (xy 338.227435 -281.627792) (xy 338.189314 -281.596667) (xy 338.156679 -281.55983)
			(xy 338.130376 -281.518234) (xy 338.111085 -281.472958) (xy 338.099308 -281.425174) (xy 338.095348 -281.37612)
			(xy 337.766406 -281.37612) (xy 337.765911 -281.400727) (xy 337.758016 -281.449304) (xy 337.742432 -281.495985)
			(xy 337.719561 -281.539562) (xy 337.689996 -281.578906) (xy 337.654503 -281.612998) (xy 337.614 -281.640954)
			(xy 337.569538 -281.662052) (xy 337.522267 -281.675744) (xy 337.473412 -281.681676) (xy 337.424237 -281.679695)
			(xy 337.376018 -281.669851) (xy 337.330002 -281.652399) (xy 337.287381 -281.627792) (xy 337.24926 -281.596667)
			(xy 337.216625 -281.55983) (xy 337.190322 -281.518234) (xy 337.171031 -281.472958) (xy 337.159254 -281.425174)
			(xy 337.155294 -281.37612) (xy 336.826352 -281.37612) (xy 336.825857 -281.400727) (xy 336.817962 -281.449304)
			(xy 336.802378 -281.495985) (xy 336.779507 -281.539562) (xy 336.749942 -281.578906) (xy 336.714449 -281.612998)
			(xy 336.673946 -281.640954) (xy 336.629484 -281.662052) (xy 336.582213 -281.675744) (xy 336.533358 -281.681676)
			(xy 336.484183 -281.679695) (xy 336.435964 -281.669851) (xy 336.389948 -281.652399) (xy 336.347327 -281.627792)
			(xy 336.309206 -281.596667) (xy 336.276571 -281.55983) (xy 336.250268 -281.518234) (xy 336.230977 -281.472958)
			(xy 336.2192 -281.425174) (xy 336.21524 -281.37612) (xy 335.886298 -281.37612) (xy 335.885803 -281.400727)
			(xy 335.877908 -281.449304) (xy 335.862324 -281.495985) (xy 335.839453 -281.539562) (xy 335.809888 -281.578906)
			(xy 335.774395 -281.612998) (xy 335.733892 -281.640954) (xy 335.68943 -281.662052) (xy 335.642159 -281.675744)
			(xy 335.593304 -281.681676) (xy 335.544129 -281.679695) (xy 335.49591 -281.669851) (xy 335.449894 -281.652399)
			(xy 335.407273 -281.627792) (xy 335.369152 -281.596667) (xy 335.336517 -281.55983) (xy 335.310214 -281.518234)
			(xy 335.290923 -281.472958) (xy 335.279146 -281.425174) (xy 335.275186 -281.37612) (xy 334.946498 -281.37612)
			(xy 334.946003 -281.400727) (xy 334.938108 -281.449304) (xy 334.922524 -281.495985) (xy 334.899653 -281.539562)
			(xy 334.870088 -281.578906) (xy 334.834595 -281.612998) (xy 334.794092 -281.640954) (xy 334.74963 -281.662052)
			(xy 334.702359 -281.675744) (xy 334.653504 -281.681676) (xy 334.604329 -281.679695) (xy 334.55611 -281.669851)
			(xy 334.510094 -281.652399) (xy 334.467473 -281.627792) (xy 334.429352 -281.596667) (xy 334.396717 -281.55983)
			(xy 334.370414 -281.518234) (xy 334.351123 -281.472958) (xy 334.339346 -281.425174) (xy 334.335386 -281.37612)
			(xy 334.006444 -281.37612) (xy 334.005949 -281.400727) (xy 333.998054 -281.449304) (xy 333.98247 -281.495985)
			(xy 333.959599 -281.539562) (xy 333.930034 -281.578906) (xy 333.894541 -281.612998) (xy 333.854038 -281.640954)
			(xy 333.809576 -281.662052) (xy 333.762305 -281.675744) (xy 333.71345 -281.681676) (xy 333.664275 -281.679695)
			(xy 333.616056 -281.669851) (xy 333.57004 -281.652399) (xy 333.527419 -281.627792) (xy 333.489298 -281.596667)
			(xy 333.456663 -281.55983) (xy 333.43036 -281.518234) (xy 333.411069 -281.472958) (xy 333.399292 -281.425174)
			(xy 333.395332 -281.37612) (xy 333.06639 -281.37612) (xy 333.065895 -281.400727) (xy 333.058 -281.449304)
			(xy 333.042416 -281.495985) (xy 333.019545 -281.539562) (xy 332.98998 -281.578906) (xy 332.954487 -281.612998)
			(xy 332.913984 -281.640954) (xy 332.869522 -281.662052) (xy 332.822251 -281.675744) (xy 332.773396 -281.681676)
			(xy 332.724221 -281.679695) (xy 332.676002 -281.669851) (xy 332.629986 -281.652399) (xy 332.587365 -281.627792)
			(xy 332.549244 -281.596667) (xy 332.516609 -281.55983) (xy 332.490306 -281.518234) (xy 332.471015 -281.472958)
			(xy 332.459238 -281.425174) (xy 332.455278 -281.37612) (xy 332.126809 -281.37612) (xy 332.122641 -281.426432)
			(xy 332.110243 -281.475391) (xy 332.089957 -281.521642) (xy 332.062335 -281.563924) (xy 332.028131 -281.601082)
			(xy 331.988278 -281.632105) (xy 331.943862 -281.656145) (xy 331.896095 -281.672547) (xy 331.84628 -281.680864)
			(xy 331.821028 -281.681428) (xy 331.808265 -281.681288) (xy 331.782832 -281.679123) (xy 331.770228 -281.67711)
			(xy 331.743541 -281.672029) (xy 331.692409 -281.653693) (xy 331.645332 -281.626592) (xy 331.624178 -281.609546)
			(xy 331.61859 -281.604974) (xy 331.605636 -281.599132) (xy 331.59827 -281.598116) (xy 331.591061 -281.597434)
			(xy 331.576753 -281.599631) (xy 331.570076 -281.602434) (xy 331.487018 -281.640788) (xy 331.479154 -281.645231)
			(xy 331.466942 -281.658523) (xy 331.460081 -281.675218) (xy 331.459332 -281.684222) (xy 331.459332 -281.867864)
			(xy 331.459571 -281.874815) (xy 331.463306 -281.888208) (xy 331.466698 -281.89428) (xy 331.47 -281.89936)
			(xy 331.480414 -281.909012) (xy 331.487526 -281.912568) (xy 331.508973 -281.923795) (xy 331.548329 -281.951979)
			(xy 331.582753 -281.986013) (xy 331.611384 -282.025045) (xy 331.633508 -282.068101) (xy 331.64857 -282.114105)
			(xy 331.656196 -282.161908) (xy 331.656195 -282.186126) (xy 331.985378 -282.186126) (xy 331.989338 -282.137072)
			(xy 332.001115 -282.089288) (xy 332.020406 -282.044012) (xy 332.046709 -282.002416) (xy 332.079344 -281.965579)
			(xy 332.117465 -281.934454) (xy 332.160086 -281.909847) (xy 332.206102 -281.892395) (xy 332.254321 -281.882551)
			(xy 332.303496 -281.88057) (xy 332.352351 -281.886502) (xy 332.399622 -281.900194) (xy 332.444084 -281.921292)
			(xy 332.484587 -281.949248) (xy 332.52008 -281.98334) (xy 332.549645 -282.022684) (xy 332.572516 -282.066261)
			(xy 332.5881 -282.112942) (xy 332.595995 -282.161519) (xy 332.59649 -282.186126) (xy 332.925178 -282.186126)
			(xy 332.929138 -282.137072) (xy 332.940915 -282.089288) (xy 332.960206 -282.044012) (xy 332.986509 -282.002416)
			(xy 333.019144 -281.965579) (xy 333.057265 -281.934454) (xy 333.099886 -281.909847) (xy 333.145902 -281.892395)
			(xy 333.194121 -281.882551) (xy 333.243296 -281.88057) (xy 333.292151 -281.886502) (xy 333.339422 -281.900194)
			(xy 333.383884 -281.921292) (xy 333.424387 -281.949248) (xy 333.45988 -281.98334) (xy 333.489445 -282.022684)
			(xy 333.512316 -282.066261) (xy 333.5279 -282.112942) (xy 333.535795 -282.161519) (xy 333.53629 -282.186126)
			(xy 333.865232 -282.186126) (xy 333.869192 -282.137072) (xy 333.880969 -282.089288) (xy 333.90026 -282.044012)
			(xy 333.926563 -282.002416) (xy 333.959198 -281.965579) (xy 333.997319 -281.934454) (xy 334.03994 -281.909847)
			(xy 334.085956 -281.892395) (xy 334.134175 -281.882551) (xy 334.18335 -281.88057) (xy 334.232205 -281.886502)
			(xy 334.279476 -281.900194) (xy 334.323938 -281.921292) (xy 334.364441 -281.949248) (xy 334.399934 -281.98334)
			(xy 334.429499 -282.022684) (xy 334.45237 -282.066261) (xy 334.467954 -282.112942) (xy 334.475849 -282.161519)
			(xy 334.476344 -282.186126) (xy 334.805286 -282.186126) (xy 334.809246 -282.137072) (xy 334.821023 -282.089288)
			(xy 334.840314 -282.044012) (xy 334.866617 -282.002416) (xy 334.899252 -281.965579) (xy 334.937373 -281.934454)
			(xy 334.979994 -281.909847) (xy 335.02601 -281.892395) (xy 335.074229 -281.882551) (xy 335.123404 -281.88057)
			(xy 335.172259 -281.886502) (xy 335.21953 -281.900194) (xy 335.263992 -281.921292) (xy 335.304495 -281.949248)
			(xy 335.339988 -281.98334) (xy 335.369553 -282.022684) (xy 335.392424 -282.066261) (xy 335.408008 -282.112942)
			(xy 335.415903 -282.161519) (xy 335.416398 -282.186126) (xy 335.74534 -282.186126) (xy 335.7493 -282.137072)
			(xy 335.761077 -282.089288) (xy 335.780368 -282.044012) (xy 335.806671 -282.002416) (xy 335.839306 -281.965579)
			(xy 335.877427 -281.934454) (xy 335.920048 -281.909847) (xy 335.966064 -281.892395) (xy 336.014283 -281.882551)
			(xy 336.063458 -281.88057) (xy 336.112313 -281.886502) (xy 336.159584 -281.900194) (xy 336.204046 -281.921292)
			(xy 336.244549 -281.949248) (xy 336.280042 -281.98334) (xy 336.309607 -282.022684) (xy 336.332478 -282.066261)
			(xy 336.348062 -282.112942) (xy 336.355957 -282.161519) (xy 336.356452 -282.186126) (xy 336.685394 -282.186126)
			(xy 336.689354 -282.137072) (xy 336.701131 -282.089288) (xy 336.720422 -282.044012) (xy 336.746725 -282.002416)
			(xy 336.77936 -281.965579) (xy 336.817481 -281.934454) (xy 336.860102 -281.909847) (xy 336.906118 -281.892395)
			(xy 336.954337 -281.882551) (xy 337.003512 -281.88057) (xy 337.052367 -281.886502) (xy 337.099638 -281.900194)
			(xy 337.1441 -281.921292) (xy 337.184603 -281.949248) (xy 337.220096 -281.98334) (xy 337.249661 -282.022684)
			(xy 337.272532 -282.066261) (xy 337.288116 -282.112942) (xy 337.296011 -282.161519) (xy 337.296506 -282.186126)
			(xy 337.625194 -282.186126) (xy 337.629154 -282.137072) (xy 337.640931 -282.089288) (xy 337.660222 -282.044012)
			(xy 337.686525 -282.002416) (xy 337.71916 -281.965579) (xy 337.757281 -281.934454) (xy 337.799902 -281.909847)
			(xy 337.845918 -281.892395) (xy 337.894137 -281.882551) (xy 337.943312 -281.88057) (xy 337.992167 -281.886502)
			(xy 338.039438 -281.900194) (xy 338.0839 -281.921292) (xy 338.124403 -281.949248) (xy 338.159896 -281.98334)
			(xy 338.189461 -282.022684) (xy 338.212332 -282.066261) (xy 338.227916 -282.112942) (xy 338.235811 -282.161519)
			(xy 338.236306 -282.186126) (xy 338.235811 -282.210733) (xy 338.227916 -282.25931) (xy 338.212332 -282.305991)
			(xy 338.189461 -282.349568) (xy 338.159896 -282.388912) (xy 338.124403 -282.423004) (xy 338.0839 -282.45096)
			(xy 338.039438 -282.472058) (xy 337.992167 -282.48575) (xy 337.943312 -282.491682) (xy 337.894137 -282.489701)
			(xy 337.845918 -282.479857) (xy 337.799902 -282.462405) (xy 337.757281 -282.437798) (xy 337.71916 -282.406673)
			(xy 337.686525 -282.369836) (xy 337.660222 -282.32824) (xy 337.640931 -282.282964) (xy 337.629154 -282.23518)
			(xy 337.625194 -282.186126) (xy 337.296506 -282.186126) (xy 337.296011 -282.210733) (xy 337.288116 -282.25931)
			(xy 337.272532 -282.305991) (xy 337.249661 -282.349568) (xy 337.220096 -282.388912) (xy 337.184603 -282.423004)
			(xy 337.1441 -282.45096) (xy 337.099638 -282.472058) (xy 337.052367 -282.48575) (xy 337.003512 -282.491682)
			(xy 336.954337 -282.489701) (xy 336.906118 -282.479857) (xy 336.860102 -282.462405) (xy 336.817481 -282.437798)
			(xy 336.77936 -282.406673) (xy 336.746725 -282.369836) (xy 336.720422 -282.32824) (xy 336.701131 -282.282964)
			(xy 336.689354 -282.23518) (xy 336.685394 -282.186126) (xy 336.356452 -282.186126) (xy 336.355957 -282.210733)
			(xy 336.348062 -282.25931) (xy 336.332478 -282.305991) (xy 336.309607 -282.349568) (xy 336.280042 -282.388912)
			(xy 336.244549 -282.423004) (xy 336.204046 -282.45096) (xy 336.159584 -282.472058) (xy 336.112313 -282.48575)
			(xy 336.063458 -282.491682) (xy 336.014283 -282.489701) (xy 335.966064 -282.479857) (xy 335.920048 -282.462405)
			(xy 335.877427 -282.437798) (xy 335.839306 -282.406673) (xy 335.806671 -282.369836) (xy 335.780368 -282.32824)
			(xy 335.761077 -282.282964) (xy 335.7493 -282.23518) (xy 335.74534 -282.186126) (xy 335.416398 -282.186126)
			(xy 335.415903 -282.210733) (xy 335.408008 -282.25931) (xy 335.392424 -282.305991) (xy 335.369553 -282.349568)
			(xy 335.339988 -282.388912) (xy 335.304495 -282.423004) (xy 335.263992 -282.45096) (xy 335.21953 -282.472058)
			(xy 335.172259 -282.48575) (xy 335.123404 -282.491682) (xy 335.074229 -282.489701) (xy 335.02601 -282.479857)
			(xy 334.979994 -282.462405) (xy 334.937373 -282.437798) (xy 334.899252 -282.406673) (xy 334.866617 -282.369836)
			(xy 334.840314 -282.32824) (xy 334.821023 -282.282964) (xy 334.809246 -282.23518) (xy 334.805286 -282.186126)
			(xy 334.476344 -282.186126) (xy 334.475849 -282.210733) (xy 334.467954 -282.25931) (xy 334.45237 -282.305991)
			(xy 334.429499 -282.349568) (xy 334.399934 -282.388912) (xy 334.364441 -282.423004) (xy 334.323938 -282.45096)
			(xy 334.279476 -282.472058) (xy 334.232205 -282.48575) (xy 334.18335 -282.491682) (xy 334.134175 -282.489701)
			(xy 334.085956 -282.479857) (xy 334.03994 -282.462405) (xy 333.997319 -282.437798) (xy 333.959198 -282.406673)
			(xy 333.926563 -282.369836) (xy 333.90026 -282.32824) (xy 333.880969 -282.282964) (xy 333.869192 -282.23518)
			(xy 333.865232 -282.186126) (xy 333.53629 -282.186126) (xy 333.535795 -282.210733) (xy 333.5279 -282.25931)
			(xy 333.512316 -282.305991) (xy 333.489445 -282.349568) (xy 333.45988 -282.388912) (xy 333.424387 -282.423004)
			(xy 333.383884 -282.45096) (xy 333.339422 -282.472058) (xy 333.292151 -282.48575) (xy 333.243296 -282.491682)
			(xy 333.194121 -282.489701) (xy 333.145902 -282.479857) (xy 333.099886 -282.462405) (xy 333.057265 -282.437798)
			(xy 333.019144 -282.406673) (xy 332.986509 -282.369836) (xy 332.960206 -282.32824) (xy 332.940915 -282.282964)
			(xy 332.929138 -282.23518) (xy 332.925178 -282.186126) (xy 332.59649 -282.186126) (xy 332.595995 -282.210733)
			(xy 332.5881 -282.25931) (xy 332.572516 -282.305991) (xy 332.549645 -282.349568) (xy 332.52008 -282.388912)
			(xy 332.484587 -282.423004) (xy 332.444084 -282.45096) (xy 332.399622 -282.472058) (xy 332.352351 -282.48575)
			(xy 332.303496 -282.491682) (xy 332.254321 -282.489701) (xy 332.206102 -282.479857) (xy 332.160086 -282.462405)
			(xy 332.117465 -282.437798) (xy 332.079344 -282.406673) (xy 332.046709 -282.369836) (xy 332.020406 -282.32824)
			(xy 332.001115 -282.282964) (xy 331.989338 -282.23518) (xy 331.985378 -282.186126) (xy 331.656195 -282.186126)
			(xy 331.656194 -282.210315) (xy 331.648565 -282.258118) (xy 331.633499 -282.304121) (xy 331.611372 -282.347175)
			(xy 331.582738 -282.386205) (xy 331.548312 -282.420236) (xy 331.508953 -282.448417) (xy 331.487526 -282.459684)
			(xy 331.486764 -282.459938) (xy 331.480509 -282.463342) (xy 331.470065 -282.473013) (xy 331.46619 -282.478988)
			(xy 331.463142 -282.484068) (xy 331.459332 -282.497276) (xy 331.459332 -282.686252) (xy 331.459807 -282.695623)
			(xy 331.466654 -282.713076) (xy 331.479333 -282.726885) (xy 331.487526 -282.731464) (xy 331.518006 -282.745688)
			(xy 331.566266 -282.76804) (xy 331.56955 -282.769537) (xy 331.576432 -282.771711) (xy 331.579982 -282.772358)
			(xy 331.584357 -282.77291) (xy 331.593171 -282.772652) (xy 331.597508 -282.77185) (xy 331.605382 -282.769818)
			(xy 331.62367 -282.76296) (xy 331.63002 -282.75788) (xy 331.650501 -282.742169) (xy 331.695638 -282.717137)
			(xy 331.74434 -282.700045) (xy 331.795221 -282.691378) (xy 331.821028 -282.690824) (xy 331.846279 -282.691348)
			(xy 331.896092 -282.699664) (xy 331.943857 -282.716066) (xy 331.988271 -282.740105) (xy 332.028123 -282.771126)
			(xy 332.062326 -282.808284) (xy 332.089946 -282.850564) (xy 332.110232 -282.896813) (xy 332.122629 -282.94577)
			(xy 332.126799 -282.9961) (xy 332.126796 -282.996132) (xy 332.455278 -282.996132) (xy 332.459238 -282.947078)
			(xy 332.471015 -282.899294) (xy 332.490306 -282.854018) (xy 332.516609 -282.812422) (xy 332.549244 -282.775585)
			(xy 332.587365 -282.74446) (xy 332.629986 -282.719853) (xy 332.676002 -282.702401) (xy 332.724221 -282.692557)
			(xy 332.773396 -282.690576) (xy 332.822251 -282.696508) (xy 332.869522 -282.7102) (xy 332.913984 -282.731298)
			(xy 332.954487 -282.759254) (xy 332.98998 -282.793346) (xy 333.019545 -282.83269) (xy 333.042416 -282.876267)
			(xy 333.058 -282.922948) (xy 333.065895 -282.971525) (xy 333.06639 -282.996132) (xy 333.395332 -282.996132)
			(xy 333.399292 -282.947078) (xy 333.411069 -282.899294) (xy 333.43036 -282.854018) (xy 333.456663 -282.812422)
			(xy 333.489298 -282.775585) (xy 333.527419 -282.74446) (xy 333.57004 -282.719853) (xy 333.616056 -282.702401)
			(xy 333.664275 -282.692557) (xy 333.71345 -282.690576) (xy 333.762305 -282.696508) (xy 333.809576 -282.7102)
			(xy 333.854038 -282.731298) (xy 333.894541 -282.759254) (xy 333.930034 -282.793346) (xy 333.959599 -282.83269)
			(xy 333.98247 -282.876267) (xy 333.998054 -282.922948) (xy 334.005949 -282.971525) (xy 334.006444 -282.996132)
			(xy 335.275186 -282.996132) (xy 335.279146 -282.947078) (xy 335.290923 -282.899294) (xy 335.310214 -282.854018)
			(xy 335.336517 -282.812422) (xy 335.369152 -282.775585) (xy 335.407273 -282.74446) (xy 335.449894 -282.719853)
			(xy 335.49591 -282.702401) (xy 335.544129 -282.692557) (xy 335.593304 -282.690576) (xy 335.642159 -282.696508)
			(xy 335.68943 -282.7102) (xy 335.733892 -282.731298) (xy 335.774395 -282.759254) (xy 335.809888 -282.793346)
			(xy 335.839453 -282.83269) (xy 335.862324 -282.876267) (xy 335.877908 -282.922948) (xy 335.885803 -282.971525)
			(xy 335.886298 -282.996132) (xy 336.21524 -282.996132) (xy 336.2192 -282.947078) (xy 336.230977 -282.899294)
			(xy 336.250268 -282.854018) (xy 336.276571 -282.812422) (xy 336.309206 -282.775585) (xy 336.347327 -282.74446)
			(xy 336.389948 -282.719853) (xy 336.435964 -282.702401) (xy 336.484183 -282.692557) (xy 336.533358 -282.690576)
			(xy 336.582213 -282.696508) (xy 336.629484 -282.7102) (xy 336.673946 -282.731298) (xy 336.714449 -282.759254)
			(xy 336.749942 -282.793346) (xy 336.779507 -282.83269) (xy 336.802378 -282.876267) (xy 336.817962 -282.922948)
			(xy 336.825857 -282.971525) (xy 336.826352 -282.996132) (xy 337.155294 -282.996132) (xy 337.159254 -282.947078)
			(xy 337.171031 -282.899294) (xy 337.190322 -282.854018) (xy 337.216625 -282.812422) (xy 337.24926 -282.775585)
			(xy 337.287381 -282.74446) (xy 337.330002 -282.719853) (xy 337.376018 -282.702401) (xy 337.424237 -282.692557)
			(xy 337.473412 -282.690576) (xy 337.522267 -282.696508) (xy 337.569538 -282.7102) (xy 337.614 -282.731298)
			(xy 337.654503 -282.759254) (xy 337.689996 -282.793346) (xy 337.719561 -282.83269) (xy 337.742432 -282.876267)
			(xy 337.758016 -282.922948) (xy 337.765911 -282.971525) (xy 337.766406 -282.996132) (xy 338.095348 -282.996132)
			(xy 338.099308 -282.947078) (xy 338.111085 -282.899294) (xy 338.130376 -282.854018) (xy 338.156679 -282.812422)
			(xy 338.189314 -282.775585) (xy 338.227435 -282.74446) (xy 338.270056 -282.719853) (xy 338.316072 -282.702401)
			(xy 338.364291 -282.692557) (xy 338.413466 -282.690576) (xy 338.462321 -282.696508) (xy 338.509592 -282.7102)
			(xy 338.554054 -282.731298) (xy 338.594557 -282.759254) (xy 338.63005 -282.793346) (xy 338.659615 -282.83269)
			(xy 338.682486 -282.876267) (xy 338.69807 -282.922948) (xy 338.705965 -282.971525) (xy 338.70646 -282.996132)
			(xy 338.705965 -283.020739) (xy 338.69807 -283.069316) (xy 338.682486 -283.115997) (xy 338.659615 -283.159574)
			(xy 338.63005 -283.198918) (xy 338.594557 -283.23301) (xy 338.554054 -283.260966) (xy 338.509592 -283.282064)
			(xy 338.462321 -283.295756) (xy 338.413466 -283.301688) (xy 338.364291 -283.299707) (xy 338.316072 -283.289863)
			(xy 338.270056 -283.272411) (xy 338.227435 -283.247804) (xy 338.189314 -283.216679) (xy 338.156679 -283.179842)
			(xy 338.130376 -283.138246) (xy 338.111085 -283.09297) (xy 338.099308 -283.045186) (xy 338.095348 -282.996132)
			(xy 337.766406 -282.996132) (xy 337.765911 -283.020739) (xy 337.758016 -283.069316) (xy 337.742432 -283.115997)
			(xy 337.719561 -283.159574) (xy 337.689996 -283.198918) (xy 337.654503 -283.23301) (xy 337.614 -283.260966)
			(xy 337.569538 -283.282064) (xy 337.522267 -283.295756) (xy 337.473412 -283.301688) (xy 337.424237 -283.299707)
			(xy 337.376018 -283.289863) (xy 337.330002 -283.272411) (xy 337.287381 -283.247804) (xy 337.24926 -283.216679)
			(xy 337.216625 -283.179842) (xy 337.190322 -283.138246) (xy 337.171031 -283.09297) (xy 337.159254 -283.045186)
			(xy 337.155294 -282.996132) (xy 336.826352 -282.996132) (xy 336.825857 -283.020739) (xy 336.817962 -283.069316)
			(xy 336.802378 -283.115997) (xy 336.779507 -283.159574) (xy 336.749942 -283.198918) (xy 336.714449 -283.23301)
			(xy 336.673946 -283.260966) (xy 336.629484 -283.282064) (xy 336.582213 -283.295756) (xy 336.533358 -283.301688)
			(xy 336.484183 -283.299707) (xy 336.435964 -283.289863) (xy 336.389948 -283.272411) (xy 336.347327 -283.247804)
			(xy 336.309206 -283.216679) (xy 336.276571 -283.179842) (xy 336.250268 -283.138246) (xy 336.230977 -283.09297)
			(xy 336.2192 -283.045186) (xy 336.21524 -282.996132) (xy 335.886298 -282.996132) (xy 335.885803 -283.020739)
			(xy 335.877908 -283.069316) (xy 335.862324 -283.115997) (xy 335.839453 -283.159574) (xy 335.809888 -283.198918)
			(xy 335.774395 -283.23301) (xy 335.733892 -283.260966) (xy 335.68943 -283.282064) (xy 335.642159 -283.295756)
			(xy 335.593304 -283.301688) (xy 335.544129 -283.299707) (xy 335.49591 -283.289863) (xy 335.449894 -283.272411)
			(xy 335.407273 -283.247804) (xy 335.369152 -283.216679) (xy 335.336517 -283.179842) (xy 335.310214 -283.138246)
			(xy 335.290923 -283.09297) (xy 335.279146 -283.045186) (xy 335.275186 -282.996132) (xy 334.006444 -282.996132)
			(xy 334.005949 -283.020739) (xy 333.998054 -283.069316) (xy 333.98247 -283.115997) (xy 333.959599 -283.159574)
			(xy 333.930034 -283.198918) (xy 333.894541 -283.23301) (xy 333.854038 -283.260966) (xy 333.809576 -283.282064)
			(xy 333.762305 -283.295756) (xy 333.71345 -283.301688) (xy 333.664275 -283.299707) (xy 333.616056 -283.289863)
			(xy 333.57004 -283.272411) (xy 333.527419 -283.247804) (xy 333.489298 -283.216679) (xy 333.456663 -283.179842)
			(xy 333.43036 -283.138246) (xy 333.411069 -283.09297) (xy 333.399292 -283.045186) (xy 333.395332 -282.996132)
			(xy 333.06639 -282.996132) (xy 333.065895 -283.020739) (xy 333.058 -283.069316) (xy 333.042416 -283.115997)
			(xy 333.019545 -283.159574) (xy 332.98998 -283.198918) (xy 332.954487 -283.23301) (xy 332.913984 -283.260966)
			(xy 332.869522 -283.282064) (xy 332.822251 -283.295756) (xy 332.773396 -283.301688) (xy 332.724221 -283.299707)
			(xy 332.676002 -283.289863) (xy 332.629986 -283.272411) (xy 332.587365 -283.247804) (xy 332.549244 -283.216679)
			(xy 332.516609 -283.179842) (xy 332.490306 -283.138246) (xy 332.471015 -283.09297) (xy 332.459238 -283.045186)
			(xy 332.455278 -282.996132) (xy 332.126796 -282.996132) (xy 332.122629 -283.04643) (xy 332.110232 -283.095387)
			(xy 332.089946 -283.141636) (xy 332.062326 -283.183916) (xy 332.028123 -283.221074) (xy 331.988271 -283.252095)
			(xy 331.943857 -283.276134) (xy 331.896092 -283.292536) (xy 331.846279 -283.300852) (xy 331.821028 -283.30144)
			(xy 331.808265 -283.3013) (xy 331.782832 -283.299135) (xy 331.770228 -283.297122) (xy 331.74354 -283.292042)
			(xy 331.692408 -283.273706) (xy 331.64533 -283.246606) (xy 331.624178 -283.229558) (xy 331.61859 -283.224986)
			(xy 331.605636 -283.219144) (xy 331.59827 -283.218128) (xy 331.591061 -283.217446) (xy 331.576753 -283.219643)
			(xy 331.570076 -283.222446) (xy 331.487018 -283.2608) (xy 331.479145 -283.265238) (xy 331.46691 -283.278526)
			(xy 331.460021 -283.295223) (xy 331.459332 -283.304234) (xy 331.459332 -283.487876) (xy 331.459573 -283.494827)
			(xy 331.46331 -283.508217) (xy 331.466698 -283.514292) (xy 331.47 -283.519372) (xy 331.480414 -283.529024)
			(xy 331.487526 -283.53258) (xy 331.508972 -283.543807) (xy 331.548327 -283.571991) (xy 331.582749 -283.606024)
			(xy 331.611378 -283.645055) (xy 331.6335 -283.68811) (xy 331.648561 -283.734113) (xy 331.656186 -283.781914)
			(xy 331.656184 -283.806138) (xy 331.985378 -283.806138) (xy 331.989338 -283.757084) (xy 332.001115 -283.7093)
			(xy 332.020406 -283.664024) (xy 332.046709 -283.622428) (xy 332.079344 -283.585591) (xy 332.117465 -283.554466)
			(xy 332.160086 -283.529859) (xy 332.206102 -283.512407) (xy 332.254321 -283.502563) (xy 332.303496 -283.500582)
			(xy 332.352351 -283.506514) (xy 332.399622 -283.520206) (xy 332.444084 -283.541304) (xy 332.484587 -283.56926)
			(xy 332.52008 -283.603352) (xy 332.549645 -283.642696) (xy 332.572516 -283.686273) (xy 332.5881 -283.732954)
			(xy 332.595995 -283.781531) (xy 332.59649 -283.806138) (xy 332.925178 -283.806138) (xy 332.929138 -283.757084)
			(xy 332.940915 -283.7093) (xy 332.960206 -283.664024) (xy 332.986509 -283.622428) (xy 333.019144 -283.585591)
			(xy 333.057265 -283.554466) (xy 333.099886 -283.529859) (xy 333.145902 -283.512407) (xy 333.194121 -283.502563)
			(xy 333.243296 -283.500582) (xy 333.292151 -283.506514) (xy 333.339422 -283.520206) (xy 333.383884 -283.541304)
			(xy 333.424387 -283.56926) (xy 333.45988 -283.603352) (xy 333.489445 -283.642696) (xy 333.512316 -283.686273)
			(xy 333.5279 -283.732954) (xy 333.535795 -283.781531) (xy 333.53629 -283.806138) (xy 333.865232 -283.806138)
			(xy 333.869192 -283.757084) (xy 333.880969 -283.7093) (xy 333.90026 -283.664024) (xy 333.926563 -283.622428)
			(xy 333.959198 -283.585591) (xy 333.997319 -283.554466) (xy 334.03994 -283.529859) (xy 334.085956 -283.512407)
			(xy 334.134175 -283.502563) (xy 334.18335 -283.500582) (xy 334.232205 -283.506514) (xy 334.279476 -283.520206)
			(xy 334.323938 -283.541304) (xy 334.364441 -283.56926) (xy 334.399934 -283.603352) (xy 334.429499 -283.642696)
			(xy 334.45237 -283.686273) (xy 334.467954 -283.732954) (xy 334.475849 -283.781531) (xy 334.476344 -283.806138)
			(xy 334.805286 -283.806138) (xy 334.809246 -283.757084) (xy 334.821023 -283.7093) (xy 334.840314 -283.664024)
			(xy 334.866617 -283.622428) (xy 334.899252 -283.585591) (xy 334.937373 -283.554466) (xy 334.979994 -283.529859)
			(xy 335.02601 -283.512407) (xy 335.074229 -283.502563) (xy 335.123404 -283.500582) (xy 335.172259 -283.506514)
			(xy 335.21953 -283.520206) (xy 335.263992 -283.541304) (xy 335.304495 -283.56926) (xy 335.339988 -283.603352)
			(xy 335.369553 -283.642696) (xy 335.392424 -283.686273) (xy 335.408008 -283.732954) (xy 335.415903 -283.781531)
			(xy 335.416398 -283.806138) (xy 335.74534 -283.806138) (xy 335.7493 -283.757084) (xy 335.761077 -283.7093)
			(xy 335.780368 -283.664024) (xy 335.806671 -283.622428) (xy 335.839306 -283.585591) (xy 335.877427 -283.554466)
			(xy 335.920048 -283.529859) (xy 335.966064 -283.512407) (xy 336.014283 -283.502563) (xy 336.063458 -283.500582)
			(xy 336.112313 -283.506514) (xy 336.159584 -283.520206) (xy 336.204046 -283.541304) (xy 336.244549 -283.56926)
			(xy 336.280042 -283.603352) (xy 336.309607 -283.642696) (xy 336.332478 -283.686273) (xy 336.348062 -283.732954)
			(xy 336.355957 -283.781531) (xy 336.356452 -283.806138) (xy 336.685394 -283.806138) (xy 336.689354 -283.757084)
			(xy 336.701131 -283.7093) (xy 336.720422 -283.664024) (xy 336.746725 -283.622428) (xy 336.77936 -283.585591)
			(xy 336.817481 -283.554466) (xy 336.860102 -283.529859) (xy 336.906118 -283.512407) (xy 336.954337 -283.502563)
			(xy 337.003512 -283.500582) (xy 337.052367 -283.506514) (xy 337.099638 -283.520206) (xy 337.1441 -283.541304)
			(xy 337.184603 -283.56926) (xy 337.220096 -283.603352) (xy 337.249661 -283.642696) (xy 337.272532 -283.686273)
			(xy 337.288116 -283.732954) (xy 337.296011 -283.781531) (xy 337.296506 -283.806138) (xy 337.625194 -283.806138)
			(xy 337.629154 -283.757084) (xy 337.640931 -283.7093) (xy 337.660222 -283.664024) (xy 337.686525 -283.622428)
			(xy 337.71916 -283.585591) (xy 337.757281 -283.554466) (xy 337.799902 -283.529859) (xy 337.845918 -283.512407)
			(xy 337.894137 -283.502563) (xy 337.943312 -283.500582) (xy 337.992167 -283.506514) (xy 338.039438 -283.520206)
			(xy 338.0839 -283.541304) (xy 338.124403 -283.56926) (xy 338.159896 -283.603352) (xy 338.189461 -283.642696)
			(xy 338.212332 -283.686273) (xy 338.227916 -283.732954) (xy 338.235811 -283.781531) (xy 338.236306 -283.806138)
			(xy 338.235811 -283.830745) (xy 338.227916 -283.879322) (xy 338.212332 -283.926003) (xy 338.189461 -283.96958)
			(xy 338.159896 -284.008924) (xy 338.124403 -284.043016) (xy 338.0839 -284.070972) (xy 338.039438 -284.09207)
			(xy 337.992167 -284.105762) (xy 337.943312 -284.111694) (xy 337.894137 -284.109713) (xy 337.845918 -284.099869)
			(xy 337.799902 -284.082417) (xy 337.757281 -284.05781) (xy 337.71916 -284.026685) (xy 337.686525 -283.989848)
			(xy 337.660222 -283.948252) (xy 337.640931 -283.902976) (xy 337.629154 -283.855192) (xy 337.625194 -283.806138)
			(xy 337.296506 -283.806138) (xy 337.296011 -283.830745) (xy 337.288116 -283.879322) (xy 337.272532 -283.926003)
			(xy 337.249661 -283.96958) (xy 337.220096 -284.008924) (xy 337.184603 -284.043016) (xy 337.1441 -284.070972)
			(xy 337.099638 -284.09207) (xy 337.052367 -284.105762) (xy 337.003512 -284.111694) (xy 336.954337 -284.109713)
			(xy 336.906118 -284.099869) (xy 336.860102 -284.082417) (xy 336.817481 -284.05781) (xy 336.77936 -284.026685)
			(xy 336.746725 -283.989848) (xy 336.720422 -283.948252) (xy 336.701131 -283.902976) (xy 336.689354 -283.855192)
			(xy 336.685394 -283.806138) (xy 336.356452 -283.806138) (xy 336.355957 -283.830745) (xy 336.348062 -283.879322)
			(xy 336.332478 -283.926003) (xy 336.309607 -283.96958) (xy 336.280042 -284.008924) (xy 336.244549 -284.043016)
			(xy 336.204046 -284.070972) (xy 336.159584 -284.09207) (xy 336.112313 -284.105762) (xy 336.063458 -284.111694)
			(xy 336.014283 -284.109713) (xy 335.966064 -284.099869) (xy 335.920048 -284.082417) (xy 335.877427 -284.05781)
			(xy 335.839306 -284.026685) (xy 335.806671 -283.989848) (xy 335.780368 -283.948252) (xy 335.761077 -283.902976)
			(xy 335.7493 -283.855192) (xy 335.74534 -283.806138) (xy 335.416398 -283.806138) (xy 335.415903 -283.830745)
			(xy 335.408008 -283.879322) (xy 335.392424 -283.926003) (xy 335.369553 -283.96958) (xy 335.339988 -284.008924)
			(xy 335.304495 -284.043016) (xy 335.263992 -284.070972) (xy 335.21953 -284.09207) (xy 335.172259 -284.105762)
			(xy 335.123404 -284.111694) (xy 335.074229 -284.109713) (xy 335.02601 -284.099869) (xy 334.979994 -284.082417)
			(xy 334.937373 -284.05781) (xy 334.899252 -284.026685) (xy 334.866617 -283.989848) (xy 334.840314 -283.948252)
			(xy 334.821023 -283.902976) (xy 334.809246 -283.855192) (xy 334.805286 -283.806138) (xy 334.476344 -283.806138)
			(xy 334.475849 -283.830745) (xy 334.467954 -283.879322) (xy 334.45237 -283.926003) (xy 334.429499 -283.96958)
			(xy 334.399934 -284.008924) (xy 334.364441 -284.043016) (xy 334.323938 -284.070972) (xy 334.279476 -284.09207)
			(xy 334.232205 -284.105762) (xy 334.18335 -284.111694) (xy 334.134175 -284.109713) (xy 334.085956 -284.099869)
			(xy 334.03994 -284.082417) (xy 333.997319 -284.05781) (xy 333.959198 -284.026685) (xy 333.926563 -283.989848)
			(xy 333.90026 -283.948252) (xy 333.880969 -283.902976) (xy 333.869192 -283.855192) (xy 333.865232 -283.806138)
			(xy 333.53629 -283.806138) (xy 333.535795 -283.830745) (xy 333.5279 -283.879322) (xy 333.512316 -283.926003)
			(xy 333.489445 -283.96958) (xy 333.45988 -284.008924) (xy 333.424387 -284.043016) (xy 333.383884 -284.070972)
			(xy 333.339422 -284.09207) (xy 333.292151 -284.105762) (xy 333.243296 -284.111694) (xy 333.194121 -284.109713)
			(xy 333.145902 -284.099869) (xy 333.099886 -284.082417) (xy 333.057265 -284.05781) (xy 333.019144 -284.026685)
			(xy 332.986509 -283.989848) (xy 332.960206 -283.948252) (xy 332.940915 -283.902976) (xy 332.929138 -283.855192)
			(xy 332.925178 -283.806138) (xy 332.59649 -283.806138) (xy 332.595995 -283.830745) (xy 332.5881 -283.879322)
			(xy 332.572516 -283.926003) (xy 332.549645 -283.96958) (xy 332.52008 -284.008924) (xy 332.484587 -284.043016)
			(xy 332.444084 -284.070972) (xy 332.399622 -284.09207) (xy 332.352351 -284.105762) (xy 332.303496 -284.111694)
			(xy 332.254321 -284.109713) (xy 332.206102 -284.099869) (xy 332.160086 -284.082417) (xy 332.117465 -284.05781)
			(xy 332.079344 -284.026685) (xy 332.046709 -283.989848) (xy 332.020406 -283.948252) (xy 332.001115 -283.902976)
			(xy 331.989338 -283.855192) (xy 331.985378 -283.806138) (xy 331.656184 -283.806138) (xy 331.656183 -283.83032)
			(xy 331.648553 -283.87812) (xy 331.633487 -283.924121) (xy 331.61136 -283.967174) (xy 331.582726 -284.006202)
			(xy 331.548301 -284.040231) (xy 331.508943 -284.06841) (xy 331.487526 -284.079696) (xy 331.486764 -284.07995)
			(xy 331.480504 -284.083349) (xy 331.470046 -284.093012) (xy 331.46619 -284.099) (xy 331.463142 -284.10408)
			(xy 331.459332 -284.117288) (xy 331.459332 -284.306264) (xy 331.459809 -284.315634) (xy 331.466658 -284.333083)
			(xy 331.479339 -284.346888) (xy 331.487526 -284.351476) (xy 331.518006 -284.3657) (xy 331.566266 -284.388052)
			(xy 331.56955 -284.389549) (xy 331.576432 -284.391722) (xy 331.579982 -284.39237) (xy 331.584357 -284.392922)
			(xy 331.593171 -284.392664) (xy 331.597508 -284.391862) (xy 331.605382 -284.38983) (xy 331.62367 -284.382972)
			(xy 331.63002 -284.377892) (xy 331.650501 -284.362181) (xy 331.695638 -284.337148) (xy 331.74434 -284.320055)
			(xy 331.795221 -284.311387) (xy 331.821028 -284.310836) (xy 331.846278 -284.31136) (xy 331.896089 -284.319676)
			(xy 331.943852 -284.336077) (xy 331.988264 -284.360115) (xy 332.028115 -284.391135) (xy 332.062316 -284.428291)
			(xy 332.089936 -284.470569) (xy 332.110221 -284.516817) (xy 332.122617 -284.565772) (xy 332.126787 -284.6161)
			(xy 332.126783 -284.616144) (xy 332.455278 -284.616144) (xy 332.459238 -284.56709) (xy 332.471015 -284.519306)
			(xy 332.490306 -284.47403) (xy 332.516609 -284.432434) (xy 332.549244 -284.395597) (xy 332.587365 -284.364472)
			(xy 332.629986 -284.339865) (xy 332.676002 -284.322413) (xy 332.724221 -284.312569) (xy 332.773396 -284.310588)
			(xy 332.822251 -284.31652) (xy 332.869522 -284.330212) (xy 332.913984 -284.35131) (xy 332.954487 -284.379266)
			(xy 332.98998 -284.413358) (xy 333.019545 -284.452702) (xy 333.042416 -284.496279) (xy 333.058 -284.54296)
			(xy 333.065895 -284.591537) (xy 333.06639 -284.616144) (xy 333.395332 -284.616144) (xy 333.399292 -284.56709)
			(xy 333.411069 -284.519306) (xy 333.43036 -284.47403) (xy 333.456663 -284.432434) (xy 333.489298 -284.395597)
			(xy 333.527419 -284.364472) (xy 333.57004 -284.339865) (xy 333.616056 -284.322413) (xy 333.664275 -284.312569)
			(xy 333.71345 -284.310588) (xy 333.762305 -284.31652) (xy 333.809576 -284.330212) (xy 333.854038 -284.35131)
			(xy 333.894541 -284.379266) (xy 333.930034 -284.413358) (xy 333.959599 -284.452702) (xy 333.98247 -284.496279)
			(xy 333.998054 -284.54296) (xy 334.005949 -284.591537) (xy 334.006444 -284.616144) (xy 334.335386 -284.616144)
			(xy 334.339346 -284.56709) (xy 334.351123 -284.519306) (xy 334.370414 -284.47403) (xy 334.396717 -284.432434)
			(xy 334.429352 -284.395597) (xy 334.467473 -284.364472) (xy 334.510094 -284.339865) (xy 334.55611 -284.322413)
			(xy 334.604329 -284.312569) (xy 334.653504 -284.310588) (xy 334.702359 -284.31652) (xy 334.74963 -284.330212)
			(xy 334.794092 -284.35131) (xy 334.834595 -284.379266) (xy 334.870088 -284.413358) (xy 334.899653 -284.452702)
			(xy 334.922524 -284.496279) (xy 334.938108 -284.54296) (xy 334.946003 -284.591537) (xy 334.946498 -284.616144)
			(xy 335.275186 -284.616144) (xy 335.279146 -284.56709) (xy 335.290923 -284.519306) (xy 335.310214 -284.47403)
			(xy 335.336517 -284.432434) (xy 335.369152 -284.395597) (xy 335.407273 -284.364472) (xy 335.449894 -284.339865)
			(xy 335.49591 -284.322413) (xy 335.544129 -284.312569) (xy 335.593304 -284.310588) (xy 335.642159 -284.31652)
			(xy 335.68943 -284.330212) (xy 335.733892 -284.35131) (xy 335.774395 -284.379266) (xy 335.809888 -284.413358)
			(xy 335.839453 -284.452702) (xy 335.862324 -284.496279) (xy 335.877908 -284.54296) (xy 335.885803 -284.591537)
			(xy 335.886298 -284.616144) (xy 336.21524 -284.616144) (xy 336.2192 -284.56709) (xy 336.230977 -284.519306)
			(xy 336.250268 -284.47403) (xy 336.276571 -284.432434) (xy 336.309206 -284.395597) (xy 336.347327 -284.364472)
			(xy 336.389948 -284.339865) (xy 336.435964 -284.322413) (xy 336.484183 -284.312569) (xy 336.533358 -284.310588)
			(xy 336.582213 -284.31652) (xy 336.629484 -284.330212) (xy 336.673946 -284.35131) (xy 336.714449 -284.379266)
			(xy 336.749942 -284.413358) (xy 336.779507 -284.452702) (xy 336.802378 -284.496279) (xy 336.817962 -284.54296)
			(xy 336.825857 -284.591537) (xy 336.826352 -284.616144) (xy 337.155294 -284.616144) (xy 337.159254 -284.56709)
			(xy 337.171031 -284.519306) (xy 337.190322 -284.47403) (xy 337.216625 -284.432434) (xy 337.24926 -284.395597)
			(xy 337.287381 -284.364472) (xy 337.330002 -284.339865) (xy 337.376018 -284.322413) (xy 337.424237 -284.312569)
			(xy 337.473412 -284.310588) (xy 337.522267 -284.31652) (xy 337.569538 -284.330212) (xy 337.614 -284.35131)
			(xy 337.654503 -284.379266) (xy 337.689996 -284.413358) (xy 337.719561 -284.452702) (xy 337.742432 -284.496279)
			(xy 337.758016 -284.54296) (xy 337.765911 -284.591537) (xy 337.766406 -284.616144) (xy 338.095348 -284.616144)
			(xy 338.099308 -284.56709) (xy 338.111085 -284.519306) (xy 338.130376 -284.47403) (xy 338.156679 -284.432434)
			(xy 338.189314 -284.395597) (xy 338.227435 -284.364472) (xy 338.270056 -284.339865) (xy 338.316072 -284.322413)
			(xy 338.364291 -284.312569) (xy 338.413466 -284.310588) (xy 338.462321 -284.31652) (xy 338.509592 -284.330212)
			(xy 338.554054 -284.35131) (xy 338.594557 -284.379266) (xy 338.63005 -284.413358) (xy 338.659615 -284.452702)
			(xy 338.682486 -284.496279) (xy 338.69807 -284.54296) (xy 338.705965 -284.591537) (xy 338.70646 -284.616144)
			(xy 338.705965 -284.640751) (xy 338.69807 -284.689328) (xy 338.682486 -284.736009) (xy 338.659615 -284.779586)
			(xy 338.63005 -284.81893) (xy 338.594557 -284.853022) (xy 338.554054 -284.880978) (xy 338.509592 -284.902076)
			(xy 338.462321 -284.915768) (xy 338.413466 -284.9217) (xy 338.364291 -284.919719) (xy 338.316072 -284.909875)
			(xy 338.270056 -284.892423) (xy 338.227435 -284.867816) (xy 338.189314 -284.836691) (xy 338.156679 -284.799854)
			(xy 338.130376 -284.758258) (xy 338.111085 -284.712982) (xy 338.099308 -284.665198) (xy 338.095348 -284.616144)
			(xy 337.766406 -284.616144) (xy 337.765911 -284.640751) (xy 337.758016 -284.689328) (xy 337.742432 -284.736009)
			(xy 337.719561 -284.779586) (xy 337.689996 -284.81893) (xy 337.654503 -284.853022) (xy 337.614 -284.880978)
			(xy 337.569538 -284.902076) (xy 337.522267 -284.915768) (xy 337.473412 -284.9217) (xy 337.424237 -284.919719)
			(xy 337.376018 -284.909875) (xy 337.330002 -284.892423) (xy 337.287381 -284.867816) (xy 337.24926 -284.836691)
			(xy 337.216625 -284.799854) (xy 337.190322 -284.758258) (xy 337.171031 -284.712982) (xy 337.159254 -284.665198)
			(xy 337.155294 -284.616144) (xy 336.826352 -284.616144) (xy 336.825857 -284.640751) (xy 336.817962 -284.689328)
			(xy 336.802378 -284.736009) (xy 336.779507 -284.779586) (xy 336.749942 -284.81893) (xy 336.714449 -284.853022)
			(xy 336.673946 -284.880978) (xy 336.629484 -284.902076) (xy 336.582213 -284.915768) (xy 336.533358 -284.9217)
			(xy 336.484183 -284.919719) (xy 336.435964 -284.909875) (xy 336.389948 -284.892423) (xy 336.347327 -284.867816)
			(xy 336.309206 -284.836691) (xy 336.276571 -284.799854) (xy 336.250268 -284.758258) (xy 336.230977 -284.712982)
			(xy 336.2192 -284.665198) (xy 336.21524 -284.616144) (xy 335.886298 -284.616144) (xy 335.885803 -284.640751)
			(xy 335.877908 -284.689328) (xy 335.862324 -284.736009) (xy 335.839453 -284.779586) (xy 335.809888 -284.81893)
			(xy 335.774395 -284.853022) (xy 335.733892 -284.880978) (xy 335.68943 -284.902076) (xy 335.642159 -284.915768)
			(xy 335.593304 -284.9217) (xy 335.544129 -284.919719) (xy 335.49591 -284.909875) (xy 335.449894 -284.892423)
			(xy 335.407273 -284.867816) (xy 335.369152 -284.836691) (xy 335.336517 -284.799854) (xy 335.310214 -284.758258)
			(xy 335.290923 -284.712982) (xy 335.279146 -284.665198) (xy 335.275186 -284.616144) (xy 334.946498 -284.616144)
			(xy 334.946003 -284.640751) (xy 334.938108 -284.689328) (xy 334.922524 -284.736009) (xy 334.899653 -284.779586)
			(xy 334.870088 -284.81893) (xy 334.834595 -284.853022) (xy 334.794092 -284.880978) (xy 334.74963 -284.902076)
			(xy 334.702359 -284.915768) (xy 334.653504 -284.9217) (xy 334.604329 -284.919719) (xy 334.55611 -284.909875)
			(xy 334.510094 -284.892423) (xy 334.467473 -284.867816) (xy 334.429352 -284.836691) (xy 334.396717 -284.799854)
			(xy 334.370414 -284.758258) (xy 334.351123 -284.712982) (xy 334.339346 -284.665198) (xy 334.335386 -284.616144)
			(xy 334.006444 -284.616144) (xy 334.005949 -284.640751) (xy 333.998054 -284.689328) (xy 333.98247 -284.736009)
			(xy 333.959599 -284.779586) (xy 333.930034 -284.81893) (xy 333.894541 -284.853022) (xy 333.854038 -284.880978)
			(xy 333.809576 -284.902076) (xy 333.762305 -284.915768) (xy 333.71345 -284.9217) (xy 333.664275 -284.919719)
			(xy 333.616056 -284.909875) (xy 333.57004 -284.892423) (xy 333.527419 -284.867816) (xy 333.489298 -284.836691)
			(xy 333.456663 -284.799854) (xy 333.43036 -284.758258) (xy 333.411069 -284.712982) (xy 333.399292 -284.665198)
			(xy 333.395332 -284.616144) (xy 333.06639 -284.616144) (xy 333.065895 -284.640751) (xy 333.058 -284.689328)
			(xy 333.042416 -284.736009) (xy 333.019545 -284.779586) (xy 332.98998 -284.81893) (xy 332.954487 -284.853022)
			(xy 332.913984 -284.880978) (xy 332.869522 -284.902076) (xy 332.822251 -284.915768) (xy 332.773396 -284.9217)
			(xy 332.724221 -284.919719) (xy 332.676002 -284.909875) (xy 332.629986 -284.892423) (xy 332.587365 -284.867816)
			(xy 332.549244 -284.836691) (xy 332.516609 -284.799854) (xy 332.490306 -284.758258) (xy 332.471015 -284.712982)
			(xy 332.459238 -284.665198) (xy 332.455278 -284.616144) (xy 332.126783 -284.616144) (xy 332.122617 -284.666428)
			(xy 332.110221 -284.715383) (xy 332.089936 -284.761631) (xy 332.062316 -284.803909) (xy 332.028115 -284.841065)
			(xy 331.988264 -284.872085) (xy 331.943852 -284.896123) (xy 331.896089 -284.912524) (xy 331.846278 -284.92084)
			(xy 331.821028 -284.921452) (xy 331.808265 -284.921312) (xy 331.782832 -284.919147) (xy 331.770228 -284.917134)
			(xy 331.74354 -284.912054) (xy 331.692407 -284.893719) (xy 331.645329 -284.866619) (xy 331.624178 -284.84957)
			(xy 331.61859 -284.844998) (xy 331.605636 -284.839156) (xy 331.59827 -284.83814) (xy 331.591061 -284.837459)
			(xy 331.576754 -284.839656) (xy 331.570076 -284.842458) (xy 331.487018 -284.880812) (xy 331.479146 -284.885251)
			(xy 331.466915 -284.898539) (xy 331.460029 -284.915236) (xy 331.459332 -284.924246) (xy 331.459332 -285.107888)
			(xy 331.459574 -285.114838) (xy 331.463315 -285.128227) (xy 331.466698 -285.134304) (xy 331.47 -285.139384)
			(xy 331.480414 -285.149036) (xy 331.487526 -285.152592) (xy 331.508979 -285.163819) (xy 331.548347 -285.192005)
			(xy 331.582782 -285.226042) (xy 331.611424 -285.26508) (xy 331.633557 -285.308143) (xy 331.648628 -285.354156)
			(xy 331.656261 -285.401969) (xy 331.656263 -285.42615) (xy 331.985378 -285.42615) (xy 331.989338 -285.377096)
			(xy 332.001115 -285.329312) (xy 332.020406 -285.284036) (xy 332.046709 -285.24244) (xy 332.079344 -285.205603)
			(xy 332.117465 -285.174478) (xy 332.160086 -285.149871) (xy 332.206102 -285.132419) (xy 332.254321 -285.122575)
			(xy 332.303496 -285.120594) (xy 332.352351 -285.126526) (xy 332.399622 -285.140218) (xy 332.444084 -285.161316)
			(xy 332.484587 -285.189272) (xy 332.52008 -285.223364) (xy 332.549645 -285.262708) (xy 332.572516 -285.306285)
			(xy 332.5881 -285.352966) (xy 332.595995 -285.401543) (xy 332.59649 -285.42615) (xy 332.925178 -285.42615)
			(xy 332.929138 -285.377096) (xy 332.940915 -285.329312) (xy 332.960206 -285.284036) (xy 332.986509 -285.24244)
			(xy 333.019144 -285.205603) (xy 333.057265 -285.174478) (xy 333.099886 -285.149871) (xy 333.145902 -285.132419)
			(xy 333.194121 -285.122575) (xy 333.243296 -285.120594) (xy 333.292151 -285.126526) (xy 333.339422 -285.140218)
			(xy 333.383884 -285.161316) (xy 333.424387 -285.189272) (xy 333.45988 -285.223364) (xy 333.489445 -285.262708)
			(xy 333.512316 -285.306285) (xy 333.5279 -285.352966) (xy 333.535795 -285.401543) (xy 333.53629 -285.42615)
			(xy 333.865232 -285.42615) (xy 333.869192 -285.377096) (xy 333.880969 -285.329312) (xy 333.90026 -285.284036)
			(xy 333.926563 -285.24244) (xy 333.959198 -285.205603) (xy 333.997319 -285.174478) (xy 334.03994 -285.149871)
			(xy 334.085956 -285.132419) (xy 334.134175 -285.122575) (xy 334.18335 -285.120594) (xy 334.232205 -285.126526)
			(xy 334.279476 -285.140218) (xy 334.323938 -285.161316) (xy 334.364441 -285.189272) (xy 334.399934 -285.223364)
			(xy 334.429499 -285.262708) (xy 334.45237 -285.306285) (xy 334.467954 -285.352966) (xy 334.475849 -285.401543)
			(xy 334.476344 -285.42615) (xy 335.74534 -285.42615) (xy 335.7493 -285.377096) (xy 335.761077 -285.329312)
			(xy 335.780368 -285.284036) (xy 335.806671 -285.24244) (xy 335.839306 -285.205603) (xy 335.877427 -285.174478)
			(xy 335.920048 -285.149871) (xy 335.966064 -285.132419) (xy 336.014283 -285.122575) (xy 336.063458 -285.120594)
			(xy 336.112313 -285.126526) (xy 336.159584 -285.140218) (xy 336.204046 -285.161316) (xy 336.244549 -285.189272)
			(xy 336.280042 -285.223364) (xy 336.309607 -285.262708) (xy 336.332478 -285.306285) (xy 336.348062 -285.352966)
			(xy 336.355957 -285.401543) (xy 336.356452 -285.42615) (xy 336.685394 -285.42615) (xy 336.689354 -285.377096)
			(xy 336.701131 -285.329312) (xy 336.720422 -285.284036) (xy 336.746725 -285.24244) (xy 336.77936 -285.205603)
			(xy 336.817481 -285.174478) (xy 336.860102 -285.149871) (xy 336.906118 -285.132419) (xy 336.954337 -285.122575)
			(xy 337.003512 -285.120594) (xy 337.052367 -285.126526) (xy 337.099638 -285.140218) (xy 337.1441 -285.161316)
			(xy 337.184603 -285.189272) (xy 337.220096 -285.223364) (xy 337.249661 -285.262708) (xy 337.272532 -285.306285)
			(xy 337.288116 -285.352966) (xy 337.296011 -285.401543) (xy 337.296506 -285.42615) (xy 337.625194 -285.42615)
			(xy 337.629154 -285.377096) (xy 337.640931 -285.329312) (xy 337.660222 -285.284036) (xy 337.686525 -285.24244)
			(xy 337.71916 -285.205603) (xy 337.757281 -285.174478) (xy 337.799902 -285.149871) (xy 337.845918 -285.132419)
			(xy 337.894137 -285.122575) (xy 337.943312 -285.120594) (xy 337.992167 -285.126526) (xy 338.039438 -285.140218)
			(xy 338.0839 -285.161316) (xy 338.124403 -285.189272) (xy 338.159896 -285.223364) (xy 338.189461 -285.262708)
			(xy 338.212332 -285.306285) (xy 338.227916 -285.352966) (xy 338.235811 -285.401543) (xy 338.236306 -285.42615)
			(xy 338.235811 -285.450757) (xy 338.227916 -285.499334) (xy 338.212332 -285.546015) (xy 338.189461 -285.589592)
			(xy 338.159896 -285.628936) (xy 338.124403 -285.663028) (xy 338.0839 -285.690984) (xy 338.039438 -285.712082)
			(xy 337.992167 -285.725774) (xy 337.943312 -285.731706) (xy 337.894137 -285.729725) (xy 337.845918 -285.719881)
			(xy 337.799902 -285.702429) (xy 337.757281 -285.677822) (xy 337.71916 -285.646697) (xy 337.686525 -285.60986)
			(xy 337.660222 -285.568264) (xy 337.640931 -285.522988) (xy 337.629154 -285.475204) (xy 337.625194 -285.42615)
			(xy 337.296506 -285.42615) (xy 337.296011 -285.450757) (xy 337.288116 -285.499334) (xy 337.272532 -285.546015)
			(xy 337.249661 -285.589592) (xy 337.220096 -285.628936) (xy 337.184603 -285.663028) (xy 337.1441 -285.690984)
			(xy 337.099638 -285.712082) (xy 337.052367 -285.725774) (xy 337.003512 -285.731706) (xy 336.954337 -285.729725)
			(xy 336.906118 -285.719881) (xy 336.860102 -285.702429) (xy 336.817481 -285.677822) (xy 336.77936 -285.646697)
			(xy 336.746725 -285.60986) (xy 336.720422 -285.568264) (xy 336.701131 -285.522988) (xy 336.689354 -285.475204)
			(xy 336.685394 -285.42615) (xy 336.356452 -285.42615) (xy 336.355957 -285.450757) (xy 336.348062 -285.499334)
			(xy 336.332478 -285.546015) (xy 336.309607 -285.589592) (xy 336.280042 -285.628936) (xy 336.244549 -285.663028)
			(xy 336.204046 -285.690984) (xy 336.159584 -285.712082) (xy 336.112313 -285.725774) (xy 336.063458 -285.731706)
			(xy 336.014283 -285.729725) (xy 335.966064 -285.719881) (xy 335.920048 -285.702429) (xy 335.877427 -285.677822)
			(xy 335.839306 -285.646697) (xy 335.806671 -285.60986) (xy 335.780368 -285.568264) (xy 335.761077 -285.522988)
			(xy 335.7493 -285.475204) (xy 335.74534 -285.42615) (xy 334.476344 -285.42615) (xy 334.475849 -285.450757)
			(xy 334.467954 -285.499334) (xy 334.45237 -285.546015) (xy 334.429499 -285.589592) (xy 334.399934 -285.628936)
			(xy 334.364441 -285.663028) (xy 334.323938 -285.690984) (xy 334.279476 -285.712082) (xy 334.232205 -285.725774)
			(xy 334.18335 -285.731706) (xy 334.134175 -285.729725) (xy 334.085956 -285.719881) (xy 334.03994 -285.702429)
			(xy 333.997319 -285.677822) (xy 333.959198 -285.646697) (xy 333.926563 -285.60986) (xy 333.90026 -285.568264)
			(xy 333.880969 -285.522988) (xy 333.869192 -285.475204) (xy 333.865232 -285.42615) (xy 333.53629 -285.42615)
			(xy 333.535795 -285.450757) (xy 333.5279 -285.499334) (xy 333.512316 -285.546015) (xy 333.489445 -285.589592)
			(xy 333.45988 -285.628936) (xy 333.424387 -285.663028) (xy 333.383884 -285.690984) (xy 333.339422 -285.712082)
			(xy 333.292151 -285.725774) (xy 333.243296 -285.731706) (xy 333.194121 -285.729725) (xy 333.145902 -285.719881)
			(xy 333.099886 -285.702429) (xy 333.057265 -285.677822) (xy 333.019144 -285.646697) (xy 332.986509 -285.60986)
			(xy 332.960206 -285.568264) (xy 332.940915 -285.522988) (xy 332.929138 -285.475204) (xy 332.925178 -285.42615)
			(xy 332.59649 -285.42615) (xy 332.595995 -285.450757) (xy 332.5881 -285.499334) (xy 332.572516 -285.546015)
			(xy 332.549645 -285.589592) (xy 332.52008 -285.628936) (xy 332.484587 -285.663028) (xy 332.444084 -285.690984)
			(xy 332.399622 -285.712082) (xy 332.352351 -285.725774) (xy 332.303496 -285.731706) (xy 332.254321 -285.729725)
			(xy 332.206102 -285.719881) (xy 332.160086 -285.702429) (xy 332.117465 -285.677822) (xy 332.079344 -285.646697)
			(xy 332.046709 -285.60986) (xy 332.020406 -285.568264) (xy 332.001115 -285.522988) (xy 331.989338 -285.475204)
			(xy 331.985378 -285.42615) (xy 331.656263 -285.42615) (xy 331.656265 -285.450387) (xy 331.648639 -285.4982)
			(xy 331.633575 -285.544215) (xy 331.611448 -285.587282) (xy 331.582812 -285.626324) (xy 331.548381 -285.660366)
			(xy 331.509017 -285.688557) (xy 331.487526 -285.699708) (xy 331.486764 -285.699962) (xy 331.480505 -285.703362)
			(xy 331.470049 -285.713026) (xy 331.46619 -285.719012) (xy 331.463142 -285.724092) (xy 331.459332 -285.7373)
			(xy 331.459332 -285.926276) (xy 331.459811 -285.935645) (xy 331.466663 -285.95309) (xy 331.479344 -285.966892)
			(xy 331.487526 -285.971488) (xy 331.518006 -285.985712) (xy 331.566266 -286.008064) (xy 331.56955 -286.009561)
			(xy 331.576432 -286.011733) (xy 331.579982 -286.012382) (xy 331.584357 -286.012933) (xy 331.593171 -286.012676)
			(xy 331.597508 -286.011874) (xy 331.605382 -286.009842) (xy 331.62367 -286.002984) (xy 331.63002 -285.997904)
			(xy 331.6505 -285.982192) (xy 331.695638 -285.957158) (xy 331.744339 -285.940064) (xy 331.795221 -285.931397)
			(xy 331.821028 -285.930848) (xy 331.846285 -285.931371) (xy 331.896111 -285.93969) (xy 331.943888 -285.956096)
			(xy 331.988313 -285.980141) (xy 332.028175 -286.01117) (xy 332.062386 -286.048337) (xy 332.090014 -286.090627)
			(xy 332.110304 -286.136888) (xy 332.122704 -286.185857) (xy 332.126872 -286.236156) (xy 332.455278 -286.236156)
			(xy 332.459238 -286.187102) (xy 332.471015 -286.139318) (xy 332.490306 -286.094042) (xy 332.516609 -286.052446)
			(xy 332.549244 -286.015609) (xy 332.587365 -285.984484) (xy 332.629986 -285.959877) (xy 332.676002 -285.942425)
			(xy 332.724221 -285.932581) (xy 332.773396 -285.9306) (xy 332.822251 -285.936532) (xy 332.869522 -285.950224)
			(xy 332.913984 -285.971322) (xy 332.954487 -285.999278) (xy 332.98998 -286.03337) (xy 333.019545 -286.072714)
			(xy 333.042416 -286.116291) (xy 333.058 -286.162972) (xy 333.065895 -286.211549) (xy 333.06639 -286.236156)
			(xy 333.395332 -286.236156) (xy 333.399292 -286.187102) (xy 333.411069 -286.139318) (xy 333.43036 -286.094042)
			(xy 333.456663 -286.052446) (xy 333.489298 -286.015609) (xy 333.527419 -285.984484) (xy 333.57004 -285.959877)
			(xy 333.616056 -285.942425) (xy 333.664275 -285.932581) (xy 333.71345 -285.9306) (xy 333.762305 -285.936532)
			(xy 333.809576 -285.950224) (xy 333.854038 -285.971322) (xy 333.894541 -285.999278) (xy 333.930034 -286.03337)
			(xy 333.959599 -286.072714) (xy 333.98247 -286.116291) (xy 333.998054 -286.162972) (xy 334.005949 -286.211549)
			(xy 334.006444 -286.236156) (xy 334.335386 -286.236156) (xy 334.339346 -286.187102) (xy 334.351123 -286.139318)
			(xy 334.370414 -286.094042) (xy 334.396717 -286.052446) (xy 334.429352 -286.015609) (xy 334.467473 -285.984484)
			(xy 334.510094 -285.959877) (xy 334.55611 -285.942425) (xy 334.604329 -285.932581) (xy 334.653504 -285.9306)
			(xy 334.702359 -285.936532) (xy 334.74963 -285.950224) (xy 334.794092 -285.971322) (xy 334.834595 -285.999278)
			(xy 334.870088 -286.03337) (xy 334.899653 -286.072714) (xy 334.922524 -286.116291) (xy 334.938108 -286.162972)
			(xy 334.946003 -286.211549) (xy 334.946498 -286.236156) (xy 335.275186 -286.236156) (xy 335.279146 -286.187102)
			(xy 335.290923 -286.139318) (xy 335.310214 -286.094042) (xy 335.336517 -286.052446) (xy 335.369152 -286.015609)
			(xy 335.407273 -285.984484) (xy 335.449894 -285.959877) (xy 335.49591 -285.942425) (xy 335.544129 -285.932581)
			(xy 335.593304 -285.9306) (xy 335.642159 -285.936532) (xy 335.68943 -285.950224) (xy 335.733892 -285.971322)
			(xy 335.774395 -285.999278) (xy 335.809888 -286.03337) (xy 335.839453 -286.072714) (xy 335.862324 -286.116291)
			(xy 335.877908 -286.162972) (xy 335.885803 -286.211549) (xy 335.886298 -286.236156) (xy 336.21524 -286.236156)
			(xy 336.2192 -286.187102) (xy 336.230977 -286.139318) (xy 336.250268 -286.094042) (xy 336.276571 -286.052446)
			(xy 336.309206 -286.015609) (xy 336.347327 -285.984484) (xy 336.389948 -285.959877) (xy 336.435964 -285.942425)
			(xy 336.484183 -285.932581) (xy 336.533358 -285.9306) (xy 336.582213 -285.936532) (xy 336.629484 -285.950224)
			(xy 336.673946 -285.971322) (xy 336.714449 -285.999278) (xy 336.749942 -286.03337) (xy 336.779507 -286.072714)
			(xy 336.802378 -286.116291) (xy 336.817962 -286.162972) (xy 336.825857 -286.211549) (xy 336.826352 -286.236156)
			(xy 337.155294 -286.236156) (xy 337.159254 -286.187102) (xy 337.171031 -286.139318) (xy 337.190322 -286.094042)
			(xy 337.216625 -286.052446) (xy 337.24926 -286.015609) (xy 337.287381 -285.984484) (xy 337.330002 -285.959877)
			(xy 337.376018 -285.942425) (xy 337.424237 -285.932581) (xy 337.473412 -285.9306) (xy 337.522267 -285.936532)
			(xy 337.569538 -285.950224) (xy 337.614 -285.971322) (xy 337.654503 -285.999278) (xy 337.689996 -286.03337)
			(xy 337.719561 -286.072714) (xy 337.742432 -286.116291) (xy 337.758016 -286.162972) (xy 337.765911 -286.211549)
			(xy 337.766406 -286.236156) (xy 338.095348 -286.236156) (xy 338.099308 -286.187102) (xy 338.111085 -286.139318)
			(xy 338.130376 -286.094042) (xy 338.156679 -286.052446) (xy 338.189314 -286.015609) (xy 338.227435 -285.984484)
			(xy 338.270056 -285.959877) (xy 338.316072 -285.942425) (xy 338.364291 -285.932581) (xy 338.413466 -285.9306)
			(xy 338.462321 -285.936532) (xy 338.509592 -285.950224) (xy 338.554054 -285.971322) (xy 338.594557 -285.999278)
			(xy 338.63005 -286.03337) (xy 338.659615 -286.072714) (xy 338.682486 -286.116291) (xy 338.69807 -286.162972)
			(xy 338.705965 -286.211549) (xy 338.70646 -286.236156) (xy 338.705965 -286.260763) (xy 338.69807 -286.30934)
			(xy 338.682486 -286.356021) (xy 338.659615 -286.399598) (xy 338.63005 -286.438942) (xy 338.594557 -286.473034)
			(xy 338.554054 -286.50099) (xy 338.509592 -286.522088) (xy 338.462321 -286.53578) (xy 338.413466 -286.541712)
			(xy 338.364291 -286.539731) (xy 338.316072 -286.529887) (xy 338.270056 -286.512435) (xy 338.227435 -286.487828)
			(xy 338.189314 -286.456703) (xy 338.156679 -286.419866) (xy 338.130376 -286.37827) (xy 338.111085 -286.332994)
			(xy 338.099308 -286.28521) (xy 338.095348 -286.236156) (xy 337.766406 -286.236156) (xy 337.765911 -286.260763)
			(xy 337.758016 -286.30934) (xy 337.742432 -286.356021) (xy 337.719561 -286.399598) (xy 337.689996 -286.438942)
			(xy 337.654503 -286.473034) (xy 337.614 -286.50099) (xy 337.569538 -286.522088) (xy 337.522267 -286.53578)
			(xy 337.473412 -286.541712) (xy 337.424237 -286.539731) (xy 337.376018 -286.529887) (xy 337.330002 -286.512435)
			(xy 337.287381 -286.487828) (xy 337.24926 -286.456703) (xy 337.216625 -286.419866) (xy 337.190322 -286.37827)
			(xy 337.171031 -286.332994) (xy 337.159254 -286.28521) (xy 337.155294 -286.236156) (xy 336.826352 -286.236156)
			(xy 336.825857 -286.260763) (xy 336.817962 -286.30934) (xy 336.802378 -286.356021) (xy 336.779507 -286.399598)
			(xy 336.749942 -286.438942) (xy 336.714449 -286.473034) (xy 336.673946 -286.50099) (xy 336.629484 -286.522088)
			(xy 336.582213 -286.53578) (xy 336.533358 -286.541712) (xy 336.484183 -286.539731) (xy 336.435964 -286.529887)
			(xy 336.389948 -286.512435) (xy 336.347327 -286.487828) (xy 336.309206 -286.456703) (xy 336.276571 -286.419866)
			(xy 336.250268 -286.37827) (xy 336.230977 -286.332994) (xy 336.2192 -286.28521) (xy 336.21524 -286.236156)
			(xy 335.886298 -286.236156) (xy 335.885803 -286.260763) (xy 335.877908 -286.30934) (xy 335.862324 -286.356021)
			(xy 335.839453 -286.399598) (xy 335.809888 -286.438942) (xy 335.774395 -286.473034) (xy 335.733892 -286.50099)
			(xy 335.68943 -286.522088) (xy 335.642159 -286.53578) (xy 335.593304 -286.541712) (xy 335.544129 -286.539731)
			(xy 335.49591 -286.529887) (xy 335.449894 -286.512435) (xy 335.407273 -286.487828) (xy 335.369152 -286.456703)
			(xy 335.336517 -286.419866) (xy 335.310214 -286.37827) (xy 335.290923 -286.332994) (xy 335.279146 -286.28521)
			(xy 335.275186 -286.236156) (xy 334.946498 -286.236156) (xy 334.946003 -286.260763) (xy 334.938108 -286.30934)
			(xy 334.922524 -286.356021) (xy 334.899653 -286.399598) (xy 334.870088 -286.438942) (xy 334.834595 -286.473034)
			(xy 334.794092 -286.50099) (xy 334.74963 -286.522088) (xy 334.702359 -286.53578) (xy 334.653504 -286.541712)
			(xy 334.604329 -286.539731) (xy 334.55611 -286.529887) (xy 334.510094 -286.512435) (xy 334.467473 -286.487828)
			(xy 334.429352 -286.456703) (xy 334.396717 -286.419866) (xy 334.370414 -286.37827) (xy 334.351123 -286.332994)
			(xy 334.339346 -286.28521) (xy 334.335386 -286.236156) (xy 334.006444 -286.236156) (xy 334.005949 -286.260763)
			(xy 333.998054 -286.30934) (xy 333.98247 -286.356021) (xy 333.959599 -286.399598) (xy 333.930034 -286.438942)
			(xy 333.894541 -286.473034) (xy 333.854038 -286.50099) (xy 333.809576 -286.522088) (xy 333.762305 -286.53578)
			(xy 333.71345 -286.541712) (xy 333.664275 -286.539731) (xy 333.616056 -286.529887) (xy 333.57004 -286.512435)
			(xy 333.527419 -286.487828) (xy 333.489298 -286.456703) (xy 333.456663 -286.419866) (xy 333.43036 -286.37827)
			(xy 333.411069 -286.332994) (xy 333.399292 -286.28521) (xy 333.395332 -286.236156) (xy 333.06639 -286.236156)
			(xy 333.065895 -286.260763) (xy 333.058 -286.30934) (xy 333.042416 -286.356021) (xy 333.019545 -286.399598)
			(xy 332.98998 -286.438942) (xy 332.954487 -286.473034) (xy 332.913984 -286.50099) (xy 332.869522 -286.522088)
			(xy 332.822251 -286.53578) (xy 332.773396 -286.541712) (xy 332.724221 -286.539731) (xy 332.676002 -286.529887)
			(xy 332.629986 -286.512435) (xy 332.587365 -286.487828) (xy 332.549244 -286.456703) (xy 332.516609 -286.419866)
			(xy 332.490306 -286.37827) (xy 332.471015 -286.332994) (xy 332.459238 -286.28521) (xy 332.455278 -286.236156)
			(xy 332.126872 -286.236156) (xy 332.126876 -286.2362) (xy 332.122704 -286.286543) (xy 332.110304 -286.335512)
			(xy 332.090014 -286.381773) (xy 332.062386 -286.424063) (xy 332.028175 -286.46123) (xy 331.988313 -286.492259)
			(xy 331.943888 -286.516304) (xy 331.896111 -286.53271) (xy 331.846285 -286.541029) (xy 331.821028 -286.541464)
			(xy 331.808265 -286.541324) (xy 331.782832 -286.539159) (xy 331.770228 -286.537146) (xy 331.74354 -286.532066)
			(xy 331.692407 -286.513732) (xy 331.645328 -286.486633) (xy 331.624178 -286.469582) (xy 331.61859 -286.46501)
			(xy 331.605636 -286.459168) (xy 331.59827 -286.458152) (xy 331.591061 -286.457471) (xy 331.576754 -286.459668)
			(xy 331.570076 -286.46247) (xy 331.487018 -286.500824) (xy 331.479147 -286.505264) (xy 331.466919 -286.518553)
			(xy 331.460037 -286.535249) (xy 331.459332 -286.544258) (xy 331.459332 -286.727646) (xy 331.459569 -286.734598)
			(xy 331.4633 -286.747993) (xy 331.466698 -286.754062) (xy 331.47 -286.759142) (xy 331.480414 -286.768794)
			(xy 331.487526 -286.77235) (xy 331.508974 -286.783577) (xy 331.548334 -286.811762) (xy 331.58276 -286.845796)
			(xy 331.611394 -286.88483) (xy 331.633519 -286.927887) (xy 331.648584 -286.973893) (xy 331.656211 -287.021699)
			(xy 331.656211 -287.045908) (xy 331.985378 -287.045908) (xy 331.989338 -286.996854) (xy 332.001115 -286.94907)
			(xy 332.020406 -286.903794) (xy 332.046709 -286.862198) (xy 332.079344 -286.825361) (xy 332.117465 -286.794236)
			(xy 332.160086 -286.769629) (xy 332.206102 -286.752177) (xy 332.254321 -286.742333) (xy 332.303496 -286.740352)
			(xy 332.352351 -286.746284) (xy 332.399622 -286.759976) (xy 332.444084 -286.781074) (xy 332.484587 -286.80903)
			(xy 332.52008 -286.843122) (xy 332.549645 -286.882466) (xy 332.572516 -286.926043) (xy 332.5881 -286.972724)
			(xy 332.595995 -287.021301) (xy 332.59649 -287.045908) (xy 332.596485 -287.046162) (xy 332.925178 -287.046162)
			(xy 332.929138 -286.997108) (xy 332.940915 -286.949324) (xy 332.960206 -286.904048) (xy 332.986509 -286.862452)
			(xy 333.019144 -286.825615) (xy 333.057265 -286.79449) (xy 333.099886 -286.769883) (xy 333.145902 -286.752431)
			(xy 333.194121 -286.742587) (xy 333.243296 -286.740606) (xy 333.292151 -286.746538) (xy 333.339422 -286.76023)
			(xy 333.383884 -286.781328) (xy 333.424387 -286.809284) (xy 333.45988 -286.843376) (xy 333.489445 -286.88272)
			(xy 333.512316 -286.926297) (xy 333.5279 -286.972978) (xy 333.535795 -287.021555) (xy 333.536285 -287.045908)
			(xy 333.865232 -287.045908) (xy 333.869192 -286.996854) (xy 333.880969 -286.94907) (xy 333.90026 -286.903794)
			(xy 333.926563 -286.862198) (xy 333.959198 -286.825361) (xy 333.997319 -286.794236) (xy 334.03994 -286.769629)
			(xy 334.085956 -286.752177) (xy 334.134175 -286.742333) (xy 334.18335 -286.740352) (xy 334.232205 -286.746284)
			(xy 334.279476 -286.759976) (xy 334.323938 -286.781074) (xy 334.364441 -286.80903) (xy 334.399934 -286.843122)
			(xy 334.429499 -286.882466) (xy 334.45237 -286.926043) (xy 334.467954 -286.972724) (xy 334.475849 -287.021301)
			(xy 334.476344 -287.045908) (xy 334.805286 -287.045908) (xy 334.809246 -286.996854) (xy 334.821023 -286.94907)
			(xy 334.840314 -286.903794) (xy 334.866617 -286.862198) (xy 334.899252 -286.825361) (xy 334.937373 -286.794236)
			(xy 334.979994 -286.769629) (xy 335.02601 -286.752177) (xy 335.074229 -286.742333) (xy 335.123404 -286.740352)
			(xy 335.172259 -286.746284) (xy 335.21953 -286.759976) (xy 335.263992 -286.781074) (xy 335.304495 -286.80903)
			(xy 335.339988 -286.843122) (xy 335.369553 -286.882466) (xy 335.392424 -286.926043) (xy 335.408008 -286.972724)
			(xy 335.415903 -287.021301) (xy 335.416398 -287.045908) (xy 335.74534 -287.045908) (xy 335.7493 -286.996854)
			(xy 335.761077 -286.94907) (xy 335.780368 -286.903794) (xy 335.806671 -286.862198) (xy 335.839306 -286.825361)
			(xy 335.877427 -286.794236) (xy 335.920048 -286.769629) (xy 335.966064 -286.752177) (xy 336.014283 -286.742333)
			(xy 336.063458 -286.740352) (xy 336.112313 -286.746284) (xy 336.159584 -286.759976) (xy 336.204046 -286.781074)
			(xy 336.244549 -286.80903) (xy 336.280042 -286.843122) (xy 336.309607 -286.882466) (xy 336.332478 -286.926043)
			(xy 336.348062 -286.972724) (xy 336.355957 -287.021301) (xy 336.356452 -287.045908) (xy 336.685394 -287.045908)
			(xy 336.689354 -286.996854) (xy 336.701131 -286.94907) (xy 336.720422 -286.903794) (xy 336.746725 -286.862198)
			(xy 336.77936 -286.825361) (xy 336.817481 -286.794236) (xy 336.860102 -286.769629) (xy 336.906118 -286.752177)
			(xy 336.954337 -286.742333) (xy 337.003512 -286.740352) (xy 337.052367 -286.746284) (xy 337.099638 -286.759976)
			(xy 337.1441 -286.781074) (xy 337.184603 -286.80903) (xy 337.220096 -286.843122) (xy 337.249661 -286.882466)
			(xy 337.272532 -286.926043) (xy 337.288116 -286.972724) (xy 337.296011 -287.021301) (xy 337.296506 -287.045908)
			(xy 337.625702 -287.045908) (xy 337.629662 -286.996854) (xy 337.641439 -286.94907) (xy 337.66073 -286.903794)
			(xy 337.687033 -286.862198) (xy 337.719668 -286.825361) (xy 337.757789 -286.794236) (xy 337.80041 -286.769629)
			(xy 337.846426 -286.752177) (xy 337.894645 -286.742333) (xy 337.94382 -286.740352) (xy 337.992675 -286.746284)
			(xy 338.039946 -286.759976) (xy 338.084408 -286.781074) (xy 338.124911 -286.80903) (xy 338.160404 -286.843122)
			(xy 338.189969 -286.882466) (xy 338.21284 -286.926043) (xy 338.228424 -286.972724) (xy 338.236319 -287.021301)
			(xy 338.236814 -287.045908) (xy 338.236319 -287.070515) (xy 338.228424 -287.119092) (xy 338.21284 -287.165773)
			(xy 338.189969 -287.20935) (xy 338.160404 -287.248694) (xy 338.124911 -287.282786) (xy 338.084408 -287.310742)
			(xy 338.039946 -287.33184) (xy 337.992675 -287.345532) (xy 337.94382 -287.351464) (xy 337.894645 -287.349483)
			(xy 337.846426 -287.339639) (xy 337.80041 -287.322187) (xy 337.757789 -287.29758) (xy 337.719668 -287.266455)
			(xy 337.687033 -287.229618) (xy 337.66073 -287.188022) (xy 337.641439 -287.142746) (xy 337.629662 -287.094962)
			(xy 337.625702 -287.045908) (xy 337.296506 -287.045908) (xy 337.296011 -287.070515) (xy 337.288116 -287.119092)
			(xy 337.272532 -287.165773) (xy 337.249661 -287.20935) (xy 337.220096 -287.248694) (xy 337.184603 -287.282786)
			(xy 337.1441 -287.310742) (xy 337.099638 -287.33184) (xy 337.052367 -287.345532) (xy 337.003512 -287.351464)
			(xy 336.954337 -287.349483) (xy 336.906118 -287.339639) (xy 336.860102 -287.322187) (xy 336.817481 -287.29758)
			(xy 336.77936 -287.266455) (xy 336.746725 -287.229618) (xy 336.720422 -287.188022) (xy 336.701131 -287.142746)
			(xy 336.689354 -287.094962) (xy 336.685394 -287.045908) (xy 336.356452 -287.045908) (xy 336.355957 -287.070515)
			(xy 336.348062 -287.119092) (xy 336.332478 -287.165773) (xy 336.309607 -287.20935) (xy 336.280042 -287.248694)
			(xy 336.244549 -287.282786) (xy 336.204046 -287.310742) (xy 336.159584 -287.33184) (xy 336.112313 -287.345532)
			(xy 336.063458 -287.351464) (xy 336.014283 -287.349483) (xy 335.966064 -287.339639) (xy 335.920048 -287.322187)
			(xy 335.877427 -287.29758) (xy 335.839306 -287.266455) (xy 335.806671 -287.229618) (xy 335.780368 -287.188022)
			(xy 335.761077 -287.142746) (xy 335.7493 -287.094962) (xy 335.74534 -287.045908) (xy 335.416398 -287.045908)
			(xy 335.415903 -287.070515) (xy 335.408008 -287.119092) (xy 335.392424 -287.165773) (xy 335.369553 -287.20935)
			(xy 335.339988 -287.248694) (xy 335.304495 -287.282786) (xy 335.263992 -287.310742) (xy 335.21953 -287.33184)
			(xy 335.172259 -287.345532) (xy 335.123404 -287.351464) (xy 335.074229 -287.349483) (xy 335.02601 -287.339639)
			(xy 334.979994 -287.322187) (xy 334.937373 -287.29758) (xy 334.899252 -287.266455) (xy 334.866617 -287.229618)
			(xy 334.840314 -287.188022) (xy 334.821023 -287.142746) (xy 334.809246 -287.094962) (xy 334.805286 -287.045908)
			(xy 334.476344 -287.045908) (xy 334.475849 -287.070515) (xy 334.467954 -287.119092) (xy 334.45237 -287.165773)
			(xy 334.429499 -287.20935) (xy 334.399934 -287.248694) (xy 334.364441 -287.282786) (xy 334.323938 -287.310742)
			(xy 334.279476 -287.33184) (xy 334.232205 -287.345532) (xy 334.18335 -287.351464) (xy 334.134175 -287.349483)
			(xy 334.085956 -287.339639) (xy 334.03994 -287.322187) (xy 333.997319 -287.29758) (xy 333.959198 -287.266455)
			(xy 333.926563 -287.229618) (xy 333.90026 -287.188022) (xy 333.880969 -287.142746) (xy 333.869192 -287.094962)
			(xy 333.865232 -287.045908) (xy 333.536285 -287.045908) (xy 333.53629 -287.046162) (xy 333.535795 -287.070769)
			(xy 333.5279 -287.119346) (xy 333.512316 -287.166027) (xy 333.489445 -287.209604) (xy 333.45988 -287.248948)
			(xy 333.424387 -287.28304) (xy 333.383884 -287.310996) (xy 333.339422 -287.332094) (xy 333.292151 -287.345786)
			(xy 333.243296 -287.351718) (xy 333.194121 -287.349737) (xy 333.145902 -287.339893) (xy 333.099886 -287.322441)
			(xy 333.057265 -287.297834) (xy 333.019144 -287.266709) (xy 332.986509 -287.229872) (xy 332.960206 -287.188276)
			(xy 332.940915 -287.143) (xy 332.929138 -287.095216) (xy 332.925178 -287.046162) (xy 332.596485 -287.046162)
			(xy 332.595995 -287.070515) (xy 332.5881 -287.119092) (xy 332.572516 -287.165773) (xy 332.549645 -287.20935)
			(xy 332.52008 -287.248694) (xy 332.484587 -287.282786) (xy 332.444084 -287.310742) (xy 332.399622 -287.33184)
			(xy 332.352351 -287.345532) (xy 332.303496 -287.351464) (xy 332.254321 -287.349483) (xy 332.206102 -287.339639)
			(xy 332.160086 -287.322187) (xy 332.117465 -287.29758) (xy 332.079344 -287.266455) (xy 332.046709 -287.229618)
			(xy 332.020406 -287.188022) (xy 332.001115 -287.142746) (xy 331.989338 -287.094962) (xy 331.985378 -287.045908)
			(xy 331.656211 -287.045908) (xy 331.656211 -287.070108) (xy 331.648582 -287.117913) (xy 331.633517 -287.163919)
			(xy 331.61139 -287.206977) (xy 331.582755 -287.246009) (xy 331.548328 -287.280043) (xy 331.508968 -287.308226)
			(xy 331.487526 -287.319466) (xy 331.486764 -287.31972) (xy 331.480508 -287.323123) (xy 331.470061 -287.332793)
			(xy 331.46619 -287.33877) (xy 331.463142 -287.34385) (xy 331.459332 -287.357058) (xy 331.459332 -287.546288)
			(xy 331.459796 -287.555666) (xy 331.466629 -287.573136) (xy 331.479306 -287.586964) (xy 331.487526 -287.5915)
			(xy 331.518006 -287.605724) (xy 331.566266 -287.628076) (xy 331.56955 -287.629572) (xy 331.576432 -287.631744)
			(xy 331.579982 -287.632394) (xy 331.584357 -287.632945) (xy 331.593171 -287.632688) (xy 331.597508 -287.631886)
			(xy 331.605382 -287.629854) (xy 331.62367 -287.622996) (xy 331.63002 -287.617916) (xy 331.6505 -287.602204)
			(xy 331.695637 -287.577169) (xy 331.744339 -287.560074) (xy 331.795221 -287.551406) (xy 331.821028 -287.55086)
			(xy 331.846284 -287.551384) (xy 331.896108 -287.559702) (xy 331.943883 -287.576107) (xy 331.988306 -287.600151)
			(xy 332.028166 -287.631179) (xy 332.062376 -287.668344) (xy 332.090003 -287.710633) (xy 332.110292 -287.756892)
			(xy 332.122692 -287.80586) (xy 332.12686 -287.856168) (xy 332.455278 -287.856168) (xy 332.459238 -287.807114)
			(xy 332.471015 -287.75933) (xy 332.490306 -287.714054) (xy 332.516609 -287.672458) (xy 332.549244 -287.635621)
			(xy 332.587365 -287.604496) (xy 332.629986 -287.579889) (xy 332.676002 -287.562437) (xy 332.724221 -287.552593)
			(xy 332.773396 -287.550612) (xy 332.822251 -287.556544) (xy 332.869522 -287.570236) (xy 332.913984 -287.591334)
			(xy 332.954487 -287.61929) (xy 332.98998 -287.653382) (xy 333.019545 -287.692726) (xy 333.042416 -287.736303)
			(xy 333.058 -287.782984) (xy 333.065895 -287.831561) (xy 333.06639 -287.856168) (xy 333.395332 -287.856168)
			(xy 333.399292 -287.807114) (xy 333.411069 -287.75933) (xy 333.43036 -287.714054) (xy 333.456663 -287.672458)
			(xy 333.489298 -287.635621) (xy 333.527419 -287.604496) (xy 333.57004 -287.579889) (xy 333.616056 -287.562437)
			(xy 333.664275 -287.552593) (xy 333.71345 -287.550612) (xy 333.762305 -287.556544) (xy 333.809576 -287.570236)
			(xy 333.854038 -287.591334) (xy 333.894541 -287.61929) (xy 333.930034 -287.653382) (xy 333.959599 -287.692726)
			(xy 333.98247 -287.736303) (xy 333.998054 -287.782984) (xy 334.005949 -287.831561) (xy 334.006444 -287.856168)
			(xy 335.275186 -287.856168) (xy 335.279146 -287.807114) (xy 335.290923 -287.75933) (xy 335.310214 -287.714054)
			(xy 335.336517 -287.672458) (xy 335.369152 -287.635621) (xy 335.407273 -287.604496) (xy 335.449894 -287.579889)
			(xy 335.49591 -287.562437) (xy 335.544129 -287.552593) (xy 335.593304 -287.550612) (xy 335.642159 -287.556544)
			(xy 335.68943 -287.570236) (xy 335.733892 -287.591334) (xy 335.774395 -287.61929) (xy 335.809888 -287.653382)
			(xy 335.839453 -287.692726) (xy 335.862324 -287.736303) (xy 335.877908 -287.782984) (xy 335.885803 -287.831561)
			(xy 335.886298 -287.856168) (xy 336.21524 -287.856168) (xy 336.2192 -287.807114) (xy 336.230977 -287.75933)
			(xy 336.250268 -287.714054) (xy 336.276571 -287.672458) (xy 336.309206 -287.635621) (xy 336.347327 -287.604496)
			(xy 336.389948 -287.579889) (xy 336.435964 -287.562437) (xy 336.484183 -287.552593) (xy 336.533358 -287.550612)
			(xy 336.582213 -287.556544) (xy 336.629484 -287.570236) (xy 336.673946 -287.591334) (xy 336.714449 -287.61929)
			(xy 336.749942 -287.653382) (xy 336.779507 -287.692726) (xy 336.802378 -287.736303) (xy 336.817962 -287.782984)
			(xy 336.825857 -287.831561) (xy 336.826352 -287.856168) (xy 337.155294 -287.856168) (xy 337.159254 -287.807114)
			(xy 337.171031 -287.75933) (xy 337.190322 -287.714054) (xy 337.216625 -287.672458) (xy 337.24926 -287.635621)
			(xy 337.287381 -287.604496) (xy 337.330002 -287.579889) (xy 337.376018 -287.562437) (xy 337.424237 -287.552593)
			(xy 337.473412 -287.550612) (xy 337.522267 -287.556544) (xy 337.569538 -287.570236) (xy 337.614 -287.591334)
			(xy 337.654503 -287.61929) (xy 337.689996 -287.653382) (xy 337.719561 -287.692726) (xy 337.742432 -287.736303)
			(xy 337.758016 -287.782984) (xy 337.765911 -287.831561) (xy 337.766406 -287.856168) (xy 338.095348 -287.856168)
			(xy 338.099308 -287.807114) (xy 338.111085 -287.75933) (xy 338.130376 -287.714054) (xy 338.156679 -287.672458)
			(xy 338.189314 -287.635621) (xy 338.227435 -287.604496) (xy 338.270056 -287.579889) (xy 338.316072 -287.562437)
			(xy 338.364291 -287.552593) (xy 338.413466 -287.550612) (xy 338.462321 -287.556544) (xy 338.509592 -287.570236)
			(xy 338.554054 -287.591334) (xy 338.594557 -287.61929) (xy 338.63005 -287.653382) (xy 338.659615 -287.692726)
			(xy 338.682486 -287.736303) (xy 338.69807 -287.782984) (xy 338.705965 -287.831561) (xy 338.70646 -287.856168)
			(xy 338.705965 -287.880775) (xy 338.69807 -287.929352) (xy 338.682486 -287.976033) (xy 338.659615 -288.01961)
			(xy 338.63005 -288.058954) (xy 338.594557 -288.093046) (xy 338.554054 -288.121002) (xy 338.509592 -288.1421)
			(xy 338.462321 -288.155792) (xy 338.413466 -288.161724) (xy 338.364291 -288.159743) (xy 338.316072 -288.149899)
			(xy 338.270056 -288.132447) (xy 338.227435 -288.10784) (xy 338.189314 -288.076715) (xy 338.156679 -288.039878)
			(xy 338.130376 -287.998282) (xy 338.111085 -287.953006) (xy 338.099308 -287.905222) (xy 338.095348 -287.856168)
			(xy 337.766406 -287.856168) (xy 337.765911 -287.880775) (xy 337.758016 -287.929352) (xy 337.742432 -287.976033)
			(xy 337.719561 -288.01961) (xy 337.689996 -288.058954) (xy 337.654503 -288.093046) (xy 337.614 -288.121002)
			(xy 337.569538 -288.1421) (xy 337.522267 -288.155792) (xy 337.473412 -288.161724) (xy 337.424237 -288.159743)
			(xy 337.376018 -288.149899) (xy 337.330002 -288.132447) (xy 337.287381 -288.10784) (xy 337.24926 -288.076715)
			(xy 337.216625 -288.039878) (xy 337.190322 -287.998282) (xy 337.171031 -287.953006) (xy 337.159254 -287.905222)
			(xy 337.155294 -287.856168) (xy 336.826352 -287.856168) (xy 336.825857 -287.880775) (xy 336.817962 -287.929352)
			(xy 336.802378 -287.976033) (xy 336.779507 -288.01961) (xy 336.749942 -288.058954) (xy 336.714449 -288.093046)
			(xy 336.673946 -288.121002) (xy 336.629484 -288.1421) (xy 336.582213 -288.155792) (xy 336.533358 -288.161724)
			(xy 336.484183 -288.159743) (xy 336.435964 -288.149899) (xy 336.389948 -288.132447) (xy 336.347327 -288.10784)
			(xy 336.309206 -288.076715) (xy 336.276571 -288.039878) (xy 336.250268 -287.998282) (xy 336.230977 -287.953006)
			(xy 336.2192 -287.905222) (xy 336.21524 -287.856168) (xy 335.886298 -287.856168) (xy 335.885803 -287.880775)
			(xy 335.877908 -287.929352) (xy 335.862324 -287.976033) (xy 335.839453 -288.01961) (xy 335.809888 -288.058954)
			(xy 335.774395 -288.093046) (xy 335.733892 -288.121002) (xy 335.68943 -288.1421) (xy 335.642159 -288.155792)
			(xy 335.593304 -288.161724) (xy 335.544129 -288.159743) (xy 335.49591 -288.149899) (xy 335.449894 -288.132447)
			(xy 335.407273 -288.10784) (xy 335.369152 -288.076715) (xy 335.336517 -288.039878) (xy 335.310214 -287.998282)
			(xy 335.290923 -287.953006) (xy 335.279146 -287.905222) (xy 335.275186 -287.856168) (xy 334.006444 -287.856168)
			(xy 334.005949 -287.880775) (xy 333.998054 -287.929352) (xy 333.98247 -287.976033) (xy 333.959599 -288.01961)
			(xy 333.930034 -288.058954) (xy 333.894541 -288.093046) (xy 333.854038 -288.121002) (xy 333.809576 -288.1421)
			(xy 333.762305 -288.155792) (xy 333.71345 -288.161724) (xy 333.664275 -288.159743) (xy 333.616056 -288.149899)
			(xy 333.57004 -288.132447) (xy 333.527419 -288.10784) (xy 333.489298 -288.076715) (xy 333.456663 -288.039878)
			(xy 333.43036 -287.998282) (xy 333.411069 -287.953006) (xy 333.399292 -287.905222) (xy 333.395332 -287.856168)
			(xy 333.06639 -287.856168) (xy 333.065895 -287.880775) (xy 333.058 -287.929352) (xy 333.042416 -287.976033)
			(xy 333.019545 -288.01961) (xy 332.98998 -288.058954) (xy 332.954487 -288.093046) (xy 332.913984 -288.121002)
			(xy 332.869522 -288.1421) (xy 332.822251 -288.155792) (xy 332.773396 -288.161724) (xy 332.724221 -288.159743)
			(xy 332.676002 -288.149899) (xy 332.629986 -288.132447) (xy 332.587365 -288.10784) (xy 332.549244 -288.076715)
			(xy 332.516609 -288.039878) (xy 332.490306 -287.998282) (xy 332.471015 -287.953006) (xy 332.459238 -287.905222)
			(xy 332.455278 -287.856168) (xy 332.12686 -287.856168) (xy 332.126863 -287.8562) (xy 332.122692 -287.90654)
			(xy 332.110292 -287.955508) (xy 332.090003 -288.001767) (xy 332.062376 -288.044056) (xy 332.028166 -288.081221)
			(xy 331.988306 -288.112249) (xy 331.943883 -288.136293) (xy 331.896108 -288.152698) (xy 331.846284 -288.161016)
			(xy 331.821028 -288.161476) (xy 331.808265 -288.161336) (xy 331.782832 -288.159171) (xy 331.770228 -288.157158)
			(xy 331.74354 -288.152078) (xy 331.692406 -288.133744) (xy 331.645326 -288.106647) (xy 331.624178 -288.089594)
			(xy 331.61859 -288.085022) (xy 331.605636 -288.07918) (xy 331.59827 -288.078164) (xy 331.591061 -288.077483)
			(xy 331.576754 -288.079681) (xy 331.570076 -288.082482) (xy 331.487018 -288.120836) (xy 331.479149 -288.125276)
			(xy 331.466924 -288.138566) (xy 331.460045 -288.155262) (xy 331.459332 -288.16427) (xy 331.459332 -288.347658)
			(xy 331.45957 -288.35461) (xy 331.463304 -288.368003) (xy 331.466698 -288.374074) (xy 331.47 -288.379154)
			(xy 331.480414 -288.388806) (xy 331.487526 -288.392362) (xy 331.508974 -288.403589) (xy 331.548331 -288.431773)
			(xy 331.582756 -288.465807) (xy 331.611388 -288.50484) (xy 331.633512 -288.547896) (xy 331.648575 -288.593901)
			(xy 331.656201 -288.641705) (xy 331.6562 -288.66592) (xy 331.985378 -288.66592) (xy 331.989338 -288.616866)
			(xy 332.001115 -288.569082) (xy 332.020406 -288.523806) (xy 332.046709 -288.48221) (xy 332.079344 -288.445373)
			(xy 332.117465 -288.414248) (xy 332.160086 -288.389641) (xy 332.206102 -288.372189) (xy 332.254321 -288.362345)
			(xy 332.303496 -288.360364) (xy 332.352351 -288.366296) (xy 332.399622 -288.379988) (xy 332.444084 -288.401086)
			(xy 332.484587 -288.429042) (xy 332.52008 -288.463134) (xy 332.549645 -288.502478) (xy 332.572516 -288.546055)
			(xy 332.5881 -288.592736) (xy 332.595995 -288.641313) (xy 332.59649 -288.66592) (xy 332.925178 -288.66592)
			(xy 332.929138 -288.616866) (xy 332.940915 -288.569082) (xy 332.960206 -288.523806) (xy 332.986509 -288.48221)
			(xy 333.019144 -288.445373) (xy 333.057265 -288.414248) (xy 333.099886 -288.389641) (xy 333.145902 -288.372189)
			(xy 333.194121 -288.362345) (xy 333.243296 -288.360364) (xy 333.292151 -288.366296) (xy 333.339422 -288.379988)
			(xy 333.383884 -288.401086) (xy 333.424387 -288.429042) (xy 333.45988 -288.463134) (xy 333.489445 -288.502478)
			(xy 333.512316 -288.546055) (xy 333.5279 -288.592736) (xy 333.535795 -288.641313) (xy 333.53629 -288.66592)
			(xy 333.865232 -288.66592) (xy 333.869192 -288.616866) (xy 333.880969 -288.569082) (xy 333.90026 -288.523806)
			(xy 333.926563 -288.48221) (xy 333.959198 -288.445373) (xy 333.997319 -288.414248) (xy 334.03994 -288.389641)
			(xy 334.085956 -288.372189) (xy 334.134175 -288.362345) (xy 334.18335 -288.360364) (xy 334.232205 -288.366296)
			(xy 334.279476 -288.379988) (xy 334.323938 -288.401086) (xy 334.364441 -288.429042) (xy 334.399934 -288.463134)
			(xy 334.429499 -288.502478) (xy 334.45237 -288.546055) (xy 334.467954 -288.592736) (xy 334.475849 -288.641313)
			(xy 334.476344 -288.66592) (xy 334.805286 -288.66592) (xy 334.809246 -288.616866) (xy 334.821023 -288.569082)
			(xy 334.840314 -288.523806) (xy 334.866617 -288.48221) (xy 334.899252 -288.445373) (xy 334.937373 -288.414248)
			(xy 334.979994 -288.389641) (xy 335.02601 -288.372189) (xy 335.074229 -288.362345) (xy 335.123404 -288.360364)
			(xy 335.172259 -288.366296) (xy 335.21953 -288.379988) (xy 335.263992 -288.401086) (xy 335.304495 -288.429042)
			(xy 335.339988 -288.463134) (xy 335.369553 -288.502478) (xy 335.392424 -288.546055) (xy 335.408008 -288.592736)
			(xy 335.415903 -288.641313) (xy 335.416398 -288.66592) (xy 335.74534 -288.66592) (xy 335.7493 -288.616866)
			(xy 335.761077 -288.569082) (xy 335.780368 -288.523806) (xy 335.806671 -288.48221) (xy 335.839306 -288.445373)
			(xy 335.877427 -288.414248) (xy 335.920048 -288.389641) (xy 335.966064 -288.372189) (xy 336.014283 -288.362345)
			(xy 336.063458 -288.360364) (xy 336.112313 -288.366296) (xy 336.159584 -288.379988) (xy 336.204046 -288.401086)
			(xy 336.244549 -288.429042) (xy 336.280042 -288.463134) (xy 336.309607 -288.502478) (xy 336.332478 -288.546055)
			(xy 336.348062 -288.592736) (xy 336.355957 -288.641313) (xy 336.356452 -288.66592) (xy 336.685394 -288.66592)
			(xy 336.689354 -288.616866) (xy 336.701131 -288.569082) (xy 336.720422 -288.523806) (xy 336.746725 -288.48221)
			(xy 336.77936 -288.445373) (xy 336.817481 -288.414248) (xy 336.860102 -288.389641) (xy 336.906118 -288.372189)
			(xy 336.954337 -288.362345) (xy 337.003512 -288.360364) (xy 337.052367 -288.366296) (xy 337.099638 -288.379988)
			(xy 337.1441 -288.401086) (xy 337.184603 -288.429042) (xy 337.220096 -288.463134) (xy 337.249661 -288.502478)
			(xy 337.272532 -288.546055) (xy 337.288116 -288.592736) (xy 337.296011 -288.641313) (xy 337.296506 -288.66592)
			(xy 337.625194 -288.66592) (xy 337.629154 -288.616866) (xy 337.640931 -288.569082) (xy 337.660222 -288.523806)
			(xy 337.686525 -288.48221) (xy 337.71916 -288.445373) (xy 337.757281 -288.414248) (xy 337.799902 -288.389641)
			(xy 337.845918 -288.372189) (xy 337.894137 -288.362345) (xy 337.943312 -288.360364) (xy 337.992167 -288.366296)
			(xy 338.039438 -288.379988) (xy 338.0839 -288.401086) (xy 338.124403 -288.429042) (xy 338.159896 -288.463134)
			(xy 338.189461 -288.502478) (xy 338.212332 -288.546055) (xy 338.227916 -288.592736) (xy 338.235811 -288.641313)
			(xy 338.236306 -288.66592) (xy 338.235811 -288.690527) (xy 338.227916 -288.739104) (xy 338.212332 -288.785785)
			(xy 338.189461 -288.829362) (xy 338.159896 -288.868706) (xy 338.124403 -288.902798) (xy 338.0839 -288.930754)
			(xy 338.039438 -288.951852) (xy 337.992167 -288.965544) (xy 337.943312 -288.971476) (xy 337.894137 -288.969495)
			(xy 337.845918 -288.959651) (xy 337.799902 -288.942199) (xy 337.757281 -288.917592) (xy 337.71916 -288.886467)
			(xy 337.686525 -288.84963) (xy 337.660222 -288.808034) (xy 337.640931 -288.762758) (xy 337.629154 -288.714974)
			(xy 337.625194 -288.66592) (xy 337.296506 -288.66592) (xy 337.296011 -288.690527) (xy 337.288116 -288.739104)
			(xy 337.272532 -288.785785) (xy 337.249661 -288.829362) (xy 337.220096 -288.868706) (xy 337.184603 -288.902798)
			(xy 337.1441 -288.930754) (xy 337.099638 -288.951852) (xy 337.052367 -288.965544) (xy 337.003512 -288.971476)
			(xy 336.954337 -288.969495) (xy 336.906118 -288.959651) (xy 336.860102 -288.942199) (xy 336.817481 -288.917592)
			(xy 336.77936 -288.886467) (xy 336.746725 -288.84963) (xy 336.720422 -288.808034) (xy 336.701131 -288.762758)
			(xy 336.689354 -288.714974) (xy 336.685394 -288.66592) (xy 336.356452 -288.66592) (xy 336.355957 -288.690527)
			(xy 336.348062 -288.739104) (xy 336.332478 -288.785785) (xy 336.309607 -288.829362) (xy 336.280042 -288.868706)
			(xy 336.244549 -288.902798) (xy 336.204046 -288.930754) (xy 336.159584 -288.951852) (xy 336.112313 -288.965544)
			(xy 336.063458 -288.971476) (xy 336.014283 -288.969495) (xy 335.966064 -288.959651) (xy 335.920048 -288.942199)
			(xy 335.877427 -288.917592) (xy 335.839306 -288.886467) (xy 335.806671 -288.84963) (xy 335.780368 -288.808034)
			(xy 335.761077 -288.762758) (xy 335.7493 -288.714974) (xy 335.74534 -288.66592) (xy 335.416398 -288.66592)
			(xy 335.415903 -288.690527) (xy 335.408008 -288.739104) (xy 335.392424 -288.785785) (xy 335.369553 -288.829362)
			(xy 335.339988 -288.868706) (xy 335.304495 -288.902798) (xy 335.263992 -288.930754) (xy 335.21953 -288.951852)
			(xy 335.172259 -288.965544) (xy 335.123404 -288.971476) (xy 335.074229 -288.969495) (xy 335.02601 -288.959651)
			(xy 334.979994 -288.942199) (xy 334.937373 -288.917592) (xy 334.899252 -288.886467) (xy 334.866617 -288.84963)
			(xy 334.840314 -288.808034) (xy 334.821023 -288.762758) (xy 334.809246 -288.714974) (xy 334.805286 -288.66592)
			(xy 334.476344 -288.66592) (xy 334.475849 -288.690527) (xy 334.467954 -288.739104) (xy 334.45237 -288.785785)
			(xy 334.429499 -288.829362) (xy 334.399934 -288.868706) (xy 334.364441 -288.902798) (xy 334.323938 -288.930754)
			(xy 334.279476 -288.951852) (xy 334.232205 -288.965544) (xy 334.18335 -288.971476) (xy 334.134175 -288.969495)
			(xy 334.085956 -288.959651) (xy 334.03994 -288.942199) (xy 333.997319 -288.917592) (xy 333.959198 -288.886467)
			(xy 333.926563 -288.84963) (xy 333.90026 -288.808034) (xy 333.880969 -288.762758) (xy 333.869192 -288.714974)
			(xy 333.865232 -288.66592) (xy 333.53629 -288.66592) (xy 333.535795 -288.690527) (xy 333.5279 -288.739104)
			(xy 333.512316 -288.785785) (xy 333.489445 -288.829362) (xy 333.45988 -288.868706) (xy 333.424387 -288.902798)
			(xy 333.383884 -288.930754) (xy 333.339422 -288.951852) (xy 333.292151 -288.965544) (xy 333.243296 -288.971476)
			(xy 333.194121 -288.969495) (xy 333.145902 -288.959651) (xy 333.099886 -288.942199) (xy 333.057265 -288.917592)
			(xy 333.019144 -288.886467) (xy 332.986509 -288.84963) (xy 332.960206 -288.808034) (xy 332.940915 -288.762758)
			(xy 332.929138 -288.714974) (xy 332.925178 -288.66592) (xy 332.59649 -288.66592) (xy 332.595995 -288.690527)
			(xy 332.5881 -288.739104) (xy 332.572516 -288.785785) (xy 332.549645 -288.829362) (xy 332.52008 -288.868706)
			(xy 332.484587 -288.902798) (xy 332.444084 -288.930754) (xy 332.399622 -288.951852) (xy 332.352351 -288.965544)
			(xy 332.303496 -288.971476) (xy 332.254321 -288.969495) (xy 332.206102 -288.959651) (xy 332.160086 -288.942199)
			(xy 332.117465 -288.917592) (xy 332.079344 -288.886467) (xy 332.046709 -288.84963) (xy 332.020406 -288.808034)
			(xy 332.001115 -288.762758) (xy 331.989338 -288.714974) (xy 331.985378 -288.66592) (xy 331.6562 -288.66592)
			(xy 331.6562 -288.690113) (xy 331.648571 -288.737916) (xy 331.633505 -288.78392) (xy 331.611378 -288.826975)
			(xy 331.582744 -288.866006) (xy 331.548317 -288.900038) (xy 331.508958 -288.92822) (xy 331.487526 -288.939478)
			(xy 331.486764 -288.939732) (xy 331.480509 -288.943136) (xy 331.470064 -288.952806) (xy 331.46619 -288.958782)
			(xy 331.463142 -288.963862) (xy 331.459332 -288.97707) (xy 331.459332 -289.166046) (xy 331.459806 -289.175418)
			(xy 331.466651 -289.192872) (xy 331.479331 -289.206683) (xy 331.487526 -289.211258) (xy 331.518006 -289.225482)
			(xy 331.566266 -289.247834) (xy 331.56955 -289.249331) (xy 331.576432 -289.251505) (xy 331.579982 -289.252152)
			(xy 331.584357 -289.252704) (xy 331.593171 -289.252446) (xy 331.597508 -289.251644) (xy 331.605382 -289.249612)
			(xy 331.62367 -289.242754) (xy 331.63002 -289.237674) (xy 331.650501 -289.221964) (xy 331.695639 -289.196932)
			(xy 331.74434 -289.17984) (xy 331.795221 -289.171173) (xy 331.821028 -289.170618) (xy 331.84628 -289.171142)
			(xy 331.896094 -289.179458) (xy 331.943859 -289.19586) (xy 331.988274 -289.2199) (xy 332.028127 -289.250922)
			(xy 332.06233 -289.28808) (xy 332.089952 -289.330361) (xy 332.110238 -289.376611) (xy 332.122635 -289.425569)
			(xy 332.126805 -289.4759) (xy 332.126803 -289.475926) (xy 332.455278 -289.475926) (xy 332.459238 -289.426872)
			(xy 332.471015 -289.379088) (xy 332.490306 -289.333812) (xy 332.516609 -289.292216) (xy 332.549244 -289.255379)
			(xy 332.587365 -289.224254) (xy 332.629986 -289.199647) (xy 332.676002 -289.182195) (xy 332.724221 -289.172351)
			(xy 332.773396 -289.17037) (xy 332.822251 -289.176302) (xy 332.869522 -289.189994) (xy 332.913984 -289.211092)
			(xy 332.954487 -289.239048) (xy 332.98998 -289.27314) (xy 333.019545 -289.312484) (xy 333.042416 -289.356061)
			(xy 333.058 -289.402742) (xy 333.065895 -289.451319) (xy 333.06639 -289.475926) (xy 333.395332 -289.475926)
			(xy 333.399292 -289.426872) (xy 333.411069 -289.379088) (xy 333.43036 -289.333812) (xy 333.456663 -289.292216)
			(xy 333.489298 -289.255379) (xy 333.527419 -289.224254) (xy 333.57004 -289.199647) (xy 333.616056 -289.182195)
			(xy 333.664275 -289.172351) (xy 333.71345 -289.17037) (xy 333.762305 -289.176302) (xy 333.809576 -289.189994)
			(xy 333.854038 -289.211092) (xy 333.894541 -289.239048) (xy 333.930034 -289.27314) (xy 333.959599 -289.312484)
			(xy 333.98247 -289.356061) (xy 333.998054 -289.402742) (xy 334.005949 -289.451319) (xy 334.006444 -289.475926)
			(xy 334.335386 -289.475926) (xy 334.339346 -289.426872) (xy 334.351123 -289.379088) (xy 334.370414 -289.333812)
			(xy 334.396717 -289.292216) (xy 334.429352 -289.255379) (xy 334.467473 -289.224254) (xy 334.510094 -289.199647)
			(xy 334.55611 -289.182195) (xy 334.604329 -289.172351) (xy 334.653504 -289.17037) (xy 334.702359 -289.176302)
			(xy 334.74963 -289.189994) (xy 334.794092 -289.211092) (xy 334.834595 -289.239048) (xy 334.870088 -289.27314)
			(xy 334.899653 -289.312484) (xy 334.922524 -289.356061) (xy 334.938108 -289.402742) (xy 334.946003 -289.451319)
			(xy 334.946498 -289.475926) (xy 335.275186 -289.475926) (xy 335.279146 -289.426872) (xy 335.290923 -289.379088)
			(xy 335.310214 -289.333812) (xy 335.336517 -289.292216) (xy 335.369152 -289.255379) (xy 335.407273 -289.224254)
			(xy 335.449894 -289.199647) (xy 335.49591 -289.182195) (xy 335.544129 -289.172351) (xy 335.593304 -289.17037)
			(xy 335.642159 -289.176302) (xy 335.68943 -289.189994) (xy 335.733892 -289.211092) (xy 335.774395 -289.239048)
			(xy 335.809888 -289.27314) (xy 335.839453 -289.312484) (xy 335.862324 -289.356061) (xy 335.877908 -289.402742)
			(xy 335.885803 -289.451319) (xy 335.886298 -289.475926) (xy 336.21524 -289.475926) (xy 336.2192 -289.426872)
			(xy 336.230977 -289.379088) (xy 336.250268 -289.333812) (xy 336.276571 -289.292216) (xy 336.309206 -289.255379)
			(xy 336.347327 -289.224254) (xy 336.389948 -289.199647) (xy 336.435964 -289.182195) (xy 336.484183 -289.172351)
			(xy 336.533358 -289.17037) (xy 336.582213 -289.176302) (xy 336.629484 -289.189994) (xy 336.673946 -289.211092)
			(xy 336.714449 -289.239048) (xy 336.749942 -289.27314) (xy 336.779507 -289.312484) (xy 336.802378 -289.356061)
			(xy 336.817962 -289.402742) (xy 336.825857 -289.451319) (xy 336.826352 -289.475926) (xy 337.155294 -289.475926)
			(xy 337.159254 -289.426872) (xy 337.171031 -289.379088) (xy 337.190322 -289.333812) (xy 337.216625 -289.292216)
			(xy 337.24926 -289.255379) (xy 337.287381 -289.224254) (xy 337.330002 -289.199647) (xy 337.376018 -289.182195)
			(xy 337.424237 -289.172351) (xy 337.473412 -289.17037) (xy 337.522267 -289.176302) (xy 337.569538 -289.189994)
			(xy 337.614 -289.211092) (xy 337.654503 -289.239048) (xy 337.689996 -289.27314) (xy 337.719561 -289.312484)
			(xy 337.742432 -289.356061) (xy 337.758016 -289.402742) (xy 337.765911 -289.451319) (xy 337.766406 -289.475926)
			(xy 338.095348 -289.475926) (xy 338.099308 -289.426872) (xy 338.111085 -289.379088) (xy 338.130376 -289.333812)
			(xy 338.156679 -289.292216) (xy 338.189314 -289.255379) (xy 338.227435 -289.224254) (xy 338.270056 -289.199647)
			(xy 338.316072 -289.182195) (xy 338.364291 -289.172351) (xy 338.413466 -289.17037) (xy 338.462321 -289.176302)
			(xy 338.509592 -289.189994) (xy 338.554054 -289.211092) (xy 338.594557 -289.239048) (xy 338.63005 -289.27314)
			(xy 338.659615 -289.312484) (xy 338.682486 -289.356061) (xy 338.69807 -289.402742) (xy 338.705965 -289.451319)
			(xy 338.70646 -289.475926) (xy 338.705965 -289.500533) (xy 338.69807 -289.54911) (xy 338.682486 -289.595791)
			(xy 338.659615 -289.639368) (xy 338.63005 -289.678712) (xy 338.594557 -289.712804) (xy 338.554054 -289.74076)
			(xy 338.509592 -289.761858) (xy 338.462321 -289.77555) (xy 338.413466 -289.781482) (xy 338.364291 -289.779501)
			(xy 338.316072 -289.769657) (xy 338.270056 -289.752205) (xy 338.227435 -289.727598) (xy 338.189314 -289.696473)
			(xy 338.156679 -289.659636) (xy 338.130376 -289.61804) (xy 338.111085 -289.572764) (xy 338.099308 -289.52498)
			(xy 338.095348 -289.475926) (xy 337.766406 -289.475926) (xy 337.765911 -289.500533) (xy 337.758016 -289.54911)
			(xy 337.742432 -289.595791) (xy 337.719561 -289.639368) (xy 337.689996 -289.678712) (xy 337.654503 -289.712804)
			(xy 337.614 -289.74076) (xy 337.569538 -289.761858) (xy 337.522267 -289.77555) (xy 337.473412 -289.781482)
			(xy 337.424237 -289.779501) (xy 337.376018 -289.769657) (xy 337.330002 -289.752205) (xy 337.287381 -289.727598)
			(xy 337.24926 -289.696473) (xy 337.216625 -289.659636) (xy 337.190322 -289.61804) (xy 337.171031 -289.572764)
			(xy 337.159254 -289.52498) (xy 337.155294 -289.475926) (xy 336.826352 -289.475926) (xy 336.825857 -289.500533)
			(xy 336.817962 -289.54911) (xy 336.802378 -289.595791) (xy 336.779507 -289.639368) (xy 336.749942 -289.678712)
			(xy 336.714449 -289.712804) (xy 336.673946 -289.74076) (xy 336.629484 -289.761858) (xy 336.582213 -289.77555)
			(xy 336.533358 -289.781482) (xy 336.484183 -289.779501) (xy 336.435964 -289.769657) (xy 336.389948 -289.752205)
			(xy 336.347327 -289.727598) (xy 336.309206 -289.696473) (xy 336.276571 -289.659636) (xy 336.250268 -289.61804)
			(xy 336.230977 -289.572764) (xy 336.2192 -289.52498) (xy 336.21524 -289.475926) (xy 335.886298 -289.475926)
			(xy 335.885803 -289.500533) (xy 335.877908 -289.54911) (xy 335.862324 -289.595791) (xy 335.839453 -289.639368)
			(xy 335.809888 -289.678712) (xy 335.774395 -289.712804) (xy 335.733892 -289.74076) (xy 335.68943 -289.761858)
			(xy 335.642159 -289.77555) (xy 335.593304 -289.781482) (xy 335.544129 -289.779501) (xy 335.49591 -289.769657)
			(xy 335.449894 -289.752205) (xy 335.407273 -289.727598) (xy 335.369152 -289.696473) (xy 335.336517 -289.659636)
			(xy 335.310214 -289.61804) (xy 335.290923 -289.572764) (xy 335.279146 -289.52498) (xy 335.275186 -289.475926)
			(xy 334.946498 -289.475926) (xy 334.946003 -289.500533) (xy 334.938108 -289.54911) (xy 334.922524 -289.595791)
			(xy 334.899653 -289.639368) (xy 334.870088 -289.678712) (xy 334.834595 -289.712804) (xy 334.794092 -289.74076)
			(xy 334.74963 -289.761858) (xy 334.702359 -289.77555) (xy 334.653504 -289.781482) (xy 334.604329 -289.779501)
			(xy 334.55611 -289.769657) (xy 334.510094 -289.752205) (xy 334.467473 -289.727598) (xy 334.429352 -289.696473)
			(xy 334.396717 -289.659636) (xy 334.370414 -289.61804) (xy 334.351123 -289.572764) (xy 334.339346 -289.52498)
			(xy 334.335386 -289.475926) (xy 334.006444 -289.475926) (xy 334.005949 -289.500533) (xy 333.998054 -289.54911)
			(xy 333.98247 -289.595791) (xy 333.959599 -289.639368) (xy 333.930034 -289.678712) (xy 333.894541 -289.712804)
			(xy 333.854038 -289.74076) (xy 333.809576 -289.761858) (xy 333.762305 -289.77555) (xy 333.71345 -289.781482)
			(xy 333.664275 -289.779501) (xy 333.616056 -289.769657) (xy 333.57004 -289.752205) (xy 333.527419 -289.727598)
			(xy 333.489298 -289.696473) (xy 333.456663 -289.659636) (xy 333.43036 -289.61804) (xy 333.411069 -289.572764)
			(xy 333.399292 -289.52498) (xy 333.395332 -289.475926) (xy 333.06639 -289.475926) (xy 333.065895 -289.500533)
			(xy 333.058 -289.54911) (xy 333.042416 -289.595791) (xy 333.019545 -289.639368) (xy 332.98998 -289.678712)
			(xy 332.954487 -289.712804) (xy 332.913984 -289.74076) (xy 332.869522 -289.761858) (xy 332.822251 -289.77555)
			(xy 332.773396 -289.781482) (xy 332.724221 -289.779501) (xy 332.676002 -289.769657) (xy 332.629986 -289.752205)
			(xy 332.587365 -289.727598) (xy 332.549244 -289.696473) (xy 332.516609 -289.659636) (xy 332.490306 -289.61804)
			(xy 332.471015 -289.572764) (xy 332.459238 -289.52498) (xy 332.455278 -289.475926) (xy 332.126803 -289.475926)
			(xy 332.122635 -289.526231) (xy 332.110238 -289.575189) (xy 332.089952 -289.621439) (xy 332.06233 -289.66372)
			(xy 332.028127 -289.700878) (xy 331.988274 -289.7319) (xy 331.943859 -289.75594) (xy 331.896094 -289.772342)
			(xy 331.84628 -289.780658) (xy 331.821028 -289.781234) (xy 331.808265 -289.781094) (xy 331.782832 -289.778929)
			(xy 331.770228 -289.776916) (xy 331.743541 -289.771835) (xy 331.692408 -289.753499) (xy 331.645331 -289.726399)
			(xy 331.624178 -289.709352) (xy 331.61859 -289.70478) (xy 331.605636 -289.698938) (xy 331.59827 -289.697922)
			(xy 331.591061 -289.69724) (xy 331.576753 -289.699437) (xy 331.570076 -289.70224) (xy 331.487018 -289.740594)
			(xy 331.479144 -289.745032) (xy 331.466908 -289.75832) (xy 331.460017 -289.775016) (xy 331.459332 -289.784028)
			(xy 331.459332 -289.96767) (xy 331.459572 -289.974621) (xy 331.463308 -289.988013) (xy 331.466698 -289.994086)
			(xy 331.47 -289.999166) (xy 331.480414 -290.008818) (xy 331.487526 -290.012374) (xy 331.508973 -290.023601)
			(xy 331.548328 -290.051785) (xy 331.582751 -290.085818) (xy 331.611381 -290.12485) (xy 331.633504 -290.167905)
			(xy 331.648566 -290.213909) (xy 331.656191 -290.261711) (xy 331.65619 -290.285932) (xy 331.985378 -290.285932)
			(xy 331.989338 -290.236878) (xy 332.001115 -290.189094) (xy 332.020406 -290.143818) (xy 332.046709 -290.102222)
			(xy 332.079344 -290.065385) (xy 332.117465 -290.03426) (xy 332.160086 -290.009653) (xy 332.206102 -289.992201)
			(xy 332.254321 -289.982357) (xy 332.303496 -289.980376) (xy 332.352351 -289.986308) (xy 332.399622 -290)
			(xy 332.444084 -290.021098) (xy 332.484587 -290.049054) (xy 332.52008 -290.083146) (xy 332.549645 -290.12249)
			(xy 332.572516 -290.166067) (xy 332.5881 -290.212748) (xy 332.595995 -290.261325) (xy 332.59649 -290.285932)
			(xy 332.925178 -290.285932) (xy 332.929138 -290.236878) (xy 332.940915 -290.189094) (xy 332.960206 -290.143818)
			(xy 332.986509 -290.102222) (xy 333.019144 -290.065385) (xy 333.057265 -290.03426) (xy 333.099886 -290.009653)
			(xy 333.145902 -289.992201) (xy 333.194121 -289.982357) (xy 333.243296 -289.980376) (xy 333.292151 -289.986308)
			(xy 333.339422 -290) (xy 333.383884 -290.021098) (xy 333.424387 -290.049054) (xy 333.45988 -290.083146)
			(xy 333.489445 -290.12249) (xy 333.512316 -290.166067) (xy 333.5279 -290.212748) (xy 333.535795 -290.261325)
			(xy 333.53629 -290.285932) (xy 333.865232 -290.285932) (xy 333.869192 -290.236878) (xy 333.880969 -290.189094)
			(xy 333.90026 -290.143818) (xy 333.926563 -290.102222) (xy 333.959198 -290.065385) (xy 333.997319 -290.03426)
			(xy 334.03994 -290.009653) (xy 334.085956 -289.992201) (xy 334.134175 -289.982357) (xy 334.18335 -289.980376)
			(xy 334.232205 -289.986308) (xy 334.279476 -290) (xy 334.323938 -290.021098) (xy 334.364441 -290.049054)
			(xy 334.399934 -290.083146) (xy 334.429499 -290.12249) (xy 334.45237 -290.166067) (xy 334.467954 -290.212748)
			(xy 334.475849 -290.261325) (xy 334.476344 -290.285932) (xy 335.74534 -290.285932) (xy 335.7493 -290.236878)
			(xy 335.761077 -290.189094) (xy 335.780368 -290.143818) (xy 335.806671 -290.102222) (xy 335.839306 -290.065385)
			(xy 335.877427 -290.03426) (xy 335.920048 -290.009653) (xy 335.966064 -289.992201) (xy 336.014283 -289.982357)
			(xy 336.063458 -289.980376) (xy 336.112313 -289.986308) (xy 336.159584 -290) (xy 336.204046 -290.021098)
			(xy 336.244549 -290.049054) (xy 336.280042 -290.083146) (xy 336.309607 -290.12249) (xy 336.332478 -290.166067)
			(xy 336.348062 -290.212748) (xy 336.355957 -290.261325) (xy 336.356452 -290.285932) (xy 336.685394 -290.285932)
			(xy 336.689354 -290.236878) (xy 336.701131 -290.189094) (xy 336.720422 -290.143818) (xy 336.746725 -290.102222)
			(xy 336.77936 -290.065385) (xy 336.817481 -290.03426) (xy 336.860102 -290.009653) (xy 336.906118 -289.992201)
			(xy 336.954337 -289.982357) (xy 337.003512 -289.980376) (xy 337.052367 -289.986308) (xy 337.099638 -290)
			(xy 337.1441 -290.021098) (xy 337.184603 -290.049054) (xy 337.220096 -290.083146) (xy 337.249661 -290.12249)
			(xy 337.272532 -290.166067) (xy 337.288116 -290.212748) (xy 337.296011 -290.261325) (xy 337.296506 -290.285932)
			(xy 337.625194 -290.285932) (xy 337.629154 -290.236878) (xy 337.640931 -290.189094) (xy 337.660222 -290.143818)
			(xy 337.686525 -290.102222) (xy 337.71916 -290.065385) (xy 337.757281 -290.03426) (xy 337.799902 -290.009653)
			(xy 337.845918 -289.992201) (xy 337.894137 -289.982357) (xy 337.943312 -289.980376) (xy 337.992167 -289.986308)
			(xy 338.039438 -290) (xy 338.0839 -290.021098) (xy 338.124403 -290.049054) (xy 338.159896 -290.083146)
			(xy 338.189461 -290.12249) (xy 338.212332 -290.166067) (xy 338.227916 -290.212748) (xy 338.235811 -290.261325)
			(xy 338.236306 -290.285932) (xy 338.235811 -290.310539) (xy 338.227916 -290.359116) (xy 338.212332 -290.405797)
			(xy 338.189461 -290.449374) (xy 338.159896 -290.488718) (xy 338.124403 -290.52281) (xy 338.0839 -290.550766)
			(xy 338.039438 -290.571864) (xy 337.992167 -290.585556) (xy 337.943312 -290.591488) (xy 337.894137 -290.589507)
			(xy 337.845918 -290.579663) (xy 337.799902 -290.562211) (xy 337.757281 -290.537604) (xy 337.71916 -290.506479)
			(xy 337.686525 -290.469642) (xy 337.660222 -290.428046) (xy 337.640931 -290.38277) (xy 337.629154 -290.334986)
			(xy 337.625194 -290.285932) (xy 337.296506 -290.285932) (xy 337.296011 -290.310539) (xy 337.288116 -290.359116)
			(xy 337.272532 -290.405797) (xy 337.249661 -290.449374) (xy 337.220096 -290.488718) (xy 337.184603 -290.52281)
			(xy 337.1441 -290.550766) (xy 337.099638 -290.571864) (xy 337.052367 -290.585556) (xy 337.003512 -290.591488)
			(xy 336.954337 -290.589507) (xy 336.906118 -290.579663) (xy 336.860102 -290.562211) (xy 336.817481 -290.537604)
			(xy 336.77936 -290.506479) (xy 336.746725 -290.469642) (xy 336.720422 -290.428046) (xy 336.701131 -290.38277)
			(xy 336.689354 -290.334986) (xy 336.685394 -290.285932) (xy 336.356452 -290.285932) (xy 336.355957 -290.310539)
			(xy 336.348062 -290.359116) (xy 336.332478 -290.405797) (xy 336.309607 -290.449374) (xy 336.280042 -290.488718)
			(xy 336.244549 -290.52281) (xy 336.204046 -290.550766) (xy 336.159584 -290.571864) (xy 336.112313 -290.585556)
			(xy 336.063458 -290.591488) (xy 336.014283 -290.589507) (xy 335.966064 -290.579663) (xy 335.920048 -290.562211)
			(xy 335.877427 -290.537604) (xy 335.839306 -290.506479) (xy 335.806671 -290.469642) (xy 335.780368 -290.428046)
			(xy 335.761077 -290.38277) (xy 335.7493 -290.334986) (xy 335.74534 -290.285932) (xy 334.476344 -290.285932)
			(xy 334.475849 -290.310539) (xy 334.467954 -290.359116) (xy 334.45237 -290.405797) (xy 334.429499 -290.449374)
			(xy 334.399934 -290.488718) (xy 334.364441 -290.52281) (xy 334.323938 -290.550766) (xy 334.279476 -290.571864)
			(xy 334.232205 -290.585556) (xy 334.18335 -290.591488) (xy 334.134175 -290.589507) (xy 334.085956 -290.579663)
			(xy 334.03994 -290.562211) (xy 333.997319 -290.537604) (xy 333.959198 -290.506479) (xy 333.926563 -290.469642)
			(xy 333.90026 -290.428046) (xy 333.880969 -290.38277) (xy 333.869192 -290.334986) (xy 333.865232 -290.285932)
			(xy 333.53629 -290.285932) (xy 333.535795 -290.310539) (xy 333.5279 -290.359116) (xy 333.512316 -290.405797)
			(xy 333.489445 -290.449374) (xy 333.45988 -290.488718) (xy 333.424387 -290.52281) (xy 333.383884 -290.550766)
			(xy 333.339422 -290.571864) (xy 333.292151 -290.585556) (xy 333.243296 -290.591488) (xy 333.194121 -290.589507)
			(xy 333.145902 -290.579663) (xy 333.099886 -290.562211) (xy 333.057265 -290.537604) (xy 333.019144 -290.506479)
			(xy 332.986509 -290.469642) (xy 332.960206 -290.428046) (xy 332.940915 -290.38277) (xy 332.929138 -290.334986)
			(xy 332.925178 -290.285932) (xy 332.59649 -290.285932) (xy 332.595995 -290.310539) (xy 332.5881 -290.359116)
			(xy 332.572516 -290.405797) (xy 332.549645 -290.449374) (xy 332.52008 -290.488718) (xy 332.484587 -290.52281)
			(xy 332.444084 -290.550766) (xy 332.399622 -290.571864) (xy 332.352351 -290.585556) (xy 332.303496 -290.591488)
			(xy 332.254321 -290.589507) (xy 332.206102 -290.579663) (xy 332.160086 -290.562211) (xy 332.117465 -290.537604)
			(xy 332.079344 -290.506479) (xy 332.046709 -290.469642) (xy 332.020406 -290.428046) (xy 332.001115 -290.38277)
			(xy 331.989338 -290.334986) (xy 331.985378 -290.285932) (xy 331.65619 -290.285932) (xy 331.656189 -290.310117)
			(xy 331.648559 -290.357919) (xy 331.633493 -290.403921) (xy 331.611366 -290.446974) (xy 331.582732 -290.486004)
			(xy 331.548306 -290.520033) (xy 331.508948 -290.548214) (xy 331.487526 -290.55949) (xy 331.486764 -290.559744)
			(xy 331.480509 -290.563148) (xy 331.470066 -290.57282) (xy 331.46619 -290.578794) (xy 331.463142 -290.583874)
			(xy 331.459332 -290.597082) (xy 331.459332 -290.786058) (xy 331.459808 -290.795429) (xy 331.466656 -290.812879)
			(xy 331.479336 -290.826687) (xy 331.487526 -290.83127) (xy 331.518006 -290.845494) (xy 331.566266 -290.867846)
			(xy 331.56955 -290.869343) (xy 331.576432 -290.871516) (xy 331.579982 -290.872164) (xy 331.584357 -290.872716)
			(xy 331.593171 -290.872458) (xy 331.597508 -290.871656) (xy 331.605382 -290.869624) (xy 331.62367 -290.862766)
			(xy 331.63002 -290.857686) (xy 331.650501 -290.841975) (xy 331.695638 -290.816943) (xy 331.74434 -290.79985)
			(xy 331.795221 -290.791183) (xy 331.821028 -290.79063) (xy 331.846279 -290.791154) (xy 331.896091 -290.79947)
			(xy 331.943855 -290.815871) (xy 331.988268 -290.83991) (xy 332.028119 -290.870931) (xy 332.062321 -290.908087)
			(xy 332.089941 -290.950366) (xy 332.110226 -290.996615) (xy 332.122623 -291.045571) (xy 332.126793 -291.0959)
			(xy 332.12679 -291.095938) (xy 332.455278 -291.095938) (xy 332.459238 -291.046884) (xy 332.471015 -290.9991)
			(xy 332.490306 -290.953824) (xy 332.516609 -290.912228) (xy 332.549244 -290.875391) (xy 332.587365 -290.844266)
			(xy 332.629986 -290.819659) (xy 332.676002 -290.802207) (xy 332.724221 -290.792363) (xy 332.773396 -290.790382)
			(xy 332.822251 -290.796314) (xy 332.869522 -290.810006) (xy 332.913984 -290.831104) (xy 332.954487 -290.85906)
			(xy 332.98998 -290.893152) (xy 333.019545 -290.932496) (xy 333.042416 -290.976073) (xy 333.058 -291.022754)
			(xy 333.065895 -291.071331) (xy 333.06639 -291.095938) (xy 333.395332 -291.095938) (xy 333.399292 -291.046884)
			(xy 333.411069 -290.9991) (xy 333.43036 -290.953824) (xy 333.456663 -290.912228) (xy 333.489298 -290.875391)
			(xy 333.527419 -290.844266) (xy 333.57004 -290.819659) (xy 333.616056 -290.802207) (xy 333.664275 -290.792363)
			(xy 333.71345 -290.790382) (xy 333.762305 -290.796314) (xy 333.809576 -290.810006) (xy 333.854038 -290.831104)
			(xy 333.894541 -290.85906) (xy 333.930034 -290.893152) (xy 333.959599 -290.932496) (xy 333.98247 -290.976073)
			(xy 333.998054 -291.022754) (xy 334.005949 -291.071331) (xy 334.006444 -291.095938) (xy 334.335386 -291.095938)
			(xy 334.339346 -291.046884) (xy 334.351123 -290.9991) (xy 334.370414 -290.953824) (xy 334.396717 -290.912228)
			(xy 334.429352 -290.875391) (xy 334.467473 -290.844266) (xy 334.510094 -290.819659) (xy 334.55611 -290.802207)
			(xy 334.604329 -290.792363) (xy 334.653504 -290.790382) (xy 334.702359 -290.796314) (xy 334.74963 -290.810006)
			(xy 334.794092 -290.831104) (xy 334.834595 -290.85906) (xy 334.870088 -290.893152) (xy 334.899653 -290.932496)
			(xy 334.922524 -290.976073) (xy 334.938108 -291.022754) (xy 334.946003 -291.071331) (xy 334.946498 -291.095938)
			(xy 335.275186 -291.095938) (xy 335.279146 -291.046884) (xy 335.290923 -290.9991) (xy 335.310214 -290.953824)
			(xy 335.336517 -290.912228) (xy 335.369152 -290.875391) (xy 335.407273 -290.844266) (xy 335.449894 -290.819659)
			(xy 335.49591 -290.802207) (xy 335.544129 -290.792363) (xy 335.593304 -290.790382) (xy 335.642159 -290.796314)
			(xy 335.68943 -290.810006) (xy 335.733892 -290.831104) (xy 335.774395 -290.85906) (xy 335.809888 -290.893152)
			(xy 335.839453 -290.932496) (xy 335.862324 -290.976073) (xy 335.877908 -291.022754) (xy 335.885803 -291.071331)
			(xy 335.886298 -291.095938) (xy 336.21524 -291.095938) (xy 336.2192 -291.046884) (xy 336.230977 -290.9991)
			(xy 336.250268 -290.953824) (xy 336.276571 -290.912228) (xy 336.309206 -290.875391) (xy 336.347327 -290.844266)
			(xy 336.389948 -290.819659) (xy 336.435964 -290.802207) (xy 336.484183 -290.792363) (xy 336.533358 -290.790382)
			(xy 336.582213 -290.796314) (xy 336.629484 -290.810006) (xy 336.673946 -290.831104) (xy 336.714449 -290.85906)
			(xy 336.749942 -290.893152) (xy 336.779507 -290.932496) (xy 336.802378 -290.976073) (xy 336.817962 -291.022754)
			(xy 336.825857 -291.071331) (xy 336.826352 -291.095938) (xy 337.155294 -291.095938) (xy 337.159254 -291.046884)
			(xy 337.171031 -290.9991) (xy 337.190322 -290.953824) (xy 337.216625 -290.912228) (xy 337.24926 -290.875391)
			(xy 337.287381 -290.844266) (xy 337.330002 -290.819659) (xy 337.376018 -290.802207) (xy 337.424237 -290.792363)
			(xy 337.473412 -290.790382) (xy 337.522267 -290.796314) (xy 337.569538 -290.810006) (xy 337.614 -290.831104)
			(xy 337.654503 -290.85906) (xy 337.689996 -290.893152) (xy 337.719561 -290.932496) (xy 337.742432 -290.976073)
			(xy 337.758016 -291.022754) (xy 337.765911 -291.071331) (xy 337.766406 -291.095938) (xy 338.095348 -291.095938)
			(xy 338.099308 -291.046884) (xy 338.111085 -290.9991) (xy 338.130376 -290.953824) (xy 338.156679 -290.912228)
			(xy 338.189314 -290.875391) (xy 338.227435 -290.844266) (xy 338.270056 -290.819659) (xy 338.316072 -290.802207)
			(xy 338.364291 -290.792363) (xy 338.413466 -290.790382) (xy 338.462321 -290.796314) (xy 338.509592 -290.810006)
			(xy 338.554054 -290.831104) (xy 338.594557 -290.85906) (xy 338.63005 -290.893152) (xy 338.659615 -290.932496)
			(xy 338.682486 -290.976073) (xy 338.69807 -291.022754) (xy 338.705965 -291.071331) (xy 338.70646 -291.095938)
			(xy 338.705965 -291.120545) (xy 338.69807 -291.169122) (xy 338.682486 -291.215803) (xy 338.659615 -291.25938)
			(xy 338.63005 -291.298724) (xy 338.594557 -291.332816) (xy 338.554054 -291.360772) (xy 338.509592 -291.38187)
			(xy 338.462321 -291.395562) (xy 338.413466 -291.401494) (xy 338.364291 -291.399513) (xy 338.316072 -291.389669)
			(xy 338.270056 -291.372217) (xy 338.227435 -291.34761) (xy 338.189314 -291.316485) (xy 338.156679 -291.279648)
			(xy 338.130376 -291.238052) (xy 338.111085 -291.192776) (xy 338.099308 -291.144992) (xy 338.095348 -291.095938)
			(xy 337.766406 -291.095938) (xy 337.765911 -291.120545) (xy 337.758016 -291.169122) (xy 337.742432 -291.215803)
			(xy 337.719561 -291.25938) (xy 337.689996 -291.298724) (xy 337.654503 -291.332816) (xy 337.614 -291.360772)
			(xy 337.569538 -291.38187) (xy 337.522267 -291.395562) (xy 337.473412 -291.401494) (xy 337.424237 -291.399513)
			(xy 337.376018 -291.389669) (xy 337.330002 -291.372217) (xy 337.287381 -291.34761) (xy 337.24926 -291.316485)
			(xy 337.216625 -291.279648) (xy 337.190322 -291.238052) (xy 337.171031 -291.192776) (xy 337.159254 -291.144992)
			(xy 337.155294 -291.095938) (xy 336.826352 -291.095938) (xy 336.825857 -291.120545) (xy 336.817962 -291.169122)
			(xy 336.802378 -291.215803) (xy 336.779507 -291.25938) (xy 336.749942 -291.298724) (xy 336.714449 -291.332816)
			(xy 336.673946 -291.360772) (xy 336.629484 -291.38187) (xy 336.582213 -291.395562) (xy 336.533358 -291.401494)
			(xy 336.484183 -291.399513) (xy 336.435964 -291.389669) (xy 336.389948 -291.372217) (xy 336.347327 -291.34761)
			(xy 336.309206 -291.316485) (xy 336.276571 -291.279648) (xy 336.250268 -291.238052) (xy 336.230977 -291.192776)
			(xy 336.2192 -291.144992) (xy 336.21524 -291.095938) (xy 335.886298 -291.095938) (xy 335.885803 -291.120545)
			(xy 335.877908 -291.169122) (xy 335.862324 -291.215803) (xy 335.839453 -291.25938) (xy 335.809888 -291.298724)
			(xy 335.774395 -291.332816) (xy 335.733892 -291.360772) (xy 335.68943 -291.38187) (xy 335.642159 -291.395562)
			(xy 335.593304 -291.401494) (xy 335.544129 -291.399513) (xy 335.49591 -291.389669) (xy 335.449894 -291.372217)
			(xy 335.407273 -291.34761) (xy 335.369152 -291.316485) (xy 335.336517 -291.279648) (xy 335.310214 -291.238052)
			(xy 335.290923 -291.192776) (xy 335.279146 -291.144992) (xy 335.275186 -291.095938) (xy 334.946498 -291.095938)
			(xy 334.946003 -291.120545) (xy 334.938108 -291.169122) (xy 334.922524 -291.215803) (xy 334.899653 -291.25938)
			(xy 334.870088 -291.298724) (xy 334.834595 -291.332816) (xy 334.794092 -291.360772) (xy 334.74963 -291.38187)
			(xy 334.702359 -291.395562) (xy 334.653504 -291.401494) (xy 334.604329 -291.399513) (xy 334.55611 -291.389669)
			(xy 334.510094 -291.372217) (xy 334.467473 -291.34761) (xy 334.429352 -291.316485) (xy 334.396717 -291.279648)
			(xy 334.370414 -291.238052) (xy 334.351123 -291.192776) (xy 334.339346 -291.144992) (xy 334.335386 -291.095938)
			(xy 334.006444 -291.095938) (xy 334.005949 -291.120545) (xy 333.998054 -291.169122) (xy 333.98247 -291.215803)
			(xy 333.959599 -291.25938) (xy 333.930034 -291.298724) (xy 333.894541 -291.332816) (xy 333.854038 -291.360772)
			(xy 333.809576 -291.38187) (xy 333.762305 -291.395562) (xy 333.71345 -291.401494) (xy 333.664275 -291.399513)
			(xy 333.616056 -291.389669) (xy 333.57004 -291.372217) (xy 333.527419 -291.34761) (xy 333.489298 -291.316485)
			(xy 333.456663 -291.279648) (xy 333.43036 -291.238052) (xy 333.411069 -291.192776) (xy 333.399292 -291.144992)
			(xy 333.395332 -291.095938) (xy 333.06639 -291.095938) (xy 333.065895 -291.120545) (xy 333.058 -291.169122)
			(xy 333.042416 -291.215803) (xy 333.019545 -291.25938) (xy 332.98998 -291.298724) (xy 332.954487 -291.332816)
			(xy 332.913984 -291.360772) (xy 332.869522 -291.38187) (xy 332.822251 -291.395562) (xy 332.773396 -291.401494)
			(xy 332.724221 -291.399513) (xy 332.676002 -291.389669) (xy 332.629986 -291.372217) (xy 332.587365 -291.34761)
			(xy 332.549244 -291.316485) (xy 332.516609 -291.279648) (xy 332.490306 -291.238052) (xy 332.471015 -291.192776)
			(xy 332.459238 -291.144992) (xy 332.455278 -291.095938) (xy 332.12679 -291.095938) (xy 332.122623 -291.146229)
			(xy 332.110226 -291.195185) (xy 332.089941 -291.241434) (xy 332.062321 -291.283713) (xy 332.028119 -291.320869)
			(xy 331.988268 -291.35189) (xy 331.943855 -291.375929) (xy 331.896091 -291.39233) (xy 331.846279 -291.400646)
			(xy 331.821028 -291.401246) (xy 331.808265 -291.401106) (xy 331.782832 -291.398941) (xy 331.770228 -291.396928)
			(xy 331.74354 -291.391848) (xy 331.692408 -291.373512) (xy 331.64533 -291.346413) (xy 331.624178 -291.329364)
			(xy 331.61859 -291.324792) (xy 331.605636 -291.31895) (xy 331.59827 -291.317934) (xy 331.591061 -291.317253)
			(xy 331.576754 -291.31945) (xy 331.570076 -291.322252) (xy 331.487018 -291.360606) (xy 331.479145 -291.365045)
			(xy 331.466912 -291.378333) (xy 331.460025 -291.395029) (xy 331.459332 -291.40404) (xy 331.459332 -291.587682)
			(xy 331.459573 -291.594633) (xy 331.463312 -291.608022) (xy 331.466698 -291.614098) (xy 331.47 -291.619178)
			(xy 331.480414 -291.62883) (xy 331.487526 -291.632386) (xy 331.508972 -291.643613) (xy 331.548325 -291.671797)
			(xy 331.582746 -291.705829) (xy 331.611375 -291.74486) (xy 331.633496 -291.787915) (xy 331.648557 -291.833917)
			(xy 331.656181 -291.881717) (xy 331.656179 -291.905944) (xy 331.985378 -291.905944) (xy 331.989338 -291.85689)
			(xy 332.001115 -291.809106) (xy 332.020406 -291.76383) (xy 332.046709 -291.722234) (xy 332.079344 -291.685397)
			(xy 332.117465 -291.654272) (xy 332.160086 -291.629665) (xy 332.206102 -291.612213) (xy 332.254321 -291.602369)
			(xy 332.303496 -291.600388) (xy 332.352351 -291.60632) (xy 332.399622 -291.620012) (xy 332.444084 -291.64111)
			(xy 332.484587 -291.669066) (xy 332.52008 -291.703158) (xy 332.549645 -291.742502) (xy 332.572516 -291.786079)
			(xy 332.5881 -291.83276) (xy 332.595995 -291.881337) (xy 332.59649 -291.905944) (xy 332.925178 -291.905944)
			(xy 332.929138 -291.85689) (xy 332.940915 -291.809106) (xy 332.960206 -291.76383) (xy 332.986509 -291.722234)
			(xy 333.019144 -291.685397) (xy 333.057265 -291.654272) (xy 333.099886 -291.629665) (xy 333.145902 -291.612213)
			(xy 333.194121 -291.602369) (xy 333.243296 -291.600388) (xy 333.292151 -291.60632) (xy 333.339422 -291.620012)
			(xy 333.383884 -291.64111) (xy 333.424387 -291.669066) (xy 333.45988 -291.703158) (xy 333.489445 -291.742502)
			(xy 333.512316 -291.786079) (xy 333.5279 -291.83276) (xy 333.535795 -291.881337) (xy 333.53629 -291.905944)
			(xy 333.865232 -291.905944) (xy 333.869192 -291.85689) (xy 333.880969 -291.809106) (xy 333.90026 -291.76383)
			(xy 333.926563 -291.722234) (xy 333.959198 -291.685397) (xy 333.997319 -291.654272) (xy 334.03994 -291.629665)
			(xy 334.085956 -291.612213) (xy 334.134175 -291.602369) (xy 334.18335 -291.600388) (xy 334.232205 -291.60632)
			(xy 334.279476 -291.620012) (xy 334.323938 -291.64111) (xy 334.364441 -291.669066) (xy 334.399934 -291.703158)
			(xy 334.429499 -291.742502) (xy 334.45237 -291.786079) (xy 334.467954 -291.83276) (xy 334.475849 -291.881337)
			(xy 334.476344 -291.905944) (xy 334.805286 -291.905944) (xy 334.809246 -291.85689) (xy 334.821023 -291.809106)
			(xy 334.840314 -291.76383) (xy 334.866617 -291.722234) (xy 334.899252 -291.685397) (xy 334.937373 -291.654272)
			(xy 334.979994 -291.629665) (xy 335.02601 -291.612213) (xy 335.074229 -291.602369) (xy 335.123404 -291.600388)
			(xy 335.172259 -291.60632) (xy 335.21953 -291.620012) (xy 335.263992 -291.64111) (xy 335.304495 -291.669066)
			(xy 335.339988 -291.703158) (xy 335.369553 -291.742502) (xy 335.392424 -291.786079) (xy 335.408008 -291.83276)
			(xy 335.415903 -291.881337) (xy 335.416398 -291.905944) (xy 335.74534 -291.905944) (xy 335.7493 -291.85689)
			(xy 335.761077 -291.809106) (xy 335.780368 -291.76383) (xy 335.806671 -291.722234) (xy 335.839306 -291.685397)
			(xy 335.877427 -291.654272) (xy 335.920048 -291.629665) (xy 335.966064 -291.612213) (xy 336.014283 -291.602369)
			(xy 336.063458 -291.600388) (xy 336.112313 -291.60632) (xy 336.159584 -291.620012) (xy 336.204046 -291.64111)
			(xy 336.244549 -291.669066) (xy 336.280042 -291.703158) (xy 336.309607 -291.742502) (xy 336.332478 -291.786079)
			(xy 336.348062 -291.83276) (xy 336.355957 -291.881337) (xy 336.356452 -291.905944) (xy 336.685394 -291.905944)
			(xy 336.689354 -291.85689) (xy 336.701131 -291.809106) (xy 336.720422 -291.76383) (xy 336.746725 -291.722234)
			(xy 336.77936 -291.685397) (xy 336.817481 -291.654272) (xy 336.860102 -291.629665) (xy 336.906118 -291.612213)
			(xy 336.954337 -291.602369) (xy 337.003512 -291.600388) (xy 337.052367 -291.60632) (xy 337.099638 -291.620012)
			(xy 337.1441 -291.64111) (xy 337.184603 -291.669066) (xy 337.220096 -291.703158) (xy 337.249661 -291.742502)
			(xy 337.272532 -291.786079) (xy 337.288116 -291.83276) (xy 337.296011 -291.881337) (xy 337.296506 -291.905944)
			(xy 337.625194 -291.905944) (xy 337.629154 -291.85689) (xy 337.640931 -291.809106) (xy 337.660222 -291.76383)
			(xy 337.686525 -291.722234) (xy 337.71916 -291.685397) (xy 337.757281 -291.654272) (xy 337.799902 -291.629665)
			(xy 337.845918 -291.612213) (xy 337.894137 -291.602369) (xy 337.943312 -291.600388) (xy 337.992167 -291.60632)
			(xy 338.039438 -291.620012) (xy 338.0839 -291.64111) (xy 338.124403 -291.669066) (xy 338.159896 -291.703158)
			(xy 338.189461 -291.742502) (xy 338.212332 -291.786079) (xy 338.227916 -291.83276) (xy 338.235811 -291.881337)
			(xy 338.236306 -291.905944) (xy 338.235811 -291.930551) (xy 338.227916 -291.979128) (xy 338.212332 -292.025809)
			(xy 338.189461 -292.069386) (xy 338.159896 -292.10873) (xy 338.124403 -292.142822) (xy 338.0839 -292.170778)
			(xy 338.039438 -292.191876) (xy 337.992167 -292.205568) (xy 337.943312 -292.2115) (xy 337.894137 -292.209519)
			(xy 337.845918 -292.199675) (xy 337.799902 -292.182223) (xy 337.757281 -292.157616) (xy 337.71916 -292.126491)
			(xy 337.686525 -292.089654) (xy 337.660222 -292.048058) (xy 337.640931 -292.002782) (xy 337.629154 -291.954998)
			(xy 337.625194 -291.905944) (xy 337.296506 -291.905944) (xy 337.296011 -291.930551) (xy 337.288116 -291.979128)
			(xy 337.272532 -292.025809) (xy 337.249661 -292.069386) (xy 337.220096 -292.10873) (xy 337.184603 -292.142822)
			(xy 337.1441 -292.170778) (xy 337.099638 -292.191876) (xy 337.052367 -292.205568) (xy 337.003512 -292.2115)
			(xy 336.954337 -292.209519) (xy 336.906118 -292.199675) (xy 336.860102 -292.182223) (xy 336.817481 -292.157616)
			(xy 336.77936 -292.126491) (xy 336.746725 -292.089654) (xy 336.720422 -292.048058) (xy 336.701131 -292.002782)
			(xy 336.689354 -291.954998) (xy 336.685394 -291.905944) (xy 336.356452 -291.905944) (xy 336.355957 -291.930551)
			(xy 336.348062 -291.979128) (xy 336.332478 -292.025809) (xy 336.309607 -292.069386) (xy 336.280042 -292.10873)
			(xy 336.244549 -292.142822) (xy 336.204046 -292.170778) (xy 336.159584 -292.191876) (xy 336.112313 -292.205568)
			(xy 336.063458 -292.2115) (xy 336.014283 -292.209519) (xy 335.966064 -292.199675) (xy 335.920048 -292.182223)
			(xy 335.877427 -292.157616) (xy 335.839306 -292.126491) (xy 335.806671 -292.089654) (xy 335.780368 -292.048058)
			(xy 335.761077 -292.002782) (xy 335.7493 -291.954998) (xy 335.74534 -291.905944) (xy 335.416398 -291.905944)
			(xy 335.415903 -291.930551) (xy 335.408008 -291.979128) (xy 335.392424 -292.025809) (xy 335.369553 -292.069386)
			(xy 335.339988 -292.10873) (xy 335.304495 -292.142822) (xy 335.263992 -292.170778) (xy 335.21953 -292.191876)
			(xy 335.172259 -292.205568) (xy 335.123404 -292.2115) (xy 335.074229 -292.209519) (xy 335.02601 -292.199675)
			(xy 334.979994 -292.182223) (xy 334.937373 -292.157616) (xy 334.899252 -292.126491) (xy 334.866617 -292.089654)
			(xy 334.840314 -292.048058) (xy 334.821023 -292.002782) (xy 334.809246 -291.954998) (xy 334.805286 -291.905944)
			(xy 334.476344 -291.905944) (xy 334.475849 -291.930551) (xy 334.467954 -291.979128) (xy 334.45237 -292.025809)
			(xy 334.429499 -292.069386) (xy 334.399934 -292.10873) (xy 334.364441 -292.142822) (xy 334.323938 -292.170778)
			(xy 334.279476 -292.191876) (xy 334.232205 -292.205568) (xy 334.18335 -292.2115) (xy 334.134175 -292.209519)
			(xy 334.085956 -292.199675) (xy 334.03994 -292.182223) (xy 333.997319 -292.157616) (xy 333.959198 -292.126491)
			(xy 333.926563 -292.089654) (xy 333.90026 -292.048058) (xy 333.880969 -292.002782) (xy 333.869192 -291.954998)
			(xy 333.865232 -291.905944) (xy 333.53629 -291.905944) (xy 333.535795 -291.930551) (xy 333.5279 -291.979128)
			(xy 333.512316 -292.025809) (xy 333.489445 -292.069386) (xy 333.45988 -292.10873) (xy 333.424387 -292.142822)
			(xy 333.383884 -292.170778) (xy 333.339422 -292.191876) (xy 333.292151 -292.205568) (xy 333.243296 -292.2115)
			(xy 333.194121 -292.209519) (xy 333.145902 -292.199675) (xy 333.099886 -292.182223) (xy 333.057265 -292.157616)
			(xy 333.019144 -292.126491) (xy 332.986509 -292.089654) (xy 332.960206 -292.048058) (xy 332.940915 -292.002782)
			(xy 332.929138 -291.954998) (xy 332.925178 -291.905944) (xy 332.59649 -291.905944) (xy 332.595995 -291.930551)
			(xy 332.5881 -291.979128) (xy 332.572516 -292.025809) (xy 332.549645 -292.069386) (xy 332.52008 -292.10873)
			(xy 332.484587 -292.142822) (xy 332.444084 -292.170778) (xy 332.399622 -292.191876) (xy 332.352351 -292.205568)
			(xy 332.303496 -292.2115) (xy 332.254321 -292.209519) (xy 332.206102 -292.199675) (xy 332.160086 -292.182223)
			(xy 332.117465 -292.157616) (xy 332.079344 -292.126491) (xy 332.046709 -292.089654) (xy 332.020406 -292.048058)
			(xy 332.001115 -292.002782) (xy 331.989338 -291.954998) (xy 331.985378 -291.905944) (xy 331.656179 -291.905944)
			(xy 331.656177 -291.930122) (xy 331.648547 -291.977922) (xy 331.633481 -292.023922) (xy 331.611354 -292.066973)
			(xy 331.582721 -292.106001) (xy 331.548295 -292.140029) (xy 331.508938 -292.168207) (xy 331.487526 -292.179502)
			(xy 331.486764 -292.179756) (xy 331.480504 -292.183156) (xy 331.470047 -292.192819) (xy 331.46619 -292.198806)
			(xy 331.463142 -292.203886) (xy 331.459332 -292.217094) (xy 331.459332 -292.40607) (xy 331.45981 -292.41544)
			(xy 331.466661 -292.432887) (xy 331.479341 -292.44669) (xy 331.487526 -292.451282) (xy 331.518006 -292.465506)
			(xy 331.566266 -292.487858) (xy 331.56955 -292.489355) (xy 331.576432 -292.491527) (xy 331.579982 -292.492176)
			(xy 331.584357 -292.492728) (xy 331.593171 -292.49247) (xy 331.597508 -292.491668) (xy 331.605382 -292.489636)
			(xy 331.62367 -292.482778) (xy 331.63002 -292.477698) (xy 331.650501 -292.461987) (xy 331.695638 -292.436953)
			(xy 331.744339 -292.41986) (xy 331.795221 -292.411192) (xy 331.821028 -292.410642) (xy 331.846278 -292.411166)
			(xy 331.896088 -292.419482) (xy 331.94385 -292.435882) (xy 331.988261 -292.45992) (xy 332.028111 -292.49094)
			(xy 332.062311 -292.528095) (xy 332.089931 -292.570372) (xy 332.110215 -292.616619) (xy 332.122611 -292.665573)
			(xy 332.126781 -292.7159) (xy 332.126777 -292.71595) (xy 332.455278 -292.71595) (xy 332.459238 -292.666896)
			(xy 332.471015 -292.619112) (xy 332.490306 -292.573836) (xy 332.516609 -292.53224) (xy 332.549244 -292.495403)
			(xy 332.587365 -292.464278) (xy 332.629986 -292.439671) (xy 332.676002 -292.422219) (xy 332.724221 -292.412375)
			(xy 332.773396 -292.410394) (xy 332.822251 -292.416326) (xy 332.869522 -292.430018) (xy 332.913984 -292.451116)
			(xy 332.954487 -292.479072) (xy 332.98998 -292.513164) (xy 333.019545 -292.552508) (xy 333.042416 -292.596085)
			(xy 333.058 -292.642766) (xy 333.065895 -292.691343) (xy 333.06639 -292.71595) (xy 333.395332 -292.71595)
			(xy 333.399292 -292.666896) (xy 333.411069 -292.619112) (xy 333.43036 -292.573836) (xy 333.456663 -292.53224)
			(xy 333.489298 -292.495403) (xy 333.527419 -292.464278) (xy 333.57004 -292.439671) (xy 333.616056 -292.422219)
			(xy 333.664275 -292.412375) (xy 333.71345 -292.410394) (xy 333.762305 -292.416326) (xy 333.809576 -292.430018)
			(xy 333.854038 -292.451116) (xy 333.894541 -292.479072) (xy 333.930034 -292.513164) (xy 333.959599 -292.552508)
			(xy 333.98247 -292.596085) (xy 333.998054 -292.642766) (xy 334.005949 -292.691343) (xy 334.006444 -292.71595)
			(xy 335.275186 -292.71595) (xy 335.279146 -292.666896) (xy 335.290923 -292.619112) (xy 335.310214 -292.573836)
			(xy 335.336517 -292.53224) (xy 335.369152 -292.495403) (xy 335.407273 -292.464278) (xy 335.449894 -292.439671)
			(xy 335.49591 -292.422219) (xy 335.544129 -292.412375) (xy 335.593304 -292.410394) (xy 335.642159 -292.416326)
			(xy 335.68943 -292.430018) (xy 335.733892 -292.451116) (xy 335.774395 -292.479072) (xy 335.809888 -292.513164)
			(xy 335.839453 -292.552508) (xy 335.862324 -292.596085) (xy 335.877908 -292.642766) (xy 335.885803 -292.691343)
			(xy 335.886298 -292.71595) (xy 336.21524 -292.71595) (xy 336.2192 -292.666896) (xy 336.230977 -292.619112)
			(xy 336.250268 -292.573836) (xy 336.276571 -292.53224) (xy 336.309206 -292.495403) (xy 336.347327 -292.464278)
			(xy 336.389948 -292.439671) (xy 336.435964 -292.422219) (xy 336.484183 -292.412375) (xy 336.533358 -292.410394)
			(xy 336.582213 -292.416326) (xy 336.629484 -292.430018) (xy 336.673946 -292.451116) (xy 336.714449 -292.479072)
			(xy 336.749942 -292.513164) (xy 336.779507 -292.552508) (xy 336.802378 -292.596085) (xy 336.817962 -292.642766)
			(xy 336.825857 -292.691343) (xy 336.826352 -292.71595) (xy 337.155294 -292.71595) (xy 337.159254 -292.666896)
			(xy 337.171031 -292.619112) (xy 337.190322 -292.573836) (xy 337.216625 -292.53224) (xy 337.24926 -292.495403)
			(xy 337.287381 -292.464278) (xy 337.330002 -292.439671) (xy 337.376018 -292.422219) (xy 337.424237 -292.412375)
			(xy 337.473412 -292.410394) (xy 337.522267 -292.416326) (xy 337.569538 -292.430018) (xy 337.614 -292.451116)
			(xy 337.654503 -292.479072) (xy 337.689996 -292.513164) (xy 337.719561 -292.552508) (xy 337.742432 -292.596085)
			(xy 337.758016 -292.642766) (xy 337.765911 -292.691343) (xy 337.766406 -292.71595) (xy 338.095348 -292.71595)
			(xy 338.099308 -292.666896) (xy 338.111085 -292.619112) (xy 338.130376 -292.573836) (xy 338.156679 -292.53224)
			(xy 338.189314 -292.495403) (xy 338.227435 -292.464278) (xy 338.270056 -292.439671) (xy 338.316072 -292.422219)
			(xy 338.364291 -292.412375) (xy 338.413466 -292.410394) (xy 338.462321 -292.416326) (xy 338.509592 -292.430018)
			(xy 338.554054 -292.451116) (xy 338.594557 -292.479072) (xy 338.63005 -292.513164) (xy 338.659615 -292.552508)
			(xy 338.682486 -292.596085) (xy 338.69807 -292.642766) (xy 338.705965 -292.691343) (xy 338.70646 -292.71595)
			(xy 338.705965 -292.740557) (xy 338.69807 -292.789134) (xy 338.682486 -292.835815) (xy 338.659615 -292.879392)
			(xy 338.63005 -292.918736) (xy 338.594557 -292.952828) (xy 338.554054 -292.980784) (xy 338.509592 -293.001882)
			(xy 338.462321 -293.015574) (xy 338.413466 -293.021506) (xy 338.364291 -293.019525) (xy 338.316072 -293.009681)
			(xy 338.270056 -292.992229) (xy 338.227435 -292.967622) (xy 338.189314 -292.936497) (xy 338.156679 -292.89966)
			(xy 338.130376 -292.858064) (xy 338.111085 -292.812788) (xy 338.099308 -292.765004) (xy 338.095348 -292.71595)
			(xy 337.766406 -292.71595) (xy 337.765911 -292.740557) (xy 337.758016 -292.789134) (xy 337.742432 -292.835815)
			(xy 337.719561 -292.879392) (xy 337.689996 -292.918736) (xy 337.654503 -292.952828) (xy 337.614 -292.980784)
			(xy 337.569538 -293.001882) (xy 337.522267 -293.015574) (xy 337.473412 -293.021506) (xy 337.424237 -293.019525)
			(xy 337.376018 -293.009681) (xy 337.330002 -292.992229) (xy 337.287381 -292.967622) (xy 337.24926 -292.936497)
			(xy 337.216625 -292.89966) (xy 337.190322 -292.858064) (xy 337.171031 -292.812788) (xy 337.159254 -292.765004)
			(xy 337.155294 -292.71595) (xy 336.826352 -292.71595) (xy 336.825857 -292.740557) (xy 336.817962 -292.789134)
			(xy 336.802378 -292.835815) (xy 336.779507 -292.879392) (xy 336.749942 -292.918736) (xy 336.714449 -292.952828)
			(xy 336.673946 -292.980784) (xy 336.629484 -293.001882) (xy 336.582213 -293.015574) (xy 336.533358 -293.021506)
			(xy 336.484183 -293.019525) (xy 336.435964 -293.009681) (xy 336.389948 -292.992229) (xy 336.347327 -292.967622)
			(xy 336.309206 -292.936497) (xy 336.276571 -292.89966) (xy 336.250268 -292.858064) (xy 336.230977 -292.812788)
			(xy 336.2192 -292.765004) (xy 336.21524 -292.71595) (xy 335.886298 -292.71595) (xy 335.885803 -292.740557)
			(xy 335.877908 -292.789134) (xy 335.862324 -292.835815) (xy 335.839453 -292.879392) (xy 335.809888 -292.918736)
			(xy 335.774395 -292.952828) (xy 335.733892 -292.980784) (xy 335.68943 -293.001882) (xy 335.642159 -293.015574)
			(xy 335.593304 -293.021506) (xy 335.544129 -293.019525) (xy 335.49591 -293.009681) (xy 335.449894 -292.992229)
			(xy 335.407273 -292.967622) (xy 335.369152 -292.936497) (xy 335.336517 -292.89966) (xy 335.310214 -292.858064)
			(xy 335.290923 -292.812788) (xy 335.279146 -292.765004) (xy 335.275186 -292.71595) (xy 334.006444 -292.71595)
			(xy 334.005949 -292.740557) (xy 333.998054 -292.789134) (xy 333.98247 -292.835815) (xy 333.959599 -292.879392)
			(xy 333.930034 -292.918736) (xy 333.894541 -292.952828) (xy 333.854038 -292.980784) (xy 333.809576 -293.001882)
			(xy 333.762305 -293.015574) (xy 333.71345 -293.021506) (xy 333.664275 -293.019525) (xy 333.616056 -293.009681)
			(xy 333.57004 -292.992229) (xy 333.527419 -292.967622) (xy 333.489298 -292.936497) (xy 333.456663 -292.89966)
			(xy 333.43036 -292.858064) (xy 333.411069 -292.812788) (xy 333.399292 -292.765004) (xy 333.395332 -292.71595)
			(xy 333.06639 -292.71595) (xy 333.065895 -292.740557) (xy 333.058 -292.789134) (xy 333.042416 -292.835815)
			(xy 333.019545 -292.879392) (xy 332.98998 -292.918736) (xy 332.954487 -292.952828) (xy 332.913984 -292.980784)
			(xy 332.869522 -293.001882) (xy 332.822251 -293.015574) (xy 332.773396 -293.021506) (xy 332.724221 -293.019525)
			(xy 332.676002 -293.009681) (xy 332.629986 -292.992229) (xy 332.587365 -292.967622) (xy 332.549244 -292.936497)
			(xy 332.516609 -292.89966) (xy 332.490306 -292.858064) (xy 332.471015 -292.812788) (xy 332.459238 -292.765004)
			(xy 332.455278 -292.71595) (xy 332.126777 -292.71595) (xy 332.122611 -292.766227) (xy 332.110215 -292.815181)
			(xy 332.089931 -292.861428) (xy 332.062311 -292.903705) (xy 332.028111 -292.94086) (xy 331.988261 -292.97188)
			(xy 331.94385 -292.995918) (xy 331.896088 -293.012318) (xy 331.846278 -293.020634) (xy 331.821028 -293.021258)
			(xy 331.795792 -293.020742) (xy 331.746005 -293.012452) (xy 331.721968 -293.004748) (xy 331.715122 -293.002607)
			(xy 331.700807 -293.00182) (xy 331.693774 -293.003224) (xy 331.686916 -293.004748) (xy 331.67447 -293.01186)
			(xy 331.66939 -293.01694) (xy 331.661982 -293.025176) (xy 331.654409 -293.045969) (xy 331.656253 -293.068021)
			(xy 331.661262 -293.0779) (xy 331.66939 -293.088568) (xy 331.752194 -293.171372) (xy 331.757694 -293.176357)
			(xy 331.770861 -293.1832) (xy 331.778102 -293.184834) (xy 331.787754 -293.18585)
		)
		(stroke
			(width 0)
			(type solid)
		)
		(fill yes)
		(layer "In6.Cu")
		(net "PVDDIO_P0")
	)
	(gr_poly
		(pts
			(xy 427.240192 -430.901348) (xy 427.247433 -430.899715) (xy 427.260593 -430.892864) (xy 427.2661 -430.887886)
			(xy 429.211232 -428.942754) (xy 429.218606 -428.934557) (xy 429.226247 -428.913897) (xy 429.225964 -428.902876)
			(xy 429.22571 -428.901352) (xy 429.224539 -428.890595) (xy 429.22327 -428.868992) (xy 429.22317 -428.858172)
			(xy 429.223658 -428.830921) (xy 429.231417 -428.776976) (xy 429.246775 -428.724683) (xy 429.269417 -428.675108)
			(xy 429.298884 -428.629259) (xy 429.334575 -428.588071) (xy 429.375764 -428.55238) (xy 429.421613 -428.522914)
			(xy 429.471189 -428.500273) (xy 429.523481 -428.484916) (xy 429.577427 -428.477157) (xy 429.604678 -428.476664)
			(xy 429.615498 -428.476762) (xy 429.637101 -428.478034) (xy 429.647858 -428.479204) (xy 429.651668 -428.479712)
			(xy 429.659288 -428.480474) (xy 429.669702 -428.476918) (xy 429.675146 -428.474863) (xy 429.685023 -428.468714)
			(xy 429.68926 -428.464726) (xy 432.187096 -425.96689) (xy 432.193779 -425.95948) (xy 432.201358 -425.941044)
			(xy 432.201828 -425.931076) (xy 432.201828 -425.128944) (xy 432.201503 -425.120665) (xy 432.19618 -425.104988)
			(xy 432.191414 -425.09821) (xy 432.186588 -425.091606) (xy 432.172872 -425.082462) (xy 432.164998 -425.080176)
			(xy 432.134968 -425.071167) (xy 432.077218 -425.046756) (xy 432.022907 -425.01543) (xy 431.972859 -424.977665)
			(xy 431.927834 -424.934034) (xy 431.888514 -424.885198) (xy 431.855496 -424.831899) (xy 431.829282 -424.774945)
			(xy 431.810268 -424.7152) (xy 431.798743 -424.653571) (xy 431.794883 -424.590992) (xy 431.798745 -424.528414)
			(xy 431.810272 -424.466785) (xy 431.829287 -424.407041) (xy 431.855504 -424.350087) (xy 431.888523 -424.296789)
			(xy 431.927844 -424.247955) (xy 431.972871 -424.204325) (xy 432.02292 -424.166561) (xy 432.077232 -424.135237)
			(xy 432.134983 -424.110828) (xy 432.164998 -424.101768) (xy 432.172872 -424.099482) (xy 432.186588 -424.090338)
			(xy 432.191414 -424.083734) (xy 432.196162 -424.07695) (xy 432.201465 -424.061273) (xy 432.201828 -424.053)
			(xy 432.201828 -406.538938) (xy 432.201731 -406.534061) (xy 432.19994 -406.524472) (xy 432.198272 -406.519888)
			(xy 432.194462 -406.510744) (xy 430.01057 -404.326852) (xy 430.004066 -404.320766) (xy 429.987957 -404.313191)
			(xy 429.970224 -404.31163) (xy 429.961548 -404.313644) (xy 429.90389 -404.328884) (xy 429.876458 -404.33625)
			(xy 429.870062 -404.338205) (xy 429.858484 -404.344891) (xy 429.853598 -404.349458) (xy 429.849026 -404.35403)
			(xy 429.842422 -404.36546) (xy 429.840644 -404.372064) (xy 429.831458 -404.404023) (xy 429.80591 -404.465416)
			(xy 429.772577 -404.522954) (xy 429.732026 -404.575655) (xy 429.68495 -404.62262) (xy 429.632153 -404.663046)
			(xy 429.574536 -404.696244) (xy 429.513082 -404.721646) (xy 429.448842 -404.73882) (xy 429.38291 -404.747471)
			(xy 429.349662 -404.747984) (xy 429.318933 -404.747518) (xy 429.257924 -404.740105) (xy 429.198253 -404.725393)
			(xy 429.14079 -404.703596) (xy 429.086373 -404.675031) (xy 429.035797 -404.640116) (xy 428.989797 -404.599359)
			(xy 428.949046 -404.553355) (xy 428.914136 -404.502774) (xy 428.885579 -404.448354) (xy 428.863788 -404.390888)
			(xy 428.849084 -404.331215) (xy 428.841679 -404.270205) (xy 428.841154 -404.239476) (xy 428.841697 -404.206231)
			(xy 428.850364 -404.140307) (xy 428.867547 -404.076075) (xy 428.892953 -404.014629) (xy 428.92615 -403.957018)
			(xy 428.96657 -403.904223) (xy 429.013525 -403.857146) (xy 429.066213 -403.816588) (xy 429.123738 -403.783241)
			(xy 429.185117 -403.757675) (xy 429.217074 -403.748494) (xy 429.223467 -403.746534) (xy 429.235035 -403.739837)
			(xy 429.239934 -403.735286) (xy 429.244506 -403.730714) (xy 429.25111 -403.719284) (xy 429.260254 -403.685248)
			(xy 429.275494 -403.62759) (xy 429.277385 -403.618905) (xy 429.275797 -403.601214) (xy 429.268301 -403.585111)
			(xy 429.262286 -403.578568) (xy 426.905674 -401.221956) (xy 426.89526 -401.218146) (xy 426.884592 -401.214336)
			(xy 426.87367 -401.215098) (xy 426.845222 -401.216114) (xy 426.844714 -401.216114) (xy 426.81746 -401.215652)
			(xy 426.763508 -401.207896) (xy 426.711208 -401.192542) (xy 426.661625 -401.1699) (xy 426.61577 -401.140432)
			(xy 426.574575 -401.104739) (xy 426.53888 -401.063546) (xy 426.50941 -401.017692) (xy 426.486765 -400.968111)
			(xy 426.471408 -400.915812) (xy 426.46365 -400.86186) (xy 426.463206 -400.834606) (xy 426.464222 -400.807174)
			(xy 426.464222 -400.79295) (xy 426.461174 -400.784314) (xy 426.459123 -400.779082) (xy 426.453105 -400.769593)
			(xy 426.449236 -400.765518) (xy 425.07027 -399.386552) (xy 425.061573 -399.37863) (xy 425.039321 -399.371087)
			(xy 425.027598 -399.372074) (xy 424.944794 -399.388076) (xy 424.938613 -399.389541) (xy 424.927182 -399.395071)
			(xy 424.922188 -399.398998) (xy 424.921934 -399.399252) (xy 424.917459 -399.40318) (xy 424.910283 -399.412678)
			(xy 424.90771 -399.418048) (xy 424.907456 -399.418556) (xy 424.897626 -399.441623) (xy 424.874094 -399.485902)
			(xy 424.860466 -399.506948) (xy 424.855386 -399.514314) (xy 424.852727 -399.518466) (xy 424.848896 -399.527549)
			(xy 424.847766 -399.532348) (xy 424.846245 -399.54085) (xy 424.84832 -399.557985) (xy 424.85183 -399.565876)
			(xy 424.869297 -399.59158) (xy 424.898525 -399.646425) (xy 424.920843 -399.704425) (xy 424.93592 -399.764716)
			(xy 424.94353 -399.826395) (xy 424.944032 -399.857468) (xy 424.944032 -399.857976) (xy 424.943567 -399.889042)
			(xy 424.935999 -399.950712) (xy 424.920972 -400.011) (xy 424.89871 -400.069007) (xy 424.869545 -400.123869)
			(xy 424.852084 -400.149568) (xy 424.847765 -400.15758) (xy 424.844531 -400.175479) (xy 424.84775 -400.193381)
			(xy 424.852084 -400.201384) (xy 424.869524 -400.227096) (xy 424.898699 -400.281952) (xy 424.920967 -400.339956)
			(xy 424.935996 -400.400242) (xy 424.943563 -400.46191) (xy 424.944032 -400.492976) (xy 424.943569 -400.523708)
			(xy 424.936163 -400.584726) (xy 424.921457 -400.644405) (xy 424.899664 -400.701877) (xy 424.871102 -400.756303)
			(xy 424.836188 -400.806889) (xy 424.795432 -400.852898) (xy 424.749427 -400.893659) (xy 424.698844 -400.928577)
			(xy 424.644421 -400.957144) (xy 424.586951 -400.978942) (xy 424.527273 -400.993655) (xy 424.466256 -401.001066)
			(xy 424.435524 -401.001484) (xy 424.40371 -401.000993) (xy 424.34058 -400.99306) (xy 424.278932 -400.977313)
			(xy 424.219729 -400.953999) (xy 424.163898 -400.923483) (xy 424.112308 -400.886241) (xy 424.065768 -400.842854)
			(xy 424.025003 -400.794001) (xy 423.99065 -400.740444) (xy 423.976546 -400.711924) (xy 423.973252 -400.705497)
			(xy 423.963714 -400.694661) (xy 423.95775 -400.690588) (xy 423.951908 -400.686778) (xy 423.938192 -400.682968)
			(xy 423.927016 -400.682968) (xy 423.92473 -400.683222) (xy 423.882566 -400.685) (xy 423.881804 -400.685)
			(xy 423.851072 -400.684555) (xy 423.790056 -400.677146) (xy 423.730378 -400.662437) (xy 423.672908 -400.640642)
			(xy 423.618484 -400.612078) (xy 423.5679 -400.577162) (xy 423.521893 -400.536404) (xy 423.481135 -400.490397)
			(xy 423.44622 -400.439813) (xy 423.417657 -400.385389) (xy 423.395862 -400.327919) (xy 423.381153 -400.26824)
			(xy 423.373745 -400.207224) (xy 423.373296 -400.176492) (xy 423.373775 -400.145797) (xy 423.381196 -400.084856)
			(xy 423.395893 -400.025251) (xy 423.417653 -399.967846) (xy 423.446159 -399.913475) (xy 423.463212 -399.887948)
			(xy 423.46753 -399.881598) (xy 423.469562 -399.874994) (xy 423.472102 -399.862548) (xy 423.472356 -399.852134)
			(xy 423.467784 -399.836894) (xy 423.463212 -399.830036) (xy 423.446342 -399.804773) (xy 423.418072 -399.751002)
			(xy 423.396401 -399.694249) (xy 423.381634 -399.635322) (xy 423.37736 -399.605246) (xy 423.376344 -399.596864)
			(xy 423.365168 -399.574258) (xy 423.363104 -399.57023) (xy 423.357742 -399.562939) (xy 423.3545 -399.55978)
			(xy 423.34053 -399.546572) (xy 423.340022 -399.546064) (xy 423.33799 -399.544286) (xy 423.334888 -399.541595)
			(xy 423.327996 -399.53713) (xy 423.324274 -399.535396) (xy 423.316146 -399.53184) (xy 423.307002 -399.531078)
			(xy 423.282169 -399.529015) (xy 423.23349 -399.51837) (xy 423.186959 -399.500543) (xy 423.143629 -399.475938)
			(xy 423.104479 -399.445112) (xy 423.070396 -399.408763) (xy 423.042151 -399.367712) (xy 423.020383 -399.322889)
			(xy 423.005585 -399.275309) (xy 422.998091 -399.226046) (xy 422.99763 -399.201132) (xy 422.998233 -399.172537)
			(xy 423.008069 -399.116198) (xy 423.027454 -399.062393) (xy 423.055808 -399.012726) (xy 423.073576 -398.990312)
			(xy 423.074592 -398.989042) (xy 423.079164 -398.983454) (xy 423.08653 -398.963388) (xy 423.088428 -398.956553)
			(xy 423.088808 -398.942378) (xy 423.087292 -398.935448) (xy 423.087038 -398.934686) (xy 423.084244 -398.92478)
			(xy 423.080942 -398.918938) (xy 423.066209 -398.892663) (xy 423.043016 -398.837068) (xy 423.027333 -398.778906)
			(xy 423.019431 -398.719188) (xy 423.018966 -398.689068) (xy 423.018966 -398.68856) (xy 423.019518 -398.656961)
			(xy 423.028244 -398.594368) (xy 423.045483 -398.533566) (xy 423.070909 -398.475708) (xy 423.087038 -398.44853)
			(xy 423.091602 -398.440319) (xy 423.095035 -398.421866) (xy 423.091577 -398.403417) (xy 423.087038 -398.39519)
			(xy 423.070896 -398.368016) (xy 423.045431 -398.310169) (xy 423.028181 -398.249364) (xy 423.019476 -398.186762)
			(xy 423.018966 -398.15516) (xy 423.019579 -398.121917) (xy 423.029232 -398.056136) (xy 423.048301 -397.992443)
			(xy 423.076383 -397.932179) (xy 423.112889 -397.876612) (xy 423.134536 -397.851376) (xy 423.13479 -397.851122)
			(xy 423.140195 -397.844356) (xy 423.146552 -397.828259) (xy 423.147236 -397.819626) (xy 423.147236 -397.754602)
			(xy 423.146474 -397.746728) (xy 423.143934 -397.73225) (xy 423.140632 -397.723868) (xy 423.136568 -397.719042)
			(xy 423.134536 -397.716756) (xy 423.113285 -397.691929) (xy 423.077306 -397.637377) (xy 423.049448 -397.578264)
			(xy 423.030279 -397.51579) (xy 423.020188 -397.451225) (xy 423.01922 -397.41856) (xy 423.01922 -397.412718)
			(xy 423.019267 -397.401014) (xy 423.020411 -397.377635) (xy 423.021506 -397.365982) (xy 423.02176 -397.364712)
			(xy 423.022014 -397.359124) (xy 423.021499 -397.349223) (xy 423.013926 -397.330921) (xy 423.007282 -397.323564)
			(xy 422.501822 -396.818104) (xy 422.494973 -396.810707) (xy 422.487233 -396.792109) (xy 422.486836 -396.782036)
			(xy 422.486836 -396.30223) (xy 422.486738 -396.297353) (xy 422.484946 -396.287765) (xy 422.48328 -396.28318)
			(xy 422.47947 -396.274036) (xy 421.63619 -395.430756) (xy 421.630867 -395.425792) (xy 421.618103 -395.41881)
			(xy 421.611044 -395.41704) (xy 421.603678 -395.415262) (xy 421.5892 -395.416532) (xy 421.529002 -395.439138)
			(xy 421.49395 -395.452346) (xy 421.487742 -395.455206) (xy 421.477041 -395.463698) (xy 421.472868 -395.46911)
			(xy 421.468296 -395.475206) (xy 421.46347 -395.488414) (xy 421.462962 -395.496034) (xy 421.460785 -395.523281)
			(xy 421.450764 -395.577017) (xy 421.434429 -395.629182) (xy 421.423592 -395.654276) (xy 421.42156 -395.658594)
			(xy 421.418849 -395.668039) (xy 421.420037 -395.687634) (xy 421.423846 -395.696694) (xy 421.430196 -395.71041)
			(xy 421.433498 -395.714728) (xy 421.438832 -395.72184) (xy 421.460812 -395.740563) (xy 421.500362 -395.782629)
			(xy 421.534325 -395.829324) (xy 421.562162 -395.87991) (xy 421.583436 -395.933588) (xy 421.597809 -395.989509)
			(xy 421.605056 -396.046792) (xy 421.605456 -396.075662) (xy 421.604954 -396.105546) (xy 421.597159 -396.164803)
			(xy 421.581747 -396.22255) (xy 421.558979 -396.277811) (xy 421.529239 -396.329655) (xy 421.493029 -396.377205)
			(xy 421.45096 -396.41966) (xy 421.427656 -396.438374) (xy 421.423917 -396.443408) (xy 421.418781 -396.454843)
			(xy 421.417496 -396.46098) (xy 421.413686 -396.482062) (xy 421.405812 -396.52575) (xy 421.405079 -396.530293)
			(xy 421.405078 -396.539495) (xy 421.405812 -396.544038) (xy 421.407082 -396.551404) (xy 421.411654 -396.559532)
			(xy 421.424201 -396.582723) (xy 421.442 -396.632352) (xy 421.451011 -396.6843) (xy 421.451532 -396.710662)
			(xy 421.451532 -396.71117) (xy 421.45144 -396.722452) (xy 421.449787 -396.744954) (xy 421.44823 -396.756128)
			(xy 421.44696 -396.765272) (xy 421.448738 -396.773654) (xy 421.449753 -396.778009) (xy 421.453074 -396.78631)
			(xy 421.455342 -396.790164) (xy 421.45839 -396.795244) (xy 421.480996 -396.832074) (xy 421.486202 -396.839776)
			(xy 421.500922 -396.851105) (xy 421.509698 -396.854172) (xy 421.534638 -396.862203) (xy 421.581638 -396.885351)
			(xy 421.624176 -396.915936) (xy 421.661084 -396.95312) (xy 421.691352 -396.995883) (xy 421.71415 -397.043055)
			(xy 421.722042 -397.06804) (xy 421.723566 -397.073882) (xy 422.04386 -397.627602) (xy 422.047924 -397.63192)
			(xy 422.06414 -397.649619) (xy 422.091571 -397.689008) (xy 422.112716 -397.7321) (xy 422.127088 -397.777897)
			(xy 422.134354 -397.825344) (xy 422.134792 -397.849344) (xy 422.134304 -397.874119) (xy 422.12655 -397.92306)
			(xy 422.111241 -397.970187) (xy 422.088753 -398.01434) (xy 422.059639 -398.054436) (xy 422.024614 -398.089486)
			(xy 421.98454 -398.118631) (xy 421.940403 -398.141152) (xy 421.893288 -398.156496) (xy 421.844353 -398.164285)
			(xy 421.819578 -398.164812) (xy 421.81907 -398.164812) (xy 421.793678 -398.164302) (xy 421.743548 -398.156168)
			(xy 421.695368 -398.140114) (xy 421.650379 -398.116554) (xy 421.609741 -398.086096) (xy 421.574503 -398.049526)
			(xy 421.545573 -398.007787) (xy 421.523698 -397.961955) (xy 421.516048 -397.937736) (xy 421.514524 -397.931894)
			(xy 421.194484 -397.378174) (xy 421.19042 -397.373856) (xy 421.174204 -397.356158) (xy 421.146772 -397.316769)
			(xy 421.125627 -397.273677) (xy 421.111256 -397.227879) (xy 421.103992 -397.180432) (xy 421.103552 -397.156432)
			(xy 421.103689 -397.142129) (xy 421.10623 -397.113636) (xy 421.108632 -397.099536) (xy 421.11041 -397.090138)
			(xy 421.107108 -397.072104) (xy 421.075866 -397.021558) (xy 421.073437 -397.017737) (xy 421.067434 -397.01096)
			(xy 421.063928 -397.008096) (xy 421.05707 -397.002762) (xy 421.048688 -396.999968) (xy 421.026298 -396.991941)
			(xy 420.98413 -396.969942) (xy 420.945884 -396.941669) (xy 420.912486 -396.907806) (xy 420.884744 -396.869173)
			(xy 420.86333 -396.826705) (xy 420.848761 -396.78143) (xy 420.84139 -396.734443) (xy 420.840916 -396.710662)
			(xy 420.840916 -396.707106) (xy 420.841654 -396.683323) (xy 420.849583 -396.636407) (xy 420.864676 -396.591284)
			(xy 420.875206 -396.569946) (xy 420.875968 -396.568422) (xy 420.878254 -396.564104) (xy 420.881048 -396.552928)
			(xy 420.881048 -396.498064) (xy 420.880286 -396.48892) (xy 420.874952 -396.460726) (xy 420.873598 -396.454728)
			(xy 420.868467 -396.443557) (xy 420.864792 -396.438628) (xy 420.841462 -396.419915) (xy 420.799368 -396.377429)
			(xy 420.763141 -396.329842) (xy 420.733391 -396.277959) (xy 420.710622 -396.222655) (xy 420.695219 -396.164865)
			(xy 420.687441 -396.105566) (xy 420.686992 -396.075662) (xy 420.687607 -396.041218) (xy 420.697908 -395.973106)
			(xy 420.718286 -395.907302) (xy 420.732712 -395.876018) (xy 420.733833 -395.868482) (xy 420.732018 -395.853361)
			(xy 420.729156 -395.8463) (xy 420.722298 -395.831314) (xy 420.718996 -395.826996) (xy 420.709344 -395.814296)
			(xy 420.705788 -395.811248) (xy 420.681565 -395.789413) (xy 420.63894 -395.740061) (xy 420.603757 -395.685155)
			(xy 420.576732 -395.625807) (xy 420.558411 -395.563221) (xy 420.549166 -395.498668) (xy 420.548562 -395.466062)
			(xy 420.548985 -395.437766) (xy 420.55596 -395.381606) (xy 420.569799 -395.326732) (xy 420.590292 -395.273981)
			(xy 420.617125 -395.224155) (xy 420.649892 -395.178014) (xy 420.688092 -395.13626) (xy 420.709344 -395.117574)
			(xy 420.716202 -395.111732) (xy 420.734236 -395.080236) (xy 420.735506 -395.07033) (xy 420.738554 -395.04874)
			(xy 420.738554 -395.048486) (xy 420.739824 -395.039088) (xy 420.73576 -395.021562) (xy 420.734744 -395.019784)
			(xy 420.73068 -395.013688) (xy 420.715694 -394.98905) (xy 420.71059 -394.980687) (xy 420.69542 -394.968315)
			(xy 420.676718 -394.962531) (xy 420.666926 -394.962888) (xy 420.61892 -394.96492) (xy 420.583118 -394.96437)
			(xy 420.512064 -394.955514) (xy 420.442643 -394.937972) (xy 420.375911 -394.91201) (xy 420.312886 -394.878025)
			(xy 420.283386 -394.857732) (xy 420.272906 -394.851021) (xy 420.248273 -394.847673) (xy 420.236396 -394.851382)
			(xy 420.14648 -394.884148) (xy 420.129462 -394.90269) (xy 420.126414 -394.914882) (xy 420.119013 -394.94091)
			(xy 420.096933 -394.990308) (xy 420.082472 -395.01318) (xy 420.078408 -395.01953) (xy 420.07409 -395.0335)
			(xy 420.07409 -395.045438) (xy 420.074598 -395.05255) (xy 420.077138 -395.07033) (xy 420.078408 -395.080236)
			(xy 420.096442 -395.111732) (xy 420.1033 -395.117574) (xy 420.124558 -395.136255) (xy 420.162768 -395.178002)
			(xy 420.195539 -395.224141) (xy 420.222373 -395.273968) (xy 420.24286 -395.326723) (xy 420.256687 -395.381601)
			(xy 420.263643 -395.437765) (xy 420.264082 -395.466062) (xy 420.264082 -395.46657) (xy 420.263511 -395.498823)
			(xy 420.254411 -395.562686) (xy 420.236431 -395.624637) (xy 420.223696 -395.654276) (xy 420.221664 -395.658594)
			(xy 420.218952 -395.668039) (xy 420.220141 -395.687634) (xy 420.22395 -395.696694) (xy 420.2303 -395.71041)
			(xy 420.233602 -395.714728) (xy 420.238936 -395.72184) (xy 420.260916 -395.740563) (xy 420.300466 -395.78263)
			(xy 420.334428 -395.829325) (xy 420.362265 -395.87991) (xy 420.383539 -395.933588) (xy 420.397912 -395.98951)
			(xy 420.405158 -396.046792) (xy 420.40556 -396.075662) (xy 420.405058 -396.105546) (xy 420.397263 -396.164803)
			(xy 420.381851 -396.22255) (xy 420.359083 -396.277812) (xy 420.329344 -396.329655) (xy 420.293134 -396.377206)
			(xy 420.251065 -396.419661) (xy 420.22776 -396.438374) (xy 420.224021 -396.443408) (xy 420.218884 -396.454842)
			(xy 420.2176 -396.46098) (xy 420.21379 -396.482062) (xy 420.205916 -396.52575) (xy 420.205183 -396.530293)
			(xy 420.205182 -396.539495) (xy 420.205916 -396.544038) (xy 420.207186 -396.551404) (xy 420.211758 -396.559532)
			(xy 420.224305 -396.582723) (xy 420.242104 -396.632352) (xy 420.251115 -396.6843) (xy 420.251636 -396.710662)
			(xy 420.251636 -396.71117) (xy 420.251544 -396.722452) (xy 420.249891 -396.744954) (xy 420.248334 -396.756128)
			(xy 420.247064 -396.765272) (xy 420.248842 -396.773654) (xy 420.249857 -396.778009) (xy 420.253178 -396.78631)
			(xy 420.255446 -396.790164) (xy 420.258494 -396.795244) (xy 420.2811 -396.832074) (xy 420.286306 -396.839776)
			(xy 420.301027 -396.851103) (xy 420.309802 -396.854172) (xy 420.334807 -396.862226) (xy 420.381924 -396.885449)
			(xy 420.424552 -396.916144) (xy 420.461518 -396.953466) (xy 420.491802 -396.996387) (xy 420.514572 -397.043725)
			(xy 420.5224 -397.068802) (xy 420.523924 -397.074644) (xy 420.84371 -397.627602) (xy 420.847774 -397.63192)
			(xy 420.863933 -397.649589) (xy 420.891268 -397.688898) (xy 420.912346 -397.731888) (xy 420.926681 -397.777571)
			(xy 420.933945 -397.824897) (xy 420.934388 -397.848836) (xy 420.934388 -397.849344) (xy 420.933899 -397.874132)
			(xy 420.926138 -397.923097) (xy 420.910813 -397.970245) (xy 420.888303 -398.014415) (xy 420.85916 -398.054522)
			(xy 420.824103 -398.089576) (xy 420.783995 -398.118715) (xy 420.739822 -398.141222) (xy 420.692673 -398.156543)
			(xy 420.643708 -398.164301) (xy 420.61892 -398.164812) (xy 420.593525 -398.164306) (xy 420.543391 -398.156178)
			(xy 420.495204 -398.140129) (xy 420.450208 -398.116572) (xy 420.409563 -398.086116) (xy 420.374319 -398.049546)
			(xy 420.345383 -398.007805) (xy 420.323504 -397.96197) (xy 420.315898 -397.937736) (xy 420.31412 -397.931894)
			(xy 419.994588 -397.378174) (xy 419.99027 -397.373856) (xy 419.974082 -397.356146) (xy 419.94671 -397.316743)
			(xy 419.925623 -397.273647) (xy 419.911307 -397.227854) (xy 419.904094 -397.180422) (xy 419.903656 -397.156432)
			(xy 419.903793 -397.142129) (xy 419.906334 -397.113636) (xy 419.908736 -397.099536) (xy 419.910514 -397.090138)
			(xy 419.907212 -397.072104) (xy 419.87597 -397.021558) (xy 419.873541 -397.017737) (xy 419.867539 -397.01096)
			(xy 419.864032 -397.008096) (xy 419.857174 -397.002762) (xy 419.848792 -396.999968) (xy 419.826402 -396.991941)
			(xy 419.784233 -396.969942) (xy 419.745987 -396.941669) (xy 419.712589 -396.907807) (xy 419.684846 -396.869174)
			(xy 419.663431 -396.826706) (xy 419.648862 -396.78143) (xy 419.641491 -396.734443) (xy 419.64102 -396.710662)
			(xy 419.64102 -396.707106) (xy 419.641758 -396.683323) (xy 419.649687 -396.636408) (xy 419.66478 -396.591284)
			(xy 419.67531 -396.569946) (xy 419.676072 -396.568422) (xy 419.678358 -396.564104) (xy 419.681152 -396.552928)
			(xy 419.681152 -396.498064) (xy 419.68039 -396.48892) (xy 419.675056 -396.460726) (xy 419.673702 -396.454728)
			(xy 419.668572 -396.443557) (xy 419.664896 -396.438628) (xy 419.641566 -396.419915) (xy 419.599472 -396.377429)
			(xy 419.563244 -396.329843) (xy 419.533494 -396.277959) (xy 419.510725 -396.222655) (xy 419.495321 -396.164865)
			(xy 419.487543 -396.105566) (xy 419.487096 -396.075662) (xy 419.487711 -396.041218) (xy 419.498012 -395.973106)
			(xy 419.518391 -395.907302) (xy 419.532816 -395.876018) (xy 419.533937 -395.868482) (xy 419.532123 -395.853361)
			(xy 419.52926 -395.8463) (xy 419.522402 -395.831314) (xy 419.5191 -395.826996) (xy 419.509448 -395.814296)
			(xy 419.505892 -395.811248) (xy 419.481669 -395.789414) (xy 419.439043 -395.740062) (xy 419.40386 -395.685155)
			(xy 419.376834 -395.625807) (xy 419.358513 -395.563221) (xy 419.349269 -395.498668) (xy 419.348666 -395.466062)
			(xy 419.349089 -395.437766) (xy 419.356064 -395.381606) (xy 419.369903 -395.326732) (xy 419.390396 -395.273981)
			(xy 419.41723 -395.224156) (xy 419.449996 -395.178015) (xy 419.488196 -395.136261) (xy 419.509448 -395.117574)
			(xy 419.516306 -395.111732) (xy 419.53434 -395.080236) (xy 419.53561 -395.07033) (xy 419.538658 -395.04874)
			(xy 419.538658 -395.048486) (xy 419.539928 -395.039088) (xy 419.535864 -395.021562) (xy 419.534848 -395.019784)
			(xy 419.530784 -395.013688) (xy 419.515798 -394.98905) (xy 419.510694 -394.980686) (xy 419.495524 -394.968313)
			(xy 419.476822 -394.962528) (xy 419.46703 -394.962888) (xy 419.419024 -394.96492) (xy 419.383196 -394.964387)
			(xy 419.312086 -394.955555) (xy 419.242607 -394.938024) (xy 419.17582 -394.912061) (xy 419.112743 -394.878061)
			(xy 419.083236 -394.857732) (xy 419.073076 -394.850366) (xy 419.048438 -394.847064) (xy 418.946076 -394.884148)
			(xy 418.929312 -394.902436) (xy 418.926264 -394.914628) (xy 418.918864 -394.940928) (xy 418.896652 -394.990839)
			(xy 418.882068 -395.013942) (xy 418.877284 -395.021833) (xy 418.873134 -395.0398) (xy 418.87394 -395.048994)
			(xy 418.878512 -395.079982) (xy 418.8802 -395.08928) (xy 418.88946 -395.105735) (xy 418.896546 -395.111986)
			(xy 418.918619 -395.130672) (xy 418.95835 -395.1727) (xy 418.992471 -395.219398) (xy 419.020439 -395.27002)
			(xy 419.04181 -395.323762) (xy 419.056241 -395.379767) (xy 419.063505 -395.437144) (xy 419.063932 -395.466062)
			(xy 419.063347 -395.499425) (xy 419.053697 -395.56545) (xy 419.034567 -395.629375) (xy 419.021006 -395.659864)
			(xy 419.016823 -395.670298) (xy 419.016968 -395.69275) (xy 419.026662 -395.713002) (xy 419.034976 -395.72057)
			(xy 419.057225 -395.739243) (xy 419.097294 -395.781296) (xy 419.13172 -395.828082) (xy 419.15995 -395.878846)
			(xy 419.181531 -395.932775) (xy 419.196115 -395.989) (xy 419.203469 -396.046619) (xy 419.203886 -396.075662)
			(xy 419.203435 -396.104666) (xy 419.196104 -396.162208) (xy 419.181567 -396.218365) (xy 419.160057 -396.272237)
			(xy 419.131917 -396.322963) (xy 419.097599 -396.36973) (xy 419.057651 -396.41179) (xy 419.035484 -396.4305)
			(xy 419.028626 -396.436088) (xy 419.019228 -396.451582) (xy 419.005512 -396.525242) (xy 419.004344 -396.534001)
			(xy 419.007341 -396.551404) (xy 419.011354 -396.559278) (xy 419.011354 -396.559532) (xy 419.023949 -396.58271)
			(xy 419.041839 -396.63233) (xy 419.050922 -396.684289) (xy 419.051486 -396.710662) (xy 419.051414 -396.72002)
			(xy 419.050268 -396.738702) (xy 419.0492 -396.748) (xy 419.048184 -396.756636) (xy 419.051994 -396.773908)
			(xy 419.095682 -396.84325) (xy 419.109652 -396.853918) (xy 419.118034 -396.856712) (xy 419.142068 -396.865167)
			(xy 419.187247 -396.888715) (xy 419.228057 -396.919213) (xy 419.263439 -396.95587) (xy 419.292473 -396.997734)
			(xy 419.314407 -397.043718) (xy 419.321996 -397.06804) (xy 419.32352 -397.073882) (xy 419.643814 -397.627602)
			(xy 419.647878 -397.63192) (xy 419.664037 -397.649589) (xy 419.691372 -397.688898) (xy 419.712449 -397.731889)
			(xy 419.726784 -397.777571) (xy 419.734048 -397.824897) (xy 419.734492 -397.848836) (xy 419.734492 -397.849344)
			(xy 419.734003 -397.874132) (xy 419.726242 -397.923097) (xy 419.710917 -397.970245) (xy 419.688407 -398.014416)
			(xy 419.659264 -398.054523) (xy 419.624208 -398.089577) (xy 419.584099 -398.118717) (xy 419.539927 -398.141225)
			(xy 419.492778 -398.156546) (xy 419.443812 -398.164304) (xy 419.419024 -398.164812) (xy 419.393629 -398.164306)
			(xy 419.343494 -398.156179) (xy 419.295306 -398.14013) (xy 419.25031 -398.116574) (xy 419.209665 -398.086118)
			(xy 419.17442 -398.049547) (xy 419.145484 -398.007806) (xy 419.123604 -397.961971) (xy 419.116002 -397.937736)
			(xy 419.114478 -397.931894) (xy 418.794184 -397.378174) (xy 418.79012 -397.373856) (xy 418.773904 -397.356158)
			(xy 418.746472 -397.316769) (xy 418.725327 -397.273677) (xy 418.710956 -397.227879) (xy 418.703692 -397.180432)
			(xy 418.703252 -397.156432) (xy 418.70341 -397.14438) (xy 418.705319 -397.120352) (xy 418.707062 -397.108426)
			(xy 418.708332 -397.099536) (xy 418.705284 -397.082518) (xy 418.667692 -397.019272) (xy 418.663026 -397.011964)
			(xy 418.649772 -397.000802) (xy 418.641784 -396.997428) (xy 418.64153 -396.997428) (xy 418.619792 -396.98902)
			(xy 418.578954 -396.966563) (xy 418.542002 -396.938161) (xy 418.509795 -396.904474) (xy 418.483081 -396.866284)
			(xy 418.462481 -396.824479) (xy 418.448472 -396.780028) (xy 418.441381 -396.733965) (xy 418.44087 -396.710662)
			(xy 418.441452 -396.684292) (xy 418.450554 -396.632341) (xy 418.46843 -396.58272) (xy 418.481002 -396.559532)
			(xy 418.481002 -396.559278) (xy 418.485046 -396.551415) (xy 418.488037 -396.534003) (xy 418.486844 -396.525242)
			(xy 418.473128 -396.451582) (xy 418.46373 -396.436088) (xy 418.456872 -396.4305) (xy 418.434682 -396.411816)
			(xy 418.394729 -396.369757) (xy 418.36041 -396.322987) (xy 418.332274 -396.272257) (xy 418.310773 -396.218378)
			(xy 418.29625 -396.162215) (xy 418.288939 -396.104667) (xy 418.28847 -396.075662) (xy 418.28847 -396.075408)
			(xy 418.289069 -396.042087) (xy 418.29873 -395.976149) (xy 418.317849 -395.912308) (xy 418.331396 -395.88186)
			(xy 418.335585 -395.871424) (xy 418.335449 -395.848965) (xy 418.325759 -395.828704) (xy 418.317426 -395.821154)
			(xy 418.29518 -395.80248) (xy 418.255118 -395.760424) (xy 418.2207 -395.713638) (xy 418.192478 -395.662872)
			(xy 418.170906 -395.608944) (xy 418.156331 -395.55272) (xy 418.148987 -395.495103) (xy 418.148516 -395.466062)
			(xy 418.148516 -395.465808) (xy 418.148957 -395.436908) (xy 418.156235 -395.379569) (xy 418.170676 -395.323603)
			(xy 418.19205 -395.269901) (xy 418.220016 -395.219318) (xy 418.25413 -395.172659) (xy 418.293848 -395.130668)
			(xy 418.315902 -395.111986) (xy 418.32289 -395.105653) (xy 418.332145 -395.08924) (xy 418.333936 -395.079982)
			(xy 418.338508 -395.048994) (xy 418.339404 -395.039821) (xy 418.335362 -395.021854) (xy 418.330634 -395.013942)
			(xy 418.315648 -394.989304) (xy 418.310562 -394.980843) (xy 418.295331 -394.968316) (xy 418.27649 -394.96249)
			(xy 418.266626 -394.962888) (xy 418.218874 -394.96492) (xy 418.183071 -394.964373) (xy 418.112015 -394.955523)
			(xy 418.042589 -394.937987) (xy 417.975854 -394.91203) (xy 417.912824 -394.878049) (xy 417.88334 -394.857732)
			(xy 417.872859 -394.851032) (xy 417.848234 -394.847705) (xy 417.83635 -394.851382) (xy 417.746434 -394.884148)
			(xy 417.729416 -394.90269) (xy 417.726368 -394.914882) (xy 417.718941 -394.941112) (xy 417.696729 -394.990892)
			(xy 417.682172 -395.013942) (xy 417.677344 -395.02189) (xy 417.673158 -395.039993) (xy 417.674044 -395.049248)
			(xy 417.678616 -395.079982) (xy 417.680304 -395.089279) (xy 417.689565 -395.105735) (xy 417.69665 -395.111986)
			(xy 417.718723 -395.130672) (xy 417.758453 -395.172701) (xy 417.792574 -395.219398) (xy 417.820542 -395.270021)
			(xy 417.841912 -395.323762) (xy 417.856344 -395.379768) (xy 417.863607 -395.437144) (xy 417.864036 -395.466062)
			(xy 417.863451 -395.499425) (xy 417.853801 -395.56545) (xy 417.834671 -395.629375) (xy 417.82111 -395.659864)
			(xy 417.816927 -395.670298) (xy 417.817072 -395.69275) (xy 417.826766 -395.713002) (xy 417.83508 -395.72057)
			(xy 417.857329 -395.739243) (xy 417.897397 -395.781297) (xy 417.931823 -395.828082) (xy 417.960053 -395.878847)
			(xy 417.981633 -395.932775) (xy 417.996218 -395.989) (xy 418.003571 -396.046619) (xy 418.00399 -396.075662)
			(xy 418.003539 -396.104666) (xy 417.996208 -396.162209) (xy 417.981671 -396.218365) (xy 417.960161 -396.272238)
			(xy 417.932022 -396.322963) (xy 417.897704 -396.36973) (xy 417.857756 -396.411791) (xy 417.835588 -396.4305)
			(xy 417.82873 -396.436088) (xy 417.819332 -396.451582) (xy 417.805616 -396.525242) (xy 417.804448 -396.534001)
			(xy 417.807445 -396.551404) (xy 417.811458 -396.559278) (xy 417.811458 -396.559532) (xy 417.824053 -396.58271)
			(xy 417.841942 -396.63233) (xy 417.851026 -396.684289) (xy 417.85159 -396.710662) (xy 417.851518 -396.72002)
			(xy 417.850372 -396.738702) (xy 417.849304 -396.748) (xy 417.848288 -396.756636) (xy 417.852098 -396.773908)
			(xy 417.895786 -396.84325) (xy 417.909756 -396.853918) (xy 417.918138 -396.856712) (xy 417.942232 -396.865198)
			(xy 417.987514 -396.888832) (xy 418.028401 -396.919447) (xy 418.063828 -396.956244) (xy 418.092869 -396.998263)
			(xy 418.114768 -397.04441) (xy 418.122354 -397.068802) (xy 418.123878 -397.074644) (xy 418.443664 -397.627602)
			(xy 418.447728 -397.63192) (xy 418.463944 -397.649619) (xy 418.491374 -397.689009) (xy 418.512519 -397.7321)
			(xy 418.526891 -397.777898) (xy 418.534157 -397.825344) (xy 418.534596 -397.849344) (xy 418.534108 -397.874119)
			(xy 418.526354 -397.92306) (xy 418.511046 -397.970187) (xy 418.488557 -398.014341) (xy 418.459443 -398.054437)
			(xy 418.424418 -398.089488) (xy 418.384345 -398.118633) (xy 418.340207 -398.141154) (xy 418.293092 -398.156499)
			(xy 418.244157 -398.164289) (xy 418.219382 -398.164812) (xy 418.218874 -398.164812) (xy 418.193481 -398.164302)
			(xy 418.143352 -398.156168) (xy 418.095171 -398.140115) (xy 418.050181 -398.116555) (xy 418.009543 -398.086098)
			(xy 417.974304 -398.049528) (xy 417.945374 -398.007788) (xy 417.923498 -397.961956) (xy 417.915852 -397.937736)
			(xy 417.914328 -397.931894) (xy 417.59378 -397.377412) (xy 417.589716 -397.373094) (xy 417.573613 -397.355425)
			(xy 417.546375 -397.316139) (xy 417.525366 -397.273198) (xy 417.511065 -397.227583) (xy 417.5038 -397.180334)
			(xy 417.503356 -397.156432) (xy 417.503514 -397.14438) (xy 417.505423 -397.120352) (xy 417.507166 -397.108426)
			(xy 417.508436 -397.099536) (xy 417.505388 -397.082518) (xy 417.467796 -397.019272) (xy 417.46313 -397.011963)
			(xy 417.449877 -397.000801) (xy 417.441888 -396.997428) (xy 417.441634 -396.997428) (xy 417.419896 -396.98902)
			(xy 417.379057 -396.966564) (xy 417.342105 -396.938162) (xy 417.309897 -396.904475) (xy 417.283183 -396.866285)
			(xy 417.262582 -396.824479) (xy 417.248573 -396.780028) (xy 417.241482 -396.733965) (xy 417.240974 -396.710662)
			(xy 417.241556 -396.684292) (xy 417.250658 -396.632341) (xy 417.268535 -396.582721) (xy 417.281106 -396.559532)
			(xy 417.281106 -396.559278) (xy 417.28515 -396.551415) (xy 417.28814 -396.534003) (xy 417.286948 -396.525242)
			(xy 417.273232 -396.451582) (xy 417.263834 -396.436088) (xy 417.256976 -396.4305) (xy 417.234786 -396.411816)
			(xy 417.194833 -396.369757) (xy 417.160513 -396.322987) (xy 417.132377 -396.272257) (xy 417.110875 -396.218378)
			(xy 417.096353 -396.162215) (xy 417.089041 -396.104667) (xy 417.088574 -396.075662) (xy 417.088574 -396.075408)
			(xy 417.089173 -396.042087) (xy 417.098832 -395.976148) (xy 417.117947 -395.912306) (xy 417.1315 -395.88186)
			(xy 417.135689 -395.871424) (xy 417.135552 -395.848965) (xy 417.125863 -395.828703) (xy 417.11753 -395.821154)
			(xy 417.095284 -395.80248) (xy 417.055222 -395.760425) (xy 417.020803 -395.713638) (xy 416.992581 -395.662873)
			(xy 416.971009 -395.608944) (xy 416.956434 -395.55272) (xy 416.949089 -395.495103) (xy 416.94862 -395.466062)
			(xy 416.94862 -395.465808) (xy 416.949061 -395.436908) (xy 416.956339 -395.379569) (xy 416.97078 -395.323603)
			(xy 416.992154 -395.269901) (xy 417.020121 -395.219318) (xy 417.054235 -395.17266) (xy 417.093953 -395.130669)
			(xy 417.116006 -395.111986) (xy 417.122994 -395.105653) (xy 417.132248 -395.08924) (xy 417.13404 -395.079982)
			(xy 417.138612 -395.048994) (xy 417.139507 -395.039821) (xy 417.135466 -395.021854) (xy 417.130738 -395.013942)
			(xy 417.115752 -394.989304) (xy 417.110667 -394.980843) (xy 417.095435 -394.968314) (xy 417.076594 -394.962487)
			(xy 417.06673 -394.962888) (xy 417.018978 -394.96492) (xy 416.983151 -394.964384) (xy 416.912043 -394.955547)
			(xy 416.842567 -394.938011) (xy 416.775783 -394.912044) (xy 416.712711 -394.878041) (xy 416.68319 -394.857732)
			(xy 416.67303 -394.850366) (xy 416.648392 -394.847064) (xy 416.54603 -394.884148) (xy 416.529266 -394.902436)
			(xy 416.526218 -394.914628) (xy 416.518819 -394.940928) (xy 416.49661 -394.990841) (xy 416.482022 -395.013942)
			(xy 416.477234 -395.021832) (xy 416.47308 -395.0398) (xy 416.473894 -395.048994) (xy 416.478466 -395.079982)
			(xy 416.480156 -395.089278) (xy 416.489423 -395.105726) (xy 416.4965 -395.111986) (xy 416.518575 -395.130671)
			(xy 416.55831 -395.172698) (xy 416.592434 -395.219394) (xy 416.620405 -395.270017) (xy 416.641778 -395.323759)
			(xy 416.656211 -395.379765) (xy 416.663475 -395.437144) (xy 416.663886 -395.466062) (xy 416.6633 -395.499425)
			(xy 416.65365 -395.56545) (xy 416.634518 -395.629374) (xy 416.62096 -395.659864) (xy 416.616779 -395.670299)
			(xy 416.616925 -395.692752) (xy 416.626612 -395.713007) (xy 416.63493 -395.72057) (xy 416.657177 -395.739244)
			(xy 416.697241 -395.7813) (xy 416.731663 -395.828086) (xy 416.75989 -395.878851) (xy 416.781468 -395.932778)
			(xy 416.79605 -395.989003) (xy 416.803403 -396.04662) (xy 416.80384 -396.075662) (xy 416.803389 -396.104666)
			(xy 416.796059 -396.16221) (xy 416.781523 -396.218368) (xy 416.760015 -396.272241) (xy 416.731877 -396.322969)
			(xy 416.697562 -396.369739) (xy 416.657617 -396.411803) (xy 416.635438 -396.4305) (xy 416.62858 -396.436088)
			(xy 416.619182 -396.451582) (xy 416.605466 -396.525242) (xy 416.604298 -396.534001) (xy 416.607297 -396.551403)
			(xy 416.611308 -396.559278) (xy 416.611308 -396.559532) (xy 416.623901 -396.582711) (xy 416.641787 -396.632331)
			(xy 416.650869 -396.684289) (xy 416.65144 -396.710662) (xy 416.651368 -396.72002) (xy 416.650222 -396.738702)
			(xy 416.649154 -396.748) (xy 416.648138 -396.756636) (xy 416.651948 -396.773908) (xy 416.695636 -396.84325)
			(xy 416.709606 -396.853918) (xy 416.717988 -396.856712) (xy 416.742025 -396.865164) (xy 416.787209 -396.888708)
			(xy 416.828024 -396.919204) (xy 416.863411 -396.95586) (xy 416.892451 -396.997724) (xy 416.914388 -397.043709)
			(xy 416.92195 -397.06804) (xy 416.923474 -397.073882) (xy 417.243768 -397.627602) (xy 417.247832 -397.63192)
			(xy 417.264047 -397.649619) (xy 417.291477 -397.689009) (xy 417.312622 -397.7321) (xy 417.326994 -397.777898)
			(xy 417.33426 -397.825344) (xy 417.3347 -397.849344) (xy 417.334212 -397.87412) (xy 417.326459 -397.923061)
			(xy 417.31115 -397.970188) (xy 417.288661 -398.014342) (xy 417.259547 -398.054438) (xy 417.224522 -398.08949)
			(xy 417.184449 -398.118635) (xy 417.140312 -398.141157) (xy 417.093196 -398.156502) (xy 417.044261 -398.164293)
			(xy 417.019486 -398.164812) (xy 417.018978 -398.164812) (xy 416.993585 -398.164303) (xy 416.943455 -398.156169)
			(xy 416.895274 -398.140116) (xy 416.850283 -398.116557) (xy 416.809644 -398.0861) (xy 416.774405 -398.049529)
			(xy 416.745475 -398.00779) (xy 416.723599 -397.961957) (xy 416.715956 -397.937736) (xy 416.714432 -397.931894)
			(xy 416.394138 -397.378174) (xy 416.390074 -397.373856) (xy 416.373886 -397.356146) (xy 416.346513 -397.316743)
			(xy 416.325426 -397.273647) (xy 416.31111 -397.227855) (xy 416.303897 -397.180422) (xy 416.30346 -397.156432)
			(xy 416.303546 -397.144384) (xy 416.305329 -397.120355) (xy 416.307016 -397.108426) (xy 416.307969 -397.099669)
			(xy 416.304599 -397.082393) (xy 416.300412 -397.074644) (xy 416.267646 -397.019272) (xy 416.262983 -397.011959)
			(xy 416.249735 -397.000784) (xy 416.241738 -396.997428) (xy 416.241484 -396.997428) (xy 416.219743 -396.989023)
			(xy 416.178899 -396.96657) (xy 416.14194 -396.938171) (xy 416.109728 -396.904485) (xy 416.083008 -396.866294)
			(xy 416.062404 -396.824486) (xy 416.048392 -396.780033) (xy 416.041299 -396.733967) (xy 416.040824 -396.710662)
			(xy 416.041406 -396.684291) (xy 416.050507 -396.63234) (xy 416.068381 -396.582718) (xy 416.080956 -396.559532)
			(xy 416.080956 -396.559278) (xy 416.085003 -396.551416) (xy 416.087997 -396.534003) (xy 416.086798 -396.525242)
			(xy 416.073082 -396.451582) (xy 416.063684 -396.436088) (xy 416.056826 -396.4305) (xy 416.034638 -396.411815)
			(xy 415.994689 -396.369754) (xy 415.960373 -396.322983) (xy 415.93224 -396.272253) (xy 415.910741 -396.218375)
			(xy 415.89622 -396.162213) (xy 415.88891 -396.104667) (xy 415.888424 -396.075662) (xy 415.888424 -396.075408)
			(xy 415.889023 -396.042087) (xy 415.898683 -395.976149) (xy 415.9178 -395.912307) (xy 415.93135 -395.88186)
			(xy 415.935536 -395.871423) (xy 415.935399 -395.848964) (xy 415.925717 -395.828698) (xy 415.91738 -395.821154)
			(xy 415.895136 -395.802479) (xy 415.855078 -395.760422) (xy 415.820663 -395.713634) (xy 415.792444 -395.662869)
			(xy 415.770875 -395.608941) (xy 415.756301 -395.552718) (xy 415.748958 -395.495103) (xy 415.74847 -395.466062)
			(xy 415.74847 -395.465808) (xy 415.748911 -395.436908) (xy 415.756188 -395.379568) (xy 415.770628 -395.323601)
			(xy 415.792 -395.269897) (xy 415.819965 -395.219312) (xy 415.854077 -395.172651) (xy 415.893793 -395.130657)
			(xy 415.915856 -395.111986) (xy 415.922849 -395.105656) (xy 415.932112 -395.089244) (xy 415.93389 -395.079982)
			(xy 415.938462 -395.048994) (xy 415.939357 -395.039821) (xy 415.935313 -395.021856) (xy 415.930588 -395.013942)
			(xy 415.915602 -394.989304) (xy 415.910515 -394.980849) (xy 415.895282 -394.968335) (xy 415.876444 -394.962526)
			(xy 415.86658 -394.962888) (xy 415.819082 -394.96492) (xy 415.783255 -394.964384) (xy 415.712147 -394.955548)
			(xy 415.642671 -394.938013) (xy 415.575887 -394.912045) (xy 415.512813 -394.878042) (xy 415.483294 -394.857732)
			(xy 415.473134 -394.850366) (xy 415.448496 -394.847064) (xy 415.346134 -394.884148) (xy 415.32937 -394.902436)
			(xy 415.326322 -394.914628) (xy 415.318921 -394.940927) (xy 415.296706 -394.990837) (xy 415.282126 -395.013942)
			(xy 415.277345 -395.021834) (xy 415.273199 -395.0398) (xy 415.273998 -395.048994) (xy 415.27857 -395.079982)
			(xy 415.28026 -395.089278) (xy 415.289528 -395.105725) (xy 415.296604 -395.111986) (xy 415.318679 -395.130671)
			(xy 415.358413 -395.172698) (xy 415.392537 -395.219394) (xy 415.420508 -395.270017) (xy 415.441881 -395.323759)
			(xy 415.456314 -395.379766) (xy 415.463578 -395.437144) (xy 415.46399 -395.466062) (xy 415.463404 -395.499425)
			(xy 415.453754 -395.56545) (xy 415.434622 -395.629374) (xy 415.421064 -395.659864) (xy 415.416883 -395.670299)
			(xy 415.417029 -395.692752) (xy 415.426716 -395.713007) (xy 415.435034 -395.72057) (xy 415.457281 -395.739244)
			(xy 415.497345 -395.7813) (xy 415.531766 -395.828086) (xy 415.559993 -395.878851) (xy 415.58157 -395.932779)
			(xy 415.596153 -395.989003) (xy 415.603505 -396.04662) (xy 415.603944 -396.075662) (xy 415.603493 -396.104666)
			(xy 415.596163 -396.16221) (xy 415.581627 -396.218368) (xy 415.560119 -396.272242) (xy 415.531982 -396.32297)
			(xy 415.497666 -396.36974) (xy 415.457721 -396.411804) (xy 415.435542 -396.4305) (xy 415.428684 -396.436088)
			(xy 415.419286 -396.451582) (xy 415.40557 -396.525242) (xy 415.404402 -396.534001) (xy 415.407401 -396.551403)
			(xy 415.411412 -396.559278) (xy 415.411412 -396.559532) (xy 415.424005 -396.582711) (xy 415.441891 -396.632331)
			(xy 415.450973 -396.684289) (xy 415.451544 -396.710662) (xy 415.451472 -396.72002) (xy 415.450326 -396.738702)
			(xy 415.449258 -396.748) (xy 415.448242 -396.756636) (xy 415.452052 -396.773908) (xy 415.49574 -396.84325)
			(xy 415.50971 -396.853918) (xy 415.518092 -396.856712) (xy 415.542129 -396.865165) (xy 415.587312 -396.888708)
			(xy 415.628127 -396.919204) (xy 415.663514 -396.955861) (xy 415.692553 -396.997725) (xy 415.71449 -397.04371)
			(xy 415.722054 -397.06804) (xy 415.723578 -397.073882) (xy 416.043872 -397.627602) (xy 416.047936 -397.63192)
			(xy 416.064151 -397.649619) (xy 416.091581 -397.689009) (xy 416.112726 -397.7321) (xy 416.127097 -397.777898)
			(xy 416.134363 -397.825344) (xy 416.134804 -397.849344) (xy 416.134316 -397.87412) (xy 416.126563 -397.923061)
			(xy 416.111254 -397.970188) (xy 416.088766 -398.014343) (xy 416.059651 -398.054439) (xy 416.024627 -398.089491)
			(xy 415.984553 -398.118637) (xy 415.940416 -398.141159) (xy 415.8933 -398.156505) (xy 415.844365 -398.164296)
			(xy 415.81959 -398.164812) (xy 415.819082 -398.164812) (xy 415.793689 -398.164303) (xy 415.743559 -398.15617)
			(xy 415.695376 -398.140117) (xy 415.650386 -398.116558) (xy 415.609746 -398.086101) (xy 415.574506 -398.049531)
			(xy 415.545575 -398.007791) (xy 415.523699 -397.961958) (xy 415.51606 -397.937736) (xy 415.514536 -397.931894)
			(xy 415.194242 -397.378174) (xy 415.190178 -397.373856) (xy 415.17399 -397.356146) (xy 415.146617 -397.316743)
			(xy 415.125529 -397.273647) (xy 415.111213 -397.227855) (xy 415.104 -397.180422) (xy 415.103564 -397.156432)
			(xy 415.10365 -397.144384) (xy 415.105433 -397.120355) (xy 415.10712 -397.108426) (xy 415.108073 -397.099669)
			(xy 415.104704 -397.082393) (xy 415.100516 -397.074644) (xy 415.06775 -397.019272) (xy 415.063088 -397.011958)
			(xy 415.04984 -397.000783) (xy 415.041842 -396.997428) (xy 415.041588 -396.997428) (xy 415.019847 -396.989023)
			(xy 414.979002 -396.966571) (xy 414.942043 -396.938171) (xy 414.90983 -396.904485) (xy 414.88311 -396.866295)
			(xy 414.862505 -396.824487) (xy 414.848494 -396.780033) (xy 414.841401 -396.733967) (xy 414.840928 -396.710662)
			(xy 414.84151 -396.684291) (xy 414.850611 -396.63234) (xy 414.868485 -396.582719) (xy 414.88106 -396.559532)
			(xy 414.88106 -396.559278) (xy 414.885107 -396.551416) (xy 414.8881 -396.534003) (xy 414.886902 -396.525242)
			(xy 414.873186 -396.451582) (xy 414.863788 -396.436088) (xy 414.85693 -396.4305) (xy 414.834742 -396.411815)
			(xy 414.794792 -396.369754) (xy 414.760476 -396.322984) (xy 414.732343 -396.272253) (xy 414.710844 -396.218375)
			(xy 414.696323 -396.162213) (xy 414.689012 -396.104667) (xy 414.688528 -396.075662) (xy 414.688528 -396.075408)
			(xy 414.689127 -396.042087) (xy 414.698787 -395.976149) (xy 414.717904 -395.912307) (xy 414.731454 -395.88186)
			(xy 414.73564 -395.871423) (xy 414.735503 -395.848964) (xy 414.725822 -395.828698) (xy 414.717484 -395.821154)
			(xy 414.69524 -395.802479) (xy 414.655182 -395.760422) (xy 414.620767 -395.713634) (xy 414.592547 -395.662869)
			(xy 414.570977 -395.608941) (xy 414.556404 -395.552718) (xy 414.54906 -395.495103) (xy 414.548574 -395.466062)
			(xy 414.548574 -395.465808) (xy 414.549015 -395.436908) (xy 414.556292 -395.379568) (xy 414.570732 -395.323601)
			(xy 414.592105 -395.269897) (xy 414.620069 -395.219313) (xy 414.654181 -395.172652) (xy 414.693897 -395.130658)
			(xy 414.71596 -395.111986) (xy 414.722952 -395.105656) (xy 414.732215 -395.089244) (xy 414.733994 -395.079982)
			(xy 414.738566 -395.048994) (xy 414.739461 -395.039821) (xy 414.735417 -395.021856) (xy 414.730692 -395.013942)
			(xy 414.715706 -394.989304) (xy 414.710619 -394.980848) (xy 414.695386 -394.968334) (xy 414.676548 -394.962523)
			(xy 414.666684 -394.962888) (xy 414.618932 -394.96492) (xy 414.583104 -394.964387) (xy 414.511993 -394.955557)
			(xy 414.442514 -394.938026) (xy 414.375726 -394.912063) (xy 414.312649 -394.878064) (xy 414.283144 -394.857732)
			(xy 414.272984 -394.850366) (xy 414.248346 -394.847064) (xy 414.145984 -394.884148) (xy 414.12922 -394.902436)
			(xy 414.126172 -394.914628) (xy 414.118772 -394.940928) (xy 414.09656 -394.990839) (xy 414.081976 -395.013942)
			(xy 414.077191 -395.021833) (xy 414.073041 -395.0398) (xy 414.073848 -395.048994) (xy 414.07842 -395.079982)
			(xy 414.080108 -395.089279) (xy 414.08937 -395.105734) (xy 414.096454 -395.111986) (xy 414.118527 -395.130673)
			(xy 414.158257 -395.172701) (xy 414.192377 -395.219398) (xy 414.220345 -395.270021) (xy 414.241715 -395.323763)
			(xy 414.256146 -395.379768) (xy 414.26341 -395.437145) (xy 414.26384 -395.466062) (xy 414.263255 -395.499425)
			(xy 414.253605 -395.56545) (xy 414.234475 -395.629376) (xy 414.220914 -395.659864) (xy 414.21673 -395.670298)
			(xy 414.216875 -395.69275) (xy 414.22657 -395.713001) (xy 414.234884 -395.72057) (xy 414.257133 -395.739243)
			(xy 414.297201 -395.781297) (xy 414.331626 -395.828082) (xy 414.359856 -395.878847) (xy 414.381436 -395.932775)
			(xy 414.39602 -395.989001) (xy 414.403374 -396.046619) (xy 414.403794 -396.075662) (xy 414.403343 -396.104666)
			(xy 414.396012 -396.162209) (xy 414.381476 -396.218366) (xy 414.359965 -396.272238) (xy 414.331826 -396.322964)
			(xy 414.297508 -396.369731) (xy 414.257561 -396.411792) (xy 414.235392 -396.4305) (xy 414.228534 -396.436088)
			(xy 414.219136 -396.451582) (xy 414.20542 -396.525242) (xy 414.204252 -396.534001) (xy 414.207249 -396.551404)
			(xy 414.211262 -396.559278) (xy 414.211262 -396.559532) (xy 414.223857 -396.58271) (xy 414.241746 -396.63233)
			(xy 414.250829 -396.684289) (xy 414.251394 -396.710662) (xy 414.251322 -396.72002) (xy 414.250176 -396.738702)
			(xy 414.249108 -396.748) (xy 414.248092 -396.756636) (xy 414.251902 -396.773908) (xy 414.29559 -396.84325)
			(xy 414.30956 -396.853918) (xy 414.317942 -396.856712) (xy 414.341976 -396.865168) (xy 414.387154 -396.888716)
			(xy 414.427963 -396.919215) (xy 414.463344 -396.955872) (xy 414.492377 -396.997736) (xy 414.51431 -397.04372)
			(xy 414.521904 -397.06804) (xy 414.523428 -397.073882) (xy 414.843722 -397.627602) (xy 414.847786 -397.63192)
			(xy 414.863945 -397.649589) (xy 414.891279 -397.688899) (xy 414.912356 -397.731889) (xy 414.92669 -397.777572)
			(xy 414.933954 -397.824897) (xy 414.9344 -397.848836) (xy 414.9344 -397.849344) (xy 414.933911 -397.874132)
			(xy 414.92615 -397.923098) (xy 414.910825 -397.970247) (xy 414.888315 -398.014418) (xy 414.859173 -398.054525)
			(xy 414.824116 -398.089581) (xy 414.784008 -398.118721) (xy 414.739835 -398.14123) (xy 414.692686 -398.156552)
			(xy 414.64372 -398.164312) (xy 414.618932 -398.164812) (xy 414.593537 -398.164307) (xy 414.543401 -398.15618)
			(xy 414.495212 -398.140132) (xy 414.450215 -398.116577) (xy 414.409568 -398.086121) (xy 414.374323 -398.049551)
			(xy 414.345386 -398.007809) (xy 414.323505 -397.961974) (xy 414.31591 -397.937736) (xy 414.314386 -397.931894)
			(xy 413.994092 -397.378174) (xy 413.990028 -397.373856) (xy 413.973811 -397.356158) (xy 413.946379 -397.316769)
			(xy 413.925233 -397.273678) (xy 413.910862 -397.227879) (xy 413.903598 -397.180432) (xy 413.90316 -397.156432)
			(xy 413.903318 -397.14438) (xy 413.905227 -397.120352) (xy 413.90697 -397.108426) (xy 413.90824 -397.099536)
			(xy 413.905192 -397.082518) (xy 413.8676 -397.019272) (xy 413.862934 -397.011963) (xy 413.849682 -397.0008)
			(xy 413.841692 -396.997428) (xy 413.841438 -396.997428) (xy 413.8197 -396.98902) (xy 413.77886 -396.966564)
			(xy 413.741908 -396.938163) (xy 413.7097 -396.904476) (xy 413.682985 -396.866286) (xy 413.662384 -396.82448)
			(xy 413.648375 -396.780029) (xy 413.641283 -396.733965) (xy 413.640778 -396.710662) (xy 413.64136 -396.684292)
			(xy 413.650462 -396.632341) (xy 413.668339 -396.582721) (xy 413.68091 -396.559532) (xy 413.68091 -396.559278)
			(xy 413.684954 -396.551415) (xy 413.687944 -396.534003) (xy 413.686752 -396.525242) (xy 413.673036 -396.451582)
			(xy 413.663638 -396.436088) (xy 413.65678 -396.4305) (xy 413.634589 -396.411816) (xy 413.594636 -396.369757)
			(xy 413.560316 -396.322988) (xy 413.53218 -396.272257) (xy 413.510678 -396.218379) (xy 413.496155 -396.162215)
			(xy 413.488844 -396.104667) (xy 413.488378 -396.075662) (xy 413.488378 -396.075408) (xy 413.488977 -396.042087)
			(xy 413.498636 -395.976148) (xy 413.517751 -395.912306) (xy 413.531304 -395.88186) (xy 413.535492 -395.871424)
			(xy 413.535356 -395.848965) (xy 413.525668 -395.828703) (xy 413.517334 -395.821154) (xy 413.495088 -395.80248)
			(xy 413.455025 -395.760425) (xy 413.420607 -395.713638) (xy 413.392384 -395.662873) (xy 413.370812 -395.608945)
			(xy 413.356236 -395.55272) (xy 413.348892 -395.495104) (xy 413.348424 -395.466062) (xy 413.348424 -395.465808)
			(xy 413.348865 -395.436908) (xy 413.356143 -395.379569) (xy 413.370584 -395.323603) (xy 413.391958 -395.269901)
			(xy 413.419925 -395.219319) (xy 413.454039 -395.172661) (xy 413.493758 -395.13067) (xy 413.51581 -395.111986)
			(xy 413.522797 -395.105653) (xy 413.532051 -395.08924) (xy 413.533844 -395.079982) (xy 413.538416 -395.048994)
			(xy 413.539311 -395.039821) (xy 413.535271 -395.021854) (xy 413.530542 -395.013942) (xy 413.515556 -394.989304)
			(xy 413.510471 -394.980842) (xy 413.49524 -394.968312) (xy 413.476398 -394.962484) (xy 413.466534 -394.962888)
			(xy 413.419036 -394.96492) (xy 413.383208 -394.964388) (xy 413.312097 -394.955558) (xy 413.242617 -394.938027)
			(xy 413.175829 -394.912065) (xy 413.112752 -394.878066) (xy 413.083248 -394.857732) (xy 413.073088 -394.850366)
			(xy 413.04845 -394.847064) (xy 412.946088 -394.884148) (xy 412.929324 -394.902436) (xy 412.926276 -394.914628)
			(xy 412.918876 -394.940928) (xy 412.896665 -394.990839) (xy 412.88208 -395.013942) (xy 412.877295 -395.021833)
			(xy 412.873144 -395.0398) (xy 412.873952 -395.048994) (xy 412.878524 -395.079982) (xy 412.880213 -395.089279)
			(xy 412.889475 -395.105733) (xy 412.896558 -395.111986) (xy 412.918631 -395.130673) (xy 412.95836 -395.172701)
			(xy 412.992481 -395.219399) (xy 413.020448 -395.270021) (xy 413.041818 -395.323763) (xy 413.056249 -395.379768)
			(xy 413.063512 -395.437145) (xy 413.063944 -395.466062) (xy 413.063359 -395.499425) (xy 413.053709 -395.56545)
			(xy 413.03458 -395.629376) (xy 413.021018 -395.659864) (xy 413.016834 -395.670298) (xy 413.016979 -395.69275)
			(xy 413.026675 -395.713001) (xy 413.034988 -395.72057) (xy 413.057237 -395.739243) (xy 413.097304 -395.781297)
			(xy 413.131729 -395.828083) (xy 413.159959 -395.878847) (xy 413.181539 -395.932776) (xy 413.196123 -395.989001)
			(xy 413.203476 -396.046619) (xy 413.203898 -396.075662) (xy 413.203447 -396.104666) (xy 413.196116 -396.162209)
			(xy 413.18158 -396.218366) (xy 413.16007 -396.272238) (xy 413.131931 -396.322964) (xy 413.097613 -396.369732)
			(xy 413.057666 -396.411793) (xy 413.035496 -396.4305) (xy 413.028638 -396.436088) (xy 413.01924 -396.451582)
			(xy 413.005524 -396.525242) (xy 413.004356 -396.534001) (xy 413.007353 -396.551404) (xy 413.011366 -396.559278)
			(xy 413.011366 -396.559532) (xy 413.023961 -396.58271) (xy 413.041849 -396.63233) (xy 413.050933 -396.684289)
			(xy 413.051498 -396.710662) (xy 413.051426 -396.72002) (xy 413.05028 -396.738702) (xy 413.049212 -396.748)
			(xy 413.048196 -396.756636) (xy 413.052006 -396.773908) (xy 413.095694 -396.84325) (xy 413.109664 -396.853918)
			(xy 413.118046 -396.856712) (xy 413.14208 -396.865168) (xy 413.187257 -396.888717) (xy 413.228066 -396.919216)
			(xy 413.263446 -396.955873) (xy 413.292479 -396.997737) (xy 413.314412 -397.043721) (xy 413.322008 -397.06804)
			(xy 413.323532 -397.073882) (xy 413.643826 -397.627602) (xy 413.64789 -397.63192) (xy 413.664049 -397.649589)
			(xy 413.691382 -397.688899) (xy 413.712459 -397.731889) (xy 413.726793 -397.777572) (xy 413.734057 -397.824897)
			(xy 413.734504 -397.848836) (xy 413.734504 -397.849344) (xy 413.734015 -397.874132) (xy 413.726254 -397.923098)
			(xy 413.710929 -397.970247) (xy 413.688419 -398.014419) (xy 413.659277 -398.054526) (xy 413.62422 -398.089582)
			(xy 413.584112 -398.118723) (xy 413.53994 -398.141232) (xy 413.49279 -398.156556) (xy 413.443824 -398.164315)
			(xy 413.419036 -398.164812) (xy 413.393641 -398.164307) (xy 413.343504 -398.156181) (xy 413.295315 -398.140134)
			(xy 413.250317 -398.116578) (xy 413.20967 -398.086122) (xy 413.174424 -398.049552) (xy 413.145487 -398.007811)
			(xy 413.123606 -397.961975) (xy 413.116014 -397.937736) (xy 413.11449 -397.931894) (xy 412.794196 -397.378174)
			(xy 412.790132 -397.373856) (xy 412.773915 -397.356158) (xy 412.746483 -397.316769) (xy 412.725337 -397.273678)
			(xy 412.710965 -397.22788) (xy 412.703701 -397.180432) (xy 412.703264 -397.156432) (xy 412.703422 -397.14438)
			(xy 412.705331 -397.120352) (xy 412.707074 -397.108426) (xy 412.708344 -397.099536) (xy 412.705296 -397.082518)
			(xy 412.667704 -397.019272) (xy 412.663039 -397.011963) (xy 412.649786 -397.000799) (xy 412.641796 -396.997428)
			(xy 412.641542 -396.997428) (xy 412.619804 -396.98902) (xy 412.578964 -396.966565) (xy 412.542011 -396.938163)
			(xy 412.509802 -396.904476) (xy 412.483087 -396.866286) (xy 412.462486 -396.82448) (xy 412.448476 -396.780029)
			(xy 412.441385 -396.733965) (xy 412.440882 -396.710662) (xy 412.441464 -396.684292) (xy 412.450566 -396.632341)
			(xy 412.468443 -396.582721) (xy 412.481014 -396.559532) (xy 412.481014 -396.559278) (xy 412.485057 -396.551415)
			(xy 412.488047 -396.534003) (xy 412.486856 -396.525242) (xy 412.47314 -396.451582) (xy 412.463742 -396.436088)
			(xy 412.456884 -396.4305) (xy 412.434693 -396.411816) (xy 412.39474 -396.369757) (xy 412.36042 -396.322988)
			(xy 412.332283 -396.272258) (xy 412.310781 -396.218379) (xy 412.296258 -396.162216) (xy 412.288946 -396.104667)
			(xy 412.288482 -396.075662) (xy 412.288482 -396.075408) (xy 412.289081 -396.042087) (xy 412.29874 -395.976148)
			(xy 412.317855 -395.912306) (xy 412.331408 -395.88186) (xy 412.335596 -395.871424) (xy 412.33546 -395.848965)
			(xy 412.325772 -395.828703) (xy 412.317438 -395.821154) (xy 412.295191 -395.80248) (xy 412.255129 -395.760425)
			(xy 412.22071 -395.713639) (xy 412.192487 -395.662873) (xy 412.170914 -395.608945) (xy 412.156339 -395.55272)
			(xy 412.148994 -395.495104) (xy 412.148528 -395.466062) (xy 412.148528 -395.465808) (xy 412.148969 -395.436908)
			(xy 412.156247 -395.379569) (xy 412.170688 -395.323603) (xy 412.192062 -395.269901) (xy 412.220029 -395.219319)
			(xy 412.254144 -395.172661) (xy 412.293863 -395.130671) (xy 412.315914 -395.111986) (xy 412.322901 -395.105653)
			(xy 412.332154 -395.089239) (xy 412.333948 -395.079982) (xy 412.33852 -395.048994) (xy 412.339415 -395.039821)
			(xy 412.335375 -395.021853) (xy 412.330646 -395.013942) (xy 412.31566 -394.989304) (xy 412.310575 -394.980841)
			(xy 412.295344 -394.96831) (xy 412.276502 -394.96248) (xy 412.266638 -394.962888) (xy 412.218886 -394.96492)
			(xy 412.183083 -394.964374) (xy 412.112026 -394.955525) (xy 412.0426 -394.93799) (xy 411.975863 -394.912034)
			(xy 411.912833 -394.878054) (xy 411.883352 -394.857732) (xy 411.872871 -394.851029) (xy 411.848244 -394.847697)
			(xy 411.836362 -394.851382) (xy 411.746446 -394.884148) (xy 411.729428 -394.90269) (xy 411.72638 -394.914882)
			(xy 411.718953 -394.941112) (xy 411.696742 -394.990893) (xy 411.682184 -395.013942) (xy 411.677355 -395.021889)
			(xy 411.673168 -395.039993) (xy 411.674056 -395.049248) (xy 411.678628 -395.079982) (xy 411.680317 -395.089279)
			(xy 411.689579 -395.105732) (xy 411.696662 -395.111986) (xy 411.718735 -395.130673) (xy 411.758464 -395.172701)
			(xy 411.792584 -395.219399) (xy 411.820551 -395.270021) (xy 411.841921 -395.323763) (xy 411.856352 -395.379768)
			(xy 411.863615 -395.437145) (xy 411.864048 -395.466062) (xy 411.863462 -395.499425) (xy 411.853811 -395.565449)
			(xy 411.834678 -395.629373) (xy 411.821122 -395.659864) (xy 411.816938 -395.670298) (xy 411.817083 -395.69275)
			(xy 411.826779 -395.713001) (xy 411.835092 -395.72057) (xy 411.857341 -395.739243) (xy 411.897408 -395.781297)
			(xy 411.931833 -395.828083) (xy 411.960062 -395.878848) (xy 411.981642 -395.932776) (xy 411.996225 -395.989001)
			(xy 412.003579 -396.046619) (xy 412.004002 -396.075662) (xy 412.003551 -396.104666) (xy 411.996221 -396.162209)
			(xy 411.981684 -396.218366) (xy 411.960174 -396.272239) (xy 411.932035 -396.322965) (xy 411.897718 -396.369733)
			(xy 411.857771 -396.411794) (xy 411.8356 -396.4305) (xy 411.828742 -396.436088) (xy 411.819344 -396.451582)
			(xy 411.805628 -396.525242) (xy 411.80446 -396.534001) (xy 411.807458 -396.551403) (xy 411.81147 -396.559278)
			(xy 411.81147 -396.559532) (xy 411.824065 -396.58271) (xy 411.841953 -396.632331) (xy 411.851036 -396.684289)
			(xy 411.851602 -396.710662) (xy 411.85153 -396.72002) (xy 411.850384 -396.738702) (xy 411.849316 -396.748)
			(xy 411.8483 -396.756636) (xy 411.85211 -396.773908) (xy 411.895798 -396.84325) (xy 411.909768 -396.853918)
			(xy 411.91815 -396.856712) (xy 411.942243 -396.865198) (xy 411.987524 -396.888834) (xy 412.02841 -396.919449)
			(xy 412.063835 -396.956247) (xy 412.092875 -396.998266) (xy 412.114773 -397.044412) (xy 412.122366 -397.068802)
			(xy 412.12389 -397.074644) (xy 412.443676 -397.627602) (xy 412.44774 -397.63192) (xy 412.463955 -397.649619)
			(xy 412.491384 -397.689009) (xy 412.512529 -397.7321) (xy 412.5269 -397.777898) (xy 412.534166 -397.825344)
			(xy 412.534608 -397.849344) (xy 412.53412 -397.87412) (xy 412.526367 -397.923061) (xy 412.511058 -397.970189)
			(xy 412.48857 -398.014344) (xy 412.459456 -398.054441) (xy 412.424431 -398.089493) (xy 412.384357 -398.118639)
			(xy 412.34022 -398.141162) (xy 412.293105 -398.156508) (xy 412.244169 -398.1643) (xy 412.219394 -398.164812)
			(xy 412.218886 -398.164812) (xy 412.193493 -398.164303) (xy 412.143362 -398.156171) (xy 412.095179 -398.140118)
			(xy 412.050188 -398.11656) (xy 412.009548 -398.086103) (xy 411.974308 -398.049533) (xy 411.945376 -398.007793)
			(xy 411.9235 -397.96196) (xy 411.915864 -397.937736) (xy 411.91434 -397.931894) (xy 411.593792 -397.377412)
			(xy 411.589728 -397.373094) (xy 411.573624 -397.355425) (xy 411.546385 -397.31614) (xy 411.525376 -397.273199)
			(xy 411.511074 -397.227583) (xy 411.503808 -397.180334) (xy 411.503368 -397.156432) (xy 411.503526 -397.14438)
			(xy 411.505435 -397.120352) (xy 411.507178 -397.108426) (xy 411.508448 -397.099536) (xy 411.5054 -397.082518)
			(xy 411.467808 -397.019272) (xy 411.463143 -397.011962) (xy 411.449891 -397.000797) (xy 411.4419 -396.997428)
			(xy 411.441646 -396.997428) (xy 411.419908 -396.989021) (xy 411.379067 -396.966565) (xy 411.342113 -396.938164)
			(xy 411.309905 -396.904477) (xy 411.283189 -396.866287) (xy 411.262587 -396.824481) (xy 411.248578 -396.780029)
			(xy 411.241486 -396.733965) (xy 411.240986 -396.710662) (xy 411.241568 -396.684292) (xy 411.250671 -396.632341)
			(xy 411.268548 -396.582721) (xy 411.281118 -396.559532) (xy 411.281118 -396.559278) (xy 411.285161 -396.551415)
			(xy 411.288151 -396.534003) (xy 411.28696 -396.525242) (xy 411.273244 -396.451582) (xy 411.263846 -396.436088)
			(xy 411.256988 -396.4305) (xy 411.234797 -396.411816) (xy 411.194843 -396.369758) (xy 411.160523 -396.322988)
			(xy 411.132386 -396.272258) (xy 411.110884 -396.218379) (xy 411.09636 -396.162216) (xy 411.089049 -396.104668)
			(xy 411.088586 -396.075662) (xy 411.088586 -396.075408) (xy 411.089185 -396.042087) (xy 411.098844 -395.976148)
			(xy 411.117959 -395.912306) (xy 411.131512 -395.88186) (xy 411.1357 -395.871424) (xy 411.135563 -395.848965)
			(xy 411.125876 -395.828702) (xy 411.117542 -395.821154) (xy 411.095299 -395.802478) (xy 411.055245 -395.760419)
			(xy 411.020833 -395.713631) (xy 410.992616 -395.662866) (xy 410.971049 -395.608939) (xy 410.956476 -395.552716)
			(xy 410.949134 -395.495102) (xy 410.948632 -395.466062) (xy 410.948632 -395.465808) (xy 410.949073 -395.436908)
			(xy 410.956351 -395.379569) (xy 410.970792 -395.323603) (xy 410.992167 -395.269902) (xy 411.020134 -395.219319)
			(xy 411.054249 -395.172662) (xy 411.093968 -395.130672) (xy 411.116018 -395.111986) (xy 411.123004 -395.105652)
			(xy 411.132256 -395.089239) (xy 411.134052 -395.079982) (xy 411.138624 -395.048994) (xy 411.139519 -395.039821)
			(xy 411.135479 -395.021853) (xy 411.13075 -395.013942) (xy 411.115764 -394.989304) (xy 411.110679 -394.980841)
			(xy 411.095448 -394.968309) (xy 411.076606 -394.962477) (xy 411.066742 -394.962888) (xy 411.01899 -394.96492)
			(xy 410.983162 -394.964385) (xy 410.912054 -394.95555) (xy 410.842578 -394.938015) (xy 410.775793 -394.912048)
			(xy 410.712719 -394.878046) (xy 410.683202 -394.857732) (xy 410.673042 -394.850366) (xy 410.648404 -394.847064)
			(xy 410.546042 -394.884148) (xy 410.529278 -394.902436) (xy 410.52623 -394.914628) (xy 410.518829 -394.940927)
			(xy 410.496615 -394.990837) (xy 410.482034 -395.013942) (xy 410.477252 -395.021834) (xy 410.473105 -395.0398)
			(xy 410.473906 -395.048994) (xy 410.478478 -395.079982) (xy 410.480169 -395.089277) (xy 410.489438 -395.105724)
			(xy 410.496512 -395.111986) (xy 410.518587 -395.130671) (xy 410.55832 -395.172698) (xy 410.592444 -395.219395)
			(xy 410.620414 -395.270018) (xy 410.641786 -395.32376) (xy 410.656219 -395.379766) (xy 410.663483 -395.437144)
			(xy 410.663898 -395.466062) (xy 410.663312 -395.499425) (xy 410.653662 -395.56545) (xy 410.634531 -395.629374)
			(xy 410.620972 -395.659864) (xy 410.616791 -395.670299) (xy 410.616936 -395.692751) (xy 410.626625 -395.713006)
			(xy 410.634942 -395.72057) (xy 410.657189 -395.739244) (xy 410.697252 -395.781301) (xy 410.731673 -395.828087)
			(xy 410.759898 -395.878852) (xy 410.781476 -395.932779) (xy 410.796058 -395.989003) (xy 410.80341 -396.04662)
			(xy 410.803852 -396.075662) (xy 410.803402 -396.104666) (xy 410.796071 -396.16221) (xy 410.781536 -396.218368)
			(xy 410.760027 -396.272242) (xy 410.731891 -396.322971) (xy 410.697576 -396.369741) (xy 410.657631 -396.411806)
			(xy 410.63545 -396.4305) (xy 410.628592 -396.436088) (xy 410.619194 -396.451582) (xy 410.605478 -396.525242)
			(xy 410.604309 -396.534001) (xy 410.60731 -396.551402) (xy 410.61132 -396.559278) (xy 410.61132 -396.559532)
			(xy 410.623917 -396.58271) (xy 410.641808 -396.63233) (xy 410.650892 -396.684289) (xy 410.651452 -396.710662)
			(xy 410.65138 -396.72002) (xy 410.650234 -396.738702) (xy 410.649166 -396.748) (xy 410.64815 -396.756636)
			(xy 410.65196 -396.773908) (xy 410.695648 -396.84325) (xy 410.709618 -396.853918) (xy 410.718 -396.856712)
			(xy 410.742036 -396.865165) (xy 410.787219 -396.88871) (xy 410.828033 -396.919206) (xy 410.863418 -396.955862)
			(xy 410.892457 -396.997727) (xy 410.914393 -397.043712) (xy 410.921962 -397.06804) (xy 410.923486 -397.073882)
			(xy 411.24378 -397.627602) (xy 411.247844 -397.63192) (xy 411.264063 -397.649617) (xy 411.291501 -397.689004)
			(xy 411.312652 -397.732095) (xy 411.327028 -397.777894) (xy 411.334296 -397.825343) (xy 411.334712 -397.849344)
			(xy 411.334224 -397.87412) (xy 411.326471 -397.923062) (xy 411.311162 -397.97019) (xy 411.288674 -398.014345)
			(xy 411.25956 -398.054442) (xy 411.224535 -398.089495) (xy 411.184462 -398.118641) (xy 411.140325 -398.141164)
			(xy 411.093209 -398.156511) (xy 411.044274 -398.164304) (xy 411.019498 -398.164812) (xy 411.01899 -398.164812)
			(xy 410.993597 -398.164303) (xy 410.943465 -398.156172) (xy 410.895282 -398.14012) (xy 410.85029 -398.116561)
			(xy 410.80965 -398.086104) (xy 410.774409 -398.049534) (xy 410.745477 -398.007794) (xy 410.7236 -397.961961)
			(xy 410.715968 -397.937736) (xy 410.714444 -397.931894) (xy 410.39415 -397.378174) (xy 410.390086 -397.373856)
			(xy 410.373898 -397.356147) (xy 410.346524 -397.316743) (xy 410.325435 -397.273648) (xy 410.311119 -397.227855)
			(xy 410.303906 -397.180422) (xy 410.303472 -397.156432) (xy 410.303558 -397.144384) (xy 410.305341 -397.120355)
			(xy 410.307028 -397.108426) (xy 410.307981 -397.099669) (xy 410.304612 -397.082392) (xy 410.300424 -397.074644)
			(xy 410.267658 -397.019272) (xy 410.262996 -397.011958) (xy 410.249749 -397.000781) (xy 410.24175 -396.997428)
			(xy 410.241496 -396.997428) (xy 410.219755 -396.989023) (xy 410.178908 -396.966572) (xy 410.141949 -396.938173)
			(xy 410.109735 -396.904487) (xy 410.083014 -396.866296) (xy 410.062409 -396.824488) (xy 410.048397 -396.780034)
			(xy 410.041303 -396.733967) (xy 410.040836 -396.710662) (xy 410.041418 -396.684291) (xy 410.050519 -396.63234)
			(xy 410.068394 -396.582719) (xy 410.080968 -396.559532) (xy 410.080968 -396.559278) (xy 410.085014 -396.551416)
			(xy 410.088007 -396.534003) (xy 410.08681 -396.525242) (xy 410.073094 -396.451582) (xy 410.063696 -396.436088)
			(xy 410.056838 -396.4305) (xy 410.034649 -396.411815) (xy 409.994699 -396.369755) (xy 409.960383 -396.322984)
			(xy 409.932249 -396.272254) (xy 409.910749 -396.218376) (xy 409.896228 -396.162214) (xy 409.888917 -396.104667)
			(xy 409.888436 -396.075662) (xy 409.888436 -396.075408) (xy 409.889035 -396.042087) (xy 409.898695 -395.976149)
			(xy 409.917812 -395.912308) (xy 409.931362 -395.88186) (xy 409.935553 -395.871425) (xy 409.935417 -395.848967)
			(xy 409.925722 -395.828708) (xy 409.917392 -395.821154) (xy 409.895147 -395.802479) (xy 409.855089 -395.760422)
			(xy 409.820673 -395.713635) (xy 409.792453 -395.66287) (xy 409.770883 -395.608942) (xy 409.756309 -395.552718)
			(xy 409.748965 -395.495103) (xy 409.748482 -395.466062) (xy 409.748482 -395.465808) (xy 409.748923 -395.436908)
			(xy 409.7562 -395.379568) (xy 409.77064 -395.323601) (xy 409.792013 -395.269898) (xy 409.819978 -395.219314)
			(xy 409.854091 -395.172653) (xy 409.893807 -395.13066) (xy 409.915868 -395.111986) (xy 409.922859 -395.105655)
			(xy 409.932121 -395.089243) (xy 409.933902 -395.079982) (xy 409.938474 -395.048994) (xy 409.939369 -395.039821)
			(xy 409.935326 -395.021855) (xy 409.9306 -395.013942) (xy 409.915614 -394.989304) (xy 409.910527 -394.980847)
			(xy 409.895295 -394.96833) (xy 409.876456 -394.962516) (xy 409.866592 -394.962888) (xy 409.819094 -394.96492)
			(xy 409.783266 -394.964385) (xy 409.712158 -394.95555) (xy 409.642681 -394.938016) (xy 409.575896 -394.91205)
			(xy 409.512822 -394.878048) (xy 409.483306 -394.857732) (xy 409.473146 -394.850366) (xy 409.448508 -394.847064)
			(xy 409.346146 -394.884148) (xy 409.329382 -394.902436) (xy 409.326334 -394.914628) (xy 409.318933 -394.940927)
			(xy 409.296719 -394.990837) (xy 409.282138 -395.013942) (xy 409.277356 -395.021834) (xy 409.273209 -395.0398)
			(xy 409.27401 -395.048994) (xy 409.278582 -395.079982) (xy 409.280273 -395.089277) (xy 409.289542 -395.105723)
			(xy 409.296616 -395.111986) (xy 409.318691 -395.130672) (xy 409.358424 -395.172699) (xy 409.392547 -395.219395)
			(xy 409.420517 -395.270018) (xy 409.441889 -395.32376) (xy 409.456322 -395.379766) (xy 409.463586 -395.437144)
			(xy 409.464002 -395.466062) (xy 409.463416 -395.499425) (xy 409.453766 -395.56545) (xy 409.434635 -395.629375)
			(xy 409.421076 -395.659864) (xy 409.416894 -395.670299) (xy 409.41704 -395.692751) (xy 409.426729 -395.713006)
			(xy 409.435046 -395.72057) (xy 409.457292 -395.739245) (xy 409.497355 -395.781301) (xy 409.531776 -395.828087)
			(xy 409.560001 -395.878852) (xy 409.581579 -395.932779) (xy 409.59616 -395.989003) (xy 409.603513 -396.04662)
			(xy 409.603956 -396.075662) (xy 409.603506 -396.104666) (xy 409.596175 -396.16221) (xy 409.58164 -396.218369)
			(xy 409.560132 -396.272243) (xy 409.531995 -396.322971) (xy 409.49768 -396.369742) (xy 409.457736 -396.411807)
			(xy 409.435554 -396.4305) (xy 409.428696 -396.436088) (xy 409.419298 -396.451582) (xy 409.405582 -396.525242)
			(xy 409.404413 -396.534001) (xy 409.407414 -396.551402) (xy 409.411424 -396.559278) (xy 409.411424 -396.559532)
			(xy 409.42402 -396.58271) (xy 409.441912 -396.63233) (xy 409.450996 -396.684289) (xy 409.451556 -396.710662)
			(xy 409.451484 -396.72002) (xy 409.450338 -396.738702) (xy 409.44927 -396.748) (xy 409.448254 -396.756636)
			(xy 409.452064 -396.773908) (xy 409.495752 -396.84325) (xy 409.509722 -396.853918) (xy 409.518104 -396.856712)
			(xy 409.54214 -396.865165) (xy 409.587322 -396.88871) (xy 409.628136 -396.919207) (xy 409.663521 -396.955863)
			(xy 409.692558 -396.997728) (xy 409.714495 -397.043712) (xy 409.722066 -397.06804) (xy 409.72359 -397.073882)
			(xy 410.043884 -397.627602) (xy 410.047948 -397.63192) (xy 410.064167 -397.649617) (xy 410.091604 -397.689005)
			(xy 410.112755 -397.732096) (xy 410.127131 -397.777894) (xy 410.134399 -397.825343) (xy 410.134816 -397.849344)
			(xy 410.134328 -397.87412) (xy 410.126575 -397.923062) (xy 410.111266 -397.97019) (xy 410.088778 -398.014346)
			(xy 410.059664 -398.054443) (xy 410.02464 -398.089496) (xy 409.984566 -398.118643) (xy 409.940429 -398.141167)
			(xy 409.893313 -398.156514) (xy 409.844378 -398.164307) (xy 409.819602 -398.164812) (xy 409.819094 -398.164812)
			(xy 409.793701 -398.164304) (xy 409.743569 -398.156173) (xy 409.695385 -398.140121) (xy 409.650392 -398.116563)
			(xy 409.609751 -398.086106) (xy 409.57451 -398.049536) (xy 409.545578 -398.007796) (xy 409.523701 -397.961962)
			(xy 409.516072 -397.937736) (xy 409.514548 -397.931894) (xy 409.194254 -397.378174) (xy 409.19019 -397.373856)
			(xy 409.174001 -397.356147) (xy 409.146627 -397.316744) (xy 409.125539 -397.273648) (xy 409.111222 -397.227855)
			(xy 409.104009 -397.180422) (xy 409.103576 -397.156432) (xy 409.103662 -397.144384) (xy 409.105445 -397.120355)
			(xy 409.107132 -397.108426) (xy 409.108085 -397.09967) (xy 409.10471 -397.082395) (xy 409.100528 -397.074644)
			(xy 409.067762 -397.019272) (xy 409.0631 -397.011957) (xy 409.049854 -397.000779) (xy 409.041854 -396.997428)
			(xy 409.0416 -396.997428) (xy 409.019859 -396.989024) (xy 408.979012 -396.966572) (xy 408.942052 -396.938174)
			(xy 408.909837 -396.904488) (xy 408.883116 -396.866297) (xy 408.862511 -396.824489) (xy 408.848498 -396.780035)
			(xy 408.841405 -396.733967) (xy 408.84094 -396.710662) (xy 408.841522 -396.684291) (xy 408.850623 -396.63234)
			(xy 408.868498 -396.582719) (xy 408.881072 -396.559532) (xy 408.881072 -396.559278) (xy 408.885118 -396.551416)
			(xy 408.888111 -396.534003) (xy 408.886914 -396.525242) (xy 408.873198 -396.451582) (xy 408.8638 -396.436088)
			(xy 408.856942 -396.4305) (xy 408.834753 -396.411815) (xy 408.794803 -396.369755) (xy 408.760486 -396.322985)
			(xy 408.732352 -396.272254) (xy 408.710852 -396.218376) (xy 408.69633 -396.162214) (xy 408.68902 -396.104667)
			(xy 408.68854 -396.075662) (xy 408.68854 -396.075408) (xy 408.689139 -396.042087) (xy 408.698799 -395.976149)
			(xy 408.717917 -395.912308) (xy 408.731466 -395.88186) (xy 408.735656 -395.871425) (xy 408.73552 -395.848966)
			(xy 408.725826 -395.828707) (xy 408.717496 -395.821154) (xy 408.695251 -395.802479) (xy 408.655192 -395.760423)
			(xy 408.620776 -395.713635) (xy 408.592556 -395.66287) (xy 408.570986 -395.608942) (xy 408.556411 -395.552719)
			(xy 408.549068 -395.495103) (xy 408.548586 -395.466062) (xy 408.548586 -395.465808) (xy 408.549027 -395.436908)
			(xy 408.556305 -395.379568) (xy 408.570745 -395.323601) (xy 408.592117 -395.269898) (xy 408.620083 -395.219314)
			(xy 408.654195 -395.172654) (xy 408.693912 -395.130661) (xy 408.715972 -395.111986) (xy 408.722963 -395.105655)
			(xy 408.732224 -395.089243) (xy 408.734006 -395.079982) (xy 408.738578 -395.048994) (xy 408.739474 -395.039821)
			(xy 408.73543 -395.021855) (xy 408.730704 -395.013942) (xy 408.715718 -394.989304) (xy 408.710631 -394.980847)
			(xy 408.695399 -394.968329) (xy 408.67656 -394.962513) (xy 408.666696 -394.962888) (xy 408.618944 -394.96492)
			(xy 408.583115 -394.964388) (xy 408.512004 -394.955559) (xy 408.442524 -394.93803) (xy 408.375736 -394.912068)
			(xy 408.312657 -394.87807) (xy 408.283156 -394.857732) (xy 408.272996 -394.850366) (xy 408.248358 -394.847064)
			(xy 408.145996 -394.884148) (xy 408.129232 -394.902436) (xy 408.126184 -394.914628) (xy 408.118784 -394.940928)
			(xy 408.096573 -394.99084) (xy 408.081988 -395.013942) (xy 408.077202 -395.021832) (xy 408.073051 -395.0398)
			(xy 408.07386 -395.048994) (xy 408.078432 -395.079982) (xy 408.080121 -395.089279) (xy 408.089384 -395.105732)
			(xy 408.096466 -395.111986) (xy 408.118543 -395.13067) (xy 408.15828 -395.172696) (xy 408.192407 -395.219391)
			(xy 408.22038 -395.270014) (xy 408.241754 -395.323757) (xy 408.256189 -395.379764) (xy 408.263454 -395.437143)
			(xy 408.263852 -395.466062) (xy 408.263266 -395.499425) (xy 408.253615 -395.565449) (xy 408.234482 -395.629373)
			(xy 408.220926 -395.659864) (xy 408.216741 -395.670298) (xy 408.216886 -395.69275) (xy 408.226583 -395.713)
			(xy 408.234896 -395.72057) (xy 408.257145 -395.739243) (xy 408.297211 -395.781298) (xy 408.331636 -395.828083)
			(xy 408.359865 -395.878848) (xy 408.381444 -395.932776) (xy 408.396028 -395.989001) (xy 408.403381 -396.046619)
			(xy 408.403806 -396.075662) (xy 408.403355 -396.104666) (xy 408.396025 -396.162209) (xy 408.381488 -396.218366)
			(xy 408.359978 -396.272239) (xy 408.33184 -396.322965) (xy 408.297522 -396.369733) (xy 408.257575 -396.411795)
			(xy 408.235404 -396.4305) (xy 408.228546 -396.436088) (xy 408.219148 -396.451582) (xy 408.205432 -396.525242)
			(xy 408.204264 -396.534001) (xy 408.207262 -396.551403) (xy 408.211274 -396.559278) (xy 408.211274 -396.559532)
			(xy 408.223869 -396.58271) (xy 408.241757 -396.632331) (xy 408.25084 -396.684289) (xy 408.251406 -396.710662)
			(xy 408.251334 -396.72002) (xy 408.250188 -396.738702) (xy 408.24912 -396.748) (xy 408.248104 -396.756636)
			(xy 408.251914 -396.773908) (xy 408.295602 -396.84325) (xy 408.309572 -396.853918) (xy 408.317954 -396.856712)
			(xy 408.341987 -396.865168) (xy 408.387164 -396.888718) (xy 408.427971 -396.919217) (xy 408.463351 -396.955875)
			(xy 408.492383 -396.997739) (xy 408.514315 -397.043723) (xy 408.521916 -397.06804) (xy 408.52344 -397.073882)
			(xy 408.843734 -397.627602) (xy 408.847798 -397.63192) (xy 408.863956 -397.649589) (xy 408.891289 -397.688899)
			(xy 408.912365 -397.73189) (xy 408.926699 -397.777572) (xy 408.933962 -397.824897) (xy 408.934412 -397.848836)
			(xy 408.934412 -397.849344) (xy 408.933923 -397.874133) (xy 408.926162 -397.923099) (xy 408.910838 -397.970248)
			(xy 408.888327 -398.014421) (xy 408.859185 -398.054529) (xy 408.824129 -398.089585) (xy 408.784021 -398.118727)
			(xy 408.739848 -398.141238) (xy 408.692699 -398.156562) (xy 408.643733 -398.164323) (xy 408.618944 -398.164812)
			(xy 408.593548 -398.164308) (xy 408.543411 -398.156183) (xy 408.495221 -398.140136) (xy 408.450222 -398.116581)
			(xy 408.409574 -398.086126) (xy 408.374326 -398.049555) (xy 408.345388 -398.007814) (xy 408.323507 -397.961977)
			(xy 408.315922 -397.937736) (xy 408.314398 -397.931894) (xy 407.994104 -397.378174) (xy 407.99004 -397.373856)
			(xy 407.973823 -397.356158) (xy 407.94639 -397.31677) (xy 407.925243 -397.273678) (xy 407.910871 -397.22788)
			(xy 407.903607 -397.180432) (xy 407.903172 -397.156432) (xy 407.90333 -397.14438) (xy 407.905239 -397.120352)
			(xy 407.906982 -397.108426) (xy 407.908252 -397.099536) (xy 407.905204 -397.082518) (xy 407.867612 -397.019272)
			(xy 407.862947 -397.011962) (xy 407.849696 -397.000796) (xy 407.841704 -396.997428) (xy 407.84145 -396.997428)
			(xy 407.819711 -396.989021) (xy 407.77887 -396.966566) (xy 407.741916 -396.938165) (xy 407.709707 -396.904478)
			(xy 407.682991 -396.866288) (xy 407.662389 -396.824481) (xy 407.648379 -396.78003) (xy 407.641287 -396.733965)
			(xy 407.64079 -396.710662) (xy 407.641372 -396.684292) (xy 407.650475 -396.632341) (xy 407.668352 -396.582721)
			(xy 407.680922 -396.559532) (xy 407.680922 -396.559278) (xy 407.684971 -396.551416) (xy 407.687967 -396.534002)
			(xy 407.686764 -396.525242) (xy 407.673048 -396.451582) (xy 407.66365 -396.436088) (xy 407.656792 -396.4305)
			(xy 407.634601 -396.411816) (xy 407.594647 -396.369758) (xy 407.560326 -396.322989) (xy 407.532189 -396.272258)
			(xy 407.510686 -396.218379) (xy 407.496163 -396.162216) (xy 407.488851 -396.104668) (xy 407.48839 -396.075662)
			(xy 407.48839 -396.075408) (xy 407.488989 -396.042087) (xy 407.498648 -395.976148) (xy 407.517764 -395.912306)
			(xy 407.531316 -395.88186) (xy 407.535504 -395.871424) (xy 407.535367 -395.848965) (xy 407.52568 -395.828702)
			(xy 407.517346 -395.821154) (xy 407.495103 -395.802478) (xy 407.455048 -395.760419) (xy 407.420636 -395.713631)
			(xy 407.392419 -395.662866) (xy 407.370851 -395.608939) (xy 407.356279 -395.552716) (xy 407.348936 -395.495102)
			(xy 407.348436 -395.466062) (xy 407.348436 -395.465808) (xy 407.348877 -395.436908) (xy 407.356155 -395.37957)
			(xy 407.370596 -395.323604) (xy 407.391971 -395.269902) (xy 407.419938 -395.21932) (xy 407.454053 -395.172663)
			(xy 407.493772 -395.130673) (xy 407.515822 -395.111986) (xy 407.522808 -395.105652) (xy 407.532059 -395.089239)
			(xy 407.533856 -395.079982) (xy 407.538428 -395.048994) (xy 407.539323 -395.039821) (xy 407.535283 -395.021853)
			(xy 407.530554 -395.013942) (xy 407.515568 -394.989304) (xy 407.510484 -394.98084) (xy 407.495253 -394.968307)
			(xy 407.47641 -394.962474) (xy 407.466546 -394.962888) (xy 407.419048 -394.96492) (xy 407.383219 -394.964388)
			(xy 407.312108 -394.95556) (xy 407.242628 -394.938031) (xy 407.175839 -394.912069) (xy 407.11276 -394.878071)
			(xy 407.08326 -394.857732) (xy 407.0731 -394.850366) (xy 407.048462 -394.847064) (xy 406.9461 -394.884148)
			(xy 406.929336 -394.902436) (xy 406.926288 -394.914628) (xy 406.918889 -394.940928) (xy 406.896678 -394.99084)
			(xy 406.882092 -395.013942) (xy 406.877306 -395.021832) (xy 406.873154 -395.0398) (xy 406.873964 -395.048994)
			(xy 406.878536 -395.079982) (xy 406.880225 -395.089279) (xy 406.889489 -395.105731) (xy 406.89657 -395.111986)
			(xy 406.918647 -395.13067) (xy 406.958383 -395.172696) (xy 406.99251 -395.219392) (xy 407.020483 -395.270014)
			(xy 407.041857 -395.323757) (xy 407.056292 -395.379764) (xy 407.063556 -395.437143) (xy 407.063956 -395.466062)
			(xy 407.06337 -395.499425) (xy 407.053719 -395.565449) (xy 407.034586 -395.629373) (xy 407.02103 -395.659864)
			(xy 407.016845 -395.670298) (xy 407.01699 -395.69275) (xy 407.026687 -395.713) (xy 407.035 -395.72057)
			(xy 407.057248 -395.739243) (xy 407.097315 -395.781298) (xy 407.131739 -395.828084) (xy 407.159968 -395.878848)
			(xy 407.181547 -395.932776) (xy 407.196131 -395.989001) (xy 407.203484 -396.046619) (xy 407.20391 -396.075662)
			(xy 407.203459 -396.104666) (xy 407.196129 -396.162209) (xy 407.181592 -396.218366) (xy 407.160083 -396.272239)
			(xy 407.131944 -396.322966) (xy 407.097627 -396.369734) (xy 407.05768 -396.411796) (xy 407.035508 -396.4305)
			(xy 407.02865 -396.436088) (xy 407.019252 -396.451582) (xy 407.005536 -396.525242) (xy 407.004368 -396.534001)
			(xy 407.007366 -396.551403) (xy 407.011378 -396.559278) (xy 407.011378 -396.559532) (xy 407.023972 -396.58271)
			(xy 407.04186 -396.632331) (xy 407.050943 -396.684289) (xy 407.05151 -396.710662) (xy 407.051438 -396.72002)
			(xy 407.050292 -396.738702) (xy 407.049224 -396.748) (xy 407.048208 -396.756636) (xy 407.052018 -396.773908)
			(xy 407.095706 -396.84325) (xy 407.109676 -396.853918) (xy 407.118058 -396.856712) (xy 407.142091 -396.865169)
			(xy 407.187267 -396.888718) (xy 407.228074 -396.919218) (xy 407.263453 -396.955876) (xy 407.292485 -396.99774)
			(xy 407.314417 -397.043723) (xy 407.32202 -397.06804) (xy 407.323544 -397.073882) (xy 407.643838 -397.627602)
			(xy 407.647902 -397.63192) (xy 407.66406 -397.649589) (xy 407.691393 -397.688899) (xy 407.712468 -397.73189)
			(xy 407.726802 -397.777572) (xy 407.734065 -397.824897) (xy 407.734516 -397.848836) (xy 407.734516 -397.849344)
			(xy 407.734027 -397.874133) (xy 407.726266 -397.923099) (xy 407.710942 -397.970249) (xy 407.688432 -398.014422)
			(xy 407.65929 -398.05453) (xy 407.624233 -398.089587) (xy 407.584125 -398.118729) (xy 407.539953 -398.14124)
			(xy 407.492803 -398.156565) (xy 407.443837 -398.164326) (xy 407.419048 -398.164812) (xy 407.393652 -398.164308)
			(xy 407.343514 -398.156184) (xy 407.295324 -398.140137) (xy 407.250324 -398.116583) (xy 407.209676 -398.086127)
			(xy 407.174428 -398.049557) (xy 407.145489 -398.007815) (xy 407.123607 -397.961979) (xy 407.116026 -397.937736)
			(xy 407.114502 -397.931894) (xy 406.794208 -397.378174) (xy 406.790144 -397.373856) (xy 406.773926 -397.356158)
			(xy 406.746493 -397.31677) (xy 406.725346 -397.273679) (xy 406.710974 -397.22788) (xy 406.70371 -397.180432)
			(xy 406.703276 -397.156432) (xy 406.703434 -397.14438) (xy 406.705343 -397.120352) (xy 406.707086 -397.108426)
			(xy 406.708356 -397.099536) (xy 406.705308 -397.082518) (xy 406.667716 -397.019272) (xy 406.663052 -397.011961)
			(xy 406.6498 -397.000794) (xy 406.641808 -396.997428) (xy 406.641554 -396.997428) (xy 406.619815 -396.989021)
			(xy 406.578974 -396.966566) (xy 406.542019 -396.938165) (xy 406.509809 -396.904479) (xy 406.483093 -396.866289)
			(xy 406.462491 -396.824482) (xy 406.448481 -396.78003) (xy 406.441389 -396.733966) (xy 406.440894 -396.710662)
			(xy 406.441476 -396.684292) (xy 406.450579 -396.632341) (xy 406.468456 -396.582721) (xy 406.481026 -396.559532)
			(xy 406.481026 -396.559278) (xy 406.485075 -396.551416) (xy 406.48807 -396.534002) (xy 406.486868 -396.525242)
			(xy 406.473152 -396.451582) (xy 406.463754 -396.436088) (xy 406.456896 -396.4305) (xy 406.434705 -396.411817)
			(xy 406.39475 -396.369758) (xy 406.360429 -396.322989) (xy 406.332292 -396.272259) (xy 406.310789 -396.21838)
			(xy 406.296266 -396.162216) (xy 406.288954 -396.104668) (xy 406.288494 -396.075662) (xy 406.288494 -396.075408)
			(xy 406.289093 -396.042087) (xy 406.298752 -395.976148) (xy 406.317868 -395.912306) (xy 406.33142 -395.88186)
			(xy 406.335607 -395.871424) (xy 406.335471 -395.848965) (xy 406.325785 -395.828701) (xy 406.31745 -395.821154)
			(xy 406.295207 -395.802478) (xy 406.255152 -395.76042) (xy 406.220739 -395.713632) (xy 406.192522 -395.662866)
			(xy 406.170954 -395.608939) (xy 406.156382 -395.552717) (xy 406.149039 -395.495102) (xy 406.14854 -395.466062)
			(xy 406.14854 -395.465808) (xy 406.148981 -395.436909) (xy 406.156259 -395.37957) (xy 406.170701 -395.323604)
			(xy 406.192075 -395.269902) (xy 406.220043 -395.21932) (xy 406.254158 -395.172663) (xy 406.293877 -395.130674)
			(xy 406.315926 -395.111986) (xy 406.322911 -395.105652) (xy 406.332162 -395.089238) (xy 406.33396 -395.079982)
			(xy 406.338532 -395.048994) (xy 406.339427 -395.039821) (xy 406.335388 -395.021853) (xy 406.330658 -395.013942)
			(xy 406.315672 -394.989304) (xy 406.310588 -394.98084) (xy 406.295357 -394.968305) (xy 406.276514 -394.962471)
			(xy 406.26665 -394.962888) (xy 406.218898 -394.96492) (xy 406.183095 -394.964375) (xy 406.112037 -394.955528)
			(xy 406.04261 -394.937993) (xy 405.975873 -394.912039) (xy 405.912841 -394.87806) (xy 405.883364 -394.857732)
			(xy 405.872883 -394.851027) (xy 405.848254 -394.847688) (xy 405.836374 -394.851382) (xy 405.746458 -394.884148)
			(xy 405.72944 -394.90269) (xy 405.726392 -394.914882) (xy 405.718965 -394.941112) (xy 405.696754 -394.990894)
			(xy 405.682196 -395.013942) (xy 405.677374 -395.021891) (xy 405.673194 -395.039993) (xy 405.674068 -395.049248)
			(xy 405.67864 -395.079982) (xy 405.680329 -395.089279) (xy 405.689593 -395.10573) (xy 405.696674 -395.111986)
			(xy 405.71875 -395.13067) (xy 405.758487 -395.172696) (xy 405.792613 -395.219392) (xy 405.820586 -395.270015)
			(xy 405.84196 -395.323757) (xy 405.856394 -395.379764) (xy 405.863659 -395.437143) (xy 405.86406 -395.466062)
			(xy 405.863474 -395.499425) (xy 405.853823 -395.565449) (xy 405.834691 -395.629373) (xy 405.821134 -395.659864)
			(xy 405.816949 -395.670298) (xy 405.817094 -395.692749) (xy 405.826792 -395.712999) (xy 405.835104 -395.72057)
			(xy 405.857352 -395.739243) (xy 405.897418 -395.781298) (xy 405.931842 -395.828084) (xy 405.96007 -395.878849)
			(xy 405.98165 -395.932777) (xy 405.996233 -395.989001) (xy 406.003586 -396.046619) (xy 406.004014 -396.075662)
			(xy 406.003563 -396.104666) (xy 405.996233 -396.162209) (xy 405.981696 -396.218366) (xy 405.960187 -396.272239)
			(xy 405.932049 -396.322966) (xy 405.897732 -396.369735) (xy 405.857785 -396.411797) (xy 405.835612 -396.4305)
			(xy 405.828754 -396.436088) (xy 405.819356 -396.451582) (xy 405.80564 -396.525242) (xy 405.804472 -396.534001)
			(xy 405.80747 -396.551403) (xy 405.811482 -396.559278) (xy 405.811482 -396.559532) (xy 405.824076 -396.58271)
			(xy 405.841964 -396.632331) (xy 405.851046 -396.684289) (xy 405.851614 -396.710662) (xy 405.851542 -396.72002)
			(xy 405.850396 -396.738702) (xy 405.849328 -396.748) (xy 405.848312 -396.756636) (xy 405.852122 -396.773908)
			(xy 405.89581 -396.84325) (xy 405.90978 -396.853918) (xy 405.918162 -396.856712) (xy 405.94226 -396.865193)
			(xy 405.987551 -396.88882) (xy 406.028447 -396.919431) (xy 406.063882 -396.956226) (xy 406.092932 -396.998246)
			(xy 406.114837 -397.044394) (xy 406.122378 -397.068802) (xy 406.123902 -397.074644) (xy 406.443688 -397.627602)
			(xy 406.447752 -397.63192) (xy 406.463971 -397.649617) (xy 406.491408 -397.689005) (xy 406.512558 -397.732096)
			(xy 406.526934 -397.777895) (xy 406.534202 -397.825343) (xy 406.53462 -397.849344) (xy 406.534131 -397.874117)
			(xy 406.526377 -397.923053) (xy 406.511068 -397.970175) (xy 406.488578 -398.014324) (xy 406.459462 -398.054413)
			(xy 406.424437 -398.089457) (xy 406.384362 -398.118593) (xy 406.340225 -398.141105) (xy 406.293111 -398.15644)
			(xy 406.244179 -398.164218) (xy 406.219406 -398.164812) (xy 406.218898 -398.164812) (xy 406.193504 -398.164304)
			(xy 406.143372 -398.156173) (xy 406.095188 -398.140122) (xy 406.050195 -398.116564) (xy 406.009553 -398.086107)
			(xy 405.974312 -398.049537) (xy 405.945379 -398.007797) (xy 405.923501 -397.961963) (xy 405.915876 -397.937736)
			(xy 405.914352 -397.931894) (xy 405.593804 -397.377412) (xy 405.58974 -397.373094) (xy 405.573635 -397.355426)
			(xy 405.546396 -397.31614) (xy 405.525385 -397.2732) (xy 405.511083 -397.227584) (xy 405.503817 -397.180334)
			(xy 405.50338 -397.156432) (xy 405.503538 -397.14438) (xy 405.505447 -397.120352) (xy 405.50719 -397.108426)
			(xy 405.50846 -397.099536) (xy 405.505412 -397.082518) (xy 405.46782 -397.019272) (xy 405.463156 -397.011961)
			(xy 405.449905 -397.000793) (xy 405.441912 -396.997428) (xy 405.441658 -396.997428) (xy 405.419919 -396.989021)
			(xy 405.379077 -396.966567) (xy 405.342122 -396.938166) (xy 405.309912 -396.90448) (xy 405.283195 -396.866289)
			(xy 405.262593 -396.824483) (xy 405.248582 -396.780031) (xy 405.24149 -396.733966) (xy 405.240998 -396.710662)
			(xy 405.24158 -396.684292) (xy 405.250683 -396.632341) (xy 405.268561 -396.582722) (xy 405.28113 -396.559532)
			(xy 405.28113 -396.559278) (xy 405.285179 -396.551416) (xy 405.288174 -396.534002) (xy 405.286972 -396.525242)
			(xy 405.273256 -396.451582) (xy 405.263858 -396.436088) (xy 405.257 -396.4305) (xy 405.234809 -396.411816)
			(xy 405.194854 -396.369758) (xy 405.160533 -396.322989) (xy 405.132395 -396.272259) (xy 405.110892 -396.21838)
			(xy 405.096369 -396.162216) (xy 405.089057 -396.104668) (xy 405.088598 -396.075662) (xy 405.088598 -396.075408)
			(xy 405.089197 -396.042087) (xy 405.098857 -395.976148) (xy 405.117972 -395.912307) (xy 405.131524 -395.88186)
			(xy 405.135711 -395.871424) (xy 405.135574 -395.848965) (xy 405.125889 -395.828701) (xy 405.117554 -395.821154)
			(xy 405.095311 -395.802478) (xy 405.055255 -395.76042) (xy 405.020842 -395.713632) (xy 404.992625 -395.662867)
			(xy 404.971057 -395.608939) (xy 404.956484 -395.552717) (xy 404.949141 -395.495102) (xy 404.948644 -395.466062)
			(xy 404.948644 -395.465808) (xy 404.949085 -395.436909) (xy 404.956363 -395.37957) (xy 404.970805 -395.323604)
			(xy 404.992179 -395.269903) (xy 405.020147 -395.219321) (xy 405.054262 -395.172664) (xy 405.093982 -395.130675)
			(xy 405.11603 -395.111986) (xy 405.123015 -395.105651) (xy 405.132265 -395.089238) (xy 405.134064 -395.079982)
			(xy 405.138636 -395.048994) (xy 405.139532 -395.039821) (xy 405.135492 -395.021853) (xy 405.130762 -395.013942)
			(xy 405.115776 -394.989304) (xy 405.110692 -394.98084) (xy 405.095461 -394.968304) (xy 405.076618 -394.962468)
			(xy 405.066754 -394.962888) (xy 405.019002 -394.96492) (xy 404.983174 -394.964386) (xy 404.912065 -394.955552)
			(xy 404.842588 -394.938018) (xy 404.775802 -394.912052) (xy 404.712728 -394.878051) (xy 404.683214 -394.857732)
			(xy 404.673054 -394.850366) (xy 404.648416 -394.847064) (xy 404.546054 -394.884148) (xy 404.52929 -394.902436)
			(xy 404.526242 -394.914628) (xy 404.518842 -394.940928) (xy 404.496628 -394.990838) (xy 404.482046 -395.013942)
			(xy 404.477263 -395.021834) (xy 404.473116 -395.0398) (xy 404.473918 -395.048994) (xy 404.47849 -395.079982)
			(xy 404.480181 -395.089277) (xy 404.489452 -395.105722) (xy 404.496524 -395.111986) (xy 404.518598 -395.130672)
			(xy 404.558331 -395.172699) (xy 404.592453 -395.219396) (xy 404.620423 -395.270018) (xy 404.641794 -395.323761)
			(xy 404.656227 -395.379766) (xy 404.663491 -395.437144) (xy 404.66391 -395.466062) (xy 404.663324 -395.499425)
			(xy 404.653674 -395.56545) (xy 404.634544 -395.629375) (xy 404.620984 -395.659864) (xy 404.616802 -395.670299)
			(xy 404.616947 -395.692751) (xy 404.626638 -395.713005) (xy 404.634954 -395.72057) (xy 404.6572 -395.739245)
			(xy 404.697262 -395.781301) (xy 404.731682 -395.828088) (xy 404.759907 -395.878853) (xy 404.781484 -395.93278)
			(xy 404.796066 -395.989004) (xy 404.803418 -396.04662) (xy 404.803864 -396.075662) (xy 404.803413 -396.104666)
			(xy 404.796082 -396.162208) (xy 404.781544 -396.218364) (xy 404.760033 -396.272236) (xy 404.731893 -396.32296)
			(xy 404.697574 -396.369726) (xy 404.657625 -396.411785) (xy 404.635462 -396.4305) (xy 404.628604 -396.436088)
			(xy 404.619206 -396.451582) (xy 404.60549 -396.525242) (xy 404.604322 -396.534002) (xy 404.607318 -396.551404)
			(xy 404.611332 -396.559278) (xy 404.611332 -396.559532) (xy 404.623928 -396.58271) (xy 404.641819 -396.63233)
			(xy 404.650903 -396.684289) (xy 404.651464 -396.710662) (xy 404.651392 -396.72002) (xy 404.650246 -396.738702)
			(xy 404.649178 -396.748) (xy 404.648162 -396.756636) (xy 404.651972 -396.773908) (xy 404.69566 -396.84325)
			(xy 404.70963 -396.853918) (xy 404.718012 -396.856712) (xy 404.742048 -396.865166) (xy 404.787229 -396.888711)
			(xy 404.828041 -396.919209) (xy 404.863426 -396.955865) (xy 404.892462 -396.997729) (xy 404.914398 -397.043714)
			(xy 404.921974 -397.06804) (xy 404.923498 -397.073882) (xy 405.243792 -397.627602) (xy 405.247856 -397.63192)
			(xy 405.264075 -397.649617) (xy 405.291511 -397.689005) (xy 405.312662 -397.732096) (xy 405.327037 -397.777895)
			(xy 405.334305 -397.825343) (xy 405.334724 -397.849344) (xy 405.334235 -397.874117) (xy 405.326481 -397.923054)
			(xy 405.311172 -397.970176) (xy 405.288682 -398.014325) (xy 405.259567 -398.054415) (xy 405.224541 -398.089459)
			(xy 405.184467 -398.118595) (xy 405.14033 -398.141108) (xy 405.093215 -398.156443) (xy 405.044283 -398.164222)
			(xy 405.01951 -398.164812) (xy 405.019002 -398.164812) (xy 404.993608 -398.164304) (xy 404.943475 -398.156174)
			(xy 404.895291 -398.140123) (xy 404.850297 -398.116566) (xy 404.809655 -398.086109) (xy 404.774413 -398.049539)
			(xy 404.74548 -398.007798) (xy 404.723602 -397.961965) (xy 404.71598 -397.937736) (xy 404.714456 -397.931894)
			(xy 404.394162 -397.378174) (xy 404.390098 -397.373856) (xy 404.373909 -397.356147) (xy 404.346534 -397.316744)
			(xy 404.325445 -397.273649) (xy 404.311128 -397.227855) (xy 404.303915 -397.180422) (xy 404.303484 -397.156432)
			(xy 404.30357 -397.144384) (xy 404.305353 -397.120355) (xy 404.30704 -397.108426) (xy 404.307994 -397.09967)
			(xy 404.304619 -397.082395) (xy 404.300436 -397.074644) (xy 404.26767 -397.019272) (xy 404.263009 -397.011957)
			(xy 404.249763 -397.000777) (xy 404.241762 -396.997428) (xy 404.241508 -396.997428) (xy 404.219766 -396.989024)
			(xy 404.178918 -396.966573) (xy 404.141957 -396.938175) (xy 404.109742 -396.904489) (xy 404.083021 -396.866298)
			(xy 404.062414 -396.82449) (xy 404.048401 -396.780035) (xy 404.041308 -396.733967) (xy 404.040848 -396.710662)
			(xy 404.04143 -396.684291) (xy 404.050531 -396.63234) (xy 404.068407 -396.582719) (xy 404.08098 -396.559532)
			(xy 404.08098 -396.559278) (xy 404.085026 -396.551416) (xy 404.088018 -396.534003) (xy 404.086822 -396.525242)
			(xy 404.073106 -396.451582) (xy 404.063708 -396.436088) (xy 404.05685 -396.4305) (xy 404.034661 -396.411815)
			(xy 403.99471 -396.369755) (xy 403.960392 -396.322985) (xy 403.932258 -396.272255) (xy 403.910758 -396.218377)
			(xy 403.896236 -396.162214) (xy 403.888925 -396.104667) (xy 403.888448 -396.075662) (xy 403.888448 -396.075408)
			(xy 403.889047 -396.042087) (xy 403.898708 -395.976149) (xy 403.917825 -395.912308) (xy 403.931374 -395.88186)
			(xy 403.935564 -395.871425) (xy 403.935428 -395.848966) (xy 403.925735 -395.828706) (xy 403.917404 -395.821154)
			(xy 403.895159 -395.80248) (xy 403.855099 -395.760423) (xy 403.820683 -395.713636) (xy 403.792462 -395.662871)
			(xy 403.770891 -395.608943) (xy 403.756317 -395.552719) (xy 403.748973 -395.495103) (xy 403.748494 -395.466062)
			(xy 403.748494 -395.465808) (xy 403.748935 -395.436908) (xy 403.756213 -395.379568) (xy 403.770653 -395.323602)
			(xy 403.792026 -395.269899) (xy 403.819992 -395.219315) (xy 403.854105 -395.172655) (xy 403.893822 -395.130663)
			(xy 403.91588 -395.111986) (xy 403.92287 -395.105654) (xy 403.932129 -395.089242) (xy 403.933914 -395.079982)
			(xy 403.938486 -395.048994) (xy 403.939382 -395.039821) (xy 403.935339 -395.021855) (xy 403.930612 -395.013942)
			(xy 403.915626 -394.989304) (xy 403.91054 -394.980846) (xy 403.895308 -394.968325) (xy 403.876468 -394.962507)
			(xy 403.866604 -394.962888) (xy 403.819106 -394.96492) (xy 403.783278 -394.964386) (xy 403.712169 -394.955552)
			(xy 403.642691 -394.938019) (xy 403.575906 -394.912054) (xy 403.51283 -394.878053) (xy 403.483318 -394.857732)
			(xy 403.473158 -394.850366) (xy 403.44852 -394.847064) (xy 403.346158 -394.884148) (xy 403.329394 -394.902436)
			(xy 403.326346 -394.914628) (xy 403.318946 -394.940928) (xy 403.296732 -394.990838) (xy 403.28215 -395.013942)
			(xy 403.277367 -395.021833) (xy 403.273219 -395.0398) (xy 403.274022 -395.048994) (xy 403.278594 -395.079982)
			(xy 403.280285 -395.089277) (xy 403.289556 -395.105721) (xy 403.296628 -395.111986) (xy 403.318702 -395.130672)
			(xy 403.358434 -395.172699) (xy 403.392557 -395.219396) (xy 403.420526 -395.270019) (xy 403.441897 -395.323761)
			(xy 403.456329 -395.379767) (xy 403.463593 -395.437144) (xy 403.464014 -395.466062) (xy 403.463428 -395.499425)
			(xy 403.453778 -395.56545) (xy 403.434648 -395.629375) (xy 403.421088 -395.659864) (xy 403.416906 -395.670299)
			(xy 403.417051 -395.692751) (xy 403.426742 -395.713004) (xy 403.435058 -395.72057) (xy 403.457304 -395.739245)
			(xy 403.497366 -395.781302) (xy 403.531785 -395.828088) (xy 403.56001 -395.878853) (xy 403.581587 -395.93278)
			(xy 403.596168 -395.989004) (xy 403.603521 -396.04662) (xy 403.603968 -396.075662) (xy 403.603517 -396.104666)
			(xy 403.596186 -396.162208) (xy 403.581649 -396.218364) (xy 403.560138 -396.272236) (xy 403.531997 -396.322961)
			(xy 403.497678 -396.369727) (xy 403.45773 -396.411786) (xy 403.435566 -396.4305) (xy 403.428708 -396.436088)
			(xy 403.41931 -396.451582) (xy 403.405594 -396.525242) (xy 403.404426 -396.534002) (xy 403.407422 -396.551404)
			(xy 403.411436 -396.559278) (xy 403.411436 -396.559532) (xy 403.424032 -396.58271) (xy 403.441922 -396.63233)
			(xy 403.451006 -396.684289) (xy 403.451568 -396.710662) (xy 403.451496 -396.72002) (xy 403.45035 -396.738702)
			(xy 403.449282 -396.748) (xy 403.448266 -396.756636) (xy 403.452076 -396.773908) (xy 403.495764 -396.84325)
			(xy 403.509734 -396.853918) (xy 403.518116 -396.856712) (xy 403.542151 -396.865166) (xy 403.587332 -396.888712)
			(xy 403.628144 -396.919209) (xy 403.663528 -396.955866) (xy 403.692564 -396.99773) (xy 403.7145 -397.043715)
			(xy 403.722078 -397.06804) (xy 403.723602 -397.073882) (xy 404.043896 -397.627602) (xy 404.04796 -397.63192)
			(xy 404.064179 -397.649617) (xy 404.091615 -397.689005) (xy 404.112765 -397.732096) (xy 404.12714 -397.777895)
			(xy 404.134408 -397.825343) (xy 404.134828 -397.849344) (xy 404.134339 -397.874117) (xy 404.126585 -397.923054)
			(xy 404.111276 -397.970177) (xy 404.088786 -398.014326) (xy 404.059671 -398.054416) (xy 404.024645 -398.08946)
			(xy 403.984571 -398.118598) (xy 403.940434 -398.141111) (xy 403.89332 -398.156446) (xy 403.844387 -398.164226)
			(xy 403.819614 -398.164812) (xy 403.819106 -398.164812) (xy 403.793712 -398.164305) (xy 403.743579 -398.156175)
			(xy 403.695394 -398.140125) (xy 403.650399 -398.116567) (xy 403.609757 -398.086111) (xy 403.574514 -398.04954)
			(xy 403.54558 -398.0078) (xy 403.523702 -397.961966) (xy 403.516084 -397.937736) (xy 403.51456 -397.931894)
			(xy 403.194266 -397.378174) (xy 403.190202 -397.373856) (xy 403.174013 -397.356147) (xy 403.146638 -397.316744)
			(xy 403.125548 -397.273649) (xy 403.111231 -397.227856) (xy 403.104018 -397.180422) (xy 403.103588 -397.156432)
			(xy 403.103674 -397.144384) (xy 403.105456 -397.120355) (xy 403.107144 -397.108426) (xy 403.108097 -397.09967)
			(xy 403.104723 -397.082395) (xy 403.10054 -397.074644) (xy 403.067774 -397.019272) (xy 403.063113 -397.011956)
			(xy 403.049868 -397.000775) (xy 403.041866 -396.997428) (xy 403.041612 -396.997428) (xy 403.01987 -396.989024)
			(xy 402.979022 -396.966574) (xy 402.94206 -396.938176) (xy 402.909844 -396.90449) (xy 402.883123 -396.866299)
			(xy 402.862516 -396.82449) (xy 402.848503 -396.780036) (xy 402.841409 -396.733967) (xy 402.840952 -396.710662)
			(xy 402.841534 -396.684291) (xy 402.850636 -396.63234) (xy 402.868511 -396.58272) (xy 402.881084 -396.559532)
			(xy 402.881084 -396.559278) (xy 402.885129 -396.551416) (xy 402.888121 -396.534003) (xy 402.886926 -396.525242)
			(xy 402.87321 -396.451582) (xy 402.863812 -396.436088) (xy 402.856954 -396.4305) (xy 402.834765 -396.411815)
			(xy 402.794813 -396.369756) (xy 402.760496 -396.322986) (xy 402.732361 -396.272255) (xy 402.71086 -396.218377)
			(xy 402.696338 -396.162214) (xy 402.689027 -396.104667) (xy 402.688552 -396.075662) (xy 402.688552 -396.075408)
			(xy 402.689151 -396.042087) (xy 402.698812 -395.976149) (xy 402.717929 -395.912308) (xy 402.731478 -395.88186)
			(xy 402.735668 -395.871425) (xy 402.735531 -395.848966) (xy 402.725839 -395.828706) (xy 402.717508 -395.821154)
			(xy 402.695263 -395.80248) (xy 402.655203 -395.760423) (xy 402.620786 -395.713636) (xy 402.592565 -395.662871)
			(xy 402.570994 -395.608943) (xy 402.556419 -395.552719) (xy 402.549075 -395.495103) (xy 402.548598 -395.466062)
			(xy 402.548598 -395.465808) (xy 402.549039 -395.436908) (xy 402.556317 -395.379569) (xy 402.570757 -395.323602)
			(xy 402.59213 -395.269899) (xy 402.620096 -395.219315) (xy 402.654209 -395.172656) (xy 402.693926 -395.130664)
			(xy 402.715984 -395.111986) (xy 402.722974 -395.105654) (xy 402.732232 -395.089242) (xy 402.734018 -395.079982)
			(xy 402.73859 -395.048994) (xy 402.739486 -395.039821) (xy 402.735443 -395.021854) (xy 402.730716 -395.013942)
			(xy 402.71767 -394.993516) (xy 402.697058 -394.949652) (xy 402.683078 -394.903246) (xy 402.676029 -394.855295)
			(xy 402.675598 -394.831062) (xy 402.676029 -394.80739) (xy 402.682782 -394.76053) (xy 402.696132 -394.715107)
			(xy 402.70557 -394.693394) (xy 402.709422 -394.684056) (xy 402.710211 -394.663886) (xy 402.707094 -394.654278)
			(xy 402.678392 -394.577316) (xy 402.664676 -394.562584) (xy 402.655278 -394.55852) (xy 402.630907 -394.546828)
			(xy 402.58602 -394.516719) (xy 402.546629 -394.47971) (xy 402.513784 -394.436784) (xy 402.488359 -394.389087)
			(xy 402.471033 -394.33789) (xy 402.462268 -394.284555) (xy 402.46173 -394.25753) (xy 402.462273 -394.230406)
			(xy 402.471123 -394.176886) (xy 402.48859 -394.125527) (xy 402.514205 -394.077708) (xy 402.547282 -394.034712)
			(xy 402.586933 -393.997691) (xy 402.632095 -393.967638) (xy 402.681557 -393.94536) (xy 402.733992 -393.931454)
			(xy 402.760942 -393.928346) (xy 402.76145 -393.928346) (xy 402.771864 -393.92733) (xy 402.790406 -393.916662)
			(xy 402.841968 -393.84732) (xy 402.84799 -393.838516) (xy 402.852709 -393.817735) (xy 402.851112 -393.807188)
			(xy 402.845675 -393.778797) (xy 402.839817 -393.721284) (xy 402.839428 -393.69238) (xy 402.839853 -393.661522)
			(xy 402.846436 -393.600157) (xy 402.859494 -393.539837) (xy 402.878878 -393.481243) (xy 402.904371 -393.425037)
			(xy 402.919692 -393.398248) (xy 402.924518 -393.39012) (xy 402.927566 -393.371832) (xy 402.912326 -393.295886)
			(xy 402.910043 -393.28682) (xy 402.900013 -393.271061) (xy 402.892768 -393.265152) (xy 402.872462 -393.249421)
			(xy 402.836505 -393.212744) (xy 402.806642 -393.170955) (xy 402.783589 -393.125056) (xy 402.7679 -393.076147)
			(xy 402.759951 -393.025403) (xy 402.759418 -392.999722) (xy 402.759868 -392.974917) (xy 402.767293 -392.925866)
			(xy 402.781963 -392.878475) (xy 402.803551 -392.833808) (xy 402.831571 -392.792868) (xy 402.865394 -392.756575)
			(xy 402.90426 -392.725744) (xy 402.947297 -392.701066) (xy 402.970238 -392.69162) (xy 402.970492 -392.691366)
			(xy 402.979728 -392.687278) (xy 402.994232 -392.673246) (xy 403.002225 -392.654715) (xy 403.00275 -392.64463)
			(xy 403.003004 -392.612372) (xy 403.003683 -392.580172) (xy 403.011303 -392.516215) (xy 403.025967 -392.453497)
			(xy 403.047496 -392.392793) (xy 403.075623 -392.33485) (xy 403.110002 -392.280383) (xy 403.150208 -392.230064)
			(xy 403.172676 -392.206988) (xy 403.291802 -392.087862) (xy 403.298642 -392.080461) (xy 403.306362 -392.061863)
			(xy 403.306788 -392.051794) (xy 403.306788 -391.552938) (xy 403.293072 -391.52957) (xy 403.281134 -391.522712)
			(xy 403.259742 -391.510085) (xy 403.220667 -391.479416) (xy 403.186622 -391.443245) (xy 403.158372 -391.402386)
			(xy 403.136555 -391.35776) (xy 403.121662 -391.310372) (xy 403.114027 -391.261289) (xy 403.113494 -391.236454)
			(xy 403.113494 -391.234676) (xy 403.113894 -391.211975) (xy 403.12014 -391.167004) (xy 403.132458 -391.123305)
			(xy 403.14118 -391.102342) (xy 403.141434 -391.101834) (xy 403.143466 -391.097262) (xy 403.146514 -391.084054)
			(xy 403.147783 -391.074547) (xy 403.143991 -391.055758) (xy 403.139148 -391.047478) (xy 403.093682 -390.97712)
			(xy 403.093428 -390.976866) (xy 403.089857 -390.971766) (xy 403.080739 -390.963295) (xy 403.075394 -390.960102)
			(xy 403.069729 -390.957168) (xy 403.057387 -390.953956) (xy 403.05101 -390.953752) (xy 402.458936 -390.953752)
			(xy 402.452125 -390.953966) (xy 402.438988 -390.957562) (xy 402.433028 -390.960864) (xy 402.426932 -390.96442)
			(xy 402.417788 -390.974072) (xy 402.415502 -390.978136) (xy 402.414232 -390.980422) (xy 402.371814 -391.0584)
			(xy 402.36683 -391.068725) (xy 402.365762 -391.091606) (xy 402.369782 -391.102342) (xy 402.373338 -391.109962)
			(xy 402.375116 -391.112756) (xy 402.387381 -391.132774) (xy 402.406755 -391.175537) (xy 402.419893 -391.220608)
			(xy 402.426532 -391.267083) (xy 402.426932 -391.290556) (xy 402.426452 -391.316548) (xy 402.418327 -391.367894)
			(xy 402.402269 -391.417335) (xy 402.378673 -391.463656) (xy 402.348122 -391.505716) (xy 402.311368 -391.542478)
			(xy 402.269315 -391.573038) (xy 402.222998 -391.596642) (xy 402.17356 -391.612711) (xy 402.122216 -391.620847)
			(xy 402.096224 -391.621264) (xy 402.071389 -391.620812) (xy 402.02228 -391.613372) (xy 401.974836 -391.59867)
			(xy 401.930125 -391.577038) (xy 401.889152 -391.548961) (xy 401.870672 -391.532364) (xy 401.870418 -391.532364)
			(xy 401.863776 -391.526601) (xy 401.847665 -391.51959) (xy 401.838922 -391.518648) (xy 401.814284 -391.51814)
			(xy 401.804378 -391.517886) (xy 401.77212 -391.529824) (xy 401.76577 -391.534904) (xy 401.743573 -391.55193)
			(xy 401.694654 -391.579057) (xy 401.641872 -391.59758) (xy 401.586729 -391.606972) (xy 401.55876 -391.607548)
			(xy 401.533483 -391.607064) (xy 401.48352 -391.599355) (xy 401.435314 -391.584124) (xy 401.389992 -391.561726)
			(xy 401.369022 -391.547604) (xy 401.362465 -391.543393) (xy 401.3476 -391.538736) (xy 401.339812 -391.53846)
			(xy 401.222972 -391.53846) (xy 401.214456 -391.538783) (xy 401.198365 -391.544365) (xy 401.191476 -391.549382)
			(xy 401.169462 -391.565997) (xy 401.121066 -391.592439) (xy 401.068959 -391.610501) (xy 401.01458 -391.619684)
			(xy 400.987006 -391.620248) (xy 400.960527 -391.61972) (xy 400.908248 -391.611277) (xy 400.857978 -391.594621)
			(xy 400.810999 -391.570177) (xy 400.76851 -391.538568) (xy 400.731593 -391.5006) (xy 400.701189 -391.45724)
			(xy 400.678074 -391.409593) (xy 400.662836 -391.358876) (xy 400.655864 -391.306379) (xy 400.657336 -391.253442)
			(xy 400.667214 -391.201415) (xy 400.685246 -391.151622) (xy 400.6977 -391.12825) (xy 400.701764 -391.120884)
			(xy 400.701764 -391.077704) (xy 400.701341 -391.067634) (xy 400.693623 -391.049032) (xy 400.686778 -391.041636)
			(xy 400.61388 -390.968738) (xy 400.606482 -390.96189) (xy 400.587884 -390.954157) (xy 400.577812 -390.953752)
			(xy 398.14373 -390.953752) (xy 398.134896 -390.954128) (xy 398.118265 -390.960096) (xy 398.111218 -390.965436)
			(xy 398.10436 -390.971024) (xy 398.09547 -390.986264) (xy 398.093946 -390.995408) (xy 398.0887 -391.021387)
			(xy 398.071979 -391.071679) (xy 398.048459 -391.119173) (xy 398.018593 -391.162955) (xy 397.982954 -391.202183)
			(xy 397.942229 -391.2361) (xy 397.897202 -391.264055) (xy 397.84874 -391.285509) (xy 397.797775 -391.300049)
			(xy 397.745287 -391.307396) (xy 397.718788 -391.307828) (xy 397.71828 -391.307828) (xy 397.694293 -391.307451)
			(xy 397.646702 -391.301398) (xy 397.600248 -391.289416) (xy 397.577818 -391.280904) (xy 397.57731 -391.280904)
			(xy 397.577056 -391.28065) (xy 397.571131 -391.278572) (xy 397.558672 -391.277035) (xy 397.552418 -391.277602)
			(xy 397.539464 -391.27938) (xy 397.4592 -391.338562) (xy 397.454155 -391.342495) (xy 397.446067 -391.352401)
			(xy 397.443198 -391.35812) (xy 397.437864 -391.369804) (xy 397.43888 -391.383012) (xy 397.439896 -391.41146)
			(xy 397.43941 -391.438711) (xy 397.431654 -391.492659) (xy 397.416299 -391.544954) (xy 397.393657 -391.594531)
			(xy 397.364191 -391.640381) (xy 397.3285 -391.681572) (xy 397.287309 -391.717263) (xy 397.241459 -391.746729)
			(xy 397.191882 -391.769371) (xy 397.139587 -391.784726) (xy 397.085639 -391.792482) (xy 397.031137 -391.792482)
			(xy 396.977189 -391.784726) (xy 396.924894 -391.769371) (xy 396.875317 -391.746729) (xy 396.829467 -391.717263)
			(xy 396.788276 -391.681572) (xy 396.752585 -391.640381) (xy 396.723119 -391.594531) (xy 396.700477 -391.544954)
			(xy 396.685122 -391.492659) (xy 396.677366 -391.438711) (xy 396.67688 -391.41146) (xy 396.677896 -391.383012)
			(xy 396.678912 -391.369804) (xy 396.673578 -391.35812) (xy 396.670702 -391.352408) (xy 396.662603 -391.342516)
			(xy 396.657576 -391.338562) (xy 396.58798 -391.287254) (xy 396.5827 -391.283525) (xy 396.57074 -391.278629)
			(xy 396.564358 -391.277602) (xy 396.551658 -391.276078) (xy 396.539466 -391.280904) (xy 396.538958 -391.280904)
			(xy 396.516524 -391.289397) (xy 396.470068 -391.30136) (xy 396.422481 -391.307414) (xy 396.398496 -391.307828)
			(xy 396.397988 -391.307828) (xy 396.370252 -391.307323) (xy 396.315365 -391.299277) (xy 396.262221 -391.283372)
			(xy 396.211939 -391.259942) (xy 396.165578 -391.22948) (xy 396.124114 -391.192629) (xy 396.088421 -391.150165)
			(xy 396.05925 -391.102981) (xy 396.037216 -391.052071) (xy 396.022782 -390.998509) (xy 396.01902 -390.971024)
			(xy 396.017242 -390.956292) (xy 396.016226 -390.926574) (xy 396.016226 -390.926066) (xy 396.016666 -390.900093)
			(xy 396.023712 -390.848626) (xy 396.03767 -390.79859) (xy 396.058282 -390.750908) (xy 396.071344 -390.728454)
			(xy 396.074646 -390.72312) (xy 396.078261 -390.713969) (xy 396.078982 -390.694325) (xy 396.072263 -390.675852)
			(xy 396.06601 -390.668256) (xy 396.064232 -390.666478) (xy 394.900912 -389.503158) (xy 394.891518 -389.494754)
			(xy 394.867398 -389.487546) (xy 394.854938 -389.489442) (xy 394.767562 -389.508238) (xy 394.763752 -389.509508)
			(xy 394.757148 -389.512556) (xy 394.749837 -389.516904) (xy 394.738422 -389.529499) (xy 394.734796 -389.537194)
			(xy 394.734288 -389.538718) (xy 394.734034 -389.539226) (xy 394.723268 -389.565896) (xy 394.694881 -389.615916)
			(xy 394.659305 -389.661106) (xy 394.617349 -389.700443) (xy 394.569962 -389.733035) (xy 394.518219 -389.758144)
			(xy 394.463293 -389.775199) (xy 394.406429 -389.783815) (xy 394.377672 -389.784336) (xy 394.350421 -389.783848)
			(xy 394.296475 -389.776089) (xy 394.244182 -389.760731) (xy 394.194607 -389.738089) (xy 394.148758 -389.708623)
			(xy 394.107569 -389.672931) (xy 394.071877 -389.631742) (xy 394.042411 -389.585893) (xy 394.019769 -389.536318)
			(xy 394.004411 -389.484025) (xy 393.996652 -389.430079) (xy 393.996164 -389.402828) (xy 393.99718 -389.37438)
			(xy 393.998196 -389.361172) (xy 393.992862 -389.349488) (xy 393.989982 -389.343779) (xy 393.981878 -389.333894)
			(xy 393.97686 -389.32993) (xy 393.907264 -389.278622) (xy 393.901982 -389.274896) (xy 393.890022 -389.270008)
			(xy 393.883642 -389.26897) (xy 393.870942 -389.267446) (xy 393.85875 -389.272272) (xy 393.858242 -389.272272)
			(xy 393.835809 -389.280771) (xy 393.789354 -389.292745) (xy 393.741766 -389.29881) (xy 393.71778 -389.299196)
			(xy 393.717272 -389.299196) (xy 393.690022 -389.298708) (xy 393.636078 -389.290948) (xy 393.583788 -389.27559)
			(xy 393.534215 -389.252947) (xy 393.488369 -389.22348) (xy 393.447183 -389.187789) (xy 393.411496 -389.146599)
			(xy 393.382033 -389.10075) (xy 393.359396 -389.051175) (xy 393.344043 -388.998882) (xy 393.336289 -388.944938)
			(xy 393.335764 -388.917688) (xy 393.336304 -388.888802) (xy 393.345026 -388.831691) (xy 393.362255 -388.776546)
			(xy 393.387597 -388.724628) (xy 393.420473 -388.677121) (xy 393.460133 -388.63511) (xy 393.50567 -388.599556)
			(xy 393.556045 -388.571269) (xy 393.610107 -388.550897) (xy 393.666621 -388.538903) (xy 393.695428 -388.536688)
			(xy 393.702794 -388.536434) (xy 393.71651 -388.531354) (xy 393.722606 -388.527036) (xy 393.728328 -388.522527)
			(xy 393.737118 -388.510917) (xy 393.739878 -388.504176) (xy 393.758928 -388.454138) (xy 393.773406 -388.416292)
			(xy 393.776094 -388.407353) (xy 393.775551 -388.388711) (xy 393.76838 -388.371496) (xy 393.76223 -388.364476)
			(xy 393.047474 -387.64972) (xy 393.044622 -387.647016) (xy 393.038241 -387.642427) (xy 393.034774 -387.640576)
			(xy 393.029347 -387.637992) (xy 393.017668 -387.635166) (xy 393.01166 -387.634988) (xy 392.406124 -387.634988)
			(xy 392.397867 -387.635271) (xy 392.382193 -387.64046) (xy 392.37539 -387.645148) (xy 392.348868 -387.664437)
			(xy 392.29181 -387.696768) (xy 392.23107 -387.721497) (xy 392.167656 -387.738215) (xy 392.102619 -387.746644)
			(xy 392.037037 -387.746644) (xy 391.972 -387.738215) (xy 391.908586 -387.721497) (xy 391.847846 -387.696768)
			(xy 391.790788 -387.664437) (xy 391.764266 -387.645148) (xy 391.757468 -387.640453) (xy 391.741789 -387.635276)
			(xy 391.733532 -387.634988) (xy 368.78387 -387.634988) (xy 368.778992 -387.635082) (xy 368.769402 -387.636868)
			(xy 368.76482 -387.638544) (xy 368.755676 -387.642354) (xy 367.168176 -389.229854) (xy 367.162842 -389.261604)
			(xy 367.169954 -389.276336) (xy 367.182041 -389.302432) (xy 367.199114 -389.35735) (xy 367.207766 -389.414205)
			(xy 367.208308 -389.44296) (xy 367.207847 -389.470215) (xy 367.200095 -389.52417) (xy 367.184742 -389.576473)
			(xy 367.162102 -389.626058) (xy 367.132635 -389.671916) (xy 367.096942 -389.713113) (xy 367.055748 -389.748811)
			(xy 367.009893 -389.778283) (xy 366.96031 -389.800928) (xy 366.908009 -389.816287) (xy 366.854055 -389.824045)
			(xy 366.8268 -389.824468) (xy 366.798043 -389.82395) (xy 366.74118 -389.815315) (xy 366.686263 -389.798226)
			(xy 366.660176 -389.786114) (xy 366.645444 -389.779002) (xy 366.613694 -389.784336) (xy 365.581184 -390.816846)
			(xy 365.575804 -390.822669) (xy 365.568574 -390.836769) (xy 365.56696 -390.844532) (xy 365.56696 -390.861042)
			(xy 365.567468 -390.864344) (xy 365.567722 -390.865614) (xy 365.569918 -390.880185) (xy 365.572335 -390.909554)
			(xy 365.572548 -390.924288) (xy 365.572548 -390.92632) (xy 365.571532 -390.953498) (xy 365.571331 -390.964762)
			(xy 365.579513 -390.985722) (xy 365.58728 -390.993884) (xy 365.610648 -391.016236) (xy 365.619309 -391.023765)
			(xy 365.641135 -391.030789) (xy 365.652558 -391.029698) (xy 365.669806 -391.027459) (xy 365.704508 -391.025047)
			(xy 365.7219 -391.024872) (xy 365.753443 -391.025348) (xy 365.816043 -391.033151) (xy 365.877198 -391.048638)
			(xy 365.935967 -391.07157) (xy 365.991449 -391.101595) (xy 366.04279 -391.138253) (xy 366.089203 -391.180979)
			(xy 366.129975 -391.229119) (xy 366.164479 -391.281932) (xy 366.180784 -391.315286) (xy 368.129087 -391.315286)
			(xy 368.129087 -391.263314) (xy 368.137217 -391.211981) (xy 368.153276 -391.162552) (xy 368.176869 -391.116244)
			(xy 368.207416 -391.074195) (xy 368.244163 -391.037443) (xy 368.286208 -391.006891) (xy 368.332513 -390.983292)
			(xy 368.38194 -390.967227) (xy 368.433272 -390.959091) (xy 368.459258 -390.958578) (xy 368.482492 -390.958965)
			(xy 368.528503 -390.965465) (xy 368.573151 -390.978344) (xy 368.615556 -390.997348) (xy 368.654881 -391.022102)
			(xy 368.672872 -391.03681) (xy 368.67973 -391.042652) (xy 368.696748 -391.049002) (xy 368.780568 -391.049002)
			(xy 368.797586 -391.042652) (xy 368.804444 -391.03681) (xy 368.822443 -391.022115) (xy 368.86177 -390.997366)
			(xy 368.904173 -390.978364) (xy 368.948817 -390.965482) (xy 368.994825 -390.958974) (xy 369.018058 -390.958578)
			(xy 369.046653 -390.959172) (xy 369.102987 -390.969026) (xy 369.156791 -390.988414) (xy 369.206462 -391.016759)
			(xy 369.228878 -391.034524) (xy 369.229132 -391.034778) (xy 369.236116 -391.040071) (xy 369.252631 -391.045902)
			(xy 369.26139 -391.046208) (xy 369.326414 -391.046208) (xy 369.335014 -391.045858) (xy 369.351241 -391.040146)
			(xy 369.358164 -391.035032) (xy 369.358672 -391.034524) (xy 369.380992 -391.016893) (xy 369.430456 -390.988819)
			(xy 369.483999 -390.969639) (xy 369.540038 -390.95992) (xy 369.568476 -390.95934) (xy 369.59447 -390.959725)
			(xy 369.645819 -390.967855) (xy 369.695264 -390.983917) (xy 369.741587 -391.007517) (xy 369.783648 -391.038073)
			(xy 369.820411 -391.074834) (xy 369.85097 -391.116892) (xy 369.874573 -391.163214) (xy 369.890639 -391.212657)
			(xy 369.898284 -391.260917) (xy 370.586256 -391.260917) (xy 370.586256 -391.208943) (xy 370.594386 -391.157608)
			(xy 370.610447 -391.108178) (xy 370.634043 -391.061868) (xy 370.664593 -391.01982) (xy 370.701344 -390.983069)
			(xy 370.743392 -390.952519) (xy 370.789702 -390.928923) (xy 370.839132 -390.912862) (xy 370.890467 -390.904732)
			(xy 370.942441 -390.904732) (xy 370.993776 -390.912862) (xy 371.043206 -390.928923) (xy 371.089516 -390.952519)
			(xy 371.131564 -390.983069) (xy 371.168315 -391.01982) (xy 371.198865 -391.061868) (xy 371.222461 -391.108178)
			(xy 371.238522 -391.157608) (xy 371.246652 -391.208943) (xy 371.247162 -391.23493) (xy 371.246652 -391.260917)
			(xy 371.786406 -391.260917) (xy 371.786406 -391.208943) (xy 371.794536 -391.157608) (xy 371.810597 -391.108178)
			(xy 371.834193 -391.061868) (xy 371.864743 -391.01982) (xy 371.901494 -390.983069) (xy 371.943542 -390.952519)
			(xy 371.989852 -390.928923) (xy 372.039282 -390.912862) (xy 372.090617 -390.904732) (xy 372.142591 -390.904732)
			(xy 372.193926 -390.912862) (xy 372.243356 -390.928923) (xy 372.289666 -390.952519) (xy 372.331714 -390.983069)
			(xy 372.368465 -391.01982) (xy 372.399015 -391.061868) (xy 372.422611 -391.108178) (xy 372.438672 -391.157608)
			(xy 372.446802 -391.208943) (xy 372.447312 -391.23493) (xy 372.446802 -391.260917) (xy 372.986302 -391.260917)
			(xy 372.986302 -391.208943) (xy 372.994432 -391.157608) (xy 373.010493 -391.108178) (xy 373.034089 -391.061868)
			(xy 373.064639 -391.01982) (xy 373.10139 -390.983069) (xy 373.143438 -390.952519) (xy 373.189748 -390.928923)
			(xy 373.239178 -390.912862) (xy 373.290513 -390.904732) (xy 373.342487 -390.904732) (xy 373.393822 -390.912862)
			(xy 373.443252 -390.928923) (xy 373.489562 -390.952519) (xy 373.53161 -390.983069) (xy 373.568361 -391.01982)
			(xy 373.598911 -391.061868) (xy 373.622507 -391.108178) (xy 373.638568 -391.157608) (xy 373.646698 -391.208943)
			(xy 373.647208 -391.23493) (xy 373.646698 -391.260917) (xy 374.186198 -391.260917) (xy 374.186198 -391.208943)
			(xy 374.194328 -391.157608) (xy 374.210389 -391.108178) (xy 374.233985 -391.061868) (xy 374.264535 -391.01982)
			(xy 374.301286 -390.983069) (xy 374.343334 -390.952519) (xy 374.389644 -390.928923) (xy 374.439074 -390.912862)
			(xy 374.490409 -390.904732) (xy 374.542383 -390.904732) (xy 374.593718 -390.912862) (xy 374.643148 -390.928923)
			(xy 374.689458 -390.952519) (xy 374.731506 -390.983069) (xy 374.768257 -391.01982) (xy 374.798807 -391.061868)
			(xy 374.822403 -391.108178) (xy 374.838464 -391.157608) (xy 374.846594 -391.208943) (xy 374.847104 -391.23493)
			(xy 374.846594 -391.260917) (xy 375.386348 -391.260917) (xy 375.386348 -391.208943) (xy 375.394478 -391.157608)
			(xy 375.410539 -391.108178) (xy 375.434135 -391.061868) (xy 375.464685 -391.01982) (xy 375.501436 -390.983069)
			(xy 375.543484 -390.952519) (xy 375.589794 -390.928923) (xy 375.639224 -390.912862) (xy 375.690559 -390.904732)
			(xy 375.742533 -390.904732) (xy 375.793868 -390.912862) (xy 375.843298 -390.928923) (xy 375.889608 -390.952519)
			(xy 375.931656 -390.983069) (xy 375.968407 -391.01982) (xy 375.998957 -391.061868) (xy 376.022553 -391.108178)
			(xy 376.038614 -391.157608) (xy 376.046744 -391.208943) (xy 376.047254 -391.23493) (xy 376.046744 -391.260917)
			(xy 376.586244 -391.260917) (xy 376.586244 -391.208943) (xy 376.594374 -391.157608) (xy 376.610435 -391.108178)
			(xy 376.634031 -391.061868) (xy 376.664581 -391.01982) (xy 376.701332 -390.983069) (xy 376.74338 -390.952519)
			(xy 376.78969 -390.928923) (xy 376.83912 -390.912862) (xy 376.890455 -390.904732) (xy 376.942429 -390.904732)
			(xy 376.993764 -390.912862) (xy 377.043194 -390.928923) (xy 377.089504 -390.952519) (xy 377.131552 -390.983069)
			(xy 377.168303 -391.01982) (xy 377.198853 -391.061868) (xy 377.222449 -391.108178) (xy 377.23851 -391.157608)
			(xy 377.24664 -391.208943) (xy 377.24715 -391.23493) (xy 377.24664 -391.260917) (xy 377.786394 -391.260917)
			(xy 377.786394 -391.208943) (xy 377.794524 -391.157608) (xy 377.810585 -391.108178) (xy 377.834181 -391.061868)
			(xy 377.864731 -391.01982) (xy 377.901482 -390.983069) (xy 377.94353 -390.952519) (xy 377.98984 -390.928923)
			(xy 378.03927 -390.912862) (xy 378.090605 -390.904732) (xy 378.142579 -390.904732) (xy 378.193914 -390.912862)
			(xy 378.243344 -390.928923) (xy 378.289654 -390.952519) (xy 378.331702 -390.983069) (xy 378.368453 -391.01982)
			(xy 378.399003 -391.061868) (xy 378.422599 -391.108178) (xy 378.43866 -391.157608) (xy 378.44679 -391.208943)
			(xy 378.4473 -391.23493) (xy 378.44679 -391.260917) (xy 378.98629 -391.260917) (xy 378.98629 -391.208943)
			(xy 378.99442 -391.157608) (xy 379.010481 -391.108178) (xy 379.034077 -391.061868) (xy 379.064627 -391.01982)
			(xy 379.101378 -390.983069) (xy 379.143426 -390.952519) (xy 379.189736 -390.928923) (xy 379.239166 -390.912862)
			(xy 379.290501 -390.904732) (xy 379.342475 -390.904732) (xy 379.39381 -390.912862) (xy 379.44324 -390.928923)
			(xy 379.48955 -390.952519) (xy 379.531598 -390.983069) (xy 379.568349 -391.01982) (xy 379.598899 -391.061868)
			(xy 379.622495 -391.108178) (xy 379.638556 -391.157608) (xy 379.646686 -391.208943) (xy 379.647196 -391.23493)
			(xy 379.646686 -391.260917) (xy 380.186186 -391.260917) (xy 380.186186 -391.208943) (xy 380.194316 -391.157608)
			(xy 380.210377 -391.108178) (xy 380.233973 -391.061868) (xy 380.264523 -391.01982) (xy 380.301274 -390.983069)
			(xy 380.343322 -390.952519) (xy 380.389632 -390.928923) (xy 380.439062 -390.912862) (xy 380.490397 -390.904732)
			(xy 380.542371 -390.904732) (xy 380.593706 -390.912862) (xy 380.643136 -390.928923) (xy 380.689446 -390.952519)
			(xy 380.731494 -390.983069) (xy 380.768245 -391.01982) (xy 380.798795 -391.061868) (xy 380.822391 -391.108178)
			(xy 380.838452 -391.157608) (xy 380.846582 -391.208943) (xy 380.847092 -391.23493) (xy 380.846582 -391.260917)
			(xy 381.386336 -391.260917) (xy 381.386336 -391.208943) (xy 381.394466 -391.157608) (xy 381.410527 -391.108178)
			(xy 381.434123 -391.061868) (xy 381.464673 -391.01982) (xy 381.501424 -390.983069) (xy 381.543472 -390.952519)
			(xy 381.589782 -390.928923) (xy 381.639212 -390.912862) (xy 381.690547 -390.904732) (xy 381.742521 -390.904732)
			(xy 381.793856 -390.912862) (xy 381.843286 -390.928923) (xy 381.889596 -390.952519) (xy 381.931644 -390.983069)
			(xy 381.968395 -391.01982) (xy 381.998945 -391.061868) (xy 382.022541 -391.108178) (xy 382.038602 -391.157608)
			(xy 382.046732 -391.208943) (xy 382.047242 -391.23493) (xy 382.046732 -391.260917) (xy 382.586232 -391.260917)
			(xy 382.586232 -391.208943) (xy 382.594362 -391.157608) (xy 382.610423 -391.108178) (xy 382.634019 -391.061868)
			(xy 382.664569 -391.01982) (xy 382.70132 -390.983069) (xy 382.743368 -390.952519) (xy 382.789678 -390.928923)
			(xy 382.839108 -390.912862) (xy 382.890443 -390.904732) (xy 382.942417 -390.904732) (xy 382.993752 -390.912862)
			(xy 383.043182 -390.928923) (xy 383.089492 -390.952519) (xy 383.13154 -390.983069) (xy 383.168291 -391.01982)
			(xy 383.198841 -391.061868) (xy 383.222437 -391.108178) (xy 383.238498 -391.157608) (xy 383.246628 -391.208943)
			(xy 383.247138 -391.23493) (xy 383.246628 -391.260917) (xy 383.786382 -391.260917) (xy 383.786382 -391.208943)
			(xy 383.794512 -391.157608) (xy 383.810573 -391.108178) (xy 383.834169 -391.061868) (xy 383.864719 -391.01982)
			(xy 383.90147 -390.983069) (xy 383.943518 -390.952519) (xy 383.989828 -390.928923) (xy 384.039258 -390.912862)
			(xy 384.090593 -390.904732) (xy 384.142567 -390.904732) (xy 384.193902 -390.912862) (xy 384.243332 -390.928923)
			(xy 384.289642 -390.952519) (xy 384.33169 -390.983069) (xy 384.368441 -391.01982) (xy 384.398991 -391.061868)
			(xy 384.422587 -391.108178) (xy 384.438648 -391.157608) (xy 384.446778 -391.208943) (xy 384.447288 -391.23493)
			(xy 384.446778 -391.260917) (xy 384.986278 -391.260917) (xy 384.986278 -391.208943) (xy 384.994408 -391.157608)
			(xy 385.010469 -391.108178) (xy 385.034065 -391.061868) (xy 385.064615 -391.01982) (xy 385.101366 -390.983069)
			(xy 385.143414 -390.952519) (xy 385.189724 -390.928923) (xy 385.239154 -390.912862) (xy 385.290489 -390.904732)
			(xy 385.342463 -390.904732) (xy 385.393798 -390.912862) (xy 385.443228 -390.928923) (xy 385.489538 -390.952519)
			(xy 385.531586 -390.983069) (xy 385.568337 -391.01982) (xy 385.598887 -391.061868) (xy 385.622483 -391.108178)
			(xy 385.638544 -391.157608) (xy 385.646674 -391.208943) (xy 385.647184 -391.23493) (xy 385.646674 -391.260917)
			(xy 386.186174 -391.260917) (xy 386.186174 -391.208943) (xy 386.194304 -391.157608) (xy 386.210365 -391.108178)
			(xy 386.233961 -391.061868) (xy 386.264511 -391.01982) (xy 386.301262 -390.983069) (xy 386.34331 -390.952519)
			(xy 386.38962 -390.928923) (xy 386.43905 -390.912862) (xy 386.490385 -390.904732) (xy 386.542359 -390.904732)
			(xy 386.593694 -390.912862) (xy 386.643124 -390.928923) (xy 386.689434 -390.952519) (xy 386.731482 -390.983069)
			(xy 386.768233 -391.01982) (xy 386.798783 -391.061868) (xy 386.822379 -391.108178) (xy 386.83844 -391.157608)
			(xy 386.84657 -391.208943) (xy 386.84708 -391.23493) (xy 386.84657 -391.260917) (xy 387.386324 -391.260917)
			(xy 387.386324 -391.208943) (xy 387.394454 -391.157608) (xy 387.410515 -391.108178) (xy 387.434111 -391.061868)
			(xy 387.464661 -391.01982) (xy 387.501412 -390.983069) (xy 387.54346 -390.952519) (xy 387.58977 -390.928923)
			(xy 387.6392 -390.912862) (xy 387.690535 -390.904732) (xy 387.742509 -390.904732) (xy 387.793844 -390.912862)
			(xy 387.843274 -390.928923) (xy 387.889584 -390.952519) (xy 387.931632 -390.983069) (xy 387.968383 -391.01982)
			(xy 387.998933 -391.061868) (xy 388.022529 -391.108178) (xy 388.03859 -391.157608) (xy 388.04672 -391.208943)
			(xy 388.04723 -391.23493) (xy 388.04672 -391.260917) (xy 388.58622 -391.260917) (xy 388.58622 -391.208943)
			(xy 388.59435 -391.157608) (xy 388.610411 -391.108178) (xy 388.634007 -391.061868) (xy 388.664557 -391.01982)
			(xy 388.701308 -390.983069) (xy 388.743356 -390.952519) (xy 388.789666 -390.928923) (xy 388.839096 -390.912862)
			(xy 388.890431 -390.904732) (xy 388.942405 -390.904732) (xy 388.99374 -390.912862) (xy 389.04317 -390.928923)
			(xy 389.08948 -390.952519) (xy 389.131528 -390.983069) (xy 389.168279 -391.01982) (xy 389.198829 -391.061868)
			(xy 389.222425 -391.108178) (xy 389.238486 -391.157608) (xy 389.246616 -391.208943) (xy 389.247126 -391.23493)
			(xy 389.246616 -391.260917) (xy 389.244198 -391.276188) (xy 389.653272 -391.276188) (xy 389.653272 -391.224212)
			(xy 389.661402 -391.172875) (xy 389.677463 -391.123443) (xy 389.701058 -391.077131) (xy 389.731608 -391.03508)
			(xy 389.768359 -390.998326) (xy 389.810407 -390.967773) (xy 389.856717 -390.944173) (xy 389.906148 -390.928109)
			(xy 389.957484 -390.919974) (xy 389.983472 -390.919462) (xy 390.007246 -390.91987) (xy 390.054306 -390.926671)
			(xy 390.099903 -390.940151) (xy 390.143096 -390.960031) (xy 390.182991 -390.9859) (xy 390.20115 -391.00125)
			(xy 390.208269 -391.006937) (xy 390.22532 -391.01332) (xy 390.234424 -391.013696) (xy 390.26592 -391.013696)
			(xy 390.275022 -391.013311) (xy 390.292072 -391.00693) (xy 390.299194 -391.00125) (xy 390.317359 -390.985908)
			(xy 390.357258 -390.960051) (xy 390.400451 -390.940175) (xy 390.446044 -390.926691) (xy 390.493099 -390.919877)
			(xy 390.516872 -390.919462) (xy 390.54286 -390.920003) (xy 390.594198 -390.92813) (xy 390.643631 -390.944188)
			(xy 390.689944 -390.967782) (xy 390.731996 -390.998331) (xy 390.76875 -391.035083) (xy 390.799303 -391.077132)
			(xy 390.822901 -391.123443) (xy 390.838963 -391.172875) (xy 390.847095 -391.224212) (xy 390.847095 -391.276188)
			(xy 390.838963 -391.327525) (xy 390.822901 -391.376957) (xy 390.799303 -391.423268) (xy 390.76875 -391.465317)
			(xy 390.731996 -391.502069) (xy 390.689944 -391.532618) (xy 390.643631 -391.556212) (xy 390.594198 -391.57227)
			(xy 390.54286 -391.580397) (xy 390.516872 -391.580878) (xy 390.493097 -391.580494) (xy 390.446037 -391.573686)
			(xy 390.40044 -391.5602) (xy 390.357247 -391.540315) (xy 390.317353 -391.514442) (xy 390.299194 -391.49909)
			(xy 390.292096 -391.493372) (xy 390.275028 -391.487009) (xy 390.26592 -391.486644) (xy 390.234424 -391.486644)
			(xy 390.225324 -391.487042) (xy 390.208273 -391.493413) (xy 390.20115 -391.49909) (xy 390.182974 -391.514418)
			(xy 390.143077 -391.540276) (xy 390.099888 -391.560154) (xy 390.054297 -391.573642) (xy 390.007244 -391.580461)
			(xy 389.983472 -391.580878) (xy 389.957484 -391.580426) (xy 389.906148 -391.572291) (xy 389.856717 -391.556227)
			(xy 389.810407 -391.532627) (xy 389.768359 -391.502074) (xy 389.731608 -391.46532) (xy 389.701058 -391.423269)
			(xy 389.677463 -391.376957) (xy 389.661402 -391.327525) (xy 389.653272 -391.276188) (xy 389.244198 -391.276188)
			(xy 389.238486 -391.312252) (xy 389.222425 -391.361682) (xy 389.198829 -391.407992) (xy 389.168279 -391.45004)
			(xy 389.131528 -391.486791) (xy 389.08948 -391.517341) (xy 389.04317 -391.540937) (xy 388.99374 -391.556998)
			(xy 388.942405 -391.565128) (xy 388.890431 -391.565128) (xy 388.839096 -391.556998) (xy 388.789666 -391.540937)
			(xy 388.743356 -391.517341) (xy 388.701308 -391.486791) (xy 388.664557 -391.45004) (xy 388.634007 -391.407992)
			(xy 388.610411 -391.361682) (xy 388.59435 -391.312252) (xy 388.58622 -391.260917) (xy 388.04672 -391.260917)
			(xy 388.03859 -391.312252) (xy 388.022529 -391.361682) (xy 387.998933 -391.407992) (xy 387.968383 -391.45004)
			(xy 387.931632 -391.486791) (xy 387.889584 -391.517341) (xy 387.843274 -391.540937) (xy 387.793844 -391.556998)
			(xy 387.742509 -391.565128) (xy 387.690535 -391.565128) (xy 387.6392 -391.556998) (xy 387.58977 -391.540937)
			(xy 387.54346 -391.517341) (xy 387.501412 -391.486791) (xy 387.464661 -391.45004) (xy 387.434111 -391.407992)
			(xy 387.410515 -391.361682) (xy 387.394454 -391.312252) (xy 387.386324 -391.260917) (xy 386.84657 -391.260917)
			(xy 386.83844 -391.312252) (xy 386.822379 -391.361682) (xy 386.798783 -391.407992) (xy 386.768233 -391.45004)
			(xy 386.731482 -391.486791) (xy 386.689434 -391.517341) (xy 386.643124 -391.540937) (xy 386.593694 -391.556998)
			(xy 386.542359 -391.565128) (xy 386.490385 -391.565128) (xy 386.43905 -391.556998) (xy 386.38962 -391.540937)
			(xy 386.34331 -391.517341) (xy 386.301262 -391.486791) (xy 386.264511 -391.45004) (xy 386.233961 -391.407992)
			(xy 386.210365 -391.361682) (xy 386.194304 -391.312252) (xy 386.186174 -391.260917) (xy 385.646674 -391.260917)
			(xy 385.638544 -391.312252) (xy 385.622483 -391.361682) (xy 385.598887 -391.407992) (xy 385.568337 -391.45004)
			(xy 385.531586 -391.486791) (xy 385.489538 -391.517341) (xy 385.443228 -391.540937) (xy 385.393798 -391.556998)
			(xy 385.342463 -391.565128) (xy 385.290489 -391.565128) (xy 385.239154 -391.556998) (xy 385.189724 -391.540937)
			(xy 385.143414 -391.517341) (xy 385.101366 -391.486791) (xy 385.064615 -391.45004) (xy 385.034065 -391.407992)
			(xy 385.010469 -391.361682) (xy 384.994408 -391.312252) (xy 384.986278 -391.260917) (xy 384.446778 -391.260917)
			(xy 384.438648 -391.312252) (xy 384.422587 -391.361682) (xy 384.398991 -391.407992) (xy 384.368441 -391.45004)
			(xy 384.33169 -391.486791) (xy 384.289642 -391.517341) (xy 384.243332 -391.540937) (xy 384.193902 -391.556998)
			(xy 384.142567 -391.565128) (xy 384.090593 -391.565128) (xy 384.039258 -391.556998) (xy 383.989828 -391.540937)
			(xy 383.943518 -391.517341) (xy 383.90147 -391.486791) (xy 383.864719 -391.45004) (xy 383.834169 -391.407992)
			(xy 383.810573 -391.361682) (xy 383.794512 -391.312252) (xy 383.786382 -391.260917) (xy 383.246628 -391.260917)
			(xy 383.238498 -391.312252) (xy 383.222437 -391.361682) (xy 383.198841 -391.407992) (xy 383.168291 -391.45004)
			(xy 383.13154 -391.486791) (xy 383.089492 -391.517341) (xy 383.043182 -391.540937) (xy 382.993752 -391.556998)
			(xy 382.942417 -391.565128) (xy 382.890443 -391.565128) (xy 382.839108 -391.556998) (xy 382.789678 -391.540937)
			(xy 382.743368 -391.517341) (xy 382.70132 -391.486791) (xy 382.664569 -391.45004) (xy 382.634019 -391.407992)
			(xy 382.610423 -391.361682) (xy 382.594362 -391.312252) (xy 382.586232 -391.260917) (xy 382.046732 -391.260917)
			(xy 382.038602 -391.312252) (xy 382.022541 -391.361682) (xy 381.998945 -391.407992) (xy 381.968395 -391.45004)
			(xy 381.931644 -391.486791) (xy 381.889596 -391.517341) (xy 381.843286 -391.540937) (xy 381.793856 -391.556998)
			(xy 381.742521 -391.565128) (xy 381.690547 -391.565128) (xy 381.639212 -391.556998) (xy 381.589782 -391.540937)
			(xy 381.543472 -391.517341) (xy 381.501424 -391.486791) (xy 381.464673 -391.45004) (xy 381.434123 -391.407992)
			(xy 381.410527 -391.361682) (xy 381.394466 -391.312252) (xy 381.386336 -391.260917) (xy 380.846582 -391.260917)
			(xy 380.838452 -391.312252) (xy 380.822391 -391.361682) (xy 380.798795 -391.407992) (xy 380.768245 -391.45004)
			(xy 380.731494 -391.486791) (xy 380.689446 -391.517341) (xy 380.643136 -391.540937) (xy 380.593706 -391.556998)
			(xy 380.542371 -391.565128) (xy 380.490397 -391.565128) (xy 380.439062 -391.556998) (xy 380.389632 -391.540937)
			(xy 380.343322 -391.517341) (xy 380.301274 -391.486791) (xy 380.264523 -391.45004) (xy 380.233973 -391.407992)
			(xy 380.210377 -391.361682) (xy 380.194316 -391.312252) (xy 380.186186 -391.260917) (xy 379.646686 -391.260917)
			(xy 379.638556 -391.312252) (xy 379.622495 -391.361682) (xy 379.598899 -391.407992) (xy 379.568349 -391.45004)
			(xy 379.531598 -391.486791) (xy 379.48955 -391.517341) (xy 379.44324 -391.540937) (xy 379.39381 -391.556998)
			(xy 379.342475 -391.565128) (xy 379.290501 -391.565128) (xy 379.239166 -391.556998) (xy 379.189736 -391.540937)
			(xy 379.143426 -391.517341) (xy 379.101378 -391.486791) (xy 379.064627 -391.45004) (xy 379.034077 -391.407992)
			(xy 379.010481 -391.361682) (xy 378.99442 -391.312252) (xy 378.98629 -391.260917) (xy 378.44679 -391.260917)
			(xy 378.43866 -391.312252) (xy 378.422599 -391.361682) (xy 378.399003 -391.407992) (xy 378.368453 -391.45004)
			(xy 378.331702 -391.486791) (xy 378.289654 -391.517341) (xy 378.243344 -391.540937) (xy 378.193914 -391.556998)
			(xy 378.142579 -391.565128) (xy 378.090605 -391.565128) (xy 378.03927 -391.556998) (xy 377.98984 -391.540937)
			(xy 377.94353 -391.517341) (xy 377.901482 -391.486791) (xy 377.864731 -391.45004) (xy 377.834181 -391.407992)
			(xy 377.810585 -391.361682) (xy 377.794524 -391.312252) (xy 377.786394 -391.260917) (xy 377.24664 -391.260917)
			(xy 377.23851 -391.312252) (xy 377.222449 -391.361682) (xy 377.198853 -391.407992) (xy 377.168303 -391.45004)
			(xy 377.131552 -391.486791) (xy 377.089504 -391.517341) (xy 377.043194 -391.540937) (xy 376.993764 -391.556998)
			(xy 376.942429 -391.565128) (xy 376.890455 -391.565128) (xy 376.83912 -391.556998) (xy 376.78969 -391.540937)
			(xy 376.74338 -391.517341) (xy 376.701332 -391.486791) (xy 376.664581 -391.45004) (xy 376.634031 -391.407992)
			(xy 376.610435 -391.361682) (xy 376.594374 -391.312252) (xy 376.586244 -391.260917) (xy 376.046744 -391.260917)
			(xy 376.038614 -391.312252) (xy 376.022553 -391.361682) (xy 375.998957 -391.407992) (xy 375.968407 -391.45004)
			(xy 375.931656 -391.486791) (xy 375.889608 -391.517341) (xy 375.843298 -391.540937) (xy 375.793868 -391.556998)
			(xy 375.742533 -391.565128) (xy 375.690559 -391.565128) (xy 375.639224 -391.556998) (xy 375.589794 -391.540937)
			(xy 375.543484 -391.517341) (xy 375.501436 -391.486791) (xy 375.464685 -391.45004) (xy 375.434135 -391.407992)
			(xy 375.410539 -391.361682) (xy 375.394478 -391.312252) (xy 375.386348 -391.260917) (xy 374.846594 -391.260917)
			(xy 374.838464 -391.312252) (xy 374.822403 -391.361682) (xy 374.798807 -391.407992) (xy 374.768257 -391.45004)
			(xy 374.731506 -391.486791) (xy 374.689458 -391.517341) (xy 374.643148 -391.540937) (xy 374.593718 -391.556998)
			(xy 374.542383 -391.565128) (xy 374.490409 -391.565128) (xy 374.439074 -391.556998) (xy 374.389644 -391.540937)
			(xy 374.343334 -391.517341) (xy 374.301286 -391.486791) (xy 374.264535 -391.45004) (xy 374.233985 -391.407992)
			(xy 374.210389 -391.361682) (xy 374.194328 -391.312252) (xy 374.186198 -391.260917) (xy 373.646698 -391.260917)
			(xy 373.638568 -391.312252) (xy 373.622507 -391.361682) (xy 373.598911 -391.407992) (xy 373.568361 -391.45004)
			(xy 373.53161 -391.486791) (xy 373.489562 -391.517341) (xy 373.443252 -391.540937) (xy 373.393822 -391.556998)
			(xy 373.342487 -391.565128) (xy 373.290513 -391.565128) (xy 373.239178 -391.556998) (xy 373.189748 -391.540937)
			(xy 373.143438 -391.517341) (xy 373.10139 -391.486791) (xy 373.064639 -391.45004) (xy 373.034089 -391.407992)
			(xy 373.010493 -391.361682) (xy 372.994432 -391.312252) (xy 372.986302 -391.260917) (xy 372.446802 -391.260917)
			(xy 372.438672 -391.312252) (xy 372.422611 -391.361682) (xy 372.399015 -391.407992) (xy 372.368465 -391.45004)
			(xy 372.331714 -391.486791) (xy 372.289666 -391.517341) (xy 372.243356 -391.540937) (xy 372.193926 -391.556998)
			(xy 372.142591 -391.565128) (xy 372.090617 -391.565128) (xy 372.039282 -391.556998) (xy 371.989852 -391.540937)
			(xy 371.943542 -391.517341) (xy 371.901494 -391.486791) (xy 371.864743 -391.45004) (xy 371.834193 -391.407992)
			(xy 371.810597 -391.361682) (xy 371.794536 -391.312252) (xy 371.786406 -391.260917) (xy 371.246652 -391.260917)
			(xy 371.238522 -391.312252) (xy 371.222461 -391.361682) (xy 371.198865 -391.407992) (xy 371.168315 -391.45004)
			(xy 371.131564 -391.486791) (xy 371.089516 -391.517341) (xy 371.043206 -391.540937) (xy 370.993776 -391.556998)
			(xy 370.942441 -391.565128) (xy 370.890467 -391.565128) (xy 370.839132 -391.556998) (xy 370.789702 -391.540937)
			(xy 370.743392 -391.517341) (xy 370.701344 -391.486791) (xy 370.664593 -391.45004) (xy 370.634043 -391.407992)
			(xy 370.610447 -391.361682) (xy 370.594386 -391.312252) (xy 370.586256 -391.260917) (xy 369.898284 -391.260917)
			(xy 369.898773 -391.264006) (xy 369.898773 -391.315994) (xy 369.890639 -391.367343) (xy 369.874573 -391.416786)
			(xy 369.85097 -391.463108) (xy 369.820411 -391.505166) (xy 369.783648 -391.541927) (xy 369.741587 -391.572483)
			(xy 369.695264 -391.596083) (xy 369.645819 -391.612145) (xy 369.59447 -391.620275) (xy 369.568476 -391.620756)
			(xy 369.539883 -391.620135) (xy 369.483549 -391.610288) (xy 369.429746 -391.590908) (xy 369.380073 -391.562571)
			(xy 369.357656 -391.54481) (xy 369.357402 -391.544556) (xy 369.350406 -391.539281) (xy 369.333901 -391.533438)
			(xy 369.325144 -391.533126) (xy 369.26012 -391.533126) (xy 369.25152 -391.533485) (xy 369.235294 -391.53919)
			(xy 369.22837 -391.544302) (xy 369.227862 -391.54481) (xy 369.205535 -391.56243) (xy 369.156073 -391.590506)
			(xy 369.102532 -391.609688) (xy 369.046495 -391.619412) (xy 369.018058 -391.619994) (xy 368.994824 -391.619604)
			(xy 368.948813 -391.613105) (xy 368.904165 -391.600227) (xy 368.86176 -391.581224) (xy 368.822435 -391.55647)
			(xy 368.804444 -391.541762) (xy 368.797586 -391.53592) (xy 368.780568 -391.52957) (xy 368.696748 -391.52957)
			(xy 368.67973 -391.53592) (xy 368.672872 -391.541762) (xy 368.654863 -391.556446) (xy 368.61554 -391.581197)
			(xy 368.573139 -391.600202) (xy 368.528497 -391.613086) (xy 368.48249 -391.619597) (xy 368.459258 -391.619994)
			(xy 368.433272 -391.619509) (xy 368.38194 -391.611373) (xy 368.332513 -391.595308) (xy 368.286208 -391.571709)
			(xy 368.244163 -391.541157) (xy 368.207416 -391.504405) (xy 368.176869 -391.462356) (xy 368.153276 -391.416048)
			(xy 368.137217 -391.366619) (xy 368.129087 -391.315286) (xy 366.180784 -391.315286) (xy 366.192185 -391.338607)
			(xy 366.212668 -391.398274) (xy 366.225613 -391.460017) (xy 366.230822 -391.522887) (xy 366.228214 -391.585918)
			(xy 366.21783 -391.648142) (xy 366.199828 -391.708604) (xy 366.174486 -391.766376) (xy 366.142193 -391.820569)
			(xy 366.103445 -391.870351) (xy 366.058836 -391.914958) (xy 366.009052 -391.953704) (xy 365.954858 -391.985996)
			(xy 365.897086 -392.011335) (xy 365.836623 -392.029334) (xy 365.774398 -392.039716) (xy 365.711366 -392.042322)
			(xy 365.648497 -392.03711) (xy 365.586755 -392.024163) (xy 365.527089 -392.003677) (xy 365.470414 -391.975969)
			(xy 365.417603 -391.941463) (xy 365.369465 -391.900689) (xy 365.32674 -391.854275) (xy 365.290084 -391.802932)
			(xy 365.260061 -391.747449) (xy 365.237131 -391.688679) (xy 365.221647 -391.627523) (xy 365.213846 -391.564923)
			(xy 365.213392 -391.53338) (xy 365.213392 -391.532872) (xy 365.213757 -391.506001) (xy 365.219453 -391.45256)
			(xy 365.230746 -391.400017) (xy 365.238792 -391.374376) (xy 365.241332 -391.366756) (xy 365.241332 -391.358628)
			(xy 365.240849 -391.348614) (xy 365.233196 -391.330107) (xy 365.219043 -391.315938) (xy 365.200545 -391.308263)
			(xy 365.190532 -391.307828) (xy 365.166544 -391.307454) (xy 365.118951 -391.301407) (xy 365.072494 -391.289431)
			(xy 365.05007 -391.280904) (xy 365.049562 -391.280904) (xy 365.049308 -391.28065) (xy 365.043383 -391.278566)
			(xy 365.030923 -391.277017) (xy 365.02467 -391.277602) (xy 365.011716 -391.27938) (xy 364.931452 -391.338562)
			(xy 364.926403 -391.342492) (xy 364.918307 -391.352395) (xy 364.91545 -391.35812) (xy 364.910116 -391.369804)
			(xy 364.911132 -391.383012) (xy 364.912148 -391.41146) (xy 364.911662 -391.438711) (xy 364.903906 -391.492659)
			(xy 364.888551 -391.544954) (xy 364.865909 -391.594531) (xy 364.836443 -391.640381) (xy 364.800752 -391.681572)
			(xy 364.759561 -391.717263) (xy 364.713711 -391.746729) (xy 364.664134 -391.769371) (xy 364.611839 -391.784726)
			(xy 364.557891 -391.792482) (xy 364.503389 -391.792482) (xy 364.449441 -391.784726) (xy 364.397146 -391.769371)
			(xy 364.347569 -391.746729) (xy 364.301719 -391.717263) (xy 364.260528 -391.681572) (xy 364.224837 -391.640381)
			(xy 364.195371 -391.594531) (xy 364.172729 -391.544954) (xy 364.157374 -391.492659) (xy 364.149618 -391.438711)
			(xy 364.149132 -391.41146) (xy 364.150148 -391.383012) (xy 364.151164 -391.369804) (xy 364.14583 -391.35812)
			(xy 364.142956 -391.352406) (xy 364.134862 -391.342507) (xy 364.129828 -391.338562) (xy 364.060232 -391.287254)
			(xy 364.05495 -391.28353) (xy 364.042988 -391.278646) (xy 364.03661 -391.277602) (xy 364.02391 -391.276078)
			(xy 364.011718 -391.280904) (xy 364.01121 -391.280904) (xy 363.988776 -391.2894) (xy 363.942321 -391.301369)
			(xy 363.894734 -391.30743) (xy 363.870748 -391.307828) (xy 363.87024 -391.307828) (xy 363.843739 -391.307376)
			(xy 363.791248 -391.300043) (xy 363.740277 -391.285514) (xy 363.691808 -391.264067) (xy 363.646776 -391.236117)
			(xy 363.606047 -391.202201) (xy 363.570406 -391.162972) (xy 363.54054 -391.119187) (xy 363.517023 -391.071689)
			(xy 363.500309 -391.021392) (xy 363.495082 -390.995408) (xy 363.493132 -390.986676) (xy 363.484171 -390.971206)
			(xy 363.477556 -390.965182) (xy 363.470698 -390.959848) (xy 363.454188 -390.953752) (xy 359.433622 -390.953752)
			(xy 359.423559 -390.953313) (xy 359.40498 -390.945574) (xy 359.397554 -390.938766) (xy 359.316528 -390.85774)
			(xy 359.310456 -390.852037) (xy 359.295532 -390.844653) (xy 359.287318 -390.843262) (xy 359.28681 -390.843262)
			(xy 359.229842 -390.835869) (xy 359.117002 -390.814284) (xy 359.005898 -390.785046) (xy 358.897048 -390.748294)
			(xy 358.790961 -390.704197) (xy 358.688132 -390.652963) (xy 358.589039 -390.594829) (xy 358.54132 -390.562846)
			(xy 358.52989 -390.555226) (xy 358.502712 -390.553194) (xy 358.398826 -390.604502) (xy 358.383586 -390.627616)
			(xy 358.382824 -390.641078) (xy 358.380663 -390.669909) (xy 358.368734 -390.726478) (xy 358.348404 -390.780598)
			(xy 358.32014 -390.831031) (xy 358.284589 -390.876622) (xy 358.242564 -390.916324) (xy 358.19503 -390.94923)
			(xy 358.143073 -390.974586) (xy 358.087886 -390.99181) (xy 358.030731 -391.000508) (xy 358.001824 -391.000996)
			(xy 357.97457 -391.000534) (xy 357.920617 -390.99278) (xy 357.868317 -390.977426) (xy 357.818735 -390.954785)
			(xy 357.77288 -390.925317) (xy 357.731685 -390.889623) (xy 357.69599 -390.84843) (xy 357.666521 -390.802576)
			(xy 357.643878 -390.752994) (xy 357.628523 -390.700694) (xy 357.620767 -390.646742) (xy 357.620316 -390.619488)
			(xy 357.620779 -390.59257) (xy 357.628348 -390.539268) (xy 357.643333 -390.487559) (xy 357.665438 -390.43847)
			(xy 357.694223 -390.392975) (xy 357.729117 -390.351978) (xy 357.769427 -390.316292) (xy 357.814353 -390.286627)
			(xy 357.863002 -390.26357) (xy 357.91441 -390.247581) (xy 357.967554 -390.238975) (xy 357.994458 -390.23798)
			(xy 358.008174 -390.237726) (xy 358.031034 -390.22401) (xy 358.08031 -390.134602) (xy 358.08427 -390.126686)
			(xy 358.087067 -390.109223) (xy 358.08374 -390.091852) (xy 358.079548 -390.084056) (xy 358.052726 -390.038452)
			(xy 358.005315 -389.943862) (xy 357.96528 -389.84592) (xy 357.932858 -389.745202) (xy 357.908239 -389.642298)
			(xy 357.891566 -389.537812) (xy 357.886762 -389.485124) (xy 357.885599 -389.475706) (xy 357.877285 -389.458662)
			(xy 357.863351 -389.445799) (xy 357.845697 -389.438873) (xy 357.836216 -389.438388) (xy 355.917246 -389.438388)
			(xy 355.90734 -389.437372) (xy 332.737968 -389.437372) (xy 332.728088 -389.43784) (xy 332.709797 -389.445317)
			(xy 332.695687 -389.459149) (xy 332.687847 -389.477288) (xy 332.687168 -389.487156) (xy 332.686028 -389.515284)
			(xy 332.6765 -389.570765) (xy 332.658925 -389.624245) (xy 332.633683 -389.674562) (xy 332.601323 -389.720625)
			(xy 332.562548 -389.761434) (xy 332.518197 -389.796104) (xy 332.469235 -389.823882) (xy 332.416723 -389.844165)
			(xy 332.3618 -389.856514) (xy 332.30566 -389.860661) (xy 332.24952 -389.856514) (xy 332.194597 -389.844165)
			(xy 332.142085 -389.823882) (xy 332.093123 -389.796104) (xy 332.048772 -389.761434) (xy 332.009997 -389.720625)
			(xy 331.977637 -389.674562) (xy 331.952395 -389.624245) (xy 331.93482 -389.570765) (xy 331.925292 -389.515284)
			(xy 331.924152 -389.487156) (xy 331.923485 -389.477291) (xy 331.915641 -389.459161) (xy 331.901524 -389.445344)
			(xy 331.883229 -389.437892) (xy 331.873352 -389.437372) (xy 331.068934 -389.437372) (xy 331.062974 -389.437618)
			(xy 331.051417 -389.440561) (xy 331.046074 -389.443214) (xy 331.043026 -389.444738) (xy 331.037708 -389.448233)
			(xy 331.02884 -389.457355) (xy 331.0255 -389.462772) (xy 330.980034 -389.529066) (xy 330.97666 -389.534247)
			(xy 330.972291 -389.545808) (xy 330.971398 -389.551926) (xy 330.970128 -389.56361) (xy 330.9747 -389.575548)
			(xy 330.982739 -389.597424) (xy 330.994042 -389.64264) (xy 330.999749 -389.688897) (xy 331.0001 -389.7122)
			(xy 330.999637 -389.739453) (xy 330.99188 -389.793403) (xy 330.976524 -389.845701) (xy 330.953881 -389.89528)
			(xy 330.924413 -389.941133) (xy 330.888719 -389.982325) (xy 330.847526 -390.018018) (xy 330.801673 -390.047485)
			(xy 330.752093 -390.070126) (xy 330.699795 -390.085481) (xy 330.645845 -390.093237) (xy 330.618592 -390.093708)
			(xy 330.589154 -390.093164) (xy 330.530978 -390.084107) (xy 330.502768 -390.075674) (xy 330.493878 -390.07288)
			(xy 330.485242 -390.073134) (xy 330.480587 -390.073468) (xy 330.471514 -390.07565) (xy 330.467208 -390.077452)
			(xy 330.448158 -390.08558) (xy 330.439776 -390.089136) (xy 330.414122 -390.113012) (xy 330.410058 -390.120886)
			(xy 330.402465 -390.135315) (xy 330.385688 -390.163276) (xy 330.37653 -390.176766) (xy 330.351892 -390.209278)
			(xy 330.350876 -390.210548) (xy 330.346558 -390.216644) (xy 330.343855 -390.221595) (xy 330.340517 -390.232368)
			(xy 330.339954 -390.23798) (xy 330.339954 -390.238996) (xy 330.3397 -390.242044) (xy 330.3397 -390.396476)
			(xy 330.339954 -390.399524) (xy 330.339954 -390.40054) (xy 330.34056 -390.406144) (xy 330.343894 -390.416909)
			(xy 330.346558 -390.421876) (xy 330.350876 -390.427972) (xy 330.351892 -390.429242) (xy 330.376276 -390.461754)
			(xy 330.385498 -390.47524) (xy 330.402403 -390.503201) (xy 330.410058 -390.517634) (xy 330.414122 -390.525508)
			(xy 330.434696 -390.544558) (xy 330.445872 -390.551924) (xy 330.453746 -390.555226) (xy 330.467208 -390.560814)
			(xy 330.4737 -390.563293) (xy 330.487491 -390.564979) (xy 330.494386 -390.564116) (xy 330.50226 -390.5631)
			(xy 330.505816 -390.56183) (xy 330.533144 -390.553922) (xy 330.589387 -390.545376) (xy 330.61783 -390.544812)
			(xy 330.618592 -390.544812) (xy 330.645844 -390.545275) (xy 330.699793 -390.55303) (xy 330.752089 -390.568385)
			(xy 330.801667 -390.591026) (xy 330.847519 -390.620492) (xy 330.888711 -390.656184) (xy 330.924403 -390.697375)
			(xy 330.95387 -390.743226) (xy 330.976512 -390.792804) (xy 330.991868 -390.845099) (xy 330.999625 -390.899048)
			(xy 330.999625 -390.953552) (xy 330.991868 -391.007501) (xy 330.976512 -391.059796) (xy 330.95387 -391.109374)
			(xy 330.924403 -391.155225) (xy 330.888711 -391.196416) (xy 330.847519 -391.232108) (xy 330.801667 -391.261574)
			(xy 330.752089 -391.284215) (xy 330.699793 -391.29957) (xy 330.645844 -391.307325) (xy 330.618592 -391.307828)
			(xy 330.618084 -391.307828) (xy 330.594097 -391.307451) (xy 330.546505 -391.301399) (xy 330.500051 -391.289417)
			(xy 330.477622 -391.280904) (xy 330.477114 -391.280904) (xy 330.47686 -391.28065) (xy 330.470935 -391.278571)
			(xy 330.458476 -391.277034) (xy 330.452222 -391.277602) (xy 330.439268 -391.27938) (xy 330.390565 -391.315291)
			(xy 333.556561 -391.315291) (xy 333.556561 -391.263309) (xy 333.564693 -391.211967) (xy 333.580757 -391.16253)
			(xy 333.604356 -391.116214) (xy 333.634911 -391.07416) (xy 333.671668 -391.037404) (xy 333.713723 -391.006851)
			(xy 333.760039 -390.983253) (xy 333.809477 -390.967191) (xy 333.860819 -390.95906) (xy 333.88681 -390.958578)
			(xy 333.910008 -390.958961) (xy 333.955948 -390.965453) (xy 334.000533 -390.978294) (xy 334.042888 -390.997233)
			(xy 334.082184 -391.021899) (xy 334.10017 -391.036556) (xy 334.107518 -391.04218) (xy 334.124956 -391.048315)
			(xy 334.134206 -391.048494) (xy 334.201008 -391.047224) (xy 334.210288 -391.04661) (xy 334.227485 -391.039572)
			(xy 334.234536 -391.033508) (xy 334.252953 -391.01716) (xy 334.293734 -390.989556) (xy 334.338157 -390.968303)
			(xy 334.38524 -390.953872) (xy 334.433942 -390.94658) (xy 334.458564 -390.946132) (xy 334.483423 -390.946569)
			(xy 334.532579 -390.954016) (xy 334.580073 -390.968718) (xy 334.624839 -390.990347) (xy 334.665875 -391.018416)
			(xy 334.68437 -391.035032) (xy 334.691372 -391.041051) (xy 334.708434 -391.048077) (xy 334.717644 -391.048748)
			(xy 334.748886 -391.04951) (xy 334.758141 -391.049354) (xy 334.775594 -391.043229) (xy 334.782922 -391.037572)
			(xy 334.805455 -391.019365) (xy 334.855596 -390.990358) (xy 334.910019 -390.970516) (xy 334.967064 -390.960443)
			(xy 334.996028 -390.959848) (xy 335.02201 -390.960448) (xy 335.073334 -390.968581) (xy 335.122755 -390.984642)
			(xy 335.169054 -391.008236) (xy 335.211093 -391.038783) (xy 335.247836 -391.075529) (xy 335.278378 -391.11757)
			(xy 335.301968 -391.163871) (xy 335.318026 -391.213293) (xy 335.325568 -391.260917) (xy 336.013808 -391.260917)
			(xy 336.013808 -391.208943) (xy 336.021938 -391.157608) (xy 336.037999 -391.108178) (xy 336.061595 -391.061868)
			(xy 336.092145 -391.01982) (xy 336.128896 -390.983069) (xy 336.170944 -390.952519) (xy 336.217254 -390.928923)
			(xy 336.266684 -390.912862) (xy 336.318019 -390.904732) (xy 336.369993 -390.904732) (xy 336.421328 -390.912862)
			(xy 336.470758 -390.928923) (xy 336.517068 -390.952519) (xy 336.559116 -390.983069) (xy 336.595867 -391.01982)
			(xy 336.626417 -391.061868) (xy 336.650013 -391.108178) (xy 336.666074 -391.157608) (xy 336.674204 -391.208943)
			(xy 336.674714 -391.23493) (xy 336.674204 -391.260917) (xy 337.213958 -391.260917) (xy 337.213958 -391.208943)
			(xy 337.222088 -391.157608) (xy 337.238149 -391.108178) (xy 337.261745 -391.061868) (xy 337.292295 -391.01982)
			(xy 337.329046 -390.983069) (xy 337.371094 -390.952519) (xy 337.417404 -390.928923) (xy 337.466834 -390.912862)
			(xy 337.518169 -390.904732) (xy 337.570143 -390.904732) (xy 337.621478 -390.912862) (xy 337.670908 -390.928923)
			(xy 337.717218 -390.952519) (xy 337.759266 -390.983069) (xy 337.796017 -391.01982) (xy 337.826567 -391.061868)
			(xy 337.850163 -391.108178) (xy 337.866224 -391.157608) (xy 337.874354 -391.208943) (xy 337.874864 -391.23493)
			(xy 337.874354 -391.260917) (xy 338.413854 -391.260917) (xy 338.413854 -391.208943) (xy 338.421984 -391.157608)
			(xy 338.438045 -391.108178) (xy 338.461641 -391.061868) (xy 338.492191 -391.01982) (xy 338.528942 -390.983069)
			(xy 338.57099 -390.952519) (xy 338.6173 -390.928923) (xy 338.66673 -390.912862) (xy 338.718065 -390.904732)
			(xy 338.770039 -390.904732) (xy 338.821374 -390.912862) (xy 338.870804 -390.928923) (xy 338.917114 -390.952519)
			(xy 338.959162 -390.983069) (xy 338.995913 -391.01982) (xy 339.026463 -391.061868) (xy 339.050059 -391.108178)
			(xy 339.06612 -391.157608) (xy 339.07425 -391.208943) (xy 339.07476 -391.23493) (xy 339.07425 -391.260917)
			(xy 339.61375 -391.260917) (xy 339.61375 -391.208943) (xy 339.62188 -391.157608) (xy 339.637941 -391.108178)
			(xy 339.661537 -391.061868) (xy 339.692087 -391.01982) (xy 339.728838 -390.983069) (xy 339.770886 -390.952519)
			(xy 339.817196 -390.928923) (xy 339.866626 -390.912862) (xy 339.917961 -390.904732) (xy 339.969935 -390.904732)
			(xy 340.02127 -390.912862) (xy 340.0707 -390.928923) (xy 340.11701 -390.952519) (xy 340.159058 -390.983069)
			(xy 340.195809 -391.01982) (xy 340.226359 -391.061868) (xy 340.249955 -391.108178) (xy 340.266016 -391.157608)
			(xy 340.274146 -391.208943) (xy 340.274656 -391.23493) (xy 340.274146 -391.260917) (xy 340.8139 -391.260917)
			(xy 340.8139 -391.208943) (xy 340.82203 -391.157608) (xy 340.838091 -391.108178) (xy 340.861687 -391.061868)
			(xy 340.892237 -391.01982) (xy 340.928988 -390.983069) (xy 340.971036 -390.952519) (xy 341.017346 -390.928923)
			(xy 341.066776 -390.912862) (xy 341.118111 -390.904732) (xy 341.170085 -390.904732) (xy 341.22142 -390.912862)
			(xy 341.27085 -390.928923) (xy 341.31716 -390.952519) (xy 341.359208 -390.983069) (xy 341.395959 -391.01982)
			(xy 341.426509 -391.061868) (xy 341.450105 -391.108178) (xy 341.466166 -391.157608) (xy 341.474296 -391.208943)
			(xy 341.474806 -391.23493) (xy 341.474296 -391.260917) (xy 342.013796 -391.260917) (xy 342.013796 -391.208943)
			(xy 342.021926 -391.157608) (xy 342.037987 -391.108178) (xy 342.061583 -391.061868) (xy 342.092133 -391.01982)
			(xy 342.128884 -390.983069) (xy 342.170932 -390.952519) (xy 342.217242 -390.928923) (xy 342.266672 -390.912862)
			(xy 342.318007 -390.904732) (xy 342.369981 -390.904732) (xy 342.421316 -390.912862) (xy 342.470746 -390.928923)
			(xy 342.517056 -390.952519) (xy 342.559104 -390.983069) (xy 342.595855 -391.01982) (xy 342.626405 -391.061868)
			(xy 342.650001 -391.108178) (xy 342.666062 -391.157608) (xy 342.674192 -391.208943) (xy 342.674702 -391.23493)
			(xy 342.674192 -391.260917) (xy 343.213946 -391.260917) (xy 343.213946 -391.208943) (xy 343.222076 -391.157608)
			(xy 343.238137 -391.108178) (xy 343.261733 -391.061868) (xy 343.292283 -391.01982) (xy 343.329034 -390.983069)
			(xy 343.371082 -390.952519) (xy 343.417392 -390.928923) (xy 343.466822 -390.912862) (xy 343.518157 -390.904732)
			(xy 343.570131 -390.904732) (xy 343.621466 -390.912862) (xy 343.670896 -390.928923) (xy 343.717206 -390.952519)
			(xy 343.759254 -390.983069) (xy 343.796005 -391.01982) (xy 343.826555 -391.061868) (xy 343.850151 -391.108178)
			(xy 343.866212 -391.157608) (xy 343.874342 -391.208943) (xy 343.874852 -391.23493) (xy 343.874342 -391.260917)
			(xy 344.413842 -391.260917) (xy 344.413842 -391.208943) (xy 344.421972 -391.157608) (xy 344.438033 -391.108178)
			(xy 344.461629 -391.061868) (xy 344.492179 -391.01982) (xy 344.52893 -390.983069) (xy 344.570978 -390.952519)
			(xy 344.617288 -390.928923) (xy 344.666718 -390.912862) (xy 344.718053 -390.904732) (xy 344.770027 -390.904732)
			(xy 344.821362 -390.912862) (xy 344.870792 -390.928923) (xy 344.917102 -390.952519) (xy 344.95915 -390.983069)
			(xy 344.995901 -391.01982) (xy 345.026451 -391.061868) (xy 345.050047 -391.108178) (xy 345.066108 -391.157608)
			(xy 345.074238 -391.208943) (xy 345.074748 -391.23493) (xy 345.074238 -391.260917) (xy 345.613738 -391.260917)
			(xy 345.613738 -391.208943) (xy 345.621868 -391.157608) (xy 345.637929 -391.108178) (xy 345.661525 -391.061868)
			(xy 345.692075 -391.01982) (xy 345.728826 -390.983069) (xy 345.770874 -390.952519) (xy 345.817184 -390.928923)
			(xy 345.866614 -390.912862) (xy 345.917949 -390.904732) (xy 345.969923 -390.904732) (xy 346.021258 -390.912862)
			(xy 346.070688 -390.928923) (xy 346.116998 -390.952519) (xy 346.159046 -390.983069) (xy 346.195797 -391.01982)
			(xy 346.226347 -391.061868) (xy 346.249943 -391.108178) (xy 346.266004 -391.157608) (xy 346.274134 -391.208943)
			(xy 346.274644 -391.23493) (xy 346.274134 -391.260917) (xy 346.813888 -391.260917) (xy 346.813888 -391.208943)
			(xy 346.822018 -391.157608) (xy 346.838079 -391.108178) (xy 346.861675 -391.061868) (xy 346.892225 -391.01982)
			(xy 346.928976 -390.983069) (xy 346.971024 -390.952519) (xy 347.017334 -390.928923) (xy 347.066764 -390.912862)
			(xy 347.118099 -390.904732) (xy 347.170073 -390.904732) (xy 347.221408 -390.912862) (xy 347.270838 -390.928923)
			(xy 347.317148 -390.952519) (xy 347.359196 -390.983069) (xy 347.395947 -391.01982) (xy 347.426497 -391.061868)
			(xy 347.450093 -391.108178) (xy 347.466154 -391.157608) (xy 347.474284 -391.208943) (xy 347.474794 -391.23493)
			(xy 347.474284 -391.260917) (xy 348.013784 -391.260917) (xy 348.013784 -391.208943) (xy 348.021914 -391.157608)
			(xy 348.037975 -391.108178) (xy 348.061571 -391.061868) (xy 348.092121 -391.01982) (xy 348.128872 -390.983069)
			(xy 348.17092 -390.952519) (xy 348.21723 -390.928923) (xy 348.26666 -390.912862) (xy 348.317995 -390.904732)
			(xy 348.369969 -390.904732) (xy 348.421304 -390.912862) (xy 348.470734 -390.928923) (xy 348.517044 -390.952519)
			(xy 348.559092 -390.983069) (xy 348.595843 -391.01982) (xy 348.626393 -391.061868) (xy 348.649989 -391.108178)
			(xy 348.66605 -391.157608) (xy 348.67418 -391.208943) (xy 348.67469 -391.23493) (xy 348.67418 -391.260917)
			(xy 349.213934 -391.260917) (xy 349.213934 -391.208943) (xy 349.222064 -391.157608) (xy 349.238125 -391.108178)
			(xy 349.261721 -391.061868) (xy 349.292271 -391.01982) (xy 349.329022 -390.983069) (xy 349.37107 -390.952519)
			(xy 349.41738 -390.928923) (xy 349.46681 -390.912862) (xy 349.518145 -390.904732) (xy 349.570119 -390.904732)
			(xy 349.621454 -390.912862) (xy 349.670884 -390.928923) (xy 349.717194 -390.952519) (xy 349.759242 -390.983069)
			(xy 349.795993 -391.01982) (xy 349.826543 -391.061868) (xy 349.850139 -391.108178) (xy 349.8662 -391.157608)
			(xy 349.87433 -391.208943) (xy 349.87484 -391.23493) (xy 349.87433 -391.260917) (xy 350.41383 -391.260917)
			(xy 350.41383 -391.208943) (xy 350.42196 -391.157608) (xy 350.438021 -391.108178) (xy 350.461617 -391.061868)
			(xy 350.492167 -391.01982) (xy 350.528918 -390.983069) (xy 350.570966 -390.952519) (xy 350.617276 -390.928923)
			(xy 350.666706 -390.912862) (xy 350.718041 -390.904732) (xy 350.770015 -390.904732) (xy 350.82135 -390.912862)
			(xy 350.87078 -390.928923) (xy 350.91709 -390.952519) (xy 350.959138 -390.983069) (xy 350.995889 -391.01982)
			(xy 351.026439 -391.061868) (xy 351.050035 -391.108178) (xy 351.066096 -391.157608) (xy 351.074226 -391.208943)
			(xy 351.074736 -391.23493) (xy 351.074226 -391.260917) (xy 351.613726 -391.260917) (xy 351.613726 -391.208943)
			(xy 351.621856 -391.157608) (xy 351.637917 -391.108178) (xy 351.661513 -391.061868) (xy 351.692063 -391.01982)
			(xy 351.728814 -390.983069) (xy 351.770862 -390.952519) (xy 351.817172 -390.928923) (xy 351.866602 -390.912862)
			(xy 351.917937 -390.904732) (xy 351.969911 -390.904732) (xy 352.021246 -390.912862) (xy 352.070676 -390.928923)
			(xy 352.116986 -390.952519) (xy 352.159034 -390.983069) (xy 352.195785 -391.01982) (xy 352.226335 -391.061868)
			(xy 352.249931 -391.108178) (xy 352.265992 -391.157608) (xy 352.274122 -391.208943) (xy 352.274632 -391.23493)
			(xy 352.274122 -391.260917) (xy 352.813876 -391.260917) (xy 352.813876 -391.208943) (xy 352.822006 -391.157608)
			(xy 352.838067 -391.108178) (xy 352.861663 -391.061868) (xy 352.892213 -391.01982) (xy 352.928964 -390.983069)
			(xy 352.971012 -390.952519) (xy 353.017322 -390.928923) (xy 353.066752 -390.912862) (xy 353.118087 -390.904732)
			(xy 353.170061 -390.904732) (xy 353.221396 -390.912862) (xy 353.270826 -390.928923) (xy 353.317136 -390.952519)
			(xy 353.359184 -390.983069) (xy 353.395935 -391.01982) (xy 353.426485 -391.061868) (xy 353.450081 -391.108178)
			(xy 353.466142 -391.157608) (xy 353.474272 -391.208943) (xy 353.474782 -391.23493) (xy 353.474272 -391.260917)
			(xy 354.013772 -391.260917) (xy 354.013772 -391.208943) (xy 354.021902 -391.157608) (xy 354.037963 -391.108178)
			(xy 354.061559 -391.061868) (xy 354.092109 -391.01982) (xy 354.12886 -390.983069) (xy 354.170908 -390.952519)
			(xy 354.217218 -390.928923) (xy 354.266648 -390.912862) (xy 354.317983 -390.904732) (xy 354.369957 -390.904732)
			(xy 354.421292 -390.912862) (xy 354.470722 -390.928923) (xy 354.517032 -390.952519) (xy 354.55908 -390.983069)
			(xy 354.595831 -391.01982) (xy 354.626381 -391.061868) (xy 354.649977 -391.108178) (xy 354.666038 -391.157608)
			(xy 354.674168 -391.208943) (xy 354.674678 -391.23493) (xy 354.674168 -391.260917) (xy 354.671749 -391.276193)
			(xy 355.080745 -391.276193) (xy 355.080745 -391.224207) (xy 355.088878 -391.172862) (xy 355.104943 -391.123421)
			(xy 355.128545 -391.077102) (xy 355.159103 -391.035045) (xy 355.195864 -390.998287) (xy 355.237922 -390.967733)
			(xy 355.284243 -390.944134) (xy 355.333685 -390.928072) (xy 355.385031 -390.919943) (xy 355.411024 -390.919462)
			(xy 355.434799 -390.919839) (xy 355.48186 -390.926648) (xy 355.527458 -390.940135) (xy 355.57065 -390.960021)
			(xy 355.610544 -390.985897) (xy 355.628702 -391.00125) (xy 355.635806 -391.006959) (xy 355.652869 -391.013329)
			(xy 355.661976 -391.013696) (xy 355.693472 -391.013696) (xy 355.702571 -391.013288) (xy 355.719622 -391.006923)
			(xy 355.726746 -391.00125) (xy 355.744929 -390.985931) (xy 355.784824 -390.96007) (xy 355.828011 -390.94019)
			(xy 355.873601 -390.9267) (xy 355.920652 -390.91988) (xy 355.944424 -390.919462) (xy 355.970408 -390.920033)
			(xy 356.021735 -390.928166) (xy 356.071157 -390.944228) (xy 356.117459 -390.967823) (xy 356.1595 -390.99837)
			(xy 356.196245 -391.035118) (xy 356.22679 -391.077161) (xy 356.250381 -391.123465) (xy 356.26644 -391.172889)
			(xy 356.274569 -391.224216) (xy 356.274569 -391.276184) (xy 356.26644 -391.327511) (xy 356.250382 -391.376935)
			(xy 356.22679 -391.423239) (xy 356.196245 -391.465282) (xy 356.1595 -391.50203) (xy 356.117459 -391.532577)
			(xy 356.071157 -391.556172) (xy 356.021735 -391.572234) (xy 355.970408 -391.580367) (xy 355.944424 -391.580878)
			(xy 355.92065 -391.580463) (xy 355.873592 -391.573662) (xy 355.827995 -391.560183) (xy 355.784802 -391.540305)
			(xy 355.744906 -391.514439) (xy 355.726746 -391.49909) (xy 355.719633 -391.493394) (xy 355.702577 -391.487018)
			(xy 355.693472 -391.486644) (xy 355.661976 -391.486644) (xy 355.652873 -391.487018) (xy 355.635823 -391.493406)
			(xy 355.628702 -391.49909) (xy 355.610544 -391.51444) (xy 355.570642 -391.540295) (xy 355.527448 -391.560169)
			(xy 355.481853 -391.573651) (xy 355.434797 -391.580464) (xy 355.411024 -391.580878) (xy 355.385031 -391.580457)
			(xy 355.333685 -391.572328) (xy 355.284243 -391.556266) (xy 355.237922 -391.532667) (xy 355.195864 -391.502113)
			(xy 355.159103 -391.465355) (xy 355.128545 -391.423298) (xy 355.104943 -391.376979) (xy 355.088878 -391.327538)
			(xy 355.080745 -391.276193) (xy 354.671749 -391.276193) (xy 354.666038 -391.312252) (xy 354.649977 -391.361682)
			(xy 354.626381 -391.407992) (xy 354.595831 -391.45004) (xy 354.55908 -391.486791) (xy 354.517032 -391.517341)
			(xy 354.470722 -391.540937) (xy 354.421292 -391.556998) (xy 354.369957 -391.565128) (xy 354.317983 -391.565128)
			(xy 354.266648 -391.556998) (xy 354.217218 -391.540937) (xy 354.170908 -391.517341) (xy 354.12886 -391.486791)
			(xy 354.092109 -391.45004) (xy 354.061559 -391.407992) (xy 354.037963 -391.361682) (xy 354.021902 -391.312252)
			(xy 354.013772 -391.260917) (xy 353.474272 -391.260917) (xy 353.466142 -391.312252) (xy 353.450081 -391.361682)
			(xy 353.426485 -391.407992) (xy 353.395935 -391.45004) (xy 353.359184 -391.486791) (xy 353.317136 -391.517341)
			(xy 353.270826 -391.540937) (xy 353.221396 -391.556998) (xy 353.170061 -391.565128) (xy 353.118087 -391.565128)
			(xy 353.066752 -391.556998) (xy 353.017322 -391.540937) (xy 352.971012 -391.517341) (xy 352.928964 -391.486791)
			(xy 352.892213 -391.45004) (xy 352.861663 -391.407992) (xy 352.838067 -391.361682) (xy 352.822006 -391.312252)
			(xy 352.813876 -391.260917) (xy 352.274122 -391.260917) (xy 352.265992 -391.312252) (xy 352.249931 -391.361682)
			(xy 352.226335 -391.407992) (xy 352.195785 -391.45004) (xy 352.159034 -391.486791) (xy 352.116986 -391.517341)
			(xy 352.070676 -391.540937) (xy 352.021246 -391.556998) (xy 351.969911 -391.565128) (xy 351.917937 -391.565128)
			(xy 351.866602 -391.556998) (xy 351.817172 -391.540937) (xy 351.770862 -391.517341) (xy 351.728814 -391.486791)
			(xy 351.692063 -391.45004) (xy 351.661513 -391.407992) (xy 351.637917 -391.361682) (xy 351.621856 -391.312252)
			(xy 351.613726 -391.260917) (xy 351.074226 -391.260917) (xy 351.066096 -391.312252) (xy 351.050035 -391.361682)
			(xy 351.026439 -391.407992) (xy 350.995889 -391.45004) (xy 350.959138 -391.486791) (xy 350.91709 -391.517341)
			(xy 350.87078 -391.540937) (xy 350.82135 -391.556998) (xy 350.770015 -391.565128) (xy 350.718041 -391.565128)
			(xy 350.666706 -391.556998) (xy 350.617276 -391.540937) (xy 350.570966 -391.517341) (xy 350.528918 -391.486791)
			(xy 350.492167 -391.45004) (xy 350.461617 -391.407992) (xy 350.438021 -391.361682) (xy 350.42196 -391.312252)
			(xy 350.41383 -391.260917) (xy 349.87433 -391.260917) (xy 349.8662 -391.312252) (xy 349.850139 -391.361682)
			(xy 349.826543 -391.407992) (xy 349.795993 -391.45004) (xy 349.759242 -391.486791) (xy 349.717194 -391.517341)
			(xy 349.670884 -391.540937) (xy 349.621454 -391.556998) (xy 349.570119 -391.565128) (xy 349.518145 -391.565128)
			(xy 349.46681 -391.556998) (xy 349.41738 -391.540937) (xy 349.37107 -391.517341) (xy 349.329022 -391.486791)
			(xy 349.292271 -391.45004) (xy 349.261721 -391.407992) (xy 349.238125 -391.361682) (xy 349.222064 -391.312252)
			(xy 349.213934 -391.260917) (xy 348.67418 -391.260917) (xy 348.66605 -391.312252) (xy 348.649989 -391.361682)
			(xy 348.626393 -391.407992) (xy 348.595843 -391.45004) (xy 348.559092 -391.486791) (xy 348.517044 -391.517341)
			(xy 348.470734 -391.540937) (xy 348.421304 -391.556998) (xy 348.369969 -391.565128) (xy 348.317995 -391.565128)
			(xy 348.26666 -391.556998) (xy 348.21723 -391.540937) (xy 348.17092 -391.517341) (xy 348.128872 -391.486791)
			(xy 348.092121 -391.45004) (xy 348.061571 -391.407992) (xy 348.037975 -391.361682) (xy 348.021914 -391.312252)
			(xy 348.013784 -391.260917) (xy 347.474284 -391.260917) (xy 347.466154 -391.312252) (xy 347.450093 -391.361682)
			(xy 347.426497 -391.407992) (xy 347.395947 -391.45004) (xy 347.359196 -391.486791) (xy 347.317148 -391.517341)
			(xy 347.270838 -391.540937) (xy 347.221408 -391.556998) (xy 347.170073 -391.565128) (xy 347.118099 -391.565128)
			(xy 347.066764 -391.556998) (xy 347.017334 -391.540937) (xy 346.971024 -391.517341) (xy 346.928976 -391.486791)
			(xy 346.892225 -391.45004) (xy 346.861675 -391.407992) (xy 346.838079 -391.361682) (xy 346.822018 -391.312252)
			(xy 346.813888 -391.260917) (xy 346.274134 -391.260917) (xy 346.266004 -391.312252) (xy 346.249943 -391.361682)
			(xy 346.226347 -391.407992) (xy 346.195797 -391.45004) (xy 346.159046 -391.486791) (xy 346.116998 -391.517341)
			(xy 346.070688 -391.540937) (xy 346.021258 -391.556998) (xy 345.969923 -391.565128) (xy 345.917949 -391.565128)
			(xy 345.866614 -391.556998) (xy 345.817184 -391.540937) (xy 345.770874 -391.517341) (xy 345.728826 -391.486791)
			(xy 345.692075 -391.45004) (xy 345.661525 -391.407992) (xy 345.637929 -391.361682) (xy 345.621868 -391.312252)
			(xy 345.613738 -391.260917) (xy 345.074238 -391.260917) (xy 345.066108 -391.312252) (xy 345.050047 -391.361682)
			(xy 345.026451 -391.407992) (xy 344.995901 -391.45004) (xy 344.95915 -391.486791) (xy 344.917102 -391.517341)
			(xy 344.870792 -391.540937) (xy 344.821362 -391.556998) (xy 344.770027 -391.565128) (xy 344.718053 -391.565128)
			(xy 344.666718 -391.556998) (xy 344.617288 -391.540937) (xy 344.570978 -391.517341) (xy 344.52893 -391.486791)
			(xy 344.492179 -391.45004) (xy 344.461629 -391.407992) (xy 344.438033 -391.361682) (xy 344.421972 -391.312252)
			(xy 344.413842 -391.260917) (xy 343.874342 -391.260917) (xy 343.866212 -391.312252) (xy 343.850151 -391.361682)
			(xy 343.826555 -391.407992) (xy 343.796005 -391.45004) (xy 343.759254 -391.486791) (xy 343.717206 -391.517341)
			(xy 343.670896 -391.540937) (xy 343.621466 -391.556998) (xy 343.570131 -391.565128) (xy 343.518157 -391.565128)
			(xy 343.466822 -391.556998) (xy 343.417392 -391.540937) (xy 343.371082 -391.517341) (xy 343.329034 -391.486791)
			(xy 343.292283 -391.45004) (xy 343.261733 -391.407992) (xy 343.238137 -391.361682) (xy 343.222076 -391.312252)
			(xy 343.213946 -391.260917) (xy 342.674192 -391.260917) (xy 342.666062 -391.312252) (xy 342.650001 -391.361682)
			(xy 342.626405 -391.407992) (xy 342.595855 -391.45004) (xy 342.559104 -391.486791) (xy 342.517056 -391.517341)
			(xy 342.470746 -391.540937) (xy 342.421316 -391.556998) (xy 342.369981 -391.565128) (xy 342.318007 -391.565128)
			(xy 342.266672 -391.556998) (xy 342.217242 -391.540937) (xy 342.170932 -391.517341) (xy 342.128884 -391.486791)
			(xy 342.092133 -391.45004) (xy 342.061583 -391.407992) (xy 342.037987 -391.361682) (xy 342.021926 -391.312252)
			(xy 342.013796 -391.260917) (xy 341.474296 -391.260917) (xy 341.466166 -391.312252) (xy 341.450105 -391.361682)
			(xy 341.426509 -391.407992) (xy 341.395959 -391.45004) (xy 341.359208 -391.486791) (xy 341.31716 -391.517341)
			(xy 341.27085 -391.540937) (xy 341.22142 -391.556998) (xy 341.170085 -391.565128) (xy 341.118111 -391.565128)
			(xy 341.066776 -391.556998) (xy 341.017346 -391.540937) (xy 340.971036 -391.517341) (xy 340.928988 -391.486791)
			(xy 340.892237 -391.45004) (xy 340.861687 -391.407992) (xy 340.838091 -391.361682) (xy 340.82203 -391.312252)
			(xy 340.8139 -391.260917) (xy 340.274146 -391.260917) (xy 340.266016 -391.312252) (xy 340.249955 -391.361682)
			(xy 340.226359 -391.407992) (xy 340.195809 -391.45004) (xy 340.159058 -391.486791) (xy 340.11701 -391.517341)
			(xy 340.0707 -391.540937) (xy 340.02127 -391.556998) (xy 339.969935 -391.565128) (xy 339.917961 -391.565128)
			(xy 339.866626 -391.556998) (xy 339.817196 -391.540937) (xy 339.770886 -391.517341) (xy 339.728838 -391.486791)
			(xy 339.692087 -391.45004) (xy 339.661537 -391.407992) (xy 339.637941 -391.361682) (xy 339.62188 -391.312252)
			(xy 339.61375 -391.260917) (xy 339.07425 -391.260917) (xy 339.06612 -391.312252) (xy 339.050059 -391.361682)
			(xy 339.026463 -391.407992) (xy 338.995913 -391.45004) (xy 338.959162 -391.486791) (xy 338.917114 -391.517341)
			(xy 338.870804 -391.540937) (xy 338.821374 -391.556998) (xy 338.770039 -391.565128) (xy 338.718065 -391.565128)
			(xy 338.66673 -391.556998) (xy 338.6173 -391.540937) (xy 338.57099 -391.517341) (xy 338.528942 -391.486791)
			(xy 338.492191 -391.45004) (xy 338.461641 -391.407992) (xy 338.438045 -391.361682) (xy 338.421984 -391.312252)
			(xy 338.413854 -391.260917) (xy 337.874354 -391.260917) (xy 337.866224 -391.312252) (xy 337.850163 -391.361682)
			(xy 337.826567 -391.407992) (xy 337.796017 -391.45004) (xy 337.759266 -391.486791) (xy 337.717218 -391.517341)
			(xy 337.670908 -391.540937) (xy 337.621478 -391.556998) (xy 337.570143 -391.565128) (xy 337.518169 -391.565128)
			(xy 337.466834 -391.556998) (xy 337.417404 -391.540937) (xy 337.371094 -391.517341) (xy 337.329046 -391.486791)
			(xy 337.292295 -391.45004) (xy 337.261745 -391.407992) (xy 337.238149 -391.361682) (xy 337.222088 -391.312252)
			(xy 337.213958 -391.260917) (xy 336.674204 -391.260917) (xy 336.666074 -391.312252) (xy 336.650013 -391.361682)
			(xy 336.626417 -391.407992) (xy 336.595867 -391.45004) (xy 336.559116 -391.486791) (xy 336.517068 -391.517341)
			(xy 336.470758 -391.540937) (xy 336.421328 -391.556998) (xy 336.369993 -391.565128) (xy 336.318019 -391.565128)
			(xy 336.266684 -391.556998) (xy 336.217254 -391.540937) (xy 336.170944 -391.517341) (xy 336.128896 -391.486791)
			(xy 336.092145 -391.45004) (xy 336.061595 -391.407992) (xy 336.037999 -391.361682) (xy 336.021938 -391.312252)
			(xy 336.013808 -391.260917) (xy 335.325568 -391.260917) (xy 335.326154 -391.264618) (xy 335.326154 -391.316582)
			(xy 335.318026 -391.367907) (xy 335.301968 -391.417329) (xy 335.278378 -391.46363) (xy 335.247836 -391.505671)
			(xy 335.211093 -391.542417) (xy 335.169054 -391.572964) (xy 335.122755 -391.596558) (xy 335.073334 -391.612619)
			(xy 335.02201 -391.620752) (xy 334.996028 -391.621264) (xy 334.971169 -391.620833) (xy 334.922012 -391.613385)
			(xy 334.874518 -391.598681) (xy 334.829752 -391.577051) (xy 334.788717 -391.548981) (xy 334.770222 -391.532364)
			(xy 334.763223 -391.526341) (xy 334.746158 -391.519318) (xy 334.736948 -391.518648) (xy 334.705706 -391.517886)
			(xy 334.69645 -391.518039) (xy 334.678997 -391.524166) (xy 334.67167 -391.529824) (xy 334.649105 -391.547988)
			(xy 334.598975 -391.577005) (xy 334.544562 -391.596858) (xy 334.487525 -391.606945) (xy 334.458564 -391.607548)
			(xy 334.435368 -391.607117) (xy 334.38943 -391.600636) (xy 334.344846 -391.587805) (xy 334.30249 -391.568877)
			(xy 334.263191 -391.544222) (xy 334.245204 -391.52957) (xy 334.23787 -391.523926) (xy 334.220421 -391.517805)
			(xy 334.211168 -391.517632) (xy 334.144366 -391.518902) (xy 334.135087 -391.519521) (xy 334.117891 -391.526557)
			(xy 334.110838 -391.532618) (xy 334.092395 -391.548936) (xy 334.051621 -391.576543) (xy 334.007204 -391.597801)
			(xy 333.960128 -391.61224) (xy 333.911431 -391.619541) (xy 333.88681 -391.619994) (xy 333.860819 -391.61954)
			(xy 333.809477 -391.611409) (xy 333.760039 -391.595347) (xy 333.713723 -391.571749) (xy 333.671668 -391.541196)
			(xy 333.634911 -391.50444) (xy 333.604356 -391.462386) (xy 333.580757 -391.41607) (xy 333.564693 -391.366633)
			(xy 333.556561 -391.315291) (xy 330.390565 -391.315291) (xy 330.359004 -391.338562) (xy 330.353958 -391.342495)
			(xy 330.34587 -391.352401) (xy 330.343002 -391.35812) (xy 330.337668 -391.369804) (xy 330.338684 -391.383012)
			(xy 330.3397 -391.41146) (xy 330.339214 -391.438711) (xy 330.331458 -391.492659) (xy 330.316103 -391.544954)
			(xy 330.293461 -391.594531) (xy 330.263995 -391.640381) (xy 330.228304 -391.681572) (xy 330.187113 -391.717263)
			(xy 330.141263 -391.746729) (xy 330.091686 -391.769371) (xy 330.039391 -391.784726) (xy 329.985443 -391.792482)
			(xy 329.930941 -391.792482) (xy 329.876993 -391.784726) (xy 329.824698 -391.769371) (xy 329.775121 -391.746729)
			(xy 329.729271 -391.717263) (xy 329.68808 -391.681572) (xy 329.652389 -391.640381) (xy 329.622923 -391.594531)
			(xy 329.600281 -391.544954) (xy 329.584926 -391.492659) (xy 329.57717 -391.438711) (xy 329.576684 -391.41146)
			(xy 329.5777 -391.383012) (xy 329.578716 -391.369804) (xy 329.573382 -391.35812) (xy 329.570506 -391.352408)
			(xy 329.562407 -391.342515) (xy 329.55738 -391.338562) (xy 329.487784 -391.287254) (xy 329.482504 -391.283524)
			(xy 329.470544 -391.278628) (xy 329.464162 -391.277602) (xy 329.451462 -391.276078) (xy 329.43927 -391.280904)
			(xy 329.438762 -391.280904) (xy 329.416328 -391.289398) (xy 329.369872 -391.301361) (xy 329.322285 -391.307415)
			(xy 329.2983 -391.307828) (xy 329.297792 -391.307828) (xy 329.27054 -391.307342) (xy 329.21659 -391.299584)
			(xy 329.164293 -391.284227) (xy 329.114715 -391.261584) (xy 329.068863 -391.232116) (xy 329.027671 -391.196423)
			(xy 328.991979 -391.155231) (xy 328.962512 -391.109378) (xy 328.93987 -391.059799) (xy 328.924515 -391.007502)
			(xy 328.916758 -390.953552) (xy 328.916758 -390.899048) (xy 328.924515 -390.845098) (xy 328.93987 -390.792801)
			(xy 328.962512 -390.743222) (xy 328.991979 -390.697369) (xy 329.027671 -390.656177) (xy 329.068863 -390.620484)
			(xy 329.114715 -390.591016) (xy 329.164293 -390.568373) (xy 329.21659 -390.553016) (xy 329.27054 -390.545258)
			(xy 329.297792 -390.544812) (xy 329.298554 -390.544812) (xy 329.326996 -390.545396) (xy 329.383236 -390.55394)
			(xy 329.410568 -390.56183) (xy 329.414124 -390.5631) (xy 329.421998 -390.564116) (xy 329.428615 -390.564957)
			(xy 329.441874 -390.56355) (xy 329.44816 -390.561322) (xy 329.470766 -390.55167) (xy 329.481688 -390.544558)
			(xy 329.502262 -390.525508) (xy 329.506326 -390.517634) (xy 329.513974 -390.503197) (xy 329.53088 -390.475236)
			(xy 329.540108 -390.461754) (xy 329.564492 -390.429242) (xy 329.565508 -390.427972) (xy 329.569826 -390.421876)
			(xy 329.572532 -390.416926) (xy 329.575875 -390.406154) (xy 329.57643 -390.40054) (xy 329.57643 -390.399524)
			(xy 329.576684 -390.396476) (xy 329.576684 -390.242044) (xy 329.57643 -390.238996) (xy 329.57643 -390.23798)
			(xy 329.575826 -390.232376) (xy 329.572495 -390.221609) (xy 329.569826 -390.216644) (xy 329.565508 -390.210548)
			(xy 329.564492 -390.209278) (xy 329.539854 -390.176766) (xy 329.53069 -390.16328) (xy 329.513911 -390.135319)
			(xy 329.506326 -390.120886) (xy 329.502262 -390.113012) (xy 329.476608 -390.089136) (xy 329.468226 -390.08558)
			(xy 329.449176 -390.077452) (xy 329.444867 -390.075664) (xy 329.435794 -390.073495) (xy 329.431142 -390.073134)
			(xy 329.422506 -390.07288) (xy 329.413616 -390.075674) (xy 329.385403 -390.084092) (xy 329.327229 -390.093155)
			(xy 329.297792 -390.093708) (xy 329.270541 -390.093222) (xy 329.216594 -390.085464) (xy 329.1643 -390.070108)
			(xy 329.114724 -390.047467) (xy 329.068875 -390.018) (xy 329.027686 -389.982309) (xy 328.991995 -389.941119)
			(xy 328.962529 -389.895269) (xy 328.939889 -389.845692) (xy 328.924534 -389.793398) (xy 328.916778 -389.739451)
			(xy 328.916284 -389.7122) (xy 328.916649 -389.689073) (xy 328.922301 -389.643166) (xy 328.933473 -389.598282)
			(xy 328.94143 -389.576564) (xy 328.941938 -389.574786) (xy 328.943622 -389.569821) (xy 328.94516 -389.559452)
			(xy 328.944986 -389.554212) (xy 328.944314 -389.54736) (xy 328.939811 -389.534354) (xy 328.936096 -389.528558)
			(xy 328.887074 -389.457438) (xy 328.879479 -389.448453) (xy 328.858436 -389.437992) (xy 328.846688 -389.437372)
			(xy 327.700894 -389.437372) (xy 327.692203 -389.43772) (xy 327.675837 -389.443568) (xy 327.66889 -389.448802)
			(xy 327.662286 -389.454136) (xy 327.653396 -389.468868) (xy 327.651364 -389.478266) (xy 327.645458 -389.505181)
			(xy 327.626934 -389.557078) (xy 327.601134 -389.605768) (xy 327.568595 -389.650237) (xy 327.529995 -389.689561)
			(xy 327.486136 -389.722919) (xy 327.437933 -389.749618) (xy 327.386389 -389.769101) (xy 327.332578 -389.780962)
			(xy 327.27762 -389.784955) (xy 327.222659 -389.780997) (xy 327.168841 -389.769169) (xy 327.117284 -389.749719)
			(xy 327.069065 -389.72305) (xy 327.025185 -389.689719) (xy 326.98656 -389.65042) (xy 326.953993 -389.605971)
			(xy 326.928162 -389.557297) (xy 326.909607 -389.505412) (xy 326.903588 -389.47852) (xy 326.903588 -389.478012)
			(xy 326.903334 -389.477504) (xy 326.901228 -389.469107) (xy 326.892272 -389.454306) (xy 326.885808 -389.448548)
			(xy 326.879204 -389.443214) (xy 326.862948 -389.437372) (xy 326.581262 -389.437372) (xy 326.571195 -389.436941)
			(xy 326.552604 -389.429214) (xy 326.545194 -389.422386) (xy 325.965566 -388.842758) (xy 325.958719 -388.83536)
			(xy 325.950989 -388.816761) (xy 325.95058 -388.80669) (xy 325.95058 -384.714242) (xy 325.950146 -384.704177)
			(xy 325.942414 -384.68559) (xy 325.935594 -384.678174) (xy 324.929246 -383.671826) (xy 324.921846 -383.664985)
			(xy 324.903247 -383.657267) (xy 324.893178 -383.65684) (xy 301.432722 -383.65684) (xy 301.422659 -383.657279)
			(xy 301.404079 -383.665017) (xy 301.396654 -383.671826) (xy 298.50334 -386.56514) (xy 298.496496 -386.572539)
			(xy 298.48877 -386.591137) (xy 298.488354 -386.601208) (xy 298.488354 -389.444738) (xy 299.34992 -389.444738)
			(xy 299.353991 -389.389116) (xy 299.366117 -389.334679) (xy 299.38604 -389.282588) (xy 299.413336 -389.233953)
			(xy 299.447422 -389.18981) (xy 299.487571 -389.151101) (xy 299.532929 -389.11865) (xy 299.582529 -389.093149)
			(xy 299.635313 -389.075142) (xy 299.690156 -389.065012) (xy 299.74589 -389.062975) (xy 299.801327 -389.069075)
			(xy 299.855284 -389.083181) (xy 299.906613 -389.104993) (xy 299.954219 -389.134047) (xy 299.997087 -389.169722)
			(xy 300.034304 -389.211259) (xy 300.065077 -389.257772) (xy 300.088749 -389.308269) (xy 300.104817 -389.361676)
			(xy 300.112937 -389.416852) (xy 300.113446 -389.444738) (xy 300.112937 -389.472624) (xy 300.104817 -389.5278)
			(xy 300.088749 -389.581207) (xy 300.065077 -389.631704) (xy 300.034304 -389.678217) (xy 299.997087 -389.719754)
			(xy 299.954219 -389.755429) (xy 299.906613 -389.784483) (xy 299.855284 -389.806295) (xy 299.801327 -389.820401)
			(xy 299.74589 -389.826501) (xy 299.690156 -389.824464) (xy 299.635313 -389.814334) (xy 299.582529 -389.796327)
			(xy 299.532929 -389.770826) (xy 299.487571 -389.738375) (xy 299.447422 -389.699666) (xy 299.413336 -389.655523)
			(xy 299.38604 -389.606888) (xy 299.366117 -389.554797) (xy 299.353991 -389.50036) (xy 299.34992 -389.444738)
			(xy 298.488354 -389.444738) (xy 298.488354 -391.315286) (xy 301.028887 -391.315286) (xy 301.028887 -391.263314)
			(xy 301.037017 -391.211981) (xy 301.053077 -391.162551) (xy 301.07667 -391.116242) (xy 301.107217 -391.074194)
			(xy 301.143965 -391.037442) (xy 301.18601 -391.00689) (xy 301.232316 -390.983291) (xy 301.281744 -390.967226)
			(xy 301.333076 -390.95909) (xy 301.359062 -390.958578) (xy 301.382296 -390.958962) (xy 301.428308 -390.965464)
			(xy 301.472955 -390.978343) (xy 301.51536 -390.997348) (xy 301.554685 -391.022102) (xy 301.572676 -391.03681)
			(xy 301.579534 -391.042652) (xy 301.596552 -391.049002) (xy 301.680372 -391.049002) (xy 301.69739 -391.042652)
			(xy 301.704248 -391.03681) (xy 301.722246 -391.022113) (xy 301.761573 -390.997364) (xy 301.803976 -390.978363)
			(xy 301.848621 -390.965481) (xy 301.894629 -390.958974) (xy 301.917862 -390.958578) (xy 301.946457 -390.95917)
			(xy 302.002792 -390.969025) (xy 302.056595 -390.988414) (xy 302.106266 -391.016759) (xy 302.128682 -391.034524)
			(xy 302.128936 -391.034778) (xy 302.135947 -391.040031) (xy 302.152441 -391.045886) (xy 302.161194 -391.046208)
			(xy 302.226218 -391.046208) (xy 302.234819 -391.04586) (xy 302.251045 -391.040147) (xy 302.257968 -391.035032)
			(xy 302.258476 -391.034524) (xy 302.280828 -391.016937) (xy 302.330281 -390.988854) (xy 302.383814 -390.969661)
			(xy 302.439845 -390.959928) (xy 302.46828 -390.95934) (xy 302.494274 -390.959726) (xy 302.545622 -390.967856)
			(xy 302.595067 -390.983919) (xy 302.64139 -391.007519) (xy 302.68345 -391.038075) (xy 302.720212 -391.074835)
			(xy 302.750771 -391.116893) (xy 302.774374 -391.163215) (xy 302.79044 -391.212658) (xy 302.798084 -391.260917)
			(xy 303.48606 -391.260917) (xy 303.48606 -391.208943) (xy 303.49419 -391.157608) (xy 303.510251 -391.108178)
			(xy 303.533847 -391.061868) (xy 303.564397 -391.01982) (xy 303.601148 -390.983069) (xy 303.643196 -390.952519)
			(xy 303.689506 -390.928923) (xy 303.738936 -390.912862) (xy 303.790271 -390.904732) (xy 303.842245 -390.904732)
			(xy 303.89358 -390.912862) (xy 303.94301 -390.928923) (xy 303.98932 -390.952519) (xy 304.031368 -390.983069)
			(xy 304.068119 -391.01982) (xy 304.098669 -391.061868) (xy 304.122265 -391.108178) (xy 304.138326 -391.157608)
			(xy 304.146456 -391.208943) (xy 304.146966 -391.23493) (xy 304.146456 -391.260917) (xy 304.68621 -391.260917)
			(xy 304.68621 -391.208943) (xy 304.69434 -391.157608) (xy 304.710401 -391.108178) (xy 304.733997 -391.061868)
			(xy 304.764547 -391.01982) (xy 304.801298 -390.983069) (xy 304.843346 -390.952519) (xy 304.889656 -390.928923)
			(xy 304.939086 -390.912862) (xy 304.990421 -390.904732) (xy 305.042395 -390.904732) (xy 305.09373 -390.912862)
			(xy 305.14316 -390.928923) (xy 305.18947 -390.952519) (xy 305.231518 -390.983069) (xy 305.268269 -391.01982)
			(xy 305.298819 -391.061868) (xy 305.322415 -391.108178) (xy 305.338476 -391.157608) (xy 305.346606 -391.208943)
			(xy 305.347116 -391.23493) (xy 305.346606 -391.260917) (xy 305.886106 -391.260917) (xy 305.886106 -391.208943)
			(xy 305.894236 -391.157608) (xy 305.910297 -391.108178) (xy 305.933893 -391.061868) (xy 305.964443 -391.01982)
			(xy 306.001194 -390.983069) (xy 306.043242 -390.952519) (xy 306.089552 -390.928923) (xy 306.138982 -390.912862)
			(xy 306.190317 -390.904732) (xy 306.242291 -390.904732) (xy 306.293626 -390.912862) (xy 306.343056 -390.928923)
			(xy 306.389366 -390.952519) (xy 306.431414 -390.983069) (xy 306.468165 -391.01982) (xy 306.498715 -391.061868)
			(xy 306.522311 -391.108178) (xy 306.538372 -391.157608) (xy 306.546502 -391.208943) (xy 306.547012 -391.23493)
			(xy 306.546502 -391.260917) (xy 307.086002 -391.260917) (xy 307.086002 -391.208943) (xy 307.094132 -391.157608)
			(xy 307.110193 -391.108178) (xy 307.133789 -391.061868) (xy 307.164339 -391.01982) (xy 307.20109 -390.983069)
			(xy 307.243138 -390.952519) (xy 307.289448 -390.928923) (xy 307.338878 -390.912862) (xy 307.390213 -390.904732)
			(xy 307.442187 -390.904732) (xy 307.493522 -390.912862) (xy 307.542952 -390.928923) (xy 307.589262 -390.952519)
			(xy 307.63131 -390.983069) (xy 307.668061 -391.01982) (xy 307.698611 -391.061868) (xy 307.722207 -391.108178)
			(xy 307.738268 -391.157608) (xy 307.746398 -391.208943) (xy 307.746908 -391.23493) (xy 307.746398 -391.260917)
			(xy 308.286152 -391.260917) (xy 308.286152 -391.208943) (xy 308.294282 -391.157608) (xy 308.310343 -391.108178)
			(xy 308.333939 -391.061868) (xy 308.364489 -391.01982) (xy 308.40124 -390.983069) (xy 308.443288 -390.952519)
			(xy 308.489598 -390.928923) (xy 308.539028 -390.912862) (xy 308.590363 -390.904732) (xy 308.642337 -390.904732)
			(xy 308.693672 -390.912862) (xy 308.743102 -390.928923) (xy 308.789412 -390.952519) (xy 308.83146 -390.983069)
			(xy 308.868211 -391.01982) (xy 308.898761 -391.061868) (xy 308.922357 -391.108178) (xy 308.938418 -391.157608)
			(xy 308.946548 -391.208943) (xy 308.947058 -391.23493) (xy 308.946548 -391.260917) (xy 309.486048 -391.260917)
			(xy 309.486048 -391.208943) (xy 309.494178 -391.157608) (xy 309.510239 -391.108178) (xy 309.533835 -391.061868)
			(xy 309.564385 -391.01982) (xy 309.601136 -390.983069) (xy 309.643184 -390.952519) (xy 309.689494 -390.928923)
			(xy 309.738924 -390.912862) (xy 309.790259 -390.904732) (xy 309.842233 -390.904732) (xy 309.893568 -390.912862)
			(xy 309.942998 -390.928923) (xy 309.989308 -390.952519) (xy 310.031356 -390.983069) (xy 310.068107 -391.01982)
			(xy 310.098657 -391.061868) (xy 310.122253 -391.108178) (xy 310.138314 -391.157608) (xy 310.146444 -391.208943)
			(xy 310.146954 -391.23493) (xy 310.146444 -391.260917) (xy 310.686198 -391.260917) (xy 310.686198 -391.208943)
			(xy 310.694328 -391.157608) (xy 310.710389 -391.108178) (xy 310.733985 -391.061868) (xy 310.764535 -391.01982)
			(xy 310.801286 -390.983069) (xy 310.843334 -390.952519) (xy 310.889644 -390.928923) (xy 310.939074 -390.912862)
			(xy 310.990409 -390.904732) (xy 311.042383 -390.904732) (xy 311.093718 -390.912862) (xy 311.143148 -390.928923)
			(xy 311.189458 -390.952519) (xy 311.231506 -390.983069) (xy 311.268257 -391.01982) (xy 311.298807 -391.061868)
			(xy 311.322403 -391.108178) (xy 311.338464 -391.157608) (xy 311.346594 -391.208943) (xy 311.347104 -391.23493)
			(xy 311.346594 -391.260917) (xy 311.886094 -391.260917) (xy 311.886094 -391.208943) (xy 311.894224 -391.157608)
			(xy 311.910285 -391.108178) (xy 311.933881 -391.061868) (xy 311.964431 -391.01982) (xy 312.001182 -390.983069)
			(xy 312.04323 -390.952519) (xy 312.08954 -390.928923) (xy 312.13897 -390.912862) (xy 312.190305 -390.904732)
			(xy 312.242279 -390.904732) (xy 312.293614 -390.912862) (xy 312.343044 -390.928923) (xy 312.389354 -390.952519)
			(xy 312.431402 -390.983069) (xy 312.468153 -391.01982) (xy 312.498703 -391.061868) (xy 312.522299 -391.108178)
			(xy 312.53836 -391.157608) (xy 312.54649 -391.208943) (xy 312.547 -391.23493) (xy 312.54649 -391.260917)
			(xy 313.08599 -391.260917) (xy 313.08599 -391.208943) (xy 313.09412 -391.157608) (xy 313.110181 -391.108178)
			(xy 313.133777 -391.061868) (xy 313.164327 -391.01982) (xy 313.201078 -390.983069) (xy 313.243126 -390.952519)
			(xy 313.289436 -390.928923) (xy 313.338866 -390.912862) (xy 313.390201 -390.904732) (xy 313.442175 -390.904732)
			(xy 313.49351 -390.912862) (xy 313.54294 -390.928923) (xy 313.58925 -390.952519) (xy 313.631298 -390.983069)
			(xy 313.668049 -391.01982) (xy 313.698599 -391.061868) (xy 313.722195 -391.108178) (xy 313.738256 -391.157608)
			(xy 313.746386 -391.208943) (xy 313.746896 -391.23493) (xy 313.746386 -391.260917) (xy 314.28614 -391.260917)
			(xy 314.28614 -391.208943) (xy 314.29427 -391.157608) (xy 314.310331 -391.108178) (xy 314.333927 -391.061868)
			(xy 314.364477 -391.01982) (xy 314.401228 -390.983069) (xy 314.443276 -390.952519) (xy 314.489586 -390.928923)
			(xy 314.539016 -390.912862) (xy 314.590351 -390.904732) (xy 314.642325 -390.904732) (xy 314.69366 -390.912862)
			(xy 314.74309 -390.928923) (xy 314.7894 -390.952519) (xy 314.831448 -390.983069) (xy 314.868199 -391.01982)
			(xy 314.898749 -391.061868) (xy 314.922345 -391.108178) (xy 314.938406 -391.157608) (xy 314.946536 -391.208943)
			(xy 314.947046 -391.23493) (xy 314.946536 -391.260917) (xy 315.486036 -391.260917) (xy 315.486036 -391.208943)
			(xy 315.494166 -391.157608) (xy 315.510227 -391.108178) (xy 315.533823 -391.061868) (xy 315.564373 -391.01982)
			(xy 315.601124 -390.983069) (xy 315.643172 -390.952519) (xy 315.689482 -390.928923) (xy 315.738912 -390.912862)
			(xy 315.790247 -390.904732) (xy 315.842221 -390.904732) (xy 315.893556 -390.912862) (xy 315.942986 -390.928923)
			(xy 315.989296 -390.952519) (xy 316.031344 -390.983069) (xy 316.068095 -391.01982) (xy 316.098645 -391.061868)
			(xy 316.122241 -391.108178) (xy 316.138302 -391.157608) (xy 316.146432 -391.208943) (xy 316.146942 -391.23493)
			(xy 316.146432 -391.260917) (xy 316.686186 -391.260917) (xy 316.686186 -391.208943) (xy 316.694316 -391.157608)
			(xy 316.710377 -391.108178) (xy 316.733973 -391.061868) (xy 316.764523 -391.01982) (xy 316.801274 -390.983069)
			(xy 316.843322 -390.952519) (xy 316.889632 -390.928923) (xy 316.939062 -390.912862) (xy 316.990397 -390.904732)
			(xy 317.042371 -390.904732) (xy 317.093706 -390.912862) (xy 317.143136 -390.928923) (xy 317.189446 -390.952519)
			(xy 317.231494 -390.983069) (xy 317.268245 -391.01982) (xy 317.298795 -391.061868) (xy 317.322391 -391.108178)
			(xy 317.338452 -391.157608) (xy 317.346582 -391.208943) (xy 317.347092 -391.23493) (xy 317.346582 -391.260917)
			(xy 317.886082 -391.260917) (xy 317.886082 -391.208943) (xy 317.894212 -391.157608) (xy 317.910273 -391.108178)
			(xy 317.933869 -391.061868) (xy 317.964419 -391.01982) (xy 318.00117 -390.983069) (xy 318.043218 -390.952519)
			(xy 318.089528 -390.928923) (xy 318.138958 -390.912862) (xy 318.190293 -390.904732) (xy 318.242267 -390.904732)
			(xy 318.293602 -390.912862) (xy 318.343032 -390.928923) (xy 318.389342 -390.952519) (xy 318.43139 -390.983069)
			(xy 318.468141 -391.01982) (xy 318.498691 -391.061868) (xy 318.522287 -391.108178) (xy 318.538348 -391.157608)
			(xy 318.546478 -391.208943) (xy 318.546988 -391.23493) (xy 318.546478 -391.260917) (xy 319.085978 -391.260917)
			(xy 319.085978 -391.208943) (xy 319.094108 -391.157608) (xy 319.110169 -391.108178) (xy 319.133765 -391.061868)
			(xy 319.164315 -391.01982) (xy 319.201066 -390.983069) (xy 319.243114 -390.952519) (xy 319.289424 -390.928923)
			(xy 319.338854 -390.912862) (xy 319.390189 -390.904732) (xy 319.442163 -390.904732) (xy 319.493498 -390.912862)
			(xy 319.542928 -390.928923) (xy 319.589238 -390.952519) (xy 319.631286 -390.983069) (xy 319.668037 -391.01982)
			(xy 319.698587 -391.061868) (xy 319.722183 -391.108178) (xy 319.738244 -391.157608) (xy 319.746374 -391.208943)
			(xy 319.746884 -391.23493) (xy 319.746374 -391.260917) (xy 320.286128 -391.260917) (xy 320.286128 -391.208943)
			(xy 320.294258 -391.157608) (xy 320.310319 -391.108178) (xy 320.333915 -391.061868) (xy 320.364465 -391.01982)
			(xy 320.401216 -390.983069) (xy 320.443264 -390.952519) (xy 320.489574 -390.928923) (xy 320.539004 -390.912862)
			(xy 320.590339 -390.904732) (xy 320.642313 -390.904732) (xy 320.693648 -390.912862) (xy 320.743078 -390.928923)
			(xy 320.789388 -390.952519) (xy 320.831436 -390.983069) (xy 320.868187 -391.01982) (xy 320.898737 -391.061868)
			(xy 320.922333 -391.108178) (xy 320.938394 -391.157608) (xy 320.946524 -391.208943) (xy 320.947034 -391.23493)
			(xy 320.946524 -391.260917) (xy 321.486024 -391.260917) (xy 321.486024 -391.208943) (xy 321.494154 -391.157608)
			(xy 321.510215 -391.108178) (xy 321.533811 -391.061868) (xy 321.564361 -391.01982) (xy 321.601112 -390.983069)
			(xy 321.64316 -390.952519) (xy 321.68947 -390.928923) (xy 321.7389 -390.912862) (xy 321.790235 -390.904732)
			(xy 321.842209 -390.904732) (xy 321.893544 -390.912862) (xy 321.942974 -390.928923) (xy 321.989284 -390.952519)
			(xy 322.031332 -390.983069) (xy 322.068083 -391.01982) (xy 322.098633 -391.061868) (xy 322.122229 -391.108178)
			(xy 322.13829 -391.157608) (xy 322.14642 -391.208943) (xy 322.14693 -391.23493) (xy 322.14642 -391.260917)
			(xy 322.144002 -391.276188) (xy 322.553072 -391.276188) (xy 322.553072 -391.224212) (xy 322.561202 -391.172875)
			(xy 322.577263 -391.123442) (xy 322.600859 -391.07713) (xy 322.631409 -391.035079) (xy 322.668161 -390.998324)
			(xy 322.710209 -390.967772) (xy 322.75652 -390.944172) (xy 322.805951 -390.928108) (xy 322.857288 -390.919973)
			(xy 322.883276 -390.919462) (xy 322.90705 -390.919867) (xy 322.95411 -390.926669) (xy 322.999707 -390.940149)
			(xy 323.0429 -390.96003) (xy 323.082795 -390.9859) (xy 323.100954 -391.00125) (xy 323.108072 -391.006938)
			(xy 323.125124 -391.013321) (xy 323.134228 -391.013696) (xy 323.165724 -391.013696) (xy 323.174826 -391.013313)
			(xy 323.191876 -391.006931) (xy 323.198998 -391.00125) (xy 323.217161 -390.985906) (xy 323.257061 -390.960049)
			(xy 323.300254 -390.940174) (xy 323.345848 -390.92669) (xy 323.392903 -390.919876) (xy 323.416676 -390.919462)
			(xy 323.442664 -390.920003) (xy 323.494001 -390.928131) (xy 323.543434 -390.944189) (xy 323.589747 -390.967784)
			(xy 323.631798 -390.998333) (xy 323.668552 -391.035084) (xy 323.699104 -391.077133) (xy 323.722701 -391.123444)
			(xy 323.738764 -391.172876) (xy 323.746895 -391.224212) (xy 323.746895 -391.276188) (xy 323.738764 -391.327524)
			(xy 323.722701 -391.376956) (xy 323.699104 -391.423267) (xy 323.668552 -391.465316) (xy 323.631798 -391.502067)
			(xy 323.589747 -391.532616) (xy 323.543434 -391.556211) (xy 323.494001 -391.572269) (xy 323.442664 -391.580397)
			(xy 323.416676 -391.580878) (xy 323.392901 -391.580492) (xy 323.345841 -391.573684) (xy 323.300244 -391.560199)
			(xy 323.257051 -391.540314) (xy 323.217157 -391.514442) (xy 323.198998 -391.49909) (xy 323.191899 -391.493374)
			(xy 323.174832 -391.48701) (xy 323.165724 -391.486644) (xy 323.134228 -391.486644) (xy 323.125128 -391.487043)
			(xy 323.108077 -391.493413) (xy 323.100954 -391.49909) (xy 323.082777 -391.514416) (xy 323.04288 -391.540274)
			(xy 322.999691 -391.560153) (xy 322.9541 -391.573641) (xy 322.907048 -391.580461) (xy 322.883276 -391.580878)
			(xy 322.857288 -391.580427) (xy 322.805951 -391.572292) (xy 322.75652 -391.556228) (xy 322.710209 -391.532628)
			(xy 322.668161 -391.502076) (xy 322.631409 -391.465321) (xy 322.600859 -391.42327) (xy 322.577263 -391.376958)
			(xy 322.561202 -391.327525) (xy 322.553072 -391.276188) (xy 322.144002 -391.276188) (xy 322.13829 -391.312252)
			(xy 322.122229 -391.361682) (xy 322.098633 -391.407992) (xy 322.068083 -391.45004) (xy 322.031332 -391.486791)
			(xy 321.989284 -391.517341) (xy 321.942974 -391.540937) (xy 321.893544 -391.556998) (xy 321.842209 -391.565128)
			(xy 321.790235 -391.565128) (xy 321.7389 -391.556998) (xy 321.68947 -391.540937) (xy 321.64316 -391.517341)
			(xy 321.601112 -391.486791) (xy 321.564361 -391.45004) (xy 321.533811 -391.407992) (xy 321.510215 -391.361682)
			(xy 321.494154 -391.312252) (xy 321.486024 -391.260917) (xy 320.946524 -391.260917) (xy 320.938394 -391.312252)
			(xy 320.922333 -391.361682) (xy 320.898737 -391.407992) (xy 320.868187 -391.45004) (xy 320.831436 -391.486791)
			(xy 320.789388 -391.517341) (xy 320.743078 -391.540937) (xy 320.693648 -391.556998) (xy 320.642313 -391.565128)
			(xy 320.590339 -391.565128) (xy 320.539004 -391.556998) (xy 320.489574 -391.540937) (xy 320.443264 -391.517341)
			(xy 320.401216 -391.486791) (xy 320.364465 -391.45004) (xy 320.333915 -391.407992) (xy 320.310319 -391.361682)
			(xy 320.294258 -391.312252) (xy 320.286128 -391.260917) (xy 319.746374 -391.260917) (xy 319.738244 -391.312252)
			(xy 319.722183 -391.361682) (xy 319.698587 -391.407992) (xy 319.668037 -391.45004) (xy 319.631286 -391.486791)
			(xy 319.589238 -391.517341) (xy 319.542928 -391.540937) (xy 319.493498 -391.556998) (xy 319.442163 -391.565128)
			(xy 319.390189 -391.565128) (xy 319.338854 -391.556998) (xy 319.289424 -391.540937) (xy 319.243114 -391.517341)
			(xy 319.201066 -391.486791) (xy 319.164315 -391.45004) (xy 319.133765 -391.407992) (xy 319.110169 -391.361682)
			(xy 319.094108 -391.312252) (xy 319.085978 -391.260917) (xy 318.546478 -391.260917) (xy 318.538348 -391.312252)
			(xy 318.522287 -391.361682) (xy 318.498691 -391.407992) (xy 318.468141 -391.45004) (xy 318.43139 -391.486791)
			(xy 318.389342 -391.517341) (xy 318.343032 -391.540937) (xy 318.293602 -391.556998) (xy 318.242267 -391.565128)
			(xy 318.190293 -391.565128) (xy 318.138958 -391.556998) (xy 318.089528 -391.540937) (xy 318.043218 -391.517341)
			(xy 318.00117 -391.486791) (xy 317.964419 -391.45004) (xy 317.933869 -391.407992) (xy 317.910273 -391.361682)
			(xy 317.894212 -391.312252) (xy 317.886082 -391.260917) (xy 317.346582 -391.260917) (xy 317.338452 -391.312252)
			(xy 317.322391 -391.361682) (xy 317.298795 -391.407992) (xy 317.268245 -391.45004) (xy 317.231494 -391.486791)
			(xy 317.189446 -391.517341) (xy 317.143136 -391.540937) (xy 317.093706 -391.556998) (xy 317.042371 -391.565128)
			(xy 316.990397 -391.565128) (xy 316.939062 -391.556998) (xy 316.889632 -391.540937) (xy 316.843322 -391.517341)
			(xy 316.801274 -391.486791) (xy 316.764523 -391.45004) (xy 316.733973 -391.407992) (xy 316.710377 -391.361682)
			(xy 316.694316 -391.312252) (xy 316.686186 -391.260917) (xy 316.146432 -391.260917) (xy 316.138302 -391.312252)
			(xy 316.122241 -391.361682) (xy 316.098645 -391.407992) (xy 316.068095 -391.45004) (xy 316.031344 -391.486791)
			(xy 315.989296 -391.517341) (xy 315.942986 -391.540937) (xy 315.893556 -391.556998) (xy 315.842221 -391.565128)
			(xy 315.790247 -391.565128) (xy 315.738912 -391.556998) (xy 315.689482 -391.540937) (xy 315.643172 -391.517341)
			(xy 315.601124 -391.486791) (xy 315.564373 -391.45004) (xy 315.533823 -391.407992) (xy 315.510227 -391.361682)
			(xy 315.494166 -391.312252) (xy 315.486036 -391.260917) (xy 314.946536 -391.260917) (xy 314.938406 -391.312252)
			(xy 314.922345 -391.361682) (xy 314.898749 -391.407992) (xy 314.868199 -391.45004) (xy 314.831448 -391.486791)
			(xy 314.7894 -391.517341) (xy 314.74309 -391.540937) (xy 314.69366 -391.556998) (xy 314.642325 -391.565128)
			(xy 314.590351 -391.565128) (xy 314.539016 -391.556998) (xy 314.489586 -391.540937) (xy 314.443276 -391.517341)
			(xy 314.401228 -391.486791) (xy 314.364477 -391.45004) (xy 314.333927 -391.407992) (xy 314.310331 -391.361682)
			(xy 314.29427 -391.312252) (xy 314.28614 -391.260917) (xy 313.746386 -391.260917) (xy 313.738256 -391.312252)
			(xy 313.722195 -391.361682) (xy 313.698599 -391.407992) (xy 313.668049 -391.45004) (xy 313.631298 -391.486791)
			(xy 313.58925 -391.517341) (xy 313.54294 -391.540937) (xy 313.49351 -391.556998) (xy 313.442175 -391.565128)
			(xy 313.390201 -391.565128) (xy 313.338866 -391.556998) (xy 313.289436 -391.540937) (xy 313.243126 -391.517341)
			(xy 313.201078 -391.486791) (xy 313.164327 -391.45004) (xy 313.133777 -391.407992) (xy 313.110181 -391.361682)
			(xy 313.09412 -391.312252) (xy 313.08599 -391.260917) (xy 312.54649 -391.260917) (xy 312.53836 -391.312252)
			(xy 312.522299 -391.361682) (xy 312.498703 -391.407992) (xy 312.468153 -391.45004) (xy 312.431402 -391.486791)
			(xy 312.389354 -391.517341) (xy 312.343044 -391.540937) (xy 312.293614 -391.556998) (xy 312.242279 -391.565128)
			(xy 312.190305 -391.565128) (xy 312.13897 -391.556998) (xy 312.08954 -391.540937) (xy 312.04323 -391.517341)
			(xy 312.001182 -391.486791) (xy 311.964431 -391.45004) (xy 311.933881 -391.407992) (xy 311.910285 -391.361682)
			(xy 311.894224 -391.312252) (xy 311.886094 -391.260917) (xy 311.346594 -391.260917) (xy 311.338464 -391.312252)
			(xy 311.322403 -391.361682) (xy 311.298807 -391.407992) (xy 311.268257 -391.45004) (xy 311.231506 -391.486791)
			(xy 311.189458 -391.517341) (xy 311.143148 -391.540937) (xy 311.093718 -391.556998) (xy 311.042383 -391.565128)
			(xy 310.990409 -391.565128) (xy 310.939074 -391.556998) (xy 310.889644 -391.540937) (xy 310.843334 -391.517341)
			(xy 310.801286 -391.486791) (xy 310.764535 -391.45004) (xy 310.733985 -391.407992) (xy 310.710389 -391.361682)
			(xy 310.694328 -391.312252) (xy 310.686198 -391.260917) (xy 310.146444 -391.260917) (xy 310.138314 -391.312252)
			(xy 310.122253 -391.361682) (xy 310.098657 -391.407992) (xy 310.068107 -391.45004) (xy 310.031356 -391.486791)
			(xy 309.989308 -391.517341) (xy 309.942998 -391.540937) (xy 309.893568 -391.556998) (xy 309.842233 -391.565128)
			(xy 309.790259 -391.565128) (xy 309.738924 -391.556998) (xy 309.689494 -391.540937) (xy 309.643184 -391.517341)
			(xy 309.601136 -391.486791) (xy 309.564385 -391.45004) (xy 309.533835 -391.407992) (xy 309.510239 -391.361682)
			(xy 309.494178 -391.312252) (xy 309.486048 -391.260917) (xy 308.946548 -391.260917) (xy 308.938418 -391.312252)
			(xy 308.922357 -391.361682) (xy 308.898761 -391.407992) (xy 308.868211 -391.45004) (xy 308.83146 -391.486791)
			(xy 308.789412 -391.517341) (xy 308.743102 -391.540937) (xy 308.693672 -391.556998) (xy 308.642337 -391.565128)
			(xy 308.590363 -391.565128) (xy 308.539028 -391.556998) (xy 308.489598 -391.540937) (xy 308.443288 -391.517341)
			(xy 308.40124 -391.486791) (xy 308.364489 -391.45004) (xy 308.333939 -391.407992) (xy 308.310343 -391.361682)
			(xy 308.294282 -391.312252) (xy 308.286152 -391.260917) (xy 307.746398 -391.260917) (xy 307.738268 -391.312252)
			(xy 307.722207 -391.361682) (xy 307.698611 -391.407992) (xy 307.668061 -391.45004) (xy 307.63131 -391.486791)
			(xy 307.589262 -391.517341) (xy 307.542952 -391.540937) (xy 307.493522 -391.556998) (xy 307.442187 -391.565128)
			(xy 307.390213 -391.565128) (xy 307.338878 -391.556998) (xy 307.289448 -391.540937) (xy 307.243138 -391.517341)
			(xy 307.20109 -391.486791) (xy 307.164339 -391.45004) (xy 307.133789 -391.407992) (xy 307.110193 -391.361682)
			(xy 307.094132 -391.312252) (xy 307.086002 -391.260917) (xy 306.546502 -391.260917) (xy 306.538372 -391.312252)
			(xy 306.522311 -391.361682) (xy 306.498715 -391.407992) (xy 306.468165 -391.45004) (xy 306.431414 -391.486791)
			(xy 306.389366 -391.517341) (xy 306.343056 -391.540937) (xy 306.293626 -391.556998) (xy 306.242291 -391.565128)
			(xy 306.190317 -391.565128) (xy 306.138982 -391.556998) (xy 306.089552 -391.540937) (xy 306.043242 -391.517341)
			(xy 306.001194 -391.486791) (xy 305.964443 -391.45004) (xy 305.933893 -391.407992) (xy 305.910297 -391.361682)
			(xy 305.894236 -391.312252) (xy 305.886106 -391.260917) (xy 305.346606 -391.260917) (xy 305.338476 -391.312252)
			(xy 305.322415 -391.361682) (xy 305.298819 -391.407992) (xy 305.268269 -391.45004) (xy 305.231518 -391.486791)
			(xy 305.18947 -391.517341) (xy 305.14316 -391.540937) (xy 305.09373 -391.556998) (xy 305.042395 -391.565128)
			(xy 304.990421 -391.565128) (xy 304.939086 -391.556998) (xy 304.889656 -391.540937) (xy 304.843346 -391.517341)
			(xy 304.801298 -391.486791) (xy 304.764547 -391.45004) (xy 304.733997 -391.407992) (xy 304.710401 -391.361682)
			(xy 304.69434 -391.312252) (xy 304.68621 -391.260917) (xy 304.146456 -391.260917) (xy 304.138326 -391.312252)
			(xy 304.122265 -391.361682) (xy 304.098669 -391.407992) (xy 304.068119 -391.45004) (xy 304.031368 -391.486791)
			(xy 303.98932 -391.517341) (xy 303.94301 -391.540937) (xy 303.89358 -391.556998) (xy 303.842245 -391.565128)
			(xy 303.790271 -391.565128) (xy 303.738936 -391.556998) (xy 303.689506 -391.540937) (xy 303.643196 -391.517341)
			(xy 303.601148 -391.486791) (xy 303.564397 -391.45004) (xy 303.533847 -391.407992) (xy 303.510251 -391.361682)
			(xy 303.49419 -391.312252) (xy 303.48606 -391.260917) (xy 302.798084 -391.260917) (xy 302.798573 -391.264006)
			(xy 302.798573 -391.315994) (xy 302.79044 -391.367342) (xy 302.774374 -391.416785) (xy 302.750771 -391.463107)
			(xy 302.720212 -391.505165) (xy 302.68345 -391.541925) (xy 302.64139 -391.572481) (xy 302.595067 -391.596081)
			(xy 302.545622 -391.612144) (xy 302.494274 -391.620274) (xy 302.46828 -391.620756) (xy 302.439687 -391.620133)
			(xy 302.383354 -391.610287) (xy 302.32955 -391.590907) (xy 302.279877 -391.56257) (xy 302.25746 -391.54481)
			(xy 302.257206 -391.544556) (xy 302.250209 -391.539283) (xy 302.233705 -391.533439) (xy 302.224948 -391.533126)
			(xy 302.159924 -391.533126) (xy 302.151325 -391.533487) (xy 302.135098 -391.53919) (xy 302.128174 -391.544302)
			(xy 302.127666 -391.54481) (xy 302.105337 -391.562429) (xy 302.055876 -391.590504) (xy 302.002335 -391.609688)
			(xy 301.946299 -391.619411) (xy 301.917862 -391.619994) (xy 301.894628 -391.619602) (xy 301.848617 -391.613103)
			(xy 301.803969 -391.600226) (xy 301.761564 -391.581223) (xy 301.722239 -391.556469) (xy 301.704248 -391.541762)
			(xy 301.69739 -391.53592) (xy 301.680372 -391.52957) (xy 301.596552 -391.52957) (xy 301.579534 -391.53592)
			(xy 301.572676 -391.541762) (xy 301.554666 -391.556444) (xy 301.515343 -391.581195) (xy 301.472943 -391.600201)
			(xy 301.4283 -391.613086) (xy 301.382294 -391.619596) (xy 301.359062 -391.619994) (xy 301.333076 -391.61951)
			(xy 301.281744 -391.611374) (xy 301.232316 -391.595309) (xy 301.18601 -391.57171) (xy 301.143965 -391.541158)
			(xy 301.107217 -391.504406) (xy 301.07667 -391.462358) (xy 301.053077 -391.416049) (xy 301.037017 -391.366619)
			(xy 301.028887 -391.315286) (xy 298.488354 -391.315286) (xy 298.488354 -391.573512) (xy 298.487927 -391.58358)
			(xy 298.480205 -391.602177) (xy 298.473368 -391.60958) (xy 298.400978 -391.68197) (xy 298.39358 -391.688816)
			(xy 298.374981 -391.696547) (xy 298.36491 -391.696956) (xy 297.701716 -391.696956) (xy 297.700954 -391.696956)
			(xy 297.693508 -391.697328) (xy 297.679309 -391.70185) (xy 297.673014 -391.705846) (xy 297.65244 -391.72224)
			(xy 297.607639 -391.749813) (xy 297.559472 -391.770964) (xy 297.508854 -391.785292) (xy 297.456747 -391.792525)
			(xy 297.404141 -391.792525) (xy 297.352034 -391.785292) (xy 297.301416 -391.770964) (xy 297.253249 -391.749813)
			(xy 297.208448 -391.72224) (xy 297.187874 -391.705846) (xy 297.182032 -391.70229) (xy 297.176646 -391.699811)
			(xy 297.1651 -391.697124) (xy 297.159172 -391.696956) (xy 296.947082 -391.696956) (xy 296.937014 -391.696528)
			(xy 296.918419 -391.688804) (xy 296.911014 -391.68197) (xy 296.186352 -390.957308) (xy 296.178732 -390.950958)
			(xy 296.168064 -390.943846) (xy 296.164 -390.942068) (xy 296.117807 -390.920698) (xy 296.029117 -390.87075)
			(xy 295.945328 -390.812955) (xy 295.867134 -390.747791) (xy 295.830752 -390.712198) (xy 295.76395 -390.645396)
			(xy 295.731523 -390.612453) (xy 295.670795 -390.54275) (xy 295.615044 -390.469006) (xy 295.589452 -390.430512)
			(xy 295.566111 -390.394032) (xy 295.523661 -390.318532) (xy 295.504616 -390.279636) (xy 295.500806 -390.271762)
			(xy 295.303194 -390.07415) (xy 295.296356 -390.066748) (xy 295.288641 -390.04815) (xy 295.288208 -390.038082)
			(xy 295.288208 -388.903972) (xy 295.287715 -388.893968) (xy 295.280051 -388.875484) (xy 295.265899 -388.861338)
			(xy 295.247413 -388.853681) (xy 295.237408 -388.853172) (xy 292.636956 -388.853172) (xy 292.628828 -388.853934)
			(xy 292.617906 -388.855966) (xy 292.610794 -388.857998) (xy 292.608508 -388.85876) (xy 292.607492 -388.859268)
			(xy 292.60673 -388.859522) (xy 292.530714 -388.888498) (xy 292.376834 -388.941338) (xy 292.221051 -388.988275)
			(xy 292.142418 -389.009128) (xy 292.044422 -389.03402) (xy 291.846536 -389.075625) (xy 291.646902 -389.107808)
			(xy 291.445966 -389.130497) (xy 291.345112 -389.137652) (xy 291.275784 -389.141851) (xy 291.136945 -389.146295)
			(xy 291.06749 -389.146542) (xy 291.067236 -389.146542) (xy 290.979354 -389.146094) (xy 290.80374 -389.138858)
			(xy 290.628572 -389.124397) (xy 290.454148 -389.102736) (xy 290.280764 -389.073911) (xy 290.108714 -389.037972)
			(xy 289.93829 -388.994978) (xy 289.769781 -388.945004) (xy 289.603472 -388.888134) (xy 289.521392 -388.856728)
			(xy 289.512502 -388.853172) (xy 288.994088 -388.853172) (xy 288.984019 -388.852746) (xy 288.965421 -388.845025)
			(xy 288.95802 -388.838186) (xy 287.00857 -386.888736) (xy 287.001726 -386.881338) (xy 286.994004 -386.862738)
			(xy 286.993584 -386.852668) (xy 286.993584 -386.158486) (xy 286.993519 -386.154679) (xy 286.992372 -386.147153)
			(xy 286.991298 -386.1435) (xy 286.96457 -386.055716) (xy 286.91776 -385.878263) (xy 286.878621 -385.698961)
			(xy 286.847226 -385.518143) (xy 286.823634 -385.336142) (xy 286.807887 -385.153296) (xy 286.800016 -384.969941)
			(xy 286.800034 -384.786418) (xy 286.807942 -384.603065) (xy 286.823724 -384.420221) (xy 286.847352 -384.238225)
			(xy 286.878783 -384.057413) (xy 286.917957 -383.878119) (xy 286.964803 -383.700676) (xy 286.991552 -383.612898)
			(xy 286.992498 -383.609418) (xy 286.993512 -383.602279) (xy 286.993584 -383.598674) (xy 286.993584 -383.14503)
			(xy 286.994019 -383.134965) (xy 287.00175 -383.116378) (xy 287.00857 -383.108962) (xy 287.369504 -382.748028)
			(xy 287.372806 -382.742186) (xy 287.419734 -382.662033) (xy 287.519628 -382.505422) (xy 287.626242 -382.353306)
			(xy 287.739373 -382.205972) (xy 287.858808 -382.063701) (xy 287.984319 -381.92676) (xy 288.11567 -381.79541)
			(xy 288.252611 -381.669899) (xy 288.394883 -381.550465) (xy 288.542217 -381.437334) (xy 288.694334 -381.330721)
			(xy 288.850945 -381.230827) (xy 288.931096 -381.183896) (xy 288.936938 -381.180594) (xy 289.423856 -380.693676)
			(xy 289.431254 -380.68683) (xy 289.449853 -380.679104) (xy 289.459924 -380.67869) (xy 290.308284 -380.67869)
			(xy 290.312856 -380.677928) (xy 290.406286 -380.661671) (xy 290.594266 -380.63645) (xy 290.783181 -380.619598)
			(xy 290.972658 -380.611151) (xy 291.06749 -380.610618) (xy 291.162323 -380.611145) (xy 291.351801 -380.619579)
			(xy 291.540716 -380.636428) (xy 291.728696 -380.661657) (xy 291.822124 -380.677928) (xy 291.826696 -380.67869)
			(xy 294.358822 -380.67869) (xy 294.368474 -380.677674) (xy 294.375717 -380.676044) (xy 294.388882 -380.669199)
			(xy 294.394382 -380.664212) (xy 295.27373 -379.784864) (xy 295.278925 -379.779113) (xy 295.2859 -379.765281)
			(xy 295.287446 -379.757686) (xy 295.288208 -379.749304) (xy 295.288208 -372.1608) (xy 295.287989 -372.153991)
			(xy 295.284382 -372.14086) (xy 295.281096 -372.134892) (xy 295.277231 -372.128861) (xy 295.266781 -372.119073)
			(xy 295.260522 -372.115588) (xy 295.17975 -372.07444) (xy 295.17349 -372.071544) (xy 295.159971 -372.068827)
			(xy 295.15308 -372.069106) (xy 295.138856 -372.070122) (xy 295.127172 -372.078504) (xy 295.101198 -372.096573)
			(xy 295.045628 -372.126832) (xy 294.986733 -372.149962) (xy 294.925422 -372.165605) (xy 294.862645 -372.173519)
			(xy 294.831008 -372.174008) (xy 294.8305 -372.174008) (xy 294.798539 -372.173506) (xy 294.735121 -372.165495)
			(xy 294.673207 -372.149598) (xy 294.613774 -372.126066) (xy 294.557759 -372.095272) (xy 294.506044 -372.057699)
			(xy 294.459447 -372.013942) (xy 294.418702 -371.964689) (xy 294.384451 -371.910718) (xy 294.357234 -371.852879)
			(xy 294.337481 -371.792086) (xy 294.325503 -371.729296) (xy 294.32149 -371.6655) (xy 294.325503 -371.601704)
			(xy 294.337481 -371.538914) (xy 294.357234 -371.478121) (xy 294.384451 -371.420282) (xy 294.418702 -371.366311)
			(xy 294.459447 -371.317058) (xy 294.506044 -371.273301) (xy 294.557759 -371.235728) (xy 294.613774 -371.204934)
			(xy 294.673207 -371.181402) (xy 294.735121 -371.165505) (xy 294.798539 -371.157494) (xy 294.8305 -371.156992)
			(xy 294.831008 -371.156992) (xy 294.862644 -371.157505) (xy 294.925419 -371.165418) (xy 294.986728 -371.181057)
			(xy 295.045623 -371.204182) (xy 295.101194 -371.234435) (xy 295.127172 -371.252496) (xy 295.132969 -371.256416)
			(xy 295.146118 -371.26119) (xy 295.15308 -371.261894) (xy 295.16705 -371.26291) (xy 295.260522 -371.215412)
			(xy 295.266782 -371.211933) (xy 295.277216 -371.202129) (xy 295.281096 -371.196108) (xy 295.284376 -371.190139)
			(xy 295.287969 -371.177007) (xy 295.288208 -371.1702) (xy 295.288208 -367.532666) (xy 295.287998 -367.52658)
			(xy 295.285041 -367.514769) (xy 295.282366 -367.509298) (xy 295.269412 -367.486692) (xy 295.26761 -367.483639)
			(xy 295.263276 -367.478029) (xy 295.260776 -367.475516) (xy 295.25722 -367.472214) (xy 295.251124 -367.468404)
			(xy 295.25087 -367.46815) (xy 295.24579 -367.465102) (xy 295.236138 -367.45926) (xy 295.233344 -367.457482)
			(xy 295.208706 -367.450116) (xy 295.205912 -367.449354) (xy 295.199562 -367.449354) (xy 295.17594 -367.453926)
			(xy 295.175432 -367.453926) (xy 295.128696 -367.463324) (xy 295.12136 -367.465068) (xy 295.108066 -367.472169)
			(xy 295.102534 -367.477294) (xy 295.096438 -367.48339) (xy 295.094152 -367.486692) (xy 295.076183 -367.510835)
			(xy 295.035453 -367.555144) (xy 294.98978 -367.594339) (xy 294.939802 -367.627873) (xy 294.886218 -367.655278)
			(xy 294.829775 -367.67617) (xy 294.771261 -367.690258) (xy 294.711495 -367.697346) (xy 294.681402 -367.697766)
			(xy 294.649442 -367.697285) (xy 294.586027 -367.689274) (xy 294.524115 -367.673378) (xy 294.464684 -367.649848)
			(xy 294.408671 -367.619055) (xy 294.356959 -367.581484) (xy 294.310363 -367.537728) (xy 294.269619 -367.488477)
			(xy 294.235369 -367.434508) (xy 294.208154 -367.376672) (xy 294.188401 -367.315881) (xy 294.176424 -367.253093)
			(xy 294.17241 -367.1893) (xy 294.176424 -367.125507) (xy 294.188401 -367.062719) (xy 294.208154 -367.001928)
			(xy 294.235369 -366.944092) (xy 294.269619 -366.890123) (xy 294.310363 -366.840872) (xy 294.356959 -366.797116)
			(xy 294.408671 -366.759545) (xy 294.464684 -366.728752) (xy 294.524115 -366.705222) (xy 294.586027 -366.689326)
			(xy 294.649442 -366.681315) (xy 294.681402 -366.68075) (xy 294.71225 -366.681203) (xy 294.773491 -366.688668)
			(xy 294.83338 -366.703489) (xy 294.891035 -366.725448) (xy 294.945609 -366.754221) (xy 294.971216 -366.771428)
			(xy 294.977566 -366.775746) (xy 294.996362 -366.781842) (xy 295.002491 -366.783596) (xy 295.015211 -366.784359)
			(xy 295.021508 -366.783366) (xy 295.039288 -366.77981) (xy 295.049448 -366.777016) (xy 295.08069 -366.756188)
			(xy 295.086278 -366.747552) (xy 295.09085 -366.740694) (xy 295.096184 -366.733328) (xy 295.100756 -366.71631)
			(xy 295.099994 -366.70742) (xy 295.098823 -366.698539) (xy 295.091282 -366.682305) (xy 295.085262 -366.67567)
			(xy 294.439848 -366.030256) (xy 294.436999 -366.027547) (xy 294.430624 -366.022947) (xy 294.427148 -366.021112)
			(xy 294.421721 -366.018529) (xy 294.410041 -366.015707) (xy 294.404034 -366.015524) (xy 283.114242 -366.015524)
			(xy 283.104176 -366.015091) (xy 283.085584 -366.007364) (xy 283.078174 -366.000538) (xy 282.518358 -365.440722)
			(xy 282.511517 -365.433322) (xy 282.503802 -365.414723) (xy 282.503372 -365.404654) (xy 282.503372 -362.0135)
			(xy 282.503272 -362.008623) (xy 282.501475 -361.999037) (xy 282.499816 -361.99445) (xy 282.496006 -361.985306)
			(xy 281.41676 -360.90606) (xy 281.413908 -360.903355) (xy 281.407529 -360.898764) (xy 281.40406 -360.896916)
			(xy 281.398633 -360.894332) (xy 281.386954 -360.891506) (xy 281.380946 -360.891328) (xy 276.40153 -360.891328)
			(xy 276.391479 -360.890824) (xy 276.372915 -360.883106) (xy 276.365462 -360.876342) (xy 274.746466 -359.257346)
			(xy 274.743614 -359.254641) (xy 274.737234 -359.250051) (xy 274.733766 -359.248202) (xy 274.728339 -359.245618)
			(xy 274.71666 -359.242792) (xy 274.710652 -359.242614) (xy 270.950436 -359.242614) (xy 270.940371 -359.24218)
			(xy 270.921782 -359.234451) (xy 270.914368 -359.227628) (xy 259.54863 -347.86189) (xy 259.541782 -347.854492)
			(xy 259.534046 -347.835894) (xy 259.533644 -347.825822) (xy 259.533644 -327.86193) (xy 259.532957 -327.850587)
			(xy 259.523089 -327.830148) (xy 259.505418 -327.815906) (xy 259.494528 -327.812654) (xy 259.492496 -327.812146)
			(xy 259.467482 -327.806934) (xy 259.419033 -327.790699) (xy 259.373189 -327.768136) (xy 259.330771 -327.739648)
			(xy 259.311394 -327.722992) (xy 259.308092 -327.719944) (xy 259.299964 -327.714864) (xy 259.298948 -327.714356)
			(xy 259.292776 -327.710872) (xy 259.27911 -327.707132) (xy 259.272024 -327.70699) (xy 259.203444 -327.708006)
			(xy 259.198674 -327.708267) (xy 259.189344 -327.710312) (xy 259.184902 -327.71207) (xy 259.176774 -327.715372)
			(xy 259.169408 -327.72223) (xy 259.147969 -327.741938) (xy 259.100229 -327.775286) (xy 259.047979 -327.800996)
			(xy 258.992431 -327.818472) (xy 258.934873 -327.82731) (xy 258.905756 -327.827894) (xy 258.8824 -327.827528)
			(xy 258.836041 -327.821801) (xy 258.8133 -327.816464) (xy 258.812538 -327.81621) (xy 258.804664 -327.814178)
			(xy 258.79552 -327.815194) (xy 258.790877 -327.815858) (xy 258.781931 -327.818676) (xy 258.77774 -327.820782)
			(xy 258.717288 -327.85304) (xy 258.713226 -327.855288) (xy 258.705948 -327.861048) (xy 258.70281 -327.86447)
			(xy 258.696714 -327.871328) (xy 258.693412 -327.880218) (xy 258.682838 -327.907256) (xy 258.654691 -327.95803)
			(xy 258.619172 -328.003952) (xy 258.577104 -328.043959) (xy 258.529459 -328.077128) (xy 258.477336 -328.102693)
			(xy 258.421941 -328.120062) (xy 258.364553 -328.128835) (xy 258.335526 -328.129392) (xy 258.308273 -328.12893)
			(xy 258.254322 -328.121177) (xy 258.202023 -328.105824) (xy 258.152442 -328.083184) (xy 258.106587 -328.053718)
			(xy 258.065393 -328.018025) (xy 258.029698 -327.976834) (xy 258.000229 -327.930981) (xy 257.977585 -327.881402)
			(xy 257.962229 -327.829104) (xy 257.954471 -327.775153) (xy 257.954471 -327.720647) (xy 257.962229 -327.666696)
			(xy 257.977585 -327.614398) (xy 258.000229 -327.564819) (xy 258.029698 -327.518966) (xy 258.065393 -327.477775)
			(xy 258.106587 -327.442082) (xy 258.152442 -327.412616) (xy 258.202023 -327.389976) (xy 258.254322 -327.374623)
			(xy 258.308273 -327.36687) (xy 258.335526 -327.366376) (xy 258.358882 -327.366741) (xy 258.405242 -327.372467)
			(xy 258.427982 -327.377806) (xy 258.428744 -327.37806) (xy 258.436618 -327.380092) (xy 258.445762 -327.379076)
			(xy 258.450405 -327.378408) (xy 258.459352 -327.375597) (xy 258.463542 -327.373488) (xy 258.523994 -327.34123)
			(xy 258.528059 -327.338987) (xy 258.535346 -327.333233) (xy 258.538472 -327.3298) (xy 258.544568 -327.322942)
			(xy 258.54787 -327.314052) (xy 258.558445 -327.287015) (xy 258.586595 -327.236243) (xy 258.622114 -327.190323)
			(xy 258.664182 -327.150317) (xy 258.711827 -327.117149) (xy 258.763949 -327.091584) (xy 258.819343 -327.074214)
			(xy 258.876729 -327.065439) (xy 258.905756 -327.064878) (xy 258.90601 -327.064878) (xy 258.933686 -327.065367)
			(xy 258.988456 -327.073361) (xy 259.041494 -327.089193) (xy 259.091684 -327.112532) (xy 259.137971 -327.142885)
			(xy 259.158994 -327.16089) (xy 259.162296 -327.163938) (xy 259.170424 -327.169018) (xy 259.17144 -327.169526)
			(xy 259.177612 -327.173013) (xy 259.191277 -327.176757) (xy 259.198364 -327.176892) (xy 259.266944 -327.175876)
			(xy 259.271714 -327.175616) (xy 259.281045 -327.173573) (xy 259.285486 -327.171812) (xy 259.293614 -327.16851)
			(xy 259.30098 -327.161652) (xy 259.321052 -327.143107) (xy 259.365538 -327.111368) (xy 259.414103 -327.08631)
			(xy 259.465749 -327.068449) (xy 259.492496 -327.062846) (xy 259.494528 -327.062338) (xy 259.505454 -327.059145)
			(xy 259.523185 -327.044918) (xy 259.53303 -327.024428) (xy 259.533644 -327.013062) (xy 259.533644 -310.163972)
			(xy 259.53355 -310.159094) (xy 259.531765 -310.149503) (xy 259.530088 -310.144922) (xy 259.526278 -310.135778)
			(xy 258.2799 -308.8894) (xy 258.277048 -308.886696) (xy 258.270668 -308.882105) (xy 258.2672 -308.880256)
			(xy 258.261775 -308.877666) (xy 258.250095 -308.874829) (xy 258.244086 -308.874668) (xy 238.408464 -308.874668)
			(xy 238.403573 -308.874803) (xy 238.393979 -308.876717) (xy 238.389414 -308.878478) (xy 238.379762 -308.882288)
			(xy 235.939076 -308.882288) (xy 235.929007 -308.882715) (xy 235.910408 -308.890434) (xy 235.903008 -308.897274)
			(xy 235.369862 -309.43042) (xy 235.363012 -309.437817) (xy 235.355275 -309.456415) (xy 235.354876 -309.466488)
			(xy 235.354876 -317.206376) (xy 237.479838 -317.206376) (xy 237.483909 -317.150754) (xy 237.496035 -317.096317)
			(xy 237.515958 -317.044226) (xy 237.543254 -316.995591) (xy 237.57734 -316.951448) (xy 237.617489 -316.912739)
			(xy 237.662847 -316.880288) (xy 237.712447 -316.854787) (xy 237.765231 -316.83678) (xy 237.820074 -316.82665)
			(xy 237.875808 -316.824613) (xy 237.931245 -316.830713) (xy 237.985202 -316.844819) (xy 238.036531 -316.866631)
			(xy 238.084137 -316.895685) (xy 238.127005 -316.93136) (xy 238.164222 -316.972897) (xy 238.194995 -317.01941)
			(xy 238.218667 -317.069907) (xy 238.234735 -317.123314) (xy 238.242855 -317.17849) (xy 238.243364 -317.206376)
			(xy 238.243012 -317.22568) (xy 238.579406 -317.22568) (xy 238.579979 -317.196765) (xy 238.588697 -317.139596)
			(xy 238.605943 -317.084398) (xy 238.631325 -317.032436) (xy 238.664259 -316.984901) (xy 238.703991 -316.942882)
			(xy 238.726472 -316.92469) (xy 238.735286 -316.91709) (xy 238.745463 -316.896183) (xy 238.74603 -316.884558)
			(xy 238.74603 -316.804802) (xy 238.7455 -316.793168) (xy 238.735307 -316.772257) (xy 238.726472 -316.76467)
			(xy 238.703968 -316.746503) (xy 238.664236 -316.704477) (xy 238.6313 -316.656937) (xy 238.605915 -316.604971)
			(xy 238.588663 -316.54977) (xy 238.579939 -316.492597) (xy 238.579406 -316.46368) (xy 238.579892 -316.436429)
			(xy 238.587648 -316.382481) (xy 238.603003 -316.330186) (xy 238.625645 -316.280609) (xy 238.655111 -316.234759)
			(xy 238.690802 -316.193568) (xy 238.731993 -316.157877) (xy 238.777843 -316.128411) (xy 238.82742 -316.105769)
			(xy 238.879715 -316.090414) (xy 238.933663 -316.082658) (xy 238.988165 -316.082658) (xy 239.042113 -316.090414)
			(xy 239.094408 -316.105769) (xy 239.143985 -316.128411) (xy 239.189835 -316.157877) (xy 239.231026 -316.193568)
			(xy 239.266717 -316.234759) (xy 239.296183 -316.280609) (xy 239.318825 -316.330186) (xy 239.33418 -316.382481)
			(xy 239.341936 -316.436429) (xy 239.342422 -316.46368) (xy 239.341919 -316.492598) (xy 239.333191 -316.549771)
			(xy 239.315932 -316.604972) (xy 239.290538 -316.656934) (xy 239.25759 -316.704467) (xy 239.217844 -316.746482)
			(xy 239.195356 -316.76467) (xy 239.186565 -316.772293) (xy 239.176374 -316.793182) (xy 239.175798 -316.804802)
			(xy 239.175798 -316.884558) (xy 239.176319 -316.896192) (xy 239.186521 -316.917101) (xy 239.195356 -316.92469)
			(xy 239.217826 -316.942898) (xy 239.257564 -316.984913) (xy 239.290506 -317.032444) (xy 239.315897 -317.084402)
			(xy 239.333155 -317.139597) (xy 239.341886 -317.196765) (xy 239.342422 -317.22568) (xy 239.342422 -317.225934)
			(xy 239.342005 -317.252608) (xy 239.334557 -317.305433) (xy 239.319825 -317.356707) (xy 239.298097 -317.405429)
			(xy 239.269795 -317.450651) (xy 239.235471 -317.49149) (xy 239.21593 -317.509652) (xy 239.207294 -317.517272)
			(xy 239.198404 -317.538354) (xy 239.202468 -317.628016) (xy 239.203629 -317.639229) (xy 239.214149 -317.659131)
			(xy 239.222788 -317.66637) (xy 239.246075 -317.684499) (xy 239.287267 -317.726759) (xy 239.321465 -317.774855)
			(xy 239.347854 -317.827641) (xy 239.365805 -317.88386) (xy 239.37489 -317.942171) (xy 239.375442 -317.971678)
			(xy 239.374956 -317.998929) (xy 239.3672 -318.052877) (xy 239.351845 -318.105172) (xy 239.329203 -318.154749)
			(xy 239.299737 -318.200599) (xy 239.264046 -318.24179) (xy 239.222855 -318.277481) (xy 239.177005 -318.306947)
			(xy 239.127428 -318.329589) (xy 239.075133 -318.344944) (xy 239.021185 -318.3527) (xy 238.966683 -318.3527)
			(xy 238.912735 -318.344944) (xy 238.86044 -318.329589) (xy 238.810863 -318.306947) (xy 238.765013 -318.277481)
			(xy 238.723822 -318.24179) (xy 238.688131 -318.200599) (xy 238.658665 -318.154749) (xy 238.636023 -318.105172)
			(xy 238.620668 -318.052877) (xy 238.612912 -317.998929) (xy 238.612426 -317.971678) (xy 238.612426 -317.971424)
			(xy 238.6129 -317.944752) (xy 238.620338 -317.89193) (xy 238.63506 -317.840658) (xy 238.656778 -317.791936)
			(xy 238.685069 -317.746713) (xy 238.719382 -317.70587) (xy 238.738918 -317.687706) (xy 238.747554 -317.680086)
			(xy 238.756444 -317.659004) (xy 238.75238 -317.569342) (xy 238.75126 -317.558121) (xy 238.740713 -317.53822)
			(xy 238.73206 -317.530988) (xy 238.708805 -317.512817) (xy 238.6676 -317.470574) (xy 238.633391 -317.422489)
			(xy 238.606994 -317.369709) (xy 238.589039 -317.313495) (xy 238.579955 -317.255186) (xy 238.579406 -317.22568)
			(xy 238.243012 -317.22568) (xy 238.242855 -317.234262) (xy 238.234735 -317.289438) (xy 238.218667 -317.342845)
			(xy 238.194995 -317.393342) (xy 238.164222 -317.439855) (xy 238.127005 -317.481392) (xy 238.084137 -317.517067)
			(xy 238.036531 -317.546121) (xy 237.985202 -317.567933) (xy 237.931245 -317.582039) (xy 237.875808 -317.588139)
			(xy 237.820074 -317.586102) (xy 237.765231 -317.575972) (xy 237.712447 -317.557965) (xy 237.662847 -317.532464)
			(xy 237.617489 -317.500013) (xy 237.57734 -317.461304) (xy 237.543254 -317.417161) (xy 237.515958 -317.368526)
			(xy 237.496035 -317.316435) (xy 237.483909 -317.261998) (xy 237.479838 -317.206376) (xy 235.354876 -317.206376)
			(xy 235.354876 -318.70448) (xy 239.823475 -318.70448) (xy 239.827208 -318.651225) (xy 239.838329 -318.59901)
			(xy 239.856619 -318.548855) (xy 239.881723 -318.50174) (xy 239.91315 -318.458584) (xy 239.950286 -318.420231)
			(xy 239.971072 -318.403478) (xy 239.979891 -318.395883) (xy 239.990065 -318.374973) (xy 239.99063 -318.363346)
			(xy 239.99063 -318.28359) (xy 239.990107 -318.271955) (xy 239.979909 -318.251044) (xy 239.971072 -318.243458)
			(xy 239.948563 -318.225298) (xy 239.90883 -318.183271) (xy 239.875895 -318.135729) (xy 239.850511 -318.083762)
			(xy 239.833261 -318.028559) (xy 239.824538 -317.971386) (xy 239.824006 -317.942468) (xy 239.824492 -317.915217)
			(xy 239.832248 -317.861269) (xy 239.847603 -317.808974) (xy 239.870245 -317.759397) (xy 239.899711 -317.713547)
			(xy 239.935402 -317.672356) (xy 239.976593 -317.636665) (xy 240.022443 -317.607199) (xy 240.07202 -317.584557)
			(xy 240.124315 -317.569202) (xy 240.178263 -317.561446) (xy 240.232765 -317.561446) (xy 240.286713 -317.569202)
			(xy 240.339008 -317.584557) (xy 240.388585 -317.607199) (xy 240.434435 -317.636665) (xy 240.475626 -317.672356)
			(xy 240.511317 -317.713547) (xy 240.540783 -317.759397) (xy 240.563425 -317.808974) (xy 240.57878 -317.861269)
			(xy 240.586536 -317.915217) (xy 240.587022 -317.942468) (xy 240.58651 -317.971386) (xy 240.577784 -318.028558)
			(xy 240.560527 -318.083759) (xy 240.535134 -318.135721) (xy 240.502188 -318.183255) (xy 240.462443 -318.225269)
			(xy 240.439956 -318.243458) (xy 240.431171 -318.251086) (xy 240.420977 -318.271971) (xy 240.420398 -318.28359)
			(xy 240.420398 -318.363346) (xy 240.420926 -318.374979) (xy 240.431123 -318.395889) (xy 240.439956 -318.403478)
			(xy 240.460707 -318.420269) (xy 240.497835 -318.458619) (xy 240.529256 -318.501769) (xy 240.554354 -318.548878)
			(xy 240.572641 -318.599026) (xy 240.583759 -318.651233) (xy 240.587492 -318.70448) (xy 242.211075 -318.70448)
			(xy 242.214808 -318.651225) (xy 242.225929 -318.59901) (xy 242.244219 -318.548855) (xy 242.269323 -318.50174)
			(xy 242.30075 -318.458584) (xy 242.337886 -318.420231) (xy 242.358672 -318.403478) (xy 242.367491 -318.395883)
			(xy 242.377665 -318.374973) (xy 242.37823 -318.363346) (xy 242.37823 -318.28359) (xy 242.377707 -318.271955)
			(xy 242.367509 -318.251044) (xy 242.358672 -318.243458) (xy 242.336163 -318.225298) (xy 242.29643 -318.183271)
			(xy 242.263495 -318.135729) (xy 242.238111 -318.083762) (xy 242.220861 -318.028559) (xy 242.212138 -317.971386)
			(xy 242.211606 -317.942468) (xy 242.212081 -317.914872) (xy 242.220051 -317.860258) (xy 242.235805 -317.807362)
			(xy 242.259015 -317.757287) (xy 242.289197 -317.711078) (xy 242.32572 -317.669699) (xy 242.367824 -317.634013)
			(xy 242.414629 -317.604764) (xy 242.439698 -317.593218) (xy 242.44972 -317.588168) (xy 242.46449 -317.571314)
			(xy 242.468146 -317.560706) (xy 242.489482 -317.485268) (xy 242.492012 -317.474245) (xy 242.488319 -317.451961)
			(xy 242.48237 -317.442342) (xy 242.466424 -317.418329) (xy 242.441172 -317.366513) (xy 242.424011 -317.311485)
			(xy 242.415334 -317.254501) (xy 242.414806 -317.22568) (xy 242.415379 -317.196765) (xy 242.424097 -317.139596)
			(xy 242.441343 -317.084398) (xy 242.466725 -317.032436) (xy 242.499659 -316.984901) (xy 242.539391 -316.942882)
			(xy 242.561872 -316.92469) (xy 242.570686 -316.91709) (xy 242.580863 -316.896183) (xy 242.58143 -316.884558)
			(xy 242.58143 -316.804802) (xy 242.5809 -316.793168) (xy 242.570707 -316.772257) (xy 242.561872 -316.76467)
			(xy 242.539368 -316.746503) (xy 242.499636 -316.704477) (xy 242.4667 -316.656937) (xy 242.441315 -316.604971)
			(xy 242.424063 -316.54977) (xy 242.415339 -316.492597) (xy 242.414806 -316.46368) (xy 242.415292 -316.436429)
			(xy 242.423048 -316.382481) (xy 242.438403 -316.330186) (xy 242.461045 -316.280609) (xy 242.490511 -316.234759)
			(xy 242.526202 -316.193568) (xy 242.567393 -316.157877) (xy 242.613243 -316.128411) (xy 242.66282 -316.105769)
			(xy 242.715115 -316.090414) (xy 242.769063 -316.082658) (xy 242.823565 -316.082658) (xy 242.877513 -316.090414)
			(xy 242.929808 -316.105769) (xy 242.979385 -316.128411) (xy 243.025235 -316.157877) (xy 243.066426 -316.193568)
			(xy 243.102117 -316.234759) (xy 243.131583 -316.280609) (xy 243.154225 -316.330186) (xy 243.16958 -316.382481)
			(xy 243.177336 -316.436429) (xy 243.177822 -316.46368) (xy 243.177319 -316.492598) (xy 243.168591 -316.549771)
			(xy 243.151332 -316.604972) (xy 243.125938 -316.656934) (xy 243.09299 -316.704467) (xy 243.053244 -316.746482)
			(xy 243.030756 -316.76467) (xy 243.021965 -316.772293) (xy 243.011774 -316.793182) (xy 243.011198 -316.804802)
			(xy 243.011198 -316.884558) (xy 243.011719 -316.896192) (xy 243.021921 -316.917101) (xy 243.030756 -316.92469)
			(xy 243.053226 -316.942898) (xy 243.092964 -316.984913) (xy 243.125906 -317.032444) (xy 243.151297 -317.084402)
			(xy 243.168555 -317.139597) (xy 243.177286 -317.196765) (xy 243.177822 -317.22568) (xy 244.472206 -317.22568)
			(xy 244.472779 -317.196765) (xy 244.481497 -317.139596) (xy 244.498743 -317.084398) (xy 244.524125 -317.032436)
			(xy 244.557059 -316.984901) (xy 244.596791 -316.942882) (xy 244.619272 -316.92469) (xy 244.628086 -316.91709)
			(xy 244.638263 -316.896183) (xy 244.63883 -316.884558) (xy 244.63883 -316.804802) (xy 244.6383 -316.793168)
			(xy 244.628107 -316.772257) (xy 244.619272 -316.76467) (xy 244.596768 -316.746503) (xy 244.557036 -316.704477)
			(xy 244.5241 -316.656937) (xy 244.498715 -316.604971) (xy 244.481463 -316.54977) (xy 244.472739 -316.492597)
			(xy 244.472206 -316.46368) (xy 244.472692 -316.436429) (xy 244.480448 -316.382481) (xy 244.495803 -316.330186)
			(xy 244.518445 -316.280609) (xy 244.547911 -316.234759) (xy 244.583602 -316.193568) (xy 244.624793 -316.157877)
			(xy 244.670643 -316.128411) (xy 244.72022 -316.105769) (xy 244.772515 -316.090414) (xy 244.826463 -316.082658)
			(xy 244.880965 -316.082658) (xy 244.934913 -316.090414) (xy 244.987208 -316.105769) (xy 245.036785 -316.128411)
			(xy 245.082635 -316.157877) (xy 245.123826 -316.193568) (xy 245.159517 -316.234759) (xy 245.188983 -316.280609)
			(xy 245.211625 -316.330186) (xy 245.22698 -316.382481) (xy 245.234736 -316.436429) (xy 245.235222 -316.46368)
			(xy 245.234719 -316.492598) (xy 245.225991 -316.549771) (xy 245.208732 -316.604972) (xy 245.183338 -316.656934)
			(xy 245.15039 -316.704467) (xy 245.110644 -316.746482) (xy 245.088156 -316.76467) (xy 245.079365 -316.772293)
			(xy 245.069174 -316.793182) (xy 245.068598 -316.804802) (xy 245.068598 -316.884558) (xy 245.069119 -316.896192)
			(xy 245.079321 -316.917101) (xy 245.088156 -316.92469) (xy 245.110626 -316.942898) (xy 245.150364 -316.984913)
			(xy 245.183306 -317.032444) (xy 245.208697 -317.084402) (xy 245.225955 -317.139597) (xy 245.234686 -317.196765)
			(xy 245.235222 -317.22568) (xy 245.23473 -317.253149) (xy 245.226852 -317.307519) (xy 245.211258 -317.360196)
			(xy 245.188269 -317.410093) (xy 245.158361 -317.456175) (xy 245.122152 -317.497492) (xy 245.080391 -317.533187)
			(xy 245.057422 -317.54826) (xy 245.045992 -317.555372) (xy 245.033292 -317.57874) (xy 245.035832 -317.692786)
			(xy 245.049294 -317.715646) (xy 245.060978 -317.72225) (xy 245.08549 -317.736983) (xy 245.130248 -317.772578)
			(xy 245.169193 -317.814455) (xy 245.201451 -317.861676) (xy 245.226301 -317.913181) (xy 245.243186 -317.967819)
			(xy 245.251727 -318.024365) (xy 245.25224 -318.052958) (xy 245.251754 -318.080209) (xy 245.243998 -318.134157)
			(xy 245.228643 -318.186452) (xy 245.206001 -318.236029) (xy 245.176535 -318.281879) (xy 245.140844 -318.32307)
			(xy 245.099653 -318.358761) (xy 245.053803 -318.388227) (xy 245.004226 -318.410869) (xy 244.951931 -318.426224)
			(xy 244.897983 -318.43398) (xy 244.843481 -318.43398) (xy 244.789533 -318.426224) (xy 244.737238 -318.410869)
			(xy 244.687661 -318.388227) (xy 244.641811 -318.358761) (xy 244.60062 -318.32307) (xy 244.564929 -318.281879)
			(xy 244.535463 -318.236029) (xy 244.512821 -318.186452) (xy 244.497466 -318.134157) (xy 244.48971 -318.080209)
			(xy 244.489224 -318.052958) (xy 244.489724 -318.025489) (xy 244.497597 -317.971119) (xy 244.513189 -317.91844)
			(xy 244.536176 -317.868543) (xy 244.566084 -317.82246) (xy 244.602293 -317.781144) (xy 244.644055 -317.74545)
			(xy 244.667024 -317.730378) (xy 244.678454 -317.723266) (xy 244.691154 -317.699898) (xy 244.688614 -317.585852)
			(xy 244.675152 -317.562992) (xy 244.663468 -317.556388) (xy 244.638916 -317.541719) (xy 244.59416 -317.506111)
			(xy 244.55522 -317.464222) (xy 244.522967 -317.416991) (xy 244.498124 -317.365475) (xy 244.481247 -317.310829)
			(xy 244.472714 -317.254276) (xy 244.472206 -317.22568) (xy 243.177822 -317.22568) (xy 243.177287 -317.253274)
			(xy 243.169325 -317.307884) (xy 243.153579 -317.360778) (xy 243.130377 -317.410852) (xy 243.100204 -317.457061)
			(xy 243.063689 -317.498441) (xy 243.021593 -317.53413) (xy 242.974796 -317.563381) (xy 242.94973 -317.57493)
			(xy 242.9397 -317.579967) (xy 242.924933 -317.59683) (xy 242.921282 -317.607442) (xy 242.899946 -317.68288)
			(xy 242.897444 -317.693908) (xy 242.901117 -317.716187) (xy 242.907058 -317.725806) (xy 242.923028 -317.749804)
			(xy 242.948274 -317.801626) (xy 242.965428 -317.856658) (xy 242.974098 -317.913646) (xy 242.974622 -317.942468)
			(xy 242.97411 -317.971386) (xy 242.965384 -318.028558) (xy 242.948127 -318.083759) (xy 242.922734 -318.135721)
			(xy 242.889788 -318.183255) (xy 242.850043 -318.225269) (xy 242.827556 -318.243458) (xy 242.818771 -318.251086)
			(xy 242.808577 -318.271971) (xy 242.807998 -318.28359) (xy 242.807998 -318.363346) (xy 242.808526 -318.374979)
			(xy 242.818723 -318.395889) (xy 242.827556 -318.403478) (xy 242.848307 -318.420269) (xy 242.885435 -318.458619)
			(xy 242.916856 -318.501769) (xy 242.941954 -318.548878) (xy 242.960241 -318.599026) (xy 242.971359 -318.651233)
			(xy 242.975092 -318.70448) (xy 245.919475 -318.70448) (xy 245.923208 -318.651225) (xy 245.934329 -318.59901)
			(xy 245.952619 -318.548855) (xy 245.977723 -318.50174) (xy 246.00915 -318.458584) (xy 246.046286 -318.420231)
			(xy 246.067072 -318.403478) (xy 246.075891 -318.395883) (xy 246.086065 -318.374973) (xy 246.08663 -318.363346)
			(xy 246.08663 -318.28359) (xy 246.086107 -318.271955) (xy 246.075909 -318.251044) (xy 246.067072 -318.243458)
			(xy 246.044563 -318.225298) (xy 246.00483 -318.183271) (xy 245.971895 -318.135729) (xy 245.946511 -318.083762)
			(xy 245.929261 -318.028559) (xy 245.920538 -317.971386) (xy 245.920006 -317.942468) (xy 245.920492 -317.915217)
			(xy 245.928248 -317.861269) (xy 245.943603 -317.808974) (xy 245.966245 -317.759397) (xy 245.995711 -317.713547)
			(xy 246.031402 -317.672356) (xy 246.072593 -317.636665) (xy 246.118443 -317.607199) (xy 246.16802 -317.584557)
			(xy 246.220315 -317.569202) (xy 246.274263 -317.561446) (xy 246.328765 -317.561446) (xy 246.382713 -317.569202)
			(xy 246.435008 -317.584557) (xy 246.484585 -317.607199) (xy 246.530435 -317.636665) (xy 246.571626 -317.672356)
			(xy 246.607317 -317.713547) (xy 246.636783 -317.759397) (xy 246.659425 -317.808974) (xy 246.67478 -317.861269)
			(xy 246.682536 -317.915217) (xy 246.683022 -317.942468) (xy 246.68251 -317.971386) (xy 246.673784 -318.028558)
			(xy 246.656527 -318.083759) (xy 246.631134 -318.135721) (xy 246.598188 -318.183255) (xy 246.558443 -318.225269)
			(xy 246.535956 -318.243458) (xy 246.527171 -318.251086) (xy 246.516977 -318.271971) (xy 246.516398 -318.28359)
			(xy 246.516398 -318.363346) (xy 246.516926 -318.374979) (xy 246.527123 -318.395889) (xy 246.535956 -318.403478)
			(xy 246.556707 -318.420269) (xy 246.593835 -318.458619) (xy 246.625256 -318.501769) (xy 246.650354 -318.548878)
			(xy 246.668641 -318.599026) (xy 246.679759 -318.651233) (xy 246.683492 -318.70448) (xy 248.307075 -318.70448)
			(xy 248.310808 -318.651225) (xy 248.321929 -318.59901) (xy 248.340219 -318.548855) (xy 248.365323 -318.50174)
			(xy 248.39675 -318.458584) (xy 248.433886 -318.420231) (xy 248.454672 -318.403478) (xy 248.463491 -318.395883)
			(xy 248.473665 -318.374973) (xy 248.47423 -318.363346) (xy 248.47423 -318.28359) (xy 248.473707 -318.271955)
			(xy 248.463509 -318.251044) (xy 248.454672 -318.243458) (xy 248.432163 -318.225298) (xy 248.39243 -318.183271)
			(xy 248.359495 -318.135729) (xy 248.334111 -318.083762) (xy 248.316861 -318.028559) (xy 248.308138 -317.971386)
			(xy 248.307606 -317.942468) (xy 248.308023 -317.915885) (xy 248.315415 -317.863236) (xy 248.33005 -317.812124)
			(xy 248.351646 -317.763541) (xy 248.379782 -317.718431) (xy 248.413913 -317.677667) (xy 248.433336 -317.659512)
			(xy 248.440949 -317.652039) (xy 248.449637 -317.632577) (xy 248.4501 -317.62192) (xy 248.4501 -317.546228)
			(xy 248.449492 -317.535601) (xy 248.440842 -317.516181) (xy 248.433336 -317.508636) (xy 248.413902 -317.490495)
			(xy 248.379783 -317.449724) (xy 248.351658 -317.404608) (xy 248.330074 -317.356023) (xy 248.315449 -317.304911)
			(xy 248.308066 -317.252262) (xy 248.307606 -317.22568) (xy 248.308179 -317.196765) (xy 248.316897 -317.139596)
			(xy 248.334143 -317.084398) (xy 248.359525 -317.032436) (xy 248.392459 -316.984901) (xy 248.432191 -316.942882)
			(xy 248.454672 -316.92469) (xy 248.463486 -316.91709) (xy 248.473663 -316.896183) (xy 248.47423 -316.884558)
			(xy 248.47423 -316.804802) (xy 248.4737 -316.793168) (xy 248.463507 -316.772257) (xy 248.454672 -316.76467)
			(xy 248.432168 -316.746503) (xy 248.392436 -316.704477) (xy 248.3595 -316.656937) (xy 248.334115 -316.604971)
			(xy 248.316863 -316.54977) (xy 248.308139 -316.492597) (xy 248.307606 -316.46368) (xy 248.308092 -316.436429)
			(xy 248.315848 -316.382481) (xy 248.331203 -316.330186) (xy 248.353845 -316.280609) (xy 248.383311 -316.234759)
			(xy 248.419002 -316.193568) (xy 248.460193 -316.157877) (xy 248.506043 -316.128411) (xy 248.55562 -316.105769)
			(xy 248.607915 -316.090414) (xy 248.661863 -316.082658) (xy 248.716365 -316.082658) (xy 248.770313 -316.090414)
			(xy 248.822608 -316.105769) (xy 248.872185 -316.128411) (xy 248.918035 -316.157877) (xy 248.959226 -316.193568)
			(xy 248.994917 -316.234759) (xy 249.024383 -316.280609) (xy 249.047025 -316.330186) (xy 249.06238 -316.382481)
			(xy 249.070136 -316.436429) (xy 249.070622 -316.46368) (xy 249.070119 -316.492598) (xy 249.061391 -316.549771)
			(xy 249.044132 -316.604972) (xy 249.018738 -316.656934) (xy 248.98579 -316.704467) (xy 248.946044 -316.746482)
			(xy 248.923556 -316.76467) (xy 248.914765 -316.772293) (xy 248.904574 -316.793182) (xy 248.903998 -316.804802)
			(xy 248.903998 -316.884558) (xy 248.904519 -316.896192) (xy 248.914721 -316.917101) (xy 248.923556 -316.92469)
			(xy 248.946026 -316.942898) (xy 248.985764 -316.984913) (xy 249.018706 -317.032444) (xy 249.044097 -317.084402)
			(xy 249.061355 -317.139597) (xy 249.070086 -317.196765) (xy 249.070622 -317.22568) (xy 249.070161 -317.252261)
			(xy 249.062777 -317.304908) (xy 249.048149 -317.356019) (xy 249.026562 -317.404601) (xy 248.998434 -317.449713)
			(xy 248.964311 -317.490479) (xy 248.944892 -317.508636) (xy 248.937262 -317.516094) (xy 248.928583 -317.535567)
			(xy 248.928128 -317.546228) (xy 248.928128 -317.62192) (xy 248.928731 -317.632547) (xy 248.937387 -317.651965)
			(xy 248.944892 -317.659512) (xy 248.964287 -317.677694) (xy 248.998413 -317.718454) (xy 249.026544 -317.763561)
			(xy 249.048135 -317.812138) (xy 249.062768 -317.863244) (xy 249.070159 -317.915888) (xy 249.070622 -317.942468)
			(xy 249.07011 -317.971386) (xy 249.061384 -318.028558) (xy 249.044127 -318.083759) (xy 249.018734 -318.135721)
			(xy 248.985788 -318.183255) (xy 248.946043 -318.225269) (xy 248.923556 -318.243458) (xy 248.914771 -318.251086)
			(xy 248.904577 -318.271971) (xy 248.903998 -318.28359) (xy 248.903998 -318.363346) (xy 248.904526 -318.374979)
			(xy 248.914723 -318.395889) (xy 248.923556 -318.403478) (xy 248.944307 -318.420269) (xy 248.981435 -318.458619)
			(xy 249.012856 -318.501769) (xy 249.037954 -318.548878) (xy 249.056241 -318.599026) (xy 249.067359 -318.651233)
			(xy 249.071092 -318.70448) (xy 249.067365 -318.757728) (xy 249.056252 -318.809936) (xy 249.03797 -318.860086)
			(xy 249.012877 -318.907197) (xy 248.981461 -318.950351) (xy 248.944336 -318.988704) (xy 248.923556 -319.005458)
			(xy 248.914771 -319.013086) (xy 248.904577 -319.033971) (xy 248.903998 -319.04559) (xy 248.903998 -319.125346)
			(xy 248.904526 -319.136979) (xy 248.914723 -319.157889) (xy 248.923556 -319.165478) (xy 248.94602 -319.183693)
			(xy 248.985758 -319.225706) (xy 249.018701 -319.273236) (xy 249.044093 -319.325193) (xy 249.061353 -319.380387)
			(xy 249.070085 -319.437553) (xy 249.070622 -319.466468) (xy 249.070136 -319.493719) (xy 249.06238 -319.547667)
			(xy 249.047025 -319.599962) (xy 249.024383 -319.649539) (xy 248.994917 -319.695389) (xy 248.959226 -319.73658)
			(xy 248.918035 -319.772271) (xy 248.872185 -319.801737) (xy 248.822608 -319.824379) (xy 248.770313 -319.839734)
			(xy 248.716365 -319.84749) (xy 248.661863 -319.84749) (xy 248.607915 -319.839734) (xy 248.55562 -319.824379)
			(xy 248.506043 -319.801737) (xy 248.460193 -319.772271) (xy 248.419002 -319.73658) (xy 248.383311 -319.695389)
			(xy 248.353845 -319.649539) (xy 248.331203 -319.599962) (xy 248.315848 -319.547667) (xy 248.308092 -319.493719)
			(xy 248.307606 -319.466468) (xy 248.308171 -319.437553) (xy 248.31689 -319.380384) (xy 248.334138 -319.325186)
			(xy 248.359521 -319.273224) (xy 248.392457 -319.225689) (xy 248.43219 -319.18367) (xy 248.454672 -319.165478)
			(xy 248.463491 -319.157883) (xy 248.473665 -319.136973) (xy 248.47423 -319.125346) (xy 248.47423 -319.04559)
			(xy 248.473707 -319.033955) (xy 248.463509 -319.013044) (xy 248.454672 -319.005458) (xy 248.433857 -318.988743)
			(xy 248.396725 -318.950386) (xy 248.365302 -318.907227) (xy 248.340203 -318.860109) (xy 248.321918 -318.809952)
			(xy 248.310803 -318.757736) (xy 248.307075 -318.70448) (xy 246.683492 -318.70448) (xy 246.679765 -318.757728)
			(xy 246.668652 -318.809936) (xy 246.65037 -318.860086) (xy 246.625277 -318.907197) (xy 246.593861 -318.950351)
			(xy 246.556736 -318.988704) (xy 246.535956 -319.005458) (xy 246.527171 -319.013086) (xy 246.516977 -319.033971)
			(xy 246.516398 -319.04559) (xy 246.516398 -319.125346) (xy 246.516926 -319.136979) (xy 246.527123 -319.157889)
			(xy 246.535956 -319.165478) (xy 246.55842 -319.183693) (xy 246.598158 -319.225706) (xy 246.631101 -319.273236)
			(xy 246.656493 -319.325193) (xy 246.673753 -319.380387) (xy 246.682485 -319.437553) (xy 246.683022 -319.466468)
			(xy 246.682536 -319.493719) (xy 246.67478 -319.547667) (xy 246.659425 -319.599962) (xy 246.636783 -319.649539)
			(xy 246.607317 -319.695389) (xy 246.571626 -319.73658) (xy 246.530435 -319.772271) (xy 246.484585 -319.801737)
			(xy 246.435008 -319.824379) (xy 246.382713 -319.839734) (xy 246.328765 -319.84749) (xy 246.274263 -319.84749)
			(xy 246.220315 -319.839734) (xy 246.16802 -319.824379) (xy 246.118443 -319.801737) (xy 246.072593 -319.772271)
			(xy 246.031402 -319.73658) (xy 245.995711 -319.695389) (xy 245.966245 -319.649539) (xy 245.943603 -319.599962)
			(xy 245.928248 -319.547667) (xy 245.920492 -319.493719) (xy 245.920006 -319.466468) (xy 245.920571 -319.437553)
			(xy 245.92929 -319.380384) (xy 245.946538 -319.325186) (xy 245.971921 -319.273224) (xy 246.004857 -319.225689)
			(xy 246.04459 -319.18367) (xy 246.067072 -319.165478) (xy 246.075891 -319.157883) (xy 246.086065 -319.136973)
			(xy 246.08663 -319.125346) (xy 246.08663 -319.04559) (xy 246.086107 -319.033955) (xy 246.075909 -319.013044)
			(xy 246.067072 -319.005458) (xy 246.046257 -318.988743) (xy 246.009125 -318.950386) (xy 245.977702 -318.907227)
			(xy 245.952603 -318.860109) (xy 245.934318 -318.809952) (xy 245.923203 -318.757736) (xy 245.919475 -318.70448)
			(xy 242.975092 -318.70448) (xy 242.971365 -318.757728) (xy 242.960252 -318.809936) (xy 242.94197 -318.860086)
			(xy 242.916877 -318.907197) (xy 242.885461 -318.950351) (xy 242.848336 -318.988704) (xy 242.827556 -319.005458)
			(xy 242.818771 -319.013086) (xy 242.808577 -319.033971) (xy 242.807998 -319.04559) (xy 242.807998 -319.125346)
			(xy 242.808526 -319.136979) (xy 242.818723 -319.157889) (xy 242.827556 -319.165478) (xy 242.85002 -319.183693)
			(xy 242.889758 -319.225706) (xy 242.922701 -319.273236) (xy 242.948093 -319.325193) (xy 242.965353 -319.380387)
			(xy 242.974085 -319.437553) (xy 242.974622 -319.466468) (xy 242.974136 -319.493719) (xy 242.96638 -319.547667)
			(xy 242.951025 -319.599962) (xy 242.928383 -319.649539) (xy 242.898917 -319.695389) (xy 242.863226 -319.73658)
			(xy 242.822035 -319.772271) (xy 242.776185 -319.801737) (xy 242.726608 -319.824379) (xy 242.674313 -319.839734)
			(xy 242.620365 -319.84749) (xy 242.565863 -319.84749) (xy 242.511915 -319.839734) (xy 242.45962 -319.824379)
			(xy 242.410043 -319.801737) (xy 242.364193 -319.772271) (xy 242.323002 -319.73658) (xy 242.287311 -319.695389)
			(xy 242.257845 -319.649539) (xy 242.235203 -319.599962) (xy 242.219848 -319.547667) (xy 242.212092 -319.493719)
			(xy 242.211606 -319.466468) (xy 242.212171 -319.437553) (xy 242.22089 -319.380384) (xy 242.238138 -319.325186)
			(xy 242.263521 -319.273224) (xy 242.296457 -319.225689) (xy 242.33619 -319.18367) (xy 242.358672 -319.165478)
			(xy 242.367491 -319.157883) (xy 242.377665 -319.136973) (xy 242.37823 -319.125346) (xy 242.37823 -319.04559)
			(xy 242.377707 -319.033955) (xy 242.367509 -319.013044) (xy 242.358672 -319.005458) (xy 242.337857 -318.988743)
			(xy 242.300725 -318.950386) (xy 242.269302 -318.907227) (xy 242.244203 -318.860109) (xy 242.225918 -318.809952)
			(xy 242.214803 -318.757736) (xy 242.211075 -318.70448) (xy 240.587492 -318.70448) (xy 240.583765 -318.757728)
			(xy 240.572652 -318.809936) (xy 240.55437 -318.860086) (xy 240.529277 -318.907197) (xy 240.497861 -318.950351)
			(xy 240.460736 -318.988704) (xy 240.439956 -319.005458) (xy 240.431171 -319.013086) (xy 240.420977 -319.033971)
			(xy 240.420398 -319.04559) (xy 240.420398 -319.125346) (xy 240.420926 -319.136979) (xy 240.431123 -319.157889)
			(xy 240.439956 -319.165478) (xy 240.46242 -319.183693) (xy 240.502158 -319.225706) (xy 240.535101 -319.273236)
			(xy 240.560493 -319.325193) (xy 240.577753 -319.380387) (xy 240.586485 -319.437553) (xy 240.587022 -319.466468)
			(xy 240.586536 -319.493719) (xy 240.57878 -319.547667) (xy 240.563425 -319.599962) (xy 240.540783 -319.649539)
			(xy 240.511317 -319.695389) (xy 240.475626 -319.73658) (xy 240.434435 -319.772271) (xy 240.388585 -319.801737)
			(xy 240.339008 -319.824379) (xy 240.286713 -319.839734) (xy 240.232765 -319.84749) (xy 240.178263 -319.84749)
			(xy 240.124315 -319.839734) (xy 240.07202 -319.824379) (xy 240.022443 -319.801737) (xy 239.976593 -319.772271)
			(xy 239.935402 -319.73658) (xy 239.899711 -319.695389) (xy 239.870245 -319.649539) (xy 239.847603 -319.599962)
			(xy 239.832248 -319.547667) (xy 239.824492 -319.493719) (xy 239.824006 -319.466468) (xy 239.824571 -319.437553)
			(xy 239.83329 -319.380384) (xy 239.850538 -319.325186) (xy 239.875921 -319.273224) (xy 239.908857 -319.225689)
			(xy 239.94859 -319.18367) (xy 239.971072 -319.165478) (xy 239.979891 -319.157883) (xy 239.990065 -319.136973)
			(xy 239.99063 -319.125346) (xy 239.99063 -319.04559) (xy 239.990107 -319.033955) (xy 239.979909 -319.013044)
			(xy 239.971072 -319.005458) (xy 239.950257 -318.988743) (xy 239.913125 -318.950386) (xy 239.881702 -318.907227)
			(xy 239.856603 -318.860109) (xy 239.838318 -318.809952) (xy 239.827203 -318.757736) (xy 239.823475 -318.70448)
			(xy 235.354876 -318.70448) (xy 235.354876 -320.356992) (xy 235.354454 -320.367062) (xy 235.346739 -320.385667)
			(xy 235.33989 -320.39306) (xy 234.866477 -320.866473) (xy 247.984766 -320.866473) (xy 247.984766 -320.802551)
			(xy 247.992777 -320.739133) (xy 248.008674 -320.677219) (xy 248.032206 -320.617786) (xy 248.063 -320.561771)
			(xy 248.100573 -320.510056) (xy 248.14433 -320.463459) (xy 248.193583 -320.422714) (xy 248.247554 -320.388463)
			(xy 248.305393 -320.361246) (xy 248.366186 -320.341493) (xy 248.428976 -320.329515) (xy 248.492772 -320.325502)
			(xy 248.556568 -320.329515) (xy 248.619358 -320.341493) (xy 248.680151 -320.361246) (xy 248.73799 -320.388463)
			(xy 248.791961 -320.422714) (xy 248.841214 -320.463459) (xy 248.884971 -320.510056) (xy 248.922544 -320.561771)
			(xy 248.953338 -320.617786) (xy 248.97687 -320.677219) (xy 248.992767 -320.739133) (xy 249.000778 -320.802551)
			(xy 249.00128 -320.834512) (xy 249.000778 -320.866473) (xy 248.992767 -320.929891) (xy 248.97687 -320.991805)
			(xy 248.953338 -321.051238) (xy 248.922544 -321.107253) (xy 248.884971 -321.158968) (xy 248.841214 -321.205565)
			(xy 248.791961 -321.24631) (xy 248.73799 -321.280561) (xy 248.680151 -321.307778) (xy 248.619358 -321.327531)
			(xy 248.556568 -321.339509) (xy 248.492772 -321.343523) (xy 248.428976 -321.339509) (xy 248.366186 -321.327531)
			(xy 248.305393 -321.307778) (xy 248.247554 -321.280561) (xy 248.193583 -321.24631) (xy 248.14433 -321.205565)
			(xy 248.100573 -321.158968) (xy 248.063 -321.107253) (xy 248.032206 -321.051238) (xy 248.008674 -320.991805)
			(xy 247.992777 -320.929891) (xy 247.984766 -320.866473) (xy 234.866477 -320.866473) (xy 234.10037 -321.63258)
			(xy 234.092971 -321.639424) (xy 234.074373 -321.647151) (xy 234.064302 -321.647566) (xy 233.502708 -321.647566)
			(xy 233.49337 -321.647982) (xy 233.48253 -321.652138) (xy 235.520736 -321.652138) (xy 235.524807 -321.596516)
			(xy 235.536933 -321.542079) (xy 235.556856 -321.489988) (xy 235.584152 -321.441353) (xy 235.618238 -321.39721)
			(xy 235.658387 -321.358501) (xy 235.703745 -321.32605) (xy 235.753345 -321.300549) (xy 235.806129 -321.282542)
			(xy 235.860972 -321.272412) (xy 235.916706 -321.270375) (xy 235.972143 -321.276475) (xy 236.0261 -321.290581)
			(xy 236.077429 -321.312393) (xy 236.125035 -321.341447) (xy 236.167903 -321.377122) (xy 236.20512 -321.418659)
			(xy 236.235893 -321.465172) (xy 236.23888 -321.471544) (xy 238.503968 -321.471544) (xy 238.50447 -321.439583)
			(xy 238.512481 -321.376165) (xy 238.528378 -321.314251) (xy 238.55191 -321.254818) (xy 238.582704 -321.198803)
			(xy 238.620277 -321.147088) (xy 238.664034 -321.100491) (xy 238.713287 -321.059746) (xy 238.767258 -321.025495)
			(xy 238.825097 -320.998278) (xy 238.88589 -320.978525) (xy 238.94868 -320.966547) (xy 239.012476 -320.962534)
			(xy 239.076272 -320.966547) (xy 239.139062 -320.978525) (xy 239.199855 -320.998278) (xy 239.257694 -321.025495)
			(xy 239.311665 -321.059746) (xy 239.360918 -321.100491) (xy 239.404675 -321.147088) (xy 239.442248 -321.198803)
			(xy 239.473042 -321.254818) (xy 239.496574 -321.314251) (xy 239.512471 -321.376165) (xy 239.520482 -321.439583)
			(xy 239.520984 -321.471544) (xy 239.520399 -321.505335) (xy 239.511436 -321.572319) (xy 239.493687 -321.637529)
			(xy 239.467464 -321.699815) (xy 239.433228 -321.758084) (xy 239.391583 -321.811309) (xy 239.384739 -321.818)
			(xy 242.187982 -321.818) (xy 242.192053 -321.762378) (xy 242.204179 -321.707941) (xy 242.224102 -321.65585)
			(xy 242.251398 -321.607215) (xy 242.285484 -321.563072) (xy 242.325633 -321.524363) (xy 242.370991 -321.491912)
			(xy 242.420591 -321.466411) (xy 242.473375 -321.448404) (xy 242.528218 -321.438274) (xy 242.583952 -321.436237)
			(xy 242.639389 -321.442337) (xy 242.693346 -321.456443) (xy 242.744675 -321.478255) (xy 242.792281 -321.507309)
			(xy 242.835149 -321.542984) (xy 242.872366 -321.584521) (xy 242.903139 -321.631034) (xy 242.926811 -321.681531)
			(xy 242.942879 -321.734938) (xy 242.950999 -321.790114) (xy 242.951508 -321.818) (xy 242.950999 -321.845886)
			(xy 242.942879 -321.901062) (xy 242.926811 -321.954469) (xy 242.903139 -322.004966) (xy 242.872366 -322.051479)
			(xy 242.835149 -322.093016) (xy 242.792281 -322.128691) (xy 242.744675 -322.157745) (xy 242.693346 -322.179557)
			(xy 242.639389 -322.193663) (xy 242.583952 -322.199763) (xy 242.528218 -322.197726) (xy 242.473375 -322.187596)
			(xy 242.420591 -322.169589) (xy 242.370991 -322.144088) (xy 242.325633 -322.111637) (xy 242.285484 -322.072928)
			(xy 242.251398 -322.028785) (xy 242.224102 -321.98015) (xy 242.204179 -321.928059) (xy 242.192053 -321.873622)
			(xy 242.187982 -321.818) (xy 239.384739 -321.818) (xy 239.343259 -321.858554) (xy 239.316514 -321.879214)
			(xy 239.306862 -321.886326) (xy 239.29594 -321.907916) (xy 239.296448 -322.001896) (xy 239.297119 -322.013773)
			(xy 239.307843 -322.034971) (xy 239.317022 -322.042536) (xy 239.317276 -322.042536) (xy 239.344475 -322.063121)
			(xy 239.393624 -322.11042) (xy 239.436008 -322.163865) (xy 239.470865 -322.222498) (xy 239.497569 -322.285266)
			(xy 239.515641 -322.35104) (xy 239.524755 -322.41864) (xy 239.525302 -322.452746) (xy 239.5248 -322.484707)
			(xy 239.516789 -322.548125) (xy 239.500892 -322.610039) (xy 239.47736 -322.669472) (xy 239.446566 -322.725487)
			(xy 239.408993 -322.777202) (xy 239.365236 -322.823799) (xy 239.352905 -322.834) (xy 242.187982 -322.834)
			(xy 242.192053 -322.778378) (xy 242.204179 -322.723941) (xy 242.224102 -322.67185) (xy 242.251398 -322.623215)
			(xy 242.285484 -322.579072) (xy 242.325633 -322.540363) (xy 242.370991 -322.507912) (xy 242.420591 -322.482411)
			(xy 242.473375 -322.464404) (xy 242.528218 -322.454274) (xy 242.583952 -322.452237) (xy 242.639389 -322.458337)
			(xy 242.693346 -322.472443) (xy 242.744675 -322.494255) (xy 242.792281 -322.523309) (xy 242.835149 -322.558984)
			(xy 242.872366 -322.600521) (xy 242.903139 -322.647034) (xy 242.926811 -322.697531) (xy 242.942879 -322.750938)
			(xy 242.950999 -322.806114) (xy 242.951508 -322.834) (xy 242.950999 -322.861886) (xy 242.942879 -322.917062)
			(xy 242.926811 -322.970469) (xy 242.903139 -323.020966) (xy 242.872366 -323.067479) (xy 242.835149 -323.109016)
			(xy 242.792281 -323.144691) (xy 242.744675 -323.173745) (xy 242.693346 -323.195557) (xy 242.639389 -323.209663)
			(xy 242.583952 -323.215763) (xy 242.528218 -323.213726) (xy 242.473375 -323.203596) (xy 242.420591 -323.185589)
			(xy 242.370991 -323.160088) (xy 242.325633 -323.127637) (xy 242.285484 -323.088928) (xy 242.251398 -323.044785)
			(xy 242.224102 -322.99615) (xy 242.204179 -322.944059) (xy 242.192053 -322.889622) (xy 242.187982 -322.834)
			(xy 239.352905 -322.834) (xy 239.315983 -322.864544) (xy 239.262012 -322.898795) (xy 239.204173 -322.926012)
			(xy 239.14338 -322.945765) (xy 239.08059 -322.957743) (xy 239.016794 -322.961757) (xy 238.952998 -322.957743)
			(xy 238.890208 -322.945765) (xy 238.829415 -322.926012) (xy 238.771576 -322.898795) (xy 238.717605 -322.864544)
			(xy 238.668352 -322.823799) (xy 238.624595 -322.777202) (xy 238.587022 -322.725487) (xy 238.556228 -322.669472)
			(xy 238.532696 -322.610039) (xy 238.516799 -322.548125) (xy 238.508788 -322.484707) (xy 238.508286 -322.452746)
			(xy 238.508836 -322.418954) (xy 238.517801 -322.351967) (xy 238.535554 -322.286755) (xy 238.561782 -322.224467)
			(xy 238.596024 -322.166199) (xy 238.637677 -322.112976) (xy 238.686007 -322.065733) (xy 238.712756 -322.045076)
			(xy 238.722408 -322.037964) (xy 238.73333 -322.016374) (xy 238.732822 -321.922394) (xy 238.732167 -321.910515)
			(xy 238.721433 -321.889316) (xy 238.712248 -321.881754) (xy 238.711994 -321.881754) (xy 238.684784 -321.861184)
			(xy 238.635636 -321.813881) (xy 238.593254 -321.760433) (xy 238.558399 -321.701797) (xy 238.531697 -321.639028)
			(xy 238.513627 -321.573252) (xy 238.504514 -321.505651) (xy 238.503968 -321.471544) (xy 236.23888 -321.471544)
			(xy 236.259565 -321.515669) (xy 236.275633 -321.569076) (xy 236.283753 -321.624252) (xy 236.284262 -321.652138)
			(xy 236.283753 -321.680024) (xy 236.275633 -321.7352) (xy 236.259565 -321.788607) (xy 236.235893 -321.839104)
			(xy 236.20512 -321.885617) (xy 236.167903 -321.927154) (xy 236.125035 -321.962829) (xy 236.077429 -321.991883)
			(xy 236.0261 -322.013695) (xy 235.972143 -322.027801) (xy 235.916706 -322.033901) (xy 235.860972 -322.031864)
			(xy 235.806129 -322.021734) (xy 235.753345 -322.003727) (xy 235.703745 -321.978226) (xy 235.658387 -321.945775)
			(xy 235.618238 -321.907066) (xy 235.584152 -321.862923) (xy 235.556856 -321.814288) (xy 235.536933 -321.762197)
			(xy 235.524807 -321.70776) (xy 235.520736 -321.652138) (xy 233.48253 -321.652138) (xy 233.475931 -321.654668)
			(xy 233.462045 -321.667156) (xy 233.453551 -321.683789) (xy 233.452162 -321.693032) (xy 233.448283 -321.725239)
			(xy 233.433391 -321.788379) (xy 233.410588 -321.849112) (xy 233.380246 -321.906451) (xy 233.342857 -321.959465)
			(xy 233.299029 -322.007293) (xy 233.249473 -322.049157) (xy 233.194995 -322.084379) (xy 233.13648 -322.112385)
			(xy 233.074877 -322.132721) (xy 233.011188 -322.145056) (xy 232.946448 -322.14919) (xy 232.881708 -322.145056)
			(xy 232.818019 -322.132721) (xy 232.756416 -322.112385) (xy 232.697901 -322.084379) (xy 232.643423 -322.049157)
			(xy 232.593867 -322.007293) (xy 232.550039 -321.959465) (xy 232.51265 -321.906451) (xy 232.482308 -321.849112)
			(xy 232.459505 -321.788379) (xy 232.444613 -321.725239) (xy 232.440734 -321.693032) (xy 232.438702 -321.673474)
			(xy 232.409746 -321.647566) (xy 231.153208 -321.647566) (xy 231.143139 -321.647989) (xy 231.124538 -321.655709)
			(xy 231.11714 -321.662552) (xy 230.563166 -322.216526) (xy 230.556317 -322.223923) (xy 230.548581 -322.242522)
			(xy 230.54818 -322.252594) (xy 230.54818 -323.913754) (xy 232.44175 -323.913754) (xy 232.442263 -323.881462)
			(xy 232.450427 -323.817396) (xy 232.466644 -323.754882) (xy 232.490651 -323.694926) (xy 232.522062 -323.638495)
			(xy 232.56037 -323.5865) (xy 232.604958 -323.539778) (xy 232.655107 -323.499082) (xy 232.710008 -323.465069)
			(xy 232.739184 -323.45122) (xy 232.747297 -323.44701) (xy 232.760139 -323.434024) (xy 232.767654 -323.417379)
			(xy 232.768648 -323.408294) (xy 232.775252 -323.304662) (xy 232.762552 -323.27977) (xy 232.75036 -323.272404)
			(xy 232.723216 -323.254933) (xy 232.673127 -323.214212) (xy 232.628592 -323.167481) (xy 232.590329 -323.11549)
			(xy 232.558952 -323.059076) (xy 232.534965 -322.999145) (xy 232.518754 -322.93666) (xy 232.51058 -322.872627)
			(xy 232.510076 -322.84035) (xy 232.510578 -322.808389) (xy 232.518589 -322.744971) (xy 232.534486 -322.683057)
			(xy 232.558018 -322.623624) (xy 232.588812 -322.567609) (xy 232.626385 -322.515894) (xy 232.670142 -322.469297)
			(xy 232.719395 -322.428552) (xy 232.773366 -322.394301) (xy 232.831205 -322.367084) (xy 232.891998 -322.347331)
			(xy 232.954788 -322.335353) (xy 233.018584 -322.33134) (xy 233.08238 -322.335353) (xy 233.14517 -322.347331)
			(xy 233.205963 -322.367084) (xy 233.263802 -322.394301) (xy 233.317773 -322.428552) (xy 233.367026 -322.469297)
			(xy 233.410783 -322.515894) (xy 233.448356 -322.567609) (xy 233.47915 -322.623624) (xy 233.502682 -322.683057)
			(xy 233.50283 -322.683632) (xy 235.558836 -322.683632) (xy 235.562907 -322.62801) (xy 235.575033 -322.573573)
			(xy 235.594956 -322.521482) (xy 235.622252 -322.472847) (xy 235.656338 -322.428704) (xy 235.696487 -322.389995)
			(xy 235.741845 -322.357544) (xy 235.791445 -322.332043) (xy 235.844229 -322.314036) (xy 235.899072 -322.303906)
			(xy 235.954806 -322.301869) (xy 236.010243 -322.307969) (xy 236.0642 -322.322075) (xy 236.115529 -322.343887)
			(xy 236.163135 -322.372941) (xy 236.206003 -322.408616) (xy 236.24322 -322.450153) (xy 236.273993 -322.496666)
			(xy 236.297665 -322.547163) (xy 236.313733 -322.60057) (xy 236.321853 -322.655746) (xy 236.322362 -322.683632)
			(xy 236.321853 -322.711518) (xy 236.313733 -322.766694) (xy 236.297665 -322.820101) (xy 236.273993 -322.870598)
			(xy 236.24322 -322.917111) (xy 236.206003 -322.958648) (xy 236.163135 -322.994323) (xy 236.115529 -323.023377)
			(xy 236.0642 -323.045189) (xy 236.010243 -323.059295) (xy 235.954806 -323.065395) (xy 235.899072 -323.063358)
			(xy 235.844229 -323.053228) (xy 235.791445 -323.035221) (xy 235.741845 -323.00972) (xy 235.696487 -322.977269)
			(xy 235.656338 -322.93856) (xy 235.622252 -322.894417) (xy 235.594956 -322.845782) (xy 235.575033 -322.793691)
			(xy 235.562907 -322.739254) (xy 235.558836 -322.683632) (xy 233.50283 -322.683632) (xy 233.518579 -322.744971)
			(xy 233.52659 -322.808389) (xy 233.527092 -322.84035) (xy 233.526616 -322.872643) (xy 233.51845 -322.936712)
			(xy 233.502231 -322.999229) (xy 233.478221 -323.059187) (xy 233.446805 -323.115618) (xy 233.408492 -323.167614)
			(xy 233.363899 -323.214335) (xy 233.313744 -323.255028) (xy 233.258837 -323.289038) (xy 233.229658 -323.302884)
			(xy 233.221531 -323.307069) (xy 233.208695 -323.320069) (xy 233.201186 -323.336722) (xy 233.200194 -323.34581)
			(xy 233.19359 -323.449442) (xy 233.20629 -323.474334) (xy 233.218482 -323.4817) (xy 233.245638 -323.499154)
			(xy 233.295725 -323.539879) (xy 233.340257 -323.586613) (xy 233.378519 -323.638607) (xy 233.409894 -323.695023)
			(xy 233.43034 -323.746114) (xy 235.54639 -323.746114) (xy 235.550461 -323.690492) (xy 235.562587 -323.636055)
			(xy 235.58251 -323.583964) (xy 235.609806 -323.535329) (xy 235.643892 -323.491186) (xy 235.684041 -323.452477)
			(xy 235.729399 -323.420026) (xy 235.778999 -323.394525) (xy 235.831783 -323.376518) (xy 235.886626 -323.366388)
			(xy 235.94236 -323.364351) (xy 235.997797 -323.370451) (xy 236.051754 -323.384557) (xy 236.103083 -323.406369)
			(xy 236.150689 -323.435423) (xy 236.193557 -323.471098) (xy 236.230774 -323.512635) (xy 236.261547 -323.559148)
			(xy 236.285219 -323.609645) (xy 236.301287 -323.663052) (xy 236.309407 -323.718228) (xy 236.309916 -323.746114)
			(xy 236.309407 -323.774) (xy 236.301287 -323.829176) (xy 236.295022 -323.85) (xy 242.187982 -323.85)
			(xy 242.192053 -323.794378) (xy 242.204179 -323.739941) (xy 242.224102 -323.68785) (xy 242.251398 -323.639215)
			(xy 242.285484 -323.595072) (xy 242.325633 -323.556363) (xy 242.370991 -323.523912) (xy 242.420591 -323.498411)
			(xy 242.473375 -323.480404) (xy 242.528218 -323.470274) (xy 242.583952 -323.468237) (xy 242.639389 -323.474337)
			(xy 242.693346 -323.488443) (xy 242.744675 -323.510255) (xy 242.792281 -323.539309) (xy 242.835149 -323.574984)
			(xy 242.872366 -323.616521) (xy 242.903139 -323.663034) (xy 242.926811 -323.713531) (xy 242.942879 -323.766938)
			(xy 242.950999 -323.822114) (xy 242.951508 -323.85) (xy 244.220492 -323.85) (xy 244.221001 -323.819154)
			(xy 244.228477 -323.757915) (xy 244.243305 -323.698031) (xy 244.265269 -323.64038) (xy 244.294045 -323.58581)
			(xy 244.329212 -323.535121) (xy 244.370252 -323.48906) (xy 244.416563 -323.448301) (xy 244.467465 -323.413443)
			(xy 244.52221 -323.385) (xy 244.579993 -323.363387) (xy 244.609874 -323.355716) (xy 244.623336 -323.352414)
			(xy 244.642894 -323.333618) (xy 244.675406 -323.222874) (xy 244.668802 -323.196204) (xy 244.659404 -323.186552)
			(xy 244.637288 -323.162772) (xy 244.598598 -323.110615) (xy 244.566862 -323.053956) (xy 244.542597 -322.993719)
			(xy 244.526198 -322.930883) (xy 244.517931 -322.86647) (xy 244.517418 -322.834) (xy 244.517845 -322.8035)
			(xy 244.525153 -322.742938) (xy 244.539653 -322.683685) (xy 244.561136 -322.626592) (xy 244.589294 -322.572479)
			(xy 244.623722 -322.522122) (xy 244.663927 -322.476244) (xy 244.686328 -322.45554) (xy 244.696234 -322.446904)
			(xy 244.704616 -322.42252) (xy 244.68836 -322.324984) (xy 244.686699 -322.316581) (xy 244.678561 -322.301522)
			(xy 244.665889 -322.290013) (xy 244.658134 -322.286376) (xy 244.65788 -322.286376) (xy 244.627613 -322.273007)
			(xy 244.570536 -322.239533) (xy 244.518281 -322.198941) (xy 244.471732 -322.151915) (xy 244.431675 -322.099249)
			(xy 244.398786 -322.041833) (xy 244.37362 -321.980637) (xy 244.356603 -321.916694) (xy 244.348023 -321.851084)
			(xy 244.347492 -321.818) (xy 244.347994 -321.786039) (xy 244.356005 -321.722621) (xy 244.371902 -321.660707)
			(xy 244.395434 -321.601274) (xy 244.426228 -321.545259) (xy 244.463801 -321.493544) (xy 244.507558 -321.446947)
			(xy 244.556811 -321.406202) (xy 244.610782 -321.371951) (xy 244.668621 -321.344734) (xy 244.729414 -321.324981)
			(xy 244.792204 -321.313003) (xy 244.856 -321.30899) (xy 244.919796 -321.313003) (xy 244.982586 -321.324981)
			(xy 245.043379 -321.344734) (xy 245.101218 -321.371951) (xy 245.155189 -321.406202) (xy 245.197166 -321.440928)
			(xy 249.087988 -321.440928) (xy 249.090594 -321.377898) (xy 249.100977 -321.315675) (xy 249.118976 -321.255214)
			(xy 249.144315 -321.197443) (xy 249.176606 -321.143251) (xy 249.215352 -321.093468) (xy 249.259958 -321.048861)
			(xy 249.309739 -321.010114) (xy 249.363931 -320.977822) (xy 249.421701 -320.95248) (xy 249.482161 -320.93448)
			(xy 249.544384 -320.924096) (xy 249.607414 -320.921488) (xy 249.670282 -320.926697) (xy 249.732023 -320.939642)
			(xy 249.791689 -320.960124) (xy 249.848363 -320.98783) (xy 249.901174 -321.022333) (xy 249.949313 -321.063103)
			(xy 249.992038 -321.109514) (xy 250.028695 -321.160855) (xy 250.05872 -321.216335) (xy 250.081652 -321.275102)
			(xy 250.097139 -321.336255) (xy 250.104942 -321.398854) (xy 250.105418 -321.430396) (xy 250.105418 -321.43065)
			(xy 250.105292 -321.446696) (xy 250.10326 -321.478725) (xy 250.101354 -321.494658) (xy 250.09983 -321.506342)
			(xy 250.10745 -321.528694) (xy 250.182634 -321.602608) (xy 250.204986 -321.60972) (xy 250.216924 -321.607942)
			(xy 250.23511 -321.605452) (xy 250.271721 -321.602779) (xy 250.290076 -321.602608) (xy 250.290584 -321.602608)
			(xy 250.322126 -321.603051) (xy 250.384726 -321.610852) (xy 250.44588 -321.626336) (xy 250.504649 -321.649266)
			(xy 250.560131 -321.679289) (xy 250.611473 -321.715944) (xy 250.657887 -321.758668) (xy 250.69866 -321.806805)
			(xy 250.726885 -321.850004) (xy 253.591058 -321.850004) (xy 253.595129 -321.794382) (xy 253.607255 -321.739945)
			(xy 253.627178 -321.687854) (xy 253.654474 -321.639219) (xy 253.68856 -321.595076) (xy 253.728709 -321.556367)
			(xy 253.774067 -321.523916) (xy 253.823667 -321.498415) (xy 253.876451 -321.480408) (xy 253.931294 -321.470278)
			(xy 253.987028 -321.468241) (xy 254.042465 -321.474341) (xy 254.096422 -321.488447) (xy 254.147751 -321.510259)
			(xy 254.195357 -321.539313) (xy 254.238225 -321.574988) (xy 254.275442 -321.616525) (xy 254.306215 -321.663038)
			(xy 254.329887 -321.713535) (xy 254.345955 -321.766942) (xy 254.354075 -321.822118) (xy 254.354584 -321.850004)
			(xy 254.354075 -321.87789) (xy 254.345955 -321.933066) (xy 254.329887 -321.986473) (xy 254.306215 -322.03697)
			(xy 254.275442 -322.083483) (xy 254.238225 -322.12502) (xy 254.195357 -322.160695) (xy 254.147751 -322.189749)
			(xy 254.096422 -322.211561) (xy 254.042465 -322.225667) (xy 253.987028 -322.231767) (xy 253.931294 -322.22973)
			(xy 253.876451 -322.2196) (xy 253.823667 -322.201593) (xy 253.774067 -322.176092) (xy 253.728709 -322.143641)
			(xy 253.68856 -322.104932) (xy 253.654474 -322.060789) (xy 253.627178 -322.012154) (xy 253.607255 -321.960063)
			(xy 253.595129 -321.905626) (xy 253.591058 -321.850004) (xy 250.726885 -321.850004) (xy 250.733165 -321.859616)
			(xy 250.760873 -321.916289) (xy 250.781358 -321.975955) (xy 250.794306 -322.037696) (xy 250.799517 -322.100564)
			(xy 250.796912 -322.163594) (xy 250.786531 -322.225818) (xy 250.768533 -322.28628) (xy 250.743194 -322.344052)
			(xy 250.710904 -322.398245) (xy 250.672159 -322.448029) (xy 250.627553 -322.492637) (xy 250.577772 -322.531386)
			(xy 250.52358 -322.563679) (xy 250.46581 -322.589022) (xy 250.405349 -322.607024) (xy 250.343126 -322.617409)
			(xy 250.280096 -322.620018) (xy 250.217227 -322.614811) (xy 250.155485 -322.601867) (xy 250.095819 -322.581385)
			(xy 250.039144 -322.553681) (xy 249.986331 -322.519179) (xy 249.938191 -322.478409) (xy 249.895464 -322.431998)
			(xy 249.858806 -322.380658) (xy 249.828779 -322.325178) (xy 249.805846 -322.266411) (xy 249.790358 -322.205257)
			(xy 249.782553 -322.142658) (xy 249.782076 -322.111116) (xy 249.782076 -322.110862) (xy 249.782205 -322.094816)
			(xy 249.784237 -322.062788) (xy 249.78614 -322.046854) (xy 249.787664 -322.03517) (xy 249.780044 -322.012818)
			(xy 249.70486 -321.938904) (xy 249.682508 -321.931792) (xy 249.67057 -321.93357) (xy 249.652384 -321.936061)
			(xy 249.615773 -321.938733) (xy 249.597418 -321.938904) (xy 249.59691 -321.938904) (xy 249.565368 -321.938443)
			(xy 249.502769 -321.930641) (xy 249.441616 -321.915156) (xy 249.382847 -321.892226) (xy 249.327366 -321.862203)
			(xy 249.276025 -321.825547) (xy 249.229613 -321.782823) (xy 249.188841 -321.734685) (xy 249.154337 -321.681875)
			(xy 249.12663 -321.625202) (xy 249.106145 -321.565536) (xy 249.093199 -321.503796) (xy 249.087988 -321.440928)
			(xy 245.197166 -321.440928) (xy 245.204442 -321.446947) (xy 245.248199 -321.493544) (xy 245.285772 -321.545259)
			(xy 245.316566 -321.601274) (xy 245.340098 -321.660707) (xy 245.355995 -321.722621) (xy 245.364006 -321.786039)
			(xy 245.364508 -321.818) (xy 245.364072 -321.8485) (xy 245.356765 -321.909061) (xy 245.342266 -321.968313)
			(xy 245.320784 -322.025406) (xy 245.292627 -322.07952) (xy 245.258201 -322.129877) (xy 245.217998 -322.175755)
			(xy 245.195598 -322.19646) (xy 245.185692 -322.205096) (xy 245.17731 -322.22948) (xy 245.193566 -322.327016)
			(xy 245.195213 -322.335422) (xy 245.203356 -322.350483) (xy 245.216034 -322.36199) (xy 245.223792 -322.365624)
			(xy 245.224046 -322.365624) (xy 245.254319 -322.37898) (xy 245.311395 -322.412456) (xy 245.363649 -322.453051)
			(xy 245.410197 -322.500079) (xy 245.450253 -322.552747) (xy 245.483141 -322.610164) (xy 245.508306 -322.671361)
			(xy 245.525323 -322.735305) (xy 245.533904 -322.800915) (xy 245.534434 -322.834) (xy 245.533905 -322.864846)
			(xy 245.52643 -322.926082) (xy 245.511603 -322.985965) (xy 245.48964 -323.043615) (xy 245.460865 -323.098184)
			(xy 245.425701 -323.148872) (xy 245.384663 -323.194934) (xy 245.338354 -323.235694) (xy 245.287455 -323.270552)
			(xy 245.232713 -323.298997) (xy 245.174932 -323.320611) (xy 245.145052 -323.328284) (xy 245.13159 -323.331586)
			(xy 245.112032 -323.350382) (xy 245.090718 -323.422983) (xy 250.505462 -323.422983) (xy 250.505462 -323.359061)
			(xy 250.513473 -323.295643) (xy 250.52937 -323.233729) (xy 250.552902 -323.174296) (xy 250.583696 -323.118281)
			(xy 250.621269 -323.066566) (xy 250.665026 -323.019969) (xy 250.714279 -322.979224) (xy 250.76825 -322.944973)
			(xy 250.826089 -322.917756) (xy 250.886882 -322.898003) (xy 250.949672 -322.886025) (xy 251.013468 -322.882012)
			(xy 251.077264 -322.886025) (xy 251.140054 -322.898003) (xy 251.200847 -322.917756) (xy 251.258686 -322.944973)
			(xy 251.312657 -322.979224) (xy 251.36191 -323.019969) (xy 251.364495 -323.022722) (xy 256.385058 -323.022722)
			(xy 256.389129 -322.9671) (xy 256.401255 -322.912663) (xy 256.421178 -322.860572) (xy 256.448474 -322.811937)
			(xy 256.48256 -322.767794) (xy 256.522709 -322.729085) (xy 256.568067 -322.696634) (xy 256.617667 -322.671133)
			(xy 256.670451 -322.653126) (xy 256.725294 -322.642996) (xy 256.781028 -322.640959) (xy 256.836465 -322.647059)
			(xy 256.890422 -322.661165) (xy 256.941751 -322.682977) (xy 256.989357 -322.712031) (xy 257.032225 -322.747706)
			(xy 257.069442 -322.789243) (xy 257.100215 -322.835756) (xy 257.123887 -322.886253) (xy 257.139955 -322.93966)
			(xy 257.148075 -322.994836) (xy 257.148584 -323.022722) (xy 257.148075 -323.050608) (xy 257.139955 -323.105784)
			(xy 257.123887 -323.159191) (xy 257.100215 -323.209688) (xy 257.069442 -323.256201) (xy 257.032225 -323.297738)
			(xy 256.989357 -323.333413) (xy 256.941751 -323.362467) (xy 256.890422 -323.384279) (xy 256.836465 -323.398385)
			(xy 256.781028 -323.404485) (xy 256.725294 -323.402448) (xy 256.670451 -323.392318) (xy 256.617667 -323.374311)
			(xy 256.568067 -323.34881) (xy 256.522709 -323.316359) (xy 256.48256 -323.27765) (xy 256.448474 -323.233507)
			(xy 256.421178 -323.184872) (xy 256.401255 -323.132781) (xy 256.389129 -323.078344) (xy 256.385058 -323.022722)
			(xy 251.364495 -323.022722) (xy 251.405667 -323.066566) (xy 251.44324 -323.118281) (xy 251.474034 -323.174296)
			(xy 251.497566 -323.233729) (xy 251.513463 -323.295643) (xy 251.521474 -323.359061) (xy 251.521976 -323.391022)
			(xy 251.521474 -323.422983) (xy 251.513463 -323.486401) (xy 251.497566 -323.548315) (xy 251.474034 -323.607748)
			(xy 251.44324 -323.663763) (xy 251.405667 -323.715478) (xy 251.36191 -323.762075) (xy 251.312657 -323.80282)
			(xy 251.258686 -323.837071) (xy 251.200847 -323.864288) (xy 251.140054 -323.884041) (xy 251.077264 -323.896019)
			(xy 251.013468 -323.900033) (xy 250.949672 -323.896019) (xy 250.886882 -323.884041) (xy 250.826089 -323.864288)
			(xy 250.76825 -323.837071) (xy 250.714279 -323.80282) (xy 250.665026 -323.762075) (xy 250.621269 -323.715478)
			(xy 250.583696 -323.663763) (xy 250.552902 -323.607748) (xy 250.52937 -323.548315) (xy 250.513473 -323.486401)
			(xy 250.505462 -323.422983) (xy 245.090718 -323.422983) (xy 245.07952 -323.461126) (xy 245.086124 -323.487796)
			(xy 245.095522 -323.497448) (xy 245.117643 -323.521224) (xy 245.156332 -323.573383) (xy 245.188066 -323.630042)
			(xy 245.21233 -323.69028) (xy 245.228728 -323.753117) (xy 245.236995 -323.817529) (xy 245.237508 -323.85)
			(xy 245.237054 -323.880464) (xy 245.229752 -323.940953) (xy 245.215289 -324.00014) (xy 245.204996 -324.028816)
			(xy 245.204996 -324.02907) (xy 245.202105 -324.038058) (xy 245.202186 -324.045072) (xy 256.377692 -324.045072)
			(xy 256.381763 -323.98945) (xy 256.393889 -323.935013) (xy 256.413812 -323.882922) (xy 256.441108 -323.834287)
			(xy 256.475194 -323.790144) (xy 256.515343 -323.751435) (xy 256.560701 -323.718984) (xy 256.610301 -323.693483)
			(xy 256.663085 -323.675476) (xy 256.717928 -323.665346) (xy 256.773662 -323.663309) (xy 256.829099 -323.669409)
			(xy 256.883056 -323.683515) (xy 256.934385 -323.705327) (xy 256.981991 -323.734381) (xy 257.024859 -323.770056)
			(xy 257.062076 -323.811593) (xy 257.092849 -323.858106) (xy 257.116521 -323.908603) (xy 257.132589 -323.96201)
			(xy 257.140709 -324.017186) (xy 257.141218 -324.045072) (xy 257.140709 -324.072958) (xy 257.132589 -324.128134)
			(xy 257.116521 -324.181541) (xy 257.092849 -324.232038) (xy 257.062076 -324.278551) (xy 257.024859 -324.320088)
			(xy 256.981991 -324.355763) (xy 256.934385 -324.384817) (xy 256.883056 -324.406629) (xy 256.829099 -324.420735)
			(xy 256.773662 -324.426835) (xy 256.717928 -324.424798) (xy 256.663085 -324.414668) (xy 256.610301 -324.396661)
			(xy 256.560701 -324.37116) (xy 256.515343 -324.338709) (xy 256.475194 -324.3) (xy 256.441108 -324.255857)
			(xy 256.413812 -324.207222) (xy 256.393889 -324.155131) (xy 256.381763 -324.100694) (xy 256.377692 -324.045072)
			(xy 245.202186 -324.045072) (xy 245.202324 -324.056919) (xy 245.209312 -324.07444) (xy 245.21541 -324.081648)
			(xy 245.27764 -324.147942) (xy 245.284356 -324.154624) (xy 245.30141 -324.162849) (xy 245.320287 -324.164301)
			(xy 245.329456 -324.161912) (xy 245.365249 -324.151807) (xy 245.438828 -324.140969) (xy 245.476014 -324.140322)
			(xy 245.507554 -324.140782) (xy 245.570148 -324.148586) (xy 245.631297 -324.164073) (xy 245.69006 -324.187004)
			(xy 245.745536 -324.217027) (xy 245.796873 -324.253682) (xy 245.843281 -324.296405) (xy 245.884048 -324.34454)
			(xy 245.918549 -324.397348) (xy 245.946253 -324.454018) (xy 245.966734 -324.51368) (xy 245.979679 -324.575416)
			(xy 245.984888 -324.63828) (xy 245.982281 -324.701305) (xy 245.971899 -324.763524) (xy 245.953901 -324.823981)
			(xy 245.928562 -324.881748) (xy 245.896274 -324.935937) (xy 245.85753 -324.985715) (xy 245.812927 -325.03032)
			(xy 245.778966 -325.056754) (xy 256.397758 -325.056754) (xy 256.401829 -325.001132) (xy 256.413955 -324.946695)
			(xy 256.433878 -324.894604) (xy 256.461174 -324.845969) (xy 256.49526 -324.801826) (xy 256.535409 -324.763117)
			(xy 256.580767 -324.730666) (xy 256.630367 -324.705165) (xy 256.683151 -324.687158) (xy 256.737994 -324.677028)
			(xy 256.793728 -324.674991) (xy 256.849165 -324.681091) (xy 256.903122 -324.695197) (xy 256.954451 -324.717009)
			(xy 257.002057 -324.746063) (xy 257.044925 -324.781738) (xy 257.082142 -324.823275) (xy 257.112915 -324.869788)
			(xy 257.136587 -324.920285) (xy 257.152655 -324.973692) (xy 257.160775 -325.028868) (xy 257.161284 -325.056754)
			(xy 257.160775 -325.08464) (xy 257.152655 -325.139816) (xy 257.136587 -325.193223) (xy 257.112915 -325.24372)
			(xy 257.082142 -325.290233) (xy 257.044925 -325.33177) (xy 257.002057 -325.367445) (xy 256.954451 -325.396499)
			(xy 256.903122 -325.418311) (xy 256.849165 -325.432417) (xy 256.793728 -325.438517) (xy 256.737994 -325.43648)
			(xy 256.683151 -325.42635) (xy 256.630367 -325.408343) (xy 256.580767 -325.382842) (xy 256.535409 -325.350391)
			(xy 256.49526 -325.311682) (xy 256.461174 -325.267539) (xy 256.433878 -325.218904) (xy 256.413955 -325.166813)
			(xy 256.401829 -325.112376) (xy 256.397758 -325.056754) (xy 245.778966 -325.056754) (xy 245.76315 -325.069065)
			(xy 245.708962 -325.101355) (xy 245.651196 -325.126695) (xy 245.59074 -325.144695) (xy 245.528521 -325.15508)
			(xy 245.465496 -325.157688) (xy 245.402632 -325.152481) (xy 245.340895 -325.139538) (xy 245.281233 -325.119059)
			(xy 245.224562 -325.091357) (xy 245.171753 -325.056858) (xy 245.123617 -325.016092) (xy 245.080892 -324.969685)
			(xy 245.044236 -324.91835) (xy 245.014211 -324.862875) (xy 244.991278 -324.804112) (xy 244.975789 -324.742964)
			(xy 244.967983 -324.68037) (xy 244.967506 -324.64883) (xy 244.967968 -324.618366) (xy 244.975266 -324.557877)
			(xy 244.989727 -324.49869) (xy 245.000018 -324.470014) (xy 245.000018 -324.46976) (xy 245.002881 -324.460765)
			(xy 245.002672 -324.44191) (xy 244.995696 -324.424391) (xy 244.989604 -324.417182) (xy 244.927374 -324.350888)
			(xy 244.920658 -324.344208) (xy 244.903603 -324.335989) (xy 244.884727 -324.334534) (xy 244.875558 -324.336918)
			(xy 244.839765 -324.347021) (xy 244.766186 -324.35786) (xy 244.729 -324.358508) (xy 244.698269 -324.358044)
			(xy 244.637255 -324.350635) (xy 244.577579 -324.335927) (xy 244.520111 -324.314132) (xy 244.465689 -324.285569)
			(xy 244.415107 -324.250655) (xy 244.369102 -324.209898) (xy 244.328345 -324.163893) (xy 244.293431 -324.113311)
			(xy 244.264868 -324.058889) (xy 244.243073 -324.001421) (xy 244.228365 -323.941745) (xy 244.220956 -323.880731)
			(xy 244.220492 -323.85) (xy 242.951508 -323.85) (xy 242.950999 -323.877886) (xy 242.942879 -323.933062)
			(xy 242.926811 -323.986469) (xy 242.903139 -324.036966) (xy 242.872366 -324.083479) (xy 242.835149 -324.125016)
			(xy 242.792281 -324.160691) (xy 242.744675 -324.189745) (xy 242.693346 -324.211557) (xy 242.639389 -324.225663)
			(xy 242.583952 -324.231763) (xy 242.528218 -324.229726) (xy 242.473375 -324.219596) (xy 242.420591 -324.201589)
			(xy 242.370991 -324.176088) (xy 242.325633 -324.143637) (xy 242.285484 -324.104928) (xy 242.251398 -324.060785)
			(xy 242.224102 -324.01215) (xy 242.204179 -323.960059) (xy 242.192053 -323.905622) (xy 242.187982 -323.85)
			(xy 236.295022 -323.85) (xy 236.285219 -323.882583) (xy 236.261547 -323.93308) (xy 236.230774 -323.979593)
			(xy 236.193557 -324.02113) (xy 236.150689 -324.056805) (xy 236.103083 -324.085859) (xy 236.051754 -324.107671)
			(xy 235.997797 -324.121777) (xy 235.94236 -324.127877) (xy 235.886626 -324.12584) (xy 235.831783 -324.11571)
			(xy 235.778999 -324.097703) (xy 235.729399 -324.072202) (xy 235.684041 -324.039751) (xy 235.643892 -324.001042)
			(xy 235.609806 -323.956899) (xy 235.58251 -323.908264) (xy 235.562587 -323.856173) (xy 235.550461 -323.801736)
			(xy 235.54639 -323.746114) (xy 233.43034 -323.746114) (xy 233.433879 -323.754956) (xy 233.450089 -323.817442)
			(xy 233.458263 -323.881477) (xy 233.458766 -323.913754) (xy 233.458227 -323.947343) (xy 233.449387 -324.013937)
			(xy 233.431854 -324.078786) (xy 233.405935 -324.140762) (xy 233.37208 -324.198786) (xy 233.330879 -324.251845)
			(xy 233.28305 -324.299018) (xy 233.229425 -324.339481) (xy 233.200448 -324.356476) (xy 233.192703 -324.36121)
			(xy 233.180965 -324.375041) (xy 233.174811 -324.392106) (xy 233.17454 -324.40118) (xy 233.175048 -324.489826)
			(xy 233.175492 -324.498848) (xy 233.181896 -324.515725) (xy 233.19373 -324.529356) (xy 233.201464 -324.534022)
			(xy 233.201718 -324.534276) (xy 233.228082 -324.549152) (xy 233.277406 -324.584252) (xy 233.322212 -324.624961)
			(xy 233.361867 -324.670702) (xy 233.39581 -324.720828) (xy 233.423561 -324.774631) (xy 233.430454 -324.793102)
			(xy 235.578648 -324.793102) (xy 235.582719 -324.73748) (xy 235.594845 -324.683043) (xy 235.614768 -324.630952)
			(xy 235.642064 -324.582317) (xy 235.67615 -324.538174) (xy 235.716299 -324.499465) (xy 235.761657 -324.467014)
			(xy 235.811257 -324.441513) (xy 235.864041 -324.423506) (xy 235.918884 -324.413376) (xy 235.974618 -324.411339)
			(xy 236.030055 -324.417439) (xy 236.084012 -324.431545) (xy 236.135341 -324.453357) (xy 236.182947 -324.482411)
			(xy 236.225815 -324.518086) (xy 236.263032 -324.559623) (xy 236.293805 -324.606136) (xy 236.317477 -324.656633)
			(xy 236.333545 -324.71004) (xy 236.341665 -324.765216) (xy 236.342174 -324.793102) (xy 236.341665 -324.820988)
			(xy 236.335041 -324.866) (xy 242.187982 -324.866) (xy 242.192053 -324.810378) (xy 242.204179 -324.755941)
			(xy 242.224102 -324.70385) (xy 242.251398 -324.655215) (xy 242.285484 -324.611072) (xy 242.325633 -324.572363)
			(xy 242.370991 -324.539912) (xy 242.420591 -324.514411) (xy 242.473375 -324.496404) (xy 242.528218 -324.486274)
			(xy 242.583952 -324.484237) (xy 242.639389 -324.490337) (xy 242.693346 -324.504443) (xy 242.744675 -324.526255)
			(xy 242.792281 -324.555309) (xy 242.835149 -324.590984) (xy 242.872366 -324.632521) (xy 242.903139 -324.679034)
			(xy 242.926811 -324.729531) (xy 242.942879 -324.782938) (xy 242.950999 -324.838114) (xy 242.951508 -324.866)
			(xy 242.950999 -324.893886) (xy 242.942879 -324.949062) (xy 242.926811 -325.002469) (xy 242.903139 -325.052966)
			(xy 242.872366 -325.099479) (xy 242.835149 -325.141016) (xy 242.792281 -325.176691) (xy 242.744675 -325.205745)
			(xy 242.693346 -325.227557) (xy 242.639389 -325.241663) (xy 242.583952 -325.247763) (xy 242.528218 -325.245726)
			(xy 242.473375 -325.235596) (xy 242.420591 -325.217589) (xy 242.370991 -325.192088) (xy 242.325633 -325.159637)
			(xy 242.285484 -325.120928) (xy 242.251398 -325.076785) (xy 242.224102 -325.02815) (xy 242.204179 -324.976059)
			(xy 242.192053 -324.921622) (xy 242.187982 -324.866) (xy 236.335041 -324.866) (xy 236.333545 -324.876164)
			(xy 236.317477 -324.929571) (xy 236.293805 -324.980068) (xy 236.263032 -325.026581) (xy 236.225815 -325.068118)
			(xy 236.182947 -325.103793) (xy 236.135341 -325.132847) (xy 236.084012 -325.154659) (xy 236.030055 -325.168765)
			(xy 235.974618 -325.174865) (xy 235.918884 -325.172828) (xy 235.864041 -325.162698) (xy 235.811257 -325.144691)
			(xy 235.761657 -325.11919) (xy 235.716299 -325.086739) (xy 235.67615 -325.04803) (xy 235.642064 -325.003887)
			(xy 235.614768 -324.955252) (xy 235.594845 -324.903161) (xy 235.582719 -324.848724) (xy 235.578648 -324.793102)
			(xy 233.430454 -324.793102) (xy 233.444726 -324.831348) (xy 233.459007 -324.890177) (xy 233.466201 -324.950285)
			(xy 233.46664 -324.980554) (xy 233.466241 -325.011065) (xy 233.458939 -325.071648) (xy 233.444435 -325.130921)
			(xy 233.422937 -325.18803) (xy 233.394755 -325.242154) (xy 233.360294 -325.292514) (xy 233.320051 -325.338385)
			(xy 233.274604 -325.379106) (xy 233.224608 -325.414092) (xy 233.197908 -325.428864) (xy 233.197654 -325.428864)
			(xy 233.189572 -325.43378) (xy 233.177418 -325.448256) (xy 233.171299 -325.46614) (xy 233.171238 -325.4756)
			(xy 233.175556 -325.582026) (xy 233.19232 -325.605902) (xy 233.205782 -325.611744) (xy 233.235794 -325.625236)
			(xy 233.292357 -325.658859) (xy 233.344113 -325.699494) (xy 233.390197 -325.746463) (xy 233.429841 -325.798982)
			(xy 233.462382 -325.856174) (xy 233.47792 -325.894192) (xy 235.54004 -325.894192) (xy 235.544111 -325.83857)
			(xy 235.556237 -325.784133) (xy 235.57616 -325.732042) (xy 235.603456 -325.683407) (xy 235.637542 -325.639264)
			(xy 235.677691 -325.600555) (xy 235.723049 -325.568104) (xy 235.772649 -325.542603) (xy 235.825433 -325.524596)
			(xy 235.880276 -325.514466) (xy 235.93601 -325.512429) (xy 235.991447 -325.518529) (xy 236.045404 -325.532635)
			(xy 236.096733 -325.554447) (xy 236.144339 -325.583501) (xy 236.187207 -325.619176) (xy 236.224424 -325.660713)
			(xy 236.255197 -325.707226) (xy 236.278869 -325.757723) (xy 236.294937 -325.81113) (xy 236.303057 -325.866306)
			(xy 236.303566 -325.894192) (xy 236.303057 -325.922078) (xy 236.294937 -325.977254) (xy 236.278869 -326.030661)
			(xy 236.255197 -326.081158) (xy 236.224424 -326.127671) (xy 236.187207 -326.169208) (xy 236.144339 -326.204883)
			(xy 236.096733 -326.233937) (xy 236.045404 -326.255749) (xy 235.991447 -326.269855) (xy 235.93601 -326.275955)
			(xy 235.880276 -326.273918) (xy 235.825433 -326.263788) (xy 235.772649 -326.245781) (xy 235.723049 -326.22028)
			(xy 235.677691 -326.187829) (xy 235.637542 -326.14912) (xy 235.603456 -326.104977) (xy 235.57616 -326.056342)
			(xy 235.556237 -326.004251) (xy 235.544111 -325.949814) (xy 235.54004 -325.894192) (xy 233.47792 -325.894192)
			(xy 233.487277 -325.917085) (xy 233.50411 -325.980697) (xy 233.512601 -326.045949) (xy 233.513122 -326.07885)
			(xy 233.51262 -326.110811) (xy 233.504609 -326.174229) (xy 233.488712 -326.236143) (xy 233.46518 -326.295576)
			(xy 233.434386 -326.351591) (xy 233.396813 -326.403306) (xy 233.353056 -326.449903) (xy 233.303803 -326.490648)
			(xy 233.249832 -326.524899) (xy 233.191993 -326.552116) (xy 233.1312 -326.571869) (xy 233.06841 -326.583847)
			(xy 233.004614 -326.587861) (xy 232.940818 -326.583847) (xy 232.878028 -326.571869) (xy 232.817235 -326.552116)
			(xy 232.759396 -326.524899) (xy 232.705425 -326.490648) (xy 232.656172 -326.449903) (xy 232.612415 -326.403306)
			(xy 232.574842 -326.351591) (xy 232.544048 -326.295576) (xy 232.520516 -326.236143) (xy 232.504619 -326.174229)
			(xy 232.496608 -326.110811) (xy 232.496106 -326.07885) (xy 232.496537 -326.04834) (xy 232.503837 -325.987759)
			(xy 232.518339 -325.928489) (xy 232.539834 -325.871381) (xy 232.568012 -325.817257) (xy 232.602469 -325.766898)
			(xy 232.642707 -325.721026) (xy 232.688149 -325.680303) (xy 232.73814 -325.645314) (xy 232.764838 -325.63054)
			(xy 232.765092 -325.63054) (xy 232.773181 -325.625636) (xy 232.785331 -325.611153) (xy 232.791447 -325.593266)
			(xy 232.791508 -325.583804) (xy 232.78719 -325.477378) (xy 232.770426 -325.453502) (xy 232.756964 -325.44766)
			(xy 232.726942 -325.434191) (xy 232.67038 -325.400564) (xy 232.618626 -325.359924) (xy 232.572544 -325.312951)
			(xy 232.532902 -325.260429) (xy 232.500363 -325.203235) (xy 232.475469 -325.142322) (xy 232.458636 -325.078708)
			(xy 232.450145 -325.013455) (xy 232.449624 -324.980554) (xy 232.450174 -324.946965) (xy 232.459013 -324.880373)
			(xy 232.476545 -324.815523) (xy 232.502463 -324.753548) (xy 232.536316 -324.695524) (xy 232.577515 -324.642464)
			(xy 232.625343 -324.595292) (xy 232.678966 -324.554828) (xy 232.707942 -324.537832) (xy 232.715681 -324.53309)
			(xy 232.727421 -324.519263) (xy 232.733578 -324.502201) (xy 232.73385 -324.493128) (xy 232.733342 -324.404482)
			(xy 232.732897 -324.39546) (xy 232.726495 -324.378582) (xy 232.714661 -324.364951) (xy 232.706926 -324.360286)
			(xy 232.706672 -324.360032) (xy 232.680309 -324.345154) (xy 232.630986 -324.310054) (xy 232.58618 -324.269345)
			(xy 232.546525 -324.223604) (xy 232.512582 -324.173478) (xy 232.484831 -324.119676) (xy 232.463666 -324.062959)
			(xy 232.449384 -324.004131) (xy 232.44219 -323.944023) (xy 232.44175 -323.913754) (xy 230.54818 -323.913754)
			(xy 230.54818 -327.039732) (xy 230.547926 -327.039986) (xy 230.54522 -327.042837) (xy 230.540626 -327.049215)
			(xy 230.538782 -327.052686) (xy 230.536204 -327.058114) (xy 230.533391 -327.069794) (xy 230.533194 -327.0758)
			(xy 230.533194 -328.25182) (xy 232.382822 -328.25182) (xy 232.383345 -328.218264) (xy 232.392159 -328.151735)
			(xy 232.40965 -328.086943) (xy 232.435514 -328.025017) (xy 232.469301 -327.967031) (xy 232.510424 -327.913995)
			(xy 232.558167 -327.866831) (xy 232.611701 -327.826359) (xy 232.640632 -327.809352) (xy 232.652316 -327.802748)
			(xy 232.666032 -327.780142) (xy 232.669842 -327.666858) (xy 232.657904 -327.64349) (xy 232.646728 -327.636124)
			(xy 232.620747 -327.618478) (xy 232.572966 -327.577715) (xy 232.53057 -327.531376) (xy 232.494205 -327.480167)
			(xy 232.464426 -327.424869) (xy 232.441686 -327.366323) (xy 232.426331 -327.305422) (xy 232.418595 -327.243093)
			(xy 232.418128 -327.21169) (xy 232.41863 -327.179729) (xy 232.426641 -327.116311) (xy 232.442538 -327.054397)
			(xy 232.46607 -326.994964) (xy 232.496864 -326.938949) (xy 232.534437 -326.887234) (xy 232.578194 -326.840637)
			(xy 232.627447 -326.799892) (xy 232.681418 -326.765641) (xy 232.739257 -326.738424) (xy 232.80005 -326.718671)
			(xy 232.86284 -326.706693) (xy 232.926636 -326.70268) (xy 232.990432 -326.706693) (xy 233.053222 -326.718671)
			(xy 233.114015 -326.738424) (xy 233.171854 -326.765641) (xy 233.225825 -326.799892) (xy 233.275078 -326.840637)
			(xy 233.318835 -326.887234) (xy 233.356408 -326.938949) (xy 233.360846 -326.947022) (xy 235.565694 -326.947022)
			(xy 235.569765 -326.8914) (xy 235.581891 -326.836963) (xy 235.601814 -326.784872) (xy 235.62911 -326.736237)
			(xy 235.663196 -326.692094) (xy 235.703345 -326.653385) (xy 235.748703 -326.620934) (xy 235.798303 -326.595433)
			(xy 235.851087 -326.577426) (xy 235.90593 -326.567296) (xy 235.961664 -326.565259) (xy 236.017101 -326.571359)
			(xy 236.071058 -326.585465) (xy 236.122387 -326.607277) (xy 236.169993 -326.636331) (xy 236.212861 -326.672006)
			(xy 236.250078 -326.713543) (xy 236.280851 -326.760056) (xy 236.304523 -326.810553) (xy 236.320591 -326.86396)
			(xy 236.328711 -326.919136) (xy 236.32922 -326.947022) (xy 236.328711 -326.974908) (xy 236.320591 -327.030084)
			(xy 236.304523 -327.083491) (xy 236.280851 -327.133988) (xy 236.250078 -327.180501) (xy 236.212861 -327.222038)
			(xy 236.169993 -327.257713) (xy 236.122387 -327.286767) (xy 236.071058 -327.308579) (xy 236.017101 -327.322685)
			(xy 235.961664 -327.328785) (xy 235.90593 -327.326748) (xy 235.851087 -327.316618) (xy 235.798303 -327.298611)
			(xy 235.748703 -327.27311) (xy 235.703345 -327.240659) (xy 235.663196 -327.20195) (xy 235.62911 -327.157807)
			(xy 235.601814 -327.109172) (xy 235.581891 -327.057081) (xy 235.569765 -327.002644) (xy 235.565694 -326.947022)
			(xy 233.360846 -326.947022) (xy 233.387202 -326.994964) (xy 233.410734 -327.054397) (xy 233.426631 -327.116311)
			(xy 233.434642 -327.179729) (xy 233.435144 -327.21169) (xy 233.434647 -327.245247) (xy 233.42583 -327.311778)
			(xy 233.408336 -327.376571) (xy 233.382469 -327.438498) (xy 233.348679 -327.496484) (xy 233.307552 -327.549519)
			(xy 233.259805 -327.596682) (xy 233.206267 -327.637153) (xy 233.177334 -327.654158) (xy 233.16565 -327.660762)
			(xy 233.151934 -327.683368) (xy 233.151421 -327.698608) (xy 238.484918 -327.698608) (xy 238.485394 -327.66603)
			(xy 238.493734 -327.601411) (xy 238.510253 -327.538384) (xy 238.534682 -327.477981) (xy 238.566619 -327.42119)
			(xy 238.605544 -327.368939) (xy 238.650819 -327.322084) (xy 238.701704 -327.28139) (xy 238.729266 -327.264014)
			(xy 238.740188 -327.25741) (xy 238.753142 -327.235566) (xy 238.757206 -327.138284) (xy 238.757 -327.125669)
			(xy 238.745944 -327.103025) (xy 238.736124 -327.095104) (xy 238.712145 -327.07713) (xy 238.668154 -327.036432)
			(xy 238.629249 -326.990847) (xy 238.595968 -326.941009) (xy 238.568772 -326.887605) (xy 238.548038 -326.831377)
			(xy 238.534053 -326.773103) (xy 238.52701 -326.713589) (xy 238.526574 -326.683624) (xy 238.527001 -326.652229)
			(xy 238.534719 -326.589915) (xy 238.550053 -326.529026) (xy 238.572769 -326.470489) (xy 238.602521 -326.415196)
			(xy 238.638856 -326.363987) (xy 238.681222 -326.317644) (xy 238.728973 -326.276871) (xy 238.75492 -326.25919)
			(xy 238.765842 -326.252078) (xy 238.77778 -326.229218) (xy 238.77651 -326.117458) (xy 238.764064 -326.09536)
			(xy 238.752888 -326.088248) (xy 238.725877 -326.070764) (xy 238.676036 -326.030071) (xy 238.63173 -325.983411)
			(xy 238.59367 -325.931531) (xy 238.562464 -325.875261) (xy 238.538612 -325.815502) (xy 238.522494 -325.75321)
			(xy 238.51437 -325.689382) (xy 238.513874 -325.65721) (xy 238.514376 -325.625249) (xy 238.522387 -325.561831)
			(xy 238.538284 -325.499917) (xy 238.561816 -325.440484) (xy 238.59261 -325.384469) (xy 238.630183 -325.332754)
			(xy 238.67394 -325.286157) (xy 238.723193 -325.245412) (xy 238.777164 -325.211161) (xy 238.835003 -325.183944)
			(xy 238.895796 -325.164191) (xy 238.958586 -325.152213) (xy 239.022382 -325.1482) (xy 239.086178 -325.152213)
			(xy 239.148968 -325.164191) (xy 239.209761 -325.183944) (xy 239.2676 -325.211161) (xy 239.321571 -325.245412)
			(xy 239.370824 -325.286157) (xy 239.414581 -325.332754) (xy 239.452154 -325.384469) (xy 239.482948 -325.440484)
			(xy 239.50648 -325.499917) (xy 239.522377 -325.561831) (xy 239.530388 -325.625249) (xy 239.53089 -325.65721)
			(xy 239.530428 -325.688604) (xy 239.522717 -325.750917) (xy 239.50739 -325.811806) (xy 239.48468 -325.870343)
			(xy 239.454933 -325.925637) (xy 239.418601 -325.976846) (xy 239.376238 -326.02319) (xy 239.32849 -326.063963)
			(xy 239.302544 -326.081644) (xy 239.291622 -326.088756) (xy 239.279684 -326.111616) (xy 239.280954 -326.223376)
			(xy 239.2934 -326.245474) (xy 239.304576 -326.252586) (xy 239.331594 -326.27006) (xy 239.381437 -326.310753)
			(xy 239.425743 -326.357414) (xy 239.463804 -326.409295) (xy 239.495009 -326.465566) (xy 239.51886 -326.525327)
			(xy 239.534975 -326.587621) (xy 239.543096 -326.651452) (xy 239.54359 -326.683624) (xy 239.543057 -326.7162)
			(xy 239.534725 -326.780817) (xy 239.518214 -326.843842) (xy 239.493794 -326.904244) (xy 239.461865 -326.961036)
			(xy 239.422947 -327.013287) (xy 239.377679 -327.060144) (xy 239.326801 -327.10084) (xy 239.299242 -327.118218)
			(xy 239.28832 -327.124822) (xy 239.275366 -327.146666) (xy 239.271302 -327.243948) (xy 239.271485 -327.256565)
			(xy 239.282557 -327.27921) (xy 239.292384 -327.287128) (xy 239.31638 -327.30508) (xy 239.36037 -327.345782)
			(xy 239.399274 -327.39137) (xy 239.432553 -327.441212) (xy 239.459747 -327.494618) (xy 239.480478 -327.550849)
			(xy 239.49446 -327.609126) (xy 239.5015 -327.668642) (xy 239.501934 -327.698608) (xy 239.50141 -327.730215)
			(xy 239.49357 -327.79294) (xy 239.478013 -327.854209) (xy 239.454979 -327.913076) (xy 239.424822 -327.968633)
			(xy 239.388009 -328.020021) (xy 239.345109 -328.066448) (xy 239.296782 -328.107197) (xy 239.27054 -328.12482)
			(xy 239.270286 -328.12482) (xy 239.263393 -328.129697) (xy 239.253086 -328.143061) (xy 239.247687 -328.159052)
			(xy 239.247426 -328.167492) (xy 239.247934 -328.25309) (xy 239.248309 -328.261564) (xy 239.253879 -328.277573)
			(xy 239.264352 -328.290902) (xy 239.271302 -328.295762) (xy 239.297922 -328.31334) (xy 239.347014 -328.354075)
			(xy 239.390623 -328.400632) (xy 239.428063 -328.45228) (xy 239.441969 -328.477626) (xy 239.960912 -328.477626)
			(xy 239.961395 -328.446906) (xy 239.968791 -328.385913) (xy 239.983479 -328.326254) (xy 240.005245 -328.268799)
			(xy 240.033772 -328.214383) (xy 240.050828 -328.188828) (xy 240.056197 -328.180131) (xy 240.060264 -328.160122)
			(xy 240.056214 -328.140109) (xy 240.050828 -328.131424) (xy 240.033788 -328.105858) (xy 240.005251 -328.051447)
			(xy 239.983476 -327.993995) (xy 239.96878 -327.934339) (xy 239.961376 -327.873346) (xy 239.960912 -327.842626)
			(xy 239.961397 -327.810271) (xy 239.969619 -327.746086) (xy 239.98592 -327.683464) (xy 240.010037 -327.623417)
			(xy 240.04158 -327.566916) (xy 240.080039 -327.514875) (xy 240.124791 -327.468136) (xy 240.149634 -327.447402)
			(xy 240.156979 -327.440906) (xy 240.166517 -327.423792) (xy 240.168176 -327.414128) (xy 240.176558 -327.34377)
			(xy 240.177281 -327.334044) (xy 240.172173 -327.315235) (xy 240.166652 -327.307194) (xy 240.166652 -327.30694)
			(xy 240.147187 -327.280383) (xy 240.114591 -327.223172) (xy 240.089655 -327.162231) (xy 240.072798 -327.09858)
			(xy 240.0643 -327.033285) (xy 240.063782 -327.000362) (xy 240.064284 -326.968401) (xy 240.072295 -326.904983)
			(xy 240.088192 -326.843069) (xy 240.111724 -326.783636) (xy 240.142518 -326.727621) (xy 240.180091 -326.675906)
			(xy 240.223848 -326.629309) (xy 240.273101 -326.588564) (xy 240.327072 -326.554313) (xy 240.384911 -326.527096)
			(xy 240.445704 -326.507343) (xy 240.508494 -326.495365) (xy 240.57229 -326.491352) (xy 240.636086 -326.495365)
			(xy 240.698876 -326.507343) (xy 240.759669 -326.527096) (xy 240.817508 -326.554313) (xy 240.871479 -326.588564)
			(xy 240.920732 -326.629309) (xy 240.964489 -326.675906) (xy 241.002062 -326.727621) (xy 241.032856 -326.783636)
			(xy 241.056388 -326.843069) (xy 241.070492 -326.898) (xy 242.061492 -326.898) (xy 242.062007 -326.866714)
			(xy 242.069678 -326.804613) (xy 242.084916 -326.743924) (xy 242.10749 -326.685565) (xy 242.137058 -326.63042)
			(xy 242.173174 -326.579322) (xy 242.215291 -326.533046) (xy 242.262771 -326.49229) (xy 242.288568 -326.474582)
			(xy 242.29871 -326.467049) (xy 242.310575 -326.444783) (xy 242.311174 -326.432164) (xy 242.311174 -326.347836)
			(xy 242.310513 -326.335233) (xy 242.298667 -326.312986) (xy 242.288568 -326.305418) (xy 242.26277 -326.28771)
			(xy 242.21529 -326.246953) (xy 242.173172 -326.200676) (xy 242.137053 -326.149579) (xy 242.10748 -326.094434)
			(xy 242.084899 -326.036076) (xy 242.069653 -325.975388) (xy 242.061972 -325.913287) (xy 242.061492 -325.882)
			(xy 242.061994 -325.850039) (xy 242.070005 -325.786621) (xy 242.085902 -325.724707) (xy 242.109434 -325.665274)
			(xy 242.140228 -325.609259) (xy 242.177801 -325.557544) (xy 242.221558 -325.510947) (xy 242.270811 -325.470202)
			(xy 242.324782 -325.435951) (xy 242.382621 -325.408734) (xy 242.443414 -325.388981) (xy 242.506204 -325.377003)
			(xy 242.57 -325.37299) (xy 242.633796 -325.377003) (xy 242.696586 -325.388981) (xy 242.757379 -325.408734)
			(xy 242.815218 -325.435951) (xy 242.869189 -325.470202) (xy 242.918442 -325.510947) (xy 242.962199 -325.557544)
			(xy 242.999772 -325.609259) (xy 243.030566 -325.665274) (xy 243.054098 -325.724707) (xy 243.069995 -325.786621)
			(xy 243.078006 -325.850039) (xy 243.078508 -325.882) (xy 243.077993 -325.913286) (xy 243.070322 -325.975387)
			(xy 243.055084 -326.036076) (xy 243.03251 -326.094435) (xy 243.002942 -326.14958) (xy 242.966826 -326.200678)
			(xy 242.924709 -326.246954) (xy 242.877229 -326.28771) (xy 242.851432 -326.305418) (xy 242.84129 -326.312951)
			(xy 242.829425 -326.335217) (xy 242.828826 -326.347836) (xy 242.828826 -326.432164) (xy 242.829487 -326.444767)
			(xy 242.841333 -326.467014) (xy 242.851432 -326.474582) (xy 242.87723 -326.49229) (xy 242.92471 -326.533047)
			(xy 242.954721 -326.566022) (xy 253.441454 -326.566022) (xy 253.441872 -326.539798) (xy 253.449066 -326.487846)
			(xy 253.463308 -326.437369) (xy 253.484329 -326.389318) (xy 253.511732 -326.344599) (xy 253.545003 -326.304054)
			(xy 253.583513 -326.268449) (xy 253.604776 -326.253094) (xy 253.616005 -326.244752) (xy 253.633731 -326.22312)
			(xy 253.644926 -326.197493) (xy 253.648751 -326.16979) (xy 253.64492 -326.142087) (xy 253.63372 -326.116462)
			(xy 253.61599 -326.094834) (xy 253.604776 -326.08647) (xy 253.583521 -326.07115) (xy 253.545072 -326.035555)
			(xy 253.511857 -325.995031) (xy 253.484503 -325.950342) (xy 253.463523 -325.90233) (xy 253.449314 -325.851897)
			(xy 253.442142 -325.799994) (xy 253.441708 -325.773796) (xy 253.442194 -325.746545) (xy 253.44995 -325.692597)
			(xy 253.465305 -325.640302) (xy 253.487947 -325.590725) (xy 253.517413 -325.544875) (xy 253.553104 -325.503684)
			(xy 253.594295 -325.467993) (xy 253.640145 -325.438527) (xy 253.689722 -325.415885) (xy 253.742017 -325.40053)
			(xy 253.795965 -325.392774) (xy 253.850467 -325.392774) (xy 253.904415 -325.40053) (xy 253.95671 -325.415885)
			(xy 254.006287 -325.438527) (xy 254.052137 -325.467993) (xy 254.093328 -325.503684) (xy 254.129019 -325.544875)
			(xy 254.158485 -325.590725) (xy 254.181127 -325.640302) (xy 254.196482 -325.692597) (xy 254.204238 -325.746545)
			(xy 254.204724 -325.773796) (xy 254.204286 -325.800019) (xy 254.197092 -325.851969) (xy 254.182851 -325.902444)
			(xy 254.161832 -325.950494) (xy 254.134432 -325.995213) (xy 254.101167 -326.035759) (xy 254.062662 -326.071367)
			(xy 254.041402 -326.086724) (xy 254.030157 -326.095046) (xy 254.012435 -326.116683) (xy 254.001244 -326.142315)
			(xy 253.997422 -326.170021) (xy 254.001255 -326.197725) (xy 254.012457 -326.223352) (xy 254.030188 -326.244982)
			(xy 254.041402 -326.253348) (xy 254.062661 -326.268664) (xy 254.101111 -326.304259) (xy 254.134326 -326.344783)
			(xy 254.16168 -326.389473) (xy 254.182659 -326.437486) (xy 254.196867 -326.48792) (xy 254.204037 -326.539824)
			(xy 254.20447 -326.566022) (xy 254.203984 -326.593273) (xy 254.196228 -326.647221) (xy 254.180873 -326.699516)
			(xy 254.158231 -326.749093) (xy 254.128765 -326.794943) (xy 254.093074 -326.836134) (xy 254.051883 -326.871825)
			(xy 254.006033 -326.901291) (xy 253.956456 -326.923933) (xy 253.904161 -326.939288) (xy 253.850213 -326.947044)
			(xy 253.795711 -326.947044) (xy 253.741763 -326.939288) (xy 253.689468 -326.923933) (xy 253.639891 -326.901291)
			(xy 253.594041 -326.871825) (xy 253.55285 -326.836134) (xy 253.517159 -326.794943) (xy 253.487693 -326.749093)
			(xy 253.465051 -326.699516) (xy 253.449696 -326.647221) (xy 253.44194 -326.593273) (xy 253.441454 -326.566022)
			(xy 242.954721 -326.566022) (xy 242.966828 -326.579324) (xy 243.002947 -326.630421) (xy 243.03252 -326.685566)
			(xy 243.055101 -326.743924) (xy 243.070347 -326.804612) (xy 243.078028 -326.866713) (xy 243.078508 -326.898)
			(xy 243.078006 -326.929961) (xy 243.069995 -326.993379) (xy 243.054098 -327.055293) (xy 243.030566 -327.114726)
			(xy 242.999772 -327.170741) (xy 242.977772 -327.201022) (xy 245.640858 -327.201022) (xy 245.644929 -327.1454)
			(xy 245.657055 -327.090963) (xy 245.676978 -327.038872) (xy 245.704274 -326.990237) (xy 245.73836 -326.946094)
			(xy 245.778509 -326.907385) (xy 245.823867 -326.874934) (xy 245.873467 -326.849433) (xy 245.926251 -326.831426)
			(xy 245.981094 -326.821296) (xy 246.036828 -326.819259) (xy 246.092265 -326.825359) (xy 246.146222 -326.839465)
			(xy 246.197551 -326.861277) (xy 246.245157 -326.890331) (xy 246.288025 -326.926006) (xy 246.325242 -326.967543)
			(xy 246.356015 -327.014056) (xy 246.379687 -327.064553) (xy 246.395755 -327.11796) (xy 246.403875 -327.173136)
			(xy 246.404384 -327.201022) (xy 246.403875 -327.228908) (xy 246.395755 -327.284084) (xy 246.379687 -327.337491)
			(xy 246.356015 -327.387988) (xy 246.325242 -327.434501) (xy 246.301848 -327.46061) (xy 253.441198 -327.46061)
			(xy 253.445269 -327.404988) (xy 253.457395 -327.350551) (xy 253.477318 -327.29846) (xy 253.504614 -327.249825)
			(xy 253.5387 -327.205682) (xy 253.578849 -327.166973) (xy 253.624207 -327.134522) (xy 253.673807 -327.109021)
			(xy 253.726591 -327.091014) (xy 253.781434 -327.080884) (xy 253.837168 -327.078847) (xy 253.892605 -327.084947)
			(xy 253.946562 -327.099053) (xy 253.997891 -327.120865) (xy 254.045497 -327.149919) (xy 254.088365 -327.185594)
			(xy 254.125582 -327.227131) (xy 254.156355 -327.273644) (xy 254.180027 -327.324141) (xy 254.196095 -327.377548)
			(xy 254.204215 -327.432724) (xy 254.204724 -327.46061) (xy 254.204215 -327.488496) (xy 254.196095 -327.543672)
			(xy 254.180027 -327.597079) (xy 254.156355 -327.647576) (xy 254.125582 -327.694089) (xy 254.088365 -327.735626)
			(xy 254.045497 -327.771301) (xy 253.997891 -327.800355) (xy 253.946562 -327.822167) (xy 253.892605 -327.836273)
			(xy 253.837168 -327.842373) (xy 253.781434 -327.840336) (xy 253.726591 -327.830206) (xy 253.673807 -327.812199)
			(xy 253.624207 -327.786698) (xy 253.578849 -327.754247) (xy 253.5387 -327.715538) (xy 253.504614 -327.671395)
			(xy 253.477318 -327.62276) (xy 253.457395 -327.570669) (xy 253.445269 -327.516232) (xy 253.441198 -327.46061)
			(xy 246.301848 -327.46061) (xy 246.288025 -327.476038) (xy 246.245157 -327.511713) (xy 246.197551 -327.540767)
			(xy 246.146222 -327.562579) (xy 246.092265 -327.576685) (xy 246.036828 -327.582785) (xy 245.981094 -327.580748)
			(xy 245.926251 -327.570618) (xy 245.873467 -327.552611) (xy 245.823867 -327.52711) (xy 245.778509 -327.494659)
			(xy 245.73836 -327.45595) (xy 245.704274 -327.411807) (xy 245.676978 -327.363172) (xy 245.657055 -327.311081)
			(xy 245.644929 -327.256644) (xy 245.640858 -327.201022) (xy 242.977772 -327.201022) (xy 242.962199 -327.222456)
			(xy 242.918442 -327.269053) (xy 242.869189 -327.309798) (xy 242.815218 -327.344049) (xy 242.757379 -327.371266)
			(xy 242.696586 -327.391019) (xy 242.633796 -327.402997) (xy 242.57 -327.407011) (xy 242.506204 -327.402997)
			(xy 242.443414 -327.391019) (xy 242.382621 -327.371266) (xy 242.324782 -327.344049) (xy 242.270811 -327.309798)
			(xy 242.221558 -327.269053) (xy 242.177801 -327.222456) (xy 242.140228 -327.170741) (xy 242.109434 -327.114726)
			(xy 242.085902 -327.055293) (xy 242.070005 -326.993379) (xy 242.061994 -326.929961) (xy 242.061492 -326.898)
			(xy 241.070492 -326.898) (xy 241.072285 -326.904983) (xy 241.080296 -326.968401) (xy 241.080798 -327.000362)
			(xy 241.080301 -327.032716) (xy 241.07208 -327.0969) (xy 241.055781 -327.159522) (xy 241.031666 -327.219569)
			(xy 241.000125 -327.27607) (xy 240.961668 -327.328112) (xy 240.916918 -327.374851) (xy 240.892076 -327.395586)
			(xy 240.884737 -327.402089) (xy 240.875196 -327.419197) (xy 240.873534 -327.42886) (xy 240.865152 -327.499218)
			(xy 240.864434 -327.508944) (xy 240.869539 -327.527752) (xy 240.875058 -327.535794) (xy 240.875058 -327.536048)
			(xy 240.894519 -327.562607) (xy 240.927116 -327.619818) (xy 240.952052 -327.680759) (xy 240.96891 -327.744409)
			(xy 240.977409 -327.809703) (xy 240.977928 -327.842626) (xy 240.977465 -327.873347) (xy 240.970063 -327.93434)
			(xy 240.95537 -327.993999) (xy 240.9336 -328.051454) (xy 240.905069 -328.10587) (xy 240.888012 -328.131424)
			(xy 240.882595 -328.140096) (xy 240.87854 -328.160122) (xy 240.882612 -328.180144) (xy 240.888012 -328.188828)
			(xy 240.905079 -328.214376) (xy 240.93361 -328.268792) (xy 240.955379 -328.326249) (xy 240.97007 -328.385909)
			(xy 240.977467 -328.446905) (xy 240.977928 -328.477626) (xy 240.977426 -328.509587) (xy 240.969415 -328.573005)
			(xy 240.953518 -328.634919) (xy 240.929986 -328.694352) (xy 240.899192 -328.750367) (xy 240.861619 -328.802082)
			(xy 240.817862 -328.848679) (xy 240.768609 -328.889424) (xy 240.714638 -328.923675) (xy 240.656799 -328.950892)
			(xy 240.596006 -328.970645) (xy 240.533216 -328.982623) (xy 240.46942 -328.986637) (xy 240.405624 -328.982623)
			(xy 240.342834 -328.970645) (xy 240.282041 -328.950892) (xy 240.224202 -328.923675) (xy 240.170231 -328.889424)
			(xy 240.120978 -328.848679) (xy 240.077221 -328.802082) (xy 240.039648 -328.750367) (xy 240.008854 -328.694352)
			(xy 239.985322 -328.634919) (xy 239.969425 -328.573005) (xy 239.961414 -328.509587) (xy 239.960912 -328.477626)
			(xy 239.441969 -328.477626) (xy 239.458747 -328.508207) (xy 239.482192 -328.567534) (xy 239.498028 -328.629328)
			(xy 239.506009 -328.692618) (xy 239.506506 -328.724514) (xy 239.506004 -328.756475) (xy 239.497993 -328.819893)
			(xy 239.482096 -328.881807) (xy 239.458564 -328.94124) (xy 239.42777 -328.997255) (xy 239.390197 -329.04897)
			(xy 239.34644 -329.095567) (xy 239.297187 -329.136312) (xy 239.243216 -329.170563) (xy 239.185377 -329.19778)
			(xy 239.124584 -329.217533) (xy 239.061794 -329.229511) (xy 238.997998 -329.233525) (xy 238.934202 -329.229511)
			(xy 238.871412 -329.217533) (xy 238.810619 -329.19778) (xy 238.75278 -329.170563) (xy 238.698809 -329.136312)
			(xy 238.649556 -329.095567) (xy 238.605799 -329.04897) (xy 238.568226 -328.997255) (xy 238.537432 -328.94124)
			(xy 238.5139 -328.881807) (xy 238.498003 -328.819893) (xy 238.489992 -328.756475) (xy 238.48949 -328.724514)
			(xy 238.489943 -328.692905) (xy 238.497792 -328.630176) (xy 238.513359 -328.568905) (xy 238.536404 -328.510037)
			(xy 238.56657 -328.454481) (xy 238.603393 -328.403093) (xy 238.646303 -328.356669) (xy 238.694638 -328.315923)
			(xy 238.720884 -328.298302) (xy 238.721138 -328.298302) (xy 238.731381 -328.29075) (xy 238.743375 -328.268342)
			(xy 238.743998 -328.25563) (xy 238.74349 -328.170032) (xy 238.743133 -328.161556) (xy 238.737561 -328.145542)
			(xy 238.727078 -328.132216) (xy 238.720122 -328.12736) (xy 238.693472 -328.109826) (xy 238.644379 -328.069086)
			(xy 238.600771 -328.022522) (xy 238.563332 -327.970868) (xy 238.532652 -327.914934) (xy 238.509213 -327.855601)
			(xy 238.493383 -327.793801) (xy 238.485411 -327.730506) (xy 238.484918 -327.698608) (xy 233.151421 -327.698608)
			(xy 233.148124 -327.796652) (xy 233.160062 -327.82002) (xy 233.171238 -327.827386) (xy 233.197216 -327.845036)
			(xy 233.244998 -327.885798) (xy 233.287396 -327.932136) (xy 233.323761 -327.983343) (xy 233.353541 -328.038641)
			(xy 233.371822 -328.085704) (xy 235.560106 -328.085704) (xy 235.564177 -328.030082) (xy 235.576303 -327.975645)
			(xy 235.596226 -327.923554) (xy 235.623522 -327.874919) (xy 235.657608 -327.830776) (xy 235.697757 -327.792067)
			(xy 235.743115 -327.759616) (xy 235.792715 -327.734115) (xy 235.845499 -327.716108) (xy 235.900342 -327.705978)
			(xy 235.956076 -327.703941) (xy 236.011513 -327.710041) (xy 236.06547 -327.724147) (xy 236.116799 -327.745959)
			(xy 236.164405 -327.775013) (xy 236.207273 -327.810688) (xy 236.24449 -327.852225) (xy 236.275263 -327.898738)
			(xy 236.298935 -327.949235) (xy 236.315003 -328.002642) (xy 236.323123 -328.057818) (xy 236.323632 -328.085704)
			(xy 236.323123 -328.11359) (xy 236.315003 -328.168766) (xy 236.298935 -328.222173) (xy 236.275263 -328.27267)
			(xy 236.24449 -328.319183) (xy 236.207273 -328.36072) (xy 236.164405 -328.396395) (xy 236.116799 -328.425449)
			(xy 236.06547 -328.447261) (xy 236.011513 -328.461367) (xy 235.956076 -328.467467) (xy 235.900342 -328.46543)
			(xy 235.845499 -328.4553) (xy 235.792715 -328.437293) (xy 235.743115 -328.411792) (xy 235.697757 -328.379341)
			(xy 235.657608 -328.340632) (xy 235.623522 -328.296489) (xy 235.596226 -328.247854) (xy 235.576303 -328.195763)
			(xy 235.564177 -328.141326) (xy 235.560106 -328.085704) (xy 233.371822 -328.085704) (xy 233.376282 -328.097187)
			(xy 233.391637 -328.158088) (xy 233.399372 -328.220417) (xy 233.399838 -328.25182) (xy 233.399313 -328.28397)
			(xy 233.391194 -328.347756) (xy 233.375099 -328.410009) (xy 233.351287 -328.469738) (xy 233.320136 -328.525989)
			(xy 233.282144 -328.577865) (xy 233.237916 -328.624538) (xy 233.188158 -328.665265) (xy 233.133664 -328.699396)
			(xy 233.10469 -328.713338) (xy 233.104436 -328.713338) (xy 233.095794 -328.717864) (xy 233.082512 -328.73213)
			(xy 233.075515 -328.750323) (xy 233.075226 -328.760074) (xy 233.076496 -328.868024) (xy 233.092752 -328.892662)
			(xy 233.106722 -328.898758) (xy 233.136596 -328.91232) (xy 233.192907 -328.945988) (xy 233.24442 -328.986621)
			(xy 233.290278 -329.033541) (xy 233.329719 -329.085971) (xy 233.362088 -329.143039) (xy 233.37433 -329.173078)
			(xy 235.579664 -329.173078) (xy 235.583735 -329.117456) (xy 235.595861 -329.063019) (xy 235.615784 -329.010928)
			(xy 235.64308 -328.962293) (xy 235.677166 -328.91815) (xy 235.717315 -328.879441) (xy 235.762673 -328.84699)
			(xy 235.812273 -328.821489) (xy 235.865057 -328.803482) (xy 235.9199 -328.793352) (xy 235.975634 -328.791315)
			(xy 236.031071 -328.797415) (xy 236.085028 -328.811521) (xy 236.136357 -328.833333) (xy 236.183963 -328.862387)
			(xy 236.226831 -328.898062) (xy 236.264048 -328.939599) (xy 236.294821 -328.986112) (xy 236.318493 -329.036609)
			(xy 236.334561 -329.090016) (xy 236.342681 -329.145192) (xy 236.34319 -329.173078) (xy 236.342681 -329.200964)
			(xy 236.334561 -329.25614) (xy 236.318493 -329.309547) (xy 236.294821 -329.360044) (xy 236.264048 -329.406557)
			(xy 236.226831 -329.448094) (xy 236.183963 -329.483769) (xy 236.136357 -329.512823) (xy 236.085028 -329.534635)
			(xy 236.031071 -329.548741) (xy 235.975634 -329.554841) (xy 235.9199 -329.552804) (xy 235.865057 -329.542674)
			(xy 235.812273 -329.524667) (xy 235.762673 -329.499166) (xy 235.717315 -329.466715) (xy 235.677166 -329.428006)
			(xy 235.64308 -329.383863) (xy 235.615784 -329.335228) (xy 235.595861 -329.283137) (xy 235.583735 -329.2287)
			(xy 235.579664 -329.173078) (xy 233.37433 -329.173078) (xy 233.386848 -329.203796) (xy 233.403586 -329.267234)
			(xy 233.412025 -329.332298) (xy 233.412538 -329.365102) (xy 233.412036 -329.397063) (xy 233.404025 -329.460481)
			(xy 233.388128 -329.522395) (xy 233.364596 -329.581828) (xy 233.333802 -329.637843) (xy 233.296229 -329.689558)
			(xy 233.283481 -329.703133) (xy 248.215906 -329.703133) (xy 248.215906 -329.639211) (xy 248.223917 -329.575793)
			(xy 248.239814 -329.513879) (xy 248.263346 -329.454446) (xy 248.29414 -329.398431) (xy 248.331713 -329.346716)
			(xy 248.37547 -329.300119) (xy 248.424723 -329.259374) (xy 248.478694 -329.225123) (xy 248.536533 -329.197906)
			(xy 248.597326 -329.178153) (xy 248.660116 -329.166175) (xy 248.723912 -329.162162) (xy 248.787708 -329.166175)
			(xy 248.850498 -329.178153) (xy 248.911291 -329.197906) (xy 248.96913 -329.225123) (xy 249.023101 -329.259374)
			(xy 249.072354 -329.300119) (xy 249.116111 -329.346716) (xy 249.153684 -329.398431) (xy 249.184478 -329.454446)
			(xy 249.20801 -329.513879) (xy 249.223907 -329.575793) (xy 249.231918 -329.639211) (xy 249.23242 -329.671172)
			(xy 249.231918 -329.703133) (xy 249.223907 -329.766551) (xy 249.20801 -329.828465) (xy 249.184478 -329.887898)
			(xy 249.153684 -329.943913) (xy 249.116111 -329.995628) (xy 249.072354 -330.042225) (xy 249.023101 -330.08297)
			(xy 248.96913 -330.117221) (xy 248.911291 -330.144438) (xy 248.850498 -330.164191) (xy 248.787708 -330.176169)
			(xy 248.723912 -330.180183) (xy 248.660116 -330.176169) (xy 248.597326 -330.164191) (xy 248.536533 -330.144438)
			(xy 248.478694 -330.117221) (xy 248.424723 -330.08297) (xy 248.37547 -330.042225) (xy 248.331713 -329.995628)
			(xy 248.29414 -329.943913) (xy 248.263346 -329.887898) (xy 248.239814 -329.828465) (xy 248.223917 -329.766551)
			(xy 248.215906 -329.703133) (xy 233.283481 -329.703133) (xy 233.252472 -329.736155) (xy 233.203219 -329.7769)
			(xy 233.149248 -329.811151) (xy 233.091409 -329.838368) (xy 233.030616 -329.858121) (xy 232.967826 -329.870099)
			(xy 232.90403 -329.874113) (xy 232.840234 -329.870099) (xy 232.777444 -329.858121) (xy 232.716651 -329.838368)
			(xy 232.658812 -329.811151) (xy 232.604841 -329.7769) (xy 232.555588 -329.736155) (xy 232.511831 -329.689558)
			(xy 232.474258 -329.637843) (xy 232.443464 -329.581828) (xy 232.419932 -329.522395) (xy 232.404035 -329.460481)
			(xy 232.396024 -329.397063) (xy 232.395522 -329.365102) (xy 232.396088 -329.332953) (xy 232.404204 -329.26917)
			(xy 232.420295 -329.206919) (xy 232.444103 -329.147192) (xy 232.475248 -329.090942) (xy 232.513235 -329.039065)
			(xy 232.557457 -328.992391) (xy 232.60721 -328.951662) (xy 232.661699 -328.917528) (xy 232.69067 -328.903584)
			(xy 232.690924 -328.903584) (xy 232.699548 -328.899028) (xy 232.712835 -328.884777) (xy 232.719841 -328.866596)
			(xy 232.720134 -328.856848) (xy 232.718864 -328.748898) (xy 232.702608 -328.72426) (xy 232.688638 -328.718164)
			(xy 232.658763 -328.704604) (xy 232.602454 -328.670933) (xy 232.550943 -328.6303) (xy 232.505086 -328.583378)
			(xy 232.465646 -328.530948) (xy 232.433277 -328.473881) (xy 232.408517 -328.413124) (xy 232.391777 -328.349687)
			(xy 232.383336 -328.284624) (xy 232.382822 -328.25182) (xy 230.533194 -328.25182) (xy 230.533194 -330.908152)
			(xy 230.533194 -330.9112) (xy 230.533646 -330.91629) (xy 230.536326 -330.926148) (xy 230.538528 -330.930758)
			(xy 230.54752 -330.945549) (xy 230.562541 -330.976736) (xy 230.5685 -330.992988) (xy 230.576749 -331.0181)
			(xy 230.585679 -331.070194) (xy 230.58628 -331.09662) (xy 230.58628 -331.724) (xy 234.314492 -331.724)
			(xy 234.315007 -331.692714) (xy 234.322678 -331.630613) (xy 234.337916 -331.569924) (xy 234.36049 -331.511565)
			(xy 234.390058 -331.45642) (xy 234.426174 -331.405322) (xy 234.468291 -331.359046) (xy 234.515771 -331.31829)
			(xy 234.541568 -331.300582) (xy 234.55171 -331.293049) (xy 234.563575 -331.270783) (xy 234.564174 -331.258164)
			(xy 234.564174 -331.173836) (xy 234.563513 -331.161233) (xy 234.551667 -331.138986) (xy 234.541568 -331.131418)
			(xy 234.51577 -331.11371) (xy 234.46829 -331.072953) (xy 234.426172 -331.026676) (xy 234.390053 -330.975579)
			(xy 234.36048 -330.920434) (xy 234.337899 -330.862076) (xy 234.322653 -330.801388) (xy 234.314972 -330.739287)
			(xy 234.314492 -330.708) (xy 234.314994 -330.676039) (xy 234.323005 -330.612621) (xy 234.338902 -330.550707)
			(xy 234.362434 -330.491274) (xy 234.393228 -330.435259) (xy 234.430801 -330.383544) (xy 234.474558 -330.336947)
			(xy 234.523811 -330.296202) (xy 234.577782 -330.261951) (xy 234.635621 -330.234734) (xy 234.696414 -330.214981)
			(xy 234.759204 -330.203003) (xy 234.823 -330.19899) (xy 234.886796 -330.203003) (xy 234.949586 -330.214981)
			(xy 235.010379 -330.234734) (xy 235.068218 -330.261951) (xy 235.122189 -330.296202) (xy 235.171442 -330.336947)
			(xy 235.215199 -330.383544) (xy 235.252772 -330.435259) (xy 235.283566 -330.491274) (xy 235.307098 -330.550707)
			(xy 235.322995 -330.612621) (xy 235.331006 -330.676039) (xy 235.331508 -330.708) (xy 235.330993 -330.739286)
			(xy 235.323322 -330.801387) (xy 235.308084 -330.862076) (xy 235.28551 -330.920435) (xy 235.255942 -330.97558)
			(xy 235.219826 -331.026678) (xy 235.177709 -331.072954) (xy 235.130229 -331.11371) (xy 235.104432 -331.131418)
			(xy 235.09429 -331.138951) (xy 235.082425 -331.161217) (xy 235.081826 -331.173836) (xy 235.081826 -331.258164)
			(xy 235.082487 -331.270767) (xy 235.094333 -331.293014) (xy 235.104432 -331.300582) (xy 235.13023 -331.31829)
			(xy 235.159016 -331.343) (xy 237.870492 -331.343) (xy 237.870975 -331.314081) (xy 237.879707 -331.256907)
			(xy 237.896969 -331.201706) (xy 237.922367 -331.149744) (xy 237.955319 -331.102211) (xy 237.995068 -331.060197)
			(xy 238.017558 -331.04201) (xy 238.02636 -331.034399) (xy 238.036544 -331.013501) (xy 238.037116 -331.001878)
			(xy 238.037116 -330.922122) (xy 238.036544 -330.910494) (xy 238.026378 -330.889585) (xy 238.017558 -330.88199)
			(xy 237.995061 -330.863815) (xy 237.955329 -330.821791) (xy 237.922392 -330.774252) (xy 237.897007 -330.722288)
			(xy 237.879753 -330.667088) (xy 237.871026 -330.609917) (xy 237.870492 -330.581) (xy 237.870978 -330.553749)
			(xy 237.878734 -330.499801) (xy 237.894089 -330.447506) (xy 237.916731 -330.397929) (xy 237.946197 -330.352079)
			(xy 237.981888 -330.310888) (xy 238.023079 -330.275197) (xy 238.068929 -330.245731) (xy 238.118506 -330.223089)
			(xy 238.170801 -330.207734) (xy 238.224749 -330.199978) (xy 238.279251 -330.199978) (xy 238.333199 -330.207734)
			(xy 238.385494 -330.223089) (xy 238.435071 -330.245731) (xy 238.480921 -330.275197) (xy 238.522112 -330.310888)
			(xy 238.557803 -330.352079) (xy 238.587269 -330.397929) (xy 238.609911 -330.447506) (xy 238.625266 -330.499801)
			(xy 238.633022 -330.553749) (xy 238.633508 -330.581) (xy 238.633025 -330.609919) (xy 238.624293 -330.667093)
			(xy 238.607031 -330.722294) (xy 238.581633 -330.774256) (xy 238.548681 -330.821789) (xy 238.508932 -330.863803)
			(xy 238.486442 -330.88199) (xy 238.47764 -330.889601) (xy 238.467456 -330.910499) (xy 238.466884 -330.922122)
			(xy 238.466884 -331.001878) (xy 238.467456 -331.013506) (xy 238.477622 -331.034415) (xy 238.486442 -331.04201)
			(xy 238.508939 -331.060185) (xy 238.548671 -331.102209) (xy 238.581608 -331.149748) (xy 238.606993 -331.201712)
			(xy 238.624247 -331.256912) (xy 238.632974 -331.314083) (xy 238.633508 -331.343) (xy 238.633322 -331.353414)
			(xy 239.74298 -331.353414) (xy 239.743447 -331.322689) (xy 239.75087 -331.261689) (xy 239.765597 -331.202029)
			(xy 239.787413 -331.144582) (xy 239.815999 -331.090186) (xy 239.850939 -331.039636) (xy 239.870996 -331.016356)
			(xy 239.876827 -331.009157) (xy 239.883343 -330.991832) (xy 239.883696 -330.982574) (xy 239.883696 -330.95184)
			(xy 239.883328 -330.942587) (xy 239.876807 -330.925269) (xy 239.870996 -330.918058) (xy 239.850962 -330.894761)
			(xy 239.816035 -330.844207) (xy 239.787455 -330.789812) (xy 239.765638 -330.732369) (xy 239.750902 -330.672717)
			(xy 239.743462 -330.611723) (xy 239.74298 -330.581) (xy 239.743482 -330.549039) (xy 239.751493 -330.485621)
			(xy 239.76739 -330.423707) (xy 239.790922 -330.364274) (xy 239.821716 -330.308259) (xy 239.859289 -330.256544)
			(xy 239.903046 -330.209947) (xy 239.952299 -330.169202) (xy 240.00627 -330.134951) (xy 240.064109 -330.107734)
			(xy 240.124902 -330.087981) (xy 240.187692 -330.076003) (xy 240.251488 -330.07199) (xy 240.315284 -330.076003)
			(xy 240.378074 -330.087981) (xy 240.438867 -330.107734) (xy 240.496706 -330.134951) (xy 240.550677 -330.169202)
			(xy 240.59993 -330.209947) (xy 240.616179 -330.227251) (xy 244.982978 -330.227251) (xy 244.982978 -330.172749)
			(xy 244.990734 -330.118801) (xy 245.006089 -330.066506) (xy 245.028731 -330.016929) (xy 245.058197 -329.971079)
			(xy 245.093888 -329.929888) (xy 245.135079 -329.894197) (xy 245.180929 -329.864731) (xy 245.230506 -329.842089)
			(xy 245.282801 -329.826734) (xy 245.336749 -329.818978) (xy 245.364 -329.818492) (xy 245.39137 -329.81896)
			(xy 245.445549 -329.826778) (xy 245.498052 -329.842266) (xy 245.547799 -329.865108) (xy 245.593766 -329.894831)
			(xy 245.614698 -329.912472) (xy 245.614952 -329.912726) (xy 245.622046 -329.918302) (xy 245.638957 -329.924554)
			(xy 245.647972 -329.924918) (xy 245.715028 -329.924918) (xy 245.724046 -329.924571) (xy 245.740963 -329.918316)
			(xy 245.748048 -329.912726) (xy 245.748048 -329.912472) (xy 245.748302 -329.912472) (xy 245.769235 -329.894831)
			(xy 245.815203 -329.865107) (xy 245.864949 -329.842261) (xy 245.917451 -329.826765) (xy 245.971629 -329.818936)
			(xy 246.026371 -329.818936) (xy 246.080549 -329.826765) (xy 246.133051 -329.842261) (xy 246.182797 -329.865107)
			(xy 246.228765 -329.894831) (xy 246.249698 -329.912472) (xy 246.249952 -329.912726) (xy 246.257046 -329.918302)
			(xy 246.273957 -329.924554) (xy 246.282972 -329.924918) (xy 246.350028 -329.924918) (xy 246.359046 -329.924571)
			(xy 246.375963 -329.918316) (xy 246.383048 -329.912726) (xy 246.383048 -329.912472) (xy 246.383302 -329.912472)
			(xy 246.404219 -329.894814) (xy 246.450196 -329.865106) (xy 246.499948 -329.842274) (xy 246.552452 -329.826787)
			(xy 246.60663 -329.818964) (xy 246.634 -329.818492) (xy 246.661251 -329.818978) (xy 246.715199 -329.826734)
			(xy 246.767494 -329.842089) (xy 246.817071 -329.864731) (xy 246.862921 -329.894197) (xy 246.904112 -329.929888)
			(xy 246.939803 -329.971079) (xy 246.969269 -330.016929) (xy 246.991911 -330.066506) (xy 247.007266 -330.118801)
			(xy 247.015022 -330.172749) (xy 247.015022 -330.227251) (xy 247.007266 -330.281199) (xy 246.991911 -330.333494)
			(xy 246.969269 -330.383071) (xy 246.939803 -330.428921) (xy 246.904112 -330.470112) (xy 246.862921 -330.505803)
			(xy 246.817071 -330.535269) (xy 246.767494 -330.557911) (xy 246.715199 -330.573266) (xy 246.661404 -330.581)
			(xy 256.005076 -330.581) (xy 256.005578 -330.549039) (xy 256.013589 -330.485621) (xy 256.029486 -330.423707)
			(xy 256.053018 -330.364274) (xy 256.083812 -330.308259) (xy 256.121385 -330.256544) (xy 256.165142 -330.209947)
			(xy 256.214395 -330.169202) (xy 256.268366 -330.134951) (xy 256.326205 -330.107734) (xy 256.386998 -330.087981)
			(xy 256.449788 -330.076003) (xy 256.513584 -330.07199) (xy 256.57738 -330.076003) (xy 256.64017 -330.087981)
			(xy 256.700963 -330.107734) (xy 256.758802 -330.134951) (xy 256.812773 -330.169202) (xy 256.862026 -330.209947)
			(xy 256.905783 -330.256544) (xy 256.943356 -330.308259) (xy 256.97415 -330.364274) (xy 256.997682 -330.423707)
			(xy 257.013579 -330.485621) (xy 257.02159 -330.549039) (xy 257.022092 -330.581) (xy 257.021583 -330.612204)
			(xy 257.013931 -330.674141) (xy 256.998755 -330.734676) (xy 256.976282 -330.792898) (xy 256.946851 -330.847931)
			(xy 256.910905 -330.898947) (xy 256.868983 -330.945179) (xy 256.821718 -330.985931) (xy 256.810081 -330.993961)
			(xy 257.555994 -330.993961) (xy 257.555994 -330.930039) (xy 257.564005 -330.866621) (xy 257.579902 -330.804707)
			(xy 257.603434 -330.745274) (xy 257.634228 -330.689259) (xy 257.671801 -330.637544) (xy 257.715558 -330.590947)
			(xy 257.764811 -330.550202) (xy 257.818782 -330.515951) (xy 257.876621 -330.488734) (xy 257.937414 -330.468981)
			(xy 258.000204 -330.457003) (xy 258.064 -330.45299) (xy 258.127796 -330.457003) (xy 258.190586 -330.468981)
			(xy 258.251379 -330.488734) (xy 258.309218 -330.515951) (xy 258.363189 -330.550202) (xy 258.412442 -330.590947)
			(xy 258.456199 -330.637544) (xy 258.493772 -330.689259) (xy 258.524566 -330.745274) (xy 258.548098 -330.804707)
			(xy 258.563995 -330.866621) (xy 258.572006 -330.930039) (xy 258.572508 -330.962) (xy 258.572006 -330.993961)
			(xy 258.563995 -331.057379) (xy 258.548098 -331.119293) (xy 258.524566 -331.178726) (xy 258.493772 -331.234741)
			(xy 258.456199 -331.286456) (xy 258.412442 -331.333053) (xy 258.363189 -331.373798) (xy 258.309218 -331.408049)
			(xy 258.251379 -331.435266) (xy 258.190586 -331.455019) (xy 258.127796 -331.466997) (xy 258.064 -331.471011)
			(xy 258.000204 -331.466997) (xy 257.937414 -331.455019) (xy 257.876621 -331.435266) (xy 257.818782 -331.408049)
			(xy 257.764811 -331.373798) (xy 257.715558 -331.333053) (xy 257.671801 -331.286456) (xy 257.634228 -331.234741)
			(xy 257.603434 -331.178726) (xy 257.579902 -331.119293) (xy 257.564005 -331.057379) (xy 257.555994 -330.993961)
			(xy 256.810081 -330.993961) (xy 256.796032 -331.003656) (xy 256.785872 -331.011169) (xy 256.774016 -331.03345)
			(xy 256.773426 -331.046074) (xy 256.773934 -331.13091) (xy 256.774551 -331.143368) (xy 256.786297 -331.165345)
			(xy 256.796286 -331.17282) (xy 256.796286 -331.173074) (xy 256.796794 -331.173074) (xy 256.825296 -331.192651)
			(xy 256.87721 -331.238327) (xy 256.922461 -331.290611) (xy 256.960219 -331.348539) (xy 256.989786 -331.411046)
			(xy 257.000756 -331.443838) (xy 257.004058 -331.454252) (xy 257.018536 -331.470508) (xy 257.10896 -331.510132)
			(xy 257.130804 -331.509878) (xy 257.14071 -331.505306) (xy 257.166079 -331.493999) (xy 257.219277 -331.478044)
			(xy 257.27423 -331.469989) (xy 257.302 -331.469492) (xy 257.329251 -331.469978) (xy 257.383199 -331.477734)
			(xy 257.435494 -331.493089) (xy 257.485071 -331.515731) (xy 257.530921 -331.545197) (xy 257.572112 -331.580888)
			(xy 257.607803 -331.622079) (xy 257.637269 -331.667929) (xy 257.659911 -331.717506) (xy 257.675266 -331.769801)
			(xy 257.683022 -331.823749) (xy 257.683022 -331.878251) (xy 257.675266 -331.932199) (xy 257.659911 -331.984494)
			(xy 257.637269 -332.034071) (xy 257.607803 -332.079921) (xy 257.572112 -332.121112) (xy 257.530921 -332.156803)
			(xy 257.485071 -332.186269) (xy 257.435494 -332.208911) (xy 257.383199 -332.224266) (xy 257.329251 -332.232022)
			(xy 257.302 -332.232508) (xy 257.273045 -332.231997) (xy 257.215802 -332.223237) (xy 257.160538 -332.205934)
			(xy 257.108521 -332.180485) (xy 257.060942 -332.147473) (xy 257.018894 -332.107655) (xy 256.983341 -332.061944)
			(xy 256.968752 -332.036928) (xy 256.963418 -332.027276) (xy 256.945892 -332.014322) (xy 256.860294 -331.996034)
			(xy 256.849591 -331.99426) (xy 256.82841 -331.998878) (xy 256.8194 -332.004924) (xy 256.793003 -332.023959)
			(xy 256.736265 -332.055838) (xy 256.675921 -332.080214) (xy 256.61296 -332.096689) (xy 256.548411 -332.104992)
			(xy 256.51587 -332.105508) (xy 256.485138 -332.105072) (xy 256.424124 -332.09766) (xy 256.364447 -332.082948)
			(xy 256.306979 -332.06115) (xy 256.252557 -332.032585) (xy 256.201975 -331.997668) (xy 256.15597 -331.956909)
			(xy 256.115214 -331.910901) (xy 256.0803 -331.860317) (xy 256.051737 -331.805894) (xy 256.029943 -331.748424)
			(xy 256.015234 -331.688747) (xy 256.007826 -331.627732) (xy 256.007362 -331.597) (xy 256.007847 -331.565795)
			(xy 256.0155 -331.503856) (xy 256.030678 -331.443319) (xy 256.053153 -331.385097) (xy 256.082588 -331.330063)
			(xy 256.118538 -331.279048) (xy 256.160464 -331.232817) (xy 256.207734 -331.192067) (xy 256.233422 -331.174344)
			(xy 256.243573 -331.166821) (xy 256.255436 -331.144548) (xy 256.256028 -331.131926) (xy 256.25552 -331.04709)
			(xy 256.254881 -331.034635) (xy 256.243149 -331.012659) (xy 256.233168 -331.00518) (xy 256.233168 -331.004926)
			(xy 256.23266 -331.004926) (xy 256.206833 -330.98718) (xy 256.159254 -330.946399) (xy 256.117045 -330.900083)
			(xy 256.080844 -330.848933) (xy 256.0512 -330.793723) (xy 256.028562 -330.735291) (xy 256.013273 -330.67452)
			(xy 256.005564 -330.612332) (xy 256.005076 -330.581) (xy 246.661404 -330.581) (xy 246.661251 -330.581022)
			(xy 246.634 -330.581508) (xy 246.60663 -330.58104) (xy 246.552451 -330.573222) (xy 246.499948 -330.557734)
			(xy 246.450201 -330.534892) (xy 246.404234 -330.505169) (xy 246.383302 -330.487528) (xy 246.383048 -330.487274)
			(xy 246.375954 -330.481698) (xy 246.359043 -330.475446) (xy 246.350028 -330.475082) (xy 246.282972 -330.475082)
			(xy 246.273954 -330.475429) (xy 246.257037 -330.481684) (xy 246.249952 -330.487274) (xy 246.249698 -330.487528)
			(xy 246.228765 -330.505169) (xy 246.182797 -330.534893) (xy 246.133051 -330.557739) (xy 246.080549 -330.573235)
			(xy 246.026371 -330.581064) (xy 245.971629 -330.581064) (xy 245.917451 -330.573235) (xy 245.864949 -330.557739)
			(xy 245.815203 -330.534893) (xy 245.769235 -330.505169) (xy 245.748302 -330.487528) (xy 245.748048 -330.487274)
			(xy 245.740954 -330.481698) (xy 245.724043 -330.475446) (xy 245.715028 -330.475082) (xy 245.647972 -330.475082)
			(xy 245.638954 -330.475429) (xy 245.622037 -330.481684) (xy 245.614952 -330.487274) (xy 245.614952 -330.487528)
			(xy 245.614698 -330.487528) (xy 245.593781 -330.505186) (xy 245.547804 -330.534894) (xy 245.498052 -330.557726)
			(xy 245.445548 -330.573213) (xy 245.39137 -330.581036) (xy 245.364 -330.581508) (xy 245.336749 -330.581022)
			(xy 245.282801 -330.573266) (xy 245.230506 -330.557911) (xy 245.180929 -330.535269) (xy 245.135079 -330.505803)
			(xy 245.093888 -330.470112) (xy 245.058197 -330.428921) (xy 245.028731 -330.383071) (xy 245.006089 -330.333494)
			(xy 244.990734 -330.281199) (xy 244.982978 -330.227251) (xy 240.616179 -330.227251) (xy 240.643687 -330.256544)
			(xy 240.68126 -330.308259) (xy 240.712054 -330.364274) (xy 240.735586 -330.423707) (xy 240.751483 -330.485621)
			(xy 240.759494 -330.549039) (xy 240.759996 -330.581) (xy 240.759544 -330.611726) (xy 240.752119 -330.672726)
			(xy 240.737389 -330.732386) (xy 240.71557 -330.789834) (xy 240.686981 -330.844229) (xy 240.652039 -330.894779)
			(xy 240.63198 -330.918058) (xy 240.62614 -330.925251) (xy 240.619631 -330.942581) (xy 240.61928 -330.95184)
			(xy 240.61928 -330.982574) (xy 240.619646 -330.991827) (xy 240.626168 -331.009145) (xy 240.63198 -331.016356)
			(xy 240.652017 -331.039651) (xy 240.686944 -331.090205) (xy 240.715524 -331.1446) (xy 240.737341 -331.202043)
			(xy 240.752076 -331.261697) (xy 240.759515 -331.322691) (xy 240.759996 -331.353414) (xy 240.759494 -331.385375)
			(xy 240.751483 -331.448793) (xy 240.735586 -331.510707) (xy 240.712054 -331.57014) (xy 240.68126 -331.626155)
			(xy 240.643687 -331.67787) (xy 240.59993 -331.724467) (xy 240.550677 -331.765212) (xy 240.496706 -331.799463)
			(xy 240.438867 -331.82668) (xy 240.378074 -331.846433) (xy 240.315284 -331.858411) (xy 240.251488 -331.862425)
			(xy 240.187692 -331.858411) (xy 240.124902 -331.846433) (xy 240.064109 -331.82668) (xy 240.00627 -331.799463)
			(xy 239.952299 -331.765212) (xy 239.903046 -331.724467) (xy 239.859289 -331.67787) (xy 239.821716 -331.626155)
			(xy 239.790922 -331.57014) (xy 239.76739 -331.510707) (xy 239.751493 -331.448793) (xy 239.743482 -331.385375)
			(xy 239.74298 -331.353414) (xy 238.633322 -331.353414) (xy 238.633022 -331.370251) (xy 238.625266 -331.424199)
			(xy 238.609911 -331.476494) (xy 238.587269 -331.526071) (xy 238.557803 -331.571921) (xy 238.522112 -331.613112)
			(xy 238.480921 -331.648803) (xy 238.435071 -331.678269) (xy 238.385494 -331.700911) (xy 238.333199 -331.716266)
			(xy 238.279251 -331.724022) (xy 238.224749 -331.724022) (xy 238.170801 -331.716266) (xy 238.118506 -331.700911)
			(xy 238.068929 -331.678269) (xy 238.023079 -331.648803) (xy 237.981888 -331.613112) (xy 237.946197 -331.571921)
			(xy 237.916731 -331.526071) (xy 237.894089 -331.476494) (xy 237.878734 -331.424199) (xy 237.870978 -331.370251)
			(xy 237.870492 -331.343) (xy 235.159016 -331.343) (xy 235.17771 -331.359047) (xy 235.219828 -331.405324)
			(xy 235.255947 -331.456421) (xy 235.28552 -331.511566) (xy 235.308101 -331.569924) (xy 235.323347 -331.630612)
			(xy 235.331028 -331.692713) (xy 235.331508 -331.724) (xy 235.331006 -331.755961) (xy 235.322995 -331.819379)
			(xy 235.307098 -331.881293) (xy 235.283566 -331.940726) (xy 235.252772 -331.996741) (xy 235.215199 -332.048456)
			(xy 235.171442 -332.095053) (xy 235.122189 -332.135798) (xy 235.068218 -332.170049) (xy 235.010379 -332.197266)
			(xy 234.949586 -332.217019) (xy 234.886796 -332.228997) (xy 234.823 -332.233011) (xy 234.759204 -332.228997)
			(xy 234.696414 -332.217019) (xy 234.635621 -332.197266) (xy 234.577782 -332.170049) (xy 234.523811 -332.135798)
			(xy 234.474558 -332.095053) (xy 234.430801 -332.048456) (xy 234.393228 -331.996741) (xy 234.362434 -331.940726)
			(xy 234.338902 -331.881293) (xy 234.323005 -331.819379) (xy 234.314994 -331.755961) (xy 234.314492 -331.724)
			(xy 230.58628 -331.724) (xy 230.58628 -332.771961) (xy 231.266994 -332.771961) (xy 231.266994 -332.708039)
			(xy 231.275005 -332.644621) (xy 231.290902 -332.582707) (xy 231.314434 -332.523274) (xy 231.345228 -332.467259)
			(xy 231.382801 -332.415544) (xy 231.426558 -332.368947) (xy 231.475811 -332.328202) (xy 231.529782 -332.293951)
			(xy 231.587621 -332.266734) (xy 231.648414 -332.246981) (xy 231.711204 -332.235003) (xy 231.775 -332.23099)
			(xy 231.838796 -332.235003) (xy 231.901586 -332.246981) (xy 231.962379 -332.266734) (xy 232.020218 -332.293951)
			(xy 232.074189 -332.328202) (xy 232.123442 -332.368947) (xy 232.167199 -332.415544) (xy 232.204772 -332.467259)
			(xy 232.235566 -332.523274) (xy 232.259098 -332.582707) (xy 232.274995 -332.644621) (xy 232.283006 -332.708039)
			(xy 232.283508 -332.74) (xy 234.313982 -332.74) (xy 234.318053 -332.684378) (xy 234.330179 -332.629941)
			(xy 234.350102 -332.57785) (xy 234.377398 -332.529215) (xy 234.411484 -332.485072) (xy 234.451633 -332.446363)
			(xy 234.496991 -332.413912) (xy 234.546591 -332.388411) (xy 234.599375 -332.370404) (xy 234.654218 -332.360274)
			(xy 234.709952 -332.358237) (xy 234.765389 -332.364337) (xy 234.819346 -332.378443) (xy 234.870675 -332.400255)
			(xy 234.918281 -332.429309) (xy 234.961149 -332.464984) (xy 234.998366 -332.506521) (xy 235.029139 -332.553034)
			(xy 235.052811 -332.603531) (xy 235.05566 -332.613) (xy 237.869982 -332.613) (xy 237.874053 -332.557378)
			(xy 237.886179 -332.502941) (xy 237.906102 -332.45085) (xy 237.933398 -332.402215) (xy 237.967484 -332.358072)
			(xy 238.007633 -332.319363) (xy 238.052991 -332.286912) (xy 238.102591 -332.261411) (xy 238.155375 -332.243404)
			(xy 238.210218 -332.233274) (xy 238.265952 -332.231237) (xy 238.321389 -332.237337) (xy 238.375346 -332.251443)
			(xy 238.426675 -332.273255) (xy 238.474281 -332.302309) (xy 238.517149 -332.337984) (xy 238.554366 -332.379521)
			(xy 238.585139 -332.426034) (xy 238.608811 -332.476531) (xy 238.624879 -332.529938) (xy 238.632999 -332.585114)
			(xy 238.633508 -332.613) (xy 238.632999 -332.640886) (xy 238.632399 -332.644961) (xy 239.678712 -332.644961)
			(xy 239.678712 -332.581039) (xy 239.686723 -332.517621) (xy 239.70262 -332.455707) (xy 239.726152 -332.396274)
			(xy 239.756946 -332.340259) (xy 239.794519 -332.288544) (xy 239.838276 -332.241947) (xy 239.887529 -332.201202)
			(xy 239.9415 -332.166951) (xy 239.999339 -332.139734) (xy 240.060132 -332.119981) (xy 240.122922 -332.108003)
			(xy 240.186718 -332.10399) (xy 240.202774 -332.105) (xy 247.267982 -332.105) (xy 247.272053 -332.049378)
			(xy 247.284179 -331.994941) (xy 247.304102 -331.94285) (xy 247.331398 -331.894215) (xy 247.365484 -331.850072)
			(xy 247.405633 -331.811363) (xy 247.450991 -331.778912) (xy 247.500591 -331.753411) (xy 247.553375 -331.735404)
			(xy 247.608218 -331.725274) (xy 247.663952 -331.723237) (xy 247.719389 -331.729337) (xy 247.773346 -331.743443)
			(xy 247.824675 -331.765255) (xy 247.872281 -331.794309) (xy 247.915149 -331.829984) (xy 247.952366 -331.871521)
			(xy 247.983139 -331.918034) (xy 248.006811 -331.968531) (xy 248.022879 -332.021938) (xy 248.030999 -332.077114)
			(xy 248.031508 -332.105) (xy 248.030999 -332.132886) (xy 248.030399 -332.136961) (xy 248.919994 -332.136961)
			(xy 248.919994 -332.073039) (xy 248.928005 -332.009621) (xy 248.943902 -331.947707) (xy 248.967434 -331.888274)
			(xy 248.998228 -331.832259) (xy 249.035801 -331.780544) (xy 249.079558 -331.733947) (xy 249.128811 -331.693202)
			(xy 249.182782 -331.658951) (xy 249.240621 -331.631734) (xy 249.301414 -331.611981) (xy 249.364204 -331.600003)
			(xy 249.428 -331.59599) (xy 249.491796 -331.600003) (xy 249.554586 -331.611981) (xy 249.615379 -331.631734)
			(xy 249.673218 -331.658951) (xy 249.727189 -331.693202) (xy 249.776442 -331.733947) (xy 249.820199 -331.780544)
			(xy 249.857772 -331.832259) (xy 249.888566 -331.888274) (xy 249.912098 -331.947707) (xy 249.927995 -332.009621)
			(xy 249.936006 -332.073039) (xy 249.936508 -332.105) (xy 249.936006 -332.136961) (xy 249.927995 -332.200379)
			(xy 249.912098 -332.262293) (xy 249.888566 -332.321726) (xy 249.857772 -332.377741) (xy 249.820199 -332.429456)
			(xy 249.776442 -332.476053) (xy 249.727189 -332.516798) (xy 249.673218 -332.551049) (xy 249.615379 -332.578266)
			(xy 249.554586 -332.598019) (xy 249.491796 -332.609997) (xy 249.428 -332.614011) (xy 249.364204 -332.609997)
			(xy 249.301414 -332.598019) (xy 249.240621 -332.578266) (xy 249.182782 -332.551049) (xy 249.128811 -332.516798)
			(xy 249.079558 -332.476053) (xy 249.035801 -332.429456) (xy 248.998228 -332.377741) (xy 248.967434 -332.321726)
			(xy 248.943902 -332.262293) (xy 248.928005 -332.200379) (xy 248.919994 -332.136961) (xy 248.030399 -332.136961)
			(xy 248.022879 -332.188062) (xy 248.006811 -332.241469) (xy 247.983139 -332.291966) (xy 247.952366 -332.338479)
			(xy 247.915149 -332.380016) (xy 247.872281 -332.415691) (xy 247.824675 -332.444745) (xy 247.773346 -332.466557)
			(xy 247.719389 -332.480663) (xy 247.663952 -332.486763) (xy 247.608218 -332.484726) (xy 247.553375 -332.474596)
			(xy 247.500591 -332.456589) (xy 247.450991 -332.431088) (xy 247.405633 -332.398637) (xy 247.365484 -332.359928)
			(xy 247.331398 -332.315785) (xy 247.304102 -332.26715) (xy 247.284179 -332.215059) (xy 247.272053 -332.160622)
			(xy 247.267982 -332.105) (xy 240.202774 -332.105) (xy 240.250514 -332.108003) (xy 240.313304 -332.119981)
			(xy 240.374097 -332.139734) (xy 240.431936 -332.166951) (xy 240.485907 -332.201202) (xy 240.53516 -332.241947)
			(xy 240.578917 -332.288544) (xy 240.61649 -332.340259) (xy 240.647284 -332.396274) (xy 240.670816 -332.455707)
			(xy 240.686713 -332.517621) (xy 240.694724 -332.581039) (xy 240.695226 -332.613) (xy 240.694724 -332.644961)
			(xy 240.686713 -332.708379) (xy 240.670816 -332.770293) (xy 240.647284 -332.829726) (xy 240.61649 -332.885741)
			(xy 240.578917 -332.937456) (xy 240.53516 -332.984053) (xy 240.485907 -333.024798) (xy 240.431936 -333.059049)
			(xy 240.374097 -333.086266) (xy 240.313304 -333.106019) (xy 240.250514 -333.117997) (xy 240.186718 -333.122011)
			(xy 240.122922 -333.117997) (xy 240.060132 -333.106019) (xy 239.999339 -333.086266) (xy 239.9415 -333.059049)
			(xy 239.887529 -333.024798) (xy 239.838276 -332.984053) (xy 239.794519 -332.937456) (xy 239.756946 -332.885741)
			(xy 239.726152 -332.829726) (xy 239.70262 -332.770293) (xy 239.686723 -332.708379) (xy 239.678712 -332.644961)
			(xy 238.632399 -332.644961) (xy 238.624879 -332.696062) (xy 238.608811 -332.749469) (xy 238.585139 -332.799966)
			(xy 238.554366 -332.846479) (xy 238.517149 -332.888016) (xy 238.474281 -332.923691) (xy 238.426675 -332.952745)
			(xy 238.375346 -332.974557) (xy 238.321389 -332.988663) (xy 238.265952 -332.994763) (xy 238.210218 -332.992726)
			(xy 238.155375 -332.982596) (xy 238.102591 -332.964589) (xy 238.052991 -332.939088) (xy 238.007633 -332.906637)
			(xy 237.967484 -332.867928) (xy 237.933398 -332.823785) (xy 237.906102 -332.77515) (xy 237.886179 -332.723059)
			(xy 237.874053 -332.668622) (xy 237.869982 -332.613) (xy 235.05566 -332.613) (xy 235.068879 -332.656938)
			(xy 235.076999 -332.712114) (xy 235.077508 -332.74) (xy 235.076999 -332.767886) (xy 235.068879 -332.823062)
			(xy 235.052811 -332.876469) (xy 235.029139 -332.926966) (xy 234.998366 -332.973479) (xy 234.961149 -333.015016)
			(xy 234.918281 -333.050691) (xy 234.870675 -333.079745) (xy 234.819346 -333.101557) (xy 234.765389 -333.115663)
			(xy 234.709952 -333.121763) (xy 234.654218 -333.119726) (xy 234.599375 -333.109596) (xy 234.546591 -333.091589)
			(xy 234.496991 -333.066088) (xy 234.451633 -333.033637) (xy 234.411484 -332.994928) (xy 234.377398 -332.950785)
			(xy 234.350102 -332.90215) (xy 234.330179 -332.850059) (xy 234.318053 -332.795622) (xy 234.313982 -332.74)
			(xy 232.283508 -332.74) (xy 232.283006 -332.771961) (xy 232.274995 -332.835379) (xy 232.259098 -332.897293)
			(xy 232.235566 -332.956726) (xy 232.204772 -333.012741) (xy 232.167199 -333.064456) (xy 232.123442 -333.111053)
			(xy 232.074189 -333.151798) (xy 232.020218 -333.186049) (xy 231.962379 -333.213266) (xy 231.901586 -333.233019)
			(xy 231.838796 -333.244997) (xy 231.775 -333.249011) (xy 231.711204 -333.244997) (xy 231.648414 -333.233019)
			(xy 231.587621 -333.213266) (xy 231.529782 -333.186049) (xy 231.475811 -333.151798) (xy 231.426558 -333.111053)
			(xy 231.382801 -333.064456) (xy 231.345228 -333.012741) (xy 231.314434 -332.956726) (xy 231.290902 -332.897293)
			(xy 231.275005 -332.835379) (xy 231.266994 -332.771961) (xy 230.58628 -332.771961) (xy 230.58628 -334.099408)
			(xy 234.558078 -334.099408) (xy 234.55858 -334.067447) (xy 234.566591 -334.004029) (xy 234.582488 -333.942115)
			(xy 234.60602 -333.882682) (xy 234.636814 -333.826667) (xy 234.674387 -333.774952) (xy 234.718144 -333.728355)
			(xy 234.767397 -333.68761) (xy 234.821368 -333.653359) (xy 234.879207 -333.626142) (xy 234.94 -333.606389)
			(xy 235.00279 -333.594411) (xy 235.066586 -333.590398) (xy 235.130382 -333.594411) (xy 235.193172 -333.606389)
			(xy 235.253965 -333.626142) (xy 235.311804 -333.653359) (xy 235.365775 -333.68761) (xy 235.415028 -333.728355)
			(xy 235.458785 -333.774952) (xy 235.496358 -333.826667) (xy 235.527152 -333.882682) (xy 235.550684 -333.942115)
			(xy 235.566581 -334.004029) (xy 235.574592 -334.067447) (xy 235.575094 -334.099408) (xy 235.573824 -334.133952)
			(xy 235.573062 -334.14462) (xy 235.580174 -334.164432) (xy 235.64596 -334.234282) (xy 235.665264 -334.24241)
			(xy 235.678726 -334.24241) (xy 235.705979 -334.242854) (xy 235.711722 -334.24368) (xy 236.610906 -334.24368)
			(xy 236.611449 -334.214834) (xy 236.620125 -334.157797) (xy 236.63729 -334.102718) (xy 236.662554 -334.050851)
			(xy 236.69534 -334.003379) (xy 236.7349 -333.961387) (xy 236.780332 -333.925829) (xy 236.830601 -333.897519)
			(xy 236.88456 -333.877101) (xy 236.912658 -333.870554) (xy 236.922056 -333.868522) (xy 236.937804 -333.858108)
			(xy 236.988858 -333.786734) (xy 236.99343 -333.7687) (xy 236.992414 -333.759302) (xy 236.992414 -333.758794)
			(xy 236.990649 -333.743488) (xy 236.988744 -333.712733) (xy 236.988604 -333.697326) (xy 236.989106 -333.665365)
			(xy 236.997117 -333.601947) (xy 237.013014 -333.540033) (xy 237.036546 -333.4806) (xy 237.06734 -333.424585)
			(xy 237.104913 -333.37287) (xy 237.14867 -333.326273) (xy 237.197923 -333.285528) (xy 237.251894 -333.251277)
			(xy 237.309733 -333.22406) (xy 237.370526 -333.204307) (xy 237.433316 -333.192329) (xy 237.497112 -333.188316)
			(xy 237.560908 -333.192329) (xy 237.623698 -333.204307) (xy 237.684491 -333.22406) (xy 237.74233 -333.251277)
			(xy 237.796301 -333.285528) (xy 237.845554 -333.326273) (xy 237.889311 -333.37287) (xy 237.926884 -333.424585)
			(xy 237.957678 -333.4806) (xy 237.98121 -333.540033) (xy 237.997107 -333.601947) (xy 238.005118 -333.665365)
			(xy 238.00562 -333.697326) (xy 238.005168 -333.727441) (xy 237.998054 -333.78725) (xy 237.983928 -333.845801)
			(xy 237.962988 -333.902275) (xy 237.956489 -333.914961) (xy 240.195094 -333.914961) (xy 240.195094 -333.851039)
			(xy 240.203105 -333.787621) (xy 240.219002 -333.725707) (xy 240.242534 -333.666274) (xy 240.273328 -333.610259)
			(xy 240.310901 -333.558544) (xy 240.354658 -333.511947) (xy 240.403911 -333.471202) (xy 240.457882 -333.436951)
			(xy 240.515721 -333.409734) (xy 240.576514 -333.389981) (xy 240.639304 -333.378003) (xy 240.7031 -333.37399)
			(xy 240.766896 -333.378003) (xy 240.829686 -333.389981) (xy 240.890479 -333.409734) (xy 240.915353 -333.421439)
			(xy 246.483626 -333.421439) (xy 246.483626 -333.357517) (xy 246.491637 -333.294099) (xy 246.507534 -333.232185)
			(xy 246.531066 -333.172752) (xy 246.56186 -333.116737) (xy 246.599433 -333.065022) (xy 246.64319 -333.018425)
			(xy 246.692443 -332.97768) (xy 246.746414 -332.943429) (xy 246.804253 -332.916212) (xy 246.865046 -332.896459)
			(xy 246.927836 -332.884481) (xy 246.991632 -332.880468) (xy 247.055428 -332.884481) (xy 247.118218 -332.896459)
			(xy 247.125918 -332.898961) (xy 253.326894 -332.898961) (xy 253.326894 -332.835039) (xy 253.334905 -332.771621)
			(xy 253.350802 -332.709707) (xy 253.374334 -332.650274) (xy 253.405128 -332.594259) (xy 253.442701 -332.542544)
			(xy 253.486458 -332.495947) (xy 253.535711 -332.455202) (xy 253.589682 -332.420951) (xy 253.647521 -332.393734)
			(xy 253.708314 -332.373981) (xy 253.771104 -332.362003) (xy 253.8349 -332.35799) (xy 253.898696 -332.362003)
			(xy 253.961486 -332.373981) (xy 254.022279 -332.393734) (xy 254.080118 -332.420951) (xy 254.134089 -332.455202)
			(xy 254.183342 -332.495947) (xy 254.227099 -332.542544) (xy 254.264672 -332.594259) (xy 254.295466 -332.650274)
			(xy 254.318998 -332.709707) (xy 254.334895 -332.771621) (xy 254.342906 -332.835039) (xy 254.343408 -332.867)
			(xy 256.323082 -332.867) (xy 256.327153 -332.811378) (xy 256.339279 -332.756941) (xy 256.359202 -332.70485)
			(xy 256.386498 -332.656215) (xy 256.420584 -332.612072) (xy 256.460733 -332.573363) (xy 256.506091 -332.540912)
			(xy 256.555691 -332.515411) (xy 256.608475 -332.497404) (xy 256.663318 -332.487274) (xy 256.719052 -332.485237)
			(xy 256.774489 -332.491337) (xy 256.828446 -332.505443) (xy 256.879775 -332.527255) (xy 256.927381 -332.556309)
			(xy 256.970249 -332.591984) (xy 257.007466 -332.633521) (xy 257.038239 -332.680034) (xy 257.061911 -332.730531)
			(xy 257.077979 -332.783938) (xy 257.086099 -332.839114) (xy 257.086608 -332.867) (xy 257.086099 -332.894886)
			(xy 257.077979 -332.950062) (xy 257.061911 -333.003469) (xy 257.038239 -333.053966) (xy 257.007466 -333.100479)
			(xy 256.970249 -333.142016) (xy 256.927381 -333.177691) (xy 256.879775 -333.206745) (xy 256.828446 -333.228557)
			(xy 256.774489 -333.242663) (xy 256.719052 -333.248763) (xy 256.663318 -333.246726) (xy 256.608475 -333.236596)
			(xy 256.555691 -333.218589) (xy 256.506091 -333.193088) (xy 256.460733 -333.160637) (xy 256.420584 -333.121928)
			(xy 256.386498 -333.077785) (xy 256.359202 -333.02915) (xy 256.339279 -332.977059) (xy 256.327153 -332.922622)
			(xy 256.323082 -332.867) (xy 254.343408 -332.867) (xy 254.342906 -332.898961) (xy 254.334895 -332.962379)
			(xy 254.318998 -333.024293) (xy 254.295466 -333.083726) (xy 254.264672 -333.139741) (xy 254.227099 -333.191456)
			(xy 254.183342 -333.238053) (xy 254.134089 -333.278798) (xy 254.080118 -333.313049) (xy 254.022279 -333.340266)
			(xy 253.961486 -333.360019) (xy 253.898696 -333.371997) (xy 253.8349 -333.376011) (xy 253.771104 -333.371997)
			(xy 253.708314 -333.360019) (xy 253.647521 -333.340266) (xy 253.589682 -333.313049) (xy 253.535711 -333.278798)
			(xy 253.486458 -333.238053) (xy 253.442701 -333.191456) (xy 253.405128 -333.139741) (xy 253.374334 -333.083726)
			(xy 253.350802 -333.024293) (xy 253.334905 -332.962379) (xy 253.326894 -332.898961) (xy 247.125918 -332.898961)
			(xy 247.179011 -332.916212) (xy 247.23685 -332.943429) (xy 247.290821 -332.97768) (xy 247.340074 -333.018425)
			(xy 247.383831 -333.065022) (xy 247.421404 -333.116737) (xy 247.452198 -333.172752) (xy 247.47573 -333.232185)
			(xy 247.491627 -333.294099) (xy 247.499638 -333.357517) (xy 247.50014 -333.389478) (xy 247.499638 -333.421439)
			(xy 247.491627 -333.484857) (xy 247.47573 -333.546771) (xy 247.452198 -333.606204) (xy 247.421404 -333.662219)
			(xy 247.383831 -333.713934) (xy 247.340074 -333.760531) (xy 247.290821 -333.801276) (xy 247.23685 -333.835527)
			(xy 247.179011 -333.862744) (xy 247.118218 -333.882497) (xy 247.055428 -333.894475) (xy 246.991632 -333.898489)
			(xy 246.927836 -333.894475) (xy 246.865046 -333.882497) (xy 246.804253 -333.862744) (xy 246.746414 -333.835527)
			(xy 246.692443 -333.801276) (xy 246.64319 -333.760531) (xy 246.599433 -333.713934) (xy 246.56186 -333.662219)
			(xy 246.531066 -333.606204) (xy 246.507534 -333.546771) (xy 246.491637 -333.484857) (xy 246.483626 -333.421439)
			(xy 240.915353 -333.421439) (xy 240.948318 -333.436951) (xy 241.002289 -333.471202) (xy 241.051542 -333.511947)
			(xy 241.095299 -333.558544) (xy 241.132872 -333.610259) (xy 241.163666 -333.666274) (xy 241.187198 -333.725707)
			(xy 241.203095 -333.787621) (xy 241.211106 -333.851039) (xy 241.211608 -333.883) (xy 241.211106 -333.914961)
			(xy 241.203095 -333.978379) (xy 241.187198 -334.040293) (xy 241.163666 -334.099726) (xy 241.132872 -334.155741)
			(xy 241.095299 -334.207456) (xy 241.051542 -334.254053) (xy 241.002289 -334.294798) (xy 240.948318 -334.329049)
			(xy 240.890479 -334.356266) (xy 240.829686 -334.376019) (xy 240.766896 -334.387997) (xy 240.7031 -334.392011)
			(xy 240.639304 -334.387997) (xy 240.576514 -334.376019) (xy 240.515721 -334.356266) (xy 240.457882 -334.329049)
			(xy 240.403911 -334.294798) (xy 240.354658 -334.254053) (xy 240.310901 -334.207456) (xy 240.273328 -334.155741)
			(xy 240.242534 -334.099726) (xy 240.219002 -334.040293) (xy 240.203105 -333.978379) (xy 240.195094 -333.914961)
			(xy 237.956489 -333.914961) (xy 237.935527 -333.955882) (xy 237.90193 -334.005871) (xy 237.862665 -334.051544)
			(xy 237.840774 -334.07223) (xy 237.832138 -334.080104) (xy 237.823756 -334.10144) (xy 237.830868 -334.20431)
			(xy 237.842552 -334.22463) (xy 237.852204 -334.23098) (xy 237.877525 -334.248772) (xy 237.924097 -334.289528)
			(xy 237.965378 -334.335636) (xy 238.000756 -334.386413) (xy 238.029709 -334.44111) (xy 238.051809 -334.498916)
			(xy 238.066728 -334.558978) (xy 238.074246 -334.620407) (xy 238.074708 -334.65135) (xy 238.074291 -334.682082)
			(xy 238.066877 -334.743098) (xy 238.052163 -334.802774) (xy 238.030363 -334.860243) (xy 238.001795 -334.914665)
			(xy 237.966877 -334.965247) (xy 237.926116 -335.011251) (xy 237.880107 -335.052008) (xy 237.871482 -335.057961)
			(xy 240.195094 -335.057961) (xy 240.195094 -334.994039) (xy 240.203105 -334.930621) (xy 240.219002 -334.868707)
			(xy 240.242534 -334.809274) (xy 240.273328 -334.753259) (xy 240.310901 -334.701544) (xy 240.354658 -334.654947)
			(xy 240.403911 -334.614202) (xy 240.457882 -334.579951) (xy 240.515721 -334.552734) (xy 240.576514 -334.532981)
			(xy 240.639304 -334.521003) (xy 240.7031 -334.51699) (xy 240.766896 -334.521003) (xy 240.829686 -334.532981)
			(xy 240.890479 -334.552734) (xy 240.948318 -334.579951) (xy 241.002289 -334.614202) (xy 241.051542 -334.654947)
			(xy 241.095299 -334.701544) (xy 241.132872 -334.753259) (xy 241.163666 -334.809274) (xy 241.187198 -334.868707)
			(xy 241.203095 -334.930621) (xy 241.211106 -334.994039) (xy 241.211608 -335.026) (xy 241.211106 -335.057961)
			(xy 241.203095 -335.121379) (xy 241.187198 -335.183293) (xy 241.163666 -335.242726) (xy 241.132872 -335.298741)
			(xy 241.095299 -335.350456) (xy 241.051542 -335.397053) (xy 241.002289 -335.437798) (xy 240.948318 -335.472049)
			(xy 240.890479 -335.499266) (xy 240.829686 -335.519019) (xy 240.766896 -335.530997) (xy 240.7031 -335.535011)
			(xy 240.639304 -335.530997) (xy 240.576514 -335.519019) (xy 240.515721 -335.499266) (xy 240.457882 -335.472049)
			(xy 240.403911 -335.437798) (xy 240.354658 -335.397053) (xy 240.310901 -335.350456) (xy 240.273328 -335.298741)
			(xy 240.242534 -335.242726) (xy 240.219002 -335.183293) (xy 240.203105 -335.121379) (xy 240.195094 -335.057961)
			(xy 237.871482 -335.057961) (xy 237.829522 -335.086921) (xy 237.775097 -335.115484) (xy 237.717627 -335.137278)
			(xy 237.657948 -335.151986) (xy 237.596932 -335.159394) (xy 237.5662 -335.159858) (xy 237.534637 -335.159433)
			(xy 237.472 -335.151597) (xy 237.410814 -335.136069) (xy 237.35202 -335.113089) (xy 237.296521 -335.08301)
			(xy 237.245172 -335.046295) (xy 237.198761 -335.003507) (xy 237.158001 -334.955304) (xy 237.12352 -334.902428)
			(xy 237.095847 -334.845691) (xy 237.075408 -334.785966) (xy 237.062517 -334.724171) (xy 237.05947 -334.692752)
			(xy 237.058192 -334.683388) (xy 237.049863 -334.666446) (xy 237.043214 -334.659732) (xy 237.005622 -334.624934)
			(xy 236.992414 -334.625188) (xy 236.965161 -334.624732) (xy 236.911208 -334.616976) (xy 236.858909 -334.601621)
			(xy 236.809328 -334.578978) (xy 236.763474 -334.54951) (xy 236.72228 -334.513815) (xy 236.686586 -334.472622)
			(xy 236.657119 -334.426767) (xy 236.634477 -334.377185) (xy 236.619123 -334.324886) (xy 236.611368 -334.270933)
			(xy 236.610906 -334.24368) (xy 235.711722 -334.24368) (xy 235.759929 -334.250614) (xy 235.812226 -334.265974)
			(xy 235.861804 -334.288619) (xy 235.907655 -334.31809) (xy 235.948846 -334.353786) (xy 235.984537 -334.39498)
			(xy 236.014002 -334.440835) (xy 236.036642 -334.490416) (xy 236.051995 -334.542714) (xy 236.059749 -334.596665)
			(xy 236.060234 -334.623918) (xy 236.059753 -334.651065) (xy 236.052054 -334.704811) (xy 236.036813 -334.756922)
			(xy 236.014338 -334.806347) (xy 235.985083 -334.852086) (xy 235.94964 -334.893216) (xy 235.908724 -334.928906)
			(xy 235.863162 -334.958435) (xy 235.813873 -334.981206) (xy 235.761854 -334.996761) (xy 235.708156 -335.004783)
			(xy 235.681012 -335.005426) (xy 235.671868 -335.005426) (xy 235.654596 -335.01203) (xy 235.5977 -335.062322)
			(xy 235.591118 -335.068597) (xy 235.582531 -335.084611) (xy 235.580936 -335.093564) (xy 235.575966 -335.126432)
			(xy 235.558634 -335.190606) (xy 235.533086 -335.251974) (xy 235.499758 -335.309489) (xy 235.459218 -335.36217)
			(xy 235.412158 -335.409118) (xy 235.359381 -335.449532) (xy 235.301787 -335.482723) (xy 235.240359 -335.508125)
			(xy 235.176143 -335.525304) (xy 235.110237 -335.533967) (xy 235.077 -335.534508) (xy 235.046269 -335.534044)
			(xy 234.985255 -335.526635) (xy 234.925579 -335.511927) (xy 234.868111 -335.490132) (xy 234.813689 -335.461569)
			(xy 234.763107 -335.426655) (xy 234.717102 -335.385898) (xy 234.676345 -335.339893) (xy 234.641431 -335.289311)
			(xy 234.612868 -335.234889) (xy 234.591073 -335.177421) (xy 234.576365 -335.117745) (xy 234.568956 -335.056731)
			(xy 234.568492 -335.026) (xy 234.568997 -334.995064) (xy 234.576504 -334.933648) (xy 234.591406 -334.873597)
			(xy 234.613483 -334.815798) (xy 234.64241 -334.761104) (xy 234.677758 -334.710323) (xy 234.719006 -334.664206)
			(xy 234.741974 -334.643476) (xy 234.750356 -334.63611) (xy 234.759246 -334.616044) (xy 234.75823 -334.516222)
			(xy 234.748832 -334.496664) (xy 234.740196 -334.489298) (xy 234.716136 -334.468576) (xy 234.672892 -334.422074)
			(xy 234.635778 -334.370548) (xy 234.605371 -334.314801) (xy 234.582144 -334.2557) (xy 234.566459 -334.194167)
			(xy 234.558561 -334.131159) (xy 234.558078 -334.099408) (xy 230.58628 -334.099408) (xy 230.58628 -335.626202)
			(xy 233.485944 -335.626202) (xy 233.48643 -335.598951) (xy 233.494186 -335.545003) (xy 233.509541 -335.492708)
			(xy 233.532183 -335.443131) (xy 233.561649 -335.397281) (xy 233.59734 -335.35609) (xy 233.638531 -335.320399)
			(xy 233.684381 -335.290933) (xy 233.733958 -335.268291) (xy 233.786253 -335.252936) (xy 233.840201 -335.24518)
			(xy 233.894703 -335.24518) (xy 233.948651 -335.252936) (xy 234.000946 -335.268291) (xy 234.050523 -335.290933)
			(xy 234.096373 -335.320399) (xy 234.137564 -335.35609) (xy 234.173255 -335.397281) (xy 234.202721 -335.443131)
			(xy 234.225363 -335.492708) (xy 234.240718 -335.545003) (xy 234.248474 -335.598951) (xy 234.24896 -335.626202)
			(xy 234.248781 -335.64209) (xy 234.24611 -335.673754) (xy 234.243626 -335.689448) (xy 234.242102 -335.698846)
			(xy 234.245912 -335.717388) (xy 234.29341 -335.790794) (xy 234.308904 -335.80197) (xy 234.318048 -335.804256)
			(xy 234.350165 -335.81337) (xy 234.411912 -335.838748) (xy 234.469809 -335.871986) (xy 234.52286 -335.912512)
			(xy 234.570153 -335.959631) (xy 234.610875 -336.012533) (xy 234.641365 -336.065195) (xy 236.020034 -336.065195)
			(xy 236.022643 -336.002172) (xy 236.033028 -335.939956) (xy 236.051029 -335.879503) (xy 236.076369 -335.82174)
			(xy 236.108659 -335.767555) (xy 236.147403 -335.71778) (xy 236.192007 -335.673179) (xy 236.241784 -335.634439)
			(xy 236.295972 -335.602152) (xy 236.353736 -335.576816) (xy 236.414191 -335.55882) (xy 236.476408 -335.54844)
			(xy 236.539431 -335.545834) (xy 236.602292 -335.551045) (xy 236.664026 -335.56399) (xy 236.723684 -335.584472)
			(xy 236.780351 -335.612176) (xy 236.833157 -335.646677) (xy 236.881289 -335.687444) (xy 236.924009 -335.733851)
			(xy 236.960661 -335.785187) (xy 236.990682 -335.840661) (xy 237.01361 -335.899423) (xy 237.029094 -335.960569)
			(xy 237.036896 -336.023162) (xy 237.037372 -336.0547) (xy 237.037372 -336.054954) (xy 237.036958 -336.084242)
			(xy 237.03021 -336.142427) (xy 237.02391 -336.171032) (xy 237.021992 -336.182458) (xy 237.026197 -336.200961)
			(xy 240.195094 -336.200961) (xy 240.195094 -336.137039) (xy 240.203105 -336.073621) (xy 240.219002 -336.011707)
			(xy 240.242534 -335.952274) (xy 240.273328 -335.896259) (xy 240.310901 -335.844544) (xy 240.354658 -335.797947)
			(xy 240.403911 -335.757202) (xy 240.457882 -335.722951) (xy 240.515721 -335.695734) (xy 240.576514 -335.675981)
			(xy 240.639304 -335.664003) (xy 240.7031 -335.65999) (xy 240.766896 -335.664003) (xy 240.829686 -335.675981)
			(xy 240.890479 -335.695734) (xy 240.948318 -335.722951) (xy 241.002289 -335.757202) (xy 241.051542 -335.797947)
			(xy 241.095299 -335.844544) (xy 241.132872 -335.896259) (xy 241.163666 -335.952274) (xy 241.187198 -336.011707)
			(xy 241.203095 -336.073621) (xy 241.211106 -336.137039) (xy 241.211608 -336.169) (xy 241.211106 -336.200961)
			(xy 241.203095 -336.264379) (xy 241.187198 -336.326293) (xy 241.163666 -336.385726) (xy 241.132872 -336.441741)
			(xy 241.095299 -336.493456) (xy 241.051542 -336.540053) (xy 241.002289 -336.580798) (xy 240.948318 -336.615049)
			(xy 240.890479 -336.642266) (xy 240.829686 -336.662019) (xy 240.766896 -336.673997) (xy 240.7031 -336.678011)
			(xy 240.639304 -336.673997) (xy 240.576514 -336.662019) (xy 240.515721 -336.642266) (xy 240.457882 -336.615049)
			(xy 240.403911 -336.580798) (xy 240.354658 -336.540053) (xy 240.310901 -336.493456) (xy 240.273328 -336.441741)
			(xy 240.242534 -336.385726) (xy 240.219002 -336.326293) (xy 240.203105 -336.264379) (xy 240.195094 -336.200961)
			(xy 237.026197 -336.200961) (xy 237.027118 -336.205015) (xy 237.033816 -336.214466) (xy 237.091474 -336.286094)
			(xy 237.112556 -336.296) (xy 237.124494 -336.295746) (xy 237.130844 -336.295746) (xy 237.15809 -336.296327)
			(xy 237.212026 -336.304088) (xy 237.264309 -336.319445) (xy 237.313875 -336.342086) (xy 237.359714 -336.37155)
			(xy 237.400894 -336.407237) (xy 237.436577 -336.448421) (xy 237.466035 -336.494264) (xy 237.488671 -336.543832)
			(xy 237.504022 -336.596117) (xy 237.511776 -336.650054) (xy 237.511776 -336.704546) (xy 237.504022 -336.758483)
			(xy 237.488671 -336.810768) (xy 237.466035 -336.860336) (xy 237.436577 -336.906179) (xy 237.400894 -336.947363)
			(xy 237.359714 -336.98305) (xy 237.313875 -337.012514) (xy 237.264309 -337.035155) (xy 237.212026 -337.050512)
			(xy 237.15809 -337.058273) (xy 237.130844 -337.058762) (xy 237.109254 -337.058254) (xy 237.095538 -337.057492)
			(xy 237.071408 -337.06943) (xy 237.007908 -337.165442) (xy 237.006384 -337.19262) (xy 237.01248 -337.204812)
			(xy 237.025082 -337.231179) (xy 237.044833 -337.286184) (xy 237.05816 -337.343088) (xy 237.058261 -337.343961)
			(xy 240.195094 -337.343961) (xy 240.195094 -337.280039) (xy 240.203105 -337.216621) (xy 240.219002 -337.154707)
			(xy 240.242534 -337.095274) (xy 240.273328 -337.039259) (xy 240.310901 -336.987544) (xy 240.354658 -336.940947)
			(xy 240.403911 -336.900202) (xy 240.457882 -336.865951) (xy 240.515721 -336.838734) (xy 240.576514 -336.818981)
			(xy 240.639304 -336.807003) (xy 240.7031 -336.80299) (xy 240.766896 -336.807003) (xy 240.829686 -336.818981)
			(xy 240.890479 -336.838734) (xy 240.948318 -336.865951) (xy 241.002289 -336.900202) (xy 241.051542 -336.940947)
			(xy 241.095299 -336.987544) (xy 241.132872 -337.039259) (xy 241.163666 -337.095274) (xy 241.187198 -337.154707)
			(xy 241.203095 -337.216621) (xy 241.211106 -337.280039) (xy 241.211608 -337.312) (xy 241.211106 -337.343961)
			(xy 241.203095 -337.407379) (xy 241.187198 -337.469293) (xy 241.163666 -337.528726) (xy 241.132872 -337.584741)
			(xy 241.095299 -337.636456) (xy 241.051542 -337.683053) (xy 241.002289 -337.723798) (xy 240.948318 -337.758049)
			(xy 240.890479 -337.785266) (xy 240.829686 -337.805019) (xy 240.766896 -337.816997) (xy 240.7031 -337.821011)
			(xy 240.639304 -337.816997) (xy 240.576514 -337.805019) (xy 240.515721 -337.785266) (xy 240.457882 -337.758049)
			(xy 240.403911 -337.723798) (xy 240.354658 -337.683053) (xy 240.310901 -337.636456) (xy 240.273328 -337.584741)
			(xy 240.242534 -337.528726) (xy 240.219002 -337.469293) (xy 240.203105 -337.407379) (xy 240.195094 -337.343961)
			(xy 237.058261 -337.343961) (xy 237.064886 -337.401143) (xy 237.065312 -337.430364) (xy 237.065312 -337.430618)
			(xy 237.064813 -337.462158) (xy 237.057009 -337.524753) (xy 237.041521 -337.585901) (xy 237.01859 -337.644665)
			(xy 236.988565 -337.700141) (xy 236.95191 -337.751477) (xy 236.909186 -337.797884) (xy 236.861049 -337.838651)
			(xy 236.80824 -337.873151) (xy 236.75157 -337.900853) (xy 236.691907 -337.921333) (xy 236.63017 -337.934277)
			(xy 236.567306 -337.939484) (xy 236.50428 -337.936876) (xy 236.442061 -337.926492) (xy 236.381605 -337.908491)
			(xy 236.323839 -337.883151) (xy 236.269651 -337.85086) (xy 236.219873 -337.812115) (xy 236.17527 -337.76751)
			(xy 236.136527 -337.717731) (xy 236.104239 -337.663541) (xy 236.078901 -337.605775) (xy 236.060903 -337.545317)
			(xy 236.050522 -337.483098) (xy 236.047916 -337.420072) (xy 236.053126 -337.357208) (xy 236.066072 -337.295471)
			(xy 236.086555 -337.23581) (xy 236.11426 -337.17914) (xy 236.148762 -337.126333) (xy 236.189531 -337.078198)
			(xy 236.235941 -337.035476) (xy 236.287278 -336.998823) (xy 236.342755 -336.968801) (xy 236.40152 -336.945872)
			(xy 236.462669 -336.930387) (xy 236.525264 -336.922585) (xy 236.556804 -336.92211) (xy 236.581217 -336.922418)
			(xy 236.629815 -336.927122) (xy 236.653832 -336.931508) (xy 236.667294 -336.934048) (xy 236.692694 -336.925412)
			(xy 236.76864 -336.838544) (xy 236.77372 -336.812128) (xy 236.769402 -336.799174) (xy 236.760059 -336.769562)
			(xy 236.74997 -336.708298) (xy 236.749336 -336.677254) (xy 236.749844 -336.658204) (xy 236.749843 -336.646549)
			(xy 236.740727 -336.625125) (xy 236.732318 -336.617056) (xy 236.671612 -336.564732) (xy 236.662435 -336.557563)
			(xy 236.639951 -336.551601) (xy 236.628432 -336.553302) (xy 236.603801 -336.557937) (xy 236.553925 -336.562896)
			(xy 236.528864 -336.563208) (xy 236.497326 -336.562694) (xy 236.434734 -336.554888) (xy 236.373588 -336.539399)
			(xy 236.314828 -336.516467) (xy 236.259356 -336.486442) (xy 236.208023 -336.449786) (xy 236.161619 -336.407063)
			(xy 236.120855 -336.358928) (xy 236.086359 -336.30612) (xy 236.058659 -336.249451) (xy 236.038181 -336.189791)
			(xy 236.025239 -336.128056) (xy 236.020034 -336.065195) (xy 234.641365 -336.065195) (xy 234.644325 -336.070307)
			(xy 234.669929 -336.131961) (xy 234.687248 -336.196435) (xy 234.695982 -336.26262) (xy 234.696508 -336.296)
			(xy 234.695993 -336.327286) (xy 234.688322 -336.389387) (xy 234.673084 -336.450076) (xy 234.65051 -336.508435)
			(xy 234.620942 -336.56358) (xy 234.584826 -336.614678) (xy 234.542709 -336.660954) (xy 234.495229 -336.70171)
			(xy 234.469432 -336.719418) (xy 234.45929 -336.726951) (xy 234.447425 -336.749217) (xy 234.446826 -336.761836)
			(xy 234.446826 -336.846164) (xy 234.447487 -336.858767) (xy 234.459333 -336.881014) (xy 234.469432 -336.888582)
			(xy 234.49523 -336.90629) (xy 234.54271 -336.947047) (xy 234.584828 -336.993324) (xy 234.620947 -337.044421)
			(xy 234.65052 -337.099566) (xy 234.673101 -337.157924) (xy 234.688347 -337.218612) (xy 234.696028 -337.280713)
			(xy 234.696508 -337.312) (xy 234.696006 -337.343961) (xy 234.687995 -337.407379) (xy 234.672098 -337.469293)
			(xy 234.648566 -337.528726) (xy 234.617772 -337.584741) (xy 234.580199 -337.636456) (xy 234.536442 -337.683053)
			(xy 234.487189 -337.723798) (xy 234.433218 -337.758049) (xy 234.375379 -337.785266) (xy 234.314586 -337.805019)
			(xy 234.251796 -337.816997) (xy 234.188 -337.821011) (xy 234.124204 -337.816997) (xy 234.061414 -337.805019)
			(xy 234.000621 -337.785266) (xy 233.942782 -337.758049) (xy 233.888811 -337.723798) (xy 233.839558 -337.683053)
			(xy 233.795801 -337.636456) (xy 233.758228 -337.584741) (xy 233.727434 -337.528726) (xy 233.703902 -337.469293)
			(xy 233.688005 -337.407379) (xy 233.679994 -337.343961) (xy 233.679492 -337.312) (xy 233.680007 -337.280714)
			(xy 233.687678 -337.218613) (xy 233.702916 -337.157924) (xy 233.72549 -337.099565) (xy 233.755058 -337.04442)
			(xy 233.791174 -336.993322) (xy 233.833291 -336.947046) (xy 233.880771 -336.90629) (xy 233.906568 -336.888582)
			(xy 233.91671 -336.881049) (xy 233.928575 -336.858783) (xy 233.929174 -336.846164) (xy 233.929174 -336.761836)
			(xy 233.928513 -336.749233) (xy 233.916667 -336.726986) (xy 233.906568 -336.719418) (xy 233.88077 -336.70171)
			(xy 233.83329 -336.660953) (xy 233.791172 -336.614676) (xy 233.755053 -336.563579) (xy 233.72548 -336.508434)
			(xy 233.702899 -336.450076) (xy 233.687653 -336.389388) (xy 233.679972 -336.327287) (xy 233.679492 -336.296)
			(xy 233.680089 -336.260403) (xy 233.690046 -336.189907) (xy 233.709723 -336.121485) (xy 233.723688 -336.088736)
			(xy 233.723688 -336.088482) (xy 233.727059 -336.07978) (xy 233.727963 -336.061153) (xy 233.725466 -336.05216)
			(xy 233.701082 -335.978246) (xy 233.688636 -335.96326) (xy 233.680508 -335.958942) (xy 233.655593 -335.944338)
			(xy 233.610106 -335.908755) (xy 233.570496 -335.866728) (xy 233.537666 -335.819216) (xy 233.512365 -335.767302)
			(xy 233.495171 -335.71217) (xy 233.486474 -335.655078) (xy 233.485944 -335.626202) (xy 230.58628 -335.626202)
			(xy 230.58628 -342.670749) (xy 233.237414 -342.670749) (xy 233.237416 -342.616235) (xy 233.245175 -342.562277)
			(xy 233.260535 -342.509972) (xy 233.283183 -342.460385) (xy 233.312657 -342.414527) (xy 233.348358 -342.37333)
			(xy 233.389559 -342.337633) (xy 233.43542 -342.308164) (xy 233.485009 -342.285521) (xy 233.537316 -342.270167)
			(xy 233.591275 -342.262413) (xy 233.618532 -342.261952) (xy 233.639106 -342.26246) (xy 233.652822 -342.263222)
			(xy 233.676698 -342.25103) (xy 233.73969 -342.154256) (xy 233.741214 -342.127078) (xy 233.734864 -342.114886)
			(xy 233.721667 -342.088017) (xy 233.700971 -342.031844) (xy 233.686999 -341.973633) (xy 233.679943 -341.914186)
			(xy 233.679492 -341.884254) (xy 233.679492 -341.884) (xy 233.680007 -341.852714) (xy 233.687678 -341.790613)
			(xy 233.702916 -341.729924) (xy 233.72549 -341.671565) (xy 233.755058 -341.61642) (xy 233.791174 -341.565322)
			(xy 233.833291 -341.519046) (xy 233.880771 -341.47829) (xy 233.906568 -341.460582) (xy 233.91671 -341.453049)
			(xy 233.928575 -341.430783) (xy 233.929174 -341.418164) (xy 233.929174 -341.333836) (xy 233.928513 -341.321233)
			(xy 233.916667 -341.298986) (xy 233.906568 -341.291418) (xy 233.88077 -341.27371) (xy 233.83329 -341.232953)
			(xy 233.791172 -341.186676) (xy 233.755053 -341.135579) (xy 233.72548 -341.080434) (xy 233.702899 -341.022076)
			(xy 233.687653 -340.961388) (xy 233.679972 -340.899287) (xy 233.679492 -340.868) (xy 233.679956 -340.837269)
			(xy 233.687365 -340.776255) (xy 233.702073 -340.716579) (xy 233.723868 -340.659111) (xy 233.752431 -340.604689)
			(xy 233.787345 -340.554107) (xy 233.828102 -340.508102) (xy 233.874107 -340.467345) (xy 233.924689 -340.432431)
			(xy 233.979111 -340.403868) (xy 234.036579 -340.382073) (xy 234.096255 -340.367365) (xy 234.157269 -340.359956)
			(xy 234.188 -340.359492) (xy 234.188254 -340.359492) (xy 234.198273 -340.359043) (xy 234.216791 -340.351386)
			(xy 234.230965 -340.337223) (xy 234.238635 -340.318711) (xy 234.239054 -340.308692) (xy 234.239054 -340.304628)
			(xy 234.238292 -340.30031) (xy 234.23591 -340.284927) (xy 234.233366 -340.2539) (xy 234.233212 -340.238334)
			(xy 234.233212 -340.23808) (xy 234.233708 -340.210224) (xy 234.241835 -340.155107) (xy 234.257884 -340.101755)
			(xy 234.281514 -340.051302) (xy 234.312224 -340.004817) (xy 234.349363 -339.963288) (xy 234.392141 -339.927595)
			(xy 234.439651 -339.898497) (xy 234.490886 -339.876611) (xy 234.517692 -339.869018) (xy 234.527598 -339.866478)
			(xy 234.544108 -339.854032) (xy 234.589828 -339.772244) (xy 234.592368 -339.751924) (xy 234.58932 -339.742018)
			(xy 234.579577 -339.706814) (xy 234.569124 -339.634522) (xy 234.568492 -339.598) (xy 234.569007 -339.566714)
			(xy 234.576678 -339.504613) (xy 234.591916 -339.443924) (xy 234.61449 -339.385565) (xy 234.644058 -339.33042)
			(xy 234.680174 -339.279322) (xy 234.722291 -339.233046) (xy 234.769771 -339.19229) (xy 234.795568 -339.174582)
			(xy 234.80571 -339.167049) (xy 234.817575 -339.144783) (xy 234.818174 -339.132164) (xy 234.818174 -339.047836)
			(xy 234.817513 -339.035233) (xy 234.805667 -339.012986) (xy 234.795568 -339.005418) (xy 234.76977 -338.98771)
			(xy 234.72229 -338.946953) (xy 234.680172 -338.900676) (xy 234.644053 -338.849579) (xy 234.61448 -338.794434)
			(xy 234.591899 -338.736076) (xy 234.576653 -338.675388) (xy 234.568972 -338.613287) (xy 234.568492 -338.582)
			(xy 234.568994 -338.550039) (xy 234.577005 -338.486621) (xy 234.592902 -338.424707) (xy 234.616434 -338.365274)
			(xy 234.647228 -338.309259) (xy 234.684801 -338.257544) (xy 234.728558 -338.210947) (xy 234.777811 -338.170202)
			(xy 234.831782 -338.135951) (xy 234.889621 -338.108734) (xy 234.950414 -338.088981) (xy 235.013204 -338.077003)
			(xy 235.077 -338.07299) (xy 235.140796 -338.077003) (xy 235.203586 -338.088981) (xy 235.264379 -338.108734)
			(xy 235.322218 -338.135951) (xy 235.376189 -338.170202) (xy 235.425442 -338.210947) (xy 235.469199 -338.257544)
			(xy 235.506772 -338.309259) (xy 235.537566 -338.365274) (xy 235.561098 -338.424707) (xy 235.576995 -338.486621)
			(xy 235.577038 -338.486961) (xy 240.195094 -338.486961) (xy 240.195094 -338.423039) (xy 240.203105 -338.359621)
			(xy 240.219002 -338.297707) (xy 240.242534 -338.238274) (xy 240.273328 -338.182259) (xy 240.310901 -338.130544)
			(xy 240.354658 -338.083947) (xy 240.403911 -338.043202) (xy 240.457882 -338.008951) (xy 240.515721 -337.981734)
			(xy 240.576514 -337.961981) (xy 240.639304 -337.950003) (xy 240.7031 -337.94599) (xy 240.766896 -337.950003)
			(xy 240.829686 -337.961981) (xy 240.890479 -337.981734) (xy 240.948318 -338.008951) (xy 241.002289 -338.043202)
			(xy 241.051542 -338.083947) (xy 241.095299 -338.130544) (xy 241.132872 -338.182259) (xy 241.163666 -338.238274)
			(xy 241.187198 -338.297707) (xy 241.203095 -338.359621) (xy 241.211106 -338.423039) (xy 241.211608 -338.455)
			(xy 241.211106 -338.486961) (xy 241.203095 -338.550379) (xy 241.187198 -338.612293) (xy 241.163666 -338.671726)
			(xy 241.132872 -338.727741) (xy 241.095299 -338.779456) (xy 241.051542 -338.826053) (xy 241.002289 -338.866798)
			(xy 240.948318 -338.901049) (xy 240.890479 -338.928266) (xy 240.829686 -338.948019) (xy 240.766896 -338.959997)
			(xy 240.7031 -338.964011) (xy 240.639304 -338.959997) (xy 240.576514 -338.948019) (xy 240.515721 -338.928266)
			(xy 240.457882 -338.901049) (xy 240.403911 -338.866798) (xy 240.354658 -338.826053) (xy 240.310901 -338.779456)
			(xy 240.273328 -338.727741) (xy 240.242534 -338.671726) (xy 240.219002 -338.612293) (xy 240.203105 -338.550379)
			(xy 240.195094 -338.486961) (xy 235.577038 -338.486961) (xy 235.585006 -338.550039) (xy 235.585508 -338.582)
			(xy 235.584993 -338.613286) (xy 235.577322 -338.675387) (xy 235.562084 -338.736076) (xy 235.53951 -338.794435)
			(xy 235.509942 -338.84958) (xy 235.473826 -338.900678) (xy 235.431709 -338.946954) (xy 235.384229 -338.98771)
			(xy 235.358432 -339.005418) (xy 235.34829 -339.012951) (xy 235.336425 -339.035217) (xy 235.335826 -339.047836)
			(xy 235.335826 -339.132164) (xy 235.336487 -339.144767) (xy 235.348333 -339.167014) (xy 235.358432 -339.174582)
			(xy 235.38423 -339.19229) (xy 235.43171 -339.233047) (xy 235.473828 -339.279324) (xy 235.509947 -339.330421)
			(xy 235.53952 -339.385566) (xy 235.562101 -339.443924) (xy 235.577347 -339.504612) (xy 235.585028 -339.566713)
			(xy 235.585508 -339.598) (xy 235.58501 -339.629961) (xy 240.195094 -339.629961) (xy 240.195094 -339.566039)
			(xy 240.203105 -339.502621) (xy 240.219002 -339.440707) (xy 240.242534 -339.381274) (xy 240.273328 -339.325259)
			(xy 240.310901 -339.273544) (xy 240.354658 -339.226947) (xy 240.403911 -339.186202) (xy 240.457882 -339.151951)
			(xy 240.515721 -339.124734) (xy 240.576514 -339.104981) (xy 240.639304 -339.093003) (xy 240.7031 -339.08899)
			(xy 240.719156 -339.09) (xy 256.539492 -339.09) (xy 256.540029 -339.060845) (xy 256.54893 -339.003218)
			(xy 256.566493 -338.947616) (xy 256.59231 -338.895332) (xy 256.625779 -338.847584) (xy 256.666123 -338.805484)
			(xy 256.712402 -338.77001) (xy 256.763538 -338.741989) (xy 256.818342 -338.722073) (xy 256.846832 -338.715858)
			(xy 256.847086 -338.715858) (xy 256.856591 -338.713432) (xy 256.872925 -338.702603) (xy 256.878836 -338.694776)
			(xy 256.918968 -338.63661) (xy 256.924097 -338.628359) (xy 256.92842 -338.609435) (xy 256.92735 -338.59978)
			(xy 256.92735 -338.599526) (xy 256.924165 -338.578972) (xy 256.920729 -338.537519) (xy 256.920492 -338.516722)
			(xy 256.920492 -338.51596) (xy 256.920965 -338.483111) (xy 256.929424 -338.417961) (xy 256.94621 -338.354443)
			(xy 256.971041 -338.293619) (xy 257.003505 -338.236503) (xy 257.043059 -338.184047) (xy 257.089043 -338.137126)
			(xy 257.114548 -338.116418) (xy 257.121912 -338.11016) (xy 257.131602 -338.093455) (xy 257.134409 -338.074347)
			(xy 257.132582 -338.064856) (xy 257.107944 -337.960462) (xy 257.086608 -337.939888) (xy 257.07213 -337.937094)
			(xy 257.041279 -337.930185) (xy 256.981433 -337.909804) (xy 256.924574 -337.882163) (xy 256.871578 -337.84769)
			(xy 256.823263 -337.806916) (xy 256.780372 -337.760469) (xy 256.743567 -337.709065) (xy 256.713416 -337.653496)
			(xy 256.690383 -337.59462) (xy 256.674824 -337.533343) (xy 256.666977 -337.470611) (xy 256.666492 -337.439)
			(xy 256.666943 -337.407234) (xy 256.674879 -337.3442) (xy 256.690604 -337.282644) (xy 256.713873 -337.223526)
			(xy 256.744322 -337.167767) (xy 256.781479 -337.116233) (xy 256.824764 -337.069727) (xy 256.873503 -337.028975)
			(xy 256.926938 -336.994609) (xy 256.984237 -336.967165) (xy 257.014218 -336.956654) (xy 257.014472 -336.956654)
			(xy 257.024107 -336.952838) (xy 257.039452 -336.938945) (xy 257.04419 -336.92973) (xy 257.079496 -336.852514)
			(xy 257.080004 -336.831432) (xy 257.07594 -336.82178) (xy 257.066915 -336.798723) (xy 257.05424 -336.750859)
			(xy 257.047867 -336.701757) (xy 257.047492 -336.677) (xy 257.047886 -336.652244) (xy 257.054261 -336.603144)
			(xy 257.066929 -336.555281) (xy 257.07594 -336.53222) (xy 257.080004 -336.522568) (xy 257.079496 -336.501486)
			(xy 257.039618 -336.414618) (xy 257.024378 -336.400902) (xy 257.014472 -336.397346) (xy 257.013964 -336.397346)
			(xy 256.984 -336.386816) (xy 256.92673 -336.359358) (xy 256.873326 -336.324981) (xy 256.824618 -336.284221)
			(xy 256.781365 -336.237713) (xy 256.744241 -336.18618) (xy 256.713824 -336.130425) (xy 256.690586 -336.071316)
			(xy 256.67489 -336.009774) (xy 256.666981 -335.946756) (xy 256.666492 -335.915) (xy 256.666974 -335.882215)
			(xy 256.675407 -335.817191) (xy 256.692132 -335.753791) (xy 256.716872 -335.693068) (xy 256.749216 -335.636032)
			(xy 256.788626 -335.583628) (xy 256.834449 -335.536729) (xy 256.885923 -335.496111) (xy 256.942192 -335.462451)
			(xy 256.972054 -335.44891) (xy 256.972308 -335.44891) (xy 256.982272 -335.443852) (xy 256.996881 -335.426971)
			(xy 257.000502 -335.416398) (xy 257.022346 -335.341214) (xy 257.024899 -335.330275) (xy 257.021344 -335.308126)
			(xy 257.015488 -335.298542) (xy 256.998848 -335.27322) (xy 256.971024 -335.219394) (xy 256.949805 -335.162638)
			(xy 256.935493 -335.10376) (xy 256.928292 -335.043596) (xy 256.927858 -335.0133) (xy 256.928332 -334.983173)
			(xy 256.935455 -334.923342) (xy 256.949602 -334.864773) (xy 256.970574 -334.808287) (xy 256.998077 -334.754677)
			(xy 257.031725 -334.704694) (xy 257.051048 -334.681576) (xy 257.056441 -334.674746) (xy 257.062674 -334.65851)
			(xy 257.06324 -334.649826) (xy 257.064002 -334.620108) (xy 257.063862 -334.611414) (xy 257.058401 -334.594917)
			(xy 257.053334 -334.58785) (xy 257.033283 -334.561018) (xy 256.999618 -334.50311) (xy 256.973855 -334.441279)
			(xy 256.956441 -334.376599) (xy 256.947678 -334.310192) (xy 256.947162 -334.2767) (xy 256.947619 -334.244387)
			(xy 256.955818 -334.180284) (xy 256.972072 -334.117735) (xy 256.996119 -334.05775) (xy 257.027571 -334.001295)
			(xy 257.065922 -333.949278) (xy 257.110553 -333.902539) (xy 257.160746 -333.861831) (xy 257.187954 -333.844392)
			(xy 257.198622 -333.837788) (xy 257.211322 -333.816452) (xy 257.21691 -333.707994) (xy 257.206242 -333.685134)
			(xy 257.196336 -333.677514) (xy 257.173591 -333.659332) (xy 257.133393 -333.617205) (xy 257.100056 -333.569463)
			(xy 257.074353 -333.517214) (xy 257.056879 -333.461669) (xy 257.04804 -333.404114) (xy 257.047492 -333.375)
			(xy 257.047978 -333.347749) (xy 257.055734 -333.293801) (xy 257.071089 -333.241506) (xy 257.093731 -333.191929)
			(xy 257.123197 -333.146079) (xy 257.158888 -333.104888) (xy 257.200079 -333.069197) (xy 257.245929 -333.039731)
			(xy 257.295506 -333.017089) (xy 257.347801 -333.001734) (xy 257.401749 -332.993978) (xy 257.456251 -332.993978)
			(xy 257.510199 -333.001734) (xy 257.562494 -333.017089) (xy 257.612071 -333.039731) (xy 257.657921 -333.069197)
			(xy 257.699112 -333.104888) (xy 257.734803 -333.146079) (xy 257.764269 -333.191929) (xy 257.786911 -333.241506)
			(xy 257.802266 -333.293801) (xy 257.810022 -333.347749) (xy 257.810508 -333.375) (xy 257.810009 -333.402224)
			(xy 257.80225 -333.456116) (xy 257.786903 -333.508357) (xy 257.764281 -333.557883) (xy 257.734844 -333.603688)
			(xy 257.699191 -333.644839) (xy 257.678936 -333.663036) (xy 257.669927 -333.671549) (xy 257.66089 -333.694605)
			(xy 257.661664 -333.706978) (xy 257.672332 -333.802736) (xy 257.686048 -333.82331) (xy 257.697224 -333.829406)
			(xy 257.723757 -333.844238) (xy 257.773435 -333.879268) (xy 257.818579 -333.919974) (xy 257.858545 -333.965775)
			(xy 257.892762 -334.016016) (xy 257.920741 -334.069981) (xy 257.942083 -334.126898) (xy 257.956482 -334.185954)
			(xy 257.963734 -334.246307) (xy 257.964178 -334.2767) (xy 257.963719 -334.306827) (xy 257.956595 -334.366659)
			(xy 257.942446 -334.425229) (xy 257.921472 -334.481715) (xy 257.893965 -334.535325) (xy 257.860313 -334.585307)
			(xy 257.840988 -334.608424) (xy 257.835587 -334.615249) (xy 257.82936 -334.631489) (xy 257.828796 -334.640174)
			(xy 257.828034 -334.669892) (xy 257.828187 -334.678585) (xy 257.83364 -334.695081) (xy 257.838702 -334.70215)
			(xy 257.858758 -334.728978) (xy 257.892421 -334.786888) (xy 257.918183 -334.84872) (xy 257.935596 -334.9134)
			(xy 257.944358 -334.979808) (xy 257.944874 -335.0133) (xy 257.944352 -335.046083) (xy 257.935921 -335.111104)
			(xy 257.919198 -335.174501) (xy 257.894462 -335.235222) (xy 257.862123 -335.292257) (xy 257.822718 -335.344661)
			(xy 257.776901 -335.391562) (xy 257.725434 -335.432182) (xy 257.669171 -335.465846) (xy 257.639312 -335.47939)
			(xy 257.639058 -335.47939) (xy 257.629107 -335.484469) (xy 257.614489 -335.501334) (xy 257.610864 -335.511902)
			(xy 257.58902 -335.587086) (xy 257.586472 -335.598025) (xy 257.590025 -335.620173) (xy 257.595878 -335.629758)
			(xy 257.612514 -335.655082) (xy 257.64034 -335.708908) (xy 257.66156 -335.765663) (xy 257.675872 -335.824541)
			(xy 257.683074 -335.884704) (xy 257.683508 -335.915) (xy 257.683077 -335.945791) (xy 257.675632 -336.00692)
			(xy 257.660851 -336.066701) (xy 257.63895 -336.124256) (xy 257.610251 -336.178741) (xy 257.593084 -336.204306)
			(xy 257.59283 -336.20456) (xy 257.587383 -336.21338) (xy 257.583451 -336.233713) (xy 257.58521 -336.24393)
			(xy 257.603244 -336.326988) (xy 257.615436 -336.344006) (xy 257.62458 -336.34934) (xy 257.648487 -336.364218)
			(xy 257.692048 -336.399896) (xy 257.729896 -336.441586) (xy 257.761209 -336.488383) (xy 257.785309 -336.539272)
			(xy 257.801672 -336.59315) (xy 257.809943 -336.648846) (xy 257.809943 -336.705154) (xy 257.801672 -336.76085)
			(xy 257.785309 -336.814728) (xy 257.761209 -336.865617) (xy 257.729896 -336.912414) (xy 257.692048 -336.954104)
			(xy 257.648487 -336.989782) (xy 257.62458 -337.00466) (xy 257.615436 -337.009994) (xy 257.603244 -337.027012)
			(xy 257.58521 -337.11007) (xy 257.583497 -337.120282) (xy 257.587443 -337.140595) (xy 257.59283 -337.14944)
			(xy 257.593084 -337.14944) (xy 257.593084 -337.149948) (xy 257.610239 -337.17549) (xy 257.638925 -337.229925)
			(xy 257.660819 -337.287428) (xy 257.6756 -337.347157) (xy 257.683051 -337.408235) (xy 257.683508 -337.439)
			(xy 257.683006 -337.471848) (xy 257.674552 -337.536997) (xy 257.657772 -337.600514) (xy 257.632945 -337.661338)
			(xy 257.600486 -337.718454) (xy 257.560936 -337.770911) (xy 257.514955 -337.817834) (xy 257.489452 -337.838542)
			(xy 257.482113 -337.844825) (xy 257.472418 -337.861518) (xy 257.469599 -337.880615) (xy 257.471418 -337.890104)
			(xy 257.496056 -337.994498) (xy 257.517392 -338.015072) (xy 257.53187 -338.017866) (xy 257.562735 -338.024719)
			(xy 257.622584 -338.045103) (xy 257.679446 -338.072748) (xy 257.732444 -338.107226) (xy 257.78076 -338.148006)
			(xy 257.823651 -338.194459) (xy 257.860454 -338.245869) (xy 257.890603 -338.301444) (xy 257.913632 -338.360327)
			(xy 257.929186 -338.421609) (xy 257.937026 -338.484347) (xy 257.937508 -338.51596) (xy 257.937007 -338.54668)
			(xy 257.929608 -338.607674) (xy 257.914913 -338.667331) (xy 257.893136 -338.724783) (xy 257.864594 -338.779192)
			(xy 257.829704 -338.829765) (xy 257.788974 -338.875766) (xy 257.742997 -338.916522) (xy 257.692444 -338.951442)
			(xy 257.638052 -338.980015) (xy 257.580612 -339.001825) (xy 257.520963 -339.016555) (xy 257.459974 -339.023989)
			(xy 257.429254 -339.024468) (xy 257.429 -339.024468) (xy 257.41717 -339.02438) (xy 257.393539 -339.023238)
			(xy 257.381756 -339.022182) (xy 257.371085 -339.021765) (xy 257.350875 -339.028591) (xy 257.34264 -339.03539)
			(xy 257.302 -339.072474) (xy 257.302508 -339.085174) (xy 257.343402 -339.120226) (xy 257.351465 -339.126583)
			(xy 257.370991 -339.132873) (xy 257.381248 -339.132418) (xy 257.393158 -339.131358) (xy 257.417044 -339.130215)
			(xy 257.429 -339.130132) (xy 257.460541 -339.130568) (xy 257.523137 -339.13837) (xy 257.584288 -339.153855)
			(xy 257.643054 -339.176785) (xy 257.698532 -339.206808) (xy 257.749871 -339.243463) (xy 257.796282 -339.286186)
			(xy 257.837052 -339.334321) (xy 257.871555 -339.38713) (xy 257.899261 -339.443801) (xy 257.919744 -339.503464)
			(xy 257.932691 -339.565202) (xy 257.937902 -339.628067) (xy 257.935296 -339.691094) (xy 257.924915 -339.753315)
			(xy 257.906918 -339.813774) (xy 257.881581 -339.871543) (xy 257.849292 -339.925734) (xy 257.810549 -339.975516)
			(xy 257.765946 -340.020122) (xy 257.716167 -340.05887) (xy 257.661979 -340.091162) (xy 257.604212 -340.116504)
			(xy 257.543754 -340.134506) (xy 257.481534 -340.144892) (xy 257.418507 -340.147502) (xy 257.355641 -340.142297)
			(xy 257.293902 -340.129355) (xy 257.234238 -340.108876) (xy 257.177565 -340.081174) (xy 257.124753 -340.046676)
			(xy 257.076615 -340.005909) (xy 257.033888 -339.959502) (xy 256.997229 -339.908166) (xy 256.967202 -339.85269)
			(xy 256.944268 -339.793926) (xy 256.928778 -339.732776) (xy 256.92097 -339.67018) (xy 256.920492 -339.63864)
			(xy 256.920582 -339.622851) (xy 256.922488 -339.591332) (xy 256.924302 -339.575648) (xy 256.925572 -339.56625)
			(xy 256.921 -339.547708) (xy 256.875026 -339.483954) (xy 256.86925 -339.476447) (xy 256.853462 -339.466007)
			(xy 256.844292 -339.463634) (xy 256.844038 -339.463634) (xy 256.815752 -339.457211) (xy 256.761366 -339.437058)
			(xy 256.710659 -339.408903) (xy 256.664799 -339.373395) (xy 256.624844 -339.331353) (xy 256.591715 -339.283746)
			(xy 256.566175 -339.231671) (xy 256.548815 -339.176331) (xy 256.540033 -339.119) (xy 256.539492 -339.09)
			(xy 240.719156 -339.09) (xy 240.766896 -339.093003) (xy 240.829686 -339.104981) (xy 240.890479 -339.124734)
			(xy 240.948318 -339.151951) (xy 241.002289 -339.186202) (xy 241.051542 -339.226947) (xy 241.095299 -339.273544)
			(xy 241.132872 -339.325259) (xy 241.163666 -339.381274) (xy 241.187198 -339.440707) (xy 241.203095 -339.502621)
			(xy 241.211106 -339.566039) (xy 241.211608 -339.598) (xy 241.211106 -339.629961) (xy 241.203095 -339.693379)
			(xy 241.187198 -339.755293) (xy 241.163666 -339.814726) (xy 241.132872 -339.870741) (xy 241.095299 -339.922456)
			(xy 241.051542 -339.969053) (xy 241.002289 -340.009798) (xy 240.948318 -340.044049) (xy 240.890479 -340.071266)
			(xy 240.829686 -340.091019) (xy 240.766896 -340.102997) (xy 240.7031 -340.107011) (xy 240.639304 -340.102997)
			(xy 240.576514 -340.091019) (xy 240.515721 -340.071266) (xy 240.457882 -340.044049) (xy 240.403911 -340.009798)
			(xy 240.354658 -339.969053) (xy 240.310901 -339.922456) (xy 240.273328 -339.870741) (xy 240.242534 -339.814726)
			(xy 240.219002 -339.755293) (xy 240.203105 -339.693379) (xy 240.195094 -339.629961) (xy 235.58501 -339.629961)
			(xy 235.585 -339.630606) (xy 235.576663 -339.695283) (xy 235.560127 -339.758363) (xy 235.535661 -339.818811)
			(xy 235.503668 -339.875636) (xy 235.464674 -339.927904) (xy 235.419317 -339.974758) (xy 235.368342 -340.015429)
			(xy 235.312586 -340.04925) (xy 235.252964 -340.075665) (xy 235.190454 -340.094242) (xy 235.126082 -340.104674)
			(xy 235.09351 -340.106254) (xy 235.083096 -340.106508) (xy 235.064808 -340.115144) (xy 235.008674 -340.176866)
			(xy 235.002181 -340.184679) (xy 234.995359 -340.203793) (xy 234.995466 -340.21395) (xy 234.995466 -340.214204)
			(xy 234.996228 -340.23808) (xy 234.995817 -340.26431) (xy 234.988619 -340.316273) (xy 234.974371 -340.366761)
			(xy 234.95334 -340.41482) (xy 234.925924 -340.459545) (xy 234.892638 -340.500093) (xy 234.854112 -340.535698)
			(xy 234.811072 -340.56569) (xy 234.764328 -340.589502) (xy 234.739688 -340.598506) (xy 234.73029 -340.601808)
			(xy 234.715558 -340.614508) (xy 234.678982 -340.686136) (xy 234.675001 -340.69485) (xy 234.673178 -340.713907)
			(xy 234.675426 -340.72322) (xy 234.675426 -340.723728) (xy 234.685251 -340.758985) (xy 234.687294 -340.772961)
			(xy 240.195094 -340.772961) (xy 240.195094 -340.709039) (xy 240.203105 -340.645621) (xy 240.219002 -340.583707)
			(xy 240.242534 -340.524274) (xy 240.273328 -340.468259) (xy 240.310901 -340.416544) (xy 240.354658 -340.369947)
			(xy 240.403911 -340.329202) (xy 240.457882 -340.294951) (xy 240.515721 -340.267734) (xy 240.576514 -340.247981)
			(xy 240.639304 -340.236003) (xy 240.7031 -340.23199) (xy 240.766896 -340.236003) (xy 240.829686 -340.247981)
			(xy 240.890479 -340.267734) (xy 240.948318 -340.294951) (xy 241.002289 -340.329202) (xy 241.051542 -340.369947)
			(xy 241.095299 -340.416544) (xy 241.098692 -340.421214) (xy 245.362982 -340.421214) (xy 245.367053 -340.365592)
			(xy 245.379179 -340.311155) (xy 245.399102 -340.259064) (xy 245.426398 -340.210429) (xy 245.460484 -340.166286)
			(xy 245.500633 -340.127577) (xy 245.545991 -340.095126) (xy 245.595591 -340.069625) (xy 245.648375 -340.051618)
			(xy 245.703218 -340.041488) (xy 245.758952 -340.039451) (xy 245.814389 -340.045551) (xy 245.868346 -340.059657)
			(xy 245.919675 -340.081469) (xy 245.967281 -340.110523) (xy 246.010149 -340.146198) (xy 246.047366 -340.187735)
			(xy 246.078139 -340.234248) (xy 246.101811 -340.284745) (xy 246.117879 -340.338152) (xy 246.125999 -340.393328)
			(xy 246.126508 -340.421214) (xy 246.125999 -340.4491) (xy 246.117879 -340.504276) (xy 246.101811 -340.557683)
			(xy 246.078139 -340.60818) (xy 246.047366 -340.654693) (xy 246.010149 -340.69623) (xy 245.967281 -340.731905)
			(xy 245.919675 -340.760959) (xy 245.868346 -340.782771) (xy 245.814389 -340.796877) (xy 245.758952 -340.802977)
			(xy 245.703218 -340.80094) (xy 245.648375 -340.79081) (xy 245.595591 -340.772803) (xy 245.545991 -340.747302)
			(xy 245.500633 -340.714851) (xy 245.460484 -340.676142) (xy 245.426398 -340.631999) (xy 245.399102 -340.583364)
			(xy 245.379179 -340.531273) (xy 245.367053 -340.476836) (xy 245.362982 -340.421214) (xy 241.098692 -340.421214)
			(xy 241.132872 -340.468259) (xy 241.163666 -340.524274) (xy 241.187198 -340.583707) (xy 241.203095 -340.645621)
			(xy 241.211106 -340.709039) (xy 241.211608 -340.741) (xy 241.211106 -340.772961) (xy 241.203095 -340.836379)
			(xy 241.187198 -340.898293) (xy 241.163666 -340.957726) (xy 241.132872 -341.013741) (xy 241.095299 -341.065456)
			(xy 241.051542 -341.112053) (xy 241.002289 -341.152798) (xy 240.948318 -341.187049) (xy 240.890479 -341.214266)
			(xy 240.829686 -341.234019) (xy 240.766896 -341.245997) (xy 240.7031 -341.250011) (xy 240.639304 -341.245997)
			(xy 240.576514 -341.234019) (xy 240.515721 -341.214266) (xy 240.457882 -341.187049) (xy 240.403911 -341.152798)
			(xy 240.354658 -341.112053) (xy 240.310901 -341.065456) (xy 240.273328 -341.013741) (xy 240.242534 -340.957726)
			(xy 240.219002 -340.898293) (xy 240.203105 -340.836379) (xy 240.195094 -340.772961) (xy 234.687294 -340.772961)
			(xy 234.695836 -340.831406) (xy 234.696508 -340.868) (xy 234.695993 -340.899286) (xy 234.688322 -340.961387)
			(xy 234.673084 -341.022076) (xy 234.65051 -341.080435) (xy 234.620942 -341.13558) (xy 234.584826 -341.186678)
			(xy 234.542709 -341.232954) (xy 234.495229 -341.27371) (xy 234.469432 -341.291418) (xy 234.45929 -341.298951)
			(xy 234.447425 -341.321217) (xy 234.446826 -341.333836) (xy 234.446826 -341.418164) (xy 234.447487 -341.430767)
			(xy 234.459333 -341.453014) (xy 234.469432 -341.460582) (xy 234.49523 -341.47829) (xy 234.54271 -341.519047)
			(xy 234.584828 -341.565324) (xy 234.620947 -341.616421) (xy 234.65052 -341.671566) (xy 234.673101 -341.729924)
			(xy 234.688347 -341.790612) (xy 234.696028 -341.852713) (xy 234.696508 -341.884) (xy 234.696044 -341.914731)
			(xy 234.695895 -341.915961) (xy 240.195094 -341.915961) (xy 240.195094 -341.852039) (xy 240.203105 -341.788621)
			(xy 240.219002 -341.726707) (xy 240.242534 -341.667274) (xy 240.273328 -341.611259) (xy 240.310901 -341.559544)
			(xy 240.354658 -341.512947) (xy 240.403911 -341.472202) (xy 240.457882 -341.437951) (xy 240.515721 -341.410734)
			(xy 240.576514 -341.390981) (xy 240.639304 -341.379003) (xy 240.7031 -341.37499) (xy 240.766896 -341.379003)
			(xy 240.829686 -341.390981) (xy 240.890479 -341.410734) (xy 240.948318 -341.437951) (xy 241.002289 -341.472202)
			(xy 241.051542 -341.512947) (xy 241.095299 -341.559544) (xy 241.132872 -341.611259) (xy 241.163666 -341.667274)
			(xy 241.187198 -341.726707) (xy 241.203095 -341.788621) (xy 241.211106 -341.852039) (xy 241.211608 -341.884)
			(xy 241.211106 -341.915961) (xy 241.203095 -341.979379) (xy 241.187198 -342.041293) (xy 241.163666 -342.100726)
			(xy 241.132872 -342.156741) (xy 241.095299 -342.208456) (xy 241.051542 -342.255053) (xy 241.039518 -342.265)
			(xy 256.666492 -342.265) (xy 256.666943 -342.233234) (xy 256.674879 -342.1702) (xy 256.690604 -342.108644)
			(xy 256.713873 -342.049526) (xy 256.744322 -341.993767) (xy 256.781479 -341.942233) (xy 256.824764 -341.895727)
			(xy 256.873503 -341.854975) (xy 256.926938 -341.820609) (xy 256.984237 -341.793165) (xy 257.014218 -341.782654)
			(xy 257.014472 -341.782654) (xy 257.024107 -341.778838) (xy 257.039452 -341.764945) (xy 257.04419 -341.75573)
			(xy 257.079496 -341.678514) (xy 257.080004 -341.657432) (xy 257.07594 -341.64778) (xy 257.066943 -341.624804)
			(xy 257.054289 -341.577109) (xy 257.047895 -341.52818) (xy 257.047492 -341.503508) (xy 257.047492 -341.503)
			(xy 257.04818 -341.469659) (xy 257.059814 -341.403998) (xy 257.070606 -341.372444) (xy 257.070606 -341.37219)
			(xy 257.073554 -341.362594) (xy 257.072511 -341.342562) (xy 257.068574 -341.333328) (xy 257.037586 -341.267796)
			(xy 257.032877 -341.258898) (xy 257.017965 -341.245399) (xy 257.00863 -341.241634) (xy 257.008122 -341.241634)
			(xy 256.978589 -341.230823) (xy 256.922176 -341.203025) (xy 256.869623 -341.16848) (xy 256.821731 -341.127718)
			(xy 256.779234 -341.081359) (xy 256.742778 -341.030113) (xy 256.712922 -340.974762) (xy 256.69012 -340.916151)
			(xy 256.674723 -340.855175) (xy 256.666963 -340.792765) (xy 256.666492 -340.76132) (xy 256.666994 -340.729359)
			(xy 256.675005 -340.665941) (xy 256.690902 -340.604027) (xy 256.714434 -340.544594) (xy 256.745228 -340.488579)
			(xy 256.782801 -340.436864) (xy 256.826558 -340.390267) (xy 256.875811 -340.349522) (xy 256.929782 -340.315271)
			(xy 256.987621 -340.288054) (xy 257.048414 -340.268301) (xy 257.111204 -340.256323) (xy 257.175 -340.25231)
			(xy 257.238796 -340.256323) (xy 257.301586 -340.268301) (xy 257.362379 -340.288054) (xy 257.420218 -340.315271)
			(xy 257.474189 -340.349522) (xy 257.523442 -340.390267) (xy 257.567199 -340.436864) (xy 257.604772 -340.488579)
			(xy 257.635566 -340.544594) (xy 257.659098 -340.604027) (xy 257.674995 -340.665941) (xy 257.683006 -340.729359)
			(xy 257.683508 -340.76132) (xy 257.683078 -340.790665) (xy 257.676329 -340.848967) (xy 257.662911 -340.906103)
			(xy 257.643003 -340.961314) (xy 257.616869 -341.013865) (xy 257.601212 -341.038688) (xy 257.595624 -341.047324)
			(xy 257.591814 -341.067136) (xy 257.609594 -341.148162) (xy 257.612234 -341.157868) (xy 257.623744 -341.174341)
			(xy 257.631946 -341.180166) (xy 257.6322 -341.180166) (xy 257.655205 -341.195255) (xy 257.697085 -341.230929)
			(xy 257.733404 -341.272251) (xy 257.763407 -341.318363) (xy 257.786472 -341.368308) (xy 257.80212 -341.42105)
			(xy 257.810026 -341.475493) (xy 257.810508 -341.503) (xy 257.809974 -341.531154) (xy 257.80169 -341.58685)
			(xy 257.785319 -341.640726) (xy 257.761213 -341.691613) (xy 257.729896 -341.73841) (xy 257.692047 -341.7801)
			(xy 257.648486 -341.81578) (xy 257.62458 -341.83066) (xy 257.615436 -341.835994) (xy 257.603244 -341.853012)
			(xy 257.58521 -341.93607) (xy 257.583497 -341.946282) (xy 257.587443 -341.966595) (xy 257.59283 -341.97544)
			(xy 257.593084 -341.97544) (xy 257.593084 -341.975948) (xy 257.610239 -342.00149) (xy 257.638925 -342.055925)
			(xy 257.660819 -342.113428) (xy 257.6756 -342.173157) (xy 257.683051 -342.234235) (xy 257.683508 -342.265)
			(xy 257.683006 -342.296961) (xy 257.674995 -342.360379) (xy 257.659098 -342.422293) (xy 257.635566 -342.481726)
			(xy 257.604772 -342.537741) (xy 257.567199 -342.589456) (xy 257.523442 -342.636053) (xy 257.474189 -342.676798)
			(xy 257.420218 -342.711049) (xy 257.362379 -342.738266) (xy 257.301586 -342.758019) (xy 257.238796 -342.769997)
			(xy 257.175 -342.774011) (xy 257.111204 -342.769997) (xy 257.048414 -342.758019) (xy 256.987621 -342.738266)
			(xy 256.929782 -342.711049) (xy 256.875811 -342.676798) (xy 256.826558 -342.636053) (xy 256.782801 -342.589456)
			(xy 256.745228 -342.537741) (xy 256.714434 -342.481726) (xy 256.690902 -342.422293) (xy 256.675005 -342.360379)
			(xy 256.666994 -342.296961) (xy 256.666492 -342.265) (xy 241.039518 -342.265) (xy 241.002289 -342.295798)
			(xy 240.948318 -342.330049) (xy 240.890479 -342.357266) (xy 240.829686 -342.377019) (xy 240.766896 -342.388997)
			(xy 240.7031 -342.393011) (xy 240.639304 -342.388997) (xy 240.576514 -342.377019) (xy 240.515721 -342.357266)
			(xy 240.457882 -342.330049) (xy 240.403911 -342.295798) (xy 240.354658 -342.255053) (xy 240.310901 -342.208456)
			(xy 240.273328 -342.156741) (xy 240.242534 -342.100726) (xy 240.219002 -342.041293) (xy 240.203105 -341.979379)
			(xy 240.195094 -341.915961) (xy 234.695895 -341.915961) (xy 234.688635 -341.975745) (xy 234.673927 -342.035421)
			(xy 234.652132 -342.092889) (xy 234.623569 -342.147311) (xy 234.588655 -342.197893) (xy 234.547898 -342.243898)
			(xy 234.501893 -342.284655) (xy 234.451311 -342.319569) (xy 234.396889 -342.348132) (xy 234.339421 -342.369927)
			(xy 234.279745 -342.384635) (xy 234.218731 -342.392044) (xy 234.188 -342.392508) (xy 234.187746 -342.392508)
			(xy 234.16398 -342.392232) (xy 234.116658 -342.387777) (xy 234.093258 -342.383618) (xy 234.08005 -342.381078)
			(xy 234.054396 -342.389968) (xy 233.978958 -342.477598) (xy 233.973878 -342.504014) (xy 233.97845 -342.516968)
			(xy 233.988506 -342.547621) (xy 233.999363 -342.611207) (xy 234.00004 -342.64346) (xy 233.999588 -342.670717)
			(xy 233.991835 -342.724676) (xy 233.976482 -342.776983) (xy 233.95384 -342.826573) (xy 233.924372 -342.872435)
			(xy 233.888676 -342.913636) (xy 233.84748 -342.949338) (xy 233.801622 -342.978813) (xy 233.752036 -343.001462)
			(xy 233.699731 -343.016823) (xy 233.645773 -343.024584) (xy 233.591259 -343.024586) (xy 233.5373 -343.01683)
			(xy 233.484994 -343.001473) (xy 233.435406 -342.978829) (xy 233.389546 -342.949357) (xy 233.348347 -342.913659)
			(xy 233.312648 -342.872461) (xy 233.283175 -342.826601) (xy 233.26053 -342.777013) (xy 233.245172 -342.724708)
			(xy 233.237414 -342.670749) (xy 230.58628 -342.670749) (xy 230.58628 -346.146077) (xy 243.411496 -346.146077)
			(xy 243.411496 -346.082155) (xy 243.419507 -346.018737) (xy 243.435404 -345.956823) (xy 243.458936 -345.89739)
			(xy 243.48973 -345.841375) (xy 243.527303 -345.78966) (xy 243.57106 -345.743063) (xy 243.620313 -345.702318)
			(xy 243.674284 -345.668067) (xy 243.732123 -345.64085) (xy 243.792916 -345.621097) (xy 243.855706 -345.609119)
			(xy 243.919502 -345.605106) (xy 243.983298 -345.609119) (xy 244.046088 -345.621097) (xy 244.106881 -345.64085)
			(xy 244.16472 -345.668067) (xy 244.218691 -345.702318) (xy 244.267944 -345.743063) (xy 244.311701 -345.78966)
			(xy 244.349274 -345.841375) (xy 244.380068 -345.89739) (xy 244.4036 -345.956823) (xy 244.409541 -345.979961)
			(xy 252.221994 -345.979961) (xy 252.221994 -345.916039) (xy 252.230005 -345.852621) (xy 252.245902 -345.790707)
			(xy 252.269434 -345.731274) (xy 252.300228 -345.675259) (xy 252.337801 -345.623544) (xy 252.381558 -345.576947)
			(xy 252.430811 -345.536202) (xy 252.484782 -345.501951) (xy 252.542621 -345.474734) (xy 252.603414 -345.454981)
			(xy 252.666204 -345.443003) (xy 252.73 -345.43899) (xy 252.793796 -345.443003) (xy 252.856586 -345.454981)
			(xy 252.917379 -345.474734) (xy 252.975218 -345.501951) (xy 253.029189 -345.536202) (xy 253.078442 -345.576947)
			(xy 253.122199 -345.623544) (xy 253.159772 -345.675259) (xy 253.187645 -345.725961) (xy 257.555994 -345.725961)
			(xy 257.555994 -345.662039) (xy 257.564005 -345.598621) (xy 257.579902 -345.536707) (xy 257.603434 -345.477274)
			(xy 257.634228 -345.421259) (xy 257.671801 -345.369544) (xy 257.715558 -345.322947) (xy 257.764811 -345.282202)
			(xy 257.818782 -345.247951) (xy 257.876621 -345.220734) (xy 257.937414 -345.200981) (xy 258.000204 -345.189003)
			(xy 258.064 -345.18499) (xy 258.127796 -345.189003) (xy 258.190586 -345.200981) (xy 258.251379 -345.220734)
			(xy 258.309218 -345.247951) (xy 258.363189 -345.282202) (xy 258.412442 -345.322947) (xy 258.456199 -345.369544)
			(xy 258.493772 -345.421259) (xy 258.524566 -345.477274) (xy 258.548098 -345.536707) (xy 258.563995 -345.598621)
			(xy 258.572006 -345.662039) (xy 258.572508 -345.694) (xy 258.572006 -345.725961) (xy 258.563995 -345.789379)
			(xy 258.548098 -345.851293) (xy 258.524566 -345.910726) (xy 258.493772 -345.966741) (xy 258.456199 -346.018456)
			(xy 258.412442 -346.065053) (xy 258.363189 -346.105798) (xy 258.309218 -346.140049) (xy 258.251379 -346.167266)
			(xy 258.190586 -346.187019) (xy 258.127796 -346.198997) (xy 258.064 -346.203011) (xy 258.000204 -346.198997)
			(xy 257.937414 -346.187019) (xy 257.876621 -346.167266) (xy 257.818782 -346.140049) (xy 257.764811 -346.105798)
			(xy 257.715558 -346.065053) (xy 257.671801 -346.018456) (xy 257.634228 -345.966741) (xy 257.603434 -345.910726)
			(xy 257.579902 -345.851293) (xy 257.564005 -345.789379) (xy 257.555994 -345.725961) (xy 253.187645 -345.725961)
			(xy 253.190566 -345.731274) (xy 253.214098 -345.790707) (xy 253.229995 -345.852621) (xy 253.238006 -345.916039)
			(xy 253.238508 -345.948) (xy 253.238006 -345.979961) (xy 253.229995 -346.043379) (xy 253.214098 -346.105293)
			(xy 253.190566 -346.164726) (xy 253.159772 -346.220741) (xy 253.122199 -346.272456) (xy 253.078442 -346.319053)
			(xy 253.029189 -346.359798) (xy 252.975218 -346.394049) (xy 252.917379 -346.421266) (xy 252.856586 -346.441019)
			(xy 252.793796 -346.452997) (xy 252.73 -346.457011) (xy 252.666204 -346.452997) (xy 252.603414 -346.441019)
			(xy 252.542621 -346.421266) (xy 252.484782 -346.394049) (xy 252.430811 -346.359798) (xy 252.381558 -346.319053)
			(xy 252.337801 -346.272456) (xy 252.300228 -346.220741) (xy 252.269434 -346.164726) (xy 252.245902 -346.105293)
			(xy 252.230005 -346.043379) (xy 252.221994 -345.979961) (xy 244.409541 -345.979961) (xy 244.419497 -346.018737)
			(xy 244.427508 -346.082155) (xy 244.42801 -346.114116) (xy 244.427508 -346.146077) (xy 244.419497 -346.209495)
			(xy 244.4036 -346.271409) (xy 244.380068 -346.330842) (xy 244.349274 -346.386857) (xy 244.311701 -346.438572)
			(xy 244.267944 -346.485169) (xy 244.218691 -346.525914) (xy 244.16472 -346.560165) (xy 244.106881 -346.587382)
			(xy 244.046088 -346.607135) (xy 243.983298 -346.619113) (xy 243.919502 -346.623127) (xy 243.855706 -346.619113)
			(xy 243.792916 -346.607135) (xy 243.732123 -346.587382) (xy 243.674284 -346.560165) (xy 243.620313 -346.525914)
			(xy 243.57106 -346.485169) (xy 243.527303 -346.438572) (xy 243.48973 -346.386857) (xy 243.458936 -346.330842)
			(xy 243.435404 -346.271409) (xy 243.419507 -346.209495) (xy 243.411496 -346.146077) (xy 230.58628 -346.146077)
			(xy 230.58628 -352.49993) (xy 231.378258 -352.49993) (xy 231.382272 -352.294246) (xy 231.394308 -352.088876)
			(xy 231.414347 -351.884132) (xy 231.44236 -351.680325) (xy 231.478303 -351.477766) (xy 231.522122 -351.276764)
			(xy 231.573749 -351.077625) (xy 231.633107 -350.880652) (xy 231.700105 -350.686144) (xy 231.774641 -350.494399)
			(xy 231.856601 -350.305708) (xy 231.945861 -350.120358) (xy 232.042284 -349.938632) (xy 232.145725 -349.760806)
			(xy 232.256024 -349.587152) (xy 232.373015 -349.417933) (xy 232.496519 -349.253407) (xy 232.626348 -349.093826)
			(xy 232.762305 -348.939431) (xy 232.904182 -348.790459) (xy 233.051763 -348.647135) (xy 233.204824 -348.509679)
			(xy 233.363131 -348.378299) (xy 233.526444 -348.253196) (xy 233.694513 -348.134559) (xy 233.867083 -348.022571)
			(xy 234.043891 -347.9174) (xy 234.224668 -347.819209) (xy 234.409138 -347.728145) (xy 234.59702 -347.644348)
			(xy 234.78803 -347.567945) (xy 234.981874 -347.499052) (xy 235.178259 -347.437775) (xy 235.376885 -347.384207)
			(xy 235.57745 -347.33843) (xy 235.779648 -347.300512) (xy 235.983172 -347.270513) (xy 236.187711 -347.248476)
			(xy 236.392954 -347.234437) (xy 236.598589 -347.228417) (xy 236.804302 -347.230424) (xy 237.00978 -347.240456)
			(xy 237.21471 -347.258497) (xy 237.41878 -347.28452) (xy 237.62168 -347.318485) (xy 237.8231 -347.36034)
			(xy 238.022733 -347.410022) (xy 238.199722 -347.46148) (xy 252.348098 -347.46148) (xy 252.353307 -347.398614)
			(xy 252.366253 -347.336874) (xy 252.386736 -347.27721) (xy 252.414441 -347.220538) (xy 252.448944 -347.167728)
			(xy 252.489714 -347.119591) (xy 252.536125 -347.076866) (xy 252.587464 -347.040211) (xy 252.642943 -347.010187)
			(xy 252.70171 -346.987256) (xy 252.762861 -346.97177) (xy 252.825459 -346.963968) (xy 252.857 -346.963492)
			(xy 252.878082 -346.964) (xy 252.878336 -346.964) (xy 252.888771 -346.96387) (xy 252.90818 -346.95626)
			(xy 252.915928 -346.949268) (xy 252.969268 -346.895928) (xy 252.976253 -346.888176) (xy 252.983862 -346.86877)
			(xy 252.984 -346.858336) (xy 252.984 -346.857828) (xy 252.983492 -346.837) (xy 252.983968 -346.805459)
			(xy 252.99177 -346.742861) (xy 253.007256 -346.68171) (xy 253.030187 -346.622943) (xy 253.060211 -346.567464)
			(xy 253.096866 -346.516125) (xy 253.139591 -346.469714) (xy 253.187728 -346.428944) (xy 253.240538 -346.394441)
			(xy 253.29721 -346.366736) (xy 253.356874 -346.346253) (xy 253.418614 -346.333307) (xy 253.48148 -346.328098)
			(xy 253.544509 -346.330705) (xy 253.60673 -346.341088) (xy 253.66719 -346.359088) (xy 253.724959 -346.384427)
			(xy 253.77915 -346.416718) (xy 253.82893 -346.455464) (xy 253.873536 -346.50007) (xy 253.912282 -346.54985)
			(xy 253.944573 -346.604041) (xy 253.969912 -346.66181) (xy 253.987912 -346.72227) (xy 253.998295 -346.784491)
			(xy 254.000902 -346.84752) (xy 253.995693 -346.910386) (xy 253.982747 -346.972126) (xy 253.962264 -347.03179)
			(xy 253.934559 -347.088462) (xy 253.900056 -347.141272) (xy 253.859286 -347.189409) (xy 253.812875 -347.232134)
			(xy 253.761536 -347.268789) (xy 253.706057 -347.298813) (xy 253.64729 -347.321744) (xy 253.586139 -347.33723)
			(xy 253.523541 -347.345032) (xy 253.492 -347.345508) (xy 253.470918 -347.345) (xy 253.470664 -347.345)
			(xy 253.460229 -347.34513) (xy 253.44082 -347.35274) (xy 253.433072 -347.359732) (xy 253.379732 -347.413072)
			(xy 253.372747 -347.420824) (xy 253.365138 -347.44023) (xy 253.365 -347.450664) (xy 253.365 -347.451172)
			(xy 253.365508 -347.472) (xy 253.365032 -347.503541) (xy 253.35723 -347.566139) (xy 253.341744 -347.62729)
			(xy 253.318813 -347.686057) (xy 253.288789 -347.741536) (xy 253.252134 -347.792875) (xy 253.209409 -347.839286)
			(xy 253.161272 -347.880056) (xy 253.108462 -347.914559) (xy 253.05179 -347.942264) (xy 252.992126 -347.962747)
			(xy 252.930386 -347.975693) (xy 252.86752 -347.980902) (xy 252.804491 -347.978295) (xy 252.74227 -347.967912)
			(xy 252.68181 -347.949912) (xy 252.624041 -347.924573) (xy 252.56985 -347.892282) (xy 252.52007 -347.853536)
			(xy 252.475464 -347.80893) (xy 252.436718 -347.75915) (xy 252.404427 -347.704959) (xy 252.379088 -347.64719)
			(xy 252.361088 -347.58673) (xy 252.350705 -347.524509) (xy 252.348098 -347.46148) (xy 238.199722 -347.46148)
			(xy 238.220276 -347.467456) (xy 238.415428 -347.532553) (xy 238.607892 -347.605214) (xy 238.797374 -347.68533)
			(xy 238.983585 -347.772777) (xy 239.166244 -347.867423) (xy 239.34507 -347.969123) (xy 239.519792 -348.077723)
			(xy 239.690145 -348.193058) (xy 239.855867 -348.314951) (xy 240.016708 -348.443217) (xy 240.172421 -348.57766)
			(xy 240.322771 -348.718077) (xy 240.467528 -348.864253) (xy 240.606471 -349.015965) (xy 240.739389 -349.172983)
			(xy 240.86608 -349.335068) (xy 240.98635 -349.501971) (xy 241.100017 -349.673441) (xy 241.206907 -349.849214)
			(xy 241.306858 -350.029024) (xy 241.399717 -350.212597) (xy 241.485344 -350.399653) (xy 241.563606 -350.589908)
			(xy 241.634387 -350.783071) (xy 241.697577 -350.978849) (xy 241.75308 -351.176943) (xy 241.800812 -351.377052)
			(xy 241.840701 -351.57887) (xy 241.872685 -351.782092) (xy 241.896715 -351.986406) (xy 241.912756 -352.191502)
			(xy 241.920782 -352.397069) (xy 241.921284 -352.49993) (xy 241.920782 -352.602791) (xy 241.912756 -352.808358)
			(xy 241.896715 -353.013454) (xy 241.872685 -353.217768) (xy 241.840701 -353.42099) (xy 241.800812 -353.622808)
			(xy 241.75308 -353.822917) (xy 241.697577 -354.021011) (xy 241.634387 -354.216789) (xy 241.563606 -354.409952)
			(xy 241.485344 -354.600207) (xy 241.399717 -354.787263) (xy 241.306858 -354.970836) (xy 241.206907 -355.150646)
			(xy 241.100017 -355.326419) (xy 240.98635 -355.497889) (xy 240.86608 -355.664792) (xy 240.739389 -355.826877)
			(xy 240.606471 -355.983895) (xy 240.467528 -356.135607) (xy 240.322771 -356.281783) (xy 240.172421 -356.4222)
			(xy 240.016708 -356.556643) (xy 239.855867 -356.684909) (xy 239.690145 -356.806802) (xy 239.519792 -356.922137)
			(xy 239.34507 -357.030737) (xy 239.166244 -357.132437) (xy 238.983585 -357.227083) (xy 238.797374 -357.31453)
			(xy 238.607892 -357.394646) (xy 238.415428 -357.467307) (xy 238.220276 -357.532404) (xy 238.022733 -357.589838)
			(xy 237.8231 -357.63952) (xy 237.62168 -357.681375) (xy 237.41878 -357.71534) (xy 237.21471 -357.741363)
			(xy 237.00978 -357.759404) (xy 236.804302 -357.769436) (xy 236.598589 -357.771443) (xy 236.392954 -357.765423)
			(xy 236.187711 -357.751384) (xy 235.983172 -357.729347) (xy 235.779648 -357.699348) (xy 235.57745 -357.66143)
			(xy 235.376885 -357.615653) (xy 235.178259 -357.562085) (xy 234.981874 -357.500808) (xy 234.78803 -357.431915)
			(xy 234.59702 -357.355512) (xy 234.409138 -357.271715) (xy 234.224668 -357.180651) (xy 234.043891 -357.08246)
			(xy 233.867083 -356.977289) (xy 233.694513 -356.865301) (xy 233.526444 -356.746664) (xy 233.363131 -356.621561)
			(xy 233.204824 -356.490181) (xy 233.051763 -356.352725) (xy 232.904182 -356.209401) (xy 232.762305 -356.060429)
			(xy 232.626348 -355.906034) (xy 232.496519 -355.746453) (xy 232.373015 -355.581927) (xy 232.256024 -355.412708)
			(xy 232.145725 -355.239054) (xy 232.042284 -355.061228) (xy 231.945861 -354.879502) (xy 231.856601 -354.694152)
			(xy 231.774641 -354.505461) (xy 231.700105 -354.313716) (xy 231.633107 -354.119208) (xy 231.573749 -353.922235)
			(xy 231.522122 -353.723096) (xy 231.478303 -353.522094) (xy 231.44236 -353.319535) (xy 231.414347 -353.115728)
			(xy 231.394308 -352.910984) (xy 231.382272 -352.705614) (xy 231.378258 -352.49993) (xy 230.58628 -352.49993)
			(xy 230.58628 -360.764074) (xy 253.856497 -360.764074) (xy 253.860504 -360.57917) (xy 253.872517 -360.394612)
			(xy 253.892513 -360.210748) (xy 253.920455 -360.027924) (xy 253.956291 -359.846481) (xy 253.999953 -359.66676)
			(xy 254.05136 -359.4891) (xy 254.110414 -359.313834) (xy 254.177005 -359.14129) (xy 254.251008 -358.971793)
			(xy 254.332284 -358.805661) (xy 254.42068 -358.643205) (xy 254.516031 -358.484731) (xy 254.618157 -358.330536)
			(xy 254.726866 -358.18091) (xy 254.841955 -358.036134) (xy 254.963208 -357.896479) (xy 255.090397 -357.762208)
			(xy 255.223282 -357.633572) (xy 255.361616 -357.510813) (xy 255.505137 -357.394163) (xy 255.653576 -357.283839)
			(xy 255.806656 -357.180048) (xy 255.964087 -357.082986) (xy 256.125576 -356.992836) (xy 256.290818 -356.909765)
			(xy 256.459504 -356.83393) (xy 256.631316 -356.765474) (xy 256.805932 -356.704524) (xy 256.983025 -356.651197)
			(xy 257.162262 -356.60559) (xy 257.343306 -356.567791) (xy 257.525817 -356.53787) (xy 257.709454 -356.515883)
			(xy 257.89387 -356.501871) (xy 258.07872 -356.495861) (xy 258.263657 -356.497865) (xy 258.448334 -356.507878)
			(xy 258.632404 -356.525881) (xy 258.81552 -356.551842) (xy 258.997341 -356.58571) (xy 259.177524 -356.627422)
			(xy 259.35573 -356.676901) (xy 259.531626 -356.734053) (xy 259.704881 -356.798771) (xy 259.87517 -356.870934)
			(xy 260.042173 -356.950405) (xy 260.205577 -357.037036) (xy 260.365074 -357.130665) (xy 260.520366 -357.231114)
			(xy 260.671161 -357.338197) (xy 260.817176 -357.451711) (xy 260.958136 -357.571443) (xy 261.093777 -357.69717)
			(xy 261.223845 -357.828654) (xy 261.348095 -357.96565) (xy 261.466293 -358.107899) (xy 261.578219 -358.255134)
			(xy 261.683662 -358.40708) (xy 261.782423 -358.563451) (xy 261.874318 -358.723954) (xy 261.959174 -358.888286)
			(xy 262.036832 -359.056141) (xy 262.107145 -359.227201) (xy 262.169982 -359.401147) (xy 262.225226 -359.577652)
			(xy 262.272771 -359.756384) (xy 262.312529 -359.937008) (xy 262.344426 -360.119185) (xy 262.368401 -360.302572)
			(xy 262.383008 -360.470704) (xy 271.47749 -360.470704) (xy 271.481519 -360.379698) (xy 271.493576 -360.289404)
			(xy 271.513566 -360.200529) (xy 271.541332 -360.113769) (xy 271.576658 -360.029802) (xy 271.619266 -359.949286)
			(xy 271.668824 -359.87285) (xy 271.724943 -359.801094) (xy 271.787184 -359.734578) (xy 271.855061 -359.673823)
			(xy 271.928041 -359.619305) (xy 272.005554 -359.571451) (xy 272.086993 -359.530634) (xy 272.171721 -359.497175)
			(xy 272.259075 -359.471334) (xy 272.34837 -359.453316) (xy 272.438908 -359.443259) (xy 272.529981 -359.441244)
			(xy 272.620876 -359.447286) (xy 272.710881 -359.461337) (xy 272.799292 -359.483288) (xy 272.885417 -359.512967)
			(xy 272.968582 -359.550141) (xy 273.048136 -359.59452) (xy 273.123456 -359.645757) (xy 273.193954 -359.70345)
			(xy 273.259076 -359.767147) (xy 273.318314 -359.836351) (xy 273.371204 -359.91052) (xy 273.417333 -359.989072)
			(xy 273.456338 -360.071395) (xy 273.487915 -360.156842) (xy 273.511816 -360.244746) (xy 273.527855 -360.334418)
			(xy 273.535906 -360.425156) (xy 273.53641 -360.470704) (xy 273.535906 -360.516252) (xy 273.527855 -360.60699)
			(xy 273.511816 -360.696662) (xy 273.487915 -360.784566) (xy 273.456338 -360.870013) (xy 273.417333 -360.952336)
			(xy 273.371204 -361.030888) (xy 273.318314 -361.105057) (xy 273.259076 -361.174261) (xy 273.193954 -361.237958)
			(xy 273.123456 -361.295651) (xy 273.048136 -361.346888) (xy 272.968582 -361.391267) (xy 272.885417 -361.428441)
			(xy 272.799292 -361.45812) (xy 272.710881 -361.480071) (xy 272.620876 -361.494122) (xy 272.529981 -361.500164)
			(xy 272.438908 -361.498149) (xy 272.34837 -361.488092) (xy 272.259075 -361.470074) (xy 272.171721 -361.444233)
			(xy 272.086993 -361.410774) (xy 272.005554 -361.369957) (xy 271.928041 -361.322103) (xy 271.855061 -361.267585)
			(xy 271.787184 -361.20683) (xy 271.724943 -361.140314) (xy 271.668824 -361.068558) (xy 271.619266 -360.992122)
			(xy 271.576658 -360.911606) (xy 271.541332 -360.827639) (xy 271.513566 -360.740879) (xy 271.493576 -360.652004)
			(xy 271.481519 -360.56171) (xy 271.47749 -360.470704) (xy 262.383008 -360.470704) (xy 262.384409 -360.486826)
			(xy 262.392421 -360.6716) (xy 262.392922 -360.764074) (xy 262.392421 -360.856548) (xy 262.384409 -361.041322)
			(xy 262.368401 -361.225576) (xy 262.344426 -361.408963) (xy 262.312529 -361.59114) (xy 262.272771 -361.771764)
			(xy 262.225226 -361.950496) (xy 262.169982 -362.127001) (xy 262.107145 -362.300947) (xy 262.036832 -362.472007)
			(xy 261.959174 -362.639862) (xy 261.874318 -362.804194) (xy 261.782423 -362.964697) (xy 261.753366 -363.010704)
			(xy 271.47749 -363.010704) (xy 271.481519 -362.919698) (xy 271.493576 -362.829404) (xy 271.513566 -362.740529)
			(xy 271.541332 -362.653769) (xy 271.576658 -362.569802) (xy 271.619266 -362.489286) (xy 271.668824 -362.41285)
			(xy 271.724943 -362.341094) (xy 271.787184 -362.274578) (xy 271.855061 -362.213823) (xy 271.928041 -362.159305)
			(xy 272.005554 -362.111451) (xy 272.086993 -362.070634) (xy 272.171721 -362.037175) (xy 272.259075 -362.011334)
			(xy 272.34837 -361.993316) (xy 272.438908 -361.983259) (xy 272.529981 -361.981244) (xy 272.620876 -361.987286)
			(xy 272.710881 -362.001337) (xy 272.799292 -362.023288) (xy 272.885417 -362.052967) (xy 272.968582 -362.090141)
			(xy 272.983195 -362.098293) (xy 274.067264 -362.098293) (xy 274.067264 -362.034371) (xy 274.075275 -361.970953)
			(xy 274.091172 -361.909039) (xy 274.114704 -361.849606) (xy 274.145498 -361.793591) (xy 274.183071 -361.741876)
			(xy 274.226828 -361.695279) (xy 274.276081 -361.654534) (xy 274.330052 -361.620283) (xy 274.387891 -361.593066)
			(xy 274.448684 -361.573313) (xy 274.511474 -361.561335) (xy 274.57527 -361.557322) (xy 274.639066 -361.561335)
			(xy 274.701856 -361.573313) (xy 274.762649 -361.593066) (xy 274.820488 -361.620283) (xy 274.874459 -361.654534)
			(xy 274.923712 -361.695279) (xy 274.967469 -361.741876) (xy 275.005042 -361.793591) (xy 275.035836 -361.849606)
			(xy 275.059368 -361.909039) (xy 275.075265 -361.970953) (xy 275.083276 -362.034371) (xy 275.083778 -362.066332)
			(xy 275.083276 -362.098293) (xy 275.075265 -362.161711) (xy 275.059368 -362.223625) (xy 275.035836 -362.283058)
			(xy 275.005042 -362.339073) (xy 274.967469 -362.390788) (xy 274.923712 -362.437385) (xy 274.874459 -362.47813)
			(xy 274.820488 -362.512381) (xy 274.762649 -362.539598) (xy 274.701856 -362.559351) (xy 274.639066 -362.571329)
			(xy 274.57527 -362.575343) (xy 274.511474 -362.571329) (xy 274.448684 -362.559351) (xy 274.387891 -362.539598)
			(xy 274.330052 -362.512381) (xy 274.276081 -362.47813) (xy 274.226828 -362.437385) (xy 274.183071 -362.390788)
			(xy 274.145498 -362.339073) (xy 274.114704 -362.283058) (xy 274.091172 -362.223625) (xy 274.075275 -362.161711)
			(xy 274.067264 -362.098293) (xy 272.983195 -362.098293) (xy 273.048136 -362.13452) (xy 273.123456 -362.185757)
			(xy 273.193954 -362.24345) (xy 273.259076 -362.307147) (xy 273.318314 -362.376351) (xy 273.371204 -362.45052)
			(xy 273.417333 -362.529072) (xy 273.456338 -362.611395) (xy 273.487915 -362.696842) (xy 273.511816 -362.784746)
			(xy 273.527855 -362.874418) (xy 273.535906 -362.965156) (xy 273.53641 -363.010704) (xy 273.535906 -363.056252)
			(xy 273.527855 -363.14699) (xy 273.511816 -363.236662) (xy 273.487915 -363.324566) (xy 273.456338 -363.410013)
			(xy 273.417333 -363.492336) (xy 273.371204 -363.570888) (xy 273.318314 -363.645057) (xy 273.259076 -363.714261)
			(xy 273.193954 -363.777958) (xy 273.123456 -363.835651) (xy 273.048136 -363.886888) (xy 272.968582 -363.931267)
			(xy 272.885417 -363.968441) (xy 272.799292 -363.99812) (xy 272.710881 -364.020071) (xy 272.620876 -364.034122)
			(xy 272.529981 -364.040164) (xy 272.438908 -364.038149) (xy 272.34837 -364.028092) (xy 272.259075 -364.010074)
			(xy 272.171721 -363.984233) (xy 272.086993 -363.950774) (xy 272.005554 -363.909957) (xy 271.928041 -363.862103)
			(xy 271.855061 -363.807585) (xy 271.787184 -363.74683) (xy 271.724943 -363.680314) (xy 271.668824 -363.608558)
			(xy 271.619266 -363.532122) (xy 271.576658 -363.451606) (xy 271.541332 -363.367639) (xy 271.513566 -363.280879)
			(xy 271.493576 -363.192004) (xy 271.481519 -363.10171) (xy 271.47749 -363.010704) (xy 261.753366 -363.010704)
			(xy 261.683662 -363.121068) (xy 261.578219 -363.273014) (xy 261.466293 -363.420249) (xy 261.348095 -363.562498)
			(xy 261.223845 -363.699494) (xy 261.093777 -363.830978) (xy 260.958136 -363.956705) (xy 260.817176 -364.076437)
			(xy 260.671161 -364.189951) (xy 260.629625 -364.219447) (xy 268.260316 -364.219447) (xy 268.260316 -364.155525)
			(xy 268.268327 -364.092107) (xy 268.284224 -364.030193) (xy 268.307756 -363.97076) (xy 268.33855 -363.914745)
			(xy 268.376123 -363.86303) (xy 268.41988 -363.816433) (xy 268.469133 -363.775688) (xy 268.523104 -363.741437)
			(xy 268.580943 -363.71422) (xy 268.641736 -363.694467) (xy 268.704526 -363.682489) (xy 268.768322 -363.678476)
			(xy 268.832118 -363.682489) (xy 268.894908 -363.694467) (xy 268.955701 -363.71422) (xy 269.01354 -363.741437)
			(xy 269.067511 -363.775688) (xy 269.116764 -363.816433) (xy 269.160521 -363.86303) (xy 269.198094 -363.914745)
			(xy 269.228888 -363.97076) (xy 269.25242 -364.030193) (xy 269.268317 -364.092107) (xy 269.276328 -364.155525)
			(xy 269.27683 -364.187486) (xy 269.276328 -364.219447) (xy 269.268317 -364.282865) (xy 269.25242 -364.344779)
			(xy 269.228888 -364.404212) (xy 269.198094 -364.460227) (xy 269.160521 -364.511942) (xy 269.116764 -364.558539)
			(xy 269.067511 -364.599284) (xy 269.01354 -364.633535) (xy 268.955701 -364.660752) (xy 268.894908 -364.680505)
			(xy 268.832118 -364.692483) (xy 268.768322 -364.696497) (xy 268.704526 -364.692483) (xy 268.641736 -364.680505)
			(xy 268.580943 -364.660752) (xy 268.523104 -364.633535) (xy 268.469133 -364.599284) (xy 268.41988 -364.558539)
			(xy 268.376123 -364.511942) (xy 268.33855 -364.460227) (xy 268.307756 -364.404212) (xy 268.284224 -364.344779)
			(xy 268.268327 -364.282865) (xy 268.260316 -364.219447) (xy 260.629625 -364.219447) (xy 260.520366 -364.297034)
			(xy 260.365074 -364.397483) (xy 260.205577 -364.491112) (xy 260.042173 -364.577743) (xy 259.87517 -364.657214)
			(xy 259.704881 -364.729377) (xy 259.531626 -364.794095) (xy 259.35573 -364.851247) (xy 259.177524 -364.900726)
			(xy 258.997341 -364.942438) (xy 258.81552 -364.976306) (xy 258.632404 -365.002267) (xy 258.448334 -365.02027)
			(xy 258.263657 -365.030283) (xy 258.07872 -365.032287) (xy 257.89387 -365.026277) (xy 257.709454 -365.012265)
			(xy 257.525817 -364.990278) (xy 257.343306 -364.960357) (xy 257.162262 -364.922558) (xy 256.983025 -364.876951)
			(xy 256.805932 -364.823624) (xy 256.631316 -364.762674) (xy 256.459504 -364.694218) (xy 256.290818 -364.618383)
			(xy 256.125576 -364.535312) (xy 255.964087 -364.445162) (xy 255.806656 -364.3481) (xy 255.653576 -364.244309)
			(xy 255.505137 -364.133985) (xy 255.361616 -364.017335) (xy 255.223282 -363.894576) (xy 255.090397 -363.76594)
			(xy 254.963208 -363.631669) (xy 254.841955 -363.492014) (xy 254.726866 -363.347238) (xy 254.618157 -363.197612)
			(xy 254.516031 -363.043417) (xy 254.42068 -362.884943) (xy 254.332284 -362.722487) (xy 254.251008 -362.556355)
			(xy 254.177005 -362.386858) (xy 254.110414 -362.214314) (xy 254.05136 -362.039048) (xy 253.999953 -361.861388)
			(xy 253.956291 -361.681667) (xy 253.920455 -361.500224) (xy 253.892513 -361.3174) (xy 253.872517 -361.133536)
			(xy 253.860504 -360.948978) (xy 253.856497 -360.764074) (xy 230.58628 -360.764074) (xy 230.58628 -362.9406)
			(xy 230.587296 -362.950252) (xy 230.588922 -362.957497) (xy 230.59576 -362.970669) (xy 230.600758 -362.97616)
			(xy 231.238255 -363.613657) (xy 246.799094 -363.613657) (xy 246.799094 -363.549735) (xy 246.807105 -363.486317)
			(xy 246.823002 -363.424403) (xy 246.846534 -363.36497) (xy 246.877328 -363.308955) (xy 246.914901 -363.25724)
			(xy 246.958658 -363.210643) (xy 247.007911 -363.169898) (xy 247.061882 -363.135647) (xy 247.119721 -363.10843)
			(xy 247.180514 -363.088677) (xy 247.243304 -363.076699) (xy 247.3071 -363.072686) (xy 247.370896 -363.076699)
			(xy 247.433686 -363.088677) (xy 247.494479 -363.10843) (xy 247.552318 -363.135647) (xy 247.606289 -363.169898)
			(xy 247.655542 -363.210643) (xy 247.699299 -363.25724) (xy 247.736872 -363.308955) (xy 247.767666 -363.36497)
			(xy 247.791198 -363.424403) (xy 247.807095 -363.486317) (xy 247.815106 -363.549735) (xy 247.815608 -363.581696)
			(xy 247.815106 -363.613657) (xy 247.807095 -363.677075) (xy 247.791198 -363.738989) (xy 247.767666 -363.798422)
			(xy 247.736872 -363.854437) (xy 247.699299 -363.906152) (xy 247.655542 -363.952749) (xy 247.606289 -363.993494)
			(xy 247.552318 -364.027745) (xy 247.494479 -364.054962) (xy 247.433686 -364.074715) (xy 247.370896 -364.086693)
			(xy 247.3071 -364.090707) (xy 247.243304 -364.086693) (xy 247.180514 -364.074715) (xy 247.119721 -364.054962)
			(xy 247.061882 -364.027745) (xy 247.007911 -363.993494) (xy 246.958658 -363.952749) (xy 246.914901 -363.906152)
			(xy 246.877328 -363.854437) (xy 246.846534 -363.798422) (xy 246.823002 -363.738989) (xy 246.807105 -363.677075)
			(xy 246.799094 -363.613657) (xy 231.238255 -363.613657) (xy 234.687829 -367.063231) (xy 271.555712 -367.063231)
			(xy 271.555712 -366.999309) (xy 271.563723 -366.935891) (xy 271.57962 -366.873977) (xy 271.603152 -366.814544)
			(xy 271.633946 -366.758529) (xy 271.671519 -366.706814) (xy 271.715276 -366.660217) (xy 271.764529 -366.619472)
			(xy 271.8185 -366.585221) (xy 271.876339 -366.558004) (xy 271.937132 -366.538251) (xy 271.999922 -366.526273)
			(xy 272.063718 -366.52226) (xy 272.127514 -366.526273) (xy 272.190304 -366.538251) (xy 272.251097 -366.558004)
			(xy 272.308936 -366.585221) (xy 272.362907 -366.619472) (xy 272.41216 -366.660217) (xy 272.455917 -366.706814)
			(xy 272.49349 -366.758529) (xy 272.524284 -366.814544) (xy 272.547816 -366.873977) (xy 272.563713 -366.935891)
			(xy 272.571724 -366.999309) (xy 272.572226 -367.03127) (xy 272.571724 -367.063231) (xy 272.563713 -367.126649)
			(xy 272.547816 -367.188563) (xy 272.524284 -367.247996) (xy 272.49349 -367.304011) (xy 272.455917 -367.355726)
			(xy 272.41216 -367.402323) (xy 272.362907 -367.443068) (xy 272.308936 -367.477319) (xy 272.251097 -367.504536)
			(xy 272.190304 -367.524289) (xy 272.127514 -367.536267) (xy 272.063718 -367.540281) (xy 271.999922 -367.536267)
			(xy 271.937132 -367.524289) (xy 271.876339 -367.504536) (xy 271.8185 -367.477319) (xy 271.764529 -367.443068)
			(xy 271.715276 -367.402323) (xy 271.671519 -367.355726) (xy 271.633946 -367.304011) (xy 271.603152 -367.247996)
			(xy 271.57962 -367.188563) (xy 271.563723 -367.126649) (xy 271.555712 -367.063231) (xy 234.687829 -367.063231)
			(xy 235.145072 -367.520474) (xy 235.150822 -367.52567) (xy 235.164655 -367.532642) (xy 235.17225 -367.53419)
			(xy 235.180632 -367.534952) (xy 238.099346 -367.534952) (xy 238.104645 -367.534817) (xy 238.115017 -367.532647)
			(xy 238.11992 -367.530634) (xy 238.129572 -367.526316) (xy 238.136684 -367.518188) (xy 238.139224 -367.515394)
			(xy 238.163953 -367.487719) (xy 238.220056 -367.439135) (xy 238.250984 -367.41862) (xy 238.275478 -367.403501)
			(xy 238.327217 -367.378272) (xy 238.381475 -367.359048) (xy 238.437557 -367.346076) (xy 238.494745 -367.339521)
			(xy 238.523526 -367.339118) (xy 238.524034 -367.339118) (xy 238.555992 -367.339622) (xy 238.619404 -367.347637)
			(xy 238.681311 -367.363535) (xy 238.740737 -367.387067) (xy 238.796746 -367.417862) (xy 238.848454 -367.455433)
			(xy 238.895045 -367.499188) (xy 238.935785 -367.548437) (xy 238.970032 -367.602404) (xy 238.997245 -367.660238)
			(xy 239.016995 -367.721026) (xy 239.028971 -367.78381) (xy 239.032985 -367.8476) (xy 239.029406 -367.904479)
			(xy 239.294664 -367.904479) (xy 239.294664 -367.840557) (xy 239.302675 -367.777139) (xy 239.318572 -367.715225)
			(xy 239.342104 -367.655792) (xy 239.372898 -367.599777) (xy 239.410471 -367.548062) (xy 239.454228 -367.501465)
			(xy 239.503481 -367.46072) (xy 239.557452 -367.426469) (xy 239.615291 -367.399252) (xy 239.676084 -367.379499)
			(xy 239.738874 -367.367521) (xy 239.80267 -367.363508) (xy 239.866466 -367.367521) (xy 239.929256 -367.379499)
			(xy 239.990049 -367.399252) (xy 240.047888 -367.426469) (xy 240.101859 -367.46072) (xy 240.151112 -367.501465)
			(xy 240.194869 -367.548062) (xy 240.232442 -367.599777) (xy 240.263236 -367.655792) (xy 240.286768 -367.715225)
			(xy 240.302665 -367.777139) (xy 240.310676 -367.840557) (xy 240.311178 -367.872518) (xy 240.310676 -367.904479)
			(xy 240.310034 -367.909559) (xy 240.592858 -367.909559) (xy 240.592858 -367.845637) (xy 240.600869 -367.782219)
			(xy 240.616766 -367.720305) (xy 240.640298 -367.660872) (xy 240.671092 -367.604857) (xy 240.708665 -367.553142)
			(xy 240.752422 -367.506545) (xy 240.801675 -367.4658) (xy 240.855646 -367.431549) (xy 240.913485 -367.404332)
			(xy 240.974278 -367.384579) (xy 241.037068 -367.372601) (xy 241.100864 -367.368588) (xy 241.16466 -367.372601)
			(xy 241.22745 -367.384579) (xy 241.288243 -367.404332) (xy 241.346082 -367.431549) (xy 241.400053 -367.4658)
			(xy 241.449306 -367.506545) (xy 241.493063 -367.553142) (xy 241.530636 -367.604857) (xy 241.56143 -367.660872)
			(xy 241.584962 -367.720305) (xy 241.600859 -367.782219) (xy 241.60887 -367.845637) (xy 241.609253 -367.87)
			(xy 241.944346 -367.87) (xy 241.948361 -367.806198) (xy 241.96034 -367.743401) (xy 241.980095 -367.682602)
			(xy 242.007315 -367.624758) (xy 242.04157 -367.570781) (xy 242.082321 -367.521524) (xy 242.128923 -367.477763)
			(xy 242.180643 -367.440187) (xy 242.236665 -367.40939) (xy 242.296104 -367.385858) (xy 242.358025 -367.369961)
			(xy 242.42145 -367.36195) (xy 242.453414 -367.36147) (xy 242.483827 -367.361886) (xy 242.54422 -367.36914)
			(xy 242.603316 -367.383544) (xy 242.660274 -367.404891) (xy 242.71428 -367.432878) (xy 242.764564 -367.467104)
			(xy 242.810407 -367.507082) (xy 242.831112 -367.529364) (xy 242.838986 -367.538) (xy 242.860576 -367.54689)
			(xy 242.951762 -367.54054) (xy 242.963272 -367.539327) (xy 242.98339 -367.52793) (xy 242.99037 -367.518696)
			(xy 243.008192 -367.493534) (xy 243.04894 -367.447258) (xy 243.094987 -367.40625) (xy 243.145657 -367.371115)
			(xy 243.200205 -367.342367) (xy 243.257831 -367.320429) (xy 243.317687 -367.305623) (xy 243.378894 -367.298167)
			(xy 243.409724 -367.297716) (xy 243.44012 -367.298167) (xy 243.500477 -367.305421) (xy 243.559538 -367.319823)
			(xy 243.61646 -367.341167) (xy 243.67043 -367.369148) (xy 243.720676 -367.403366) (xy 243.766482 -367.443334)
			(xy 243.787168 -367.46561) (xy 243.793855 -367.472434) (xy 243.810963 -367.480914) (xy 243.820442 -367.48212)
			(xy 243.899182 -367.488978) (xy 243.91747 -367.483644) (xy 243.92509 -367.477548) (xy 243.951986 -367.457257)
			(xy 244.010132 -367.423222) (xy 244.072263 -367.397163) (xy 244.137291 -367.379536) (xy 244.204077 -367.370648)
			(xy 244.237764 -367.370106) (xy 244.26902 -367.370627) (xy 244.331054 -367.378339) (xy 244.391677 -367.393591)
			(xy 244.449976 -367.416153) (xy 244.505073 -367.445684) (xy 244.53088 -367.463324) (xy 244.538431 -367.468146)
			(xy 244.55571 -367.472828) (xy 244.564662 -367.472468) (xy 244.594634 -367.469674) (xy 244.603371 -367.468529)
			(xy 244.619345 -367.461113) (xy 244.625876 -367.455196) (xy 244.649781 -367.43231) (xy 244.702454 -367.392246)
			(xy 244.759881 -367.359357) (xy 244.821092 -367.3342) (xy 244.885049 -367.3172) (xy 244.950673 -367.308645)
			(xy 244.983762 -367.30813) (xy 245.012775 -367.308551) (xy 245.070423 -367.315162) (xy 245.126944 -367.328289)
			(xy 245.181604 -367.347763) (xy 245.233693 -367.37333) (xy 245.258336 -367.388648) (xy 245.267259 -367.393737)
			(xy 245.287502 -367.39711) (xy 245.307461 -367.392333) (xy 245.315994 -367.386616) (xy 245.342349 -367.367739)
			(xy 245.398921 -367.336084) (xy 245.459062 -367.311884) (xy 245.521793 -367.295534) (xy 245.586094 -367.287298)
			(xy 245.618508 -367.286794) (xy 245.652845 -367.287357) (xy 245.720894 -367.2966) (xy 245.78708 -367.314918)
			(xy 245.850199 -367.341977) (xy 245.909101 -367.377284) (xy 245.936262 -367.3983) (xy 245.945706 -367.405102)
			(xy 245.968411 -367.410099) (xy 245.99099 -367.404562) (xy 246.00027 -367.397538) (xy 246.023155 -367.379078)
			(xy 246.072409 -367.346968) (xy 246.12504 -367.320756) (xy 246.180344 -367.300793) (xy 246.237583 -367.287345)
			(xy 246.295991 -367.280593) (xy 246.32539 -367.28019) (xy 246.357353 -367.280674) (xy 246.420774 -367.288685)
			(xy 246.482691 -367.304582) (xy 246.542128 -367.328113) (xy 246.598146 -367.358909) (xy 246.649863 -367.396482)
			(xy 246.696463 -367.440242) (xy 246.737211 -367.489497) (xy 246.771464 -367.54347) (xy 246.798683 -367.601312)
			(xy 246.818437 -367.662108) (xy 246.830416 -367.724901) (xy 246.83443 -367.7887) (xy 246.830416 -367.852499)
			(xy 246.818437 -367.915292) (xy 246.798683 -367.976088) (xy 246.771464 -368.03393) (xy 246.737211 -368.087903)
			(xy 246.696463 -368.137158) (xy 246.649863 -368.180918) (xy 246.598146 -368.218491) (xy 246.542128 -368.249287)
			(xy 246.482691 -368.272818) (xy 246.420774 -368.288715) (xy 246.357353 -368.296726) (xy 246.32539 -368.297206)
			(xy 246.291053 -368.296645) (xy 246.223004 -368.287401) (xy 246.156818 -368.269083) (xy 246.093699 -368.242023)
			(xy 246.034797 -368.206716) (xy 246.007636 -368.1857) (xy 245.998193 -368.178897) (xy 245.975487 -368.1739)
			(xy 245.952908 -368.179437) (xy 245.943628 -368.186462) (xy 245.920744 -368.204923) (xy 245.87149 -368.237033)
			(xy 245.818858 -368.263245) (xy 245.763554 -368.283208) (xy 245.706315 -368.296655) (xy 245.647907 -368.303407)
			(xy 245.618508 -368.30381) (xy 245.589495 -368.303397) (xy 245.531847 -368.296784) (xy 245.475326 -368.283654)
			(xy 245.420666 -368.264179) (xy 245.368577 -368.23861) (xy 245.343934 -368.223292) (xy 245.335021 -368.218184)
			(xy 245.314772 -368.214824) (xy 245.294811 -368.219607) (xy 245.286276 -368.225324) (xy 245.259925 -368.244207)
			(xy 245.203352 -368.275863) (xy 245.143211 -368.300062) (xy 245.080479 -368.316411) (xy 245.016176 -368.324643)
			(xy 244.983762 -368.325146) (xy 244.952506 -368.324621) (xy 244.890472 -368.316911) (xy 244.829848 -368.30166)
			(xy 244.77155 -368.279099) (xy 244.716453 -368.249568) (xy 244.690646 -368.231928) (xy 244.68311 -368.227078)
			(xy 244.665819 -368.222412) (xy 244.656864 -368.222784) (xy 244.626892 -368.225578) (xy 244.61816 -368.226747)
			(xy 244.602185 -368.234147) (xy 244.59565 -368.240056) (xy 244.57177 -368.262969) (xy 244.519092 -368.303031)
			(xy 244.46166 -368.335918) (xy 244.400444 -368.36107) (xy 244.336482 -368.378064) (xy 244.270855 -368.386612)
			(xy 244.237764 -368.387122) (xy 244.207368 -368.386667) (xy 244.147012 -368.379412) (xy 244.087951 -368.36501)
			(xy 244.03103 -368.343666) (xy 243.97706 -368.315686) (xy 243.926813 -368.281469) (xy 243.881007 -368.241503)
			(xy 243.86032 -368.219228) (xy 243.853632 -368.212404) (xy 243.836525 -368.203923) (xy 243.827046 -368.202718)
			(xy 243.748306 -368.19586) (xy 243.730018 -368.201194) (xy 243.722398 -368.20729) (xy 243.69551 -368.227592)
			(xy 243.637361 -368.261623) (xy 243.575228 -368.28768) (xy 243.510199 -368.305305) (xy 243.443412 -368.31419)
			(xy 243.409724 -368.314732) (xy 243.379311 -368.314289) (xy 243.31892 -368.307039) (xy 243.259824 -368.29264)
			(xy 243.202867 -368.271297) (xy 243.14886 -368.243315) (xy 243.098576 -368.209092) (xy 243.052731 -368.169118)
			(xy 243.032026 -368.146838) (xy 243.024152 -368.138202) (xy 243.002562 -368.129312) (xy 242.911376 -368.135662)
			(xy 242.899869 -368.136895) (xy 242.87975 -368.148277) (xy 242.872768 -368.157506) (xy 242.854987 -368.182697)
			(xy 242.814232 -368.228973) (xy 242.768179 -368.269979) (xy 242.717503 -368.305112) (xy 242.662949 -368.333856)
			(xy 242.605318 -368.355789) (xy 242.545457 -368.37059) (xy 242.484246 -368.378039) (xy 242.453414 -368.378486)
			(xy 242.42145 -368.37805) (xy 242.358025 -368.370039) (xy 242.296104 -368.354142) (xy 242.236665 -368.33061)
			(xy 242.180643 -368.299813) (xy 242.128923 -368.262237) (xy 242.082321 -368.218476) (xy 242.04157 -368.169219)
			(xy 242.007315 -368.115242) (xy 241.980095 -368.057398) (xy 241.96034 -367.996599) (xy 241.948361 -367.933802)
			(xy 241.944346 -367.87) (xy 241.609253 -367.87) (xy 241.609372 -367.877598) (xy 241.60887 -367.909559)
			(xy 241.600859 -367.972977) (xy 241.584962 -368.034891) (xy 241.56143 -368.094324) (xy 241.530636 -368.150339)
			(xy 241.493063 -368.202054) (xy 241.449306 -368.248651) (xy 241.400053 -368.289396) (xy 241.346082 -368.323647)
			(xy 241.288243 -368.350864) (xy 241.22745 -368.370617) (xy 241.16466 -368.382595) (xy 241.100864 -368.386609)
			(xy 241.037068 -368.382595) (xy 240.974278 -368.370617) (xy 240.913485 -368.350864) (xy 240.855646 -368.323647)
			(xy 240.801675 -368.289396) (xy 240.752422 -368.248651) (xy 240.708665 -368.202054) (xy 240.671092 -368.150339)
			(xy 240.640298 -368.094324) (xy 240.616766 -368.034891) (xy 240.600869 -367.972977) (xy 240.592858 -367.909559)
			(xy 240.310034 -367.909559) (xy 240.302665 -367.967897) (xy 240.286768 -368.029811) (xy 240.263236 -368.089244)
			(xy 240.232442 -368.145259) (xy 240.194869 -368.196974) (xy 240.151112 -368.243571) (xy 240.101859 -368.284316)
			(xy 240.047888 -368.318567) (xy 239.990049 -368.345784) (xy 239.929256 -368.365537) (xy 239.866466 -368.377515)
			(xy 239.80267 -368.381529) (xy 239.738874 -368.377515) (xy 239.676084 -368.365537) (xy 239.615291 -368.345784)
			(xy 239.557452 -368.318567) (xy 239.503481 -368.284316) (xy 239.454228 -368.243571) (xy 239.410471 -368.196974)
			(xy 239.372898 -368.145259) (xy 239.342104 -368.089244) (xy 239.318572 -368.029811) (xy 239.302675 -367.967897)
			(xy 239.294664 -367.904479) (xy 239.029406 -367.904479) (xy 239.028971 -367.91139) (xy 239.016995 -367.974174)
			(xy 238.997245 -368.034962) (xy 238.970032 -368.092796) (xy 238.935785 -368.146763) (xy 238.895045 -368.196012)
			(xy 238.848454 -368.239767) (xy 238.796746 -368.277338) (xy 238.740737 -368.308133) (xy 238.681311 -368.331665)
			(xy 238.619404 -368.347563) (xy 238.555992 -368.355578) (xy 238.524034 -368.356134) (xy 238.492814 -368.35566)
			(xy 238.430843 -368.348015) (xy 238.370276 -368.332835) (xy 238.312024 -368.310349) (xy 238.256966 -368.280897)
			(xy 238.205931 -368.244921) (xy 238.159688 -368.202963) (xy 238.13897 -368.179604) (xy 238.1377 -368.17808)
			(xy 238.136684 -368.177064) (xy 238.133128 -368.173254) (xy 238.124492 -368.16665) (xy 238.11992 -368.164618)
			(xy 238.115022 -368.162589) (xy 238.104647 -368.160418) (xy 238.099346 -368.1603) (xy 235.029248 -368.1603)
			(xy 235.004721 -368.159802) (xy 234.956273 -368.152105) (xy 234.90962 -368.13694) (xy 234.865907 -368.114678)
			(xy 234.826205 -368.085864) (xy 234.808522 -368.06886) (xy 232.643172 -365.90351) (xy 232.642156 -365.902494)
			(xy 232.635655 -365.896865) (xy 232.619941 -365.889906) (xy 232.602812 -365.888495) (xy 232.594404 -365.890302)
			(xy 232.51033 -365.916718) (xy 232.506012 -365.917988) (xy 232.499402 -365.920264) (xy 232.487681 -365.927875)
			(xy 232.482898 -365.932974) (xy 232.478326 -365.938054) (xy 232.472484 -365.9505) (xy 232.471214 -365.957612)
			(xy 232.465094 -365.989295) (xy 232.445892 -366.050902) (xy 232.419051 -366.109585) (xy 232.385004 -366.164402)
			(xy 232.344295 -366.214471) (xy 232.297581 -366.25899) (xy 232.245611 -366.297241) (xy 232.189219 -366.328612)
			(xy 232.129313 -366.352598) (xy 232.066854 -366.368814) (xy 232.002845 -366.376999) (xy 231.97058 -366.377474)
			(xy 231.940735 -366.377045) (xy 231.881455 -366.370056) (xy 231.8234 -366.356178) (xy 231.767369 -366.3356)
			(xy 231.714132 -366.308605) (xy 231.664419 -366.275566) (xy 231.641396 -366.25657) (xy 231.633776 -366.25022)
			(xy 231.625902 -366.247426) (xy 231.621356 -366.245908) (xy 231.611898 -366.244372) (xy 231.607106 -366.244378)
			(xy 231.547924 -366.24641) (xy 231.538272 -366.246664) (xy 231.504998 -366.260888) (xy 231.498394 -366.266984)
			(xy 231.474756 -366.288481) (xy 231.423055 -366.326023) (xy 231.367056 -366.356791) (xy 231.307643 -366.380298)
			(xy 231.245753 -366.396175) (xy 231.182361 -366.404171) (xy 231.150414 -366.404652) (xy 231.118448 -366.404172)
			(xy 231.055021 -366.396161) (xy 230.993098 -366.380263) (xy 230.933655 -366.35673) (xy 230.877631 -366.325931)
			(xy 230.825909 -366.288354) (xy 230.779305 -366.244591) (xy 230.738553 -366.195332) (xy 230.704296 -366.141353)
			(xy 230.677075 -366.083506) (xy 230.657319 -366.022704) (xy 230.645339 -365.959905) (xy 230.641324 -365.8961)
			(xy 230.645339 -365.832295) (xy 230.657319 -365.769496) (xy 230.677075 -365.708694) (xy 230.704296 -365.650847)
			(xy 230.738553 -365.596868) (xy 230.779305 -365.547609) (xy 230.825909 -365.503846) (xy 230.877631 -365.466269)
			(xy 230.933655 -365.43547) (xy 230.993098 -365.411937) (xy 231.055021 -365.396039) (xy 231.118448 -365.388028)
			(xy 231.150414 -365.387636) (xy 231.180259 -365.388065) (xy 231.239539 -365.395053) (xy 231.297594 -365.408931)
			(xy 231.353625 -365.429509) (xy 231.406863 -365.456503) (xy 231.456575 -365.489543) (xy 231.479598 -365.50854)
			(xy 231.487218 -365.51489) (xy 231.495092 -365.517684) (xy 231.499638 -365.519202) (xy 231.509096 -365.520739)
			(xy 231.513888 -365.520732) (xy 231.57307 -365.5187) (xy 231.582722 -365.518446) (xy 231.615996 -365.504222)
			(xy 231.622346 -365.49838) (xy 231.622854 -365.497872) (xy 231.644588 -365.478097) (xy 231.691829 -365.443151)
			(xy 231.742784 -365.413885) (xy 231.796773 -365.390689) (xy 231.853077 -365.373872) (xy 231.881934 -365.368332)
			(xy 231.882188 -365.368332) (xy 231.88897 -365.366849) (xy 231.901456 -365.360794) (xy 231.906826 -365.356394)
			(xy 231.911906 -365.351822) (xy 231.919272 -365.340392) (xy 231.922828 -365.329216) (xy 231.949244 -365.245142)
			(xy 231.951116 -365.236738) (xy 231.949732 -365.219587) (xy 231.942715 -365.203877) (xy 231.937052 -365.19739)
			(xy 231.936036 -365.196374) (xy 230.619554 -363.879892) (xy 230.614131 -363.874864) (xy 230.601091 -363.867903)
			(xy 230.5939 -363.866176) (xy 230.586788 -363.864652) (xy 230.571802 -363.866176) (xy 230.560626 -363.870748)
			(xy 230.552944 -363.875131) (xy 230.540924 -363.888089) (xy 230.534028 -363.904361) (xy 230.533194 -363.913166)
			(xy 230.533194 -367.50625) (xy 230.533388 -367.51156) (xy 230.535699 -367.521929) (xy 230.537766 -367.526824)
			(xy 230.540306 -367.531904) (xy 230.543901 -367.53749) (xy 230.553419 -367.546752) (xy 230.559102 -367.550192)
			(xy 230.60787 -367.574322) (xy 230.642922 -367.591594) (xy 230.649385 -367.594458) (xy 230.663302 -367.596905)
			(xy 230.670354 -367.59642) (xy 230.677466 -367.595912) (xy 230.690166 -367.590832) (xy 230.696262 -367.58626)
			(xy 230.722995 -367.566449) (xy 230.780632 -367.533201) (xy 230.842115 -367.507758) (xy 230.906392 -367.490557)
			(xy 230.972364 -367.481891) (xy 231.005634 -367.481358) (xy 231.006142 -367.481358) (xy 231.038103 -367.481863)
			(xy 231.101522 -367.489879) (xy 231.163435 -367.50578) (xy 231.222868 -367.529316) (xy 231.278882 -367.560114)
			(xy 231.330595 -367.597689) (xy 231.377191 -367.64145) (xy 231.417936 -367.690705) (xy 231.452186 -367.744678)
			(xy 231.479401 -367.802518) (xy 231.499154 -367.863312) (xy 231.511131 -367.926103) (xy 231.515145 -367.9899)
			(xy 231.511131 -368.053697) (xy 231.499154 -368.116488) (xy 231.479401 -368.177282) (xy 231.452186 -368.235122)
			(xy 231.417936 -368.289095) (xy 231.377191 -368.33835) (xy 231.330595 -368.382111) (xy 231.278882 -368.419686)
			(xy 231.222868 -368.450484) (xy 231.163435 -368.47402) (xy 231.101522 -368.489921) (xy 231.038103 -368.497937)
			(xy 231.006142 -368.498374) (xy 231.005634 -368.498374) (xy 230.972645 -368.497832) (xy 230.907226 -368.489266)
			(xy 230.843464 -368.472311) (xy 230.78243 -368.447254) (xy 230.725149 -368.414513) (xy 230.698548 -368.394996)
			(xy 230.69677 -368.393472) (xy 230.681276 -368.38382) (xy 230.67772 -368.381788) (xy 230.669256 -368.377866)
			(xy 230.650733 -368.375788) (xy 230.632699 -368.380499) (xy 230.624888 -368.385598) (xy 230.620062 -368.389662)
			(xy 230.602282 -368.405918) (xy 230.590852 -368.413792) (xy 230.590598 -368.413792) (xy 230.561642 -368.42827)
			(xy 230.554535 -368.432083) (xy 230.543 -368.443345) (xy 230.539036 -368.450368) (xy 230.536337 -368.455898)
			(xy 230.533377 -368.467839) (xy 230.533194 -368.47399) (xy 230.533194 -369.039097) (xy 245.74982 -369.039097)
			(xy 245.74982 -368.975175) (xy 245.757831 -368.911757) (xy 245.773728 -368.849843) (xy 245.79726 -368.79041)
			(xy 245.828054 -368.734395) (xy 245.865627 -368.68268) (xy 245.909384 -368.636083) (xy 245.958637 -368.595338)
			(xy 246.012608 -368.561087) (xy 246.070447 -368.53387) (xy 246.13124 -368.514117) (xy 246.19403 -368.502139)
			(xy 246.257826 -368.498126) (xy 246.321622 -368.502139) (xy 246.384412 -368.514117) (xy 246.445205 -368.53387)
			(xy 246.503044 -368.561087) (xy 246.557015 -368.595338) (xy 246.606268 -368.636083) (xy 246.646737 -368.679179)
			(xy 247.320556 -368.679179) (xy 247.320556 -368.615257) (xy 247.328567 -368.551839) (xy 247.344464 -368.489925)
			(xy 247.367996 -368.430492) (xy 247.39879 -368.374477) (xy 247.436363 -368.322762) (xy 247.48012 -368.276165)
			(xy 247.529373 -368.23542) (xy 247.583344 -368.201169) (xy 247.641183 -368.173952) (xy 247.701976 -368.154199)
			(xy 247.764766 -368.142221) (xy 247.828562 -368.138208) (xy 247.892358 -368.142221) (xy 247.955148 -368.154199)
			(xy 248.015941 -368.173952) (xy 248.07378 -368.201169) (xy 248.127751 -368.23542) (xy 248.177004 -368.276165)
			(xy 248.220761 -368.322762) (xy 248.258334 -368.374477) (xy 248.289128 -368.430492) (xy 248.31266 -368.489925)
			(xy 248.328557 -368.551839) (xy 248.336568 -368.615257) (xy 248.33707 -368.647218) (xy 248.336568 -368.679179)
			(xy 248.330857 -368.724391) (xy 248.60986 -368.724391) (xy 248.60986 -368.660469) (xy 248.617871 -368.597051)
			(xy 248.633768 -368.535137) (xy 248.6573 -368.475704) (xy 248.688094 -368.419689) (xy 248.725667 -368.367974)
			(xy 248.769424 -368.321377) (xy 248.818677 -368.280632) (xy 248.872648 -368.246381) (xy 248.930487 -368.219164)
			(xy 248.99128 -368.199411) (xy 249.05407 -368.187433) (xy 249.117866 -368.18342) (xy 249.181662 -368.187433)
			(xy 249.244452 -368.199411) (xy 249.305245 -368.219164) (xy 249.363084 -368.246381) (xy 249.417055 -368.280632)
			(xy 249.466308 -368.321377) (xy 249.510065 -368.367974) (xy 249.547638 -368.419689) (xy 249.578432 -368.475704)
			(xy 249.601964 -368.535137) (xy 249.617861 -368.597051) (xy 249.625872 -368.660469) (xy 249.626374 -368.69243)
			(xy 249.625872 -368.724391) (xy 249.617861 -368.787809) (xy 249.610854 -368.8151) (xy 271.35018 -368.8151)
			(xy 271.354195 -368.751299) (xy 271.366174 -368.688505) (xy 271.38593 -368.627707) (xy 271.41315 -368.569865)
			(xy 271.447406 -368.51589) (xy 271.488157 -368.466635) (xy 271.534759 -368.422877) (xy 271.58648 -368.385304)
			(xy 271.642501 -368.354511) (xy 271.701941 -368.330982) (xy 271.763861 -368.315089) (xy 271.827284 -368.307082)
			(xy 271.859248 -368.306604) (xy 271.893816 -368.307209) (xy 271.962313 -368.316585) (xy 272.028907 -368.335157)
			(xy 272.09237 -368.362582) (xy 272.151531 -368.398356) (xy 272.17878 -368.419634) (xy 272.186072 -368.425017)
			(xy 272.203246 -368.430758) (xy 272.212308 -368.43081) (xy 272.242788 -368.430048) (xy 272.251847 -368.429367)
			(xy 272.26864 -368.422478) (xy 272.275554 -368.416586) (xy 272.299063 -368.395539) (xy 272.350402 -368.358852)
			(xy 272.405883 -368.328794) (xy 272.464656 -368.305827) (xy 272.525817 -368.290303) (xy 272.588428 -368.282461)
			(xy 272.619978 -368.281966) (xy 272.653018 -368.282473) (xy 272.718543 -368.291025) (xy 272.782406 -368.308)
			(xy 272.843529 -368.333112) (xy 272.900881 -368.365937) (xy 272.953492 -368.405921) (xy 272.977356 -368.428778)
			(xy 272.97761 -368.429032) (xy 272.986132 -368.436585) (xy 273.007645 -368.443962) (xy 273.019012 -368.443256)
			(xy 273.109182 -368.432588) (xy 273.12874 -368.420396) (xy 273.134836 -368.41049) (xy 273.15236 -368.38353)
			(xy 273.193105 -368.333786) (xy 273.239794 -368.289574) (xy 273.291682 -368.251597) (xy 273.347942 -368.220462)
			(xy 273.407678 -368.196664) (xy 273.469936 -368.180584) (xy 273.533724 -368.172478) (xy 273.565874 -368.171984)
			(xy 273.597837 -368.172479) (xy 273.661259 -368.180488) (xy 273.723177 -368.196383) (xy 273.746236 -368.205512)
			(xy 290.223954 -368.205512) (xy 290.228025 -368.14989) (xy 290.240151 -368.095453) (xy 290.260074 -368.043362)
			(xy 290.28737 -367.994727) (xy 290.321456 -367.950584) (xy 290.361605 -367.911875) (xy 290.406963 -367.879424)
			(xy 290.456563 -367.853923) (xy 290.509347 -367.835916) (xy 290.56419 -367.825786) (xy 290.619924 -367.823749)
			(xy 290.675361 -367.829849) (xy 290.729318 -367.843955) (xy 290.780647 -367.865767) (xy 290.828253 -367.894821)
			(xy 290.871121 -367.930496) (xy 290.908338 -367.972033) (xy 290.939111 -368.018546) (xy 290.962783 -368.069043)
			(xy 290.978851 -368.12245) (xy 290.986971 -368.177626) (xy 290.98748 -368.205512) (xy 290.986971 -368.233398)
			(xy 290.978851 -368.288574) (xy 290.962783 -368.341981) (xy 290.939111 -368.392478) (xy 290.908338 -368.438991)
			(xy 290.871121 -368.480528) (xy 290.828253 -368.516203) (xy 290.780647 -368.545257) (xy 290.729318 -368.567069)
			(xy 290.675361 -368.581175) (xy 290.619924 -368.587275) (xy 290.56419 -368.585238) (xy 290.509347 -368.575108)
			(xy 290.456563 -368.557101) (xy 290.406963 -368.5316) (xy 290.361605 -368.499149) (xy 290.321456 -368.46044)
			(xy 290.28737 -368.416297) (xy 290.260074 -368.367662) (xy 290.240151 -368.315571) (xy 290.228025 -368.261134)
			(xy 290.223954 -368.205512) (xy 273.746236 -368.205512) (xy 273.782615 -368.219914) (xy 273.838634 -368.250708)
			(xy 273.890353 -368.288281) (xy 273.936954 -368.33204) (xy 273.977703 -368.381295) (xy 274.011957 -368.435269)
			(xy 274.039176 -368.49311) (xy 274.058931 -368.553907) (xy 274.070909 -368.6167) (xy 274.074924 -368.6805)
			(xy 274.070909 -368.7443) (xy 274.058931 -368.807093) (xy 274.039176 -368.86789) (xy 274.011957 -368.925731)
			(xy 273.977703 -368.979705) (xy 273.936954 -369.02896) (xy 273.890353 -369.072719) (xy 273.838634 -369.110292)
			(xy 273.782615 -369.141086) (xy 273.723177 -369.164617) (xy 273.661259 -369.180512) (xy 273.620192 -369.185698)
			(xy 288.630866 -369.185698) (xy 288.634937 -369.130076) (xy 288.647063 -369.075639) (xy 288.666986 -369.023548)
			(xy 288.694282 -368.974913) (xy 288.728368 -368.93077) (xy 288.768517 -368.892061) (xy 288.813875 -368.85961)
			(xy 288.863475 -368.834109) (xy 288.916259 -368.816102) (xy 288.971102 -368.805972) (xy 289.026836 -368.803935)
			(xy 289.082273 -368.810035) (xy 289.13623 -368.824141) (xy 289.187559 -368.845953) (xy 289.235165 -368.875007)
			(xy 289.278033 -368.910682) (xy 289.31525 -368.952219) (xy 289.346023 -368.998732) (xy 289.369695 -369.049229)
			(xy 289.385763 -369.102636) (xy 289.393883 -369.157812) (xy 289.394392 -369.185698) (xy 289.393883 -369.213584)
			(xy 289.385763 -369.26876) (xy 289.369695 -369.322167) (xy 289.346023 -369.372664) (xy 289.31525 -369.419177)
			(xy 289.278033 -369.460714) (xy 289.235165 -369.496389) (xy 289.187559 -369.525443) (xy 289.13623 -369.547255)
			(xy 289.082273 -369.561361) (xy 289.026836 -369.567461) (xy 288.971102 -369.565424) (xy 288.916259 -369.555294)
			(xy 288.863475 -369.537287) (xy 288.813875 -369.511786) (xy 288.768517 -369.479335) (xy 288.728368 -369.440626)
			(xy 288.694282 -369.396483) (xy 288.666986 -369.347848) (xy 288.647063 -369.295757) (xy 288.634937 -369.24132)
			(xy 288.630866 -369.185698) (xy 273.620192 -369.185698) (xy 273.597837 -369.188521) (xy 273.565874 -369.189)
			(xy 273.532835 -369.188441) (xy 273.467313 -369.179897) (xy 273.403452 -369.16293) (xy 273.342329 -369.137828)
			(xy 273.284977 -369.105013) (xy 273.232362 -369.06504) (xy 273.208496 -369.042188) (xy 273.208242 -369.041934)
			(xy 273.199703 -369.034404) (xy 273.178203 -369.027015) (xy 273.16684 -369.02771) (xy 273.07667 -369.038378)
			(xy 273.057112 -369.05057) (xy 273.051016 -369.060476) (xy 273.033547 -369.087473) (xy 272.992792 -369.137214)
			(xy 272.946093 -369.181423) (xy 272.894197 -369.219395) (xy 272.837929 -369.250525) (xy 272.778187 -369.274317)
			(xy 272.715923 -369.290391) (xy 272.652131 -369.298491) (xy 272.619978 -369.298982) (xy 272.585409 -369.298422)
			(xy 272.51691 -369.289036) (xy 272.450315 -369.270453) (xy 272.386852 -369.243018) (xy 272.327693 -369.207235)
			(xy 272.300446 -369.185952) (xy 272.293176 -369.180536) (xy 272.275985 -369.174816) (xy 272.266918 -369.174776)
			(xy 272.236438 -369.175538) (xy 272.227375 -369.176188) (xy 272.210583 -369.183099) (xy 272.203672 -369.189)
			(xy 272.18015 -369.210032) (xy 272.128815 -369.246721) (xy 272.073336 -369.276782) (xy 272.014566 -369.299752)
			(xy 271.953407 -369.315278) (xy 271.890797 -369.323123) (xy 271.859248 -369.32362) (xy 271.827284 -369.323118)
			(xy 271.763861 -369.315111) (xy 271.701941 -369.299218) (xy 271.642501 -369.275689) (xy 271.58648 -369.244896)
			(xy 271.534759 -369.207323) (xy 271.488157 -369.163565) (xy 271.447406 -369.11431) (xy 271.41315 -369.060335)
			(xy 271.38593 -369.002493) (xy 271.366174 -368.941695) (xy 271.354195 -368.878901) (xy 271.35018 -368.8151)
			(xy 249.610854 -368.8151) (xy 249.601964 -368.849723) (xy 249.578432 -368.909156) (xy 249.547638 -368.965171)
			(xy 249.510065 -369.016886) (xy 249.466308 -369.063483) (xy 249.417055 -369.104228) (xy 249.363084 -369.138479)
			(xy 249.305245 -369.165696) (xy 249.244452 -369.185449) (xy 249.181662 -369.197427) (xy 249.117866 -369.201441)
			(xy 249.05407 -369.197427) (xy 248.99128 -369.185449) (xy 248.930487 -369.165696) (xy 248.872648 -369.138479)
			(xy 248.818677 -369.104228) (xy 248.769424 -369.063483) (xy 248.725667 -369.016886) (xy 248.688094 -368.965171)
			(xy 248.6573 -368.909156) (xy 248.633768 -368.849723) (xy 248.617871 -368.787809) (xy 248.60986 -368.724391)
			(xy 248.330857 -368.724391) (xy 248.328557 -368.742597) (xy 248.31266 -368.804511) (xy 248.289128 -368.863944)
			(xy 248.258334 -368.919959) (xy 248.220761 -368.971674) (xy 248.177004 -369.018271) (xy 248.127751 -369.059016)
			(xy 248.07378 -369.093267) (xy 248.015941 -369.120484) (xy 247.955148 -369.140237) (xy 247.892358 -369.152215)
			(xy 247.828562 -369.156229) (xy 247.764766 -369.152215) (xy 247.701976 -369.140237) (xy 247.641183 -369.120484)
			(xy 247.583344 -369.093267) (xy 247.529373 -369.059016) (xy 247.48012 -369.018271) (xy 247.436363 -368.971674)
			(xy 247.39879 -368.919959) (xy 247.367996 -368.863944) (xy 247.344464 -368.804511) (xy 247.328567 -368.742597)
			(xy 247.320556 -368.679179) (xy 246.646737 -368.679179) (xy 246.650025 -368.68268) (xy 246.687598 -368.734395)
			(xy 246.718392 -368.79041) (xy 246.741924 -368.849843) (xy 246.757821 -368.911757) (xy 246.765832 -368.975175)
			(xy 246.766334 -369.007136) (xy 246.765832 -369.039097) (xy 246.757821 -369.102515) (xy 246.741924 -369.164429)
			(xy 246.718392 -369.223862) (xy 246.687598 -369.279877) (xy 246.650025 -369.331592) (xy 246.606268 -369.378189)
			(xy 246.557015 -369.418934) (xy 246.503044 -369.453185) (xy 246.445205 -369.480402) (xy 246.384412 -369.500155)
			(xy 246.321622 -369.512133) (xy 246.257826 -369.516147) (xy 246.19403 -369.512133) (xy 246.13124 -369.500155)
			(xy 246.070447 -369.480402) (xy 246.012608 -369.453185) (xy 245.958637 -369.418934) (xy 245.909384 -369.378189)
			(xy 245.865627 -369.331592) (xy 245.828054 -369.279877) (xy 245.79726 -369.223862) (xy 245.773728 -369.164429)
			(xy 245.757831 -369.102515) (xy 245.74982 -369.039097) (xy 230.533194 -369.039097) (xy 230.533194 -369.613688)
			(xy 230.533274 -369.617897) (xy 230.534676 -369.626198) (xy 230.535988 -369.630198) (xy 230.540168 -369.640588)
			(xy 230.555711 -369.656676) (xy 230.56596 -369.661186) (xy 230.596048 -369.673108) (xy 230.653186 -369.703502)
			(xy 230.706005 -369.740901) (xy 230.75365 -369.784702) (xy 230.795351 -369.834195) (xy 230.830434 -369.88858)
			(xy 230.85833 -369.946978) (xy 230.87859 -370.008444) (xy 230.890885 -370.071985) (xy 230.895016 -370.136572)
			(xy 230.890917 -370.201161) (xy 230.878654 -370.264708) (xy 230.858426 -370.326184) (xy 230.830558 -370.384596)
			(xy 230.795503 -370.438999) (xy 230.753827 -370.488513) (xy 230.706204 -370.532338) (xy 230.653404 -370.569764)
			(xy 230.596281 -370.600186) (xy 230.566214 -370.612162) (xy 230.565706 -370.612162) (xy 230.565452 -370.612416)
			(xy 230.558508 -370.615377) (xy 230.546623 -370.624673) (xy 230.542084 -370.630704) (xy 230.537766 -370.637308)
			(xy 230.533194 -370.651532) (xy 230.533194 -371.458553) (xy 237.538967 -371.458553) (xy 237.538967 -371.404047)
			(xy 237.546725 -371.350096) (xy 237.562081 -371.297798) (xy 237.584725 -371.248218) (xy 237.614194 -371.202365)
			(xy 237.649889 -371.161173) (xy 237.691083 -371.125481) (xy 237.736937 -371.096014) (xy 237.786519 -371.073374)
			(xy 237.838817 -371.05802) (xy 237.892769 -371.050266) (xy 237.920022 -371.049804) (xy 237.948488 -371.050285)
			(xy 238.004788 -371.058744) (xy 238.059208 -371.07547) (xy 238.11054 -371.100093) (xy 238.157646 -371.132067)
			(xy 238.199481 -371.170682) (xy 238.21771 -371.192552) (xy 238.224314 -371.200934) (xy 238.243364 -371.21084)
			(xy 238.340138 -371.216682) (xy 238.360204 -371.209316) (xy 238.367824 -371.201696) (xy 238.378746 -371.191536)
			(xy 238.386503 -371.183715) (xy 238.395051 -371.163435) (xy 238.395256 -371.15242) (xy 238.392462 -371.06352)
			(xy 238.38281 -371.043708) (xy 238.37392 -371.036596) (xy 238.351914 -371.018403) (xy 238.313077 -370.976551)
			(xy 238.280904 -370.929383) (xy 238.256112 -370.877951) (xy 238.239256 -370.8234) (xy 238.23071 -370.766947)
			(xy 238.230156 -370.7384) (xy 238.230719 -370.709342) (xy 238.23955 -370.651901) (xy 238.256993 -370.596465)
			(xy 238.282643 -370.544316) (xy 238.315907 -370.496661) (xy 238.335566 -370.475256) (xy 238.341909 -370.467909)
			(xy 238.349099 -370.449899) (xy 238.349536 -370.440204) (xy 238.349536 -370.360194) (xy 238.342424 -370.34216)
			(xy 238.335566 -370.335048) (xy 238.315921 -370.313628) (xy 238.282638 -370.265986) (xy 238.256976 -370.213841)
			(xy 238.23953 -370.158405) (xy 238.230704 -370.100962) (xy 238.230156 -370.071904) (xy 238.230681 -370.044654)
			(xy 238.238436 -369.99071) (xy 238.253789 -369.938418) (xy 238.276427 -369.888843) (xy 238.30589 -369.842995)
			(xy 238.341577 -369.801805) (xy 238.382763 -369.766114) (xy 238.428608 -369.736646) (xy 238.478181 -369.714003)
			(xy 238.530471 -369.698645) (xy 238.584415 -369.690884) (xy 238.611664 -369.690396) (xy 238.641678 -369.690999)
			(xy 238.700964 -369.700406) (xy 238.758047 -369.718977) (xy 238.811519 -369.746255) (xy 238.860062 -369.781567)
			(xy 238.881666 -369.80241) (xy 238.888778 -369.809522) (xy 238.906558 -369.817142) (xy 238.997236 -369.818666)
			(xy 239.01527 -369.811808) (xy 239.022636 -369.80495) (xy 239.043931 -369.785911) (xy 239.091131 -369.753742)
			(xy 239.142597 -369.728966) (xy 239.197181 -369.712136) (xy 239.253664 -369.703628) (xy 239.282224 -369.703096)
			(xy 239.311204 -369.703591) (xy 239.368496 -369.712356) (xy 239.423806 -369.729681) (xy 239.475861 -369.755168)
			(xy 239.523464 -369.788232) (xy 239.565523 -369.828111) (xy 239.583722 -369.85067) (xy 239.591342 -369.860576)
			(xy 239.614202 -369.87099) (xy 239.723422 -369.864386) (xy 239.745012 -369.851178) (xy 239.751362 -369.840256)
			(xy 239.766161 -369.816189) (xy 239.801781 -369.772335) (xy 239.843482 -369.734218) (xy 239.890352 -369.702673)
			(xy 239.941365 -369.67839) (xy 239.995402 -369.661901) (xy 240.051281 -369.653568) (xy 240.07953 -369.653058)
			(xy 240.109324 -369.65364) (xy 240.168188 -369.662895) (xy 240.224896 -369.681191) (xy 240.27807 -369.708083)
			(xy 240.326415 -369.742917) (xy 240.368755 -369.784845) (xy 240.38687 -369.808506) (xy 240.394236 -369.818412)
			(xy 240.415572 -369.829334) (xy 240.521998 -369.82908) (xy 240.543588 -369.818158) (xy 240.5507 -369.808506)
			(xy 240.568788 -369.78473) (xy 240.611148 -369.742606) (xy 240.659557 -369.707601) (xy 240.712831 -369.680572)
			(xy 240.769669 -369.662179) (xy 240.828678 -369.652872) (xy 240.858548 -369.652296) (xy 240.888564 -369.652846)
			(xy 240.947853 -369.662266) (xy 241.004936 -369.680849) (xy 241.058407 -369.708139) (xy 241.106948 -369.743462)
			(xy 241.12855 -369.76431) (xy 241.135662 -369.771422) (xy 241.153442 -369.779042) (xy 241.24412 -369.780566)
			(xy 241.262154 -369.773708) (xy 241.26952 -369.76685) (xy 241.290821 -369.747819) (xy 241.338019 -369.715649)
			(xy 241.389484 -369.690871) (xy 241.444067 -369.674039) (xy 241.500548 -369.665529) (xy 241.529108 -369.664996)
			(xy 241.529362 -369.664996) (xy 241.558277 -369.665536) (xy 241.61544 -369.674294) (xy 241.670629 -369.69157)
			(xy 241.722583 -369.716969) (xy 241.770114 -369.749911) (xy 241.79149 -369.76939) (xy 241.798856 -369.776502)
			(xy 241.81816 -369.783868) (xy 241.911632 -369.779804) (xy 241.930174 -369.770914) (xy 241.937032 -369.763294)
			(xy 241.955222 -369.743572) (xy 241.99617 -369.708908) (xy 242.04157 -369.680321) (xy 242.090526 -369.658372)
			(xy 242.142072 -369.643496) (xy 242.195195 -369.635986) (xy 242.22202 -369.635532) (xy 242.249275 -369.635936)
			(xy 242.30323 -369.643697) (xy 242.355532 -369.659058) (xy 242.405115 -369.681705) (xy 242.45097 -369.711179)
			(xy 242.492163 -369.746879) (xy 242.527857 -369.788078) (xy 242.557323 -369.833938) (xy 242.579963 -369.883524)
			(xy 242.595316 -369.935828) (xy 242.603068 -369.989785) (xy 242.603528 -370.01704) (xy 242.60316 -370.037317)
			(xy 246.698764 -370.037317) (xy 246.698764 -369.973395) (xy 246.706775 -369.909977) (xy 246.722672 -369.848063)
			(xy 246.746204 -369.78863) (xy 246.776998 -369.732615) (xy 246.814571 -369.6809) (xy 246.858328 -369.634303)
			(xy 246.907581 -369.593558) (xy 246.961552 -369.559307) (xy 247.019391 -369.53209) (xy 247.080184 -369.512337)
			(xy 247.142974 -369.500359) (xy 247.20677 -369.496346) (xy 247.270566 -369.500359) (xy 247.333356 -369.512337)
			(xy 247.394149 -369.53209) (xy 247.451988 -369.559307) (xy 247.505959 -369.593558) (xy 247.555212 -369.634303)
			(xy 247.598969 -369.6809) (xy 247.636542 -369.732615) (xy 247.667336 -369.78863) (xy 247.690868 -369.848063)
			(xy 247.706765 -369.909977) (xy 247.714776 -369.973395) (xy 247.715278 -370.005356) (xy 247.714776 -370.037317)
			(xy 247.706765 -370.100735) (xy 247.690868 -370.162649) (xy 247.667336 -370.222082) (xy 247.636542 -370.278097)
			(xy 247.598969 -370.329812) (xy 247.555212 -370.376409) (xy 247.505959 -370.417154) (xy 247.451988 -370.451405)
			(xy 247.394149 -370.478622) (xy 247.333356 -370.498375) (xy 247.270566 -370.510353) (xy 247.20677 -370.514367)
			(xy 247.142974 -370.510353) (xy 247.080184 -370.498375) (xy 247.019391 -370.478622) (xy 246.961552 -370.451405)
			(xy 246.907581 -370.417154) (xy 246.858328 -370.376409) (xy 246.814571 -370.329812) (xy 246.776998 -370.278097)
			(xy 246.746204 -370.222082) (xy 246.722672 -370.162649) (xy 246.706775 -370.100735) (xy 246.698764 -370.037317)
			(xy 242.60316 -370.037317) (xy 242.603037 -370.0441) (xy 242.595379 -370.097676) (xy 242.580222 -370.149631)
			(xy 242.557872 -370.198921) (xy 242.528777 -370.244556) (xy 242.493522 -370.285618) (xy 242.47348 -370.303806)
			(xy 242.473226 -370.30406) (xy 242.465494 -370.311544) (xy 242.456682 -370.331155) (xy 242.456208 -370.341906)
			(xy 242.4557 -370.417852) (xy 242.456189 -370.428655) (xy 242.464994 -370.448385) (xy 242.472718 -370.455952)
			(xy 242.492308 -370.474079) (xy 242.526727 -370.514871) (xy 242.541298 -370.537232) (xy 242.541298 -370.537486)
			(xy 242.548336 -370.547222) (xy 242.568995 -370.559419) (xy 242.580922 -370.560854) (xy 242.67541 -370.56695)
			(xy 242.697762 -370.557044) (xy 242.705636 -370.547646) (xy 242.723841 -370.526328) (xy 242.765478 -370.488792)
			(xy 242.812156 -370.457747) (xy 242.862872 -370.433861) (xy 242.916535 -370.417647) (xy 242.971992 -370.409454)
			(xy 243.000022 -370.408962) (xy 243.027272 -370.409457) (xy 243.081218 -370.417216) (xy 243.133511 -370.432572)
			(xy 243.183086 -370.455214) (xy 243.228935 -370.48468) (xy 243.270124 -370.52037) (xy 243.305816 -370.561558)
			(xy 243.335282 -370.607407) (xy 243.357925 -370.656982) (xy 243.373282 -370.709274) (xy 243.381042 -370.76322)
			(xy 243.38153 -370.79047) (xy 243.381084 -370.815921) (xy 243.374289 -370.866367) (xy 243.372896 -370.871453)
			(xy 247.910598 -370.871453) (xy 247.910598 -370.807531) (xy 247.918609 -370.744113) (xy 247.934506 -370.682199)
			(xy 247.958038 -370.622766) (xy 247.988832 -370.566751) (xy 248.026405 -370.515036) (xy 248.070162 -370.468439)
			(xy 248.119415 -370.427694) (xy 248.173386 -370.393443) (xy 248.231225 -370.366226) (xy 248.292018 -370.346473)
			(xy 248.354808 -370.334495) (xy 248.418604 -370.330482) (xy 248.4824 -370.334495) (xy 248.54519 -370.346473)
			(xy 248.605983 -370.366226) (xy 248.663822 -370.393443) (xy 248.717793 -370.427694) (xy 248.767046 -370.468439)
			(xy 248.810803 -370.515036) (xy 248.848376 -370.566751) (xy 248.87917 -370.622766) (xy 248.902702 -370.682199)
			(xy 248.918599 -370.744113) (xy 248.92661 -370.807531) (xy 248.927112 -370.839492) (xy 248.92661 -370.871453)
			(xy 248.918599 -370.934871) (xy 248.902702 -370.996785) (xy 248.87917 -371.056218) (xy 248.848376 -371.112233)
			(xy 248.810803 -371.163948) (xy 248.767046 -371.210545) (xy 248.717793 -371.25129) (xy 248.663822 -371.285541)
			(xy 248.605983 -371.312758) (xy 248.54519 -371.332511) (xy 248.4824 -371.344489) (xy 248.418604 -371.348503)
			(xy 248.354808 -371.344489) (xy 248.292018 -371.332511) (xy 248.231225 -371.312758) (xy 248.173386 -371.285541)
			(xy 248.119415 -371.25129) (xy 248.070162 -371.210545) (xy 248.026405 -371.163948) (xy 247.988832 -371.112233)
			(xy 247.958038 -371.056218) (xy 247.934506 -370.996785) (xy 247.918609 -370.934871) (xy 247.910598 -370.871453)
			(xy 243.372896 -370.871453) (xy 243.360844 -370.915461) (xy 243.351304 -370.93906) (xy 243.34703 -370.950746)
			(xy 243.34917 -370.975513) (xy 243.355368 -370.986304) (xy 243.40058 -371.056916) (xy 243.407698 -371.067025)
			(xy 243.429151 -371.079266) (xy 243.441474 -371.080284) (xy 243.441728 -371.080284) (xy 243.468384 -371.081618)
			(xy 243.520964 -371.090763) (xy 243.571756 -371.107149) (xy 243.619767 -371.130456) (xy 243.66406 -371.160228)
			(xy 243.70377 -371.195886) (xy 243.738121 -371.236731) (xy 243.766442 -371.281966) (xy 243.78818 -371.330708)
			(xy 243.802911 -371.382004) (xy 243.810346 -371.434853) (xy 243.81079 -371.461538) (xy 243.810304 -371.488789)
			(xy 243.802548 -371.542737) (xy 243.80065 -371.5492) (xy 291.773357 -371.5492) (xy 291.777371 -371.485402)
			(xy 291.789349 -371.422611) (xy 291.809102 -371.361815) (xy 291.836318 -371.303975) (xy 291.870569 -371.250001)
			(xy 291.911315 -371.200746) (xy 291.957912 -371.156986) (xy 292.009626 -371.119411) (xy 292.065642 -371.088613)
			(xy 292.125076 -371.065079) (xy 292.186991 -371.049179) (xy 292.25041 -371.041164) (xy 292.282372 -371.04066)
			(xy 292.317104 -371.041239) (xy 292.38592 -371.050708) (xy 292.452805 -371.069458) (xy 292.516515 -371.097142)
			(xy 292.575861 -371.133243) (xy 292.603174 -371.154706) (xy 292.610521 -371.160122) (xy 292.62783 -371.165865)
			(xy 292.636956 -371.165882) (xy 292.667182 -371.16512) (xy 292.67633 -371.164435) (xy 292.693257 -371.157399)
			(xy 292.700202 -371.151404) (xy 292.723761 -371.130248) (xy 292.7752 -371.093322) (xy 292.830828 -371.063073)
			(xy 292.889783 -371.039967) (xy 292.951151 -371.024363) (xy 293.013982 -371.016503) (xy 293.045642 -371.016022)
			(xy 293.045896 -371.016022) (xy 293.07786 -371.016443) (xy 293.141285 -371.024455) (xy 293.203206 -371.040353)
			(xy 293.262645 -371.063886) (xy 293.318667 -371.094684) (xy 293.370386 -371.13226) (xy 293.416989 -371.176022)
			(xy 293.457738 -371.22528) (xy 293.491993 -371.279257) (xy 293.519213 -371.337101) (xy 293.538968 -371.397901)
			(xy 293.550947 -371.460697) (xy 293.554962 -371.5245) (xy 293.550947 -371.588303) (xy 293.538968 -371.651099)
			(xy 293.519213 -371.711899) (xy 293.491993 -371.769743) (xy 293.457738 -371.82372) (xy 293.416989 -371.872978)
			(xy 293.370386 -371.91674) (xy 293.318667 -371.954316) (xy 293.262645 -371.985114) (xy 293.203206 -372.008647)
			(xy 293.141285 -372.024545) (xy 293.07786 -372.032557) (xy 293.045896 -372.033038) (xy 293.011164 -372.032447)
			(xy 292.942346 -372.022987) (xy 292.875457 -372.004245) (xy 292.811744 -371.976568) (xy 292.752393 -371.940473)
			(xy 292.725094 -371.918992) (xy 292.717756 -371.913561) (xy 292.70044 -371.907827) (xy 292.691312 -371.907816)
			(xy 292.661086 -371.908578) (xy 292.651936 -371.909248) (xy 292.635009 -371.916295) (xy 292.628066 -371.922294)
			(xy 292.60452 -371.943465) (xy 292.553078 -371.980389) (xy 292.497447 -372.010637) (xy 292.43849 -372.03374)
			(xy 292.37712 -372.04934) (xy 292.314287 -372.057197) (xy 292.282626 -372.057676) (xy 292.282372 -372.057676)
			(xy 292.25041 -372.057236) (xy 292.186991 -372.049221) (xy 292.125076 -372.033321) (xy 292.065642 -372.009787)
			(xy 292.009626 -371.978989) (xy 291.957912 -371.941414) (xy 291.911315 -371.897654) (xy 291.870569 -371.848399)
			(xy 291.836318 -371.794425) (xy 291.809102 -371.736585) (xy 291.789349 -371.675789) (xy 291.777371 -371.612998)
			(xy 291.773357 -371.5492) (xy 243.80065 -371.5492) (xy 243.787193 -371.595032) (xy 243.764551 -371.644609)
			(xy 243.735085 -371.690459) (xy 243.699394 -371.73165) (xy 243.658203 -371.767341) (xy 243.612353 -371.796807)
			(xy 243.562776 -371.819449) (xy 243.510481 -371.834804) (xy 243.456533 -371.84256) (xy 243.402031 -371.84256)
			(xy 243.348083 -371.834804) (xy 243.295788 -371.819449) (xy 243.246211 -371.796807) (xy 243.200361 -371.767341)
			(xy 243.15917 -371.73165) (xy 243.123479 -371.690459) (xy 243.094013 -371.644609) (xy 243.071371 -371.595032)
			(xy 243.056016 -371.542737) (xy 243.04826 -371.488789) (xy 243.047774 -371.461538) (xy 243.048222 -371.436087)
			(xy 243.055016 -371.385641) (xy 243.068461 -371.336547) (xy 243.078 -371.312948) (xy 243.082268 -371.30126)
			(xy 243.080132 -371.276495) (xy 243.073936 -371.265704) (xy 243.028724 -371.195092) (xy 243.021603 -371.184986)
			(xy 243.000153 -371.172743) (xy 242.98783 -371.171724) (xy 242.987576 -371.171724) (xy 242.96099 -371.170394)
			(xy 242.908547 -371.161279) (xy 242.85788 -371.144962) (xy 242.809975 -371.121757) (xy 242.765761 -371.092118)
			(xy 242.726098 -371.056618) (xy 242.691756 -371.015948) (xy 242.677188 -370.99367) (xy 242.677188 -370.993416)
			(xy 242.670156 -370.983674) (xy 242.649492 -370.971481) (xy 242.637564 -370.970048) (xy 242.543076 -370.963952)
			(xy 242.520724 -370.973858) (xy 242.51285 -370.983256) (xy 242.494653 -371.004581) (xy 242.453014 -371.042117)
			(xy 242.406334 -371.07316) (xy 242.355617 -371.097045) (xy 242.301952 -371.113258) (xy 242.246494 -371.121449)
			(xy 242.218464 -371.12194) (xy 242.191914 -371.121462) (xy 242.139329 -371.114089) (xy 242.088275 -371.099493)
			(xy 242.039741 -371.077954) (xy 241.994664 -371.049889) (xy 241.953917 -371.015842) (xy 241.935762 -370.996464)
			(xy 241.935508 -370.99621) (xy 241.928335 -370.989223) (xy 241.910174 -370.980847) (xy 241.900202 -370.979954)
			(xy 241.817144 -370.976652) (xy 241.798348 -370.98351) (xy 241.790728 -370.990622) (xy 241.769394 -371.010045)
			(xy 241.721929 -371.04284) (xy 241.670066 -371.068114) (xy 241.61499 -371.08529) (xy 241.557955 -371.093978)
			(xy 241.529108 -371.094508) (xy 241.499092 -371.09395) (xy 241.439802 -371.084537) (xy 241.382718 -371.065956)
			(xy 241.329246 -371.038667) (xy 241.280707 -371.003343) (xy 241.259106 -370.982494) (xy 241.251994 -370.975382)
			(xy 241.234214 -370.967762) (xy 241.143536 -370.966238) (xy 241.125502 -370.973096) (xy 241.118136 -370.979954)
			(xy 241.096853 -370.999007) (xy 241.04965 -371.031174) (xy 240.99818 -371.055947) (xy 240.943593 -371.072774)
			(xy 240.887109 -371.081278) (xy 240.858548 -371.081808) (xy 240.828753 -371.081256) (xy 240.769887 -371.071997)
			(xy 240.713177 -371.053695) (xy 240.660003 -371.026798) (xy 240.611659 -370.991958) (xy 240.569321 -370.950024)
			(xy 240.551208 -370.92636) (xy 240.543842 -370.916454) (xy 240.522506 -370.905532) (xy 240.41608 -370.905786)
			(xy 240.39449 -370.916708) (xy 240.387378 -370.92636) (xy 240.369293 -370.950139) (xy 240.326934 -370.992265)
			(xy 240.278525 -371.027271) (xy 240.225249 -371.0543) (xy 240.168411 -371.072691) (xy 240.1094 -371.081995)
			(xy 240.07953 -371.08257) (xy 240.050553 -371.082011) (xy 239.993264 -371.073256) (xy 239.937957 -371.055941)
			(xy 239.885903 -371.030466) (xy 239.838297 -370.997416) (xy 239.796234 -370.957549) (xy 239.778032 -370.934996)
			(xy 239.770412 -370.92509) (xy 239.747552 -370.914676) (xy 239.638332 -370.92128) (xy 239.616742 -370.934488)
			(xy 239.610392 -370.94541) (xy 239.595543 -370.969445) (xy 239.559933 -371.0133) (xy 239.518241 -371.05142)
			(xy 239.471379 -371.08297) (xy 239.420374 -371.107258) (xy 239.366344 -371.123754) (xy 239.31047 -371.132094)
			(xy 239.282224 -371.132608) (xy 239.252208 -371.13204) (xy 239.192919 -371.122629) (xy 239.135835 -371.104051)
			(xy 239.082363 -371.076764) (xy 239.033824 -371.041442) (xy 239.012222 -371.020594) (xy 239.00511 -371.013482)
			(xy 238.98733 -371.005862) (xy 238.896652 -371.004338) (xy 238.878618 -371.011196) (xy 238.871252 -371.018054)
			(xy 238.867696 -371.021102) (xy 238.859974 -371.028953) (xy 238.851404 -371.04921) (xy 238.851186 -371.060218)
			(xy 238.85398 -371.149118) (xy 238.863632 -371.16893) (xy 238.872522 -371.176042) (xy 238.894486 -371.194284)
			(xy 238.933329 -371.236123) (xy 238.965509 -371.283281) (xy 238.990308 -371.334704) (xy 239.007172 -371.389247)
			(xy 239.015727 -371.445693) (xy 239.016286 -371.474238) (xy 239.015857 -371.501491) (xy 239.008095 -371.555442)
			(xy 238.992734 -371.607739) (xy 238.970087 -371.657318) (xy 238.940615 -371.703169) (xy 238.904917 -371.74436)
			(xy 238.863721 -371.780051) (xy 238.817865 -371.809516) (xy 238.768283 -371.832155) (xy 238.715983 -371.847508)
			(xy 238.662031 -371.855262) (xy 238.634778 -371.855746) (xy 238.606313 -371.855247) (xy 238.550014 -371.846789)
			(xy 238.495595 -371.830065) (xy 238.444263 -371.805446) (xy 238.397157 -371.773476) (xy 238.35532 -371.734866)
			(xy 238.33709 -371.712998) (xy 238.330486 -371.704616) (xy 238.311436 -371.69471) (xy 238.214662 -371.688868)
			(xy 238.194596 -371.696234) (xy 238.186976 -371.703854) (xy 238.165432 -371.724136) (xy 238.117285 -371.758524)
			(xy 238.064405 -371.785064) (xy 238.008061 -371.803121) (xy 237.949605 -371.812261) (xy 237.920022 -371.81282)
			(xy 237.892769 -371.812334) (xy 237.838817 -371.80458) (xy 237.786519 -371.789226) (xy 237.736937 -371.766586)
			(xy 237.691083 -371.737119) (xy 237.649889 -371.701427) (xy 237.614194 -371.660235) (xy 237.584725 -371.614382)
			(xy 237.562081 -371.564802) (xy 237.546725 -371.512504) (xy 237.538967 -371.458553) (xy 230.533194 -371.458553)
			(xy 230.533194 -372.586758) (xy 230.533956 -372.59514) (xy 230.535474 -372.602743) (xy 230.542464 -372.616573)
			(xy 230.547672 -372.622318) (xy 231.882188 -373.956834) (xy 282.726384 -373.956834) (xy 282.726983 -373.921869)
			(xy 282.73658 -373.8526) (xy 282.755584 -373.785302) (xy 282.783636 -373.721244) (xy 282.820205 -373.661638)
			(xy 282.841954 -373.634254) (xy 282.847208 -373.627244) (xy 282.853063 -373.61075) (xy 282.853384 -373.601996)
			(xy 282.853384 -373.448072) (xy 282.853036 -373.439324) (xy 282.847189 -373.422832) (xy 282.841954 -373.415814)
			(xy 282.820231 -373.388411) (xy 282.783674 -373.328803) (xy 282.755623 -373.264749) (xy 282.736608 -373.197458)
			(xy 282.726987 -373.128197) (xy 282.726384 -373.093234) (xy 282.72687 -373.062503) (xy 282.734274 -373.001488)
			(xy 282.748979 -372.941811) (xy 282.770771 -372.884342) (xy 282.799331 -372.829919) (xy 282.834243 -372.779335)
			(xy 282.874998 -372.733328) (xy 282.921002 -372.692569) (xy 282.971583 -372.657653) (xy 283.026004 -372.629088)
			(xy 283.083471 -372.607292) (xy 283.143147 -372.592582) (xy 283.204161 -372.585172) (xy 283.234892 -372.584726)
			(xy 283.266082 -372.585189) (xy 283.32799 -372.592857) (xy 283.388497 -372.60803) (xy 283.446697 -372.630481)
			(xy 283.501719 -372.659874) (xy 283.5275 -372.677436) (xy 283.527754 -372.67769) (xy 283.536137 -372.682837)
			(xy 283.555333 -372.687034) (xy 283.565092 -372.685818) (xy 283.635958 -372.67388) (xy 283.645692 -372.671725)
			(xy 283.66256 -372.661141) (xy 283.668724 -372.653306) (xy 283.68559 -372.630707) (xy 283.72522 -372.590594)
			(xy 283.770676 -372.557229) (xy 283.820824 -372.531447) (xy 283.874408 -372.513891) (xy 283.93009 -372.505)
			(xy 283.958284 -372.504462) (xy 283.984934 -372.504994) (xy 284.037638 -372.512936) (xy 284.08857 -372.528644)
			(xy 284.136592 -372.551768) (xy 284.180631 -372.581792) (xy 284.219703 -372.618043) (xy 284.252935 -372.659714)
			(xy 284.279585 -372.705872) (xy 284.299058 -372.755487) (xy 284.310919 -372.80745) (xy 284.314902 -372.8606)
			(xy 284.310919 -372.91375) (xy 284.299058 -372.965713) (xy 284.279585 -373.015328) (xy 284.252935 -373.061486)
			(xy 284.219703 -373.103157) (xy 284.180631 -373.139408) (xy 284.136592 -373.169432) (xy 284.08857 -373.192556)
			(xy 284.037638 -373.208264) (xy 283.984934 -373.216206) (xy 283.958284 -373.216678) (xy 283.929106 -373.216064)
			(xy 283.871539 -373.206483) (xy 283.84373 -373.197628) (xy 283.834197 -373.194956) (xy 283.814465 -373.196246)
			(xy 283.805376 -373.200168) (xy 283.731716 -373.236236) (xy 283.718508 -373.250968) (xy 283.715206 -373.26062)
			(xy 283.704972 -373.288638) (xy 283.678876 -373.342277) (xy 283.64668 -373.392492) (xy 283.628084 -373.415814)
			(xy 283.622782 -373.422809) (xy 283.61681 -373.439304) (xy 283.6164 -373.448072) (xy 283.6164 -373.601996)
			(xy 283.616766 -373.610743) (xy 283.622601 -373.627234) (xy 283.62783 -373.634254) (xy 283.651434 -373.664087)
			(xy 283.672894 -373.699997) (xy 292.81729 -373.699997) (xy 292.81729 -373.636075) (xy 292.825301 -373.572657)
			(xy 292.841198 -373.510743) (xy 292.86473 -373.45131) (xy 292.895524 -373.395295) (xy 292.933097 -373.34358)
			(xy 292.976854 -373.296983) (xy 293.026107 -373.256238) (xy 293.080078 -373.221987) (xy 293.137917 -373.19477)
			(xy 293.19871 -373.175017) (xy 293.2615 -373.163039) (xy 293.325296 -373.159026) (xy 293.389092 -373.163039)
			(xy 293.451882 -373.175017) (xy 293.512675 -373.19477) (xy 293.570514 -373.221987) (xy 293.624485 -373.256238)
			(xy 293.673738 -373.296983) (xy 293.717495 -373.34358) (xy 293.755068 -373.395295) (xy 293.785862 -373.45131)
			(xy 293.809394 -373.510743) (xy 293.825291 -373.572657) (xy 293.833302 -373.636075) (xy 293.833804 -373.668036)
			(xy 293.83331 -373.699489) (xy 293.949876 -373.699489) (xy 293.949876 -373.635567) (xy 293.957887 -373.572149)
			(xy 293.973784 -373.510235) (xy 293.997316 -373.450802) (xy 294.02811 -373.394787) (xy 294.065683 -373.343072)
			(xy 294.10944 -373.296475) (xy 294.158693 -373.25573) (xy 294.212664 -373.221479) (xy 294.270503 -373.194262)
			(xy 294.331296 -373.174509) (xy 294.394086 -373.162531) (xy 294.457882 -373.158518) (xy 294.521678 -373.162531)
			(xy 294.584468 -373.174509) (xy 294.645261 -373.194262) (xy 294.7031 -373.221479) (xy 294.757071 -373.25573)
			(xy 294.806324 -373.296475) (xy 294.850081 -373.343072) (xy 294.887654 -373.394787) (xy 294.918448 -373.450802)
			(xy 294.94198 -373.510235) (xy 294.957877 -373.572149) (xy 294.965888 -373.635567) (xy 294.96639 -373.667528)
			(xy 294.965888 -373.699489) (xy 294.957877 -373.762907) (xy 294.94198 -373.824821) (xy 294.918448 -373.884254)
			(xy 294.887654 -373.940269) (xy 294.850081 -373.991984) (xy 294.806324 -374.038581) (xy 294.757071 -374.079326)
			(xy 294.7031 -374.113577) (xy 294.645261 -374.140794) (xy 294.584468 -374.160547) (xy 294.521678 -374.172525)
			(xy 294.457882 -374.176539) (xy 294.394086 -374.172525) (xy 294.331296 -374.160547) (xy 294.270503 -374.140794)
			(xy 294.212664 -374.113577) (xy 294.158693 -374.079326) (xy 294.10944 -374.038581) (xy 294.065683 -373.991984)
			(xy 294.02811 -373.940269) (xy 293.997316 -373.884254) (xy 293.973784 -373.824821) (xy 293.957887 -373.762907)
			(xy 293.949876 -373.699489) (xy 293.83331 -373.699489) (xy 293.833302 -373.699997) (xy 293.825291 -373.763415)
			(xy 293.809394 -373.825329) (xy 293.785862 -373.884762) (xy 293.755068 -373.940777) (xy 293.717495 -373.992492)
			(xy 293.673738 -374.039089) (xy 293.624485 -374.079834) (xy 293.570514 -374.114085) (xy 293.512675 -374.141302)
			(xy 293.451882 -374.161055) (xy 293.389092 -374.173033) (xy 293.325296 -374.177047) (xy 293.2615 -374.173033)
			(xy 293.19871 -374.161055) (xy 293.137917 -374.141302) (xy 293.080078 -374.114085) (xy 293.026107 -374.079834)
			(xy 292.976854 -374.039089) (xy 292.933097 -373.992492) (xy 292.895524 -373.940777) (xy 292.86473 -373.884762)
			(xy 292.841198 -373.825329) (xy 292.825301 -373.763415) (xy 292.81729 -373.699997) (xy 283.672894 -373.699997)
			(xy 283.690457 -373.729385) (xy 283.705554 -373.764302) (xy 283.70911 -373.773192) (xy 283.72181 -373.786654)
			(xy 283.792168 -373.820436) (xy 283.800652 -373.824058) (xy 283.819013 -373.825636) (xy 283.827982 -373.823484)
			(xy 283.82849 -373.823484) (xy 283.852898 -373.816764) (xy 283.903 -373.809503) (xy 283.928312 -373.809006)
			(xy 283.954962 -373.809477) (xy 284.007666 -373.817422) (xy 284.058597 -373.833134) (xy 284.106618 -373.856261)
			(xy 284.150655 -373.886286) (xy 284.189726 -373.92254) (xy 284.222957 -373.964212) (xy 284.249606 -374.010371)
			(xy 284.269078 -374.059986) (xy 284.280939 -374.111949) (xy 284.284922 -374.1651) (xy 284.280939 -374.218251)
			(xy 284.269078 -374.270214) (xy 284.249606 -374.319829) (xy 284.222957 -374.365988) (xy 284.189726 -374.40766)
			(xy 284.150655 -374.443914) (xy 284.106618 -374.473939) (xy 284.058597 -374.497066) (xy 284.007666 -374.512778)
			(xy 283.954962 -374.520723) (xy 283.928312 -374.521222) (xy 283.902525 -374.520738) (xy 283.851493 -374.513282)
			(xy 283.802071 -374.498537) (xy 283.755296 -374.476814) (xy 283.712145 -374.448566) (xy 283.673524 -374.414387)
			(xy 283.656532 -374.394984) (xy 283.656278 -374.39473) (xy 283.649965 -374.388061) (xy 283.633821 -374.379337)
			(xy 283.624782 -374.377712) (xy 283.547566 -374.367044) (xy 283.529532 -374.371362) (xy 283.521658 -374.376696)
			(xy 283.496235 -374.393514) (xy 283.442159 -374.421652) (xy 283.385105 -374.443116) (xy 283.325892 -374.457599)
			(xy 283.265371 -374.464893) (xy 283.234892 -374.465342) (xy 283.204162 -374.464852) (xy 283.143151 -374.457443)
			(xy 283.083477 -374.442734) (xy 283.026011 -374.420941) (xy 282.971591 -374.392379) (xy 282.92101 -374.357467)
			(xy 282.875006 -374.316713) (xy 282.834249 -374.270711) (xy 282.799334 -374.220132) (xy 282.77077 -374.165713)
			(xy 282.748973 -374.108248) (xy 282.734262 -374.048575) (xy 282.72685 -373.987564) (xy 282.726384 -373.956834)
			(xy 231.882188 -373.956834) (xy 233.185208 -375.259854) (xy 233.190954 -375.265059) (xy 233.204784 -375.272051)
			(xy 233.212386 -375.27357) (xy 233.220768 -375.274332) (xy 277.68931 -375.274332) (xy 277.707598 -375.281698)
			(xy 277.713186 -375.287286) (xy 277.713948 -375.288048) (xy 277.714964 -375.289064) (xy 278.846788 -376.420888)
			(xy 278.847804 -376.421904) (xy 278.848566 -376.422666) (xy 278.854154 -376.428254) (xy 278.86152 -376.446542)
			(xy 278.86152 -378.470668) (xy 285.209742 -378.470668) (xy 285.210303 -378.437329) (xy 285.219017 -378.371223)
			(xy 285.23629 -378.306822) (xy 285.261827 -378.245228) (xy 285.295191 -378.187497) (xy 285.335809 -378.134619)
			(xy 285.382986 -378.0875) (xy 285.409132 -378.066808) (xy 285.415944 -378.061125) (xy 285.425558 -378.046236)
			(xy 285.429504 -378.028958) (xy 285.427306 -378.011371) (xy 285.42361 -378.003308) (xy 285.410347 -377.976425)
			(xy 285.389542 -377.920204) (xy 285.375505 -377.861924) (xy 285.36843 -377.802395) (xy 285.367984 -377.772422)
			(xy 285.367984 -377.772168) (xy 285.368443 -377.741128) (xy 285.375986 -377.679507) (xy 285.390981 -377.619264)
			(xy 285.413203 -377.561298) (xy 285.442323 -377.50647) (xy 285.477905 -377.455599) (xy 285.51942 -377.409442)
			(xy 285.56625 -377.368686) (xy 285.617696 -377.33394) (xy 285.672992 -377.305721) (xy 285.701994 -377.294648)
			(xy 285.710485 -377.291126) (xy 285.724409 -377.279143) (xy 285.729172 -377.27128) (xy 285.743904 -377.24461)
			(xy 285.747965 -377.23641) (xy 285.750575 -377.218314) (xy 285.748984 -377.209304) (xy 285.743398 -377.182345)
			(xy 285.737417 -377.127613) (xy 285.737046 -377.100084) (xy 285.737548 -377.068123) (xy 285.745559 -377.004705)
			(xy 285.761456 -376.942791) (xy 285.784988 -376.883358) (xy 285.815782 -376.827343) (xy 285.853355 -376.775628)
			(xy 285.897112 -376.729031) (xy 285.946365 -376.688286) (xy 286.000336 -376.654035) (xy 286.058175 -376.626818)
			(xy 286.118968 -376.607065) (xy 286.181758 -376.595087) (xy 286.245554 -376.591074) (xy 286.30935 -376.595087)
			(xy 286.37214 -376.607065) (xy 286.432933 -376.626818) (xy 286.490772 -376.654035) (xy 286.544743 -376.688286)
			(xy 286.593996 -376.729031) (xy 286.637753 -376.775628) (xy 286.675326 -376.827343) (xy 286.70612 -376.883358)
			(xy 286.729652 -376.942791) (xy 286.745549 -377.004705) (xy 286.75356 -377.068123) (xy 286.754062 -377.100084)
			(xy 286.753619 -377.131124) (xy 286.74607 -377.192745) (xy 286.731071 -377.252986) (xy 286.713619 -377.2985)
			(xy 286.886326 -377.2985) (xy 286.890341 -377.234695) (xy 286.90232 -377.171897) (xy 286.922076 -377.111095)
			(xy 286.949297 -377.053249) (xy 286.983554 -376.99927) (xy 287.024305 -376.950011) (xy 287.07091 -376.906248)
			(xy 287.122631 -376.868671) (xy 287.178655 -376.837873) (xy 287.238097 -376.814339) (xy 287.30002 -376.798442)
			(xy 287.363447 -376.79043) (xy 287.395412 -376.78995) (xy 287.425159 -376.790408) (xy 287.484239 -376.797408)
			(xy 287.513268 -376.80392) (xy 287.522586 -376.805748) (xy 287.54138 -376.803143) (xy 287.549844 -376.79884)
			(xy 287.576768 -376.783854) (xy 287.584886 -376.778997) (xy 287.597024 -376.764502) (xy 287.60039 -376.75566)
			(xy 287.610915 -376.725725) (xy 287.63839 -376.668526) (xy 287.672771 -376.615191) (xy 287.713524 -376.566551)
			(xy 287.760013 -376.523362) (xy 287.811517 -376.486295) (xy 287.867235 -376.455927) (xy 287.926299 -376.432731)
			(xy 287.987791 -376.417067) (xy 288.050754 -376.409179) (xy 288.082482 -376.408696) (xy 288.114445 -376.409168)
			(xy 288.177868 -376.417178) (xy 288.239787 -376.433074) (xy 288.299225 -376.456605) (xy 288.355245 -376.487401)
			(xy 288.406964 -376.524975) (xy 288.453565 -376.568735) (xy 288.494314 -376.617991) (xy 288.528568 -376.671965)
			(xy 288.555788 -376.729808) (xy 288.575542 -376.790605) (xy 288.587521 -376.8534) (xy 288.591536 -376.9172)
			(xy 288.587521 -376.981) (xy 288.575542 -377.043795) (xy 288.555788 -377.104592) (xy 288.528568 -377.162435)
			(xy 288.494314 -377.216409) (xy 288.453565 -377.265665) (xy 288.406964 -377.309425) (xy 288.355245 -377.346999)
			(xy 288.299225 -377.377795) (xy 288.239787 -377.401326) (xy 288.177868 -377.417222) (xy 288.114445 -377.425232)
			(xy 288.082482 -377.425712) (xy 288.052735 -377.425253) (xy 287.993655 -377.418253) (xy 287.964626 -377.411742)
			(xy 287.955308 -377.409915) (xy 287.936515 -377.412521) (xy 287.92805 -377.416822) (xy 287.901126 -377.431808)
			(xy 287.893017 -377.436678) (xy 287.880875 -377.451164) (xy 287.877504 -377.460002) (xy 287.86702 -377.489952)
			(xy 287.839538 -377.54715) (xy 287.805151 -377.600483) (xy 287.764393 -377.649122) (xy 287.717898 -377.692309)
			(xy 287.66639 -377.729374) (xy 287.610669 -377.759739) (xy 287.551602 -377.782934) (xy 287.490107 -377.798597)
			(xy 287.427141 -377.806484) (xy 287.395412 -377.806966) (xy 287.363447 -377.80657) (xy 287.30002 -377.798558)
			(xy 287.238097 -377.782661) (xy 287.178655 -377.759127) (xy 287.122631 -377.728329) (xy 287.07091 -377.690752)
			(xy 287.024305 -377.646989) (xy 286.983554 -377.59773) (xy 286.949297 -377.543751) (xy 286.922076 -377.485905)
			(xy 286.90232 -377.425103) (xy 286.890341 -377.362305) (xy 286.886326 -377.2985) (xy 286.713619 -377.2985)
			(xy 286.708845 -377.310952) (xy 286.679723 -377.365778) (xy 286.64414 -377.416649) (xy 286.602624 -377.462806)
			(xy 286.555794 -377.503561) (xy 286.504349 -377.538308) (xy 286.449053 -377.56653) (xy 286.420052 -377.577604)
			(xy 286.411577 -377.581158) (xy 286.397644 -377.593118) (xy 286.392874 -377.600972) (xy 286.378142 -377.627642)
			(xy 286.374056 -377.635832) (xy 286.371461 -377.653936) (xy 286.373062 -377.662948) (xy 286.378641 -377.689908)
			(xy 286.384627 -377.744639) (xy 286.385 -377.772168) (xy 286.384448 -377.805507) (xy 286.375731 -377.871613)
			(xy 286.358455 -377.936014) (xy 286.332916 -377.997607) (xy 286.299551 -378.055337) (xy 286.258932 -378.108215)
			(xy 286.211756 -378.155336) (xy 286.18561 -378.176028) (xy 286.178764 -378.181672) (xy 286.169161 -378.196579)
			(xy 286.165226 -378.213868) (xy 286.167432 -378.231462) (xy 286.171132 -378.239528) (xy 286.184367 -378.266424)
			(xy 286.20518 -378.32264) (xy 286.219225 -378.380916) (xy 286.226309 -378.440442) (xy 286.226758 -378.470414)
			(xy 286.226758 -378.470668) (xy 286.226256 -378.502629) (xy 286.218245 -378.566047) (xy 286.202348 -378.627961)
			(xy 286.178816 -378.687394) (xy 286.148022 -378.743409) (xy 286.110449 -378.795124) (xy 286.066692 -378.841721)
			(xy 286.017439 -378.882466) (xy 285.963468 -378.916717) (xy 285.905629 -378.943934) (xy 285.844836 -378.963687)
			(xy 285.782046 -378.975665) (xy 285.71825 -378.979679) (xy 285.654454 -378.975665) (xy 285.591664 -378.963687)
			(xy 285.530871 -378.943934) (xy 285.473032 -378.916717) (xy 285.419061 -378.882466) (xy 285.369808 -378.841721)
			(xy 285.326051 -378.795124) (xy 285.288478 -378.743409) (xy 285.257684 -378.687394) (xy 285.234152 -378.627961)
			(xy 285.218255 -378.566047) (xy 285.210244 -378.502629) (xy 285.209742 -378.470668) (xy 278.86152 -378.470668)
			(xy 278.86152 -380.063205) (xy 279.462986 -380.063205) (xy 279.462986 -379.999283) (xy 279.470997 -379.935865)
			(xy 279.486894 -379.873951) (xy 279.510426 -379.814518) (xy 279.54122 -379.758503) (xy 279.578793 -379.706788)
			(xy 279.62255 -379.660191) (xy 279.671803 -379.619446) (xy 279.725774 -379.585195) (xy 279.783613 -379.557978)
			(xy 279.844406 -379.538225) (xy 279.907196 -379.526247) (xy 279.970992 -379.522234) (xy 280.034788 -379.526247)
			(xy 280.097578 -379.538225) (xy 280.158371 -379.557978) (xy 280.21621 -379.585195) (xy 280.270181 -379.619446)
			(xy 280.319434 -379.660191) (xy 280.363191 -379.706788) (xy 280.400764 -379.758503) (xy 280.431558 -379.814518)
			(xy 280.45509 -379.873951) (xy 280.470987 -379.935865) (xy 280.478998 -379.999283) (xy 280.4795 -380.031244)
			(xy 280.478998 -380.063205) (xy 280.470987 -380.126623) (xy 280.45509 -380.188537) (xy 280.431558 -380.24797)
			(xy 280.400764 -380.303985) (xy 280.363191 -380.3557) (xy 280.319434 -380.402297) (xy 280.270181 -380.443042)
			(xy 280.21621 -380.477293) (xy 280.158371 -380.50451) (xy 280.097578 -380.524263) (xy 280.034788 -380.536241)
			(xy 279.970992 -380.540255) (xy 279.907196 -380.536241) (xy 279.844406 -380.524263) (xy 279.783613 -380.50451)
			(xy 279.725774 -380.477293) (xy 279.671803 -380.443042) (xy 279.62255 -380.402297) (xy 279.578793 -380.3557)
			(xy 279.54122 -380.303985) (xy 279.510426 -380.24797) (xy 279.486894 -380.188537) (xy 279.470997 -380.126623)
			(xy 279.462986 -380.063205) (xy 278.86152 -380.063205) (xy 278.86152 -380.73203) (xy 278.862283 -380.744216)
			(xy 278.873548 -380.765841) (xy 278.88311 -380.773432) (xy 278.931878 -380.807722) (xy 278.952706 -380.8222)
			(xy 278.95654 -380.824551) (xy 278.964845 -380.828001) (xy 278.969216 -380.829058) (xy 278.976328 -380.830328)
			(xy 278.980597 -380.830718) (xy 278.989154 -380.830208) (xy 278.993346 -380.829312) (xy 278.998426 -380.827534)
			(xy 279.02616 -380.817959) (xy 279.083273 -380.804513) (xy 279.141555 -380.797734) (xy 279.170892 -380.797308)
			(xy 279.202854 -380.797788) (xy 279.266273 -380.805799) (xy 279.328188 -380.821696) (xy 279.387623 -380.845227)
			(xy 279.44364 -380.876021) (xy 279.495355 -380.913594) (xy 279.541954 -380.957352) (xy 279.5827 -381.006606)
			(xy 279.616952 -381.060578) (xy 279.64417 -381.118417) (xy 279.663924 -381.179212) (xy 279.675902 -381.242003)
			(xy 279.679916 -381.3058) (xy 279.675902 -381.369597) (xy 279.663924 -381.432388) (xy 279.64417 -381.493183)
			(xy 279.616952 -381.551022) (xy 279.5827 -381.604994) (xy 279.541954 -381.654248) (xy 279.495355 -381.698006)
			(xy 279.44364 -381.735579) (xy 279.387623 -381.766373) (xy 279.328188 -381.789904) (xy 279.266273 -381.805801)
			(xy 279.202854 -381.813812) (xy 279.170892 -381.814324) (xy 279.170638 -381.814324) (xy 279.140172 -381.813882)
			(xy 279.079677 -381.806603) (xy 279.020489 -381.792133) (xy 278.991822 -381.781812) (xy 278.979376 -381.780542)
			(xy 278.969216 -381.782574) (xy 278.964402 -381.783755) (xy 278.955317 -381.787715) (xy 278.951182 -381.790448)
			(xy 278.88311 -381.8382) (xy 278.873532 -381.845778) (xy 278.862272 -381.867409) (xy 278.86152 -381.879602)
			(xy 278.86152 -382.671066) (xy 278.86141 -382.690602) (xy 278.85925 -382.729615) (xy 278.857202 -382.749044)
			(xy 278.856948 -382.751838) (xy 278.856694 -382.753362) (xy 278.85644 -382.755394) (xy 278.85644 -382.75768)
			(xy 278.856857 -382.767701) (xy 278.864525 -382.786218) (xy 278.878699 -382.800387) (xy 278.897219 -382.808047)
			(xy 278.90724 -382.80848) (xy 279.878536 -382.80848) (xy 279.888604 -382.808909) (xy 279.907201 -382.81663)
			(xy 279.914604 -382.823466) (xy 280.85161 -383.760472) (xy 280.858455 -383.76787) (xy 280.866177 -383.786469)
			(xy 280.866596 -383.79654) (xy 280.866596 -384.973576) (xy 283.18841 -384.973576) (xy 283.18841 -384.973322)
			(xy 283.188853 -384.943114) (xy 283.195991 -384.883122) (xy 283.210191 -384.8244) (xy 283.231253 -384.767776)
			(xy 283.258881 -384.714048) (xy 283.292685 -384.663975) (xy 283.312108 -384.640836) (xy 283.317763 -384.633772)
			(xy 283.324146 -384.616855) (xy 283.324554 -384.607816) (xy 283.324554 -384.577336) (xy 283.324139 -384.568299)
			(xy 283.317758 -384.551382) (xy 283.312108 -384.544316) (xy 283.292674 -384.521187) (xy 283.258888 -384.471103)
			(xy 283.231271 -384.41737) (xy 283.210209 -384.360746) (xy 283.196 -384.302026) (xy 283.188843 -384.242037)
			(xy 283.18841 -384.21183) (xy 283.18841 -384.211576) (xy 283.189016 -384.177336) (xy 283.198238 -384.109479)
			(xy 283.216472 -384.04347) (xy 283.243389 -383.980501) (xy 283.278504 -383.921709) (xy 283.299408 -383.894584)
			(xy 283.306024 -383.88519) (xy 283.311131 -383.862827) (xy 283.306047 -383.840458) (xy 283.299408 -383.831084)
			(xy 283.278483 -383.80397) (xy 283.243325 -383.745193) (xy 283.216386 -383.682225) (xy 283.198155 -383.616206)
			(xy 283.188964 -383.548337) (xy 283.18841 -383.514092) (xy 283.188894 -383.482926) (xy 283.19651 -383.42106)
			(xy 283.211627 -383.360587) (xy 283.234019 -383.302415) (xy 283.26335 -383.247414) (xy 283.299181 -383.196409)
			(xy 283.319728 -383.17297) (xy 283.325806 -383.165814) (xy 283.332581 -383.148317) (xy 283.332936 -383.138934)
			(xy 283.332936 -383.1082) (xy 283.332494 -383.098839) (xy 283.325701 -383.081387) (xy 283.319728 -383.074164)
			(xy 283.299156 -383.050745) (xy 283.263323 -382.999737) (xy 283.233992 -382.944733) (xy 283.211602 -382.886557)
			(xy 283.196488 -382.82608) (xy 283.188878 -382.76421) (xy 283.18841 -382.733042) (xy 283.188877 -382.70231)
			(xy 283.196281 -382.641294) (xy 283.210987 -382.581615) (xy 283.232779 -382.524144) (xy 283.26134 -382.46972)
			(xy 283.296253 -382.419135) (xy 283.33701 -382.373127) (xy 283.383016 -382.332368) (xy 283.433599 -382.297452)
			(xy 283.488022 -382.268889) (xy 283.545492 -382.247094) (xy 283.60517 -382.232386) (xy 283.666186 -382.224979)
			(xy 283.696918 -382.224534) (xy 283.728714 -382.225071) (xy 283.791809 -382.232994) (xy 283.853427 -382.248715)
			(xy 283.912606 -382.271989) (xy 283.968426 -382.302453) (xy 284.020016 -382.339633) (xy 284.043628 -382.360932)
			(xy 284.050506 -382.366907) (xy 284.067311 -382.373919) (xy 284.076394 -382.374648) (xy 284.10662 -382.375664)
			(xy 284.115679 -382.375582) (xy 284.132854 -382.36986) (xy 284.140148 -382.364488) (xy 284.167291 -382.343503)
			(xy 284.226149 -382.308247) (xy 284.289219 -382.281239) (xy 284.355352 -382.262972) (xy 284.423343 -382.253778)
			(xy 284.457648 -382.253236) (xy 284.488382 -382.253611) (xy 284.5494 -382.261025) (xy 284.60908 -382.275741)
			(xy 284.666552 -382.297543) (xy 284.720976 -382.326114) (xy 284.771559 -382.361036) (xy 284.817565 -382.4018)
			(xy 284.858321 -382.447813) (xy 284.893234 -382.498403) (xy 284.921795 -382.552832) (xy 284.943586 -382.610307)
			(xy 284.958291 -382.66999) (xy 284.965695 -382.73101) (xy 284.966156 -382.761744) (xy 284.965734 -382.791403)
			(xy 284.958803 -382.850314) (xy 284.945065 -382.90802) (xy 284.924705 -382.963734) (xy 284.898001 -383.016701)
			(xy 284.865315 -383.066201) (xy 284.846522 -383.08915) (xy 284.841106 -383.096247) (xy 284.834985 -383.112999)
			(xy 284.834584 -383.121916) (xy 284.834584 -383.152142) (xy 284.834911 -383.161075) (xy 284.841025 -383.17786)
			(xy 284.846522 -383.184908) (xy 284.865303 -383.207866) (xy 284.897986 -383.257365) (xy 284.924689 -383.310331)
			(xy 284.945048 -383.366044) (xy 284.958788 -383.423747) (xy 284.965722 -383.482656) (xy 284.966156 -383.512314)
			(xy 284.966156 -383.512568) (xy 284.96556 -383.546904) (xy 284.956323 -383.614951) (xy 284.938012 -383.681136)
			(xy 284.910961 -383.744256) (xy 284.875661 -383.80316) (xy 284.85465 -383.830322) (xy 284.847905 -383.839657)
			(xy 284.842762 -383.862078) (xy 284.847886 -383.884504) (xy 284.85465 -383.893822) (xy 284.875648 -383.920995)
			(xy 284.91096 -383.979894) (xy 284.938022 -384.043009) (xy 284.956343 -384.109193) (xy 284.965589 -384.17724)
			(xy 284.966156 -384.211576) (xy 284.966156 -384.21183) (xy 284.965752 -384.242039) (xy 284.958608 -384.302033)
			(xy 284.944401 -384.360756) (xy 284.923331 -384.417381) (xy 284.895696 -384.471107) (xy 284.861885 -384.521178)
			(xy 284.842458 -384.544316) (xy 284.836819 -384.551391) (xy 284.830428 -384.5683) (xy 284.830012 -384.577336)
			(xy 284.830012 -384.607816) (xy 284.830457 -384.61685) (xy 284.836818 -384.633766) (xy 284.842458 -384.640836)
			(xy 284.861864 -384.663988) (xy 284.895654 -384.714067) (xy 284.923276 -384.767794) (xy 284.944343 -384.824414)
			(xy 284.958558 -384.88313) (xy 284.96572 -384.943116) (xy 284.966156 -384.973322) (xy 284.966156 -384.973576)
			(xy 284.965621 -385.004305) (xy 284.958217 -385.065314) (xy 284.943512 -385.124986) (xy 284.921723 -385.182451)
			(xy 284.893165 -385.236871) (xy 284.858257 -385.287451) (xy 284.817506 -385.333455) (xy 284.771508 -385.374212)
			(xy 284.720932 -385.409128) (xy 284.666517 -385.437693) (xy 284.609055 -385.459491) (xy 284.549385 -385.474204)
			(xy 284.488377 -385.481617) (xy 284.457648 -385.482084) (xy 284.427501 -385.481652) (xy 284.367629 -385.474522)
			(xy 284.309018 -385.460369) (xy 284.252491 -385.43939) (xy 284.198837 -385.411879) (xy 284.14881 -385.378223)
			(xy 284.12567 -385.358894) (xy 284.118596 -385.353253) (xy 284.101687 -385.346862) (xy 284.09265 -385.346448)
			(xy 284.061916 -385.346448) (xy 284.052878 -385.346853) (xy 284.035961 -385.353241) (xy 284.028896 -385.358894)
			(xy 284.005791 -385.37827) (xy 283.95577 -385.41195) (xy 283.902114 -385.439472) (xy 283.845577 -385.460447)
			(xy 283.786954 -385.474581) (xy 283.72707 -385.481676) (xy 283.696918 -385.482084) (xy 283.666185 -385.481645)
			(xy 283.605168 -385.474238) (xy 283.545488 -385.45953) (xy 283.488017 -385.437735) (xy 283.433592 -385.409171)
			(xy 283.383007 -385.374255) (xy 283.337 -385.333496) (xy 283.296241 -385.287488) (xy 283.261326 -385.236903)
			(xy 283.232762 -385.182477) (xy 283.210968 -385.125006) (xy 283.196261 -385.065326) (xy 283.188854 -385.004309)
			(xy 283.18841 -384.973576) (xy 280.866596 -384.973576) (xy 280.866596 -387.158738) (xy 280.867217 -387.170162)
			(xy 280.8771 -387.190759) (xy 280.885646 -387.198362) (xy 280.947622 -387.248146) (xy 280.956949 -387.254808)
			(xy 280.979248 -387.259963) (xy 280.990548 -387.258052) (xy 281.017997 -387.252264) (xy 281.07375 -387.246024)
			(xy 281.1018 -387.245606) (xy 281.102054 -387.245606) (xy 281.134004 -387.246123) (xy 281.197396 -387.254161)
			(xy 281.259282 -387.270078) (xy 281.318686 -387.293624) (xy 281.374671 -387.324427) (xy 281.426356 -387.362002)
			(xy 281.472926 -387.405757) (xy 281.513647 -387.455002) (xy 281.547876 -387.50896) (xy 281.575075 -387.566783)
			(xy 281.594816 -387.627557) (xy 281.606786 -387.690326) (xy 281.608447 -387.716733) (xy 282.604712 -387.716733)
			(xy 282.604712 -387.652811) (xy 282.612723 -387.589393) (xy 282.62862 -387.527479) (xy 282.652152 -387.468046)
			(xy 282.682946 -387.412031) (xy 282.720519 -387.360316) (xy 282.764276 -387.313719) (xy 282.813529 -387.272974)
			(xy 282.8675 -387.238723) (xy 282.925339 -387.211506) (xy 282.986132 -387.191753) (xy 283.048922 -387.179775)
			(xy 283.112718 -387.175762) (xy 283.176514 -387.179775) (xy 283.239304 -387.191753) (xy 283.300097 -387.211506)
			(xy 283.357936 -387.238723) (xy 283.411907 -387.272974) (xy 283.46116 -387.313719) (xy 283.504917 -387.360316)
			(xy 283.54249 -387.412031) (xy 283.573284 -387.468046) (xy 283.596816 -387.527479) (xy 283.612713 -387.589393)
			(xy 283.620724 -387.652811) (xy 283.621226 -387.684772) (xy 283.620724 -387.716733) (xy 283.612713 -387.780151)
			(xy 283.596816 -387.842065) (xy 283.573284 -387.901498) (xy 283.54249 -387.957513) (xy 283.504917 -388.009228)
			(xy 283.46116 -388.055825) (xy 283.411907 -388.09657) (xy 283.357936 -388.130821) (xy 283.300097 -388.158038)
			(xy 283.239304 -388.177791) (xy 283.176514 -388.189769) (xy 283.112718 -388.193783) (xy 283.048922 -388.189769)
			(xy 282.986132 -388.177791) (xy 282.925339 -388.158038) (xy 282.8675 -388.130821) (xy 282.813529 -388.09657)
			(xy 282.764276 -388.055825) (xy 282.720519 -388.009228) (xy 282.682946 -387.957513) (xy 282.652152 -387.901498)
			(xy 282.62862 -387.842065) (xy 282.612723 -387.780151) (xy 282.604712 -387.716733) (xy 281.608447 -387.716733)
			(xy 281.610797 -387.7541) (xy 281.606786 -387.817874) (xy 281.594816 -387.880643) (xy 281.575075 -387.941417)
			(xy 281.547876 -387.99924) (xy 281.513647 -388.053198) (xy 281.472926 -388.102443) (xy 281.426356 -388.146198)
			(xy 281.374671 -388.183773) (xy 281.318686 -388.214576) (xy 281.259282 -388.238122) (xy 281.197396 -388.254039)
			(xy 281.134004 -388.262077) (xy 281.102054 -388.262622) (xy 281.1018 -388.262622) (xy 281.073749 -388.262219)
			(xy 281.017995 -388.255977) (xy 280.990548 -388.250176) (xy 280.979248 -388.248285) (xy 280.956959 -388.25344)
			(xy 280.947622 -388.260082) (xy 280.885646 -388.309866) (xy 280.877128 -388.317496) (xy 280.867223 -388.338073)
			(xy 280.866596 -388.34949) (xy 280.866596 -392.067499) (xy 282.419292 -392.067499) (xy 282.419292 -392.003577)
			(xy 282.427303 -391.940159) (xy 282.4432 -391.878245) (xy 282.466732 -391.818812) (xy 282.497526 -391.762797)
			(xy 282.535099 -391.711082) (xy 282.578856 -391.664485) (xy 282.628109 -391.62374) (xy 282.68208 -391.589489)
			(xy 282.739919 -391.562272) (xy 282.800712 -391.542519) (xy 282.863502 -391.530541) (xy 282.927298 -391.526528)
			(xy 282.991094 -391.530541) (xy 283.053884 -391.542519) (xy 283.114677 -391.562272) (xy 283.172516 -391.589489)
			(xy 283.226487 -391.62374) (xy 283.27574 -391.664485) (xy 283.319497 -391.711082) (xy 283.35707 -391.762797)
			(xy 283.387864 -391.818812) (xy 283.411396 -391.878245) (xy 283.427293 -391.940159) (xy 283.435304 -392.003577)
			(xy 283.435806 -392.035538) (xy 283.435304 -392.067499) (xy 283.428015 -392.1252) (xy 299.683676 -392.1252)
			(xy 299.687747 -392.069578) (xy 299.699873 -392.015141) (xy 299.719796 -391.96305) (xy 299.747092 -391.914415)
			(xy 299.781178 -391.870272) (xy 299.821327 -391.831563) (xy 299.866685 -391.799112) (xy 299.916285 -391.773611)
			(xy 299.969069 -391.755604) (xy 300.023912 -391.745474) (xy 300.079646 -391.743437) (xy 300.135083 -391.749537)
			(xy 300.18904 -391.763643) (xy 300.240369 -391.785455) (xy 300.287975 -391.814509) (xy 300.330843 -391.850184)
			(xy 300.36806 -391.891721) (xy 300.398833 -391.938234) (xy 300.422505 -391.988731) (xy 300.438573 -392.042138)
			(xy 300.446693 -392.097314) (xy 300.447202 -392.1252) (xy 300.446693 -392.153086) (xy 300.438573 -392.208262)
			(xy 300.422505 -392.261669) (xy 300.398833 -392.312166) (xy 300.36806 -392.358679) (xy 300.330843 -392.400216)
			(xy 300.287975 -392.435891) (xy 300.240369 -392.464945) (xy 300.18904 -392.486757) (xy 300.135083 -392.500863)
			(xy 300.079646 -392.506963) (xy 300.023912 -392.504926) (xy 299.969069 -392.494796) (xy 299.916285 -392.476789)
			(xy 299.866685 -392.451288) (xy 299.821327 -392.418837) (xy 299.781178 -392.380128) (xy 299.747092 -392.335985)
			(xy 299.719796 -392.28735) (xy 299.699873 -392.235259) (xy 299.687747 -392.180822) (xy 299.683676 -392.1252)
			(xy 283.428015 -392.1252) (xy 283.427293 -392.130917) (xy 283.411396 -392.192831) (xy 283.387864 -392.252264)
			(xy 283.35707 -392.308279) (xy 283.319497 -392.359994) (xy 283.27574 -392.406591) (xy 283.226487 -392.447336)
			(xy 283.172516 -392.481587) (xy 283.114677 -392.508804) (xy 283.053884 -392.528557) (xy 282.991094 -392.540535)
			(xy 282.927298 -392.544549) (xy 282.863502 -392.540535) (xy 282.800712 -392.528557) (xy 282.739919 -392.508804)
			(xy 282.68208 -392.481587) (xy 282.628109 -392.447336) (xy 282.578856 -392.406591) (xy 282.535099 -392.359994)
			(xy 282.497526 -392.308279) (xy 282.466732 -392.252264) (xy 282.4432 -392.192831) (xy 282.427303 -392.130917)
			(xy 282.419292 -392.067499) (xy 280.866596 -392.067499) (xy 280.866596 -393.137855) (xy 282.07436 -393.137855)
			(xy 282.07436 -393.073933) (xy 282.082371 -393.010515) (xy 282.098268 -392.948601) (xy 282.1218 -392.889168)
			(xy 282.152594 -392.833153) (xy 282.190167 -392.781438) (xy 282.233924 -392.734841) (xy 282.283177 -392.694096)
			(xy 282.337148 -392.659845) (xy 282.394987 -392.632628) (xy 282.45578 -392.612875) (xy 282.51857 -392.600897)
			(xy 282.582366 -392.596884) (xy 282.646162 -392.600897) (xy 282.708952 -392.612875) (xy 282.769745 -392.632628)
			(xy 282.827584 -392.659845) (xy 282.881555 -392.694096) (xy 282.930808 -392.734841) (xy 282.974565 -392.781438)
			(xy 283.012138 -392.833153) (xy 283.042932 -392.889168) (xy 283.066464 -392.948601) (xy 283.082361 -393.010515)
			(xy 283.090372 -393.073933) (xy 283.090874 -393.105894) (xy 283.090372 -393.137855) (xy 283.082361 -393.201273)
			(xy 283.066464 -393.263187) (xy 283.042932 -393.32262) (xy 283.012138 -393.378635) (xy 282.974565 -393.43035)
			(xy 282.930808 -393.476947) (xy 282.881555 -393.517692) (xy 282.827584 -393.551943) (xy 282.769745 -393.57916)
			(xy 282.708952 -393.598913) (xy 282.646162 -393.610891) (xy 282.582366 -393.614905) (xy 282.51857 -393.610891)
			(xy 282.45578 -393.598913) (xy 282.394987 -393.57916) (xy 282.337148 -393.551943) (xy 282.283177 -393.517692)
			(xy 282.233924 -393.476947) (xy 282.190167 -393.43035) (xy 282.152594 -393.378635) (xy 282.1218 -393.32262)
			(xy 282.098268 -393.263187) (xy 282.082371 -393.201273) (xy 282.07436 -393.137855) (xy 280.866596 -393.137855)
			(xy 280.866596 -394.070078) (xy 283.861 -394.070078) (xy 283.865071 -394.014456) (xy 283.877197 -393.960019)
			(xy 283.89712 -393.907928) (xy 283.924416 -393.859293) (xy 283.958502 -393.81515) (xy 283.998651 -393.776441)
			(xy 284.044009 -393.74399) (xy 284.093609 -393.718489) (xy 284.146393 -393.700482) (xy 284.201236 -393.690352)
			(xy 284.25697 -393.688315) (xy 284.312407 -393.694415) (xy 284.366364 -393.708521) (xy 284.417693 -393.730333)
			(xy 284.465299 -393.759387) (xy 284.508167 -393.795062) (xy 284.545384 -393.836599) (xy 284.576157 -393.883112)
			(xy 284.599829 -393.933609) (xy 284.615897 -393.987016) (xy 284.61758 -393.99845) (xy 294.51046 -393.99845)
			(xy 294.510873 -393.968733) (xy 294.517813 -393.909705) (xy 294.531581 -393.851888) (xy 294.55199 -393.796068)
			(xy 294.578761 -393.743004) (xy 294.611531 -393.69342) (xy 294.649853 -393.647991) (xy 294.671242 -393.627356)
			(xy 294.671496 -393.627102) (xy 294.678191 -393.620236) (xy 294.686278 -393.602862) (xy 294.687244 -393.59332)
			(xy 294.69207 -393.514072) (xy 294.686228 -393.495784) (xy 294.679878 -393.488164) (xy 294.663232 -393.467537)
			(xy 294.63526 -393.422512) (xy 294.613799 -393.374045) (xy 294.599263 -393.32307) (xy 294.591934 -393.270573)
			(xy 294.591486 -393.24407) (xy 294.591486 -393.243816) (xy 294.59201 -393.216113) (xy 294.600049 -393.161294)
			(xy 294.615932 -393.108213) (xy 294.639324 -393.057987) (xy 294.669733 -393.011673) (xy 294.706521 -392.970243)
			(xy 294.748914 -392.934568) (xy 294.796021 -392.9054) (xy 294.84685 -392.88335) (xy 294.900334 -392.868884)
			(xy 294.927782 -392.865102) (xy 294.928036 -392.865102) (xy 294.937428 -392.8635) (xy 294.954134 -392.854367)
			(xy 294.960548 -392.847322) (xy 295.005506 -392.793982) (xy 295.011222 -392.78654) (xy 295.017346 -392.768821)
			(xy 295.017444 -392.759438) (xy 295.017444 -392.758422) (xy 295.016682 -392.733784) (xy 295.016682 -392.733276)
			(xy 295.017199 -392.702556) (xy 295.02463 -392.641567) (xy 295.039355 -392.581917) (xy 295.061162 -392.524477)
			(xy 295.089731 -392.470082) (xy 295.124646 -392.419527) (xy 295.165399 -392.373548) (xy 295.211396 -392.332814)
			(xy 295.261966 -392.29792) (xy 295.316372 -392.269374) (xy 295.373821 -392.247592) (xy 295.433477 -392.232891)
			(xy 295.49447 -392.225486) (xy 295.52519 -392.225022) (xy 295.555923 -392.225447) (xy 295.616941 -392.232855)
			(xy 295.676621 -392.247565) (xy 295.734093 -392.269361) (xy 295.788518 -392.297926) (xy 295.839104 -392.332843)
			(xy 295.885111 -392.373603) (xy 295.92587 -392.419612) (xy 295.960785 -392.470199) (xy 295.989348 -392.524625)
			(xy 296.011141 -392.582098) (xy 296.025848 -392.641779) (xy 296.033254 -392.702797) (xy 296.033698 -392.73353)
			(xy 296.033273 -392.764252) (xy 296.025865 -392.825249) (xy 296.011162 -392.884908) (xy 295.989377 -392.942361)
			(xy 295.960828 -392.996771) (xy 295.927769 -393.04468) (xy 299.683676 -393.04468) (xy 299.687747 -392.989058)
			(xy 299.699873 -392.934621) (xy 299.719796 -392.88253) (xy 299.747092 -392.833895) (xy 299.781178 -392.789752)
			(xy 299.821327 -392.751043) (xy 299.866685 -392.718592) (xy 299.916285 -392.693091) (xy 299.969069 -392.675084)
			(xy 300.023912 -392.664954) (xy 300.079646 -392.662917) (xy 300.135083 -392.669017) (xy 300.18904 -392.683123)
			(xy 300.240369 -392.704935) (xy 300.287975 -392.733989) (xy 300.330454 -392.76934) (xy 300.943754 -392.76934)
			(xy 300.943754 -392.709404) (xy 300.951577 -392.649982) (xy 300.96709 -392.592089) (xy 300.990026 -392.536716)
			(xy 301.019993 -392.48481) (xy 301.05648 -392.43726) (xy 301.09886 -392.39488) (xy 301.14641 -392.358393)
			(xy 301.198316 -392.328426) (xy 301.253689 -392.30549) (xy 301.311582 -392.289977) (xy 301.371004 -392.282154)
			(xy 301.43094 -392.282154) (xy 301.490362 -392.289977) (xy 301.548255 -392.30549) (xy 301.603628 -392.328426)
			(xy 301.655534 -392.358393) (xy 301.703084 -392.39488) (xy 301.745464 -392.43726) (xy 301.781951 -392.48481)
			(xy 301.811918 -392.536716) (xy 301.834854 -392.592089) (xy 301.850367 -392.649982) (xy 301.85819 -392.709404)
			(xy 301.85868 -392.739372) (xy 301.85819 -392.76934) (xy 301.850367 -392.828762) (xy 301.834854 -392.886655)
			(xy 301.811918 -392.942028) (xy 301.781951 -392.993934) (xy 301.745464 -393.041484) (xy 301.703084 -393.083864)
			(xy 301.655534 -393.120351) (xy 301.603628 -393.150318) (xy 301.548255 -393.173254) (xy 301.490362 -393.188767)
			(xy 301.43094 -393.19659) (xy 301.371004 -393.19659) (xy 301.311582 -393.188767) (xy 301.253689 -393.173254)
			(xy 301.198316 -393.150318) (xy 301.14641 -393.120351) (xy 301.09886 -393.083864) (xy 301.05648 -393.041484)
			(xy 301.019993 -392.993934) (xy 300.990026 -392.942028) (xy 300.96709 -392.886655) (xy 300.951577 -392.828762)
			(xy 300.943754 -392.76934) (xy 300.330454 -392.76934) (xy 300.330843 -392.769664) (xy 300.36806 -392.811201)
			(xy 300.398833 -392.857714) (xy 300.422505 -392.908211) (xy 300.438573 -392.961618) (xy 300.446693 -393.016794)
			(xy 300.447202 -393.04468) (xy 300.446693 -393.072566) (xy 300.438573 -393.127742) (xy 300.422505 -393.181149)
			(xy 300.398833 -393.231646) (xy 300.36806 -393.278159) (xy 300.330843 -393.319696) (xy 300.287975 -393.355371)
			(xy 300.240369 -393.384425) (xy 300.18904 -393.406237) (xy 300.135083 -393.420343) (xy 300.079646 -393.426443)
			(xy 300.023912 -393.424406) (xy 299.969069 -393.414276) (xy 299.916285 -393.396269) (xy 299.866685 -393.370768)
			(xy 299.821327 -393.338317) (xy 299.781178 -393.299608) (xy 299.747092 -393.255465) (xy 299.719796 -393.20683)
			(xy 299.699873 -393.154739) (xy 299.687747 -393.100302) (xy 299.683676 -393.04468) (xy 295.927769 -393.04468)
			(xy 295.925931 -393.047344) (xy 295.885195 -393.093343) (xy 295.839212 -393.134099) (xy 295.788654 -393.169018)
			(xy 295.734257 -393.197589) (xy 295.676813 -393.219398) (xy 295.617159 -393.234127) (xy 295.556166 -393.24156)
			(xy 295.525444 -393.242038) (xy 295.52519 -393.242038) (xy 295.508759 -393.241884) (xy 295.475967 -393.239723)
			(xy 295.459658 -393.23772) (xy 295.450006 -393.23645) (xy 295.431464 -393.241022) (xy 295.359328 -393.292838)
			(xy 295.348914 -393.309094) (xy 295.347136 -393.318746) (xy 295.342089 -393.342115) (xy 295.326919 -393.387455)
			(xy 295.3062 -393.430544) (xy 295.293542 -393.450826) (xy 295.288208 -393.458954) (xy 295.284398 -393.47775)
			(xy 295.300908 -393.565888) (xy 295.311068 -393.582144) (xy 295.318942 -393.587732) (xy 295.346205 -393.60832)
			(xy 295.39547 -393.655652) (xy 295.437957 -393.709153) (xy 295.4729 -393.767859) (xy 295.499672 -393.830714)
			(xy 295.517789 -393.896586) (xy 295.526927 -393.964291) (xy 295.527364 -393.991454) (xy 299.684638 -393.991454)
			(xy 299.684638 -393.936946) (xy 299.692395 -393.882993) (xy 299.707751 -393.830694) (xy 299.730395 -393.781112)
			(xy 299.759863 -393.735257) (xy 299.795558 -393.694062) (xy 299.836752 -393.658367) (xy 299.882606 -393.628897)
			(xy 299.932188 -393.606254) (xy 299.984487 -393.590896) (xy 300.03844 -393.583138) (xy 300.065694 -393.582652)
			(xy 300.094327 -393.583205) (xy 300.150949 -393.591764) (xy 300.205656 -393.608688) (xy 300.257219 -393.6336)
			(xy 300.30448 -393.665938) (xy 300.346377 -393.704976) (xy 300.381968 -393.749838) (xy 300.396656 -393.774422)
			(xy 300.401481 -393.782122) (xy 300.415417 -393.793764) (xy 300.43253 -393.799837) (xy 300.441614 -393.800076)
			(xy 300.544738 -393.798044) (xy 300.568106 -393.783566) (xy 300.57471 -393.771374) (xy 300.589643 -393.744119)
			(xy 300.625774 -393.693554) (xy 300.668418 -393.648346) (xy 300.716789 -393.609327) (xy 300.769998 -393.577216)
			(xy 300.827063 -393.552603) (xy 300.886936 -393.535943) (xy 300.948512 -393.527541) (xy 300.979586 -393.527026)
			(xy 301.009556 -393.527474) (xy 301.068984 -393.535297) (xy 301.126882 -393.55081) (xy 301.182259 -393.573748)
			(xy 301.234169 -393.603718) (xy 301.281722 -393.640208) (xy 301.324105 -393.682593) (xy 301.360593 -393.730148)
			(xy 301.390561 -393.782059) (xy 301.413497 -393.837437) (xy 301.429007 -393.895336) (xy 301.436827 -393.954764)
			(xy 301.437294 -393.984734) (xy 301.436783 -394.015614) (xy 301.428468 -394.076811) (xy 301.411994 -394.136333)
			(xy 301.387661 -394.193096) (xy 301.355911 -394.246069) (xy 301.317321 -394.294288) (xy 301.295308 -394.31595)
			(xy 301.28716 -394.324555) (xy 301.279071 -394.346796) (xy 301.279814 -394.358622) (xy 301.289212 -394.43914)
			(xy 301.291064 -394.450804) (xy 301.303782 -394.47067) (xy 301.313596 -394.47724) (xy 301.31385 -394.47724)
			(xy 301.339186 -394.492753) (xy 301.38604 -394.529278) (xy 301.427772 -394.571559) (xy 301.463681 -394.618886)
			(xy 301.493162 -394.670463) (xy 301.515721 -394.725421) (xy 301.530976 -394.782837) (xy 301.538671 -394.841744)
			(xy 301.539148 -394.871448) (xy 301.538676 -394.902107) (xy 301.530484 -394.962875) (xy 301.514253 -395.022006)
			(xy 301.490274 -395.078441) (xy 301.458977 -395.131169) (xy 301.42092 -395.179248) (xy 301.399194 -395.200886)
			(xy 301.391457 -395.209199) (xy 301.38346 -395.23042) (xy 301.385367 -395.253017) (xy 301.390558 -395.263116)
			(xy 301.404693 -395.288586) (xy 301.424764 -395.343264) (xy 301.434928 -395.400617) (xy 301.435516 -395.42974)
			(xy 301.435006 -395.455727) (xy 301.426876 -395.507062) (xy 301.410815 -395.556492) (xy 301.387219 -395.602802)
			(xy 301.356669 -395.64485) (xy 301.319918 -395.681601) (xy 301.27787 -395.712151) (xy 301.23156 -395.735747)
			(xy 301.18213 -395.751808) (xy 301.130795 -395.759938) (xy 301.078821 -395.759938) (xy 301.027486 -395.751808)
			(xy 300.978056 -395.735747) (xy 300.931746 -395.712151) (xy 300.889698 -395.681601) (xy 300.852947 -395.64485)
			(xy 300.822397 -395.602802) (xy 300.798801 -395.556492) (xy 300.78274 -395.507062) (xy 300.77461 -395.455727)
			(xy 300.7741 -395.42974) (xy 300.7741 -395.429486) (xy 300.774536 -395.405015) (xy 300.781733 -395.356606)
			(xy 300.795996 -395.30979) (xy 300.806104 -395.2875) (xy 300.810447 -395.277031) (xy 300.810451 -395.25439)
			(xy 300.800764 -395.233926) (xy 300.792388 -395.226286) (xy 300.770175 -395.207612) (xy 300.730164 -395.165578)
			(xy 300.695791 -395.118822) (xy 300.667607 -395.068093) (xy 300.646065 -395.014208) (xy 300.631511 -394.958031)
			(xy 300.624178 -394.900464) (xy 300.623732 -394.871448) (xy 300.624223 -394.840568) (xy 300.632541 -394.779369)
			(xy 300.649018 -394.719847) (xy 300.673355 -394.663083) (xy 300.705109 -394.610111) (xy 300.743703 -394.561893)
			(xy 300.765718 -394.540232) (xy 300.773866 -394.531626) (xy 300.781958 -394.509386) (xy 300.781212 -394.49756)
			(xy 300.771814 -394.417042) (xy 300.769961 -394.405379) (xy 300.757243 -394.385513) (xy 300.74743 -394.378942)
			(xy 300.747176 -394.378942) (xy 300.723786 -394.364728) (xy 300.680277 -394.331521) (xy 300.641044 -394.293354)
			(xy 300.60665 -394.250776) (xy 300.577587 -394.204395) (xy 300.565566 -394.179806) (xy 300.565566 -394.179552)
			(xy 300.561385 -394.171546) (xy 300.548417 -394.158986) (xy 300.531885 -394.151734) (xy 300.522894 -394.15085)
			(xy 300.433994 -394.145008) (xy 300.4249 -394.144771) (xy 300.40748 -394.149965) (xy 300.392968 -394.160913)
			(xy 300.387766 -394.168376) (xy 300.387766 -394.16863) (xy 300.37268 -394.191512) (xy 300.336989 -394.233104)
			(xy 300.295713 -394.269161) (xy 300.249702 -394.29894) (xy 300.199902 -394.321827) (xy 300.14734 -394.337352)
			(xy 300.093097 -394.345194) (xy 300.065694 -394.345668) (xy 300.03844 -394.345262) (xy 299.984487 -394.337504)
			(xy 299.932188 -394.322146) (xy 299.882606 -394.299503) (xy 299.836752 -394.270033) (xy 299.795558 -394.234338)
			(xy 299.759863 -394.193143) (xy 299.730395 -394.147288) (xy 299.707751 -394.097706) (xy 299.692395 -394.045407)
			(xy 299.684638 -393.991454) (xy 295.527364 -393.991454) (xy 295.527476 -393.99845) (xy 295.526974 -394.030411)
			(xy 295.518963 -394.093829) (xy 295.503066 -394.155743) (xy 295.479534 -394.215176) (xy 295.44874 -394.271191)
			(xy 295.411167 -394.322906) (xy 295.36741 -394.369503) (xy 295.318157 -394.410248) (xy 295.264186 -394.444499)
			(xy 295.206347 -394.471716) (xy 295.145554 -394.491469) (xy 295.082764 -394.503447) (xy 295.018968 -394.507461)
			(xy 294.955172 -394.503447) (xy 294.892382 -394.491469) (xy 294.831589 -394.471716) (xy 294.77375 -394.444499)
			(xy 294.719779 -394.410248) (xy 294.670526 -394.369503) (xy 294.626769 -394.322906) (xy 294.589196 -394.271191)
			(xy 294.558402 -394.215176) (xy 294.53487 -394.155743) (xy 294.518973 -394.093829) (xy 294.510962 -394.030411)
			(xy 294.51046 -393.99845) (xy 284.61758 -393.99845) (xy 284.624017 -394.042192) (xy 284.624526 -394.070078)
			(xy 284.624017 -394.097964) (xy 284.615897 -394.15314) (xy 284.599829 -394.206547) (xy 284.576157 -394.257044)
			(xy 284.545384 -394.303557) (xy 284.508167 -394.345094) (xy 284.465299 -394.380769) (xy 284.417693 -394.409823)
			(xy 284.366364 -394.431635) (xy 284.312407 -394.445741) (xy 284.25697 -394.451841) (xy 284.201236 -394.449804)
			(xy 284.146393 -394.439674) (xy 284.093609 -394.421667) (xy 284.044009 -394.396166) (xy 283.998651 -394.363715)
			(xy 283.958502 -394.325006) (xy 283.924416 -394.280863) (xy 283.89712 -394.232228) (xy 283.877197 -394.180137)
			(xy 283.865071 -394.1257) (xy 283.861 -394.070078) (xy 280.866596 -394.070078) (xy 280.866596 -394.47597)
			(xy 280.870152 -394.48867) (xy 280.872692 -394.493242) (xy 280.876746 -394.49965) (xy 280.881272 -394.514114)
			(xy 280.881582 -394.52169) (xy 280.881582 -395.343083) (xy 283.83458 -395.343083) (xy 283.83458 -395.279161)
			(xy 283.842591 -395.215743) (xy 283.858488 -395.153829) (xy 283.88202 -395.094396) (xy 283.912814 -395.038381)
			(xy 283.950387 -394.986666) (xy 283.994144 -394.940069) (xy 284.043397 -394.899324) (xy 284.097368 -394.865073)
			(xy 284.155207 -394.837856) (xy 284.216 -394.818103) (xy 284.27879 -394.806125) (xy 284.342586 -394.802112)
			(xy 284.406382 -394.806125) (xy 284.469172 -394.818103) (xy 284.529965 -394.837856) (xy 284.587804 -394.865073)
			(xy 284.641775 -394.899324) (xy 284.691028 -394.940069) (xy 284.734785 -394.986666) (xy 284.772358 -395.038381)
			(xy 284.803152 -395.094396) (xy 284.826684 -395.153829) (xy 284.842581 -395.215743) (xy 284.847218 -395.252448)
			(xy 287.789874 -395.252448) (xy 287.79034 -395.22093) (xy 287.798144 -395.158379) (xy 287.813612 -395.097271)
			(xy 287.836509 -395.038541) (xy 287.866484 -394.983088) (xy 287.903077 -394.931761) (xy 287.945729 -394.885346)
			(xy 287.969452 -394.86459) (xy 287.976269 -394.858256) (xy 287.985262 -394.841985) (xy 287.986978 -394.83284)
			(xy 287.991042 -394.80236) (xy 287.991925 -394.793185) (xy 287.9879 -394.775216) (xy 287.983168 -394.767308)
			(xy 287.968105 -394.74373) (xy 287.944271 -394.693112) (xy 287.928089 -394.639555) (xy 287.919908 -394.584208)
			(xy 287.919414 -394.556234) (xy 287.9199 -394.528983) (xy 287.927656 -394.475035) (xy 287.943011 -394.42274)
			(xy 287.965653 -394.373163) (xy 287.995119 -394.327313) (xy 288.03081 -394.286122) (xy 288.072001 -394.250431)
			(xy 288.117851 -394.220965) (xy 288.167428 -394.198323) (xy 288.219723 -394.182968) (xy 288.273671 -394.175212)
			(xy 288.328173 -394.175212) (xy 288.382121 -394.182968) (xy 288.434416 -394.198323) (xy 288.483993 -394.220965)
			(xy 288.529843 -394.250431) (xy 288.571034 -394.286122) (xy 288.606725 -394.327313) (xy 288.636191 -394.373163)
			(xy 288.658833 -394.42274) (xy 288.674188 -394.475035) (xy 288.681944 -394.528983) (xy 288.68243 -394.556234)
			(xy 288.68243 -394.556488) (xy 288.681877 -394.584772) (xy 288.673473 -394.640714) (xy 288.656908 -394.694804)
			(xy 288.632543 -394.745858) (xy 288.617152 -394.769594) (xy 288.612388 -394.777426) (xy 288.608218 -394.795261)
			(xy 288.609024 -394.804392) (xy 288.612834 -394.835126) (xy 288.614378 -394.844345) (xy 288.623243 -394.860786)
			(xy 288.630106 -394.86713) (xy 288.653471 -394.88788) (xy 288.695485 -394.934138) (xy 288.731513 -394.985196)
			(xy 288.761011 -395.040285) (xy 288.783535 -395.098575) (xy 288.798744 -395.159185) (xy 288.80641 -395.221203)
			(xy 288.80689 -395.252448) (xy 288.806792 -395.258657) (xy 292.070421 -395.258657) (xy 292.070421 -395.204143)
			(xy 292.07818 -395.150184) (xy 292.093539 -395.097879) (xy 292.116186 -395.048292) (xy 292.14566 -395.002433)
			(xy 292.181361 -394.961235) (xy 292.222562 -394.925538) (xy 292.268423 -394.896069) (xy 292.318012 -394.873426)
			(xy 292.370319 -394.858072) (xy 292.424279 -394.850318) (xy 292.451536 -394.849858) (xy 292.480512 -394.850422)
			(xy 292.537797 -394.859202) (xy 292.593091 -394.876553) (xy 292.645122 -394.902075) (xy 292.669214 -394.918184)
			(xy 292.669468 -394.918438) (xy 292.677464 -394.923307) (xy 292.695707 -394.927462) (xy 292.705028 -394.926566)
			(xy 292.78326 -394.915644) (xy 292.800278 -394.905992) (xy 292.80612 -394.898626) (xy 292.826876 -394.873816)
			(xy 292.873641 -394.829124) (xy 292.925693 -394.790721) (xy 292.982194 -394.759226) (xy 293.042232 -394.735147)
			(xy 293.104837 -394.718873) (xy 293.169001 -394.710666) (xy 293.201344 -394.710158) (xy 293.230888 -394.710546)
			(xy 293.289579 -394.717394) (xy 293.347079 -394.731004) (xy 293.402612 -394.751192) (xy 293.455428 -394.777686)
			(xy 293.504814 -394.810128) (xy 293.527734 -394.828776) (xy 293.534719 -394.834093) (xy 293.551221 -394.840054)
			(xy 293.559992 -394.84046) (xy 293.589964 -394.840714) (xy 293.598646 -394.840318) (xy 293.615004 -394.834482)
			(xy 293.621968 -394.829284) (xy 293.649297 -394.807861) (xy 293.708666 -394.771842) (xy 293.772379 -394.744225)
			(xy 293.839254 -394.725523) (xy 293.90805 -394.716083) (xy 293.94277 -394.715492) (xy 293.973501 -394.715966)
			(xy 294.034517 -394.723371) (xy 294.094194 -394.738077) (xy 294.151664 -394.75987) (xy 294.206088 -394.788431)
			(xy 294.256672 -394.823344) (xy 294.302679 -394.8641) (xy 294.343438 -394.910104) (xy 294.378354 -394.960686)
			(xy 294.406918 -395.015109) (xy 294.428714 -395.072577) (xy 294.443424 -395.132254) (xy 294.450832 -395.193269)
			(xy 294.451278 -395.224) (xy 294.450836 -395.254943) (xy 294.443347 -395.316375) (xy 294.428457 -395.376444)
			(xy 294.406385 -395.43426) (xy 294.377458 -395.48897) (xy 294.342103 -395.539764) (xy 294.300844 -395.58589)
			(xy 294.254291 -395.626667) (xy 294.203132 -395.661491) (xy 294.148124 -395.689847) (xy 294.090081 -395.711316)
			(xy 294.02986 -395.72558) (xy 293.999158 -395.72946) (xy 293.987982 -395.73073) (xy 293.96817 -395.742922)
			(xy 293.913306 -395.82979) (xy 293.910766 -395.852904) (xy 293.914576 -395.863572) (xy 293.923514 -395.890476)
			(xy 293.936068 -395.945762) (xy 293.942381 -396.002103) (xy 293.94277 -396.03045) (xy 293.94277 -396.030704)
			(xy 293.942268 -396.062665) (xy 293.934257 -396.126083) (xy 293.91836 -396.187997) (xy 293.894828 -396.24743)
			(xy 293.864034 -396.303445) (xy 293.826461 -396.35516) (xy 293.782704 -396.401757) (xy 293.733451 -396.442502)
			(xy 293.67948 -396.476753) (xy 293.621641 -396.50397) (xy 293.560848 -396.523723) (xy 293.498058 -396.535701)
			(xy 293.434262 -396.539715) (xy 293.370466 -396.535701) (xy 293.307676 -396.523723) (xy 293.246883 -396.50397)
			(xy 293.189044 -396.476753) (xy 293.135073 -396.442502) (xy 293.08582 -396.401757) (xy 293.042063 -396.35516)
			(xy 293.00449 -396.303445) (xy 292.973696 -396.24743) (xy 292.950164 -396.187997) (xy 292.934267 -396.126083)
			(xy 292.926256 -396.062665) (xy 292.925754 -396.030704) (xy 292.925754 -396.03045) (xy 292.926208 -395.999621)
			(xy 292.933669 -395.938415) (xy 292.948486 -395.878563) (xy 292.970443 -395.820947) (xy 292.984428 -395.793468)
			(xy 292.989 -395.784832) (xy 292.991032 -395.765274) (xy 292.96614 -395.678406) (xy 292.954456 -395.663166)
			(xy 292.94582 -395.65834) (xy 292.921862 -395.64395) (xy 292.87692 -395.610727) (xy 292.835893 -395.572775)
			(xy 292.817296 -395.551914) (xy 292.817042 -395.55166) (xy 292.810551 -395.544852) (xy 292.79384 -395.536243)
			(xy 292.78453 -395.534896) (xy 292.715442 -395.527276) (xy 292.705906 -395.526682) (xy 292.687505 -395.531774)
			(xy 292.679628 -395.537182) (xy 292.654741 -395.554957) (xy 292.60052 -395.583237) (xy 292.542481 -395.602505)
			(xy 292.482112 -395.612266) (xy 292.451536 -395.612874) (xy 292.424279 -395.612482) (xy 292.370319 -395.604728)
			(xy 292.318012 -395.589374) (xy 292.268423 -395.566731) (xy 292.222562 -395.537262) (xy 292.181361 -395.501565)
			(xy 292.14566 -395.460367) (xy 292.116186 -395.414508) (xy 292.093539 -395.364921) (xy 292.07818 -395.312616)
			(xy 292.070421 -395.258657) (xy 288.806792 -395.258657) (xy 288.806388 -395.284409) (xy 288.798377 -395.347827)
			(xy 288.78248 -395.409741) (xy 288.758948 -395.469174) (xy 288.728154 -395.525189) (xy 288.690581 -395.576904)
			(xy 288.646824 -395.623501) (xy 288.597571 -395.664246) (xy 288.5436 -395.698497) (xy 288.485761 -395.725714)
			(xy 288.424968 -395.745467) (xy 288.362178 -395.757445) (xy 288.298382 -395.761459) (xy 288.234586 -395.757445)
			(xy 288.171796 -395.745467) (xy 288.111003 -395.725714) (xy 288.053164 -395.698497) (xy 287.999193 -395.664246)
			(xy 287.94994 -395.623501) (xy 287.906183 -395.576904) (xy 287.86861 -395.525189) (xy 287.837816 -395.469174)
			(xy 287.814284 -395.409741) (xy 287.798387 -395.347827) (xy 287.790376 -395.284409) (xy 287.789874 -395.252448)
			(xy 284.847218 -395.252448) (xy 284.850592 -395.279161) (xy 284.851094 -395.311122) (xy 284.850592 -395.343083)
			(xy 284.842581 -395.406501) (xy 284.826684 -395.468415) (xy 284.803152 -395.527848) (xy 284.772358 -395.583863)
			(xy 284.734785 -395.635578) (xy 284.691028 -395.682175) (xy 284.641775 -395.72292) (xy 284.587804 -395.757171)
			(xy 284.529965 -395.784388) (xy 284.469172 -395.804141) (xy 284.406382 -395.816119) (xy 284.342586 -395.820133)
			(xy 284.27879 -395.816119) (xy 284.216 -395.804141) (xy 284.155207 -395.784388) (xy 284.097368 -395.757171)
			(xy 284.043397 -395.72292) (xy 283.994144 -395.682175) (xy 283.950387 -395.635578) (xy 283.912814 -395.583863)
			(xy 283.88202 -395.527848) (xy 283.858488 -395.468415) (xy 283.842591 -395.406501) (xy 283.83458 -395.343083)
			(xy 280.881582 -395.343083) (xy 280.881582 -395.926521) (xy 281.864048 -395.926521) (xy 281.864048 -395.862599)
			(xy 281.872059 -395.799181) (xy 281.887956 -395.737267) (xy 281.911488 -395.677834) (xy 281.942282 -395.621819)
			(xy 281.979855 -395.570104) (xy 282.023612 -395.523507) (xy 282.072865 -395.482762) (xy 282.126836 -395.448511)
			(xy 282.184675 -395.421294) (xy 282.245468 -395.401541) (xy 282.308258 -395.389563) (xy 282.372054 -395.38555)
			(xy 282.43585 -395.389563) (xy 282.49864 -395.401541) (xy 282.559433 -395.421294) (xy 282.617272 -395.448511)
			(xy 282.671243 -395.482762) (xy 282.720496 -395.523507) (xy 282.764253 -395.570104) (xy 282.801826 -395.621819)
			(xy 282.83262 -395.677834) (xy 282.856152 -395.737267) (xy 282.872049 -395.799181) (xy 282.88006 -395.862599)
			(xy 282.880562 -395.89456) (xy 282.88006 -395.926521) (xy 282.872049 -395.989939) (xy 282.856152 -396.051853)
			(xy 282.83262 -396.111286) (xy 282.801826 -396.167301) (xy 282.764253 -396.219016) (xy 282.720496 -396.265613)
			(xy 282.671243 -396.306358) (xy 282.617272 -396.340609) (xy 282.559433 -396.367826) (xy 282.49864 -396.387579)
			(xy 282.43585 -396.399557) (xy 282.372054 -396.403571) (xy 282.308258 -396.399557) (xy 282.245468 -396.387579)
			(xy 282.184675 -396.367826) (xy 282.126836 -396.340609) (xy 282.072865 -396.306358) (xy 282.023612 -396.265613)
			(xy 281.979855 -396.219016) (xy 281.942282 -396.167301) (xy 281.911488 -396.111286) (xy 281.887956 -396.051853)
			(xy 281.872059 -395.989939) (xy 281.864048 -395.926521) (xy 280.881582 -395.926521) (xy 280.881582 -396.980367)
			(xy 289.7223 -396.980367) (xy 289.7223 -396.916445) (xy 289.730311 -396.853027) (xy 289.746208 -396.791113)
			(xy 289.76974 -396.73168) (xy 289.800534 -396.675665) (xy 289.838107 -396.62395) (xy 289.881864 -396.577353)
			(xy 289.931117 -396.536608) (xy 289.985088 -396.502357) (xy 290.042927 -396.47514) (xy 290.10372 -396.455387)
			(xy 290.16651 -396.443409) (xy 290.230306 -396.439396) (xy 290.294102 -396.443409) (xy 290.356892 -396.455387)
			(xy 290.417685 -396.47514) (xy 290.475524 -396.502357) (xy 290.529495 -396.536608) (xy 290.578748 -396.577353)
			(xy 290.622505 -396.62395) (xy 290.660078 -396.675665) (xy 290.690872 -396.73168) (xy 290.714404 -396.791113)
			(xy 290.730301 -396.853027) (xy 290.738312 -396.916445) (xy 290.738814 -396.948406) (xy 290.738312 -396.980367)
			(xy 290.737221 -396.989003) (xy 291.03675 -396.989003) (xy 291.03675 -396.925081) (xy 291.044761 -396.861663)
			(xy 291.060658 -396.799749) (xy 291.08419 -396.740316) (xy 291.114984 -396.684301) (xy 291.152557 -396.632586)
			(xy 291.196314 -396.585989) (xy 291.245567 -396.545244) (xy 291.299538 -396.510993) (xy 291.357377 -396.483776)
			(xy 291.41817 -396.464023) (xy 291.48096 -396.452045) (xy 291.544756 -396.448032) (xy 291.608552 -396.452045)
			(xy 291.671342 -396.464023) (xy 291.732135 -396.483776) (xy 291.789974 -396.510993) (xy 291.843945 -396.545244)
			(xy 291.893198 -396.585989) (xy 291.909642 -396.6035) (xy 295.876642 -396.6035) (xy 295.880657 -396.539695)
			(xy 295.892637 -396.476896) (xy 295.912394 -396.416094) (xy 295.939616 -396.358248) (xy 295.973874 -396.30427)
			(xy 296.014627 -396.255011) (xy 296.061233 -396.211249) (xy 296.112956 -396.173674) (xy 296.168981 -396.142878)
			(xy 296.228425 -396.119347) (xy 296.290348 -396.103452) (xy 296.353776 -396.095444) (xy 296.385742 -396.094966)
			(xy 296.417867 -396.09545) (xy 296.481606 -396.103543) (xy 296.543818 -396.119596) (xy 296.603515 -396.143353)
			(xy 296.631868 -396.158466) (xy 296.632122 -396.158466) (xy 296.64309 -396.163731) (xy 296.667369 -396.164401)
			(xy 296.678604 -396.159736) (xy 296.764456 -396.118334) (xy 296.779188 -396.09903) (xy 296.78122 -396.086584)
			(xy 296.787265 -396.05412) (xy 296.806695 -395.991007) (xy 296.834132 -395.930941) (xy 296.869115 -395.874932)
			(xy 296.889678 -395.849094) (xy 296.89496 -395.842102) (xy 296.900798 -395.825594) (xy 296.901108 -395.816836)
			(xy 296.901108 -395.662912) (xy 296.900736 -395.654166) (xy 296.894905 -395.637675) (xy 296.889678 -395.630654)
			(xy 296.867916 -395.603281) (xy 296.831367 -395.543663) (xy 296.803325 -395.479602) (xy 296.784319 -395.412305)
			(xy 296.774706 -395.343039) (xy 296.774108 -395.308074) (xy 296.774532 -395.277342) (xy 296.781943 -395.216326)
			(xy 296.796656 -395.156648) (xy 296.818454 -395.099179) (xy 296.84702 -395.044757) (xy 296.881938 -394.994174)
			(xy 296.922699 -394.948169) (xy 296.968707 -394.907412) (xy 297.019292 -394.872499) (xy 297.073718 -394.843937)
			(xy 297.131189 -394.822143) (xy 297.190867 -394.807436) (xy 297.251884 -394.800029) (xy 297.282616 -394.799566)
			(xy 297.28287 -394.799566) (xy 297.303732 -394.799785) (xy 297.345314 -394.803215) (xy 297.365928 -394.806424)
			(xy 297.374873 -394.807544) (xy 297.392569 -394.804158) (xy 297.400472 -394.79982) (xy 297.457368 -394.765784)
			(xy 297.464848 -394.760888) (xy 297.476041 -394.746964) (xy 297.479212 -394.738606) (xy 297.479212 -394.738098)
			(xy 297.48801 -394.7131) (xy 297.511518 -394.665605) (xy 297.541376 -394.621824) (xy 297.577009 -394.582598)
			(xy 297.61773 -394.548685) (xy 297.662755 -394.520737) (xy 297.711217 -394.499293) (xy 297.762181 -394.484766)
			(xy 297.814665 -394.477437) (xy 297.841162 -394.476986) (xy 297.868414 -394.477491) (xy 297.922363 -394.485242)
			(xy 297.97466 -394.500593) (xy 298.024239 -394.523231) (xy 298.070092 -394.552694) (xy 298.111285 -394.588384)
			(xy 298.146979 -394.629573) (xy 298.176448 -394.675422) (xy 298.199091 -394.724999) (xy 298.214448 -394.777294)
			(xy 298.222206 -394.831242) (xy 298.22267 -394.858494) (xy 298.222107 -394.886464) (xy 298.213966 -394.941808)
			(xy 298.197827 -394.995369) (xy 298.174037 -395.045998) (xy 298.143107 -395.092609) (xy 298.1057 -395.134201)
			(xy 298.062619 -395.169883) (xy 298.014787 -395.198889) (xy 297.963231 -395.220597) (xy 297.909057 -395.234541)
			(xy 297.881294 -395.23797) (xy 297.87215 -395.238732) (xy 297.855894 -395.24686) (xy 297.804078 -395.30147)
			(xy 297.798202 -395.308187) (xy 297.791185 -395.324587) (xy 297.790362 -395.333474) (xy 297.790362 -395.333728)
			(xy 297.788249 -395.366054) (xy 297.776778 -395.429814) (xy 297.757302 -395.491601) (xy 297.730134 -395.550413)
			(xy 297.695717 -395.605297) (xy 297.675554 -395.630654) (xy 297.67033 -395.637607) (xy 297.664477 -395.653969)
			(xy 297.664124 -395.662658) (xy 297.664124 -395.816836) (xy 297.664467 -395.825585) (xy 297.670317 -395.842076)
			(xy 297.675554 -395.849094) (xy 297.697282 -395.876493) (xy 297.733838 -395.936103) (xy 297.761888 -396.000157)
			(xy 297.780902 -396.067449) (xy 297.790521 -396.136711) (xy 297.791124 -396.171674) (xy 297.791124 -396.172182)
			(xy 297.790354 -396.211032) (xy 297.778498 -396.287821) (xy 297.767502 -396.32509) (xy 297.763946 -396.336012)
			(xy 297.767248 -396.358872) (xy 297.82389 -396.443962) (xy 297.843702 -396.4559) (xy 297.855132 -396.456916)
			(xy 297.883235 -396.459951) (xy 297.938162 -396.473286) (xy 297.990521 -396.494579) (xy 298.039166 -396.523364)
			(xy 298.083033 -396.55901) (xy 298.12116 -396.600737) (xy 298.152714 -396.647633) (xy 298.167963 -396.679674)
			(xy 299.808644 -396.679674) (xy 299.812715 -396.624052) (xy 299.824841 -396.569615) (xy 299.844764 -396.517524)
			(xy 299.87206 -396.468889) (xy 299.906146 -396.424746) (xy 299.946295 -396.386037) (xy 299.991653 -396.353586)
			(xy 300.041253 -396.328085) (xy 300.094037 -396.310078) (xy 300.14888 -396.299948) (xy 300.204614 -396.297911)
			(xy 300.260051 -396.304011) (xy 300.314008 -396.318117) (xy 300.365337 -396.339929) (xy 300.412943 -396.368983)
			(xy 300.455811 -396.404658) (xy 300.493028 -396.446195) (xy 300.523801 -396.492708) (xy 300.547473 -396.543205)
			(xy 300.563541 -396.596612) (xy 300.571661 -396.651788) (xy 300.57217 -396.679674) (xy 300.571723 -396.704137)
			(xy 300.77461 -396.704137) (xy 300.77461 -396.652163) (xy 300.78274 -396.600828) (xy 300.798801 -396.551398)
			(xy 300.822397 -396.505088) (xy 300.852947 -396.46304) (xy 300.889698 -396.426289) (xy 300.931746 -396.395739)
			(xy 300.978056 -396.372143) (xy 301.027486 -396.356082) (xy 301.078821 -396.347952) (xy 301.130795 -396.347952)
			(xy 301.18213 -396.356082) (xy 301.23156 -396.372143) (xy 301.27787 -396.395739) (xy 301.319918 -396.426289)
			(xy 301.356669 -396.46304) (xy 301.387219 -396.505088) (xy 301.410815 -396.551398) (xy 301.426876 -396.600828)
			(xy 301.435006 -396.652163) (xy 301.435516 -396.67815) (xy 301.435006 -396.704137) (xy 301.426876 -396.755472)
			(xy 301.410815 -396.804902) (xy 301.387219 -396.851212) (xy 301.356669 -396.89326) (xy 301.319918 -396.930011)
			(xy 301.27787 -396.960561) (xy 301.23156 -396.984157) (xy 301.18213 -397.000218) (xy 301.130795 -397.008348)
			(xy 301.078821 -397.008348) (xy 301.027486 -397.000218) (xy 300.978056 -396.984157) (xy 300.931746 -396.960561)
			(xy 300.889698 -396.930011) (xy 300.852947 -396.89326) (xy 300.822397 -396.851212) (xy 300.798801 -396.804902)
			(xy 300.78274 -396.755472) (xy 300.77461 -396.704137) (xy 300.571723 -396.704137) (xy 300.571661 -396.70756)
			(xy 300.563541 -396.762736) (xy 300.547473 -396.816143) (xy 300.523801 -396.86664) (xy 300.493028 -396.913153)
			(xy 300.455811 -396.95469) (xy 300.412943 -396.990365) (xy 300.365337 -397.019419) (xy 300.314008 -397.041231)
			(xy 300.260051 -397.055337) (xy 300.204614 -397.061437) (xy 300.14888 -397.0594) (xy 300.094037 -397.04927)
			(xy 300.041253 -397.031263) (xy 299.991653 -397.005762) (xy 299.946295 -396.973311) (xy 299.906146 -396.934602)
			(xy 299.87206 -396.890459) (xy 299.844764 -396.841824) (xy 299.824841 -396.789733) (xy 299.812715 -396.735296)
			(xy 299.808644 -396.679674) (xy 298.167963 -396.679674) (xy 298.177004 -396.698671) (xy 298.1935 -396.752734)
			(xy 298.201838 -396.808638) (xy 298.20235 -396.8369) (xy 298.201864 -396.864151) (xy 298.194108 -396.918099)
			(xy 298.178753 -396.970394) (xy 298.156111 -397.019971) (xy 298.126645 -397.065821) (xy 298.090954 -397.107012)
			(xy 298.049763 -397.142703) (xy 298.003913 -397.172169) (xy 297.954336 -397.194811) (xy 297.902041 -397.210166)
			(xy 297.848093 -397.217922) (xy 297.793591 -397.217922) (xy 297.739643 -397.210166) (xy 297.687348 -397.194811)
			(xy 297.637771 -397.172169) (xy 297.591921 -397.142703) (xy 297.55073 -397.107012) (xy 297.515039 -397.065821)
			(xy 297.485573 -397.019971) (xy 297.462931 -396.970394) (xy 297.447576 -396.918099) (xy 297.43982 -396.864151)
			(xy 297.439334 -396.8369) (xy 297.439436 -396.825441) (xy 297.440834 -396.802566) (xy 297.442128 -396.79118)
			(xy 297.442833 -396.779849) (xy 297.435586 -396.758363) (xy 297.428158 -396.749778) (xy 297.372786 -396.692882)
			(xy 297.364359 -396.685233) (xy 297.343009 -396.677442) (xy 297.331638 -396.677896) (xy 297.331384 -396.677896)
			(xy 297.319221 -396.678974) (xy 297.294827 -396.680119) (xy 297.282616 -396.680182) (xy 297.250491 -396.67968)
			(xy 297.186753 -396.671593) (xy 297.124541 -396.655545) (xy 297.064843 -396.631792) (xy 297.03649 -396.616682)
			(xy 297.036236 -396.616682) (xy 297.025279 -396.611392) (xy 297.00099 -396.61074) (xy 296.989754 -396.615412)
			(xy 296.903902 -396.656814) (xy 296.88917 -396.676118) (xy 296.887138 -396.688564) (xy 296.881168 -396.720447)
			(xy 296.862263 -396.782498) (xy 296.835622 -396.84164) (xy 296.801677 -396.896916) (xy 296.760979 -396.947426)
			(xy 296.714189 -396.992351) (xy 296.662067 -397.030963) (xy 296.605458 -397.062633) (xy 296.545281 -397.086848)
			(xy 296.482514 -397.103215) (xy 296.418175 -397.111469) (xy 296.385742 -397.111982) (xy 296.353776 -397.111556)
			(xy 296.290348 -397.103548) (xy 296.228425 -397.087653) (xy 296.168981 -397.064122) (xy 296.112956 -397.033326)
			(xy 296.061233 -396.995751) (xy 296.014627 -396.951989) (xy 295.973874 -396.90273) (xy 295.939616 -396.848752)
			(xy 295.912394 -396.790906) (xy 295.892637 -396.730104) (xy 295.880657 -396.667305) (xy 295.876642 -396.6035)
			(xy 291.909642 -396.6035) (xy 291.936955 -396.632586) (xy 291.974528 -396.684301) (xy 292.005322 -396.740316)
			(xy 292.028854 -396.799749) (xy 292.044751 -396.861663) (xy 292.052762 -396.925081) (xy 292.053264 -396.957042)
			(xy 292.052762 -396.989003) (xy 292.044751 -397.052421) (xy 292.028854 -397.114335) (xy 292.005322 -397.173768)
			(xy 291.974528 -397.229783) (xy 291.936955 -397.281498) (xy 291.893198 -397.328095) (xy 291.843945 -397.36884)
			(xy 291.789974 -397.403091) (xy 291.732135 -397.430308) (xy 291.671342 -397.450061) (xy 291.608552 -397.462039)
			(xy 291.544756 -397.466053) (xy 291.48096 -397.462039) (xy 291.41817 -397.450061) (xy 291.357377 -397.430308)
			(xy 291.299538 -397.403091) (xy 291.245567 -397.36884) (xy 291.196314 -397.328095) (xy 291.152557 -397.281498)
			(xy 291.114984 -397.229783) (xy 291.08419 -397.173768) (xy 291.060658 -397.114335) (xy 291.044761 -397.052421)
			(xy 291.03675 -396.989003) (xy 290.737221 -396.989003) (xy 290.730301 -397.043785) (xy 290.714404 -397.105699)
			(xy 290.690872 -397.165132) (xy 290.660078 -397.221147) (xy 290.622505 -397.272862) (xy 290.578748 -397.319459)
			(xy 290.529495 -397.360204) (xy 290.475524 -397.394455) (xy 290.417685 -397.421672) (xy 290.356892 -397.441425)
			(xy 290.294102 -397.453403) (xy 290.230306 -397.457417) (xy 290.16651 -397.453403) (xy 290.10372 -397.441425)
			(xy 290.042927 -397.421672) (xy 289.985088 -397.394455) (xy 289.931117 -397.360204) (xy 289.881864 -397.319459)
			(xy 289.838107 -397.272862) (xy 289.800534 -397.221147) (xy 289.76974 -397.165132) (xy 289.746208 -397.105699)
			(xy 289.730311 -397.043785) (xy 289.7223 -396.980367) (xy 280.881582 -396.980367) (xy 280.881582 -398.513808)
			(xy 287.467802 -398.513808) (xy 287.468245 -398.483076) (xy 287.475653 -398.422059) (xy 287.490362 -398.36238)
			(xy 287.512157 -398.30491) (xy 287.540721 -398.250485) (xy 287.575637 -398.199901) (xy 287.616395 -398.153894)
			(xy 287.662402 -398.113136) (xy 287.712987 -398.07822) (xy 287.767412 -398.049656) (xy 287.824882 -398.027861)
			(xy 287.884561 -398.013153) (xy 287.945578 -398.005745) (xy 287.97631 -398.0053) (xy 288.00863 -398.005806)
			(xy 288.072747 -398.014022) (xy 288.135307 -398.030293) (xy 288.195301 -398.054359) (xy 288.251764 -398.085831)
			(xy 288.303784 -398.124202) (xy 288.350524 -398.168855) (xy 288.391232 -398.219068) (xy 288.42525 -398.274034)
			(xy 288.439098 -398.303242) (xy 288.444432 -398.31518) (xy 288.464752 -398.33042) (xy 288.562288 -398.344898)
			(xy 288.570726 -398.345793) (xy 288.587391 -398.342642) (xy 288.602133 -398.334259) (xy 288.608008 -398.328134)
			(xy 288.628732 -398.305264) (xy 288.674791 -398.264181) (xy 288.725485 -398.228978) (xy 288.780069 -398.200172)
			(xy 288.837739 -398.178187) (xy 288.897647 -398.163346) (xy 288.958911 -398.15587) (xy 288.98977 -398.155414)
			(xy 289.021735 -398.155849) (xy 289.085161 -398.163858) (xy 289.147083 -398.179754) (xy 289.206525 -398.203285)
			(xy 289.262548 -398.234082) (xy 289.31427 -398.271657) (xy 289.360874 -398.315418) (xy 289.401626 -398.364676)
			(xy 289.435882 -398.418653) (xy 289.463103 -398.476498) (xy 289.482859 -398.537299) (xy 289.494839 -398.600096)
			(xy 289.498854 -398.6639) (xy 289.494839 -398.727704) (xy 289.482859 -398.790501) (xy 289.463103 -398.851302)
			(xy 289.435882 -398.909147) (xy 289.426444 -398.924018) (xy 292.273226 -398.924018) (xy 292.277297 -398.868396)
			(xy 292.289423 -398.813959) (xy 292.309346 -398.761868) (xy 292.336642 -398.713233) (xy 292.370728 -398.66909)
			(xy 292.410877 -398.630381) (xy 292.456235 -398.59793) (xy 292.505835 -398.572429) (xy 292.558619 -398.554422)
			(xy 292.613462 -398.544292) (xy 292.669196 -398.542255) (xy 292.724633 -398.548355) (xy 292.77859 -398.562461)
			(xy 292.829919 -398.584273) (xy 292.877525 -398.613327) (xy 292.920393 -398.649002) (xy 292.95761 -398.690539)
			(xy 292.988383 -398.737052) (xy 293.012055 -398.787549) (xy 293.028123 -398.840956) (xy 293.036243 -398.896132)
			(xy 293.036752 -398.924018) (xy 293.036243 -398.951904) (xy 293.028123 -399.00708) (xy 293.012055 -399.060487)
			(xy 292.988383 -399.110984) (xy 292.95761 -399.157497) (xy 292.920393 -399.199034) (xy 292.877525 -399.234709)
			(xy 292.829919 -399.263763) (xy 292.77859 -399.285575) (xy 292.724633 -399.299681) (xy 292.669196 -399.305781)
			(xy 292.613462 -399.303744) (xy 292.558619 -399.293614) (xy 292.505835 -399.275607) (xy 292.456235 -399.250106)
			(xy 292.410877 -399.217655) (xy 292.370728 -399.178946) (xy 292.336642 -399.134803) (xy 292.309346 -399.086168)
			(xy 292.289423 -399.034077) (xy 292.277297 -398.97964) (xy 292.273226 -398.924018) (xy 289.426444 -398.924018)
			(xy 289.401626 -398.963124) (xy 289.360874 -399.012382) (xy 289.31427 -399.056143) (xy 289.262548 -399.093718)
			(xy 289.206525 -399.124515) (xy 289.147083 -399.148046) (xy 289.085161 -399.163942) (xy 289.021735 -399.171951)
			(xy 288.98977 -399.17243) (xy 288.95745 -399.171897) (xy 288.893332 -399.16369) (xy 288.830772 -399.147425)
			(xy 288.770776 -399.123365) (xy 288.714312 -399.091897) (xy 288.662291 -399.053528) (xy 288.615551 -399.008876)
			(xy 288.574844 -398.958663) (xy 288.540829 -398.903696) (xy 288.526982 -398.874488) (xy 288.521648 -398.86255)
			(xy 288.501328 -398.84731) (xy 288.403792 -398.832832) (xy 288.39535 -398.831985) (xy 288.378691 -398.835113)
			(xy 288.363948 -398.843478) (xy 288.358072 -398.849596) (xy 288.340853 -398.868684) (xy 288.303192 -398.903679)
			(xy 288.282888 -398.919446) (xy 288.274887 -398.926105) (xy 288.264656 -398.944209) (xy 288.263076 -398.954498)
			(xy 288.254694 -399.027904) (xy 288.254049 -399.038328) (xy 288.260229 -399.05826) (xy 288.266632 -399.066512)
			(xy 288.283378 -399.086834) (xy 288.311693 -399.131233) (xy 288.333631 -399.179103) (xy 288.348776 -399.229537)
			(xy 288.353246 -399.255488) (xy 288.355024 -399.26641) (xy 288.366962 -399.284444) (xy 288.440622 -399.331434)
			(xy 288.450027 -399.336845) (xy 288.471466 -399.340021) (xy 288.482024 -399.33753) (xy 288.507939 -399.330514)
			(xy 288.561098 -399.322997) (xy 288.587942 -399.322544) (xy 288.615192 -399.323039) (xy 288.669137 -399.3308)
			(xy 288.721429 -399.346158) (xy 288.771003 -399.3688) (xy 288.816851 -399.398266) (xy 288.858039 -399.433957)
			(xy 288.89373 -399.475144) (xy 288.923197 -399.520992) (xy 288.94584 -399.570566) (xy 288.956101 -399.6055)
			(xy 297.438824 -399.6055) (xy 297.442895 -399.549878) (xy 297.455021 -399.495441) (xy 297.474944 -399.44335)
			(xy 297.50224 -399.394715) (xy 297.536326 -399.350572) (xy 297.576475 -399.311863) (xy 297.621833 -399.279412)
			(xy 297.671433 -399.253911) (xy 297.724217 -399.235904) (xy 297.77906 -399.225774) (xy 297.834794 -399.223737)
			(xy 297.890231 -399.229837) (xy 297.944188 -399.243943) (xy 297.995517 -399.265755) (xy 298.043123 -399.294809)
			(xy 298.085991 -399.330484) (xy 298.123208 -399.372021) (xy 298.153981 -399.418534) (xy 298.177653 -399.469031)
			(xy 298.193721 -399.522438) (xy 298.201841 -399.577614) (xy 298.20235 -399.6055) (xy 298.201841 -399.633386)
			(xy 298.193721 -399.688562) (xy 298.177653 -399.741969) (xy 298.153981 -399.792466) (xy 298.123208 -399.838979)
			(xy 298.085991 -399.880516) (xy 298.043123 -399.916191) (xy 297.995517 -399.945245) (xy 297.944188 -399.967057)
			(xy 297.890231 -399.981163) (xy 297.834794 -399.987263) (xy 297.77906 -399.985226) (xy 297.724217 -399.975096)
			(xy 297.671433 -399.957089) (xy 297.621833 -399.931588) (xy 297.576475 -399.899137) (xy 297.536326 -399.860428)
			(xy 297.50224 -399.816285) (xy 297.474944 -399.76765) (xy 297.455021 -399.715559) (xy 297.442895 -399.661122)
			(xy 297.438824 -399.6055) (xy 288.956101 -399.6055) (xy 288.961199 -399.622857) (xy 288.968961 -399.676802)
			(xy 288.96945 -399.704052) (xy 288.969226 -399.722459) (xy 288.965668 -399.7591) (xy 288.962338 -399.777204)
			(xy 288.960513 -399.789543) (xy 288.967714 -399.813394) (xy 288.976054 -399.82267) (xy 289.04438 -399.891504)
			(xy 289.068002 -399.89887) (xy 289.080702 -399.896584) (xy 289.103793 -399.89253) (xy 289.150478 -399.888207)
			(xy 289.17392 -399.887948) (xy 289.20465 -399.888437) (xy 289.265661 -399.895847) (xy 289.325334 -399.910557)
			(xy 289.3828 -399.932351) (xy 289.437219 -399.960913) (xy 289.4878 -399.995825) (xy 289.533804 -400.036579)
			(xy 289.57456 -400.082581) (xy 289.609475 -400.13316) (xy 289.638039 -400.187579) (xy 289.659836 -400.245043)
			(xy 289.674549 -400.304715) (xy 289.681961 -400.365726) (xy 289.682428 -400.396456) (xy 289.681928 -400.42818)
			(xy 289.674017 -400.491134) (xy 289.658337 -400.552614) (xy 289.635132 -400.611668) (xy 289.604762 -400.667376)
			(xy 289.567699 -400.718874) (xy 289.524518 -400.765362) (xy 289.475891 -400.806119) (xy 289.422571 -400.840511)
			(xy 289.365389 -400.868003) (xy 289.335464 -400.878548) (xy 289.33521 -400.878548) (xy 289.32526 -400.882506)
			(xy 289.309603 -400.897083) (xy 289.304984 -400.906742) (xy 289.270694 -400.987006) (xy 289.271202 -401.008342)
			(xy 289.275774 -401.018248) (xy 289.287296 -401.043829) (xy 289.303577 -401.097518) (xy 289.311831 -401.153011)
			(xy 289.31235 -401.181062) (xy 289.311864 -401.208313) (xy 289.304108 -401.262261) (xy 289.288753 -401.314556)
			(xy 289.266111 -401.364133) (xy 289.236645 -401.409983) (xy 289.200954 -401.451174) (xy 289.159763 -401.486865)
			(xy 289.113913 -401.516331) (xy 289.064336 -401.538973) (xy 289.012041 -401.554328) (xy 288.958093 -401.562084)
			(xy 288.903591 -401.562084) (xy 288.849643 -401.554328) (xy 288.797348 -401.538973) (xy 288.747771 -401.516331)
			(xy 288.701921 -401.486865) (xy 288.66073 -401.451174) (xy 288.625039 -401.409983) (xy 288.595573 -401.364133)
			(xy 288.572931 -401.314556) (xy 288.557576 -401.262261) (xy 288.54982 -401.208313) (xy 288.549334 -401.181062)
			(xy 288.549908 -401.152658) (xy 288.558342 -401.09648) (xy 288.575006 -401.042171) (xy 288.599529 -400.990929)
			(xy 288.631373 -400.943885) (xy 288.669833 -400.902076) (xy 288.714062 -400.866426) (xy 288.73831 -400.851624)
			(xy 288.747708 -400.846036) (xy 288.760154 -400.828764) (xy 288.777172 -400.74342) (xy 288.778846 -400.732752)
			(xy 288.774107 -400.711705) (xy 288.768028 -400.70278) (xy 288.748615 -400.676228) (xy 288.716095 -400.619053)
			(xy 288.69122 -400.558162) (xy 288.674403 -400.494572) (xy 288.665927 -400.429344) (xy 288.665412 -400.396456)
			(xy 288.665866 -400.366758) (xy 288.672819 -400.30777) (xy 288.686592 -400.249993) (xy 288.6964 -400.221958)
			(xy 288.6964 -400.221704) (xy 288.700061 -400.209799) (xy 288.696582 -400.18516) (xy 288.689796 -400.174714)
			(xy 288.64052 -400.106388) (xy 288.632813 -400.096714) (xy 288.610719 -400.085662) (xy 288.598356 -400.085306)
			(xy 288.598102 -400.085306) (xy 288.588196 -400.08556) (xy 288.587688 -400.08556) (xy 288.560661 -400.085101)
			(xy 288.507157 -400.077416) (xy 288.455272 -400.062257) (xy 288.406045 -400.039928) (xy 288.360463 -400.010875)
			(xy 288.319436 -399.975681) (xy 288.283786 -399.93505) (xy 288.254226 -399.889794) (xy 288.231349 -399.84082)
			(xy 288.215611 -399.789108) (xy 288.211006 -399.762472) (xy 288.209228 -399.75155) (xy 288.19729 -399.733516)
			(xy 288.12363 -399.686526) (xy 288.114239 -399.681086) (xy 288.092789 -399.677929) (xy 288.082228 -399.68043)
			(xy 288.056311 -399.687437) (xy 288.003154 -399.694959) (xy 287.97631 -399.695416) (xy 287.949058 -399.694935)
			(xy 287.895108 -399.68718) (xy 287.842811 -399.671826) (xy 287.793231 -399.649185) (xy 287.747378 -399.619719)
			(xy 287.706186 -399.584027) (xy 287.670492 -399.542836) (xy 287.641024 -399.496985) (xy 287.618381 -399.447406)
			(xy 287.603024 -399.39511) (xy 287.595266 -399.34116) (xy 287.594802 -399.313908) (xy 287.595237 -399.286973)
			(xy 287.602832 -399.23364) (xy 287.617857 -399.181906) (xy 287.640013 -399.132802) (xy 287.66886 -399.087305)
			(xy 287.685988 -399.066512) (xy 287.6924 -399.058264) (xy 287.698572 -399.03833) (xy 287.697926 -399.027904)
			(xy 287.689544 -398.954498) (xy 287.687886 -398.944233) (xy 287.677685 -398.926141) (xy 287.669732 -398.919446)
			(xy 287.643256 -398.898816) (xy 287.59549 -398.85166) (xy 287.554346 -398.798627) (xy 287.52054 -398.74064)
			(xy 287.49466 -398.678708) (xy 287.477157 -398.613908) (xy 287.468335 -398.547369) (xy 287.467802 -398.513808)
			(xy 280.881582 -398.513808) (xy 280.881582 -404.215092) (xy 283.497274 -404.215092) (xy 283.497857 -404.180137)
			(xy 283.507419 -404.110884) (xy 283.526376 -404.043593) (xy 283.554371 -403.979533) (xy 283.590875 -403.91991)
			(xy 283.61259 -403.892512) (xy 283.617822 -403.885564) (xy 283.623672 -403.869198) (xy 283.62402 -403.860508)
			(xy 283.62402 -403.706076) (xy 283.623651 -403.697391) (xy 283.617796 -403.681034) (xy 283.61259 -403.674072)
			(xy 283.590863 -403.646684) (xy 283.554368 -403.587055) (xy 283.526378 -403.522992) (xy 283.507421 -403.4557)
			(xy 283.497852 -403.386447) (xy 283.497274 -403.351492) (xy 283.497764 -403.32) (xy 283.505533 -403.257496)
			(xy 283.520964 -403.196431) (xy 283.543819 -403.137739) (xy 283.57375 -403.082321) (xy 283.610297 -403.031024)
			(xy 283.6529 -402.984634) (xy 283.676598 -402.963888) (xy 283.684472 -402.957284) (xy 283.693616 -402.93925)
			(xy 283.700474 -402.846032) (xy 283.69387 -402.826982) (xy 283.687012 -402.819108) (xy 283.669122 -402.798081)
			(xy 283.638929 -402.751863) (xy 283.615714 -402.701775) (xy 283.599961 -402.648864) (xy 283.591999 -402.594235)
			(xy 283.591508 -402.566632) (xy 283.591994 -402.539381) (xy 283.59975 -402.485433) (xy 283.615105 -402.433138)
			(xy 283.637747 -402.383561) (xy 283.667213 -402.337711) (xy 283.702904 -402.29652) (xy 283.744095 -402.260829)
			(xy 283.789945 -402.231363) (xy 283.839522 -402.208721) (xy 283.891817 -402.193366) (xy 283.945765 -402.18561)
			(xy 284.000267 -402.18561) (xy 284.054215 -402.193366) (xy 284.10651 -402.208721) (xy 284.156087 -402.231363)
			(xy 284.201937 -402.260829) (xy 284.243128 -402.29652) (xy 284.278819 -402.337711) (xy 284.308285 -402.383561)
			(xy 284.330927 -402.433138) (xy 284.346282 -402.485433) (xy 284.354038 -402.539381) (xy 284.354524 -402.566632)
			(xy 284.353951 -402.597168) (xy 284.344223 -402.65746) (xy 284.32502 -402.715435) (xy 284.296831 -402.769612)
			(xy 284.279086 -402.79447) (xy 284.27299 -402.802852) (xy 284.268164 -402.822156) (xy 284.282388 -402.914612)
			(xy 284.293056 -402.93163) (xy 284.301438 -402.937726) (xy 284.325787 -402.955622) (xy 284.370435 -402.996347)
			(xy 284.395499 -403.025356) (xy 289.79241 -403.025356) (xy 289.792964 -402.9904) (xy 289.802532 -402.921145)
			(xy 289.821496 -402.853854) (xy 289.849497 -402.789794) (xy 289.886008 -402.730173) (xy 289.907726 -402.702776)
			(xy 289.912977 -402.69584) (xy 289.918814 -402.679465) (xy 289.919156 -402.670772) (xy 289.919156 -402.51634)
			(xy 289.91877 -402.507657) (xy 289.912929 -402.491298) (xy 289.907726 -402.484336) (xy 289.886033 -402.456921)
			(xy 289.849532 -402.3973) (xy 289.821535 -402.333244) (xy 289.802569 -402.265958) (xy 289.792993 -402.19671)
			(xy 289.79241 -402.161756) (xy 289.792994 -402.12798) (xy 289.801948 -402.061024) (xy 289.819693 -401.995844)
			(xy 289.845916 -401.933589) (xy 289.880154 -401.875356) (xy 289.921805 -401.822172) (xy 289.970133 -401.774974)
			(xy 289.99688 -401.75434) (xy 290.004337 -401.748133) (xy 290.014402 -401.731567) (xy 290.016438 -401.722082)
			(xy 290.0299 -401.643342) (xy 290.025836 -401.624546) (xy 290.020502 -401.616418) (xy 290.005351 -401.592809)
			(xy 289.981427 -401.542071) (xy 289.965188 -401.488377) (xy 289.956985 -401.432884) (xy 289.956494 -401.404836)
			(xy 289.95698 -401.377585) (xy 289.964736 -401.323637) (xy 289.980091 -401.271342) (xy 290.002733 -401.221765)
			(xy 290.032199 -401.175915) (xy 290.06789 -401.134724) (xy 290.109081 -401.099033) (xy 290.154931 -401.069567)
			(xy 290.204508 -401.046925) (xy 290.256803 -401.03157) (xy 290.310751 -401.023814) (xy 290.365253 -401.023814)
			(xy 290.419201 -401.03157) (xy 290.471496 -401.046925) (xy 290.521073 -401.069567) (xy 290.566923 -401.099033)
			(xy 290.608114 -401.134724) (xy 290.643805 -401.175915) (xy 290.673271 -401.221765) (xy 290.695913 -401.271342)
			(xy 290.711268 -401.323637) (xy 290.719024 -401.377585) (xy 290.71951 -401.404836) (xy 290.719072 -401.431011)
			(xy 290.711902 -401.482867) (xy 290.697702 -401.533254) (xy 290.676739 -401.581223) (xy 290.649407 -401.625872)
			(xy 290.63315 -401.64639) (xy 290.63315 -401.646644) (xy 290.627453 -401.654351) (xy 290.621712 -401.672623)
			(xy 290.621974 -401.682204) (xy 290.627816 -401.76196) (xy 290.636198 -401.779486) (xy 290.64331 -401.785836)
			(xy 290.665381 -401.8065) (xy 290.704945 -401.852221) (xy 290.738805 -401.902312) (xy 290.766485 -401.956067)
			(xy 290.787592 -402.012726) (xy 290.801829 -402.071488) (xy 290.808995 -402.131525) (xy 290.809426 -402.161756)
			(xy 290.80887 -402.196712) (xy 290.799302 -402.265966) (xy 290.780338 -402.333257) (xy 290.752337 -402.397317)
			(xy 290.715827 -402.456939) (xy 290.69411 -402.484336) (xy 290.688858 -402.491271) (xy 290.68302 -402.507647)
			(xy 290.68268 -402.51634) (xy 290.68268 -402.670772) (xy 290.683073 -402.679454) (xy 290.688911 -402.695812)
			(xy 290.69411 -402.702776) (xy 290.715813 -402.730182) (xy 290.752312 -402.789806) (xy 290.780307 -402.853865)
			(xy 290.79927 -402.921152) (xy 290.808844 -402.990402) (xy 290.809426 -403.025356) (xy 290.809337 -403.037951)
			(xy 290.808068 -403.063108) (xy 290.806886 -403.075648) (xy 290.80587 -403.0853) (xy 290.811458 -403.10435)
			(xy 290.8681 -403.17547) (xy 290.884864 -403.185122) (xy 290.894516 -403.186392) (xy 290.895024 -403.186392)
			(xy 290.922204 -403.190464) (xy 290.9751 -403.205373) (xy 291.025309 -403.227719) (xy 291.071791 -403.257039)
			(xy 291.113585 -403.292726) (xy 291.149824 -403.334042) (xy 291.179759 -403.380131) (xy 291.20277 -403.430038)
			(xy 291.218381 -403.482731) (xy 291.226268 -403.537119) (xy 291.226748 -403.564598) (xy 291.22622 -403.591847)
			(xy 291.218465 -403.645792) (xy 291.203112 -403.698083) (xy 291.192619 -403.721062) (xy 291.534594 -403.721062)
			(xy 291.538665 -403.66544) (xy 291.550791 -403.611003) (xy 291.570714 -403.558912) (xy 291.59801 -403.510277)
			(xy 291.632096 -403.466134) (xy 291.672245 -403.427425) (xy 291.717603 -403.394974) (xy 291.767203 -403.369473)
			(xy 291.819987 -403.351466) (xy 291.87483 -403.341336) (xy 291.930564 -403.339299) (xy 291.986001 -403.345399)
			(xy 292.039958 -403.359505) (xy 292.091287 -403.381317) (xy 292.138893 -403.410371) (xy 292.181761 -403.446046)
			(xy 292.218978 -403.487583) (xy 292.249751 -403.534096) (xy 292.273423 -403.584593) (xy 292.289491 -403.638)
			(xy 292.297611 -403.693176) (xy 292.29812 -403.721062) (xy 292.297611 -403.748948) (xy 292.289491 -403.804124)
			(xy 292.273423 -403.857531) (xy 292.249751 -403.908028) (xy 292.218978 -403.954541) (xy 292.181761 -403.996078)
			(xy 292.138893 -404.031753) (xy 292.091287 -404.060807) (xy 292.039958 -404.082619) (xy 291.986001 -404.096725)
			(xy 291.930564 -404.102825) (xy 291.87483 -404.100788) (xy 291.819987 -404.090658) (xy 291.767203 -404.072651)
			(xy 291.717603 -404.04715) (xy 291.672245 -404.014699) (xy 291.632096 -403.97599) (xy 291.59801 -403.931847)
			(xy 291.570714 -403.883212) (xy 291.550791 -403.831121) (xy 291.538665 -403.776684) (xy 291.534594 -403.721062)
			(xy 291.192619 -403.721062) (xy 291.180474 -403.747658) (xy 291.151012 -403.793506) (xy 291.115325 -403.834695)
			(xy 291.07414 -403.870387) (xy 291.028295 -403.899854) (xy 290.978722 -403.922498) (xy 290.926433 -403.937856)
			(xy 290.872489 -403.945617) (xy 290.84524 -403.946106) (xy 290.817933 -403.945605) (xy 290.763881 -403.937796)
			(xy 290.711494 -403.922361) (xy 290.661843 -403.899615) (xy 290.615942 -403.870022) (xy 290.574728 -403.834188)
			(xy 290.539044 -403.792845) (xy 290.509619 -403.746836) (xy 290.487054 -403.697102) (xy 290.47181 -403.644659)
			(xy 290.467542 -403.617684) (xy 290.467542 -403.61743) (xy 290.465672 -403.607916) (xy 290.455876 -403.591202)
			(xy 290.448492 -403.584918) (xy 290.392358 -403.54123) (xy 290.384479 -403.535649) (xy 290.365934 -403.530313)
			(xy 290.35629 -403.530816) (xy 290.355528 -403.530816) (xy 290.341919 -403.532223) (xy 290.314599 -403.533745)
			(xy 290.300918 -403.533864) (xy 290.270185 -403.533445) (xy 290.209166 -403.526038) (xy 290.149485 -403.511329)
			(xy 290.092012 -403.489533) (xy 290.037586 -403.460968) (xy 289.987 -403.42605) (xy 289.940993 -403.385289)
			(xy 289.900234 -403.339279) (xy 289.865319 -403.288692) (xy 289.836756 -403.234264) (xy 289.814963 -403.17679)
			(xy 289.800257 -403.117109) (xy 289.792853 -403.056089) (xy 289.79241 -403.025356) (xy 284.395499 -403.025356)
			(xy 284.409944 -403.042074) (xy 284.443757 -403.09216) (xy 284.471398 -403.1459) (xy 284.492476 -403.202536)
			(xy 284.506696 -403.261271) (xy 284.513857 -403.321276) (xy 284.51429 -403.351492) (xy 284.513706 -403.386447)
			(xy 284.504145 -403.4557) (xy 284.485189 -403.522992) (xy 284.457194 -403.587052) (xy 284.420689 -403.646674)
			(xy 284.398974 -403.674072) (xy 284.393745 -403.681022) (xy 284.387894 -403.697386) (xy 284.387544 -403.706076)
			(xy 284.387544 -403.860508) (xy 284.387908 -403.869193) (xy 284.393764 -403.885552) (xy 284.398974 -403.892512)
			(xy 284.420689 -403.91991) (xy 284.457187 -403.979536) (xy 284.48518 -404.043596) (xy 284.50414 -404.110886)
			(xy 284.513711 -404.180137) (xy 284.51429 -404.215092) (xy 284.513769 -404.248552) (xy 284.504998 -404.314895)
			(xy 284.487594 -404.379512) (xy 284.461858 -404.441285) (xy 284.428235 -404.499145) (xy 284.387308 -404.55209)
			(xy 284.363922 -404.576026) (xy 284.357589 -404.58285) (xy 284.3499 -404.599786) (xy 284.348936 -404.609046)
			(xy 284.347158 -404.63978) (xy 284.346998 -404.648906) (xy 284.352324 -404.666349) (xy 284.357572 -404.673816)
			(xy 284.372438 -404.693877) (xy 284.397383 -404.737131) (xy 284.416475 -404.783269) (xy 284.429389 -404.831501)
			(xy 284.435903 -404.881006) (xy 284.436312 -404.905972) (xy 284.435826 -404.933223) (xy 284.42807 -404.987171)
			(xy 284.412715 -405.039466) (xy 284.390073 -405.089043) (xy 284.360607 -405.134893) (xy 284.324916 -405.176084)
			(xy 284.283725 -405.211775) (xy 284.237875 -405.241241) (xy 284.188298 -405.263883) (xy 284.136003 -405.279238)
			(xy 284.082055 -405.286994) (xy 284.027553 -405.286994) (xy 283.973605 -405.279238) (xy 283.92131 -405.263883)
			(xy 283.871733 -405.241241) (xy 283.825883 -405.211775) (xy 283.784692 -405.176084) (xy 283.749001 -405.134893)
			(xy 283.719535 -405.089043) (xy 283.696893 -405.039466) (xy 283.681538 -404.987171) (xy 283.673782 -404.933223)
			(xy 283.673296 -404.905972) (xy 283.673701 -404.88154) (xy 283.679957 -404.833077) (xy 283.69235 -404.78581)
			(xy 283.710677 -404.740512) (xy 283.722318 -404.719028) (xy 283.726484 -404.710865) (xy 283.729209 -404.692755)
			(xy 283.727652 -404.683722) (xy 283.721556 -404.653496) (xy 283.719262 -404.644489) (xy 283.709225 -404.628862)
			(xy 283.701998 -404.623016) (xy 283.675218 -404.602354) (xy 283.626818 -404.555104) (xy 283.585106 -404.501858)
			(xy 283.550818 -404.443553) (xy 283.524558 -404.381219) (xy 283.50679 -404.315955) (xy 283.497828 -404.248912)
			(xy 283.497274 -404.215092) (xy 280.881582 -404.215092) (xy 280.881582 -407.556716) (xy 282.40863 -407.556716)
			(xy 282.40916 -407.524427) (xy 282.417344 -407.460369) (xy 282.433571 -407.397862) (xy 282.45758 -407.337912)
			(xy 282.488983 -407.281483) (xy 282.527276 -407.229483) (xy 282.571844 -407.182748) (xy 282.59659 -407.162)
			(xy 282.604176 -407.155301) (xy 282.613737 -407.137481) (xy 282.615132 -407.127456) (xy 282.622752 -407.044906)
			(xy 282.616656 -407.025602) (xy 282.610052 -407.017728) (xy 282.593089 -406.996981) (xy 282.564562 -406.951614)
			(xy 282.542663 -406.902703) (xy 282.527822 -406.851208) (xy 282.520332 -406.798143) (xy 282.519882 -406.771348)
			(xy 282.520386 -406.742528) (xy 282.529076 -406.685547) (xy 282.546236 -406.63052) (xy 282.571476 -406.5787)
			(xy 282.604222 -406.531264) (xy 282.643728 -406.489292) (xy 282.689097 -406.453738) (xy 282.713938 -406.439116)
			(xy 282.714192 -406.438862) (xy 282.722247 -406.433892) (xy 282.73426 -406.419285) (xy 282.73756 -406.410414)
			(xy 282.761436 -406.335484) (xy 282.760166 -406.31618) (xy 282.756102 -406.307544) (xy 282.741052 -406.27374)
			(xy 282.719796 -406.202864) (xy 282.709035 -406.129657) (xy 282.70835 -406.09266) (xy 282.70835 -406.092152)
			(xy 282.708852 -406.060191) (xy 282.716863 -405.996773) (xy 282.73276 -405.934859) (xy 282.756292 -405.875426)
			(xy 282.787086 -405.819411) (xy 282.824659 -405.767696) (xy 282.868416 -405.721099) (xy 282.917669 -405.680354)
			(xy 282.97164 -405.646103) (xy 283.029479 -405.618886) (xy 283.090272 -405.599133) (xy 283.153062 -405.587155)
			(xy 283.216858 -405.583142) (xy 283.280654 -405.587155) (xy 283.343444 -405.599133) (xy 283.404237 -405.618886)
			(xy 283.462076 -405.646103) (xy 283.516047 -405.680354) (xy 283.5653 -405.721099) (xy 283.609057 -405.767696)
			(xy 283.64663 -405.819411) (xy 283.677424 -405.875426) (xy 283.700956 -405.934859) (xy 283.716853 -405.996773)
			(xy 283.724864 -406.060191) (xy 283.725366 -406.092152) (xy 283.725366 -406.092406) (xy 283.724901 -406.122507)
			(xy 283.71778 -406.182287) (xy 283.703662 -406.240811) (xy 283.693616 -406.26919) (xy 283.689298 -406.280874)
			(xy 283.692346 -406.305258) (xy 283.75356 -406.394412) (xy 283.775404 -406.406096) (xy 283.78785 -406.406096)
			(xy 283.814958 -406.406795) (xy 283.868575 -406.414902) (xy 283.920504 -406.430519) (xy 283.969698 -406.453332)
			(xy 284.015166 -406.482881) (xy 284.055992 -406.51857) (xy 284.091353 -406.559681) (xy 284.120537 -406.605384)
			(xy 284.142955 -406.654759) (xy 284.158157 -406.706811) (xy 284.165834 -406.760491) (xy 284.16631 -406.787604)
			(xy 284.165912 -406.812802) (xy 284.159267 -406.862759) (xy 284.146095 -406.911404) (xy 284.126625 -406.957888)
			(xy 284.101196 -407.001399) (xy 284.086046 -407.021538) (xy 284.085792 -407.021792) (xy 284.080221 -407.029815)
			(xy 284.074996 -407.048621) (xy 284.075632 -407.058368) (xy 284.08376 -407.129234) (xy 284.08531 -407.138849)
			(xy 284.094586 -407.155957) (xy 284.101794 -407.162508) (xy 284.102048 -407.162762) (xy 284.126719 -407.183475)
			(xy 284.171096 -407.230175) (xy 284.209222 -407.282101) (xy 284.24049 -407.338425) (xy 284.264399 -407.398245)
			(xy 284.268541 -407.414222) (xy 286.974788 -407.414222) (xy 286.975379 -407.379257) (xy 286.984978 -407.309988)
			(xy 287.003984 -407.242689) (xy 287.032037 -407.178632) (xy 287.068609 -407.119026) (xy 287.090358 -407.091642)
			(xy 287.095618 -407.084636) (xy 287.101469 -407.068138) (xy 287.101788 -407.059384) (xy 287.101788 -406.90546)
			(xy 287.101444 -406.896711) (xy 287.095594 -406.88022) (xy 287.090358 -406.873202) (xy 287.068615 -406.845815)
			(xy 287.032064 -406.7862) (xy 287.004018 -406.722143) (xy 286.985008 -406.654849) (xy 286.97539 -406.585586)
			(xy 286.974788 -406.550622) (xy 286.97518 -406.520869) (xy 286.982147 -406.461771) (xy 286.995965 -406.40389)
			(xy 287.016445 -406.348019) (xy 287.043307 -406.29492) (xy 287.076184 -406.245319) (xy 287.114626 -406.199896)
			(xy 287.136078 -406.179274) (xy 287.14221 -406.172999) (xy 287.150267 -406.157427) (xy 287.151826 -406.148794)
			(xy 287.155636 -406.119076) (xy 287.15637 -406.110468) (xy 287.152748 -406.09359) (xy 287.148524 -406.086056)
			(xy 287.135381 -406.0636) (xy 287.114673 -406.015865) (xy 287.100655 -405.965757) (xy 287.093588 -405.914206)
			(xy 287.093152 -405.88819) (xy 287.093152 -405.887936) (xy 287.093638 -405.860685) (xy 287.101394 -405.806737)
			(xy 287.116749 -405.754442) (xy 287.139391 -405.704865) (xy 287.168857 -405.659015) (xy 287.204548 -405.617824)
			(xy 287.245739 -405.582133) (xy 287.291589 -405.552667) (xy 287.341166 -405.530025) (xy 287.393461 -405.51467)
			(xy 287.447409 -405.506914) (xy 287.501911 -405.506914) (xy 287.555859 -405.51467) (xy 287.608154 -405.530025)
			(xy 287.657731 -405.552667) (xy 287.703581 -405.582133) (xy 287.744772 -405.617824) (xy 287.780463 -405.659015)
			(xy 287.809929 -405.704865) (xy 287.832571 -405.754442) (xy 287.847926 -405.806737) (xy 287.855682 -405.860685)
			(xy 287.856168 -405.887936) (xy 287.855781 -405.912728) (xy 287.849364 -405.961895) (xy 287.836641 -406.009819)
			(xy 287.817828 -406.055696) (xy 287.805876 -406.07742) (xy 287.801869 -406.085093) (xy 287.798738 -406.102102)
			(xy 287.79978 -406.110694) (xy 287.804352 -406.140412) (xy 287.806124 -406.148929) (xy 287.814569 -406.164124)
			(xy 287.820862 -406.17013) (xy 287.8435 -406.190885) (xy 287.884179 -406.236896) (xy 287.919025 -406.28747)
			(xy 287.947529 -406.341871) (xy 287.969277 -406.399308) (xy 287.983953 -406.458944) (xy 287.991344 -406.519914)
			(xy 287.991804 -406.550622) (xy 287.99124 -406.585588) (xy 287.981635 -406.654858) (xy 287.962623 -406.722157)
			(xy 287.934563 -406.786214) (xy 287.897986 -406.845819) (xy 287.876234 -406.873202) (xy 287.870955 -406.880196)
			(xy 287.865115 -406.896703) (xy 287.864804 -406.90546) (xy 287.864804 -407.059384) (xy 287.865175 -407.06813)
			(xy 287.871006 -407.084622) (xy 287.876234 -407.091642) (xy 287.897996 -407.119015) (xy 287.934545 -407.178633)
			(xy 287.962586 -407.242694) (xy 287.981593 -407.309992) (xy 287.991205 -407.379257) (xy 287.991804 -407.414222)
			(xy 287.9914 -407.444414) (xy 287.984236 -407.504371) (xy 287.970024 -407.563058) (xy 287.948963 -407.61965)
			(xy 287.92135 -407.67335) (xy 287.887573 -407.723404) (xy 287.848107 -407.769105) (xy 287.803508 -407.809813)
			(xy 287.779206 -407.827734) (xy 287.770649 -407.83447) (xy 287.759725 -407.853285) (xy 287.758124 -407.864056)
			(xy 287.750758 -407.94051) (xy 287.750286 -407.951156) (xy 287.756981 -407.971363) (xy 287.763712 -407.979626)
			(xy 287.76422 -407.980134) (xy 287.783389 -408.001422) (xy 287.815773 -408.048676) (xy 287.84073 -408.100238)
			(xy 287.8577 -408.154952) (xy 287.866302 -408.211588) (xy 287.866836 -408.24023) (xy 287.86635 -408.267481)
			(xy 287.858594 -408.321429) (xy 287.843239 -408.373724) (xy 287.820597 -408.423301) (xy 287.791131 -408.469151)
			(xy 287.75544 -408.510342) (xy 287.714249 -408.546033) (xy 287.668399 -408.575499) (xy 287.618822 -408.598141)
			(xy 287.566527 -408.613496) (xy 287.512579 -408.621252) (xy 287.458077 -408.621252) (xy 287.404129 -408.613496)
			(xy 287.351834 -408.598141) (xy 287.302257 -408.575499) (xy 287.256407 -408.546033) (xy 287.215216 -408.510342)
			(xy 287.179525 -408.469151) (xy 287.150059 -408.423301) (xy 287.127417 -408.373724) (xy 287.112062 -408.321429)
			(xy 287.104306 -408.267481) (xy 287.10382 -408.24023) (xy 287.104357 -408.211729) (xy 287.112843 -408.155363)
			(xy 287.129631 -408.10089) (xy 287.154345 -408.049524) (xy 287.186435 -408.002414) (xy 287.20542 -407.98115)
			(xy 287.205674 -407.980896) (xy 287.212465 -407.972596) (xy 287.219145 -407.95224) (xy 287.218628 -407.941526)
			(xy 287.209484 -407.854404) (xy 287.198562 -407.835608) (xy 287.189418 -407.829258) (xy 287.16489 -407.811376)
			(xy 287.119887 -407.770636) (xy 287.080052 -407.72483) (xy 287.045952 -407.674609) (xy 287.018071 -407.620687)
			(xy 286.996805 -407.56383) (xy 286.982457 -407.504846) (xy 286.97523 -407.444574) (xy 286.974788 -407.414222)
			(xy 284.268541 -407.414222) (xy 284.280566 -407.460605) (xy 284.288733 -407.524506) (xy 284.289246 -407.556716)
			(xy 284.288759 -407.587446) (xy 284.281349 -407.648457) (xy 284.26664 -407.708131) (xy 284.244846 -407.765597)
			(xy 284.216284 -407.820017) (xy 284.181372 -407.870597) (xy 284.140617 -407.916601) (xy 284.094615 -407.957358)
			(xy 284.044036 -407.992273) (xy 283.989617 -408.020837) (xy 283.932152 -408.042634) (xy 283.872479 -408.057345)
			(xy 283.811468 -408.064758) (xy 283.780738 -408.065224) (xy 283.745773 -408.064621) (xy 283.676505 -408.055025)
			(xy 283.609206 -408.036022) (xy 283.545149 -408.007971) (xy 283.485542 -407.971402) (xy 283.458158 -407.949654)
			(xy 283.451146 -407.944402) (xy 283.434653 -407.938545) (xy 283.4259 -407.938224) (xy 283.271976 -407.938224)
			(xy 283.263228 -407.938573) (xy 283.246736 -407.944419) (xy 283.239718 -407.949654) (xy 283.212315 -407.971376)
			(xy 283.152706 -408.007934) (xy 283.088653 -408.035984) (xy 283.021362 -408.054999) (xy 282.952101 -408.064621)
			(xy 282.917138 -408.065224) (xy 282.886407 -408.064727) (xy 282.825394 -408.057323) (xy 282.765717 -408.042618)
			(xy 282.708248 -408.020827) (xy 282.653825 -407.992268) (xy 282.603242 -407.957357) (xy 282.557235 -407.916603)
			(xy 282.516476 -407.870601) (xy 282.48156 -407.820021) (xy 282.452995 -407.765601) (xy 282.431198 -407.708134)
			(xy 282.416487 -407.64846) (xy 282.409077 -407.587447) (xy 282.40863 -407.556716) (xy 280.881582 -407.556716)
			(xy 280.881582 -409.88234) (xy 280.882264 -409.89498) (xy 280.894265 -409.91723) (xy 280.904442 -409.924758)
			(xy 280.975562 -409.971494) (xy 280.980865 -409.974864) (xy 280.992695 -409.979092) (xy 280.99893 -409.979876)
			(xy 281.01163 -409.980892) (xy 281.045082 -409.966205) (xy 281.115142 -409.945498) (xy 281.187446 -409.935036)
			(xy 281.223974 -409.93441) (xy 281.224228 -409.93441) (xy 281.255915 -409.934896) (xy 281.318796 -409.942773)
			(xy 281.380212 -409.958401) (xy 281.439211 -409.981539) (xy 281.494877 -410.011828) (xy 281.5209 -410.029914)
			(xy 281.521154 -410.030168) (xy 281.528012 -410.034994) (xy 281.544522 -410.040074) (xy 281.55116 -410.041676)
			(xy 281.564808 -410.041676) (xy 281.571446 -410.040074) (xy 281.587956 -410.034994) (xy 281.594814 -410.030168)
			(xy 281.595068 -410.029914) (xy 281.621087 -410.011823) (xy 281.676754 -409.981535) (xy 281.735754 -409.9584)
			(xy 281.797171 -409.942777) (xy 281.860053 -409.934906) (xy 281.89174 -409.93441) (xy 281.895804 -409.93441)
			(xy 281.928935 -409.935192) (xy 281.994579 -409.944293) (xy 282.058484 -409.961844) (xy 282.119568 -409.987549)
			(xy 282.13209 -409.994862) (xy 288.80689 -409.994862) (xy 288.80748 -409.960269) (xy 288.816839 -409.891719)
			(xy 288.835406 -409.825071) (xy 288.862838 -409.761556) (xy 288.898629 -409.702347) (xy 288.91992 -409.675076)
			(xy 288.926827 -409.665719) (xy 288.932054 -409.643078) (xy 288.926807 -409.620442) (xy 288.91992 -409.611068)
			(xy 288.898654 -409.583779) (xy 288.862871 -409.524569) (xy 288.835437 -409.461058) (xy 288.816858 -409.394417)
			(xy 288.807476 -409.325873) (xy 288.80689 -409.291282) (xy 288.807392 -409.259321) (xy 288.815403 -409.195903)
			(xy 288.8313 -409.133989) (xy 288.854832 -409.074556) (xy 288.885626 -409.018541) (xy 288.923199 -408.966826)
			(xy 288.966956 -408.920229) (xy 289.016209 -408.879484) (xy 289.07018 -408.845233) (xy 289.128019 -408.818016)
			(xy 289.188812 -408.798263) (xy 289.251602 -408.786285) (xy 289.315398 -408.782272) (xy 289.379194 -408.786285)
			(xy 289.441984 -408.798263) (xy 289.502777 -408.818016) (xy 289.560616 -408.845233) (xy 289.614587 -408.879484)
			(xy 289.66384 -408.920229) (xy 289.707597 -408.966826) (xy 289.74517 -409.018541) (xy 289.775964 -409.074556)
			(xy 289.799496 -409.133989) (xy 289.815393 -409.195903) (xy 289.823404 -409.259321) (xy 289.823906 -409.291282)
			(xy 289.823342 -409.325876) (xy 289.813977 -409.394427) (xy 289.795404 -409.461075) (xy 289.767966 -409.52459)
			(xy 289.73217 -409.583798) (xy 289.710876 -409.611068) (xy 289.704011 -409.620454) (xy 289.698758 -409.643078)
			(xy 289.703991 -409.665707) (xy 289.710876 -409.675076) (xy 289.732162 -409.70235) (xy 289.767942 -409.761564)
			(xy 289.795372 -409.825079) (xy 289.813946 -409.891723) (xy 289.823322 -409.96027) (xy 289.823906 -409.994862)
			(xy 289.823404 -410.026823) (xy 289.815393 -410.090241) (xy 289.799496 -410.152155) (xy 289.775964 -410.211588)
			(xy 289.74517 -410.267603) (xy 289.707597 -410.319318) (xy 289.66384 -410.365915) (xy 289.614587 -410.40666)
			(xy 289.560616 -410.440911) (xy 289.502777 -410.468128) (xy 289.441984 -410.487881) (xy 289.379194 -410.499859)
			(xy 289.315398 -410.503873) (xy 289.251602 -410.499859) (xy 289.188812 -410.487881) (xy 289.128019 -410.468128)
			(xy 289.07018 -410.440911) (xy 289.016209 -410.40666) (xy 288.966956 -410.365915) (xy 288.923199 -410.319318)
			(xy 288.885626 -410.267603) (xy 288.854832 -410.211588) (xy 288.8313 -410.152155) (xy 288.815403 -410.090241)
			(xy 288.807392 -410.026823) (xy 288.80689 -409.994862) (xy 282.13209 -409.994862) (xy 282.176794 -410.020971)
			(xy 282.229194 -410.061545) (xy 282.275879 -410.108582) (xy 282.316057 -410.161285) (xy 282.349049 -410.218761)
			(xy 282.374294 -410.280036) (xy 282.391364 -410.344072) (xy 282.399971 -410.409782) (xy 282.400502 -410.442918)
			(xy 282.400037 -410.473648) (xy 282.392627 -410.53466) (xy 282.377916 -410.594334) (xy 282.35612 -410.6518)
			(xy 282.327557 -410.706219) (xy 282.292642 -410.756799) (xy 282.251885 -410.802802) (xy 282.205881 -410.843557)
			(xy 282.155299 -410.878469) (xy 282.100878 -410.90703) (xy 282.043411 -410.928823) (xy 281.983737 -410.943531)
			(xy 281.922724 -410.950938) (xy 281.891994 -410.951426) (xy 281.89174 -410.951426) (xy 281.860054 -410.950938)
			(xy 281.797175 -410.943056) (xy 281.735762 -410.927423) (xy 281.676768 -410.90428) (xy 281.621106 -410.873985)
			(xy 281.595068 -410.855922) (xy 281.594814 -410.855668) (xy 281.587956 -410.850842) (xy 281.571446 -410.845762)
			(xy 281.564808 -410.84416) (xy 281.55116 -410.84416) (xy 281.544522 -410.845762) (xy 281.528012 -410.850842)
			(xy 281.521154 -410.855668) (xy 281.5209 -410.855922) (xy 281.494882 -410.874014) (xy 281.439215 -410.904301)
			(xy 281.380215 -410.927436) (xy 281.318797 -410.943058) (xy 281.255915 -410.950925) (xy 281.224228 -410.951426)
			(xy 281.220164 -410.951426) (xy 281.186416 -410.95064) (xy 281.119568 -410.94124) (xy 281.054552 -410.923075)
			(xy 281.023314 -410.910278) (xy 281.018996 -410.9085) (xy 281.007978 -410.905634) (xy 280.985445 -410.908685)
			(xy 280.975562 -410.914342) (xy 280.904442 -410.961078) (xy 280.894257 -410.968596) (xy 280.882268 -410.990855)
			(xy 280.881582 -411.003496) (xy 280.881582 -411.557724) (xy 282.928058 -411.557724) (xy 282.932129 -411.502102)
			(xy 282.944255 -411.447665) (xy 282.964178 -411.395574) (xy 282.991474 -411.346939) (xy 283.02556 -411.302796)
			(xy 283.065709 -411.264087) (xy 283.111067 -411.231636) (xy 283.160667 -411.206135) (xy 283.213451 -411.188128)
			(xy 283.268294 -411.177998) (xy 283.324028 -411.175961) (xy 283.379465 -411.182061) (xy 283.410544 -411.190186)
			(xy 288.83356 -411.190186) (xy 288.834062 -411.158225) (xy 288.842073 -411.094807) (xy 288.85797 -411.032893)
			(xy 288.881502 -410.97346) (xy 288.912296 -410.917445) (xy 288.949869 -410.86573) (xy 288.993626 -410.819133)
			(xy 289.042879 -410.778388) (xy 289.09685 -410.744137) (xy 289.154689 -410.71692) (xy 289.215482 -410.697167)
			(xy 289.278272 -410.685189) (xy 289.342068 -410.681176) (xy 289.405864 -410.685189) (xy 289.468654 -410.697167)
			(xy 289.529447 -410.71692) (xy 289.587286 -410.744137) (xy 289.641257 -410.778388) (xy 289.69051 -410.819133)
			(xy 289.734267 -410.86573) (xy 289.77184 -410.917445) (xy 289.802634 -410.97346) (xy 289.826166 -411.032893)
			(xy 289.842063 -411.094807) (xy 289.850074 -411.158225) (xy 289.850576 -411.190186) (xy 289.850576 -411.190694)
			(xy 289.850078 -411.224035) (xy 289.841365 -411.290145) (xy 289.824073 -411.354545) (xy 289.798501 -411.416128)
			(xy 289.765088 -411.473835) (xy 289.745166 -411.500574) (xy 289.738622 -411.50999) (xy 289.733869 -411.532395)
			(xy 289.739312 -411.554642) (xy 289.746182 -411.56382) (xy 289.768037 -411.591241) (xy 289.804777 -411.650965)
			(xy 289.832958 -411.715174) (xy 289.852045 -411.782646) (xy 289.861676 -411.852102) (xy 289.86226 -411.887162)
			(xy 289.8617 -411.920295) (xy 289.85309 -411.985998) (xy 289.836023 -412.050028) (xy 289.810789 -412.111301)
			(xy 289.777814 -412.16878) (xy 289.737657 -412.221491) (xy 289.690997 -412.268544) (xy 289.638623 -412.309141)
			(xy 289.610292 -412.326328) (xy 289.601656 -412.331154) (xy 289.589464 -412.34741) (xy 289.568382 -412.426404)
			(xy 289.566355 -412.436091) (xy 289.568965 -412.455689) (xy 289.573462 -412.464504) (xy 289.573462 -412.464758)
			(xy 289.585567 -412.486572) (xy 289.604641 -412.532669) (xy 289.617555 -412.580857) (xy 289.62409 -412.630314)
			(xy 289.624516 -412.655258) (xy 289.62403 -412.682509) (xy 289.616274 -412.736457) (xy 289.600919 -412.788752)
			(xy 289.578277 -412.838329) (xy 289.548811 -412.884179) (xy 289.51312 -412.92537) (xy 289.471929 -412.961061)
			(xy 289.426079 -412.990527) (xy 289.376502 -413.013169) (xy 289.324207 -413.028524) (xy 289.270259 -413.03628)
			(xy 289.215757 -413.03628) (xy 289.161809 -413.028524) (xy 289.109514 -413.013169) (xy 289.059937 -412.990527)
			(xy 289.014087 -412.961061) (xy 288.972896 -412.92537) (xy 288.937205 -412.884179) (xy 288.907739 -412.838329)
			(xy 288.885097 -412.788752) (xy 288.869742 -412.736457) (xy 288.861986 -412.682509) (xy 288.8615 -412.655258)
			(xy 288.861928 -412.629517) (xy 288.86886 -412.578504) (xy 288.882594 -412.528887) (xy 288.902879 -412.48157)
			(xy 288.929346 -412.437412) (xy 288.961514 -412.397217) (xy 288.979864 -412.37916) (xy 288.986689 -412.371944)
			(xy 288.994648 -412.353763) (xy 288.995358 -412.343854) (xy 288.997644 -412.261812) (xy 288.990532 -412.24327)
			(xy 288.983674 -412.235904) (xy 288.962046 -412.212265) (xy 288.924309 -412.160483) (xy 288.893377 -412.104371)
			(xy 288.86974 -412.044817) (xy 288.853773 -411.982765) (xy 288.845727 -411.919199) (xy 288.845244 -411.887162)
			(xy 288.845244 -411.886654) (xy 288.845764 -411.853314) (xy 288.854472 -411.787205) (xy 288.871758 -411.722805)
			(xy 288.897326 -411.661221) (xy 288.930734 -411.603514) (xy 288.950654 -411.576774) (xy 288.957243 -411.567385)
			(xy 288.96198 -411.544963) (xy 288.956517 -411.522707) (xy 288.949638 -411.513528) (xy 288.927808 -411.486088)
			(xy 288.891064 -411.426369) (xy 288.862877 -411.362166) (xy 288.843785 -411.294697) (xy 288.834148 -411.225245)
			(xy 288.83356 -411.190186) (xy 283.410544 -411.190186) (xy 283.433422 -411.196167) (xy 283.484751 -411.217979)
			(xy 283.532357 -411.247033) (xy 283.575225 -411.282708) (xy 283.612442 -411.324245) (xy 283.643215 -411.370758)
			(xy 283.666887 -411.421255) (xy 283.682955 -411.474662) (xy 283.691075 -411.529838) (xy 283.691584 -411.557724)
			(xy 283.691075 -411.58561) (xy 283.682955 -411.640786) (xy 283.666887 -411.694193) (xy 283.664896 -411.69844)
			(xy 287.188654 -411.69844) (xy 287.192725 -411.642818) (xy 287.204851 -411.588381) (xy 287.224774 -411.53629)
			(xy 287.25207 -411.487655) (xy 287.286156 -411.443512) (xy 287.326305 -411.404803) (xy 287.371663 -411.372352)
			(xy 287.421263 -411.346851) (xy 287.474047 -411.328844) (xy 287.52889 -411.318714) (xy 287.584624 -411.316677)
			(xy 287.640061 -411.322777) (xy 287.694018 -411.336883) (xy 287.745347 -411.358695) (xy 287.792953 -411.387749)
			(xy 287.835821 -411.423424) (xy 287.873038 -411.464961) (xy 287.903811 -411.511474) (xy 287.927483 -411.561971)
			(xy 287.943551 -411.615378) (xy 287.951671 -411.670554) (xy 287.95218 -411.69844) (xy 287.951671 -411.726326)
			(xy 287.943551 -411.781502) (xy 287.927483 -411.834909) (xy 287.903811 -411.885406) (xy 287.873038 -411.931919)
			(xy 287.835821 -411.973456) (xy 287.792953 -412.009131) (xy 287.745347 -412.038185) (xy 287.694018 -412.059997)
			(xy 287.640061 -412.074103) (xy 287.584624 -412.080203) (xy 287.52889 -412.078166) (xy 287.474047 -412.068036)
			(xy 287.421263 -412.050029) (xy 287.371663 -412.024528) (xy 287.326305 -411.992077) (xy 287.286156 -411.953368)
			(xy 287.25207 -411.909225) (xy 287.224774 -411.86059) (xy 287.204851 -411.808499) (xy 287.192725 -411.754062)
			(xy 287.188654 -411.69844) (xy 283.664896 -411.69844) (xy 283.643215 -411.74469) (xy 283.612442 -411.791203)
			(xy 283.575225 -411.83274) (xy 283.532357 -411.868415) (xy 283.484751 -411.897469) (xy 283.433422 -411.919281)
			(xy 283.379465 -411.933387) (xy 283.324028 -411.939487) (xy 283.268294 -411.93745) (xy 283.213451 -411.92732)
			(xy 283.160667 -411.909313) (xy 283.111067 -411.883812) (xy 283.065709 -411.851361) (xy 283.02556 -411.812652)
			(xy 282.991474 -411.768509) (xy 282.964178 -411.719874) (xy 282.944255 -411.667783) (xy 282.932129 -411.613346)
			(xy 282.928058 -411.557724) (xy 280.881582 -411.557724) (xy 280.881582 -414.1488) (xy 282.519546 -414.1488)
			(xy 282.523561 -414.084995) (xy 282.535541 -414.022197) (xy 282.555298 -413.961395) (xy 282.58252 -413.903549)
			(xy 282.616777 -413.849572) (xy 282.65753 -413.800313) (xy 282.704136 -413.756552) (xy 282.755859 -413.718977)
			(xy 282.811884 -413.688181) (xy 282.871327 -413.66465) (xy 282.933251 -413.648756) (xy 282.996678 -413.640748)
			(xy 283.028644 -413.64027) (xy 283.063281 -413.640852) (xy 283.131911 -413.650291) (xy 283.198623 -413.668961)
			(xy 283.262183 -413.696515) (xy 283.321413 -413.732444) (xy 283.348684 -413.753808) (xy 283.355899 -413.759154)
			(xy 283.372884 -413.764942) (xy 283.390823 -413.764533) (xy 283.407526 -413.757975) (xy 283.41447 -413.752284)
			(xy 283.437801 -413.732123) (xy 283.488479 -413.696996) (xy 283.54303 -413.668247) (xy 283.600654 -413.646297)
			(xy 283.660507 -413.631468) (xy 283.721713 -413.623978) (xy 283.752544 -413.623506) (xy 283.784504 -413.623983)
			(xy 283.84792 -413.631999) (xy 283.909831 -413.6479) (xy 283.969261 -413.671434) (xy 284.025273 -413.702232)
			(xy 284.076983 -413.739806) (xy 284.123577 -413.783564) (xy 284.16432 -413.832817) (xy 284.198568 -413.886788)
			(xy 284.225783 -413.944625) (xy 284.245534 -414.005418) (xy 284.257511 -414.068206) (xy 284.261525 -414.132)
			(xy 284.257511 -414.195794) (xy 284.245534 -414.258582) (xy 284.225783 -414.319375) (xy 284.198568 -414.377212)
			(xy 284.16432 -414.431183) (xy 284.123577 -414.480436) (xy 284.076983 -414.524194) (xy 284.025273 -414.561768)
			(xy 283.969261 -414.592566) (xy 283.909831 -414.6161) (xy 283.84792 -414.632001) (xy 283.784504 -414.640017)
			(xy 283.752544 -414.640522) (xy 283.717906 -414.639948) (xy 283.649276 -414.630508) (xy 283.582564 -414.611836)
			(xy 283.519004 -414.58428) (xy 283.459774 -414.548349) (xy 283.432504 -414.526984) (xy 283.425296 -414.521628)
			(xy 283.408308 -414.515842) (xy 283.390367 -414.516255) (xy 283.373663 -414.522815) (xy 283.366718 -414.528508)
			(xy 283.343391 -414.548673) (xy 283.292712 -414.5838) (xy 283.23816 -414.612549) (xy 283.180536 -414.634498)
			(xy 283.120682 -414.649326) (xy 283.059475 -414.656815) (xy 283.028644 -414.657286) (xy 282.996678 -414.656852)
			(xy 282.933251 -414.648844) (xy 282.871327 -414.63295) (xy 282.811884 -414.609419) (xy 282.755859 -414.578623)
			(xy 282.704136 -414.541048) (xy 282.65753 -414.497287) (xy 282.616777 -414.448028) (xy 282.58252 -414.394051)
			(xy 282.555298 -414.336205) (xy 282.535541 -414.275403) (xy 282.523561 -414.212605) (xy 282.519546 -414.1488)
			(xy 280.881582 -414.1488) (xy 280.881582 -415.300371) (xy 285.123122 -415.300371) (xy 285.123122 -415.236449)
			(xy 285.131133 -415.173031) (xy 285.14703 -415.111117) (xy 285.170562 -415.051684) (xy 285.201356 -414.995669)
			(xy 285.238929 -414.943954) (xy 285.282686 -414.897357) (xy 285.331939 -414.856612) (xy 285.38591 -414.822361)
			(xy 285.443749 -414.795144) (xy 285.504542 -414.775391) (xy 285.567332 -414.763413) (xy 285.631128 -414.7594)
			(xy 285.694924 -414.763413) (xy 285.757714 -414.775391) (xy 285.818507 -414.795144) (xy 285.876346 -414.822361)
			(xy 285.930317 -414.856612) (xy 285.97957 -414.897357) (xy 286.023327 -414.943954) (xy 286.0609 -414.995669)
			(xy 286.091694 -415.051684) (xy 286.115226 -415.111117) (xy 286.131123 -415.173031) (xy 286.134888 -415.202835)
			(xy 287.269168 -415.202835) (xy 287.269168 -415.138913) (xy 287.277179 -415.075495) (xy 287.293076 -415.013581)
			(xy 287.316608 -414.954148) (xy 287.347402 -414.898133) (xy 287.384975 -414.846418) (xy 287.428732 -414.799821)
			(xy 287.477985 -414.759076) (xy 287.531956 -414.724825) (xy 287.589795 -414.697608) (xy 287.650588 -414.677855)
			(xy 287.713378 -414.665877) (xy 287.777174 -414.661864) (xy 287.84097 -414.665877) (xy 287.90376 -414.677855)
			(xy 287.964553 -414.697608) (xy 288.022392 -414.724825) (xy 288.076363 -414.759076) (xy 288.125616 -414.799821)
			(xy 288.169373 -414.846418) (xy 288.206946 -414.898133) (xy 288.23774 -414.954148) (xy 288.261272 -415.013581)
			(xy 288.277169 -415.075495) (xy 288.28518 -415.138913) (xy 288.285682 -415.170874) (xy 288.28518 -415.202835)
			(xy 288.277169 -415.266253) (xy 288.261272 -415.328167) (xy 288.23774 -415.3876) (xy 288.206946 -415.443615)
			(xy 288.169373 -415.49533) (xy 288.125616 -415.541927) (xy 288.076363 -415.582672) (xy 288.022392 -415.616923)
			(xy 287.964553 -415.64414) (xy 287.90376 -415.663893) (xy 287.84097 -415.675871) (xy 287.777174 -415.679885)
			(xy 287.713378 -415.675871) (xy 287.650588 -415.663893) (xy 287.589795 -415.64414) (xy 287.531956 -415.616923)
			(xy 287.477985 -415.582672) (xy 287.428732 -415.541927) (xy 287.384975 -415.49533) (xy 287.347402 -415.443615)
			(xy 287.316608 -415.3876) (xy 287.293076 -415.328167) (xy 287.277179 -415.266253) (xy 287.269168 -415.202835)
			(xy 286.134888 -415.202835) (xy 286.139134 -415.236449) (xy 286.139636 -415.26841) (xy 286.139134 -415.300371)
			(xy 286.131123 -415.363789) (xy 286.115226 -415.425703) (xy 286.091694 -415.485136) (xy 286.0609 -415.541151)
			(xy 286.023327 -415.592866) (xy 285.97957 -415.639463) (xy 285.930317 -415.680208) (xy 285.876346 -415.714459)
			(xy 285.818507 -415.741676) (xy 285.757714 -415.761429) (xy 285.694924 -415.773407) (xy 285.631128 -415.777421)
			(xy 285.567332 -415.773407) (xy 285.504542 -415.761429) (xy 285.443749 -415.741676) (xy 285.38591 -415.714459)
			(xy 285.331939 -415.680208) (xy 285.282686 -415.639463) (xy 285.238929 -415.592866) (xy 285.201356 -415.541151)
			(xy 285.170562 -415.485136) (xy 285.14703 -415.425703) (xy 285.131133 -415.363789) (xy 285.123122 -415.300371)
			(xy 280.881582 -415.300371) (xy 280.881582 -415.502344) (xy 280.882344 -415.510726) (xy 280.88386 -415.51833)
			(xy 280.890846 -415.532164) (xy 280.89606 -415.537904) (xy 282.372541 -417.014385) (xy 284.219894 -417.014385)
			(xy 284.219894 -416.961087) (xy 284.227837 -416.908383) (xy 284.243547 -416.857453) (xy 284.266673 -416.809432)
			(xy 284.296697 -416.765395) (xy 284.332949 -416.726324) (xy 284.37462 -416.693093) (xy 284.420778 -416.666444)
			(xy 284.470392 -416.646972) (xy 284.522354 -416.635112) (xy 284.575504 -416.631129) (xy 284.628654 -416.635112)
			(xy 284.680616 -416.646972) (xy 284.73023 -416.666444) (xy 284.776388 -416.693093) (xy 284.818059 -416.726324)
			(xy 284.854311 -416.765395) (xy 284.884335 -416.809432) (xy 284.907461 -416.857453) (xy 284.923171 -416.908383)
			(xy 284.931114 -416.961087) (xy 284.931612 -416.987736) (xy 284.931114 -417.014385) (xy 284.928434 -417.032165)
			(xy 285.518088 -417.032165) (xy 285.518088 -416.978867) (xy 285.526031 -416.926163) (xy 285.541741 -416.875233)
			(xy 285.564867 -416.827212) (xy 285.594891 -416.783175) (xy 285.631143 -416.744104) (xy 285.672814 -416.710873)
			(xy 285.718972 -416.684224) (xy 285.768586 -416.664752) (xy 285.820548 -416.652892) (xy 285.873698 -416.648909)
			(xy 285.926848 -416.652892) (xy 285.97881 -416.664752) (xy 286.028424 -416.684224) (xy 286.074582 -416.710873)
			(xy 286.116253 -416.744104) (xy 286.152505 -416.783175) (xy 286.182529 -416.827212) (xy 286.205655 -416.875233)
			(xy 286.221365 -416.926163) (xy 286.229308 -416.978867) (xy 286.229806 -417.005516) (xy 286.229313 -417.031911)
			(xy 286.860478 -417.031911) (xy 286.860478 -416.978613) (xy 286.868421 -416.925909) (xy 286.884131 -416.874979)
			(xy 286.907257 -416.826958) (xy 286.937281 -416.782921) (xy 286.973533 -416.74385) (xy 287.015204 -416.710619)
			(xy 287.061362 -416.68397) (xy 287.110976 -416.664498) (xy 287.162938 -416.652638) (xy 287.216088 -416.648655)
			(xy 287.269238 -416.652638) (xy 287.3212 -416.664498) (xy 287.370814 -416.68397) (xy 287.416972 -416.710619)
			(xy 287.458643 -416.74385) (xy 287.494895 -416.782921) (xy 287.524919 -416.826958) (xy 287.548045 -416.874979)
			(xy 287.563755 -416.925909) (xy 287.571698 -416.978613) (xy 287.572196 -417.005262) (xy 287.571698 -417.031911)
			(xy 287.563755 -417.084615) (xy 287.548045 -417.135545) (xy 287.524919 -417.183566) (xy 287.494895 -417.227603)
			(xy 287.458643 -417.266674) (xy 287.416972 -417.299905) (xy 287.370814 -417.326554) (xy 287.3212 -417.346026)
			(xy 287.269238 -417.357886) (xy 287.216088 -417.36187) (xy 287.162938 -417.357886) (xy 287.110976 -417.346026)
			(xy 287.061362 -417.326554) (xy 287.015204 -417.299905) (xy 286.973533 -417.266674) (xy 286.937281 -417.227603)
			(xy 286.907257 -417.183566) (xy 286.884131 -417.135545) (xy 286.868421 -417.084615) (xy 286.860478 -417.031911)
			(xy 286.229313 -417.031911) (xy 286.229308 -417.032165) (xy 286.221365 -417.084869) (xy 286.205655 -417.135799)
			(xy 286.182529 -417.18382) (xy 286.152505 -417.227857) (xy 286.116253 -417.266928) (xy 286.074582 -417.300159)
			(xy 286.028424 -417.326808) (xy 285.97881 -417.34628) (xy 285.926848 -417.35814) (xy 285.873698 -417.362124)
			(xy 285.820548 -417.35814) (xy 285.768586 -417.34628) (xy 285.718972 -417.326808) (xy 285.672814 -417.300159)
			(xy 285.631143 -417.266928) (xy 285.594891 -417.227857) (xy 285.564867 -417.18382) (xy 285.541741 -417.135799)
			(xy 285.526031 -417.084869) (xy 285.518088 -417.032165) (xy 284.928434 -417.032165) (xy 284.923171 -417.067089)
			(xy 284.907461 -417.118019) (xy 284.884335 -417.16604) (xy 284.854311 -417.210077) (xy 284.818059 -417.249148)
			(xy 284.776388 -417.282379) (xy 284.73023 -417.309028) (xy 284.680616 -417.3285) (xy 284.628654 -417.34036)
			(xy 284.575504 -417.344344) (xy 284.522354 -417.34036) (xy 284.470392 -417.3285) (xy 284.420778 -417.309028)
			(xy 284.37462 -417.282379) (xy 284.332949 -417.249148) (xy 284.296697 -417.210077) (xy 284.266673 -417.16604)
			(xy 284.243547 -417.118019) (xy 284.227837 -417.067089) (xy 284.219894 -417.014385) (xy 282.372541 -417.014385)
			(xy 283.620443 -418.262287) (xy 284.17519 -418.262287) (xy 284.17519 -418.208989) (xy 284.183133 -418.156285)
			(xy 284.198843 -418.105355) (xy 284.221969 -418.057334) (xy 284.251993 -418.013297) (xy 284.288245 -417.974226)
			(xy 284.329916 -417.940995) (xy 284.376074 -417.914346) (xy 284.425688 -417.894874) (xy 284.47765 -417.883014)
			(xy 284.5308 -417.879031) (xy 284.58395 -417.883014) (xy 284.635912 -417.894874) (xy 284.685526 -417.914346)
			(xy 284.731684 -417.940995) (xy 284.773355 -417.974226) (xy 284.809607 -418.013297) (xy 284.839631 -418.057334)
			(xy 284.862757 -418.105355) (xy 284.878467 -418.156285) (xy 284.88641 -418.208989) (xy 284.886908 -418.235638)
			(xy 284.88641 -418.262287) (xy 284.878467 -418.314991) (xy 284.867145 -418.351695) (xy 286.838126 -418.351695)
			(xy 286.838126 -418.298397) (xy 286.846069 -418.245693) (xy 286.861779 -418.194763) (xy 286.884905 -418.146742)
			(xy 286.914929 -418.102705) (xy 286.951181 -418.063634) (xy 286.992852 -418.030403) (xy 287.03901 -418.003754)
			(xy 287.088624 -417.984282) (xy 287.140586 -417.972422) (xy 287.193736 -417.968439) (xy 287.246886 -417.972422)
			(xy 287.298848 -417.984282) (xy 287.348462 -418.003754) (xy 287.39462 -418.030403) (xy 287.436291 -418.063634)
			(xy 287.472543 -418.102705) (xy 287.502567 -418.146742) (xy 287.525693 -418.194763) (xy 287.541403 -418.245693)
			(xy 287.549346 -418.298397) (xy 287.549844 -418.325046) (xy 287.549346 -418.351695) (xy 287.541403 -418.404399)
			(xy 287.525693 -418.455329) (xy 287.502567 -418.50335) (xy 287.472543 -418.547387) (xy 287.448871 -418.5729)
			(xy 288.426739 -418.5729) (xy 288.430752 -418.509113) (xy 288.442728 -418.446332) (xy 288.462478 -418.385546)
			(xy 288.48969 -418.327715) (xy 288.523935 -418.273751) (xy 288.564673 -418.224504) (xy 288.611263 -418.180751)
			(xy 288.662968 -418.143181) (xy 288.718974 -418.112389) (xy 288.778398 -418.088858) (xy 288.840303 -418.07296)
			(xy 288.903711 -418.064946) (xy 288.935668 -418.064442) (xy 288.971156 -418.065025) (xy 289.041441 -418.074903)
			(xy 289.109666 -418.094471) (xy 289.174503 -418.123348) (xy 289.204908 -418.141658) (xy 289.214956 -418.14729)
			(xy 289.237826 -418.149817) (xy 289.24885 -418.146484) (xy 289.32378 -418.119814) (xy 289.334289 -418.115415)
			(xy 289.350383 -418.099339) (xy 289.354768 -418.088826) (xy 289.354768 -418.088572) (xy 289.365014 -418.060314)
			(xy 289.39124 -418.006228) (xy 289.423659 -417.95561) (xy 289.442398 -417.932108) (xy 289.447665 -417.925106)
			(xy 289.453514 -417.908606) (xy 289.453828 -417.89985) (xy 289.453828 -417.745926) (xy 289.453446 -417.737181)
			(xy 289.447621 -417.72069) (xy 289.442398 -417.713668) (xy 289.420645 -417.686288) (xy 289.384094 -417.626672)
			(xy 289.35605 -417.562613) (xy 289.337042 -417.495317) (xy 289.327427 -417.426052) (xy 289.326828 -417.391088)
			(xy 289.327379 -417.358939) (xy 289.335497 -417.295155) (xy 289.351589 -417.232903) (xy 289.375399 -417.173176)
			(xy 289.406547 -417.116925) (xy 289.444535 -417.065049) (xy 289.488759 -417.018375) (xy 289.538513 -416.977647)
			(xy 289.593004 -416.943514) (xy 289.621976 -416.92957) (xy 289.632136 -416.924744) (xy 289.646614 -416.90798)
			(xy 289.67303 -416.810952) (xy 289.669474 -416.789108) (xy 289.663124 -416.779964) (xy 289.647364 -416.756017)
			(xy 289.622391 -416.704417) (xy 289.605422 -416.64966) (xy 289.596839 -416.592981) (xy 289.596322 -416.564318)
			(xy 289.596808 -416.537067) (xy 289.604564 -416.483119) (xy 289.619919 -416.430824) (xy 289.642561 -416.381247)
			(xy 289.672027 -416.335397) (xy 289.707718 -416.294206) (xy 289.748909 -416.258515) (xy 289.794759 -416.229049)
			(xy 289.844336 -416.206407) (xy 289.896631 -416.191052) (xy 289.950579 -416.183296) (xy 290.005081 -416.183296)
			(xy 290.059029 -416.191052) (xy 290.111324 -416.206407) (xy 290.160901 -416.229049) (xy 290.206751 -416.258515)
			(xy 290.247942 -416.294206) (xy 290.283633 -416.335397) (xy 290.313099 -416.381247) (xy 290.335741 -416.430824)
			(xy 290.351096 -416.483119) (xy 290.358852 -416.537067) (xy 290.359338 -416.564318) (xy 290.358948 -416.589999)
			(xy 290.35207 -416.640897) (xy 290.338429 -416.690413) (xy 290.318271 -416.737653) (xy 290.291959 -416.781762)
			(xy 290.259969 -416.821944) (xy 290.22288 -416.857473) (xy 290.202366 -416.872928) (xy 290.193222 -416.879532)
			(xy 290.1823 -416.89909) (xy 290.17595 -416.987736) (xy 290.175681 -416.998791) (xy 290.183458 -417.019467)
			(xy 290.190936 -417.027614) (xy 290.214675 -417.051622) (xy 290.256268 -417.104805) (xy 290.290456 -417.163025)
			(xy 290.316639 -417.225258) (xy 290.334354 -417.290408) (xy 290.343292 -417.35733) (xy 290.343844 -417.391088)
			(xy 290.343251 -417.426053) (xy 290.333652 -417.495322) (xy 290.314646 -417.56262) (xy 290.286593 -417.626677)
			(xy 290.250023 -417.686284) (xy 290.228274 -417.713668) (xy 290.223014 -417.720674) (xy 290.217162 -417.737171)
			(xy 290.216844 -417.745926) (xy 290.216844 -417.89985) (xy 290.217177 -417.9086) (xy 290.223034 -417.925092)
			(xy 290.228274 -417.932108) (xy 290.250012 -417.959499) (xy 290.286566 -418.019112) (xy 290.314613 -418.083168)
			(xy 290.333625 -418.150462) (xy 290.343243 -418.219725) (xy 290.343844 -418.254688) (xy 290.343844 -418.254942)
			(xy 290.343468 -418.282533) (xy 290.337481 -418.337391) (xy 290.331906 -418.364416) (xy 290.32962 -418.374576)
			(xy 290.33343 -418.39515) (xy 290.381182 -418.465) (xy 290.387384 -418.473301) (xy 290.404826 -418.484449)
			(xy 290.414964 -418.48659) (xy 290.440587 -418.491137) (xy 290.490351 -418.506359) (xy 290.537587 -418.528197)
			(xy 290.58142 -418.556249) (xy 290.621038 -418.589993) (xy 290.655706 -418.628804) (xy 290.684782 -418.671964)
			(xy 290.69665 -418.695124) (xy 290.69665 -418.695378) (xy 290.700766 -418.702772) (xy 290.712873 -418.71458)
			(xy 290.728159 -418.721817) (xy 290.736528 -418.723064) (xy 290.821872 -418.732716) (xy 290.830395 -418.73327)
			(xy 290.847025 -418.729433) (xy 290.861486 -418.720368) (xy 290.867084 -418.71392) (xy 290.885312 -418.692133)
			(xy 290.927107 -418.653663) (xy 290.974143 -418.621814) (xy 291.02538 -418.597289) (xy 291.079686 -418.58063)
			(xy 291.135862 -418.572205) (xy 291.164264 -418.57168) (xy 291.191515 -418.572189) (xy 291.245464 -418.579941)
			(xy 291.29776 -418.595291) (xy 291.34734 -418.617929) (xy 291.393192 -418.647392) (xy 291.434385 -418.683081)
			(xy 291.470079 -418.724269) (xy 291.499548 -418.770118) (xy 291.522192 -418.819695) (xy 291.537549 -418.871989)
			(xy 291.545308 -418.925937) (xy 291.545772 -418.953188) (xy 291.545332 -418.979234) (xy 291.538257 -419.030842)
			(xy 291.524235 -419.08101) (xy 291.503528 -419.128808) (xy 291.4904 -419.151308) (xy 291.48588 -419.159562)
			(xy 291.482488 -419.178057) (xy 291.483796 -419.187376) (xy 291.489892 -419.217856) (xy 291.492072 -419.227216)
			(xy 291.502406 -419.243406) (xy 291.509958 -419.249352) (xy 291.533966 -419.267305) (xy 291.578009 -419.307977)
			(xy 291.616963 -419.353546) (xy 291.650287 -419.403381) (xy 291.677518 -419.45679) (xy 291.698279 -419.51303)
			(xy 291.71228 -419.571323) (xy 291.719327 -419.630857) (xy 291.719762 -419.660832) (xy 291.719185 -419.695787)
			(xy 291.70962 -419.76504) (xy 291.690661 -419.832331) (xy 291.662665 -419.896391) (xy 291.626161 -419.956013)
			(xy 291.604446 -419.983412) (xy 291.599197 -419.990349) (xy 291.593359 -420.006723) (xy 291.593016 -420.015416)
			(xy 291.593016 -420.169848) (xy 291.593413 -420.17853) (xy 291.599247 -420.194888) (xy 291.604446 -420.201852)
			(xy 291.626144 -420.229263) (xy 291.662642 -420.288886) (xy 291.690637 -420.352943) (xy 291.709602 -420.42023)
			(xy 291.719179 -420.489478) (xy 291.719623 -420.516122) (xy 292.906778 -420.516122) (xy 292.909385 -420.45309)
			(xy 292.919769 -420.390864) (xy 292.93777 -420.330401) (xy 292.963112 -420.272628) (xy 292.995405 -420.218434)
			(xy 293.034154 -420.168651) (xy 293.078763 -420.124043) (xy 293.128548 -420.085296) (xy 293.182743 -420.053004)
			(xy 293.240516 -420.027664) (xy 293.30098 -420.009665) (xy 293.363205 -419.999284) (xy 293.426238 -419.996679)
			(xy 293.489108 -420.00189) (xy 293.550851 -420.014839) (xy 293.610518 -420.035326) (xy 293.667193 -420.063035)
			(xy 293.720004 -420.097543) (xy 293.768142 -420.138317) (xy 293.810867 -420.184734) (xy 293.847522 -420.236078)
			(xy 293.877544 -420.291562) (xy 293.900473 -420.350334) (xy 293.915955 -420.411491) (xy 293.923754 -420.474093)
			(xy 293.924228 -420.505636) (xy 293.923867 -420.532374) (xy 293.918244 -420.585554) (xy 293.907063 -420.637848)
			(xy 293.899082 -420.66337) (xy 293.89451 -420.67734) (xy 293.901622 -420.705788) (xy 293.990522 -420.7891)
			(xy 294.01897 -420.794688) (xy 294.03294 -420.789354) (xy 294.062691 -420.77817) (xy 294.124277 -420.762455)
			(xy 294.187342 -420.754537) (xy 294.219122 -420.754048) (xy 294.251872 -420.75454) (xy 294.316829 -420.762969)
			(xy 294.380164 -420.77967) (xy 294.440831 -420.804368) (xy 294.497822 -420.836653) (xy 294.550195 -420.875991)
			(xy 294.597082 -420.921729) (xy 294.637705 -420.973111) (xy 294.654986 -421.000936) (xy 294.660162 -421.008629)
			(xy 294.674758 -421.020033) (xy 294.692454 -421.025504) (xy 294.701722 -421.02532) (xy 294.791892 -421.019732)
			(xy 294.801191 -421.018789) (xy 294.818172 -421.011009) (xy 294.831237 -420.997659) (xy 294.835326 -420.989252)
			(xy 294.84685 -420.96417) (xy 294.876088 -420.917353) (xy 294.91177 -420.87524) (xy 294.953151 -420.838712)
			(xy 294.999366 -420.808531) (xy 295.04945 -420.785329) (xy 295.102355 -420.76959) (xy 295.156977 -420.761643)
			(xy 295.184576 -420.76116) (xy 295.21082 -420.761574) (xy 295.262812 -420.768759) (xy 295.313327 -420.78301)
			(xy 295.361409 -420.804057) (xy 295.406148 -420.831502) (xy 295.446699 -420.864827) (xy 295.482293 -420.9034)
			(xy 295.512258 -420.946493) (xy 295.536027 -420.993289) (xy 295.545002 -421.017954) (xy 295.545002 -421.018208)
			(xy 295.548316 -421.02656) (xy 295.559778 -421.040382) (xy 295.575328 -421.049362) (xy 295.584118 -421.051228)
			(xy 295.685464 -421.069008) (xy 295.711372 -421.059356) (xy 295.720008 -421.048688) (xy 295.740753 -421.023936)
			(xy 295.787479 -420.979355) (xy 295.839476 -420.94105) (xy 295.895905 -420.90964) (xy 295.955859 -420.885629)
			(xy 296.01837 -420.869405) (xy 296.082433 -420.861229) (xy 296.114724 -420.860728) (xy 296.146686 -420.861159)
			(xy 296.210107 -420.869174) (xy 296.272022 -420.885074) (xy 296.331457 -420.908608) (xy 296.387474 -420.939406)
			(xy 296.439189 -420.976982) (xy 296.485787 -421.020742) (xy 296.526533 -421.069998) (xy 296.560785 -421.123972)
			(xy 296.588002 -421.181813) (xy 296.607755 -421.242609) (xy 296.619733 -421.305401) (xy 296.623747 -421.3692)
			(xy 296.619733 -421.432999) (xy 296.607755 -421.495791) (xy 296.588002 -421.556587) (xy 296.560785 -421.614428)
			(xy 296.526533 -421.668402) (xy 296.485787 -421.717658) (xy 296.439189 -421.761418) (xy 296.387474 -421.798994)
			(xy 296.331457 -421.829792) (xy 296.272022 -421.853326) (xy 296.210107 -421.869226) (xy 296.146686 -421.877241)
			(xy 296.114724 -421.877744) (xy 296.083133 -421.877219) (xy 296.02044 -421.869372) (xy 295.959203 -421.853819)
			(xy 295.900363 -421.830801) (xy 295.844827 -421.800673) (xy 295.793451 -421.763897) (xy 295.747025 -421.721041)
			(xy 295.706265 -421.672765) (xy 295.671799 -421.619811) (xy 295.644158 -421.562997) (xy 295.623766 -421.503196)
			(xy 295.616884 -421.47236) (xy 295.614692 -421.463606) (xy 295.605112 -421.448325) (xy 295.590836 -421.437303)
			(xy 295.58234 -421.43426) (xy 295.497504 -421.40759) (xy 295.48882 -421.4052) (xy 295.47084 -421.40608)
			(xy 295.454269 -421.413116) (xy 295.447466 -421.41902) (xy 295.447212 -421.419274) (xy 295.425831 -421.438856)
			(xy 295.378245 -421.471975) (xy 295.326192 -421.497506) (xy 295.270873 -421.51486) (xy 295.213564 -421.523637)
			(xy 295.184576 -421.524176) (xy 295.15563 -421.523645) (xy 295.098404 -421.514888) (xy 295.043155 -421.497594)
			(xy 294.991149 -421.472159) (xy 294.943579 -421.439166) (xy 294.901533 -421.39937) (xy 294.883332 -421.376856)
			(xy 294.877325 -421.369784) (xy 294.86148 -421.360158) (xy 294.843248 -421.356791) (xy 294.834056 -421.35806)
			(xy 294.731186 -421.37711) (xy 294.710104 -421.395906) (xy 294.705786 -421.409368) (xy 294.705786 -421.409876)
			(xy 294.69596 -421.440835) (xy 294.669379 -421.500103) (xy 294.635465 -421.555502) (xy 294.594772 -421.606132)
			(xy 294.547962 -421.651166) (xy 294.495798 -421.689872) (xy 294.43913 -421.72162) (xy 294.378879 -421.745892)
			(xy 294.316028 -421.762293) (xy 294.2516 -421.770555) (xy 294.219122 -421.771064) (xy 294.188389 -421.770642)
			(xy 294.12737 -421.763235) (xy 294.067689 -421.748526) (xy 294.010216 -421.72673) (xy 293.95579 -421.698166)
			(xy 293.905205 -421.663248) (xy 293.859197 -421.622488) (xy 293.818438 -421.576478) (xy 293.783523 -421.525891)
			(xy 293.75496 -421.471463) (xy 293.733167 -421.41399) (xy 293.718461 -421.354308) (xy 293.711057 -421.293289)
			(xy 293.710614 -421.262556) (xy 293.710971 -421.235818) (xy 293.716596 -421.182638) (xy 293.727778 -421.130343)
			(xy 293.73576 -421.104822) (xy 293.740332 -421.090852) (xy 293.73322 -421.062404) (xy 293.64432 -420.979092)
			(xy 293.615872 -420.973504) (xy 293.601902 -420.978838) (xy 293.572147 -420.99001) (xy 293.510563 -421.005729)
			(xy 293.447499 -421.013652) (xy 293.41572 -421.014144) (xy 293.384177 -421.013653) (xy 293.321575 -421.005852)
			(xy 293.260419 -420.990368) (xy 293.201648 -420.967437) (xy 293.146165 -420.937413) (xy 293.094821 -420.900757)
			(xy 293.048406 -420.858031) (xy 293.007633 -420.809892) (xy 292.973127 -420.757079) (xy 292.945419 -420.700403)
			(xy 292.924935 -420.640735) (xy 292.911988 -420.578992) (xy 292.906778 -420.516122) (xy 291.719623 -420.516122)
			(xy 291.719762 -420.524432) (xy 291.719274 -420.555431) (xy 291.711728 -420.616969) (xy 291.696753 -420.677131)
			(xy 291.67457 -420.735025) (xy 291.64551 -420.789791) (xy 291.610004 -420.840615) (xy 291.568579 -420.886743)
			(xy 291.545518 -420.907464) (xy 291.538899 -420.913662) (xy 291.530175 -420.929541) (xy 291.5285 -420.938452)
			(xy 291.519102 -421.004238) (xy 291.518252 -421.013202) (xy 291.522158 -421.030767) (xy 291.526722 -421.038528)
			(xy 291.526722 -421.038782) (xy 291.54092 -421.061871) (xy 291.563326 -421.111226) (xy 291.578519 -421.163256)
			(xy 291.586191 -421.216913) (xy 291.586666 -421.244014) (xy 291.58618 -421.271265) (xy 291.578424 -421.325213)
			(xy 291.563069 -421.377508) (xy 291.540427 -421.427085) (xy 291.510961 -421.472935) (xy 291.47527 -421.514126)
			(xy 291.434079 -421.549817) (xy 291.388229 -421.579283) (xy 291.338652 -421.601925) (xy 291.286357 -421.61728)
			(xy 291.232409 -421.625036) (xy 291.177907 -421.625036) (xy 291.123959 -421.61728) (xy 291.071664 -421.601925)
			(xy 291.022087 -421.579283) (xy 290.976237 -421.549817) (xy 290.935046 -421.514126) (xy 290.899355 -421.472935)
			(xy 290.869889 -421.427085) (xy 290.847247 -421.377508) (xy 290.831892 -421.325213) (xy 290.824136 -421.271265)
			(xy 290.82365 -421.244014) (xy 290.824142 -421.216112) (xy 290.832292 -421.160906) (xy 290.848404 -421.107478)
			(xy 290.872135 -421.056971) (xy 290.88715 -421.033448) (xy 290.8919 -421.025684) (xy 290.896052 -421.007974)
			(xy 290.895278 -420.998904) (xy 290.886642 -420.933118) (xy 290.885174 -420.924245) (xy 290.876991 -420.908243)
			(xy 290.87064 -420.901876) (xy 290.870386 -420.901876) (xy 290.848169 -420.881142) (xy 290.80825 -420.835322)
			(xy 290.774076 -420.785071) (xy 290.746132 -420.731107) (xy 290.724817 -420.674198) (xy 290.710435 -420.615154)
			(xy 290.70319 -420.554817) (xy 290.702746 -420.524432) (xy 290.703301 -420.489476) (xy 290.712871 -420.420222)
			(xy 290.731835 -420.352931) (xy 290.759836 -420.288871) (xy 290.796345 -420.22925) (xy 290.818062 -420.201852)
			(xy 290.823286 -420.194899) (xy 290.829139 -420.178537) (xy 290.829492 -420.169848) (xy 290.829492 -420.015416)
			(xy 290.82911 -420.006733) (xy 290.823265 -419.990375) (xy 290.818062 -419.983412) (xy 290.796349 -419.956013)
			(xy 290.759853 -419.896387) (xy 290.73186 -419.832326) (xy 290.7129 -419.765037) (xy 290.703327 -419.695787)
			(xy 290.702746 -419.660832) (xy 290.7033 -419.62647) (xy 290.712537 -419.558369) (xy 290.730862 -419.492132)
			(xy 290.75794 -419.428967) (xy 290.793277 -419.370023) (xy 290.836231 -419.316376) (xy 290.860734 -419.292278)
			(xy 290.867404 -419.285391) (xy 290.875505 -419.268033) (xy 290.876482 -419.258496) (xy 290.87826 -419.227508)
			(xy 290.878371 -419.218126) (xy 290.872632 -419.200278) (xy 290.867084 -419.19271) (xy 290.854065 -419.176012)
			(xy 290.831405 -419.140242) (xy 290.821872 -419.121336) (xy 290.821872 -419.121082) (xy 290.817816 -419.11365)
			(xy 290.805681 -419.10185) (xy 290.790372 -419.09463) (xy 290.781994 -419.093396) (xy 290.69665 -419.083744)
			(xy 290.688128 -419.083148) (xy 290.671496 -419.087007) (xy 290.657036 -419.096086) (xy 290.651438 -419.10254)
			(xy 290.633188 -419.124308) (xy 290.591399 -419.162781) (xy 290.544368 -419.194633) (xy 290.493135 -419.219162)
			(xy 290.438832 -419.235825) (xy 290.382659 -419.244254) (xy 290.354258 -419.24478) (xy 290.327016 -419.244362)
			(xy 290.273087 -419.236606) (xy 290.220809 -419.221257) (xy 290.171247 -419.198627) (xy 290.125408 -419.169177)
			(xy 290.084224 -419.133506) (xy 290.048533 -419.09234) (xy 290.019061 -419.046515) (xy 289.996408 -418.996963)
			(xy 289.981034 -418.944693) (xy 289.973251 -418.890768) (xy 289.97275 -418.863526) (xy 289.97275 -418.852858)
			(xy 289.964622 -418.834062) (xy 289.895534 -418.768784) (xy 289.875722 -418.761672) (xy 289.865308 -418.762434)
			(xy 289.835336 -418.763196) (xy 289.799848 -418.76262) (xy 289.729562 -418.752741) (xy 289.661336 -418.733172)
			(xy 289.596501 -418.704292) (xy 289.566096 -418.68598) (xy 289.556046 -418.680351) (xy 289.533178 -418.67782)
			(xy 289.522154 -418.681154) (xy 289.447224 -418.707824) (xy 289.436707 -418.712207) (xy 289.420616 -418.728294)
			(xy 289.416236 -418.738812) (xy 289.416236 -418.739066) (xy 289.405481 -418.768663) (xy 289.377729 -418.82519)
			(xy 289.343207 -418.877857) (xy 289.302445 -418.925856) (xy 289.256066 -418.968454) (xy 289.204781 -419.004996)
			(xy 289.149375 -419.034925) (xy 289.090697 -419.05778) (xy 289.029645 -419.073213) (xy 288.967154 -419.080987)
			(xy 288.935668 -419.081458) (xy 288.903711 -419.080854) (xy 288.840303 -419.07284) (xy 288.778398 -419.056942)
			(xy 288.718974 -419.033411) (xy 288.662968 -419.002619) (xy 288.611263 -418.965049) (xy 288.564673 -418.921296)
			(xy 288.523935 -418.872049) (xy 288.48969 -418.818085) (xy 288.462478 -418.760254) (xy 288.442728 -418.699468)
			(xy 288.430752 -418.636687) (xy 288.426739 -418.5729) (xy 287.448871 -418.5729) (xy 287.436291 -418.586458)
			(xy 287.39462 -418.619689) (xy 287.348462 -418.646338) (xy 287.298848 -418.66581) (xy 287.246886 -418.67767)
			(xy 287.193736 -418.681654) (xy 287.140586 -418.67767) (xy 287.088624 -418.66581) (xy 287.03901 -418.646338)
			(xy 286.992852 -418.619689) (xy 286.951181 -418.586458) (xy 286.914929 -418.547387) (xy 286.884905 -418.50335)
			(xy 286.861779 -418.455329) (xy 286.846069 -418.404399) (xy 286.838126 -418.351695) (xy 284.867145 -418.351695)
			(xy 284.862757 -418.365921) (xy 284.839631 -418.413942) (xy 284.809607 -418.457979) (xy 284.773355 -418.49705)
			(xy 284.731684 -418.530281) (xy 284.685526 -418.55693) (xy 284.635912 -418.576402) (xy 284.58395 -418.588262)
			(xy 284.5308 -418.592246) (xy 284.47765 -418.588262) (xy 284.425688 -418.576402) (xy 284.376074 -418.55693)
			(xy 284.329916 -418.530281) (xy 284.288245 -418.49705) (xy 284.251993 -418.457979) (xy 284.221969 -418.413942)
			(xy 284.198843 -418.365921) (xy 284.183133 -418.314991) (xy 284.17519 -418.262287) (xy 283.620443 -418.262287)
			(xy 284.605222 -419.247066) (xy 284.610582 -419.251895) (xy 284.62335 -419.258598) (xy 284.630368 -419.260274)
			(xy 284.639258 -419.26129) (xy 284.666414 -419.262425) (xy 284.719931 -419.27191) (xy 284.771386 -419.289415)
			(xy 284.819584 -419.314533) (xy 284.863406 -419.346682) (xy 284.901837 -419.385115) (xy 284.933982 -419.428941)
			(xy 284.959097 -419.477141) (xy 284.976597 -419.528597) (xy 284.986078 -419.582114) (xy 284.987238 -419.60927)
			(xy 284.987492 -419.619176) (xy 284.991302 -419.628066) (xy 284.993281 -419.632429) (xy 284.998648 -419.640363)
			(xy 285.00197 -419.643814) (xy 285.040811 -419.682655) (xy 285.590224 -419.682655) (xy 285.590224 -419.629357)
			(xy 285.598167 -419.576653) (xy 285.613877 -419.525723) (xy 285.637003 -419.477702) (xy 285.667027 -419.433665)
			(xy 285.703279 -419.394594) (xy 285.74495 -419.361363) (xy 285.791108 -419.334714) (xy 285.840722 -419.315242)
			(xy 285.892684 -419.303382) (xy 285.945834 -419.299399) (xy 285.998984 -419.303382) (xy 286.050946 -419.315242)
			(xy 286.10056 -419.334714) (xy 286.146718 -419.361363) (xy 286.188389 -419.394594) (xy 286.224641 -419.433665)
			(xy 286.254665 -419.477702) (xy 286.277791 -419.525723) (xy 286.293501 -419.576653) (xy 286.301444 -419.629357)
			(xy 286.301942 -419.656006) (xy 286.301444 -419.682655) (xy 286.72662 -419.682655) (xy 286.72662 -419.629357)
			(xy 286.734563 -419.576653) (xy 286.750273 -419.525723) (xy 286.773399 -419.477702) (xy 286.803423 -419.433665)
			(xy 286.839675 -419.394594) (xy 286.881346 -419.361363) (xy 286.927504 -419.334714) (xy 286.977118 -419.315242)
			(xy 287.02908 -419.303382) (xy 287.08223 -419.299399) (xy 287.13538 -419.303382) (xy 287.187342 -419.315242)
			(xy 287.236956 -419.334714) (xy 287.283114 -419.361363) (xy 287.324785 -419.394594) (xy 287.361037 -419.433665)
			(xy 287.391061 -419.477702) (xy 287.414187 -419.525723) (xy 287.429897 -419.576653) (xy 287.43784 -419.629357)
			(xy 287.438338 -419.656006) (xy 287.43784 -419.682655) (xy 287.429897 -419.735359) (xy 287.414187 -419.786289)
			(xy 287.391061 -419.83431) (xy 287.361037 -419.878347) (xy 287.324785 -419.917418) (xy 287.283114 -419.950649)
			(xy 287.236956 -419.977298) (xy 287.187342 -419.99677) (xy 287.13538 -420.00863) (xy 287.08223 -420.012614)
			(xy 287.02908 -420.00863) (xy 286.977118 -419.99677) (xy 286.927504 -419.977298) (xy 286.881346 -419.950649)
			(xy 286.839675 -419.917418) (xy 286.803423 -419.878347) (xy 286.773399 -419.83431) (xy 286.750273 -419.786289)
			(xy 286.734563 -419.735359) (xy 286.72662 -419.682655) (xy 286.301444 -419.682655) (xy 286.293501 -419.735359)
			(xy 286.277791 -419.786289) (xy 286.254665 -419.83431) (xy 286.224641 -419.878347) (xy 286.188389 -419.917418)
			(xy 286.146718 -419.950649) (xy 286.10056 -419.977298) (xy 286.050946 -419.99677) (xy 285.998984 -420.00863)
			(xy 285.945834 -420.012614) (xy 285.892684 -420.00863) (xy 285.840722 -419.99677) (xy 285.791108 -419.977298)
			(xy 285.74495 -419.950649) (xy 285.703279 -419.917418) (xy 285.667027 -419.878347) (xy 285.637003 -419.83431)
			(xy 285.613877 -419.786289) (xy 285.598167 -419.735359) (xy 285.590224 -419.682655) (xy 285.040811 -419.682655)
			(xy 286.767735 -421.409579) (xy 287.123118 -421.409579) (xy 287.123118 -421.345657) (xy 287.131129 -421.282239)
			(xy 287.147026 -421.220325) (xy 287.170558 -421.160892) (xy 287.201352 -421.104877) (xy 287.238925 -421.053162)
			(xy 287.282682 -421.006565) (xy 287.331935 -420.96582) (xy 287.385906 -420.931569) (xy 287.443745 -420.904352)
			(xy 287.504538 -420.884599) (xy 287.567328 -420.872621) (xy 287.631124 -420.868608) (xy 287.69492 -420.872621)
			(xy 287.75771 -420.884599) (xy 287.818503 -420.904352) (xy 287.876342 -420.931569) (xy 287.930313 -420.96582)
			(xy 287.979566 -421.006565) (xy 288.023323 -421.053162) (xy 288.060896 -421.104877) (xy 288.09169 -421.160892)
			(xy 288.115222 -421.220325) (xy 288.131119 -421.282239) (xy 288.13913 -421.345657) (xy 288.139632 -421.377618)
			(xy 288.13913 -421.409579) (xy 288.131119 -421.472997) (xy 288.115222 -421.534911) (xy 288.09169 -421.594344)
			(xy 288.060896 -421.650359) (xy 288.023323 -421.702074) (xy 287.979566 -421.748671) (xy 287.930313 -421.789416)
			(xy 287.876342 -421.823667) (xy 287.818503 -421.850884) (xy 287.75771 -421.870637) (xy 287.69492 -421.882615)
			(xy 287.631124 -421.886629) (xy 287.567328 -421.882615) (xy 287.504538 -421.870637) (xy 287.443745 -421.850884)
			(xy 287.385906 -421.823667) (xy 287.331935 -421.789416) (xy 287.282682 -421.748671) (xy 287.238925 -421.702074)
			(xy 287.201352 -421.650359) (xy 287.170558 -421.594344) (xy 287.147026 -421.534911) (xy 287.131129 -421.472997)
			(xy 287.123118 -421.409579) (xy 286.767735 -421.409579) (xy 287.926526 -422.56837) (xy 292.02507 -422.56837)
			(xy 292.025572 -422.536409) (xy 292.033583 -422.472991) (xy 292.04948 -422.411077) (xy 292.073012 -422.351644)
			(xy 292.103806 -422.295629) (xy 292.141379 -422.243914) (xy 292.185136 -422.197317) (xy 292.234389 -422.156572)
			(xy 292.28836 -422.122321) (xy 292.346199 -422.095104) (xy 292.406992 -422.075351) (xy 292.469782 -422.063373)
			(xy 292.533578 -422.05936) (xy 292.597374 -422.063373) (xy 292.660164 -422.075351) (xy 292.720957 -422.095104)
			(xy 292.778796 -422.122321) (xy 292.832767 -422.156572) (xy 292.88202 -422.197317) (xy 292.925777 -422.243914)
			(xy 292.96335 -422.295629) (xy 292.994144 -422.351644) (xy 293.017676 -422.411077) (xy 293.033573 -422.472991)
			(xy 293.041584 -422.536409) (xy 293.042086 -422.56837) (xy 293.041583 -422.600623) (xy 293.033438 -422.664611)
			(xy 293.017262 -422.727055) (xy 292.993316 -422.78695) (xy 292.961984 -422.843334) (xy 292.94328 -422.869614)
			(xy 292.938081 -422.877292) (xy 292.933139 -422.895151) (xy 292.933628 -422.904412) (xy 292.936422 -422.934638)
			(xy 292.93758 -422.943844) (xy 292.945675 -422.960522) (xy 292.95217 -422.96715) (xy 292.973545 -422.987763)
			(xy 293.011812 -423.033174) (xy 293.023197 -423.050419) (xy 294.052746 -423.050419) (xy 294.052746 -422.986497)
			(xy 294.060757 -422.923079) (xy 294.076654 -422.861165) (xy 294.100186 -422.801732) (xy 294.13098 -422.745717)
			(xy 294.168553 -422.694002) (xy 294.21231 -422.647405) (xy 294.261563 -422.60666) (xy 294.315534 -422.572409)
			(xy 294.373373 -422.545192) (xy 294.434166 -422.525439) (xy 294.496956 -422.513461) (xy 294.560752 -422.509448)
			(xy 294.624548 -422.513461) (xy 294.687338 -422.525439) (xy 294.748131 -422.545192) (xy 294.80597 -422.572409)
			(xy 294.859941 -422.60666) (xy 294.909194 -422.647405) (xy 294.952951 -422.694002) (xy 294.990524 -422.745717)
			(xy 295.021318 -422.801732) (xy 295.04485 -422.861165) (xy 295.060747 -422.923079) (xy 295.068758 -422.986497)
			(xy 295.06926 -423.018458) (xy 295.068758 -423.050419) (xy 295.060747 -423.113837) (xy 295.04485 -423.175751)
			(xy 295.021318 -423.235184) (xy 295.004062 -423.266573) (xy 296.442886 -423.266573) (xy 296.442886 -423.202651)
			(xy 296.450897 -423.139233) (xy 296.466794 -423.077319) (xy 296.490326 -423.017886) (xy 296.52112 -422.961871)
			(xy 296.558693 -422.910156) (xy 296.60245 -422.863559) (xy 296.651703 -422.822814) (xy 296.705674 -422.788563)
			(xy 296.763513 -422.761346) (xy 296.824306 -422.741593) (xy 296.887096 -422.729615) (xy 296.950892 -422.725602)
			(xy 297.014688 -422.729615) (xy 297.077478 -422.741593) (xy 297.138271 -422.761346) (xy 297.19611 -422.788563)
			(xy 297.250081 -422.822814) (xy 297.299334 -422.863559) (xy 297.343091 -422.910156) (xy 297.380664 -422.961871)
			(xy 297.411458 -423.017886) (xy 297.43499 -423.077319) (xy 297.450887 -423.139233) (xy 297.458898 -423.202651)
			(xy 297.4594 -423.234612) (xy 297.458898 -423.266573) (xy 297.45809 -423.272966) (xy 299.13148 -423.272966)
			(xy 299.135551 -423.217344) (xy 299.147677 -423.162907) (xy 299.1676 -423.110816) (xy 299.194896 -423.062181)
			(xy 299.228982 -423.018038) (xy 299.269131 -422.979329) (xy 299.314489 -422.946878) (xy 299.364089 -422.921377)
			(xy 299.416873 -422.90337) (xy 299.471716 -422.89324) (xy 299.52745 -422.891203) (xy 299.582887 -422.897303)
			(xy 299.636844 -422.911409) (xy 299.688173 -422.933221) (xy 299.735779 -422.962275) (xy 299.778647 -422.99795)
			(xy 299.815864 -423.039487) (xy 299.846637 -423.086) (xy 299.870309 -423.136497) (xy 299.886377 -423.189904)
			(xy 299.892882 -423.234104) (xy 302.615344 -423.234104) (xy 302.619415 -423.178482) (xy 302.631541 -423.124045)
			(xy 302.651464 -423.071954) (xy 302.67876 -423.023319) (xy 302.712846 -422.979176) (xy 302.752995 -422.940467)
			(xy 302.798353 -422.908016) (xy 302.847953 -422.882515) (xy 302.900737 -422.864508) (xy 302.95558 -422.854378)
			(xy 303.011314 -422.852341) (xy 303.066751 -422.858441) (xy 303.120708 -422.872547) (xy 303.172037 -422.894359)
			(xy 303.219643 -422.923413) (xy 303.262511 -422.959088) (xy 303.299728 -423.000625) (xy 303.330501 -423.047138)
			(xy 303.354173 -423.097635) (xy 303.370241 -423.151042) (xy 303.378361 -423.206218) (xy 303.37887 -423.234104)
			(xy 303.378361 -423.26199) (xy 303.370241 -423.317166) (xy 303.354173 -423.370573) (xy 303.330501 -423.42107)
			(xy 303.299728 -423.467583) (xy 303.262511 -423.50912) (xy 303.219643 -423.544795) (xy 303.172037 -423.573849)
			(xy 303.120708 -423.595661) (xy 303.066751 -423.609767) (xy 303.011314 -423.615867) (xy 302.95558 -423.61383)
			(xy 302.900737 -423.6037) (xy 302.847953 -423.585693) (xy 302.798353 -423.560192) (xy 302.752995 -423.527741)
			(xy 302.712846 -423.489032) (xy 302.67876 -423.444889) (xy 302.651464 -423.396254) (xy 302.631541 -423.344163)
			(xy 302.619415 -423.289726) (xy 302.615344 -423.234104) (xy 299.892882 -423.234104) (xy 299.894497 -423.24508)
			(xy 299.895006 -423.272966) (xy 299.894497 -423.300852) (xy 299.886377 -423.356028) (xy 299.870309 -423.409435)
			(xy 299.846637 -423.459932) (xy 299.815864 -423.506445) (xy 299.778647 -423.547982) (xy 299.735779 -423.583657)
			(xy 299.688173 -423.612711) (xy 299.636844 -423.634523) (xy 299.582887 -423.648629) (xy 299.52745 -423.654729)
			(xy 299.471716 -423.652692) (xy 299.416873 -423.642562) (xy 299.364089 -423.624555) (xy 299.314489 -423.599054)
			(xy 299.269131 -423.566603) (xy 299.228982 -423.527894) (xy 299.194896 -423.483751) (xy 299.1676 -423.435116)
			(xy 299.147677 -423.383025) (xy 299.135551 -423.328588) (xy 299.13148 -423.272966) (xy 297.45809 -423.272966)
			(xy 297.450887 -423.329991) (xy 297.43499 -423.391905) (xy 297.411458 -423.451338) (xy 297.380664 -423.507353)
			(xy 297.343091 -423.559068) (xy 297.299334 -423.605665) (xy 297.250081 -423.64641) (xy 297.19611 -423.680661)
			(xy 297.189686 -423.683684) (xy 298.183298 -423.683684) (xy 298.187369 -423.628062) (xy 298.199495 -423.573625)
			(xy 298.219418 -423.521534) (xy 298.246714 -423.472899) (xy 298.2808 -423.428756) (xy 298.320949 -423.390047)
			(xy 298.366307 -423.357596) (xy 298.415907 -423.332095) (xy 298.468691 -423.314088) (xy 298.523534 -423.303958)
			(xy 298.579268 -423.301921) (xy 298.634705 -423.308021) (xy 298.688662 -423.322127) (xy 298.739991 -423.343939)
			(xy 298.787597 -423.372993) (xy 298.830465 -423.408668) (xy 298.867682 -423.450205) (xy 298.898455 -423.496718)
			(xy 298.922127 -423.547215) (xy 298.938195 -423.600622) (xy 298.946315 -423.655798) (xy 298.946824 -423.683684)
			(xy 298.946315 -423.71157) (xy 298.938195 -423.766746) (xy 298.922127 -423.820153) (xy 298.898455 -423.87065)
			(xy 298.867682 -423.917163) (xy 298.830465 -423.9587) (xy 298.787597 -423.994375) (xy 298.739991 -424.023429)
			(xy 298.688662 -424.045241) (xy 298.634705 -424.059347) (xy 298.579268 -424.065447) (xy 298.523534 -424.06341)
			(xy 298.468691 -424.05328) (xy 298.415907 -424.035273) (xy 298.366307 -424.009772) (xy 298.320949 -423.977321)
			(xy 298.2808 -423.938612) (xy 298.246714 -423.894469) (xy 298.219418 -423.845834) (xy 298.199495 -423.793743)
			(xy 298.187369 -423.739306) (xy 298.183298 -423.683684) (xy 297.189686 -423.683684) (xy 297.138271 -423.707878)
			(xy 297.077478 -423.727631) (xy 297.014688 -423.739609) (xy 296.950892 -423.743623) (xy 296.887096 -423.739609)
			(xy 296.824306 -423.727631) (xy 296.763513 -423.707878) (xy 296.705674 -423.680661) (xy 296.651703 -423.64641)
			(xy 296.60245 -423.605665) (xy 296.558693 -423.559068) (xy 296.52112 -423.507353) (xy 296.490326 -423.451338)
			(xy 296.466794 -423.391905) (xy 296.450897 -423.329991) (xy 296.442886 -423.266573) (xy 295.004062 -423.266573)
			(xy 294.990524 -423.291199) (xy 294.952951 -423.342914) (xy 294.909194 -423.389511) (xy 294.859941 -423.430256)
			(xy 294.80597 -423.464507) (xy 294.748131 -423.491724) (xy 294.687338 -423.511477) (xy 294.624548 -423.523455)
			(xy 294.560752 -423.527469) (xy 294.496956 -423.523455) (xy 294.434166 -423.511477) (xy 294.373373 -423.491724)
			(xy 294.315534 -423.464507) (xy 294.261563 -423.430256) (xy 294.21231 -423.389511) (xy 294.168553 -423.342914)
			(xy 294.13098 -423.291199) (xy 294.100186 -423.235184) (xy 294.076654 -423.175751) (xy 294.060757 -423.113837)
			(xy 294.052746 -423.050419) (xy 293.023197 -423.050419) (xy 293.044531 -423.082732) (xy 293.071257 -423.135762)
			(xy 293.091627 -423.191544) (xy 293.105363 -423.249318) (xy 293.112278 -423.308298) (xy 293.112698 -423.33799)
			(xy 293.112194 -423.36986) (xy 293.104227 -423.433102) (xy 293.088429 -423.494854) (xy 293.065047 -423.554151)
			(xy 293.034448 -423.610067) (xy 293.016178 -423.636186) (xy 293.011287 -423.643583) (xy 293.006336 -423.660595)
			(xy 293.006526 -423.66946) (xy 293.008812 -423.699432) (xy 293.009797 -423.708292) (xy 293.017077 -423.724552)
			(xy 293.023036 -423.731182) (xy 293.045472 -423.754981) (xy 293.084659 -423.807348) (xy 293.116805 -423.86431)
			(xy 293.141378 -423.924925) (xy 293.157974 -423.98819) (xy 293.166317 -424.053062) (xy 293.1668 -424.085766)
			(xy 293.166333 -424.115864) (xy 293.165986 -424.118786) (xy 294.192196 -424.118786) (xy 294.196267 -424.063164)
			(xy 294.208393 -424.008727) (xy 294.228316 -423.956636) (xy 294.255612 -423.908001) (xy 294.289698 -423.863858)
			(xy 294.329847 -423.825149) (xy 294.375205 -423.792698) (xy 294.424805 -423.767197) (xy 294.477589 -423.74919)
			(xy 294.532432 -423.73906) (xy 294.588166 -423.737023) (xy 294.643603 -423.743123) (xy 294.69756 -423.757229)
			(xy 294.748889 -423.779041) (xy 294.796495 -423.808095) (xy 294.839363 -423.84377) (xy 294.87658 -423.885307)
			(xy 294.907353 -423.93182) (xy 294.931025 -423.982317) (xy 294.947093 -424.035724) (xy 294.955213 -424.0909)
			(xy 294.955722 -424.118786) (xy 294.955213 -424.146672) (xy 294.947093 -424.201848) (xy 294.931025 -424.255255)
			(xy 294.929176 -424.2592) (xy 299.562837 -424.2592) (xy 299.566851 -424.195411) (xy 299.578827 -424.132628)
			(xy 299.598578 -424.071841) (xy 299.625791 -424.014008) (xy 299.660038 -423.960043) (xy 299.700779 -423.910795)
			(xy 299.747371 -423.867041) (xy 299.799079 -423.829472) (xy 299.855088 -423.79868) (xy 299.914514 -423.77515)
			(xy 299.976421 -423.759254) (xy 300.039832 -423.751242) (xy 300.07179 -423.75074) (xy 300.106744 -423.751341)
			(xy 300.175996 -423.7609) (xy 300.243287 -423.779853) (xy 300.307347 -423.807844) (xy 300.366971 -423.844344)
			(xy 300.39437 -423.866056) (xy 300.401579 -423.871505) (xy 300.418612 -423.877503) (xy 300.427644 -423.87774)
			(xy 300.457616 -423.876978) (xy 300.466608 -423.876468) (xy 300.48339 -423.869956) (xy 300.490382 -423.864278)
			(xy 300.513699 -423.844189) (xy 300.564316 -423.809171) (xy 300.618789 -423.78052) (xy 300.676323 -423.758655)
			(xy 300.736076 -423.743897) (xy 300.797174 -423.73646) (xy 300.827948 -423.736008) (xy 300.859908 -423.736481)
			(xy 300.923324 -423.744498) (xy 300.985234 -423.760399) (xy 301.044664 -423.783934) (xy 301.100676 -423.814731)
			(xy 301.152386 -423.852305) (xy 301.19898 -423.896064) (xy 301.239722 -423.945317) (xy 301.273971 -423.999288)
			(xy 301.301185 -424.057126) (xy 301.320936 -424.117918) (xy 301.332913 -424.180706) (xy 301.336927 -424.2445)
			(xy 301.332913 -424.308294) (xy 301.320936 -424.371082) (xy 301.319736 -424.374775) (xy 301.908458 -424.374775)
			(xy 301.908458 -424.310853) (xy 301.916469 -424.247435) (xy 301.932366 -424.185521) (xy 301.955898 -424.126088)
			(xy 301.986692 -424.070073) (xy 302.024265 -424.018358) (xy 302.068022 -423.971761) (xy 302.117275 -423.931016)
			(xy 302.171246 -423.896765) (xy 302.229085 -423.869548) (xy 302.289878 -423.849795) (xy 302.352668 -423.837817)
			(xy 302.416464 -423.833804) (xy 302.48026 -423.837817) (xy 302.54305 -423.849795) (xy 302.603843 -423.869548)
			(xy 302.661682 -423.896765) (xy 302.715653 -423.931016) (xy 302.764906 -423.971761) (xy 302.808663 -424.018358)
			(xy 302.846236 -424.070073) (xy 302.87703 -424.126088) (xy 302.900562 -424.185521) (xy 302.916459 -424.247435)
			(xy 302.92447 -424.310853) (xy 302.924972 -424.342814) (xy 302.92447 -424.374775) (xy 302.916459 -424.438193)
			(xy 302.900562 -424.500107) (xy 302.87703 -424.55954) (xy 302.846236 -424.615555) (xy 302.808663 -424.66727)
			(xy 302.764906 -424.713867) (xy 302.715653 -424.754612) (xy 302.661682 -424.788863) (xy 302.603843 -424.81608)
			(xy 302.54305 -424.835833) (xy 302.48026 -424.847811) (xy 302.416464 -424.851825) (xy 302.352668 -424.847811)
			(xy 302.289878 -424.835833) (xy 302.229085 -424.81608) (xy 302.171246 -424.788863) (xy 302.117275 -424.754612)
			(xy 302.068022 -424.713867) (xy 302.024265 -424.66727) (xy 301.986692 -424.615555) (xy 301.955898 -424.55954)
			(xy 301.932366 -424.500107) (xy 301.916469 -424.438193) (xy 301.908458 -424.374775) (xy 301.319736 -424.374775)
			(xy 301.301185 -424.431874) (xy 301.273971 -424.489712) (xy 301.239722 -424.543683) (xy 301.19898 -424.592936)
			(xy 301.152386 -424.636695) (xy 301.100676 -424.674269) (xy 301.044664 -424.705066) (xy 300.985234 -424.728601)
			(xy 300.923324 -424.744502) (xy 300.859908 -424.752519) (xy 300.827948 -424.753024) (xy 300.792992 -424.752467)
			(xy 300.723738 -424.742898) (xy 300.656447 -424.723935) (xy 300.592387 -424.695935) (xy 300.532766 -424.659425)
			(xy 300.505368 -424.637708) (xy 300.498179 -424.632229) (xy 300.481131 -424.62625) (xy 300.472094 -424.626024)
			(xy 300.442122 -424.626786) (xy 300.433133 -424.627322) (xy 300.416352 -424.633817) (xy 300.409356 -424.639486)
			(xy 300.386058 -424.659599) (xy 300.335438 -424.694615) (xy 300.280961 -424.723263) (xy 300.223423 -424.745124)
			(xy 300.163666 -424.759878) (xy 300.102565 -424.767308) (xy 300.07179 -424.767756) (xy 300.039832 -424.767158)
			(xy 299.976421 -424.759146) (xy 299.914514 -424.74325) (xy 299.855088 -424.71972) (xy 299.799079 -424.688928)
			(xy 299.747371 -424.651359) (xy 299.700779 -424.607605) (xy 299.660038 -424.558357) (xy 299.625791 -424.504392)
			(xy 299.598578 -424.446559) (xy 299.578827 -424.385772) (xy 299.566851 -424.322989) (xy 299.562837 -424.2592)
			(xy 294.929176 -424.2592) (xy 294.907353 -424.305752) (xy 294.87658 -424.352265) (xy 294.839363 -424.393802)
			(xy 294.796495 -424.429477) (xy 294.748889 -424.458531) (xy 294.69756 -424.480343) (xy 294.643603 -424.494449)
			(xy 294.588166 -424.500549) (xy 294.532432 -424.498512) (xy 294.477589 -424.488382) (xy 294.424805 -424.470375)
			(xy 294.375205 -424.444874) (xy 294.329847 -424.412423) (xy 294.289698 -424.373714) (xy 294.255612 -424.329571)
			(xy 294.228316 -424.280936) (xy 294.208393 -424.228845) (xy 294.196267 -424.174408) (xy 294.192196 -424.118786)
			(xy 293.165986 -424.118786) (xy 293.159236 -424.175641) (xy 293.145124 -424.23416) (xy 293.124196 -424.290602)
			(xy 293.096745 -424.344175) (xy 293.063156 -424.394129) (xy 293.043864 -424.417236) (xy 293.038455 -424.424055)
			(xy 293.032234 -424.440299) (xy 293.031672 -424.448986) (xy 293.030656 -424.47845) (xy 293.030699 -424.48719)
			(xy 293.03603 -424.503821) (xy 293.04107 -424.510962) (xy 293.060776 -424.537626) (xy 293.093839 -424.595096)
			(xy 293.119147 -424.656378) (xy 293.136269 -424.720431) (xy 293.144916 -424.786167) (xy 293.145464 -424.819318)
			(xy 293.144962 -424.851279) (xy 293.136951 -424.914697) (xy 293.121054 -424.976611) (xy 293.097522 -425.036044)
			(xy 293.066728 -425.092059) (xy 293.029155 -425.143774) (xy 292.985398 -425.190371) (xy 292.936145 -425.231116)
			(xy 292.882174 -425.265367) (xy 292.824335 -425.292584) (xy 292.763542 -425.312337) (xy 292.700752 -425.324315)
			(xy 292.636956 -425.328329) (xy 292.57316 -425.324315) (xy 292.51037 -425.312337) (xy 292.449577 -425.292584)
			(xy 292.391738 -425.265367) (xy 292.337767 -425.231116) (xy 292.288514 -425.190371) (xy 292.244757 -425.143774)
			(xy 292.207184 -425.092059) (xy 292.17639 -425.036044) (xy 292.152858 -424.976611) (xy 292.136961 -424.914697)
			(xy 292.12895 -424.851279) (xy 292.128448 -424.819318) (xy 292.128918 -424.78922) (xy 292.136017 -424.729444)
			(xy 292.150129 -424.670925) (xy 292.171056 -424.614484) (xy 292.198506 -424.56091) (xy 292.232094 -424.510956)
			(xy 292.251384 -424.487848) (xy 292.256753 -424.481001) (xy 292.263 -424.464778) (xy 292.263576 -424.456098)
			(xy 292.264592 -424.426634) (xy 292.264548 -424.417894) (xy 292.259217 -424.401263) (xy 292.254178 -424.394122)
			(xy 292.234458 -424.367468) (xy 292.201399 -424.309995) (xy 292.176095 -424.24871) (xy 292.158975 -424.184655)
			(xy 292.150331 -424.118917) (xy 292.149784 -424.085766) (xy 292.150269 -424.053895) (xy 292.158241 -423.990653)
			(xy 292.174043 -423.928901) (xy 292.197429 -423.869604) (xy 292.228033 -423.813688) (xy 292.246304 -423.78757)
			(xy 292.251213 -423.780183) (xy 292.256153 -423.763163) (xy 292.255956 -423.754296) (xy 292.25367 -423.724324)
			(xy 292.252709 -423.71546) (xy 292.245413 -423.699201) (xy 292.239446 -423.692574) (xy 292.217034 -423.668754)
			(xy 292.177845 -423.616391) (xy 292.145696 -423.559433) (xy 292.121119 -423.498823) (xy 292.104518 -423.435561)
			(xy 292.096168 -423.370692) (xy 292.095682 -423.33799) (xy 292.096169 -423.305737) (xy 292.104319 -423.241748)
			(xy 292.120498 -423.179304) (xy 292.144448 -423.119409) (xy 292.175783 -423.063025) (xy 292.194488 -423.036746)
			(xy 292.199657 -423.029049) (xy 292.204618 -423.011206) (xy 292.20414 -423.001948) (xy 292.201346 -422.971722)
			(xy 292.200142 -422.962525) (xy 292.192078 -422.945845) (xy 292.185598 -422.93921) (xy 292.164246 -422.918574)
			(xy 292.125979 -422.873167) (xy 292.093258 -422.823613) (xy 292.066529 -422.770586) (xy 292.046156 -422.714809)
			(xy 292.032415 -422.657038) (xy 292.025493 -422.598061) (xy 292.02507 -422.56837) (xy 287.926526 -422.56837)
			(xy 289.50539 -424.147234) (xy 289.506152 -424.147996) (xy 289.51426 -424.154947) (xy 289.534336 -424.162163)
			(xy 289.545014 -424.161966) (xy 289.55615 -424.160757) (xy 289.578517 -424.159485) (xy 289.589718 -424.159426)
			(xy 289.616969 -424.159891) (xy 289.670916 -424.16765) (xy 289.72321 -424.183008) (xy 289.772786 -424.205652)
			(xy 289.818634 -424.235121) (xy 289.859822 -424.270815) (xy 289.89551 -424.312008) (xy 289.924973 -424.35786)
			(xy 289.94761 -424.407439) (xy 289.962961 -424.459735) (xy 289.96357 -424.463972) (xy 290.22116 -424.463972)
			(xy 290.225231 -424.40835) (xy 290.237357 -424.353913) (xy 290.25728 -424.301822) (xy 290.284576 -424.253187)
			(xy 290.318662 -424.209044) (xy 290.358811 -424.170335) (xy 290.404169 -424.137884) (xy 290.453769 -424.112383)
			(xy 290.506553 -424.094376) (xy 290.561396 -424.084246) (xy 290.61713 -424.082209) (xy 290.672567 -424.088309)
			(xy 290.726524 -424.102415) (xy 290.777853 -424.124227) (xy 290.825459 -424.153281) (xy 290.868327 -424.188956)
			(xy 290.905544 -424.230493) (xy 290.936317 -424.277006) (xy 290.959989 -424.327503) (xy 290.976057 -424.38091)
			(xy 290.984177 -424.436086) (xy 290.984686 -424.463972) (xy 290.984177 -424.491858) (xy 290.976057 -424.547034)
			(xy 290.959989 -424.600441) (xy 290.936317 -424.650938) (xy 290.905544 -424.697451) (xy 290.868327 -424.738988)
			(xy 290.825459 -424.774663) (xy 290.777853 -424.803717) (xy 290.726524 -424.825529) (xy 290.672567 -424.839635)
			(xy 290.61713 -424.845735) (xy 290.561396 -424.843698) (xy 290.506553 -424.833568) (xy 290.453769 -424.815561)
			(xy 290.404169 -424.79006) (xy 290.358811 -424.757609) (xy 290.318662 -424.7189) (xy 290.284576 -424.674757)
			(xy 290.25728 -424.626122) (xy 290.237357 -424.574031) (xy 290.225231 -424.519594) (xy 290.22116 -424.463972)
			(xy 289.96357 -424.463972) (xy 289.970713 -424.513683) (xy 289.971226 -424.540934) (xy 289.971167 -424.552135)
			(xy 289.969896 -424.574502) (xy 289.968686 -424.585638) (xy 289.96835 -424.596336) (xy 289.975594 -424.616456)
			(xy 289.982656 -424.6245) (xy 289.983418 -424.625262) (xy 291.348117 -425.989961) (xy 292.734994 -425.989961)
			(xy 292.734994 -425.926039) (xy 292.743005 -425.862621) (xy 292.758902 -425.800707) (xy 292.782434 -425.741274)
			(xy 292.813228 -425.685259) (xy 292.850801 -425.633544) (xy 292.894558 -425.586947) (xy 292.943811 -425.546202)
			(xy 292.997782 -425.511951) (xy 293.055621 -425.484734) (xy 293.116414 -425.464981) (xy 293.179204 -425.453003)
			(xy 293.243 -425.44899) (xy 293.306796 -425.453003) (xy 293.369586 -425.464981) (xy 293.430379 -425.484734)
			(xy 293.488218 -425.511951) (xy 293.542189 -425.546202) (xy 293.591442 -425.586947) (xy 293.635199 -425.633544)
			(xy 293.656092 -425.662301) (xy 301.962814 -425.662301) (xy 301.962814 -425.598379) (xy 301.970825 -425.534961)
			(xy 301.986722 -425.473047) (xy 302.010254 -425.413614) (xy 302.041048 -425.357599) (xy 302.078621 -425.305884)
			(xy 302.122378 -425.259287) (xy 302.171631 -425.218542) (xy 302.225602 -425.184291) (xy 302.283441 -425.157074)
			(xy 302.344234 -425.137321) (xy 302.407024 -425.125343) (xy 302.47082 -425.12133) (xy 302.534616 -425.125343)
			(xy 302.597406 -425.137321) (xy 302.658199 -425.157074) (xy 302.716038 -425.184291) (xy 302.770009 -425.218542)
			(xy 302.819262 -425.259287) (xy 302.863019 -425.305884) (xy 302.900592 -425.357599) (xy 302.931386 -425.413614)
			(xy 302.954918 -425.473047) (xy 302.970815 -425.534961) (xy 302.978826 -425.598379) (xy 302.979328 -425.63034)
			(xy 302.978826 -425.662301) (xy 302.970815 -425.725719) (xy 302.954918 -425.787633) (xy 302.931386 -425.847066)
			(xy 302.900592 -425.903081) (xy 302.863019 -425.954796) (xy 302.819262 -426.001393) (xy 302.770009 -426.042138)
			(xy 302.716038 -426.076389) (xy 302.658199 -426.103606) (xy 302.597406 -426.123359) (xy 302.534616 -426.135337)
			(xy 302.47082 -426.139351) (xy 302.407024 -426.135337) (xy 302.344234 -426.123359) (xy 302.283441 -426.103606)
			(xy 302.225602 -426.076389) (xy 302.171631 -426.042138) (xy 302.122378 -426.001393) (xy 302.078621 -425.954796)
			(xy 302.041048 -425.903081) (xy 302.010254 -425.847066) (xy 301.986722 -425.787633) (xy 301.970825 -425.725719)
			(xy 301.962814 -425.662301) (xy 293.656092 -425.662301) (xy 293.672772 -425.685259) (xy 293.703566 -425.741274)
			(xy 293.727098 -425.800707) (xy 293.742995 -425.862621) (xy 293.751006 -425.926039) (xy 293.751508 -425.958)
			(xy 293.751006 -425.989961) (xy 293.742995 -426.053379) (xy 293.727098 -426.115293) (xy 293.703566 -426.174726)
			(xy 293.672772 -426.230741) (xy 293.635199 -426.282456) (xy 293.591442 -426.329053) (xy 293.542189 -426.369798)
			(xy 293.488218 -426.404049) (xy 293.430379 -426.431266) (xy 293.369586 -426.451019) (xy 293.306796 -426.462997)
			(xy 293.243 -426.467011) (xy 293.179204 -426.462997) (xy 293.116414 -426.451019) (xy 293.055621 -426.431266)
			(xy 292.997782 -426.404049) (xy 292.943811 -426.369798) (xy 292.894558 -426.329053) (xy 292.850801 -426.282456)
			(xy 292.813228 -426.230741) (xy 292.782434 -426.174726) (xy 292.758902 -426.115293) (xy 292.743005 -426.053379)
			(xy 292.734994 -425.989961) (xy 291.348117 -425.989961) (xy 292.278054 -426.919898) (xy 292.285674 -426.925994)
			(xy 292.286182 -426.926502) (xy 292.293098 -426.930807) (xy 292.308771 -426.935213) (xy 292.316916 -426.935138)
			(xy 292.324282 -426.934884) (xy 292.339268 -426.92955) (xy 292.346126 -426.923962) (xy 292.37316 -426.903257)
			(xy 292.431716 -426.868498) (xy 292.49439 -426.841871) (xy 292.560059 -426.823855) (xy 292.627546 -426.814772)
			(xy 292.661594 -426.814234) (xy 292.692325 -426.814679) (xy 292.75334 -426.822088) (xy 292.761665 -426.82414)
			(xy 302.54143 -426.82414) (xy 302.545501 -426.768518) (xy 302.557627 -426.714081) (xy 302.57755 -426.66199)
			(xy 302.604846 -426.613355) (xy 302.638932 -426.569212) (xy 302.679081 -426.530503) (xy 302.724439 -426.498052)
			(xy 302.774039 -426.472551) (xy 302.826823 -426.454544) (xy 302.881666 -426.444414) (xy 302.9374 -426.442377)
			(xy 302.992837 -426.448477) (xy 303.046794 -426.462583) (xy 303.098123 -426.484395) (xy 303.145729 -426.513449)
			(xy 303.188597 -426.549124) (xy 303.225814 -426.590661) (xy 303.256587 -426.637174) (xy 303.280259 -426.687671)
			(xy 303.296327 -426.741078) (xy 303.304447 -426.796254) (xy 303.304956 -426.82414) (xy 303.304447 -426.852026)
			(xy 303.296327 -426.907202) (xy 303.280259 -426.960609) (xy 303.256587 -427.011106) (xy 303.225814 -427.057619)
			(xy 303.188597 -427.099156) (xy 303.145729 -427.134831) (xy 303.098123 -427.163885) (xy 303.046794 -427.185697)
			(xy 302.992837 -427.199803) (xy 302.9374 -427.205903) (xy 302.881666 -427.203866) (xy 302.826823 -427.193736)
			(xy 302.774039 -427.175729) (xy 302.724439 -427.150228) (xy 302.679081 -427.117777) (xy 302.638932 -427.079068)
			(xy 302.604846 -427.034925) (xy 302.57755 -426.98629) (xy 302.557627 -426.934199) (xy 302.545501 -426.879762)
			(xy 302.54143 -426.82414) (xy 292.761665 -426.82414) (xy 292.813017 -426.836797) (xy 292.870486 -426.858592)
			(xy 292.924908 -426.887156) (xy 292.97549 -426.922073) (xy 293.021494 -426.962831) (xy 293.06225 -427.008839)
			(xy 293.097162 -427.059423) (xy 293.125722 -427.113847) (xy 293.147514 -427.171317) (xy 293.162219 -427.230995)
			(xy 293.169623 -427.292011) (xy 293.170102 -427.322742) (xy 293.169532 -427.357208) (xy 293.16548 -427.386961)
			(xy 294.004994 -427.386961) (xy 294.004994 -427.323039) (xy 294.013005 -427.259621) (xy 294.028902 -427.197707)
			(xy 294.052434 -427.138274) (xy 294.083228 -427.082259) (xy 294.120801 -427.030544) (xy 294.164558 -426.983947)
			(xy 294.213811 -426.943202) (xy 294.267782 -426.908951) (xy 294.325621 -426.881734) (xy 294.386414 -426.861981)
			(xy 294.449204 -426.850003) (xy 294.513 -426.84599) (xy 294.576796 -426.850003) (xy 294.639586 -426.861981)
			(xy 294.700379 -426.881734) (xy 294.758218 -426.908951) (xy 294.812189 -426.943202) (xy 294.861442 -426.983947)
			(xy 294.905199 -427.030544) (xy 294.942772 -427.082259) (xy 294.973566 -427.138274) (xy 294.997098 -427.197707)
			(xy 295.012995 -427.259621) (xy 295.021006 -427.323039) (xy 295.021508 -427.355) (xy 295.021006 -427.386961)
			(xy 295.01937 -427.399915) (xy 301.564796 -427.399915) (xy 301.564796 -427.335993) (xy 301.572807 -427.272575)
			(xy 301.588704 -427.210661) (xy 301.612236 -427.151228) (xy 301.64303 -427.095213) (xy 301.680603 -427.043498)
			(xy 301.72436 -426.996901) (xy 301.773613 -426.956156) (xy 301.827584 -426.921905) (xy 301.885423 -426.894688)
			(xy 301.946216 -426.874935) (xy 302.009006 -426.862957) (xy 302.072802 -426.858944) (xy 302.136598 -426.862957)
			(xy 302.199388 -426.874935) (xy 302.260181 -426.894688) (xy 302.31802 -426.921905) (xy 302.371991 -426.956156)
			(xy 302.421244 -426.996901) (xy 302.465001 -427.043498) (xy 302.502574 -427.095213) (xy 302.533368 -427.151228)
			(xy 302.5569 -427.210661) (xy 302.572797 -427.272575) (xy 302.580808 -427.335993) (xy 302.58131 -427.367954)
			(xy 302.580808 -427.399915) (xy 302.572797 -427.463333) (xy 302.5569 -427.525247) (xy 302.533368 -427.58468)
			(xy 302.502574 -427.640695) (xy 302.465001 -427.69241) (xy 302.421244 -427.739007) (xy 302.371991 -427.779752)
			(xy 302.31802 -427.814003) (xy 302.260181 -427.84122) (xy 302.199388 -427.860973) (xy 302.136598 -427.872951)
			(xy 302.072802 -427.876965) (xy 302.009006 -427.872951) (xy 301.946216 -427.860973) (xy 301.885423 -427.84122)
			(xy 301.827584 -427.814003) (xy 301.773613 -427.779752) (xy 301.72436 -427.739007) (xy 301.680603 -427.69241)
			(xy 301.64303 -427.640695) (xy 301.612236 -427.58468) (xy 301.588704 -427.525247) (xy 301.572807 -427.463333)
			(xy 301.564796 -427.399915) (xy 295.01937 -427.399915) (xy 295.012995 -427.450379) (xy 294.997098 -427.512293)
			(xy 294.973566 -427.571726) (xy 294.942772 -427.627741) (xy 294.905199 -427.679456) (xy 294.861442 -427.726053)
			(xy 294.812189 -427.766798) (xy 294.758218 -427.801049) (xy 294.700379 -427.828266) (xy 294.639586 -427.848019)
			(xy 294.576796 -427.859997) (xy 294.513 -427.864011) (xy 294.449204 -427.859997) (xy 294.386414 -427.848019)
			(xy 294.325621 -427.828266) (xy 294.267782 -427.801049) (xy 294.213811 -427.766798) (xy 294.164558 -427.726053)
			(xy 294.120801 -427.679456) (xy 294.083228 -427.627741) (xy 294.052434 -427.571726) (xy 294.028902 -427.512293)
			(xy 294.013005 -427.450379) (xy 294.004994 -427.386961) (xy 293.16548 -427.386961) (xy 293.16023 -427.425508)
			(xy 293.141788 -427.491927) (xy 293.114545 -427.555246) (xy 293.078999 -427.614305) (xy 293.057834 -427.641512)
			(xy 293.057326 -427.64202) (xy 293.054278 -427.64583) (xy 293.04869 -427.66361) (xy 293.049452 -427.673008)
			(xy 293.050362 -427.682245) (xy 293.057917 -427.699182) (xy 293.064184 -427.706028) (xy 293.448232 -428.090076)
			(xy 293.45398 -428.095277) (xy 293.467812 -428.102259) (xy 293.47541 -428.103792) (xy 293.483792 -428.104554)
			(xy 298.219368 -428.104554) (xy 298.221146 -428.104554) (xy 298.224448 -428.1043) (xy 298.233801 -428.103041)
			(xy 298.250651 -428.09457) (xy 298.257214 -428.08779) (xy 298.279505 -428.063845) (xy 298.329205 -428.021303)
			(xy 298.383955 -427.985492) (xy 298.442849 -427.957005) (xy 298.504912 -427.936314) (xy 298.569118 -427.923761)
			(xy 298.634404 -427.919553) (xy 298.69969 -427.923761) (xy 298.763896 -427.936314) (xy 298.825959 -427.957005)
			(xy 298.884853 -427.985492) (xy 298.939603 -428.021303) (xy 298.989303 -428.063845) (xy 299.011594 -428.08779)
			(xy 299.01823 -428.094477) (xy 299.035036 -428.102957) (xy 299.04436 -428.1043) (xy 299.04944 -428.104554)
			(xy 299.213524 -428.104554) (xy 299.224954 -428.10303) (xy 299.226986 -428.102522) (xy 299.22724 -428.102522)
			(xy 299.228764 -428.102014) (xy 299.242734 -428.098458) (xy 299.250608 -428.095156) (xy 299.260514 -428.089314)
			(xy 299.282118 -428.077523) (xy 299.327709 -428.058978) (xy 299.375306 -428.046447) (xy 299.424119 -428.040138)
			(xy 299.448728 -428.039784) (xy 299.474849 -428.040193) (xy 299.526606 -428.047284) (xy 299.576911 -428.061371)
			(xy 299.624825 -428.082189) (xy 299.647356 -428.09541) (xy 299.655738 -428.098712) (xy 299.670216 -428.102522)
			(xy 299.683932 -428.104554) (xy 304.98796 -428.104554) (xy 304.997612 -428.103538) (xy 305.004858 -428.101914)
			(xy 305.018032 -428.095077) (xy 305.02352 -428.090076) (xy 305.551078 -427.562518) (xy 305.556272 -427.556767)
			(xy 305.563242 -427.542933) (xy 305.564794 -427.53534) (xy 305.565556 -427.526958) (xy 305.565556 -425.56684)
			(xy 305.565107 -425.557054) (xy 305.55779 -425.5389) (xy 305.551332 -425.531534) (xy 305.513994 -425.492672)
			(xy 305.502056 -425.48048) (xy 305.498624 -425.477034) (xy 305.490691 -425.471412) (xy 305.486308 -425.469304)
			(xy 305.477926 -425.465748) (xy 305.467512 -425.46524) (xy 305.435249 -425.463627) (xy 305.371489 -425.453248)
			(xy 305.309558 -425.434877) (xy 305.250451 -425.408811) (xy 305.195121 -425.37547) (xy 305.14446 -425.33539)
			(xy 305.099282 -425.289216) (xy 305.060315 -425.237693) (xy 305.028187 -425.181651) (xy 305.003414 -425.12199)
			(xy 304.986397 -425.059673) (xy 304.977409 -424.995702) (xy 304.976595 -424.931109) (xy 304.983967 -424.866932)
			(xy 304.999407 -424.804205) (xy 305.022667 -424.743939) (xy 305.053372 -424.687104) (xy 305.091027 -424.634615)
			(xy 305.135027 -424.587317) (xy 305.184662 -424.545973) (xy 305.239133 -424.511247) (xy 305.268122 -424.496992)
			(xy 305.283362 -424.490134) (xy 305.28895 -424.487594) (xy 305.293776 -424.484038) (xy 305.302158 -424.476164)
			(xy 305.31689 -424.458384) (xy 305.317906 -424.457114) (xy 305.318668 -424.456098) (xy 305.321698 -424.451709)
			(xy 305.326062 -424.44198) (xy 305.327304 -424.436794) (xy 305.327558 -424.436032) (xy 305.341782 -424.365674)
			(xy 305.343457 -424.35477) (xy 305.338462 -424.333305) (xy 305.33213 -424.324272) (xy 305.32959 -424.321224)
			(xy 303.07661 -422.068244) (xy 303.069771 -422.060843) (xy 303.062055 -422.042245) (xy 303.061624 -422.032176)
			(xy 303.061624 -421.261032) (xy 303.061455 -421.255023) (xy 303.058629 -421.243342) (xy 303.056036 -421.237918)
			(xy 303.050702 -421.22725) (xy 303.028971 -421.21208) (xy 302.990191 -421.175965) (xy 302.957666 -421.134127)
			(xy 302.932229 -421.087637) (xy 302.914532 -421.037686) (xy 302.905027 -420.985552) (xy 302.903958 -420.93257)
			(xy 302.911352 -420.880095) (xy 302.92702 -420.829471) (xy 302.95056 -420.781993) (xy 302.981371 -420.738877)
			(xy 303.018663 -420.701226) (xy 303.03978 -420.685214) (xy 303.044352 -420.682166) (xy 303.052734 -420.673022)
			(xy 303.055782 -420.66718) (xy 303.058511 -420.661594) (xy 303.061459 -420.649519) (xy 303.061624 -420.643304)
			(xy 303.061624 -413.155384) (xy 303.061461 -413.149373) (xy 303.058645 -413.137687) (xy 303.056036 -413.13227)
			(xy 303.050702 -413.121602) (xy 303.028975 -413.106432) (xy 302.990202 -413.070318) (xy 302.957684 -413.028482)
			(xy 302.932255 -412.981996) (xy 302.914564 -412.932049) (xy 302.905064 -412.879921) (xy 302.904 -412.826945)
			(xy 302.911397 -412.774477) (xy 302.927067 -412.72386) (xy 302.950609 -412.676389) (xy 302.981419 -412.633281)
			(xy 303.01871 -412.595638) (xy 303.03978 -412.579566) (xy 303.044352 -412.576518) (xy 303.052734 -412.567374)
			(xy 303.055782 -412.561532) (xy 303.058517 -412.555947) (xy 303.061477 -412.543873) (xy 303.061624 -412.537656)
			(xy 303.061624 -411.667706) (xy 303.061203 -411.657635) (xy 303.053493 -411.639026) (xy 303.046638 -411.631638)
			(xy 303.009046 -411.594046) (xy 303.001647 -411.587203) (xy 302.983048 -411.579481) (xy 302.972978 -411.57906)
			(xy 301.673768 -411.57906) (xy 301.661524 -411.579791) (xy 301.639787 -411.591078) (xy 301.632112 -411.60065)
			(xy 301.577248 -411.679136) (xy 301.573946 -411.703774) (xy 301.578264 -411.715458) (xy 301.609582 -411.803046)
			(xy 301.665489 -411.980482) (xy 301.713611 -412.160186) (xy 301.753858 -412.341815) (xy 301.786152 -412.525026)
			(xy 301.810432 -412.70947) (xy 301.826652 -412.894797) (xy 301.834781 -413.080654) (xy 301.835312 -413.173672)
			(xy 301.835312 -413.174688) (xy 301.834818 -413.266523) (xy 301.826916 -413.450023) (xy 301.811127 -413.633013)
			(xy 301.78748 -413.815155) (xy 301.756018 -413.99611) (xy 301.716801 -414.175545) (xy 301.6699 -414.353126)
			(xy 301.615403 -414.528524) (xy 301.55341 -414.701416) (xy 301.484036 -414.871481) (xy 301.40741 -415.038404)
			(xy 301.323674 -415.201875) (xy 301.232982 -415.361593) (xy 301.135503 -415.517261) (xy 301.031417 -415.668591)
			(xy 300.920916 -415.815303) (xy 300.804206 -415.957125) (xy 300.681503 -416.093794) (xy 300.553033 -416.225058)
			(xy 300.419036 -416.350674) (xy 300.279757 -416.470408) (xy 300.135457 -416.58404) (xy 299.986402 -416.691358)
			(xy 299.832867 -416.792164) (xy 299.675138 -416.886271) (xy 299.513506 -416.973505) (xy 299.348271 -417.053705)
			(xy 299.179738 -417.126722) (xy 299.00822 -417.19242) (xy 298.834034 -417.250679) (xy 298.657503 -417.30139)
			(xy 298.478954 -417.344459) (xy 298.298718 -417.379806) (xy 298.117127 -417.407367) (xy 297.934519 -417.42709)
			(xy 297.751232 -417.438938) (xy 297.567604 -417.44289) (xy 297.383976 -417.438938) (xy 297.200689 -417.42709)
			(xy 297.018081 -417.407367) (xy 296.83649 -417.379806) (xy 296.656254 -417.344459) (xy 296.477705 -417.30139)
			(xy 296.301174 -417.250679) (xy 296.126988 -417.19242) (xy 295.95547 -417.126722) (xy 295.786937 -417.053705)
			(xy 295.621702 -416.973505) (xy 295.46007 -416.886271) (xy 295.302341 -416.792164) (xy 295.148806 -416.691358)
			(xy 294.999751 -416.58404) (xy 294.855451 -416.470408) (xy 294.716172 -416.350674) (xy 294.582175 -416.225058)
			(xy 294.453705 -416.093794) (xy 294.331002 -415.957125) (xy 294.214292 -415.815303) (xy 294.103791 -415.668591)
			(xy 293.999705 -415.517261) (xy 293.902226 -415.361593) (xy 293.811534 -415.201875) (xy 293.727798 -415.038404)
			(xy 293.651172 -414.871481) (xy 293.581798 -414.701416) (xy 293.519805 -414.528524) (xy 293.465308 -414.353126)
			(xy 293.418407 -414.175545) (xy 293.37919 -413.99611) (xy 293.347728 -413.815155) (xy 293.324081 -413.633013)
			(xy 293.308292 -413.450023) (xy 293.30039 -413.266523) (xy 293.299896 -413.174688) (xy 293.300379 -413.083702)
			(xy 293.308135 -412.901894) (xy 293.323634 -412.720583) (xy 293.346847 -412.540096) (xy 293.377732 -412.360763)
			(xy 293.416232 -412.18291) (xy 293.462278 -412.006859) (xy 293.515785 -411.832931) (xy 293.576658 -411.661441)
			(xy 293.644785 -411.492702) (xy 293.720041 -411.32702) (xy 293.802292 -411.164697) (xy 293.891386 -411.006026)
			(xy 293.987162 -410.851297) (xy 294.089447 -410.700791) (xy 294.198053 -410.554782) (xy 294.312784 -410.413534)
			(xy 294.433431 -410.277305) (xy 294.559775 -410.146342) (xy 294.691586 -410.020883) (xy 294.828625 -409.901156)
			(xy 294.970643 -409.78738) (xy 295.11738 -409.679759) (xy 295.268572 -409.578491) (xy 295.423943 -409.48376)
			(xy 295.58321 -409.395736) (xy 295.746084 -409.314581) (xy 295.828974 -409.277058) (xy 295.839926 -409.271343)
			(xy 295.855174 -409.251958) (xy 295.858184 -409.239974) (xy 295.873424 -409.157424) (xy 295.874917 -409.145195)
			(xy 295.867601 -409.121711) (xy 295.859454 -409.112466) (xy 295.720008 -408.97302) (xy 295.712585 -408.966239)
			(xy 295.693988 -408.958639) (xy 295.68394 -408.958288) (xy 295.677082 -408.958288) (xy 295.652492 -408.957829)
			(xy 295.603917 -408.95013) (xy 295.557146 -408.934924) (xy 295.513331 -408.912586) (xy 295.473552 -408.883666)
			(xy 295.455848 -408.866594) (xy 292.986206 -406.396698) (xy 292.978808 -406.389851) (xy 292.96021 -406.382114)
			(xy 292.950138 -406.381712) (xy 290.067238 -406.381712) (xy 290.06194 -406.381848) (xy 290.051568 -406.38402)
			(xy 290.046664 -406.38603) (xy 290.037012 -406.390348) (xy 290.0299 -406.398476) (xy 290.028884 -406.399492)
			(xy 290.027614 -406.401016) (xy 290.006878 -406.424361) (xy 289.960639 -406.466323) (xy 289.909608 -406.502304)
			(xy 289.854554 -406.531764) (xy 289.796305 -406.554257) (xy 289.73574 -406.569446) (xy 289.67377 -406.577101)
			(xy 289.64255 -406.577546) (xy 289.61182 -406.57708) (xy 289.550809 -406.569666) (xy 289.491136 -406.554954)
			(xy 289.433671 -406.533156) (xy 289.379253 -406.504592) (xy 289.328673 -406.469677) (xy 289.282671 -406.428921)
			(xy 289.241915 -406.382917) (xy 289.207002 -406.332337) (xy 289.178439 -406.277918) (xy 289.156643 -406.220452)
			(xy 289.141932 -406.160779) (xy 289.13452 -406.099768) (xy 289.134042 -406.069038) (xy 289.134546 -406.036326)
			(xy 289.142931 -405.971442) (xy 289.159568 -405.908169) (xy 289.184182 -405.847552) (xy 289.216366 -405.790593)
			(xy 289.255589 -405.73823) (xy 289.27806 -405.714454) (xy 289.284664 -405.707596) (xy 289.28822 -405.699214)
			(xy 289.290012 -405.694783) (xy 289.292054 -405.685446) (xy 289.292284 -405.680672) (xy 289.293554 -405.642064)
			(xy 289.293554 -405.641556) (xy 289.294316 -405.6126) (xy 289.294352 -405.607945) (xy 289.292951 -405.598742)
			(xy 289.291522 -405.594312) (xy 289.288474 -405.58593) (xy 289.28187 -405.578564) (xy 289.262534 -405.555429)
			(xy 289.228864 -405.505407) (xy 289.201345 -405.451755) (xy 289.180365 -405.395225) (xy 289.166217 -405.336611)
			(xy 289.159099 -405.276735) (xy 289.15868 -405.246586) (xy 289.15868 -405.246078) (xy 289.15868 -405.24557)
			(xy 289.159146 -405.21484) (xy 289.166557 -405.153828) (xy 289.181268 -405.094155) (xy 289.203065 -405.036689)
			(xy 289.231629 -404.98227) (xy 289.266543 -404.93169) (xy 289.3073 -404.885687) (xy 289.353304 -404.844932)
			(xy 289.403885 -404.810019) (xy 289.458306 -404.781457) (xy 289.515772 -404.759663) (xy 289.575446 -404.744954)
			(xy 289.636458 -404.737545) (xy 289.667188 -404.737062) (xy 289.698408 -404.737537) (xy 289.760377 -404.745185)
			(xy 289.820943 -404.760367) (xy 289.879193 -404.782854) (xy 289.934249 -404.812308) (xy 289.985282 -404.848285)
			(xy 290.031523 -404.890243) (xy 290.052252 -404.913592) (xy 290.053522 -404.915116) (xy 290.054538 -404.916132)
			(xy 290.058094 -404.919942) (xy 290.06673 -404.926546) (xy 290.071302 -404.928578) (xy 290.076199 -404.930615)
			(xy 290.086574 -404.932803) (xy 290.091876 -404.932896) (xy 291.921692 -404.932896) (xy 291.929886 -404.932588)
			(xy 291.945433 -404.927407) (xy 291.952172 -404.922736) (xy 291.95776 -404.91791) (xy 295.803828 -401.071842)
			(xy 295.821529 -401.054765) (xy 295.861304 -401.025835) (xy 295.905119 -401.003491) (xy 295.951892 -400.988285)
			(xy 296.00047 -400.980591) (xy 296.025062 -400.980148) (xy 300.291246 -400.980148) (xy 300.301148 -400.979637)
			(xy 300.319452 -400.972064) (xy 300.326806 -400.965416) (xy 301.261272 -400.03095) (xy 301.2684 -400.022983)
			(xy 301.276011 -400.003033) (xy 301.276004 -399.992342) (xy 301.27194 -399.91665) (xy 301.271538 -399.911369)
			(xy 301.268848 -399.901128) (xy 301.266606 -399.89633) (xy 301.26178 -399.886932) (xy 301.253144 -399.880074)
			(xy 301.234263 -399.86428) (xy 301.200935 -399.828055) (xy 301.173349 -399.787288) (xy 301.152115 -399.74288)
			(xy 301.137701 -399.695813) (xy 301.130428 -399.64713) (xy 301.129954 -399.622518) (xy 301.129954 -399.62074)
			(xy 301.131732 -399.586958) (xy 301.131732 -399.58645) (xy 301.133002 -399.577052) (xy 301.134526 -399.566892)
			(xy 301.131986 -399.55724) (xy 301.130514 -399.552304) (xy 301.125901 -399.543096) (xy 301.122842 -399.538952)
			(xy 301.077884 -399.482056) (xy 301.07162 -399.474878) (xy 301.055198 -399.465253) (xy 301.04588 -399.46326)
			(xy 301.043594 -399.463006) (xy 301.04334 -399.463006) (xy 301.013154 -399.459198) (xy 300.954085 -399.44462)
			(xy 300.897466 -399.422346) (xy 300.844297 -399.392769) (xy 300.795514 -399.356411) (xy 300.751976 -399.313912)
			(xy 300.714451 -399.26602) (xy 300.683599 -399.21358) (xy 300.659966 -399.157516) (xy 300.643966 -399.098815)
			(xy 300.635882 -399.038513) (xy 300.635416 -399.008092) (xy 300.635416 -399.007584) (xy 300.635975 -398.976461)
			(xy 300.644485 -398.914799) (xy 300.661276 -398.854861) (xy 300.68604 -398.797752) (xy 300.70171 -398.770856)
			(xy 300.70171 -398.770602) (xy 300.705012 -398.765268) (xy 300.7106 -398.756378) (xy 300.71441 -398.742408)
			(xy 300.716083 -398.73565) (xy 300.716081 -398.721734) (xy 300.71441 -398.714976) (xy 300.7106 -398.701006)
			(xy 300.705012 -398.692116) (xy 300.70171 -398.686782) (xy 300.70171 -398.686528) (xy 300.686026 -398.65964)
			(xy 300.661272 -398.602526) (xy 300.644483 -398.542586) (xy 300.635969 -398.480923) (xy 300.635416 -398.4498)
			(xy 300.635416 -398.449292) (xy 300.635906 -398.419324) (xy 300.643729 -398.359902) (xy 300.659242 -398.302009)
			(xy 300.682178 -398.246636) (xy 300.712145 -398.19473) (xy 300.748632 -398.14718) (xy 300.791012 -398.1048)
			(xy 300.838562 -398.068313) (xy 300.890468 -398.038346) (xy 300.945841 -398.01541) (xy 301.003734 -397.999897)
			(xy 301.063156 -397.992074) (xy 301.123092 -397.992074) (xy 301.182514 -397.999897) (xy 301.240407 -398.01541)
			(xy 301.29578 -398.038346) (xy 301.347686 -398.068313) (xy 301.395236 -398.1048) (xy 301.437616 -398.14718)
			(xy 301.474103 -398.19473) (xy 301.50407 -398.246636) (xy 301.527006 -398.302009) (xy 301.542519 -398.359902)
			(xy 301.550342 -398.419324) (xy 301.550832 -398.449292) (xy 301.550832 -398.4498) (xy 301.550274 -398.480923)
			(xy 301.541767 -398.542586) (xy 301.524979 -398.602527) (xy 301.500219 -398.659638) (xy 301.484538 -398.686528)
			(xy 301.484538 -398.686782) (xy 301.481236 -398.692116) (xy 301.475648 -398.701006) (xy 301.471838 -398.714976)
			(xy 301.470162 -398.721733) (xy 301.47016 -398.735651) (xy 301.471838 -398.742408) (xy 301.475648 -398.756378)
			(xy 301.481236 -398.765268) (xy 301.484538 -398.770602) (xy 301.484538 -398.770856) (xy 301.500225 -398.797743)
			(xy 301.524984 -398.854856) (xy 301.541776 -398.914797) (xy 301.550293 -398.97646) (xy 301.550832 -399.007584)
			(xy 301.550832 -399.008346) (xy 301.550358 -399.03756) (xy 301.542881 -399.095507) (xy 301.528069 -399.152026)
			(xy 301.517558 -399.179288) (xy 301.513748 -399.18894) (xy 301.513748 -399.198846) (xy 301.513974 -399.203887)
			(xy 301.516142 -399.21374) (xy 301.518066 -399.218404) (xy 301.547276 -399.28546) (xy 301.549496 -399.290148)
			(xy 301.555506 -399.298598) (xy 301.559214 -399.302224) (xy 301.56658 -399.309082) (xy 301.576486 -399.312638)
			(xy 301.603904 -399.323572) (xy 301.654646 -399.35372) (xy 301.699217 -399.39241) (xy 301.718218 -399.415)
			(xy 301.72152 -399.419318) (xy 301.730156 -399.426176) (xy 301.734474 -399.428462) (xy 301.739263 -399.430726)
			(xy 301.74951 -399.433409) (xy 301.754794 -399.433796) (xy 301.830486 -399.43786) (xy 301.841194 -399.437978)
			(xy 301.861184 -399.430347) (xy 301.869094 -399.423128) (xy 302.349662 -398.94256) (xy 302.367353 -398.925562)
			(xy 302.407047 -398.896736) (xy 302.450758 -398.874465) (xy 302.49741 -398.859295) (xy 302.54586 -398.851599)
			(xy 302.570388 -398.85112) (xy 303.040796 -398.85112) (xy 303.042066 -398.85112) (xy 303.053498 -398.850318)
			(xy 303.073877 -398.839883) (xy 303.081182 -398.831054) (xy 303.084992 -398.825212) (xy 303.126902 -398.751552)
			(xy 303.129969 -398.745597) (xy 303.13318 -398.732597) (xy 303.133252 -398.725898) (xy 303.133252 -398.712436)
			(xy 303.12614 -398.700498) (xy 303.112356 -398.676382) (xy 303.092762 -398.624411) (xy 303.082786 -398.569773)
			(xy 303.082198 -398.542002) (xy 303.082674 -398.517751) (xy 303.090261 -398.469847) (xy 303.105249 -398.42372)
			(xy 303.127268 -398.380504) (xy 303.155776 -398.341266) (xy 303.190072 -398.30697) (xy 303.22931 -398.278462)
			(xy 303.272526 -398.256443) (xy 303.318653 -398.241455) (xy 303.366557 -398.233868) (xy 303.415059 -398.233868)
			(xy 303.462963 -398.241455) (xy 303.50909 -398.256443) (xy 303.552306 -398.278462) (xy 303.591544 -398.30697)
			(xy 303.62584 -398.341266) (xy 303.654348 -398.380504) (xy 303.676367 -398.42372) (xy 303.691355 -398.469847)
			(xy 303.698942 -398.517751) (xy 303.699418 -398.542002) (xy 303.698782 -398.570307) (xy 303.68847 -398.625969)
			(xy 303.668192 -398.678822) (xy 303.653952 -398.703292) (xy 303.65319 -398.704562) (xy 303.650136 -398.71027)
			(xy 303.646661 -398.722735) (xy 303.646332 -398.7292) (xy 303.646332 -398.736566) (xy 303.696624 -398.825212)
			(xy 303.701346 -398.832851) (xy 303.715014 -398.844483) (xy 303.731848 -398.850709) (xy 303.74082 -398.85112)
			(xy 304.240946 -398.85112) (xy 304.242216 -398.85112) (xy 304.253643 -398.850308) (xy 304.274005 -398.83986)
			(xy 304.281332 -398.831054) (xy 304.285142 -398.825212) (xy 304.327052 -398.751552) (xy 304.330121 -398.745597)
			(xy 304.333336 -398.732597) (xy 304.333402 -398.725898) (xy 304.333402 -398.712436) (xy 304.32629 -398.700498)
			(xy 304.312508 -398.676381) (xy 304.292917 -398.62441) (xy 304.282943 -398.569772) (xy 304.282348 -398.542002)
			(xy 304.282824 -398.517751) (xy 304.290411 -398.469847) (xy 304.305399 -398.42372) (xy 304.327418 -398.380504)
			(xy 304.355926 -398.341266) (xy 304.390222 -398.30697) (xy 304.42946 -398.278462) (xy 304.472676 -398.256443)
			(xy 304.518803 -398.241455) (xy 304.566707 -398.233868) (xy 304.615209 -398.233868) (xy 304.663113 -398.241455)
			(xy 304.70924 -398.256443) (xy 304.752456 -398.278462) (xy 304.791694 -398.30697) (xy 304.82599 -398.341266)
			(xy 304.854498 -398.380504) (xy 304.876517 -398.42372) (xy 304.891505 -398.469847) (xy 304.899092 -398.517751)
			(xy 304.899568 -398.542002) (xy 304.898932 -398.570307) (xy 304.888619 -398.625968) (xy 304.868338 -398.678819)
			(xy 304.854102 -398.703292) (xy 304.85334 -398.704562) (xy 304.850283 -398.710269) (xy 304.846805 -398.722735)
			(xy 304.846482 -398.7292) (xy 304.846482 -398.736566) (xy 304.896774 -398.825212) (xy 304.901494 -398.832857)
			(xy 304.91516 -398.844502) (xy 304.931994 -398.850744) (xy 304.94097 -398.85112) (xy 305.13274 -398.85112)
			(xy 305.142744 -398.850626) (xy 305.161225 -398.84296) (xy 305.175371 -398.828809) (xy 305.183029 -398.810324)
			(xy 305.18354 -398.80032) (xy 305.18354 -398.109186) (xy 305.183113 -398.099118) (xy 305.175388 -398.080523)
			(xy 305.168554 -398.073118) (xy 305.150095 -398.054025) (xy 305.119203 -398.010832) (xy 305.095983 -397.963076)
			(xy 305.088036 -397.937736) (xy 305.086512 -397.931894) (xy 304.766218 -397.378174) (xy 304.762154 -397.373856)
			(xy 304.745963 -397.356148) (xy 304.718583 -397.316747) (xy 304.69749 -397.273651) (xy 304.683171 -397.227858)
			(xy 304.675956 -397.180423) (xy 304.67554 -397.156432) (xy 304.675626 -397.144384) (xy 304.677409 -397.120355)
			(xy 304.679096 -397.108426) (xy 304.680049 -397.099669) (xy 304.676678 -397.082393) (xy 304.672492 -397.074644)
			(xy 304.639726 -397.019272) (xy 304.635062 -397.01196) (xy 304.621812 -397.000791) (xy 304.613818 -396.997428)
			(xy 304.613564 -396.997428) (xy 304.591825 -396.989022) (xy 304.550982 -396.966567) (xy 304.514026 -396.938167)
			(xy 304.481816 -396.904481) (xy 304.455098 -396.86629) (xy 304.434495 -396.824484) (xy 304.420485 -396.780031)
			(xy 304.413392 -396.733966) (xy 304.412904 -396.710662) (xy 304.413486 -396.684291) (xy 304.422586 -396.63234)
			(xy 304.440459 -396.582718) (xy 304.453036 -396.559532) (xy 304.453036 -396.559278) (xy 304.457084 -396.551416)
			(xy 304.460079 -396.534002) (xy 304.458878 -396.525242) (xy 304.445162 -396.451582) (xy 304.435764 -396.436088)
			(xy 304.428906 -396.4305) (xy 304.406719 -396.411814) (xy 304.366771 -396.369753) (xy 304.332457 -396.322982)
			(xy 304.304326 -396.272251) (xy 304.282827 -396.218374) (xy 304.268307 -396.162212) (xy 304.260997 -396.104666)
			(xy 304.260504 -396.075662) (xy 304.260504 -396.075408) (xy 304.261103 -396.042087) (xy 304.270763 -395.976148)
			(xy 304.289879 -395.912307) (xy 304.30343 -395.88186) (xy 304.307617 -395.871423) (xy 304.30748 -395.848965)
			(xy 304.297795 -395.8287) (xy 304.28946 -395.821154) (xy 304.267217 -395.802478) (xy 304.227161 -395.76042)
			(xy 304.192747 -395.713633) (xy 304.16453 -395.662867) (xy 304.142961 -395.60894) (xy 304.128388 -395.552717)
			(xy 304.121045 -395.495102) (xy 304.12055 -395.466062) (xy 304.12055 -395.465808) (xy 304.120991 -395.436909)
			(xy 304.128269 -395.37957) (xy 304.142711 -395.323604) (xy 304.164086 -395.269903) (xy 304.192054 -395.219322)
			(xy 304.226169 -395.172665) (xy 304.265889 -395.130677) (xy 304.287936 -395.111986) (xy 304.29492 -395.105651)
			(xy 304.304169 -395.089238) (xy 304.30597 -395.079982) (xy 304.310542 -395.048994) (xy 304.311438 -395.039821)
			(xy 304.307399 -395.021852) (xy 304.302668 -395.013942) (xy 304.286419 -394.988089) (xy 304.262646 -394.931851)
			(xy 304.255424 -394.902182) (xy 304.253331 -394.893935) (xy 304.244497 -394.879405) (xy 304.238152 -394.873734)
			(xy 304.200814 -394.843) (xy 304.191162 -394.843) (xy 304.161196 -394.842508) (xy 304.101778 -394.83468)
			(xy 304.043889 -394.819165) (xy 303.988521 -394.796226) (xy 303.93662 -394.766257) (xy 303.889075 -394.72977)
			(xy 303.846699 -394.68739) (xy 303.810217 -394.639841) (xy 303.780254 -394.587938) (xy 303.757321 -394.532567)
			(xy 303.741811 -394.474677) (xy 303.733989 -394.415258) (xy 303.733454 -394.385292) (xy 303.73397 -394.354228)
			(xy 303.742375 -394.292672) (xy 303.750218 -394.26261) (xy 303.753012 -394.252704) (xy 303.750472 -394.232384)
			(xy 303.708308 -394.159486) (xy 303.702792 -394.15099) (xy 303.686711 -394.138707) (xy 303.677066 -394.13561)
			(xy 303.676812 -394.13561) (xy 303.665089 -394.13247) (xy 303.641962 -394.125101) (xy 303.630584 -394.120878)
			(xy 303.618138 -394.116306) (xy 303.59223 -394.120116) (xy 303.502822 -394.188696) (xy 303.492408 -394.212826)
			(xy 303.493678 -394.22578) (xy 303.495202 -394.25753) (xy 303.495202 -394.257784) (xy 303.494756 -394.281413)
			(xy 303.487992 -394.328186) (xy 303.474656 -394.373525) (xy 303.46523 -394.395198) (xy 303.461376 -394.404536)
			(xy 303.460585 -394.424707) (xy 303.463706 -394.434314) (xy 303.492408 -394.511276) (xy 303.506124 -394.526008)
			(xy 303.515522 -394.530072) (xy 303.539893 -394.541764) (xy 303.584781 -394.571872) (xy 303.624173 -394.608882)
			(xy 303.657019 -394.651807) (xy 303.682445 -394.699504) (xy 303.699772 -394.750702) (xy 303.708539 -394.804037)
			(xy 303.70907 -394.831062) (xy 303.70907 -394.831316) (xy 303.708606 -394.855514) (xy 303.701516 -394.90339)
			(xy 303.687532 -394.949723) (xy 303.666954 -394.993528) (xy 303.653952 -395.013942) (xy 303.649215 -395.02185)
			(xy 303.645174 -395.039821) (xy 303.646078 -395.048994) (xy 303.65065 -395.079982) (xy 303.652339 -395.089278)
			(xy 303.661605 -395.105729) (xy 303.668684 -395.111986) (xy 303.69076 -395.130671) (xy 303.730496 -395.172697)
			(xy 303.764621 -395.219393) (xy 303.792594 -395.270015) (xy 303.813967 -395.323758) (xy 303.828401 -395.379765)
			(xy 303.835665 -395.437143) (xy 303.83607 -395.466062) (xy 303.835484 -395.499425) (xy 303.825833 -395.56545)
			(xy 303.806701 -395.629374) (xy 303.793144 -395.659864) (xy 303.788964 -395.6703) (xy 303.78911 -395.692752)
			(xy 303.798794 -395.713009) (xy 303.807114 -395.72057) (xy 303.829362 -395.739244) (xy 303.869427 -395.781299)
			(xy 303.90385 -395.828085) (xy 303.932078 -395.878849) (xy 303.953657 -395.932777) (xy 303.96824 -395.989002)
			(xy 303.975593 -396.04662) (xy 303.976024 -396.075662) (xy 303.975573 -396.104666) (xy 303.968243 -396.162209)
			(xy 303.953707 -396.218367) (xy 303.932198 -396.27224) (xy 303.90406 -396.322967) (xy 303.869743 -396.369736)
			(xy 303.829797 -396.411799) (xy 303.807622 -396.4305) (xy 303.800764 -396.436088) (xy 303.791366 -396.451582)
			(xy 303.77765 -396.525242) (xy 303.776482 -396.534001) (xy 303.779481 -396.551403) (xy 303.783492 -396.559278)
			(xy 303.783492 -396.559532) (xy 303.796086 -396.58271) (xy 303.813973 -396.632331) (xy 303.823055 -396.684289)
			(xy 303.823624 -396.710662) (xy 303.823552 -396.72002) (xy 303.822406 -396.738702) (xy 303.821338 -396.748)
			(xy 303.820322 -396.756636) (xy 303.824132 -396.773908) (xy 303.86782 -396.84325) (xy 303.88179 -396.853918)
			(xy 303.890172 -396.856712) (xy 303.914204 -396.865169) (xy 303.959379 -396.888721) (xy 304.000184 -396.919221)
			(xy 304.035561 -396.955879) (xy 304.064592 -396.997743) (xy 304.086523 -397.043726) (xy 304.094134 -397.06804)
			(xy 304.095658 -397.073882) (xy 304.415952 -397.627602) (xy 304.420016 -397.63192) (xy 304.436232 -397.649619)
			(xy 304.463664 -397.689008) (xy 304.48481 -397.732099) (xy 304.499182 -397.777897) (xy 304.506449 -397.825344)
			(xy 304.506884 -397.849344) (xy 304.506396 -397.874119) (xy 304.498642 -397.923059) (xy 304.483333 -397.970185)
			(xy 304.460845 -398.014339) (xy 304.43173 -398.054433) (xy 304.396705 -398.089483) (xy 304.356632 -398.118627)
			(xy 304.312494 -398.141147) (xy 304.265379 -398.156489) (xy 304.216445 -398.164278) (xy 304.19167 -398.164812)
			(xy 304.191162 -398.164812) (xy 304.16577 -398.164301) (xy 304.115642 -398.156166) (xy 304.067462 -398.140111)
			(xy 304.022474 -398.116551) (xy 303.981837 -398.086093) (xy 303.9466 -398.049523) (xy 303.917671 -398.007784)
			(xy 303.895797 -397.961952) (xy 303.88814 -397.937736) (xy 303.886616 -397.931894) (xy 303.566322 -397.378174)
			(xy 303.562258 -397.373856) (xy 303.546071 -397.356146) (xy 303.518699 -397.316742) (xy 303.497613 -397.273646)
			(xy 303.483298 -397.227854) (xy 303.476086 -397.180421) (xy 303.475644 -397.156432) (xy 303.47573 -397.144384)
			(xy 303.477513 -397.120355) (xy 303.4792 -397.108426) (xy 303.480153 -397.099669) (xy 303.476782 -397.082393)
			(xy 303.472596 -397.074644) (xy 303.43983 -397.019272) (xy 303.435166 -397.01196) (xy 303.421917 -397.00079)
			(xy 303.413922 -396.997428) (xy 303.413668 -396.997428) (xy 303.391928 -396.989022) (xy 303.351085 -396.966568)
			(xy 303.314129 -396.938168) (xy 303.281918 -396.904481) (xy 303.2552 -396.866291) (xy 303.234597 -396.824484)
			(xy 303.220586 -396.780032) (xy 303.213494 -396.733966) (xy 303.213008 -396.710662) (xy 303.21359 -396.684291)
			(xy 303.22269 -396.63234) (xy 303.240563 -396.582718) (xy 303.25314 -396.559532) (xy 303.25314 -396.559278)
			(xy 303.257188 -396.551416) (xy 303.260182 -396.534002) (xy 303.258982 -396.525242) (xy 303.245266 -396.451582)
			(xy 303.235868 -396.436088) (xy 303.22901 -396.4305) (xy 303.206822 -396.411814) (xy 303.166875 -396.369753)
			(xy 303.13256 -396.322982) (xy 303.104428 -396.272252) (xy 303.08293 -396.218374) (xy 303.06841 -396.162212)
			(xy 303.061099 -396.104666) (xy 303.060608 -396.075662) (xy 303.060608 -396.075408) (xy 303.061207 -396.042087)
			(xy 303.070867 -395.976148) (xy 303.089983 -395.912307) (xy 303.103534 -395.88186) (xy 303.10772 -395.871423)
			(xy 303.107584 -395.848964) (xy 303.0979 -395.8287) (xy 303.089564 -395.821154) (xy 303.06732 -395.802478)
			(xy 303.027264 -395.760421) (xy 302.992851 -395.713633) (xy 302.964633 -395.662867) (xy 302.943064 -395.60894)
			(xy 302.928491 -395.552717) (xy 302.921148 -395.495102) (xy 302.920654 -395.466062) (xy 302.920654 -395.465808)
			(xy 302.921095 -395.436909) (xy 302.928373 -395.37957) (xy 302.942815 -395.323605) (xy 302.96419 -395.269904)
			(xy 302.992158 -395.219322) (xy 303.026274 -395.172666) (xy 303.065994 -395.130678) (xy 303.08804 -395.111986)
			(xy 303.095035 -395.105657) (xy 303.104301 -395.089245) (xy 303.106074 -395.079982) (xy 303.110646 -395.048994)
			(xy 303.111542 -395.039821) (xy 303.107503 -395.021852) (xy 303.102772 -395.013942) (xy 303.089724 -394.993517)
			(xy 303.069109 -394.949653) (xy 303.055126 -394.903247) (xy 303.048076 -394.855296) (xy 303.047654 -394.831062)
			(xy 303.048085 -394.80739) (xy 303.05484 -394.760531) (xy 303.068191 -394.715109) (xy 303.077626 -394.693394)
			(xy 303.081475 -394.684055) (xy 303.082263 -394.663887) (xy 303.07915 -394.654278) (xy 303.050448 -394.577316)
			(xy 303.036732 -394.562584) (xy 303.027334 -394.55852) (xy 303.002966 -394.546826) (xy 302.958084 -394.516714)
			(xy 302.918698 -394.479703) (xy 302.885857 -394.436777) (xy 302.860437 -394.389081) (xy 302.843114 -394.337886)
			(xy 302.834349 -394.284554) (xy 302.833786 -394.25753) (xy 302.834267 -394.231539) (xy 302.842394 -394.180196)
			(xy 302.858454 -394.130758) (xy 302.88205 -394.08444) (xy 302.912602 -394.042384) (xy 302.949356 -394.005625)
			(xy 302.991409 -393.975069) (xy 303.037724 -393.951468) (xy 303.087161 -393.935403) (xy 303.138503 -393.92727)
			(xy 303.164494 -393.926822) (xy 303.180927 -393.927048) (xy 303.213628 -393.930352) (xy 303.229772 -393.933426)
			(xy 303.238279 -393.934774) (xy 303.255322 -393.932367) (xy 303.27062 -393.924477) (xy 303.276762 -393.91844)
			(xy 303.345088 -393.846304) (xy 303.351692 -393.820904) (xy 303.34839 -393.808204) (xy 303.341416 -393.779756)
			(xy 303.333903 -393.721666) (xy 303.333404 -393.69238) (xy 303.333912 -393.661492) (xy 303.342223 -393.600277)
			(xy 303.35869 -393.540735) (xy 303.383014 -393.483949) (xy 303.398428 -393.457176) (xy 303.40378 -393.44724)
			(xy 303.406167 -393.424827) (xy 303.403 -393.413996) (xy 303.377092 -393.340336) (xy 303.372818 -393.329989)
			(xy 303.35714 -393.314047) (xy 303.346866 -393.309602) (xy 303.323496 -393.300402) (xy 303.279621 -393.275963)
			(xy 303.239944 -393.245173) (xy 303.205377 -393.208738) (xy 303.176715 -393.167497) (xy 303.154617 -393.122398)
			(xy 303.13959 -393.074476) (xy 303.131979 -393.024833) (xy 303.131474 -392.999722) (xy 303.131984 -392.973735)
			(xy 303.140114 -392.9224) (xy 303.156175 -392.87297) (xy 303.179771 -392.82666) (xy 303.210321 -392.784612)
			(xy 303.247072 -392.747861) (xy 303.28912 -392.717311) (xy 303.33543 -392.693715) (xy 303.38486 -392.677654)
			(xy 303.436195 -392.669524) (xy 303.488169 -392.669524) (xy 303.539504 -392.677654) (xy 303.588934 -392.693715)
			(xy 303.635244 -392.717311) (xy 303.677292 -392.747861) (xy 303.714043 -392.784612) (xy 303.744593 -392.82666)
			(xy 303.768189 -392.87297) (xy 303.78425 -392.9224) (xy 303.79238 -392.973735) (xy 303.79289 -392.999722)
			(xy 303.79289 -393.00023) (xy 303.792334 -393.027205) (xy 303.783521 -393.08043) (xy 303.775364 -393.106148)
			(xy 303.771554 -393.11707) (xy 303.774094 -393.139422) (xy 303.82083 -393.215876) (xy 303.827161 -393.225036)
			(xy 303.845732 -393.237277) (xy 303.856644 -393.239498) (xy 303.856898 -393.239498) (xy 303.886205 -393.244238)
			(xy 303.943358 -393.260308) (xy 303.997954 -393.283632) (xy 304.049076 -393.313818) (xy 304.095866 -393.35036)
			(xy 304.13754 -393.392644) (xy 304.173397 -393.439962) (xy 304.202836 -393.491517) (xy 304.225363 -393.546447)
			(xy 304.2406 -393.603827) (xy 304.248291 -393.662696) (xy 304.24882 -393.69238) (xy 304.248299 -393.723443)
			(xy 304.239884 -393.784997) (xy 304.232056 -393.815062) (xy 304.229262 -393.824968) (xy 304.231802 -393.845288)
			(xy 304.273966 -393.918186) (xy 304.279478 -393.926688) (xy 304.295555 -393.938986) (xy 304.305208 -393.942062)
			(xy 304.305462 -393.942062) (xy 304.33457 -393.950067) (xy 304.390538 -393.972695) (xy 304.443045 -394.002486)
			(xy 304.491179 -394.038921) (xy 304.534104 -394.08137) (xy 304.571075 -394.129093) (xy 304.601451 -394.181264)
			(xy 304.624704 -394.236975) (xy 304.640429 -394.295261) (xy 304.648355 -394.355107) (xy 304.64887 -394.385292)
			(xy 304.648746 -394.399427) (xy 304.646965 -394.427641) (xy 304.645314 -394.44168) (xy 304.644578 -394.450285)
			(xy 304.648218 -394.467157) (xy 304.652426 -394.4747) (xy 304.668428 -394.5001) (xy 304.673071 -394.507145)
			(xy 304.68605 -394.517911) (xy 304.693828 -394.521182) (xy 304.717186 -394.53039) (xy 304.761035 -394.554841)
			(xy 304.800683 -394.58564) (xy 304.83522 -394.622079) (xy 304.863851 -394.66332) (xy 304.885918 -394.708416)
			(xy 304.900915 -394.756329) (xy 304.908495 -394.805959) (xy 304.908966 -394.831062) (xy 304.908966 -394.831316)
			(xy 304.908502 -394.855514) (xy 304.901411 -394.90339) (xy 304.887428 -394.949723) (xy 304.866849 -394.993528)
			(xy 304.853848 -395.013942) (xy 304.849112 -395.02185) (xy 304.845071 -395.039821) (xy 304.845974 -395.048994)
			(xy 304.850546 -395.079982) (xy 304.852235 -395.089278) (xy 304.8615 -395.105729) (xy 304.86858 -395.111986)
			(xy 304.890656 -395.130671) (xy 304.930392 -395.172696) (xy 304.964518 -395.219392) (xy 304.992491 -395.270015)
			(xy 305.013864 -395.323758) (xy 305.028298 -395.379765) (xy 305.035563 -395.437143) (xy 305.035966 -395.466062)
			(xy 305.035362 -395.499382) (xy 305.025692 -395.565317) (xy 305.006567 -395.629153) (xy 304.99304 -395.65961)
			(xy 304.988779 -395.670079) (xy 304.988854 -395.692654) (xy 304.998605 -395.713014) (xy 305.00701 -395.72057)
			(xy 305.0159 -395.727936) (xy 305.02733 -395.737588) (xy 305.05654 -395.741652) (xy 305.154076 -395.696948)
			(xy 305.162705 -395.692513) (xy 305.176042 -395.678443) (xy 305.18317 -395.660415) (xy 305.18354 -395.65072)
			(xy 305.18354 -394.823188) (xy 305.183168 -394.8144) (xy 305.177212 -394.797863) (xy 305.166008 -394.78432)
			(xy 305.158648 -394.7795) (xy 305.13329 -394.764019) (xy 305.086428 -394.727497) (xy 305.04469 -394.685215)
			(xy 305.008779 -394.637884) (xy 304.9793 -394.586302) (xy 304.956748 -394.531336) (xy 304.941504 -394.473912)
			(xy 304.933824 -394.414998) (xy 304.93335 -394.385292) (xy 304.933866 -394.354228) (xy 304.942271 -394.292672)
			(xy 304.950114 -394.26261) (xy 304.952908 -394.252704) (xy 304.950368 -394.232384) (xy 304.908204 -394.159486)
			(xy 304.902688 -394.150991) (xy 304.886606 -394.138708) (xy 304.876962 -394.13561) (xy 304.876708 -394.13561)
			(xy 304.847599 -394.127605) (xy 304.79163 -394.104975) (xy 304.739121 -394.075184) (xy 304.690985 -394.038749)
			(xy 304.648056 -393.996301) (xy 304.61108 -393.948578) (xy 304.580699 -393.896409) (xy 304.55744 -393.840698)
			(xy 304.541707 -393.782413) (xy 304.533773 -393.722566) (xy 304.5333 -393.69238) (xy 304.533808 -393.661492)
			(xy 304.542119 -393.600277) (xy 304.558586 -393.540735) (xy 304.58291 -393.483949) (xy 304.598324 -393.457176)
			(xy 304.603676 -393.44724) (xy 304.606064 -393.424826) (xy 304.602896 -393.413996) (xy 304.576988 -393.340336)
			(xy 304.572714 -393.32999) (xy 304.557036 -393.314048) (xy 304.546762 -393.309602) (xy 304.523392 -393.300402)
			(xy 304.479517 -393.275963) (xy 304.439841 -393.245172) (xy 304.405274 -393.208738) (xy 304.376613 -393.167497)
			(xy 304.354515 -393.122397) (xy 304.339488 -393.074476) (xy 304.331878 -393.024833) (xy 304.33137 -392.999722)
			(xy 304.33188 -392.973735) (xy 304.34001 -392.9224) (xy 304.356071 -392.87297) (xy 304.379667 -392.82666)
			(xy 304.410217 -392.784612) (xy 304.446968 -392.747861) (xy 304.489016 -392.717311) (xy 304.535326 -392.693715)
			(xy 304.584756 -392.677654) (xy 304.636091 -392.669524) (xy 304.688065 -392.669524) (xy 304.7394 -392.677654)
			(xy 304.78883 -392.693715) (xy 304.83514 -392.717311) (xy 304.877188 -392.747861) (xy 304.913939 -392.784612)
			(xy 304.944489 -392.82666) (xy 304.968085 -392.87297) (xy 304.984146 -392.9224) (xy 304.992276 -392.973735)
			(xy 304.992786 -392.999722) (xy 304.992786 -393.00023) (xy 304.99223 -393.027205) (xy 304.983417 -393.08043)
			(xy 304.97526 -393.106148) (xy 304.97145 -393.11707) (xy 304.97399 -393.139422) (xy 305.020726 -393.215876)
			(xy 305.027057 -393.225036) (xy 305.045628 -393.237279) (xy 305.05654 -393.239498) (xy 305.056794 -393.239498)
			(xy 305.086102 -393.244238) (xy 305.143255 -393.260307) (xy 305.197851 -393.283631) (xy 305.248973 -393.313817)
			(xy 305.295764 -393.350359) (xy 305.337438 -393.392643) (xy 305.373296 -393.439961) (xy 305.402735 -393.491517)
			(xy 305.425263 -393.546446) (xy 305.440499 -393.603827) (xy 305.44819 -393.662696) (xy 305.448716 -393.69238)
			(xy 305.448195 -393.723443) (xy 305.43978 -393.784997) (xy 305.431952 -393.815062) (xy 305.429158 -393.824968)
			(xy 305.431698 -393.845288) (xy 305.473862 -393.918186) (xy 305.479373 -393.926689) (xy 305.49545 -393.938987)
			(xy 305.505104 -393.942062) (xy 305.505358 -393.942062) (xy 305.534528 -393.950087) (xy 305.590611 -393.972777)
			(xy 305.643218 -394.002655) (xy 305.691434 -394.039199) (xy 305.734417 -394.081774) (xy 305.77142 -394.129638)
			(xy 305.801798 -394.181957) (xy 305.825023 -394.237822) (xy 305.833272 -394.266928) (xy 305.83759 -394.283438)
			(xy 305.865022 -394.30452) (xy 306.11699 -394.30452) (xy 306.144422 -394.283438) (xy 306.14874 -394.266928)
			(xy 306.15001 -394.262356) (xy 306.152804 -394.25245) (xy 306.150264 -394.23213) (xy 306.108354 -394.159486)
			(xy 306.102854 -394.150899) (xy 306.086609 -394.138598) (xy 306.076858 -394.13561) (xy 306.047747 -394.127607)
			(xy 305.991772 -394.104982) (xy 305.939258 -394.075194) (xy 305.891117 -394.03876) (xy 305.848183 -393.996313)
			(xy 305.811202 -393.94859) (xy 305.780818 -393.896419) (xy 305.757556 -393.840706) (xy 305.74182 -393.782418)
			(xy 305.733885 -393.722567) (xy 305.73345 -393.69238) (xy 305.733958 -393.661492) (xy 305.742268 -393.600276)
			(xy 305.758733 -393.540734) (xy 305.783055 -393.483946) (xy 305.798474 -393.457176) (xy 305.80383 -393.447241)
			(xy 305.80622 -393.424826) (xy 305.803046 -393.413996) (xy 305.777138 -393.340336) (xy 305.772868 -393.329985)
			(xy 305.757195 -393.31403) (xy 305.746912 -393.309602) (xy 305.72354 -393.300404) (xy 305.679659 -393.275969)
			(xy 305.639976 -393.245181) (xy 305.605405 -393.208747) (xy 305.576738 -393.167506) (xy 305.554637 -393.122404)
			(xy 305.539607 -393.07448) (xy 305.531996 -393.024835) (xy 305.53152 -392.999722) (xy 305.53203 -392.973735)
			(xy 305.54016 -392.9224) (xy 305.556221 -392.87297) (xy 305.579817 -392.82666) (xy 305.610367 -392.784612)
			(xy 305.647118 -392.747861) (xy 305.689166 -392.717311) (xy 305.735476 -392.693715) (xy 305.784906 -392.677654)
			(xy 305.836241 -392.669524) (xy 305.888215 -392.669524) (xy 305.93955 -392.677654) (xy 305.98898 -392.693715)
			(xy 306.03529 -392.717311) (xy 306.077338 -392.747861) (xy 306.114089 -392.784612) (xy 306.144639 -392.82666)
			(xy 306.168235 -392.87297) (xy 306.184296 -392.9224) (xy 306.192426 -392.973735) (xy 306.192936 -392.999722)
			(xy 306.192936 -393.00023) (xy 306.19238 -393.027205) (xy 306.183569 -393.08043) (xy 306.17541 -393.106148)
			(xy 306.1716 -393.11707) (xy 306.17414 -393.139422) (xy 306.220876 -393.215876) (xy 306.227203 -393.225043)
			(xy 306.245771 -393.237303) (xy 306.25669 -393.239498) (xy 306.256944 -393.239498) (xy 306.286254 -393.244235)
			(xy 306.343412 -393.2603) (xy 306.398013 -393.28362) (xy 306.449141 -393.313804) (xy 306.495937 -393.350345)
			(xy 306.537616 -393.392629) (xy 306.573479 -393.439948) (xy 306.602922 -393.491506) (xy 306.625452 -393.546437)
			(xy 306.640691 -393.603821) (xy 306.648383 -393.662694) (xy 306.648866 -393.69238) (xy 306.648345 -393.723443)
			(xy 306.639929 -393.784997) (xy 306.632102 -393.815062) (xy 306.629308 -393.824968) (xy 306.631848 -393.845288)
			(xy 306.674266 -393.91844) (xy 306.679729 -393.926943) (xy 306.695838 -393.939121) (xy 306.705508 -393.942062)
			(xy 306.734663 -393.950096) (xy 306.790714 -393.972801) (xy 306.843288 -394.002688) (xy 306.891469 -394.039237)
			(xy 306.934418 -394.081812) (xy 306.971388 -394.129671) (xy 307.001734 -394.181981) (xy 307.024929 -394.237831)
			(xy 307.033168 -394.266928) (xy 307.037486 -394.283438) (xy 307.064918 -394.30452) (xy 307.31714 -394.30452)
			(xy 307.344572 -394.283438) (xy 307.34889 -394.266928) (xy 307.35016 -394.26261) (xy 307.352954 -394.252704)
			(xy 307.350414 -394.232384) (xy 307.30825 -394.159486) (xy 307.30273 -394.150996) (xy 307.286644 -394.13873)
			(xy 307.277008 -394.13561) (xy 307.276754 -394.13561) (xy 307.247643 -394.127607) (xy 307.191669 -394.104981)
			(xy 307.139155 -394.075193) (xy 307.091014 -394.038759) (xy 307.048081 -393.996312) (xy 307.011101 -393.948589)
			(xy 306.980716 -393.896418) (xy 306.957454 -393.840705) (xy 306.941719 -393.782417) (xy 306.933784 -393.722567)
			(xy 306.933346 -393.69238) (xy 306.933854 -393.661492) (xy 306.942164 -393.600276) (xy 306.958629 -393.540734)
			(xy 306.982951 -393.483946) (xy 306.99837 -393.457176) (xy 307.003727 -393.447241) (xy 307.006117 -393.424825)
			(xy 307.002942 -393.413996) (xy 306.977034 -393.340336) (xy 306.972763 -393.329986) (xy 306.95709 -393.314031)
			(xy 306.946808 -393.309602) (xy 306.923436 -393.300404) (xy 306.879555 -393.275969) (xy 306.839873 -393.24518)
			(xy 306.805302 -393.208746) (xy 306.776636 -393.167505) (xy 306.754535 -393.122404) (xy 306.739506 -393.07448)
			(xy 306.731894 -393.024835) (xy 306.731416 -392.999722) (xy 306.731926 -392.973735) (xy 306.740056 -392.9224)
			(xy 306.756117 -392.87297) (xy 306.779713 -392.82666) (xy 306.810263 -392.784612) (xy 306.847014 -392.747861)
			(xy 306.889062 -392.717311) (xy 306.935372 -392.693715) (xy 306.984802 -392.677654) (xy 307.036137 -392.669524)
			(xy 307.088111 -392.669524) (xy 307.139446 -392.677654) (xy 307.188876 -392.693715) (xy 307.235186 -392.717311)
			(xy 307.277234 -392.747861) (xy 307.313985 -392.784612) (xy 307.344535 -392.82666) (xy 307.368131 -392.87297)
			(xy 307.384192 -392.9224) (xy 307.392322 -392.973735) (xy 307.392832 -392.999722) (xy 307.392832 -393.00023)
			(xy 307.392276 -393.027205) (xy 307.383464 -393.08043) (xy 307.375306 -393.106148) (xy 307.371496 -393.11707)
			(xy 307.374036 -393.139422) (xy 307.420772 -393.215876) (xy 307.427099 -393.225044) (xy 307.445666 -393.237305)
			(xy 307.456586 -393.239498) (xy 307.45684 -393.239498) (xy 307.48615 -393.244235) (xy 307.543308 -393.260299)
			(xy 307.59791 -393.283619) (xy 307.649038 -393.313803) (xy 307.695835 -393.350344) (xy 307.737515 -393.392628)
			(xy 307.773377 -393.439947) (xy 307.802821 -393.491505) (xy 307.825351 -393.546437) (xy 307.84059 -393.603821)
			(xy 307.848282 -393.662694) (xy 307.848762 -393.69238) (xy 307.848242 -393.723443) (xy 307.839827 -393.784997)
			(xy 307.831998 -393.815062) (xy 307.829204 -393.824968) (xy 307.831744 -393.845288) (xy 307.873908 -393.918186)
			(xy 307.879423 -393.926683) (xy 307.895503 -393.938969) (xy 307.90515 -393.942062) (xy 307.905404 -393.942062)
			(xy 307.934572 -393.950089) (xy 307.990651 -393.972784) (xy 308.043253 -394.002664) (xy 308.091464 -394.03921)
			(xy 308.134443 -394.081786) (xy 308.171442 -394.12965) (xy 308.201816 -394.181969) (xy 308.225038 -394.237831)
			(xy 308.233318 -394.266928) (xy 308.237636 -394.283438) (xy 308.265068 -394.30452) (xy 308.517036 -394.30452)
			(xy 308.544468 -394.283438) (xy 308.548786 -394.266928) (xy 308.550056 -394.26261) (xy 308.55285 -394.252704)
			(xy 308.55031 -394.232384) (xy 308.508146 -394.159486) (xy 308.502632 -394.150986) (xy 308.486555 -394.138692)
			(xy 308.476904 -394.13561) (xy 308.47665 -394.13561) (xy 308.447539 -394.127607) (xy 308.391566 -394.104981)
			(xy 308.339052 -394.075192) (xy 308.290911 -394.038758) (xy 308.247978 -393.996311) (xy 308.210999 -393.948588)
			(xy 308.180615 -393.896417) (xy 308.157353 -393.840704) (xy 308.141618 -393.782417) (xy 308.133683 -393.722567)
			(xy 308.133242 -393.69238) (xy 308.133242 -393.691872) (xy 308.133768 -393.661016) (xy 308.142098 -393.599868)
			(xy 308.158562 -393.540391) (xy 308.182863 -393.483664) (xy 308.198266 -393.456922) (xy 308.204108 -393.44727)
			(xy 308.206648 -393.424918) (xy 308.17693 -393.340336) (xy 308.172659 -393.329986) (xy 308.156985 -393.314033)
			(xy 308.146704 -393.309602) (xy 308.123345 -393.300396) (xy 308.079494 -393.275947) (xy 308.039843 -393.245149)
			(xy 308.005305 -393.20871) (xy 307.976672 -393.167468) (xy 307.954605 -393.122371) (xy 307.939609 -393.074457)
			(xy 307.93203 -393.024825) (xy 307.931566 -392.999722) (xy 307.932076 -392.973735) (xy 307.940206 -392.9224)
			(xy 307.956267 -392.87297) (xy 307.979863 -392.82666) (xy 308.010413 -392.784612) (xy 308.047164 -392.747861)
			(xy 308.089212 -392.717311) (xy 308.135522 -392.693715) (xy 308.184952 -392.677654) (xy 308.236287 -392.669524)
			(xy 308.288261 -392.669524) (xy 308.339596 -392.677654) (xy 308.389026 -392.693715) (xy 308.435336 -392.717311)
			(xy 308.477384 -392.747861) (xy 308.514135 -392.784612) (xy 308.544685 -392.82666) (xy 308.568281 -392.87297)
			(xy 308.584342 -392.9224) (xy 308.592472 -392.973735) (xy 308.592982 -392.999722) (xy 308.592982 -393.00023)
			(xy 308.592426 -393.027205) (xy 308.583613 -393.08043) (xy 308.575456 -393.106148) (xy 308.571646 -393.11707)
			(xy 308.574186 -393.139422) (xy 308.620922 -393.215876) (xy 308.627253 -393.225037) (xy 308.645823 -393.237281)
			(xy 308.656736 -393.239498) (xy 308.65699 -393.239498) (xy 308.686286 -393.244249) (xy 308.743414 -393.260338)
			(xy 308.797983 -393.283677) (xy 308.849077 -393.313873) (xy 308.895839 -393.350421) (xy 308.937485 -393.392706)
			(xy 308.973316 -393.44002) (xy 309.002731 -393.491569) (xy 309.025235 -393.546487) (xy 309.040452 -393.603853)
			(xy 309.048126 -393.662705) (xy 309.048658 -393.69238) (xy 309.048138 -393.723443) (xy 309.039723 -393.784997)
			(xy 309.031894 -393.815062) (xy 309.0291 -393.824968) (xy 309.03164 -393.845288) (xy 309.073804 -393.918186)
			(xy 309.079318 -393.926684) (xy 309.095399 -393.93897) (xy 309.105046 -393.942062) (xy 309.1053 -393.942062)
			(xy 309.134468 -393.950089) (xy 309.190547 -393.972783) (xy 309.24315 -394.002663) (xy 309.291361 -394.039209)
			(xy 309.334341 -394.081785) (xy 309.37134 -394.129649) (xy 309.401715 -394.181968) (xy 309.424937 -394.23783)
			(xy 309.433214 -394.266928) (xy 309.437532 -394.283438) (xy 309.464964 -394.30452) (xy 309.717186 -394.30452)
			(xy 309.744618 -394.283438) (xy 309.748936 -394.266928) (xy 309.750206 -394.26261) (xy 309.753 -394.252704)
			(xy 309.75046 -394.232384) (xy 309.708296 -394.159486) (xy 309.702779 -394.150992) (xy 309.686697 -394.138712)
			(xy 309.677054 -394.13561) (xy 309.6768 -394.13561) (xy 309.647692 -394.127604) (xy 309.591723 -394.104974)
			(xy 309.539215 -394.075183) (xy 309.491079 -394.038747) (xy 309.448151 -393.996299) (xy 309.411176 -393.948577)
			(xy 309.380796 -393.896407) (xy 309.357537 -393.840697) (xy 309.341805 -393.782412) (xy 309.333871 -393.722565)
			(xy 309.333392 -393.69238) (xy 309.3339 -393.661492) (xy 309.342211 -393.600276) (xy 309.358677 -393.540735)
			(xy 309.383001 -393.483948) (xy 309.398416 -393.457176) (xy 309.403769 -393.44724) (xy 309.406157 -393.424826)
			(xy 309.402988 -393.413996) (xy 309.37708 -393.340336) (xy 309.372806 -393.32999) (xy 309.357126 -393.314051)
			(xy 309.346854 -393.309602) (xy 309.323485 -393.300401) (xy 309.279611 -393.275962) (xy 309.239935 -393.245171)
			(xy 309.20537 -393.208736) (xy 309.176709 -393.167495) (xy 309.154611 -393.122396) (xy 309.139585 -393.074475)
			(xy 309.131975 -393.024833) (xy 309.131462 -392.999722) (xy 309.131972 -392.973735) (xy 309.140102 -392.9224)
			(xy 309.156163 -392.87297) (xy 309.179759 -392.82666) (xy 309.210309 -392.784612) (xy 309.24706 -392.747861)
			(xy 309.289108 -392.717311) (xy 309.335418 -392.693715) (xy 309.384848 -392.677654) (xy 309.436183 -392.669524)
			(xy 309.488157 -392.669524) (xy 309.539492 -392.677654) (xy 309.588922 -392.693715) (xy 309.635232 -392.717311)
			(xy 309.67728 -392.747861) (xy 309.714031 -392.784612) (xy 309.744581 -392.82666) (xy 309.768177 -392.87297)
			(xy 309.784238 -392.9224) (xy 309.792368 -392.973735) (xy 309.792878 -392.999722) (xy 309.792878 -393.00023)
			(xy 309.792322 -393.027205) (xy 309.783509 -393.08043) (xy 309.775352 -393.106148) (xy 309.771542 -393.11707)
			(xy 309.774082 -393.139422) (xy 309.820818 -393.215876) (xy 309.827148 -393.225037) (xy 309.845719 -393.237283)
			(xy 309.856632 -393.239498) (xy 309.856886 -393.239498) (xy 309.886194 -393.244237) (xy 309.943348 -393.260306)
			(xy 309.997945 -393.283629) (xy 310.049068 -393.313815) (xy 310.09586 -393.350357) (xy 310.137535 -393.392641)
			(xy 310.173393 -393.439959) (xy 310.202833 -393.491515) (xy 310.225361 -393.546445) (xy 310.240598 -393.603826)
			(xy 310.248289 -393.662695) (xy 310.248808 -393.69238) (xy 310.248287 -393.723443) (xy 310.239872 -393.784997)
			(xy 310.232044 -393.815062) (xy 310.22925 -393.824968) (xy 310.23179 -393.845288) (xy 310.273954 -393.918186)
			(xy 310.279465 -393.926689) (xy 310.295541 -393.938991) (xy 310.305196 -393.942062) (xy 310.30545 -393.942062)
			(xy 310.33462 -393.950087) (xy 310.390704 -393.972776) (xy 310.443312 -394.002653) (xy 310.491528 -394.039197)
			(xy 310.534512 -394.081772) (xy 310.571516 -394.129636) (xy 310.601895 -394.181956) (xy 310.62512 -394.23782)
			(xy 310.633364 -394.266928) (xy 310.637682 -394.283438) (xy 310.665114 -394.30452) (xy 310.917082 -394.30452)
			(xy 310.944514 -394.283438) (xy 310.948832 -394.266928) (xy 310.950102 -394.26261) (xy 310.952896 -394.252704)
			(xy 310.950356 -394.232384) (xy 310.908192 -394.159486) (xy 310.902675 -394.150992) (xy 310.886592 -394.138714)
			(xy 310.87695 -394.13561) (xy 310.876696 -394.13561) (xy 310.847588 -394.127604) (xy 310.79162 -394.104974)
			(xy 310.739112 -394.075182) (xy 310.690977 -394.038746) (xy 310.648049 -393.996298) (xy 310.611074 -393.948576)
			(xy 310.580694 -393.896407) (xy 310.557436 -393.840696) (xy 310.541704 -393.782412) (xy 310.53377 -393.722565)
			(xy 310.533288 -393.69238) (xy 310.533796 -393.661492) (xy 310.542106 -393.600276) (xy 310.558573 -393.540735)
			(xy 310.582897 -393.483948) (xy 310.598312 -393.457176) (xy 310.603666 -393.44724) (xy 310.606054 -393.424826)
			(xy 310.602884 -393.413996) (xy 310.576976 -393.340336) (xy 310.572702 -393.329991) (xy 310.557021 -393.314052)
			(xy 310.54675 -393.309602) (xy 310.523381 -393.300401) (xy 310.479507 -393.275961) (xy 310.439832 -393.24517)
			(xy 310.405267 -393.208735) (xy 310.376607 -393.167495) (xy 310.35451 -393.122395) (xy 310.339484 -393.074474)
			(xy 310.331874 -393.024833) (xy 310.331358 -392.999722) (xy 310.331868 -392.973735) (xy 310.339998 -392.9224)
			(xy 310.356059 -392.87297) (xy 310.379655 -392.82666) (xy 310.410205 -392.784612) (xy 310.446956 -392.747861)
			(xy 310.489004 -392.717311) (xy 310.535314 -392.693715) (xy 310.584744 -392.677654) (xy 310.636079 -392.669524)
			(xy 310.688053 -392.669524) (xy 310.739388 -392.677654) (xy 310.788818 -392.693715) (xy 310.835128 -392.717311)
			(xy 310.877176 -392.747861) (xy 310.913927 -392.784612) (xy 310.944477 -392.82666) (xy 310.968073 -392.87297)
			(xy 310.984134 -392.9224) (xy 310.992264 -392.973735) (xy 310.992774 -392.999722) (xy 310.992774 -393.00023)
			(xy 310.992218 -393.027205) (xy 310.983405 -393.08043) (xy 310.975248 -393.106148) (xy 310.971438 -393.11707)
			(xy 310.973978 -393.139422) (xy 311.020714 -393.215876) (xy 311.027044 -393.225038) (xy 311.045614 -393.237285)
			(xy 311.056528 -393.239498) (xy 311.056782 -393.239498) (xy 311.08609 -393.244237) (xy 311.143244 -393.260305)
			(xy 311.197842 -393.283628) (xy 311.248965 -393.313814) (xy 311.295758 -393.350355) (xy 311.337433 -393.39264)
			(xy 311.373292 -393.439958) (xy 311.402732 -393.491514) (xy 311.42526 -393.546444) (xy 311.440497 -393.603825)
			(xy 311.448188 -393.662695) (xy 311.448704 -393.69238) (xy 311.448183 -393.723443) (xy 311.439768 -393.784997)
			(xy 311.43194 -393.815062) (xy 311.429146 -393.824968) (xy 311.431686 -393.845288) (xy 311.47385 -393.918186)
			(xy 311.479368 -393.926679) (xy 311.495452 -393.938952) (xy 311.505092 -393.942062) (xy 311.505346 -393.942062)
			(xy 311.534516 -393.950086) (xy 311.590601 -393.972776) (xy 311.643209 -394.002652) (xy 311.691426 -394.039196)
			(xy 311.73441 -394.081771) (xy 311.771414 -394.129635) (xy 311.801793 -394.181955) (xy 311.825019 -394.237819)
			(xy 311.83326 -394.266928) (xy 311.837578 -394.283438) (xy 311.86501 -394.30452) (xy 312.116978 -394.30452)
			(xy 312.14441 -394.283438) (xy 312.148728 -394.266928) (xy 312.149998 -394.262356) (xy 312.152792 -394.25245)
			(xy 312.150252 -394.23213) (xy 312.108342 -394.159486) (xy 312.102841 -394.1509) (xy 312.086596 -394.138602)
			(xy 312.076846 -394.13561) (xy 312.047736 -394.127606) (xy 311.991762 -394.10498) (xy 311.939249 -394.075191)
			(xy 311.891109 -394.038757) (xy 311.848176 -393.99631) (xy 311.811197 -393.948587) (xy 311.780813 -393.896416)
			(xy 311.757552 -393.840704) (xy 311.741817 -393.782417) (xy 311.733882 -393.722567) (xy 311.733438 -393.69238)
			(xy 311.733946 -393.661491) (xy 311.742256 -393.600276) (xy 311.758721 -393.540733) (xy 311.783042 -393.483945)
			(xy 311.798462 -393.457176) (xy 311.80382 -393.447241) (xy 311.80621 -393.424825) (xy 311.803034 -393.413996)
			(xy 311.777126 -393.340336) (xy 311.772855 -393.329986) (xy 311.757181 -393.314034) (xy 311.7469 -393.309602)
			(xy 311.723528 -393.300404) (xy 311.679649 -393.275967) (xy 311.639968 -393.245179) (xy 311.605397 -393.208745)
			(xy 311.576732 -393.167503) (xy 311.554631 -393.122403) (xy 311.539603 -393.074479) (xy 311.531991 -393.024834)
			(xy 311.531508 -392.999722) (xy 311.532018 -392.973735) (xy 311.540148 -392.9224) (xy 311.556209 -392.87297)
			(xy 311.579805 -392.82666) (xy 311.610355 -392.784612) (xy 311.647106 -392.747861) (xy 311.689154 -392.717311)
			(xy 311.735464 -392.693715) (xy 311.784894 -392.677654) (xy 311.836229 -392.669524) (xy 311.888203 -392.669524)
			(xy 311.939538 -392.677654) (xy 311.988968 -392.693715) (xy 312.035278 -392.717311) (xy 312.077326 -392.747861)
			(xy 312.114077 -392.784612) (xy 312.144627 -392.82666) (xy 312.168223 -392.87297) (xy 312.184284 -392.9224)
			(xy 312.192414 -392.973735) (xy 312.192924 -392.999722) (xy 312.192924 -393.00023) (xy 312.192368 -393.027205)
			(xy 312.183556 -393.08043) (xy 312.175398 -393.106148) (xy 312.171588 -393.11707) (xy 312.174128 -393.139422)
			(xy 312.220864 -393.215876) (xy 312.227198 -393.225031) (xy 312.245771 -393.23726) (xy 312.256678 -393.239498)
			(xy 312.256932 -393.239498) (xy 312.286242 -393.244234) (xy 312.343402 -393.260298) (xy 312.398004 -393.283617)
			(xy 312.449133 -393.313801) (xy 312.495931 -393.350341) (xy 312.537611 -393.392626) (xy 312.573474 -393.439945)
			(xy 312.602919 -393.491503) (xy 312.62545 -393.546435) (xy 312.640689 -393.60382) (xy 312.648381 -393.662693)
			(xy 312.648854 -393.69238) (xy 312.648334 -393.723443) (xy 312.639919 -393.784997) (xy 312.63209 -393.815062)
			(xy 312.629296 -393.824968) (xy 312.631836 -393.845288) (xy 312.674254 -393.91844) (xy 312.679716 -393.926944)
			(xy 312.695824 -393.939127) (xy 312.705496 -393.942062) (xy 312.734651 -393.950095) (xy 312.790704 -393.972799)
			(xy 312.843279 -394.002685) (xy 312.891461 -394.039234) (xy 312.934412 -394.081808) (xy 312.971382 -394.129668)
			(xy 313.00173 -394.181978) (xy 313.024925 -394.237829) (xy 313.033156 -394.266928) (xy 313.037474 -394.283438)
			(xy 313.064906 -394.30452) (xy 313.317128 -394.30452) (xy 313.34456 -394.283438) (xy 313.348878 -394.266928)
			(xy 313.350148 -394.26261) (xy 313.352942 -394.252704) (xy 313.350402 -394.232384) (xy 313.308238 -394.159486)
			(xy 313.302724 -394.150987) (xy 313.286646 -394.138695) (xy 313.276996 -394.13561) (xy 313.276742 -394.13561)
			(xy 313.247632 -394.127606) (xy 313.191659 -394.10498) (xy 313.139146 -394.075191) (xy 313.091006 -394.038756)
			(xy 313.048074 -393.996309) (xy 313.011095 -393.948586) (xy 312.980712 -393.896415) (xy 312.957451 -393.840703)
			(xy 312.941716 -393.782416) (xy 312.933781 -393.722567) (xy 312.933334 -393.69238) (xy 312.933842 -393.661491)
			(xy 312.942151 -393.600276) (xy 312.958616 -393.540733) (xy 312.982938 -393.483945) (xy 312.998358 -393.457176)
			(xy 313.003716 -393.447241) (xy 313.006106 -393.424825) (xy 313.00293 -393.413996) (xy 312.977022 -393.340336)
			(xy 312.972751 -393.329987) (xy 312.957076 -393.314035) (xy 312.946796 -393.309602) (xy 312.923424 -393.300403)
			(xy 312.879545 -393.275967) (xy 312.839865 -393.245178) (xy 312.805295 -393.208744) (xy 312.77663 -393.167503)
			(xy 312.75453 -393.122402) (xy 312.739501 -393.074479) (xy 312.73189 -393.024834) (xy 312.731404 -392.999722)
			(xy 312.731914 -392.973735) (xy 312.740044 -392.9224) (xy 312.756105 -392.87297) (xy 312.779701 -392.82666)
			(xy 312.810251 -392.784612) (xy 312.847002 -392.747861) (xy 312.88905 -392.717311) (xy 312.93536 -392.693715)
			(xy 312.98479 -392.677654) (xy 313.036125 -392.669524) (xy 313.088099 -392.669524) (xy 313.139434 -392.677654)
			(xy 313.188864 -392.693715) (xy 313.235174 -392.717311) (xy 313.277222 -392.747861) (xy 313.313973 -392.784612)
			(xy 313.344523 -392.82666) (xy 313.368119 -392.87297) (xy 313.38418 -392.9224) (xy 313.39231 -392.973735)
			(xy 313.39282 -392.999722) (xy 313.39282 -393.00023) (xy 313.392264 -393.027205) (xy 313.383452 -393.08043)
			(xy 313.375294 -393.106148) (xy 313.371484 -393.11707) (xy 313.374024 -393.139422) (xy 313.42076 -393.215876)
			(xy 313.427093 -393.225032) (xy 313.445666 -393.237262) (xy 313.456574 -393.239498) (xy 313.456828 -393.239498)
			(xy 313.486139 -393.244234) (xy 313.543298 -393.260297) (xy 313.597901 -393.283616) (xy 313.649031 -393.3138)
			(xy 313.695829 -393.35034) (xy 313.737509 -393.392625) (xy 313.773373 -393.439944) (xy 313.802818 -393.491502)
			(xy 313.825349 -393.546435) (xy 313.840588 -393.60382) (xy 313.84828 -393.662693) (xy 313.84875 -393.69238)
			(xy 313.84823 -393.723443) (xy 313.839815 -393.784997) (xy 313.831986 -393.815062) (xy 313.829192 -393.824968)
			(xy 313.831732 -393.845288) (xy 313.873896 -393.918186) (xy 313.87941 -393.926685) (xy 313.89549 -393.938973)
			(xy 313.905138 -393.942062) (xy 313.905392 -393.942062) (xy 313.93456 -393.950089) (xy 313.99064 -393.972782)
			(xy 314.043244 -394.002662) (xy 314.091456 -394.039207) (xy 314.134436 -394.081783) (xy 314.171436 -394.129647)
			(xy 314.201812 -394.181966) (xy 314.225034 -394.237829) (xy 314.233306 -394.266928) (xy 314.237624 -394.283438)
			(xy 314.265056 -394.30452) (xy 314.517024 -394.30452) (xy 314.544456 -394.283438) (xy 314.548774 -394.266928)
			(xy 314.550044 -394.26261) (xy 314.552838 -394.252704) (xy 314.550298 -394.232384) (xy 314.508134 -394.159486)
			(xy 314.50262 -394.150987) (xy 314.486541 -394.138696) (xy 314.476892 -394.13561) (xy 314.476638 -394.13561)
			(xy 314.447528 -394.127606) (xy 314.391555 -394.104979) (xy 314.339043 -394.07519) (xy 314.290904 -394.038755)
			(xy 314.247972 -393.996308) (xy 314.210993 -393.948585) (xy 314.18061 -393.896415) (xy 314.157349 -393.840703)
			(xy 314.141615 -393.782416) (xy 314.13368 -393.722567) (xy 314.13323 -393.69238) (xy 314.13323 -393.691872)
			(xy 314.133756 -393.661016) (xy 314.142086 -393.599867) (xy 314.15855 -393.540391) (xy 314.18285 -393.483664)
			(xy 314.198254 -393.456922) (xy 314.204096 -393.44727) (xy 314.206636 -393.424918) (xy 314.176918 -393.340336)
			(xy 314.172646 -393.329987) (xy 314.156971 -393.314037) (xy 314.146692 -393.309602) (xy 314.123334 -393.300395)
			(xy 314.079484 -393.275945) (xy 314.039835 -393.245147) (xy 314.005297 -393.208708) (xy 313.976666 -393.167466)
			(xy 313.9546 -393.12237) (xy 313.939604 -393.074455) (xy 313.932026 -393.024825) (xy 313.931554 -392.999722)
			(xy 313.932064 -392.973735) (xy 313.940194 -392.9224) (xy 313.956255 -392.87297) (xy 313.979851 -392.82666)
			(xy 314.010401 -392.784612) (xy 314.047152 -392.747861) (xy 314.0892 -392.717311) (xy 314.13551 -392.693715)
			(xy 314.18494 -392.677654) (xy 314.236275 -392.669524) (xy 314.288249 -392.669524) (xy 314.339584 -392.677654)
			(xy 314.389014 -392.693715) (xy 314.435324 -392.717311) (xy 314.477372 -392.747861) (xy 314.514123 -392.784612)
			(xy 314.544673 -392.82666) (xy 314.568269 -392.87297) (xy 314.58433 -392.9224) (xy 314.59246 -392.973735)
			(xy 314.59297 -392.999722) (xy 314.59297 -393.00023) (xy 314.592414 -393.027205) (xy 314.583601 -393.08043)
			(xy 314.575444 -393.106148) (xy 314.571634 -393.11707) (xy 314.574174 -393.139422) (xy 314.62091 -393.215876)
			(xy 314.62724 -393.225038) (xy 314.64581 -393.237287) (xy 314.656724 -393.239498) (xy 314.656978 -393.239498)
			(xy 314.686275 -393.244248) (xy 314.743404 -393.260337) (xy 314.797974 -393.283674) (xy 314.849069 -393.31387)
			(xy 314.895833 -393.350417) (xy 314.93748 -393.392703) (xy 314.973312 -393.440017) (xy 315.002728 -393.491566)
			(xy 315.025233 -393.546485) (xy 315.04045 -393.603852) (xy 315.048125 -393.662704) (xy 315.048646 -393.69238)
			(xy 315.048126 -393.723443) (xy 315.039711 -393.784997) (xy 315.031882 -393.815062) (xy 315.029088 -393.824968)
			(xy 315.031628 -393.845288) (xy 315.073792 -393.918186) (xy 315.079306 -393.926685) (xy 315.095385 -393.938975)
			(xy 315.105034 -393.942062) (xy 315.105288 -393.942062) (xy 315.134457 -393.950089) (xy 315.190537 -393.972781)
			(xy 315.243141 -394.002661) (xy 315.291353 -394.039206) (xy 315.334334 -394.081782) (xy 315.371334 -394.129646)
			(xy 315.40171 -394.181965) (xy 315.424933 -394.237828) (xy 315.433202 -394.266928) (xy 315.43752 -394.283438)
			(xy 315.464952 -394.30452) (xy 315.717174 -394.30452) (xy 315.744606 -394.283438) (xy 315.748924 -394.266928)
			(xy 315.750194 -394.26261) (xy 315.752988 -394.252704) (xy 315.750448 -394.232384) (xy 315.708284 -394.159486)
			(xy 315.702766 -394.150993) (xy 315.686683 -394.138717) (xy 315.677042 -394.13561) (xy 315.676788 -394.13561)
			(xy 315.64768 -394.127603) (xy 315.591713 -394.104972) (xy 315.539206 -394.07518) (xy 315.491072 -394.038744)
			(xy 315.448145 -393.996297) (xy 315.411171 -393.948574) (xy 315.380791 -393.896405) (xy 315.357534 -393.840695)
			(xy 315.341801 -393.782411) (xy 315.333868 -393.722565) (xy 315.33338 -393.69238) (xy 315.333888 -393.661492)
			(xy 315.342198 -393.600276) (xy 315.358665 -393.540734) (xy 315.382988 -393.483948) (xy 315.398404 -393.457176)
			(xy 315.403758 -393.447241) (xy 315.406147 -393.424826) (xy 315.402976 -393.413996) (xy 315.377068 -393.340336)
			(xy 315.372793 -393.329991) (xy 315.357112 -393.314055) (xy 315.346842 -393.309602) (xy 315.323473 -393.300401)
			(xy 315.2796 -393.27596) (xy 315.239926 -393.245169) (xy 315.205362 -393.208734) (xy 315.176702 -393.167493)
			(xy 315.154606 -393.122395) (xy 315.13958 -393.074474) (xy 315.131971 -393.024832) (xy 315.13145 -392.999722)
			(xy 315.13196 -392.973735) (xy 315.14009 -392.9224) (xy 315.156151 -392.87297) (xy 315.179747 -392.82666)
			(xy 315.210297 -392.784612) (xy 315.247048 -392.747861) (xy 315.289096 -392.717311) (xy 315.335406 -392.693715)
			(xy 315.384836 -392.677654) (xy 315.436171 -392.669524) (xy 315.488145 -392.669524) (xy 315.53948 -392.677654)
			(xy 315.58891 -392.693715) (xy 315.63522 -392.717311) (xy 315.677268 -392.747861) (xy 315.714019 -392.784612)
			(xy 315.744569 -392.82666) (xy 315.768165 -392.87297) (xy 315.784226 -392.9224) (xy 315.792356 -392.973735)
			(xy 315.792866 -392.999722) (xy 315.792866 -393.00023) (xy 315.79231 -393.027205) (xy 315.783497 -393.08043)
			(xy 315.77534 -393.106148) (xy 315.77153 -393.11707) (xy 315.77407 -393.139422) (xy 315.820806 -393.215876)
			(xy 315.827136 -393.225039) (xy 315.845705 -393.237288) (xy 315.85662 -393.239498) (xy 315.856874 -393.239498)
			(xy 315.886183 -393.244236) (xy 315.943338 -393.260304) (xy 315.997936 -393.283626) (xy 316.04906 -393.313812)
			(xy 316.095853 -393.350353) (xy 316.137529 -393.392638) (xy 316.173389 -393.439955) (xy 316.20283 -393.491512)
			(xy 316.225358 -393.546443) (xy 316.240596 -393.603824) (xy 316.248287 -393.662695) (xy 316.248796 -393.69238)
			(xy 316.248275 -393.723443) (xy 316.23986 -393.784997) (xy 316.232032 -393.815062) (xy 316.229238 -393.824968)
			(xy 316.231778 -393.845288) (xy 316.273942 -393.918186) (xy 316.279459 -393.92668) (xy 316.295543 -393.938955)
			(xy 316.305184 -393.942062) (xy 316.305438 -393.942062) (xy 316.334604 -393.950091) (xy 316.39068 -393.972788)
			(xy 316.443279 -394.002671) (xy 316.491486 -394.039218) (xy 316.534462 -394.081795) (xy 316.571458 -394.129659)
			(xy 316.60183 -394.181977) (xy 316.62505 -394.237838) (xy 316.633352 -394.266928) (xy 316.63767 -394.283438)
			(xy 316.665102 -394.30452) (xy 316.91707 -394.30452) (xy 316.944502 -394.283438) (xy 316.94882 -394.266928)
			(xy 316.95009 -394.26261) (xy 316.952884 -394.252704) (xy 316.950344 -394.232384) (xy 316.90818 -394.159486)
			(xy 316.902662 -394.150993) (xy 316.886579 -394.138718) (xy 316.876938 -394.13561) (xy 316.876684 -394.13561)
			(xy 316.847576 -394.127603) (xy 316.791609 -394.104972) (xy 316.739103 -394.07518) (xy 316.690969 -394.038743)
			(xy 316.648043 -393.996296) (xy 316.611069 -393.948573) (xy 316.58069 -393.896404) (xy 316.557432 -393.840695)
			(xy 316.5417 -393.782411) (xy 316.533767 -393.722565) (xy 316.533276 -393.69238) (xy 316.533784 -393.661492)
			(xy 316.542094 -393.600276) (xy 316.55856 -393.540734) (xy 316.582884 -393.483947) (xy 316.5983 -393.457176)
			(xy 316.603655 -393.447241) (xy 316.606043 -393.424826) (xy 316.602872 -393.413996) (xy 316.576964 -393.340336)
			(xy 316.572689 -393.329992) (xy 316.557007 -393.314057) (xy 316.546738 -393.309602) (xy 316.523369 -393.300401)
			(xy 316.479497 -393.27596) (xy 316.439823 -393.245168) (xy 316.40526 -393.208733) (xy 316.3766 -393.167493)
			(xy 316.354504 -393.122394) (xy 316.339479 -393.074473) (xy 316.331869 -393.024832) (xy 316.331346 -392.999722)
			(xy 316.331856 -392.973735) (xy 316.339986 -392.9224) (xy 316.356047 -392.87297) (xy 316.379643 -392.82666)
			(xy 316.410193 -392.784612) (xy 316.446944 -392.747861) (xy 316.488992 -392.717311) (xy 316.535302 -392.693715)
			(xy 316.584732 -392.677654) (xy 316.636067 -392.669524) (xy 316.688041 -392.669524) (xy 316.739376 -392.677654)
			(xy 316.788806 -392.693715) (xy 316.835116 -392.717311) (xy 316.877164 -392.747861) (xy 316.913915 -392.784612)
			(xy 316.944465 -392.82666) (xy 316.968061 -392.87297) (xy 316.984122 -392.9224) (xy 316.992252 -392.973735)
			(xy 316.992762 -392.999722) (xy 316.992762 -393.00023) (xy 316.992206 -393.027205) (xy 316.983392 -393.08043)
			(xy 316.975236 -393.106148) (xy 316.971426 -393.11707) (xy 316.973966 -393.139422) (xy 317.020702 -393.215876)
			(xy 317.027031 -393.225039) (xy 317.045601 -393.23729) (xy 317.056516 -393.239498) (xy 317.05677 -393.239498)
			(xy 317.086079 -393.244236) (xy 317.143234 -393.260304) (xy 317.197833 -393.283626) (xy 317.248958 -393.313811)
			(xy 317.295751 -393.350352) (xy 317.337428 -393.392637) (xy 317.373287 -393.439954) (xy 317.402729 -393.491511)
			(xy 317.425258 -393.546442) (xy 317.440495 -393.603824) (xy 317.448187 -393.662695) (xy 317.448692 -393.69238)
			(xy 317.448171 -393.723443) (xy 317.439756 -393.784997) (xy 317.431928 -393.815062) (xy 317.429134 -393.824968)
			(xy 317.431674 -393.845288) (xy 317.473838 -393.918186) (xy 317.479354 -393.92668) (xy 317.495438 -393.938957)
			(xy 317.50508 -393.942062) (xy 317.505334 -393.942062) (xy 317.534501 -393.950091) (xy 317.590577 -393.972788)
			(xy 317.643176 -394.00267) (xy 317.691384 -394.039217) (xy 317.73436 -394.081794) (xy 317.771356 -394.129658)
			(xy 317.801728 -394.181976) (xy 317.824948 -394.237837) (xy 317.833248 -394.266928) (xy 317.837566 -394.283438)
			(xy 317.864998 -394.30452) (xy 318.116966 -394.30452) (xy 318.144398 -394.283438) (xy 318.148716 -394.266928)
			(xy 318.149986 -394.262356) (xy 318.15278 -394.25245) (xy 318.15024 -394.23213) (xy 318.10833 -394.159486)
			(xy 318.102828 -394.150901) (xy 318.086582 -394.138607) (xy 318.076834 -394.13561) (xy 318.047724 -394.127606)
			(xy 317.991752 -394.104979) (xy 317.93924 -394.075189) (xy 317.891101 -394.038755) (xy 317.84817 -393.996307)
			(xy 317.811192 -393.948584) (xy 317.780809 -393.896414) (xy 317.757548 -393.840702) (xy 317.741814 -393.782416)
			(xy 317.733879 -393.722566) (xy 317.733426 -393.69238) (xy 317.733934 -393.661491) (xy 317.742243 -393.600276)
			(xy 317.758708 -393.540733) (xy 317.783029 -393.483945) (xy 317.79845 -393.457176) (xy 317.803808 -393.447241)
			(xy 317.806199 -393.424825) (xy 317.803022 -393.413996) (xy 317.777114 -393.340336) (xy 317.772842 -393.329987)
			(xy 317.757167 -393.314038) (xy 317.746888 -393.309602) (xy 317.723517 -393.300403) (xy 317.679639 -393.275966)
			(xy 317.639959 -393.245177) (xy 317.60539 -393.208742) (xy 317.576726 -393.167501) (xy 317.554626 -393.122401)
			(xy 317.539598 -393.074478) (xy 317.531987 -393.024834) (xy 317.531496 -392.999722) (xy 317.532006 -392.973735)
			(xy 317.540136 -392.9224) (xy 317.556197 -392.87297) (xy 317.579793 -392.82666) (xy 317.610343 -392.784612)
			(xy 317.647094 -392.747861) (xy 317.689142 -392.717311) (xy 317.735452 -392.693715) (xy 317.784882 -392.677654)
			(xy 317.836217 -392.669524) (xy 317.888191 -392.669524) (xy 317.939526 -392.677654) (xy 317.988956 -392.693715)
			(xy 318.035266 -392.717311) (xy 318.077314 -392.747861) (xy 318.114065 -392.784612) (xy 318.144615 -392.82666)
			(xy 318.168211 -392.87297) (xy 318.184272 -392.9224) (xy 318.192402 -392.973735) (xy 318.192912 -392.999722)
			(xy 318.192912 -393.00023) (xy 318.192356 -393.027205) (xy 318.183544 -393.08043) (xy 318.175386 -393.106148)
			(xy 318.171576 -393.11707) (xy 318.174116 -393.139422) (xy 318.220852 -393.215876) (xy 318.227185 -393.225033)
			(xy 318.245757 -393.237266) (xy 318.256666 -393.239498) (xy 318.25692 -393.239498) (xy 318.286231 -393.244233)
			(xy 318.343391 -393.260296) (xy 318.397995 -393.283615) (xy 318.449126 -393.313798) (xy 318.495924 -393.350338)
			(xy 318.537606 -393.392623) (xy 318.57347 -393.439941) (xy 318.602915 -393.4915) (xy 318.625447 -393.546433)
			(xy 318.640687 -393.603819) (xy 318.648379 -393.662693) (xy 318.648842 -393.69238) (xy 318.648322 -393.723443)
			(xy 318.639907 -393.784997) (xy 318.632078 -393.815062) (xy 318.629284 -393.824968) (xy 318.631824 -393.845288)
			(xy 318.674242 -393.91844) (xy 318.679703 -393.926946) (xy 318.695811 -393.939132) (xy 318.705484 -393.942062)
			(xy 318.73464 -393.950095) (xy 318.790694 -393.972797) (xy 318.84327 -394.002683) (xy 318.891453 -394.039231)
			(xy 318.934405 -394.081805) (xy 318.971377 -394.129664) (xy 319.001725 -394.181975) (xy 319.024921 -394.237826)
			(xy 319.033144 -394.266928) (xy 319.037462 -394.283438) (xy 319.064894 -394.30452) (xy 319.317116 -394.30452)
			(xy 319.344548 -394.283438) (xy 319.348866 -394.266928) (xy 319.350136 -394.26261) (xy 319.35293 -394.252704)
			(xy 319.35039 -394.232384) (xy 319.308226 -394.159486) (xy 319.302711 -394.150988) (xy 319.286632 -394.1387)
			(xy 319.276984 -394.13561) (xy 319.27673 -394.13561) (xy 319.24762 -394.127606) (xy 319.191649 -394.104978)
			(xy 319.139137 -394.075188) (xy 319.090999 -394.038754) (xy 319.048068 -393.996306) (xy 319.01109 -393.948583)
			(xy 318.980707 -393.896413) (xy 318.957447 -393.840701) (xy 318.941713 -393.782415) (xy 318.933778 -393.722566)
			(xy 318.933322 -393.69238) (xy 318.93383 -393.661491) (xy 318.942139 -393.600276) (xy 318.958604 -393.540733)
			(xy 318.982925 -393.483945) (xy 318.998346 -393.457176) (xy 319.003697 -393.44724) (xy 319.006083 -393.424827)
			(xy 319.002918 -393.413996) (xy 318.97701 -393.340336) (xy 318.972738 -393.329988) (xy 318.957062 -393.31404)
			(xy 318.946784 -393.309602) (xy 318.923413 -393.300403) (xy 318.879535 -393.275965) (xy 318.839856 -393.245176)
			(xy 318.805288 -393.208742) (xy 318.776624 -393.167501) (xy 318.754524 -393.1224) (xy 318.739497 -393.074478)
			(xy 318.731886 -393.024834) (xy 318.731392 -392.999722) (xy 318.731902 -392.973735) (xy 318.740032 -392.9224)
			(xy 318.756093 -392.87297) (xy 318.779689 -392.82666) (xy 318.810239 -392.784612) (xy 318.84699 -392.747861)
			(xy 318.889038 -392.717311) (xy 318.935348 -392.693715) (xy 318.984778 -392.677654) (xy 319.036113 -392.669524)
			(xy 319.088087 -392.669524) (xy 319.139422 -392.677654) (xy 319.188852 -392.693715) (xy 319.235162 -392.717311)
			(xy 319.27721 -392.747861) (xy 319.313961 -392.784612) (xy 319.344511 -392.82666) (xy 319.368107 -392.87297)
			(xy 319.384168 -392.9224) (xy 319.392298 -392.973735) (xy 319.392808 -392.999722) (xy 319.392808 -393.00023)
			(xy 319.392252 -393.027205) (xy 319.38344 -393.08043) (xy 319.375282 -393.106148) (xy 319.371472 -393.11707)
			(xy 319.374012 -393.139422) (xy 319.420748 -393.215876) (xy 319.427081 -393.225033) (xy 319.445653 -393.237268)
			(xy 319.456562 -393.239498) (xy 319.456816 -393.239498) (xy 319.486127 -393.244233) (xy 319.543288 -393.260296)
			(xy 319.597892 -393.283614) (xy 319.649023 -393.313796) (xy 319.695822 -393.350337) (xy 319.737504 -393.392621)
			(xy 319.773369 -393.43994) (xy 319.802814 -393.491499) (xy 319.825346 -393.546433) (xy 319.840586 -393.603818)
			(xy 319.848279 -393.662693) (xy 319.848738 -393.69238) (xy 319.848218 -393.723443) (xy 319.839803 -393.784997)
			(xy 319.831974 -393.815062) (xy 319.82918 -393.824968) (xy 319.83172 -393.845288) (xy 319.873884 -393.918186)
			(xy 319.879397 -393.926686) (xy 319.895476 -393.938979) (xy 319.905126 -393.942062) (xy 319.90538 -393.942062)
			(xy 319.934549 -393.950088) (xy 319.99063 -393.97278) (xy 320.043235 -394.002659) (xy 320.091448 -394.039204)
			(xy 320.134429 -394.08178) (xy 320.17143 -394.129644) (xy 320.201807 -394.181963) (xy 320.22503 -394.237826)
			(xy 320.233294 -394.266928) (xy 320.237612 -394.283438) (xy 320.265044 -394.30452) (xy 320.517012 -394.30452)
			(xy 320.544444 -394.283438) (xy 320.548762 -394.266928) (xy 320.550032 -394.262356) (xy 320.552826 -394.25245)
			(xy 320.550286 -394.23213) (xy 320.508376 -394.159486) (xy 320.502878 -394.150896) (xy 320.486635 -394.138588)
			(xy 320.47688 -394.13561) (xy 320.447768 -394.127608) (xy 320.391791 -394.104985) (xy 320.339275 -394.075198)
			(xy 320.291131 -394.038765) (xy 320.248195 -393.996318) (xy 320.211212 -393.948594) (xy 320.180826 -393.896423)
			(xy 320.157563 -393.840709) (xy 320.141826 -393.78242) (xy 320.133891 -393.722568) (xy 320.133472 -393.69238)
			(xy 320.13398 -393.661492) (xy 320.14229 -393.600276) (xy 320.158756 -393.540734) (xy 320.183079 -393.483947)
			(xy 320.198496 -393.457176) (xy 320.203851 -393.447241) (xy 320.20624 -393.424826) (xy 320.203068 -393.413996)
			(xy 320.17716 -393.340336) (xy 320.172885 -393.329992) (xy 320.157203 -393.314058) (xy 320.146934 -393.309602)
			(xy 320.123566 -393.300401) (xy 320.079694 -393.275959) (xy 320.04002 -393.245167) (xy 320.005457 -393.208733)
			(xy 319.976798 -393.167492) (xy 319.954702 -393.122393) (xy 319.939677 -393.074473) (xy 319.932068 -393.024832)
			(xy 319.931542 -392.999722) (xy 319.932052 -392.973735) (xy 319.940182 -392.9224) (xy 319.956243 -392.87297)
			(xy 319.979839 -392.82666) (xy 320.010389 -392.784612) (xy 320.04714 -392.747861) (xy 320.089188 -392.717311)
			(xy 320.135498 -392.693715) (xy 320.184928 -392.677654) (xy 320.236263 -392.669524) (xy 320.288237 -392.669524)
			(xy 320.339572 -392.677654) (xy 320.389002 -392.693715) (xy 320.435312 -392.717311) (xy 320.47736 -392.747861)
			(xy 320.514111 -392.784612) (xy 320.544661 -392.82666) (xy 320.568257 -392.87297) (xy 320.584318 -392.9224)
			(xy 320.592448 -392.973735) (xy 320.592958 -392.999722) (xy 321.131438 -392.999722) (xy 321.131948 -392.973735)
			(xy 321.140078 -392.9224) (xy 321.156139 -392.87297) (xy 321.179735 -392.82666) (xy 321.210285 -392.784612)
			(xy 321.247036 -392.747861) (xy 321.289084 -392.717311) (xy 321.335394 -392.693715) (xy 321.384824 -392.677654)
			(xy 321.436159 -392.669524) (xy 321.488133 -392.669524) (xy 321.539468 -392.677654) (xy 321.588898 -392.693715)
			(xy 321.635208 -392.717311) (xy 321.677256 -392.747861) (xy 321.714007 -392.784612) (xy 321.744557 -392.82666)
			(xy 321.768153 -392.87297) (xy 321.784214 -392.9224) (xy 321.792344 -392.973735) (xy 321.792854 -392.999722)
			(xy 321.792854 -393.00023) (xy 321.792288 -393.027204) (xy 321.783481 -393.08043) (xy 321.775328 -393.106148)
			(xy 321.771518 -393.11707) (xy 321.774058 -393.139422) (xy 321.820794 -393.215876) (xy 321.82708 -393.225082)
			(xy 321.845672 -393.237335) (xy 321.856608 -393.239498) (xy 321.856862 -393.239498) (xy 321.886184 -393.244181)
			(xy 321.943355 -393.260233) (xy 321.997969 -393.283547) (xy 322.049108 -393.313729) (xy 322.095913 -393.350273)
			(xy 322.137597 -393.392564) (xy 322.173461 -393.439893) (xy 322.2029 -393.491463) (xy 322.219247 -393.531344)
			(xy 323.302122 -393.531344) (xy 323.302547 -393.502708) (xy 323.309704 -393.445886) (xy 323.323886 -393.390398)
			(xy 323.344873 -393.33711) (xy 323.372338 -393.286854) (xy 323.388736 -393.263374) (xy 323.394412 -393.254857)
			(xy 323.399022 -393.23493) (xy 323.395455 -393.214791) (xy 323.39026 -393.20597) (xy 323.372788 -393.17802)
			(xy 323.345177 -393.118169) (xy 323.326432 -393.054978) (xy 323.316941 -392.989752) (xy 323.316346 -392.956796)
			(xy 323.316346 -392.956542) (xy 323.316808 -392.927301) (xy 323.324241 -392.869294) (xy 323.339002 -392.812706)
			(xy 323.360853 -392.75846) (xy 323.389436 -392.707439) (xy 323.424286 -392.660476) (xy 323.464835 -392.618335)
			(xy 323.510423 -392.581703) (xy 323.560305 -392.551177) (xy 323.61367 -392.527255) (xy 323.669648 -392.510327)
			(xy 323.727326 -392.500667) (xy 323.756528 -392.499088) (xy 323.76618 -392.498834) (xy 323.783452 -392.491214)
			(xy 323.839332 -392.43508) (xy 323.845735 -392.428096) (xy 323.853305 -392.410742) (xy 323.854064 -392.401298)
			(xy 323.854064 -392.401044) (xy 323.855653 -392.368494) (xy 323.866143 -392.304172) (xy 323.884763 -392.241718)
			(xy 323.91121 -392.182155) (xy 323.945051 -392.126459) (xy 323.985729 -392.075542) (xy 324.032579 -392.03024)
			(xy 324.084833 -391.991294) (xy 324.141634 -391.959343) (xy 324.202051 -391.93491) (xy 324.265095 -391.918397)
			(xy 324.329733 -391.910073) (xy 324.362318 -391.909554) (xy 324.395901 -391.910123) (xy 324.462484 -391.918949)
			(xy 324.527324 -391.936469) (xy 324.58929 -391.96238) (xy 324.647303 -391.99623) (xy 324.70035 -392.037427)
			(xy 324.747506 -392.085255) (xy 324.78795 -392.138878) (xy 324.820977 -392.197363) (xy 324.833996 -392.228324)
			(xy 324.833996 -392.228578) (xy 324.837983 -392.237256) (xy 324.851132 -392.25108) (xy 324.868438 -392.259112)
			(xy 324.877938 -392.260074) (xy 324.984364 -392.266678) (xy 325.010018 -392.252454) (xy 325.01713 -392.2395)
			(xy 325.034073 -392.210169) (xy 325.07448 -392.155808) (xy 325.121742 -392.107288) (xy 325.175024 -392.065467)
			(xy 325.233384 -392.031086) (xy 325.295789 -392.004751) (xy 325.361137 -391.986929) (xy 325.428271 -391.977934)
			(xy 325.462138 -391.977372) (xy 325.50139 -391.978139) (xy 325.578955 -391.990257) (xy 325.61657 -392.001502)
			(xy 325.616824 -392.001502) (xy 325.625066 -392.003763) (xy 325.64214 -392.003222) (xy 325.658091 -391.997108)
			(xy 325.66483 -391.99185) (xy 325.730616 -391.93597) (xy 325.736937 -391.930172) (xy 325.745565 -391.915358)
			(xy 325.74881 -391.898524) (xy 325.747888 -391.889996) (xy 325.747888 -391.889742) (xy 325.745996 -391.875977)
			(xy 325.743961 -391.848264) (xy 325.743824 -391.83437) (xy 325.743824 -391.834116) (xy 325.74431 -391.806865)
			(xy 325.752066 -391.752917) (xy 325.767421 -391.700622) (xy 325.790063 -391.651045) (xy 325.819529 -391.605195)
			(xy 325.85522 -391.564004) (xy 325.896411 -391.528313) (xy 325.942261 -391.498847) (xy 325.991838 -391.476205)
			(xy 326.044133 -391.46085) (xy 326.098081 -391.453094) (xy 326.152583 -391.453094) (xy 326.206531 -391.46085)
			(xy 326.258826 -391.476205) (xy 326.308403 -391.498847) (xy 326.354253 -391.528313) (xy 326.395444 -391.564004)
			(xy 326.431135 -391.605195) (xy 326.460601 -391.651045) (xy 326.483243 -391.700622) (xy 326.498598 -391.752917)
			(xy 326.506354 -391.806865) (xy 326.50684 -391.834116) (xy 326.506137 -391.865698) (xy 326.495673 -391.927992)
			(xy 326.486012 -391.958068) (xy 326.483501 -391.966404) (xy 326.483639 -391.983803) (xy 326.486266 -391.992104)
			(xy 326.496934 -392.020552) (xy 326.500273 -392.028611) (xy 326.511442 -392.041993) (xy 326.518778 -392.046714)
			(xy 326.547091 -392.063933) (xy 326.599476 -392.104517) (xy 326.619996 -392.1252) (xy 332.211424 -392.1252)
			(xy 332.215495 -392.069578) (xy 332.227621 -392.015141) (xy 332.247544 -391.96305) (xy 332.27484 -391.914415)
			(xy 332.308926 -391.870272) (xy 332.349075 -391.831563) (xy 332.394433 -391.799112) (xy 332.444033 -391.773611)
			(xy 332.496817 -391.755604) (xy 332.55166 -391.745474) (xy 332.607394 -391.743437) (xy 332.662831 -391.749537)
			(xy 332.716788 -391.763643) (xy 332.768117 -391.785455) (xy 332.815723 -391.814509) (xy 332.858591 -391.850184)
			(xy 332.895808 -391.891721) (xy 332.926581 -391.938234) (xy 332.950253 -391.988731) (xy 332.966321 -392.042138)
			(xy 332.974441 -392.097314) (xy 332.97495 -392.1252) (xy 332.974441 -392.153086) (xy 332.966321 -392.208262)
			(xy 332.950253 -392.261669) (xy 332.926581 -392.312166) (xy 332.895808 -392.358679) (xy 332.858591 -392.400216)
			(xy 332.815723 -392.435891) (xy 332.768117 -392.464945) (xy 332.716788 -392.486757) (xy 332.662831 -392.500863)
			(xy 332.607394 -392.506963) (xy 332.55166 -392.504926) (xy 332.496817 -392.494796) (xy 332.444033 -392.476789)
			(xy 332.394433 -392.451288) (xy 332.349075 -392.418837) (xy 332.308926 -392.380128) (xy 332.27484 -392.335985)
			(xy 332.247544 -392.28735) (xy 332.227621 -392.235259) (xy 332.215495 -392.180822) (xy 332.211424 -392.1252)
			(xy 326.619996 -392.1252) (xy 326.646147 -392.151559) (xy 326.686314 -392.204265) (xy 326.719296 -392.26174)
			(xy 326.744535 -392.323012) (xy 326.761603 -392.387042) (xy 326.770211 -392.452747) (xy 326.770746 -392.48588)
			(xy 326.770328 -392.51599) (xy 326.763197 -392.575788) (xy 326.749054 -392.634325) (xy 326.728099 -392.690782)
			(xy 326.700624 -392.744371) (xy 326.667014 -392.79434) (xy 326.627738 -392.839991) (xy 326.583348 -392.880686)
			(xy 326.559164 -392.89863) (xy 326.5497 -392.906256) (xy 326.538699 -392.927892) (xy 326.538082 -392.940032)
			(xy 326.538082 -393.022328) (xy 326.538689 -393.034463) (xy 326.543906 -393.04468) (xy 332.211424 -393.04468)
			(xy 332.215495 -392.989058) (xy 332.227621 -392.934621) (xy 332.247544 -392.88253) (xy 332.27484 -392.833895)
			(xy 332.308926 -392.789752) (xy 332.349075 -392.751043) (xy 332.394433 -392.718592) (xy 332.444033 -392.693091)
			(xy 332.496817 -392.675084) (xy 332.55166 -392.664954) (xy 332.607394 -392.662917) (xy 332.662831 -392.669017)
			(xy 332.716788 -392.683123) (xy 332.768117 -392.704935) (xy 332.815723 -392.733989) (xy 332.858202 -392.76934)
			(xy 333.471502 -392.76934) (xy 333.471502 -392.709404) (xy 333.479325 -392.649982) (xy 333.494838 -392.592089)
			(xy 333.517774 -392.536716) (xy 333.547741 -392.48481) (xy 333.584228 -392.43726) (xy 333.626608 -392.39488)
			(xy 333.674158 -392.358393) (xy 333.726064 -392.328426) (xy 333.781437 -392.30549) (xy 333.83933 -392.289977)
			(xy 333.898752 -392.282154) (xy 333.958688 -392.282154) (xy 334.01811 -392.289977) (xy 334.076003 -392.30549)
			(xy 334.131376 -392.328426) (xy 334.183282 -392.358393) (xy 334.230832 -392.39488) (xy 334.273212 -392.43726)
			(xy 334.309699 -392.48481) (xy 334.339666 -392.536716) (xy 334.362602 -392.592089) (xy 334.378115 -392.649982)
			(xy 334.385938 -392.709404) (xy 334.386428 -392.739372) (xy 334.385938 -392.76934) (xy 334.378115 -392.828762)
			(xy 334.362602 -392.886655) (xy 334.339666 -392.942028) (xy 334.309699 -392.993934) (xy 334.273212 -393.041484)
			(xy 334.230832 -393.083864) (xy 334.183282 -393.120351) (xy 334.131376 -393.150318) (xy 334.076003 -393.173254)
			(xy 334.01811 -393.188767) (xy 333.958688 -393.19659) (xy 333.898752 -393.19659) (xy 333.83933 -393.188767)
			(xy 333.781437 -393.173254) (xy 333.726064 -393.150318) (xy 333.674158 -393.120351) (xy 333.626608 -393.083864)
			(xy 333.584228 -393.041484) (xy 333.547741 -392.993934) (xy 333.517774 -392.942028) (xy 333.494838 -392.886655)
			(xy 333.479325 -392.828762) (xy 333.471502 -392.76934) (xy 332.858202 -392.76934) (xy 332.858591 -392.769664)
			(xy 332.895808 -392.811201) (xy 332.926581 -392.857714) (xy 332.950253 -392.908211) (xy 332.966321 -392.961618)
			(xy 332.974441 -393.016794) (xy 332.97495 -393.04468) (xy 332.974441 -393.072566) (xy 332.966321 -393.127742)
			(xy 332.950253 -393.181149) (xy 332.926581 -393.231646) (xy 332.895808 -393.278159) (xy 332.858591 -393.319696)
			(xy 332.815723 -393.355371) (xy 332.768117 -393.384425) (xy 332.716788 -393.406237) (xy 332.662831 -393.420343)
			(xy 332.607394 -393.426443) (xy 332.55166 -393.424406) (xy 332.496817 -393.414276) (xy 332.444033 -393.396269)
			(xy 332.394433 -393.370768) (xy 332.349075 -393.338317) (xy 332.308926 -393.299608) (xy 332.27484 -393.255465)
			(xy 332.247544 -393.20683) (xy 332.227621 -393.154739) (xy 332.215495 -393.100302) (xy 332.211424 -393.04468)
			(xy 326.543906 -393.04468) (xy 326.549724 -393.056076) (xy 326.559164 -393.06373) (xy 326.583358 -393.081662)
			(xy 326.62776 -393.122347) (xy 326.667043 -393.167995) (xy 326.700656 -393.217966) (xy 326.728127 -393.271558)
			(xy 326.749072 -393.328022) (xy 326.763198 -393.386566) (xy 326.770306 -393.446368) (xy 326.770746 -393.47648)
			(xy 326.770225 -393.507209) (xy 326.76282 -393.56822) (xy 326.748115 -393.627893) (xy 326.726324 -393.685358)
			(xy 326.697766 -393.739778) (xy 326.662856 -393.790359) (xy 326.622104 -393.836363) (xy 326.576105 -393.87712)
			(xy 326.525528 -393.912036) (xy 326.471111 -393.9406) (xy 326.413648 -393.962397) (xy 326.353977 -393.977109)
			(xy 326.292967 -393.984522) (xy 326.262238 -393.984988) (xy 326.230113 -393.984517) (xy 326.166377 -393.976406)
			(xy 326.104169 -393.960335) (xy 326.044481 -393.936558) (xy 325.988261 -393.905455) (xy 325.936405 -393.867521)
			(xy 325.912734 -393.845796) (xy 325.905388 -393.839452) (xy 325.887378 -393.832261) (xy 325.877682 -393.831826)
			(xy 325.846694 -393.831826) (xy 325.836992 -393.832252) (xy 325.818966 -393.839422) (xy 325.811642 -393.845796)
			(xy 325.795894 -393.860274) (xy 325.787258 -393.86764) (xy 325.778114 -393.888722) (xy 325.780908 -393.978892)
			(xy 325.78189 -393.990217) (xy 325.782531 -393.991458) (xy 332.212315 -393.991458) (xy 332.212315 -393.936942)
			(xy 332.220074 -393.882982) (xy 332.235434 -393.830675) (xy 332.258082 -393.781087) (xy 332.287557 -393.735227)
			(xy 332.323259 -393.694029) (xy 332.364461 -393.658332) (xy 332.410324 -393.628862) (xy 332.459915 -393.606219)
			(xy 332.512223 -393.590865) (xy 332.566184 -393.583112) (xy 332.593442 -393.582652) (xy 332.622076 -393.583167)
			(xy 332.6787 -393.591733) (xy 332.733408 -393.608664) (xy 332.784971 -393.633582) (xy 332.832232 -393.665926)
			(xy 332.874127 -393.704969) (xy 332.909717 -393.749836) (xy 332.924404 -393.774422) (xy 332.929199 -393.782144)
			(xy 332.943148 -393.793783) (xy 332.960274 -393.799845) (xy 332.969362 -393.800076) (xy 333.072486 -393.798044)
			(xy 333.095854 -393.783566) (xy 333.102458 -393.771374) (xy 333.117429 -393.744141) (xy 333.153555 -393.693577)
			(xy 333.196194 -393.648368) (xy 333.244559 -393.609348) (xy 333.297762 -393.577234) (xy 333.354822 -393.552618)
			(xy 333.41469 -393.535952) (xy 333.476262 -393.527544) (xy 333.507334 -393.527026) (xy 333.537304 -393.52745)
			(xy 333.59673 -393.535278) (xy 333.654626 -393.550796) (xy 333.710002 -393.573738) (xy 333.761909 -393.603712)
			(xy 333.80946 -393.640205) (xy 333.85184 -393.682592) (xy 333.888326 -393.730148) (xy 333.918292 -393.782059)
			(xy 333.941226 -393.837438) (xy 333.956735 -393.895337) (xy 333.964554 -393.954764) (xy 333.965042 -393.984734)
			(xy 333.964547 -394.015614) (xy 333.956231 -394.076813) (xy 333.939755 -394.136335) (xy 333.915419 -394.193099)
			(xy 333.883665 -394.246072) (xy 333.845071 -394.294289) (xy 333.823056 -394.31595) (xy 333.814914 -394.324561)
			(xy 333.806819 -394.346797) (xy 333.807562 -394.358622) (xy 333.81696 -394.43914) (xy 333.818834 -394.450798)
			(xy 333.831538 -394.470665) (xy 333.841344 -394.47724) (xy 333.841598 -394.47724) (xy 333.866945 -394.492735)
			(xy 333.913797 -394.529264) (xy 333.955527 -394.571549) (xy 333.991434 -394.618879) (xy 334.020914 -394.670458)
			(xy 334.04347 -394.725418) (xy 334.058724 -394.782835) (xy 334.06642 -394.841744) (xy 334.066896 -394.871448)
			(xy 334.06644 -394.902108) (xy 334.058247 -394.962877) (xy 334.042014 -395.022009) (xy 334.018032 -395.078444)
			(xy 333.986731 -395.131172) (xy 333.94867 -395.179249) (xy 333.926942 -395.200886) (xy 333.919206 -395.209201)
			(xy 333.911202 -395.23042) (xy 333.913111 -395.253018) (xy 333.918306 -395.263116) (xy 333.932445 -395.288584)
			(xy 333.952514 -395.343264) (xy 333.962676 -395.400616) (xy 333.963264 -395.42974) (xy 333.962754 -395.455727)
			(xy 333.954624 -395.507062) (xy 333.938563 -395.556492) (xy 333.914967 -395.602802) (xy 333.884417 -395.64485)
			(xy 333.847666 -395.681601) (xy 333.805618 -395.712151) (xy 333.759308 -395.735747) (xy 333.709878 -395.751808)
			(xy 333.658543 -395.759938) (xy 333.606569 -395.759938) (xy 333.555234 -395.751808) (xy 333.505804 -395.735747)
			(xy 333.459494 -395.712151) (xy 333.417446 -395.681601) (xy 333.380695 -395.64485) (xy 333.350145 -395.602802)
			(xy 333.326549 -395.556492) (xy 333.310488 -395.507062) (xy 333.302358 -395.455727) (xy 333.301848 -395.42974)
			(xy 333.301848 -395.429486) (xy 333.302289 -395.405015) (xy 333.309484 -395.356607) (xy 333.323745 -395.30979)
			(xy 333.333852 -395.2875) (xy 333.338211 -395.277035) (xy 333.338216 -395.254388) (xy 333.328519 -395.233922)
			(xy 333.320136 -395.226286) (xy 333.297912 -395.207625) (xy 333.257904 -395.165587) (xy 333.223533 -395.118828)
			(xy 333.195351 -395.068097) (xy 333.173811 -395.01421) (xy 333.159258 -394.958032) (xy 333.151926 -394.900464)
			(xy 333.15148 -394.871448) (xy 333.151987 -394.840568) (xy 333.160304 -394.779371) (xy 333.176779 -394.71985)
			(xy 333.201113 -394.663086) (xy 333.232864 -394.610113) (xy 333.271453 -394.561894) (xy 333.293466 -394.540232)
			(xy 333.30162 -394.531631) (xy 333.309707 -394.509387) (xy 333.30896 -394.49756) (xy 333.299562 -394.417042)
			(xy 333.297689 -394.405384) (xy 333.284984 -394.385518) (xy 333.275178 -394.378942) (xy 333.274924 -394.378942)
			(xy 333.251543 -394.364714) (xy 333.208032 -394.331511) (xy 333.168797 -394.293348) (xy 333.134401 -394.250773)
			(xy 333.105336 -394.204394) (xy 333.093314 -394.179806) (xy 333.093314 -394.179552) (xy 333.089102 -394.171565)
			(xy 333.076147 -394.159003) (xy 333.059628 -394.151742) (xy 333.050642 -394.15085) (xy 332.961742 -394.145008)
			(xy 332.952649 -394.144807) (xy 332.935231 -394.149985) (xy 332.920718 -394.160919) (xy 332.915514 -394.168376)
			(xy 332.915514 -394.16863) (xy 332.900462 -394.191536) (xy 332.864765 -394.233128) (xy 332.823484 -394.269183)
			(xy 332.777467 -394.298959) (xy 332.727662 -394.321842) (xy 332.675094 -394.337362) (xy 332.620847 -394.345198)
			(xy 332.593442 -394.345668) (xy 332.566184 -394.345288) (xy 332.512223 -394.337535) (xy 332.459915 -394.322181)
			(xy 332.410324 -394.299538) (xy 332.364461 -394.270068) (xy 332.323259 -394.234371) (xy 332.287557 -394.193173)
			(xy 332.258082 -394.147313) (xy 332.235434 -394.097725) (xy 332.220074 -394.045418) (xy 332.212315 -393.991458)
			(xy 325.782531 -393.991458) (xy 325.792314 -394.010388) (xy 325.800974 -394.017754) (xy 325.827295 -394.038434)
			(xy 325.874833 -394.085558) (xy 325.915774 -394.138514) (xy 325.94941 -394.196386) (xy 325.975159 -394.258172)
			(xy 325.992575 -394.322803) (xy 326.001357 -394.389162) (xy 326.001888 -394.42263) (xy 326.001472 -394.453362)
			(xy 325.99406 -394.514379) (xy 325.979347 -394.574057) (xy 325.957548 -394.631526) (xy 325.928981 -394.685949)
			(xy 325.894062 -394.736532) (xy 325.853301 -394.782537) (xy 325.807292 -394.823293) (xy 325.756706 -394.858207)
			(xy 325.70228 -394.886769) (xy 325.644809 -394.908562) (xy 325.585129 -394.923269) (xy 325.524112 -394.930675)
			(xy 325.49338 -394.931138) (xy 325.461878 -394.930652) (xy 325.399357 -394.922863) (xy 325.338278 -394.907407)
			(xy 325.279577 -394.884521) (xy 325.224154 -394.854557) (xy 325.198232 -394.83665) (xy 325.191034 -394.831907)
			(xy 325.174466 -394.827176) (xy 325.15727 -394.828254) (xy 325.14921 -394.831316) (xy 325.057008 -394.870178)
			(xy 325.041006 -394.890752) (xy 325.038974 -394.90396) (xy 325.033538 -394.936309) (xy 325.015308 -394.999323)
			(xy 324.989128 -395.059471) (xy 324.955432 -395.115754) (xy 324.914781 -395.167238) (xy 324.867848 -395.213069)
			(xy 324.815412 -395.252486) (xy 324.758344 -395.284834) (xy 324.697591 -395.309577) (xy 324.634161 -395.326305)
			(xy 324.569107 -395.33474) (xy 324.536308 -395.335252) (xy 324.504904 -395.334719) (xy 324.442575 -395.326985)
			(xy 324.381673 -395.311633) (xy 324.323126 -395.288897) (xy 324.267824 -395.259123) (xy 324.216611 -395.222766)
			(xy 324.170265 -395.180377) (xy 324.129492 -395.132603) (xy 324.094914 -395.080171) (xy 324.067057 -395.02388)
			(xy 324.046344 -394.964586) (xy 324.033092 -394.903193) (xy 324.029832 -394.871956) (xy 324.02907 -394.86205)
			(xy 324.02018 -394.844778) (xy 323.959728 -394.791946) (xy 323.952034 -394.785832) (xy 323.933485 -394.779412)
			(xy 323.92366 -394.7795) (xy 323.89953 -394.780008) (xy 323.868799 -394.779534) (xy 323.807783 -394.772129)
			(xy 323.748106 -394.757423) (xy 323.690636 -394.73563) (xy 323.636212 -394.707069) (xy 323.585628 -394.672156)
			(xy 323.539621 -394.6314) (xy 323.498862 -394.585396) (xy 323.463946 -394.534814) (xy 323.435382 -394.480391)
			(xy 323.413586 -394.422923) (xy 323.398876 -394.363246) (xy 323.391468 -394.302231) (xy 323.391022 -394.2715)
			(xy 323.391459 -394.240718) (xy 323.398852 -394.1796) (xy 323.413576 -394.119824) (xy 323.435418 -394.062265)
			(xy 323.464055 -394.007768) (xy 323.481192 -393.982194) (xy 323.48627 -393.9742) (xy 323.490719 -393.955807)
			(xy 323.489828 -393.94638) (xy 323.48551 -393.915646) (xy 323.483848 -393.906382) (xy 323.474724 -393.889939)
			(xy 323.46773 -393.883642) (xy 323.445905 -393.864953) (xy 323.406599 -393.823039) (xy 323.372851 -393.776534)
			(xy 323.345191 -393.72617) (xy 323.324054 -393.672738) (xy 323.309774 -393.617081) (xy 323.302574 -393.560074)
			(xy 323.302122 -393.531344) (xy 322.219247 -393.531344) (xy 322.225422 -393.546408) (xy 322.240646 -393.603805)
			(xy 322.248317 -393.662689) (xy 322.248784 -393.69238) (xy 322.248257 -393.723443) (xy 322.239845 -393.784996)
			(xy 322.23202 -393.815062) (xy 322.229226 -393.824968) (xy 322.231766 -393.845288) (xy 322.27393 -393.918186)
			(xy 322.279317 -393.926797) (xy 322.295451 -393.939112) (xy 322.305172 -393.942062) (xy 322.305426 -393.942062)
			(xy 322.33453 -393.950079) (xy 322.390497 -393.97271) (xy 322.443003 -394.002502) (xy 322.491137 -394.038937)
			(xy 322.534064 -394.081384) (xy 322.571039 -394.129105) (xy 322.601419 -394.181272) (xy 322.624679 -394.23698)
			(xy 322.640414 -394.295263) (xy 322.64835 -394.355108) (xy 322.648834 -394.385292) (xy 322.648733 -394.399042)
			(xy 322.647079 -394.426493) (xy 322.645532 -394.440156) (xy 322.644789 -394.448845) (xy 322.648568 -394.465859)
			(xy 322.652898 -394.47343) (xy 322.6689 -394.49883) (xy 322.673669 -394.505867) (xy 322.686912 -394.516509)
			(xy 322.694808 -394.519658) (xy 322.718583 -394.528582) (xy 322.763232 -394.552775) (xy 322.803657 -394.583509)
			(xy 322.838908 -394.620063) (xy 322.868157 -394.661576) (xy 322.890714 -394.707073) (xy 322.90605 -394.755484)
			(xy 322.913805 -394.805671) (xy 322.914264 -394.831062) (xy 322.91379 -394.857052) (xy 322.905663 -394.908394)
			(xy 322.889603 -394.957832) (xy 322.866006 -395.004148) (xy 322.835453 -395.046202) (xy 322.798697 -395.082957)
			(xy 322.756643 -395.113509) (xy 322.710326 -395.137105) (xy 322.660888 -395.153164) (xy 322.609546 -395.16129)
			(xy 322.583556 -395.16177) (xy 322.55866 -395.161267) (xy 322.50943 -395.153804) (xy 322.461878 -395.139039)
			(xy 322.417079 -395.117306) (xy 322.376049 -395.089097) (xy 322.339716 -395.055051) (xy 322.308902 -395.015939)
			(xy 322.284306 -394.972645) (xy 322.266485 -394.926152) (xy 322.260722 -394.901928) (xy 322.258552 -394.893664)
			(xy 322.24961 -394.879122) (xy 322.243196 -394.87348) (xy 322.205604 -394.842746) (xy 322.191126 -394.843)
			(xy 322.161157 -394.842515) (xy 322.101732 -394.834694) (xy 322.043836 -394.819184) (xy 321.98846 -394.796249)
			(xy 321.936552 -394.766282) (xy 321.889 -394.729795) (xy 321.846617 -394.687414) (xy 321.810128 -394.639863)
			(xy 321.780159 -394.587956) (xy 321.757222 -394.532581) (xy 321.741709 -394.474686) (xy 321.733887 -394.415261)
			(xy 321.733418 -394.385292) (xy 321.73394 -394.354229) (xy 321.742355 -394.292675) (xy 321.750182 -394.26261)
			(xy 321.752976 -394.252704) (xy 321.750436 -394.232384) (xy 321.708272 -394.159486) (xy 321.702865 -394.150889)
			(xy 321.686747 -394.138564) (xy 321.67703 -394.13561) (xy 321.676776 -394.13561) (xy 321.647664 -394.127617)
			(xy 321.591696 -394.104984) (xy 321.539189 -394.07519) (xy 321.491054 -394.038753) (xy 321.448127 -393.996304)
			(xy 321.411153 -393.94858) (xy 321.380774 -393.896409) (xy 321.357516 -393.840698) (xy 321.341784 -393.782413)
			(xy 321.33385 -393.722566) (xy 321.333368 -393.69238) (xy 321.333898 -393.661492) (xy 321.342203 -393.600277)
			(xy 321.358658 -393.540733) (xy 321.382967 -393.483941) (xy 321.398392 -393.457176) (xy 321.403775 -393.447256)
			(xy 321.406129 -393.424832) (xy 321.402964 -393.413996) (xy 321.377056 -393.340336) (xy 321.372803 -393.329978)
			(xy 321.357113 -393.314036) (xy 321.34683 -393.309602) (xy 321.323434 -393.300454) (xy 321.279539 -393.276027)
			(xy 321.239845 -393.245239) (xy 321.205266 -393.2088) (xy 321.176599 -393.167549) (xy 321.154504 -393.122435)
			(xy 321.139489 -393.074497) (xy 321.1319 -393.024839) (xy 321.131438 -392.999722) (xy 320.592958 -392.999722)
			(xy 320.592958 -393.00023) (xy 320.592402 -393.027205) (xy 320.583588 -393.08043) (xy 320.575432 -393.106148)
			(xy 320.571622 -393.11707) (xy 320.574162 -393.139422) (xy 320.620898 -393.215876) (xy 320.627227 -393.22504)
			(xy 320.645796 -393.237292) (xy 320.656712 -393.239498) (xy 320.656966 -393.239498) (xy 320.686275 -393.244236)
			(xy 320.743431 -393.260303) (xy 320.79803 -393.283625) (xy 320.849155 -393.31381) (xy 320.895949 -393.350351)
			(xy 320.937626 -393.392635) (xy 320.973486 -393.439953) (xy 321.002928 -393.49151) (xy 321.025457 -393.546441)
			(xy 321.040695 -393.603824) (xy 321.048386 -393.662695) (xy 321.048888 -393.69238) (xy 321.048367 -393.723443)
			(xy 321.039952 -393.784997) (xy 321.032124 -393.815062) (xy 321.02933 -393.824968) (xy 321.03187 -393.845288)
			(xy 321.074288 -393.91844) (xy 321.079753 -393.92694) (xy 321.095864 -393.939113) (xy 321.10553 -393.942062)
			(xy 321.134627 -393.950076) (xy 321.190571 -393.97272) (xy 321.243053 -394.002523) (xy 321.291161 -394.038966)
			(xy 321.334061 -394.081417) (xy 321.371008 -394.12914) (xy 321.40136 -394.181306) (xy 321.424591 -394.237009)
			(xy 321.440298 -394.295282) (xy 321.448207 -394.355115) (xy 321.448684 -394.385292) (xy 321.44856 -394.399427)
			(xy 321.446779 -394.427641) (xy 321.445128 -394.44168) (xy 321.444392 -394.450286) (xy 321.448026 -394.46716)
			(xy 321.45224 -394.4747) (xy 321.467988 -394.5001) (xy 321.472695 -394.507162) (xy 321.485805 -394.517924)
			(xy 321.493642 -394.521182) (xy 321.517012 -394.530382) (xy 321.560888 -394.554821) (xy 321.600566 -394.585611)
			(xy 321.635134 -394.622046) (xy 321.663797 -394.663286) (xy 321.685896 -394.708386) (xy 321.700925 -394.756308)
			(xy 321.708538 -394.805951) (xy 321.709034 -394.831062) (xy 321.709034 -394.831316) (xy 321.70857 -394.855515)
			(xy 321.701481 -394.903391) (xy 321.6875 -394.949725) (xy 321.666925 -394.993532) (xy 321.653916 -395.013942)
			(xy 321.649174 -395.021849) (xy 321.645128 -395.039821) (xy 321.646042 -395.048994) (xy 321.650614 -395.079982)
			(xy 321.652302 -395.08928) (xy 321.661563 -395.105735) (xy 321.668648 -395.111986) (xy 321.690721 -395.130672)
			(xy 321.730452 -395.172701) (xy 321.764573 -395.219398) (xy 321.792541 -395.27002) (xy 321.813911 -395.323762)
			(xy 321.828343 -395.379768) (xy 321.835606 -395.437144) (xy 321.836034 -395.466062) (xy 325.883522 -395.466062)
			(xy 325.887593 -395.41044) (xy 325.899719 -395.356003) (xy 325.919642 -395.303912) (xy 325.946938 -395.255277)
			(xy 325.981024 -395.211134) (xy 326.021173 -395.172425) (xy 326.066531 -395.139974) (xy 326.116131 -395.114473)
			(xy 326.168915 -395.096466) (xy 326.223758 -395.086336) (xy 326.279492 -395.084299) (xy 326.334929 -395.090399)
			(xy 326.388886 -395.104505) (xy 326.440215 -395.126317) (xy 326.487821 -395.155371) (xy 326.530689 -395.191046)
			(xy 326.567906 -395.232583) (xy 326.598679 -395.279096) (xy 326.622351 -395.329593) (xy 326.638419 -395.383)
			(xy 326.646539 -395.438176) (xy 326.647048 -395.466062) (xy 326.646539 -395.493948) (xy 326.638419 -395.549124)
			(xy 326.622351 -395.602531) (xy 326.598679 -395.653028) (xy 326.567906 -395.699541) (xy 326.530689 -395.741078)
			(xy 326.487821 -395.776753) (xy 326.440215 -395.805807) (xy 326.388886 -395.827619) (xy 326.334929 -395.841725)
			(xy 326.279492 -395.847825) (xy 326.223758 -395.845788) (xy 326.168915 -395.835658) (xy 326.116131 -395.817651)
			(xy 326.066531 -395.79215) (xy 326.021173 -395.759699) (xy 325.981024 -395.72099) (xy 325.946938 -395.676847)
			(xy 325.919642 -395.628212) (xy 325.899719 -395.576121) (xy 325.887593 -395.521684) (xy 325.883522 -395.466062)
			(xy 321.836034 -395.466062) (xy 321.835449 -395.499425) (xy 321.825799 -395.56545) (xy 321.806669 -395.629375)
			(xy 321.793108 -395.659864) (xy 321.788925 -395.670298) (xy 321.78907 -395.69275) (xy 321.798764 -395.713002)
			(xy 321.807078 -395.72057) (xy 321.829327 -395.739243) (xy 321.869396 -395.781297) (xy 321.903821 -395.828082)
			(xy 321.932051 -395.878847) (xy 321.953632 -395.932775) (xy 321.968216 -395.989) (xy 321.97557 -396.046619)
			(xy 321.975988 -396.075662) (xy 321.975537 -396.104666) (xy 321.968206 -396.162209) (xy 321.964507 -396.1765)
			(xy 327.956924 -396.1765) (xy 327.960995 -396.120878) (xy 327.973121 -396.066441) (xy 327.993044 -396.01435)
			(xy 328.02034 -395.965715) (xy 328.054426 -395.921572) (xy 328.094575 -395.882863) (xy 328.139933 -395.850412)
			(xy 328.189533 -395.824911) (xy 328.242317 -395.806904) (xy 328.29716 -395.796774) (xy 328.352894 -395.794737)
			(xy 328.408331 -395.800837) (xy 328.462288 -395.814943) (xy 328.513617 -395.836755) (xy 328.561223 -395.865809)
			(xy 328.604091 -395.901484) (xy 328.641308 -395.943021) (xy 328.672081 -395.989534) (xy 328.695753 -396.040031)
			(xy 328.711821 -396.093438) (xy 328.719941 -396.148614) (xy 328.72045 -396.1765) (xy 328.719941 -396.204386)
			(xy 328.711821 -396.259562) (xy 328.695753 -396.312969) (xy 328.672081 -396.363466) (xy 328.641308 -396.409979)
			(xy 328.604091 -396.451516) (xy 328.561223 -396.487191) (xy 328.513617 -396.516245) (xy 328.462288 -396.538057)
			(xy 328.408331 -396.552163) (xy 328.352894 -396.558263) (xy 328.29716 -396.556226) (xy 328.242317 -396.546096)
			(xy 328.189533 -396.528089) (xy 328.139933 -396.502588) (xy 328.094575 -396.470137) (xy 328.054426 -396.431428)
			(xy 328.02034 -396.387285) (xy 327.993044 -396.33865) (xy 327.973121 -396.286559) (xy 327.960995 -396.232122)
			(xy 327.956924 -396.1765) (xy 321.964507 -396.1765) (xy 321.953669 -396.218365) (xy 321.932159 -396.272237)
			(xy 321.90402 -396.322963) (xy 321.869702 -396.36973) (xy 321.829754 -396.411791) (xy 321.807586 -396.4305)
			(xy 321.800728 -396.436088) (xy 321.79133 -396.451582) (xy 321.777614 -396.525242) (xy 321.776446 -396.534001)
			(xy 321.779443 -396.551404) (xy 321.783456 -396.559278) (xy 321.783456 -396.559532) (xy 321.796051 -396.58271)
			(xy 321.81394 -396.63233) (xy 321.823024 -396.684289) (xy 321.823588 -396.710662) (xy 321.823516 -396.72002)
			(xy 321.82237 -396.738702) (xy 321.821302 -396.748) (xy 321.820286 -396.756636) (xy 321.824096 -396.773908)
			(xy 321.867784 -396.84325) (xy 321.881754 -396.853918) (xy 321.890136 -396.856712) (xy 321.91417 -396.865167)
			(xy 321.959349 -396.888715) (xy 322.000159 -396.919214) (xy 322.03554 -396.955871) (xy 322.064574 -396.997735)
			(xy 322.086508 -397.043719) (xy 322.094098 -397.06804) (xy 322.094606 -397.070072) (xy 322.095622 -397.074136)
			(xy 322.415916 -397.627602) (xy 322.41998 -397.63192) (xy 322.436198 -397.649618) (xy 322.463632 -397.689006)
			(xy 322.484781 -397.732097) (xy 322.499155 -397.777896) (xy 322.506422 -397.825343) (xy 322.506848 -397.849344)
			(xy 322.506359 -397.874118) (xy 322.498606 -397.923056) (xy 322.483296 -397.97018) (xy 322.460807 -398.01433)
			(xy 322.431692 -398.054422) (xy 322.396667 -398.089468) (xy 322.356593 -398.118608) (xy 322.312455 -398.141123)
			(xy 322.265341 -398.156461) (xy 322.216408 -398.164244) (xy 322.191634 -398.164812) (xy 322.191126 -398.164812)
			(xy 322.165731 -398.164306) (xy 322.115596 -398.156179) (xy 322.067408 -398.140131) (xy 322.022411 -398.116575)
			(xy 321.981766 -398.086118) (xy 321.946521 -398.049548) (xy 321.917585 -398.007807) (xy 321.895704 -397.961972)
			(xy 321.888104 -397.937736) (xy 321.88658 -397.931894) (xy 321.566032 -397.37792) (xy 321.561206 -397.37284)
			(xy 321.525392 -397.382492) (xy 321.514794 -397.385925) (xy 321.497748 -397.400229) (xy 321.488328 -397.420389)
			(xy 321.4878 -397.431514) (xy 321.4878 -398.229328) (xy 321.504056 -398.254474) (xy 321.51447 -398.259046)
			(xy 321.514978 -398.2593) (xy 321.53817 -398.270007) (xy 321.580938 -398.297933) (xy 321.618521 -398.332524)
			(xy 321.649892 -398.372833) (xy 321.674194 -398.41776) (xy 321.690762 -398.466077) (xy 321.699144 -398.516463)
			(xy 321.699636 -398.542002) (xy 321.699 -398.570306) (xy 321.688686 -398.625967) (xy 321.668403 -398.678818)
			(xy 321.65417 -398.703292) (xy 321.653408 -398.704562) (xy 321.650353 -398.710269) (xy 321.646877 -398.722735)
			(xy 321.64655 -398.7292) (xy 321.64655 -398.736566) (xy 321.696842 -398.825212) (xy 321.701565 -398.832849)
			(xy 321.715234 -398.844476) (xy 321.732067 -398.850697) (xy 321.741038 -398.85112) (xy 322.365878 -398.85112)
			(xy 322.366386 -398.85112) (xy 322.374847 -398.850727) (xy 322.390798 -398.845055) (xy 322.404028 -398.834493)
			(xy 322.408804 -398.827498) (xy 322.409312 -398.826736) (xy 322.45427 -398.751552) (xy 322.455032 -398.750028)
			(xy 322.459407 -398.741171) (xy 322.461744 -398.721574) (xy 322.459604 -398.711928) (xy 322.45808 -398.70634)
			(xy 322.449698 -398.690846) (xy 322.438597 -398.667709) (xy 322.422889 -398.618858) (xy 322.414915 -398.568167)
			(xy 322.414392 -398.54251) (xy 322.414392 -398.542002) (xy 322.414902 -398.516015) (xy 322.423032 -398.46468)
			(xy 322.439093 -398.41525) (xy 322.462689 -398.36894) (xy 322.493239 -398.326892) (xy 322.52999 -398.290141)
			(xy 322.572038 -398.259591) (xy 322.618348 -398.235995) (xy 322.667778 -398.219934) (xy 322.719113 -398.211804)
			(xy 322.771087 -398.211804) (xy 322.822422 -398.219934) (xy 322.871852 -398.235995) (xy 322.918162 -398.259591)
			(xy 322.96021 -398.290141) (xy 322.996961 -398.326892) (xy 323.027511 -398.36894) (xy 323.051107 -398.41525)
			(xy 323.067168 -398.46468) (xy 323.075298 -398.516015) (xy 323.075808 -398.542002) (xy 323.075808 -398.54251)
			(xy 323.075309 -398.568639) (xy 323.067092 -398.620248) (xy 323.050881 -398.669929) (xy 323.027075 -398.71645)
			(xy 323.012054 -398.737836) (xy 323.00672 -398.744948) (xy 323.004688 -398.751552) (xy 323.00354 -398.755324)
			(xy 323.002261 -398.763105) (xy 323.002148 -398.767046) (xy 323.002148 -398.806416) (xy 323.002148 -398.809464)
			(xy 323.002545 -398.813782) (xy 323.004587 -398.822208) (xy 323.006212 -398.826228) (xy 323.036438 -398.889474)
			(xy 323.041116 -398.897176) (xy 323.05476 -398.908928) (xy 323.071631 -398.915224) (xy 323.080634 -398.915636)
			(xy 323.304154 -398.915636) (xy 323.30771 -398.915382) (xy 323.317854 -398.914254) (xy 323.336065 -398.905077)
			(xy 323.343016 -398.897602) (xy 323.34327 -398.897348) (xy 323.343778 -398.896586) (xy 323.393308 -398.834356)
			(xy 323.396715 -398.82981) (xy 323.401584 -398.819548) (xy 323.40296 -398.814036) (xy 323.403468 -398.81175)
			(xy 323.403468 -398.793462) (xy 323.40169 -398.785842) (xy 323.397922 -398.767752) (xy 323.392961 -398.731131)
			(xy 323.391784 -398.71269) (xy 323.391784 -398.712182) (xy 323.391276 -398.691608) (xy 323.391276 -398.686528)
			(xy 323.39143 -398.672072) (xy 323.393338 -398.643221) (xy 323.395086 -398.62887) (xy 323.399835 -398.597057)
			(xy 323.417107 -398.535097) (xy 323.442899 -398.476172) (xy 323.459348 -398.44853) (xy 323.463911 -398.440318)
			(xy 323.467343 -398.421866) (xy 323.463887 -398.403418) (xy 323.459348 -398.39519) (xy 323.443206 -398.368016)
			(xy 323.41774 -398.310169) (xy 323.40049 -398.249364) (xy 323.391784 -398.186762) (xy 323.391276 -398.15516)
			(xy 323.391889 -398.121917) (xy 323.401542 -398.056136) (xy 323.420611 -397.992443) (xy 323.448694 -397.93218)
			(xy 323.485201 -397.876613) (xy 323.506846 -397.851376) (xy 323.5071 -397.851122) (xy 323.512504 -397.844356)
			(xy 323.51886 -397.828259) (xy 323.519546 -397.819626) (xy 323.519546 -397.754602) (xy 323.518784 -397.746728)
			(xy 323.516244 -397.73225) (xy 323.512942 -397.723868) (xy 323.508878 -397.719042) (xy 323.506846 -397.716756)
			(xy 323.485236 -397.691502) (xy 323.448783 -397.635926) (xy 323.420755 -397.57566) (xy 323.401742 -397.511973)
			(xy 323.392143 -397.446205) (xy 323.39153 -397.412972) (xy 323.39207 -397.381181) (xy 323.400859 -397.318209)
			(xy 323.418279 -397.257059) (xy 323.443994 -397.198909) (xy 323.477509 -397.144876) (xy 323.497448 -397.12011)
			(xy 323.498718 -397.118586) (xy 323.503544 -397.112744) (xy 323.506592 -397.104108) (xy 323.507855 -397.100292)
			(xy 323.509265 -397.092378) (xy 323.509386 -397.08836) (xy 323.507862 -397.035528) (xy 323.507354 -397.018764)
			(xy 323.506767 -397.010413) (xy 323.500947 -396.994726) (xy 323.495924 -396.98803) (xy 323.492368 -396.983966)
			(xy 323.491352 -396.98295) (xy 323.472226 -396.961714) (xy 323.438844 -396.915326) (xy 323.411491 -396.865146)
			(xy 323.390592 -396.811953) (xy 323.376473 -396.756573) (xy 323.369353 -396.699867) (xy 323.368924 -396.671292)
			(xy 323.369414 -396.641324) (xy 323.377237 -396.581902) (xy 323.39275 -396.524009) (xy 323.415686 -396.468636)
			(xy 323.445653 -396.41673) (xy 323.48214 -396.36918) (xy 323.52452 -396.3268) (xy 323.57207 -396.290313)
			(xy 323.623976 -396.260346) (xy 323.679349 -396.23741) (xy 323.737242 -396.221897) (xy 323.796664 -396.214074)
			(xy 323.8566 -396.214074) (xy 323.916022 -396.221897) (xy 323.973915 -396.23741) (xy 324.029288 -396.260346)
			(xy 324.081194 -396.290313) (xy 324.128744 -396.3268) (xy 324.171124 -396.36918) (xy 324.207611 -396.41673)
			(xy 324.237578 -396.468636) (xy 324.260514 -396.524009) (xy 324.276027 -396.581902) (xy 324.28385 -396.641324)
			(xy 324.28434 -396.671292) (xy 324.28434 -396.6718) (xy 324.284246 -396.684399) (xy 324.282848 -396.70956)
			(xy 324.281546 -396.722092) (xy 324.276732 -396.758697) (xy 324.256823 -396.82979) (xy 324.241922 -396.86357)
			(xy 324.228971 -396.89045) (xy 324.19712 -396.940903) (xy 324.178422 -396.964154) (xy 324.177406 -396.96517)
			(xy 324.172072 -396.971774) (xy 324.169278 -396.980156) (xy 324.168037 -396.984043) (xy 324.166638 -396.992081)
			(xy 324.166484 -396.996158) (xy 324.1675 -397.029432) (xy 324.168516 -397.065754) (xy 324.169184 -397.074689)
			(xy 324.175804 -397.091325) (xy 324.18147 -397.098266) (xy 324.182232 -397.099028) (xy 324.194729 -397.112546)
			(xy 324.217741 -397.141286) (xy 324.228206 -397.156432) (xy 324.232524 -397.162782) (xy 324.241922 -397.17091)
			(xy 324.25005 -397.174466) (xy 324.255187 -397.176586) (xy 324.266083 -397.178767) (xy 324.27164 -397.178784)
			(xy 324.275704 -397.17853) (xy 324.354444 -397.169386) (xy 324.360286 -397.168116) (xy 324.364858 -397.166338)
			(xy 324.375018 -397.161004) (xy 324.396354 -397.144494) (xy 324.405752 -397.135096) (xy 324.4088 -397.131032)
			(xy 324.411848 -397.124428) (xy 324.411848 -397.124174) (xy 324.423283 -397.098813) (xy 324.452415 -397.05142)
			(xy 324.488117 -397.008756) (xy 324.529632 -396.971725) (xy 324.576081 -396.94111) (xy 324.626482 -396.917561)
			(xy 324.679766 -396.901574) (xy 324.734807 -396.89349) (xy 324.762622 -396.893034) (xy 324.788238 -396.89345)
			(xy 324.839008 -396.900314) (xy 324.888402 -396.913915) (xy 324.935529 -396.934007) (xy 324.979542 -396.96023)
			(xy 324.999858 -396.975838) (xy 325.000112 -396.976092) (xy 325.00189 -396.977616) (xy 325.008416 -396.98192)
			(xy 325.023288 -396.986715) (xy 325.0311 -396.987014) (xy 325.064374 -396.987014) (xy 325.064374 -396.99819)
			(xy 325.115174 -396.99819) (xy 325.119722 -396.998066) (xy 325.128665 -396.996405) (xy 325.132954 -396.994888)
			(xy 325.141336 -396.99184) (xy 325.148448 -396.985744) (xy 325.169325 -396.968352) (xy 325.215076 -396.939036)
			(xy 325.264524 -396.916511) (xy 325.316668 -396.901232) (xy 325.370454 -396.893509) (xy 325.397622 -396.893034)
			(xy 325.397876 -396.893034) (xy 325.422545 -396.893418) (xy 325.471469 -396.899783) (xy 325.495412 -396.905734)
			(xy 325.520625 -396.912899) (xy 325.568954 -396.933187) (xy 325.614058 -396.959888) (xy 325.634858 -396.975838)
			(xy 325.635112 -396.976092) (xy 325.63689 -396.977616) (xy 325.643416 -396.98192) (xy 325.658288 -396.986715)
			(xy 325.6661 -396.987014) (xy 325.699374 -396.987014) (xy 325.699374 -396.99819) (xy 325.750174 -396.99819)
			(xy 325.754722 -396.998066) (xy 325.763665 -396.996405) (xy 325.767954 -396.994888) (xy 325.776336 -396.99184)
			(xy 325.783448 -396.985744) (xy 325.804325 -396.968352) (xy 325.850076 -396.939036) (xy 325.899524 -396.916511)
			(xy 325.951668 -396.901232) (xy 326.005454 -396.893509) (xy 326.032622 -396.893034) (xy 326.059869 -396.893522)
			(xy 326.113809 -396.90128) (xy 326.166095 -396.916635) (xy 326.215664 -396.939275) (xy 326.261506 -396.968739)
			(xy 326.302689 -397.004426) (xy 326.338375 -397.045611) (xy 326.367835 -397.091456) (xy 326.390473 -397.141026)
			(xy 326.40202 -397.180352) (xy 327.740985 -397.180352) (xy 327.740985 -397.125848) (xy 327.748742 -397.071899)
			(xy 327.764099 -397.019603) (xy 327.786741 -396.970025) (xy 327.816209 -396.924175) (xy 327.851903 -396.882984)
			(xy 327.893095 -396.847294) (xy 327.938948 -396.817829) (xy 327.988528 -396.795189) (xy 328.040825 -396.779837)
			(xy 328.094774 -396.772083) (xy 328.122026 -396.771622) (xy 328.149397 -396.772067) (xy 328.203577 -396.779889)
			(xy 328.256081 -396.795383) (xy 328.305827 -396.818229) (xy 328.351793 -396.847959) (xy 328.372724 -396.865602)
			(xy 328.372978 -396.865856) (xy 328.380062 -396.871446) (xy 328.396981 -396.877689) (xy 328.405998 -396.878048)
			(xy 328.473054 -396.878048) (xy 328.48207 -396.87768) (xy 328.498988 -396.871441) (xy 328.506074 -396.865856)
			(xy 328.506074 -396.865602) (xy 328.506328 -396.865602) (xy 328.527277 -396.847984) (xy 328.573245 -396.818269)
			(xy 328.622988 -396.795429) (xy 328.675485 -396.779933) (xy 328.729658 -396.772099) (xy 328.757026 -396.771622)
			(xy 328.784278 -396.77205) (xy 328.838227 -396.77981) (xy 328.890523 -396.795168) (xy 328.940101 -396.817813)
			(xy 328.985952 -396.847282) (xy 329.027142 -396.882976) (xy 329.062834 -396.924169) (xy 329.0923 -396.970022)
			(xy 329.114941 -397.019601) (xy 329.130296 -397.071898) (xy 329.138052 -397.125848) (xy 329.138052 -397.180352)
			(xy 329.130296 -397.234302) (xy 329.114941 -397.286599) (xy 329.0923 -397.336178) (xy 329.062834 -397.382031)
			(xy 329.027142 -397.423224) (xy 328.985952 -397.458918) (xy 328.940101 -397.488387) (xy 328.890523 -397.511032)
			(xy 328.838227 -397.52639) (xy 328.784278 -397.53415) (xy 328.757026 -397.534638) (xy 328.729656 -397.534172)
			(xy 328.675476 -397.526356) (xy 328.622972 -397.510868) (xy 328.573225 -397.488026) (xy 328.527259 -397.4583)
			(xy 328.506328 -397.440658) (xy 328.506074 -397.440404) (xy 328.49897 -397.434843) (xy 328.482067 -397.428581)
			(xy 328.473054 -397.428212) (xy 328.405998 -397.428212) (xy 328.396981 -397.428565) (xy 328.380064 -397.434815)
			(xy 328.372978 -397.440404) (xy 328.372978 -397.440658) (xy 328.372724 -397.440658) (xy 328.351788 -397.458293)
			(xy 328.305817 -397.488007) (xy 328.256071 -397.510844) (xy 328.203571 -397.526336) (xy 328.149395 -397.534164)
			(xy 328.122026 -397.534638) (xy 328.094774 -397.534117) (xy 328.040825 -397.526363) (xy 327.988528 -397.511011)
			(xy 327.938948 -397.488371) (xy 327.893095 -397.458906) (xy 327.851903 -397.423216) (xy 327.816209 -397.382025)
			(xy 327.786741 -397.336175) (xy 327.764099 -397.286597) (xy 327.748742 -397.234301) (xy 327.740985 -397.180352)
			(xy 326.40202 -397.180352) (xy 326.405825 -397.193313) (xy 326.41358 -397.247253) (xy 326.41358 -397.301747)
			(xy 326.405825 -397.355687) (xy 326.390473 -397.407974) (xy 326.367835 -397.457544) (xy 326.338375 -397.503389)
			(xy 326.302689 -397.544574) (xy 326.261506 -397.580261) (xy 326.215664 -397.609725) (xy 326.166095 -397.632365)
			(xy 326.113809 -397.64772) (xy 326.059869 -397.655478) (xy 326.032622 -397.65605) (xy 326.007005 -397.655636)
			(xy 325.956232 -397.648778) (xy 325.906836 -397.635181) (xy 325.859705 -397.615092) (xy 325.815689 -397.588872)
			(xy 325.795386 -397.573246) (xy 325.795132 -397.572992) (xy 325.793354 -397.571468) (xy 325.786825 -397.567172)
			(xy 325.771953 -397.562396) (xy 325.764144 -397.56207) (xy 325.73087 -397.56207) (xy 325.73087 -397.550894)
			(xy 325.68007 -397.550894) (xy 325.675522 -397.551014) (xy 325.666575 -397.552668) (xy 325.66229 -397.554196)
			(xy 325.653908 -397.557244) (xy 325.646796 -397.56334) (xy 325.625918 -397.58073) (xy 325.580167 -397.61004)
			(xy 325.530718 -397.632559) (xy 325.478574 -397.647831) (xy 325.424789 -397.655547) (xy 325.397622 -397.65605)
			(xy 325.397368 -397.65605) (xy 325.3727 -397.655662) (xy 325.323777 -397.64929) (xy 325.299832 -397.64335)
			(xy 325.274617 -397.63619) (xy 325.226282 -397.61591) (xy 325.18117 -397.589217) (xy 325.160386 -397.573246)
			(xy 325.160132 -397.572992) (xy 325.158354 -397.571468) (xy 325.151825 -397.567172) (xy 325.136953 -397.562396)
			(xy 325.129144 -397.56207) (xy 325.09587 -397.56207) (xy 325.09587 -397.550894) (xy 325.04507 -397.550894)
			(xy 325.040522 -397.551014) (xy 325.031575 -397.552668) (xy 325.02729 -397.554196) (xy 325.018908 -397.557244)
			(xy 325.011796 -397.56334) (xy 324.990918 -397.58073) (xy 324.945167 -397.61004) (xy 324.895718 -397.632559)
			(xy 324.843574 -397.647831) (xy 324.789789 -397.655547) (xy 324.762622 -397.65605) (xy 324.73417 -397.655528)
			(xy 324.677895 -397.647094) (xy 324.623492 -397.630408) (xy 324.572166 -397.605839) (xy 324.52505 -397.573931)
			(xy 324.483186 -397.535389) (xy 324.464934 -397.513556) (xy 324.463664 -397.512032) (xy 324.462902 -397.511016)
			(xy 324.4596 -397.507714) (xy 324.450302 -397.499536) (xy 324.42668 -397.49224) (xy 324.414388 -397.493744)
			(xy 324.340474 -397.507968) (xy 324.33376 -397.509478) (xy 324.321409 -397.515538) (xy 324.31609 -397.519906)
			(xy 324.292722 -397.540734) (xy 324.28561 -397.55191) (xy 324.283578 -397.558006) (xy 324.273334 -397.587093)
			(xy 324.246123 -397.642433) (xy 324.211725 -397.693617) (xy 324.19163 -397.71701) (xy 324.191376 -397.717264)
			(xy 324.18528 -397.724122) (xy 324.181978 -397.732758) (xy 324.180438 -397.737106) (xy 324.178784 -397.74618)
			(xy 324.178676 -397.750792) (xy 324.178676 -397.817848) (xy 324.179067 -397.827039) (xy 324.185584 -397.844228)
			(xy 324.191376 -397.851376) (xy 324.212989 -397.876629) (xy 324.249449 -397.932204) (xy 324.277484 -397.99247)
			(xy 324.296506 -398.056157) (xy 324.306113 -398.121926) (xy 324.306692 -398.15516) (xy 324.306138 -398.186758)
			(xy 324.297409 -398.24935) (xy 324.280167 -398.31015) (xy 324.254737 -398.368005) (xy 324.23862 -398.39519)
			(xy 324.234044 -398.403403) (xy 324.230587 -398.421866) (xy 324.234019 -398.440333) (xy 324.23862 -398.44853)
			(xy 324.25467 -398.475536) (xy 324.280024 -398.533015) (xy 324.297266 -398.593425) (xy 324.30607 -398.655627)
			(xy 324.306692 -398.687036) (xy 324.306692 -398.690846) (xy 324.306293 -398.714849) (xy 324.301069 -398.762573)
			(xy 324.296278 -398.786096) (xy 324.296024 -398.786858) (xy 324.29577 -398.787874) (xy 324.295008 -398.791176)
			(xy 324.294246 -398.794732) (xy 324.293172 -398.80456) (xy 324.297759 -398.823771) (xy 324.303136 -398.83207)
			(xy 324.353936 -398.896332) (xy 324.358449 -398.901571) (xy 324.369654 -398.909664) (xy 324.376034 -398.912334)
			(xy 324.38467 -398.915636) (xy 325.16572 -398.915636) (xy 325.167752 -398.913604) (xy 326.24776 -397.833596)
			(xy 326.26545 -397.816597) (xy 326.305143 -397.787767) (xy 326.348853 -397.765493) (xy 326.395507 -397.750321)
			(xy 326.443957 -397.742623) (xy 326.468486 -397.742156) (xy 329.606402 -397.742156) (xy 329.613211 -397.741938)
			(xy 329.626344 -397.738333) (xy 329.63231 -397.735044) (xy 329.633072 -397.734536) (xy 329.634342 -397.733774)
			(xy 329.636628 -397.73225) (xy 329.639613 -397.730066) (xy 329.644969 -397.724965) (xy 329.647296 -397.72209)
			(xy 329.70343 -397.643858) (xy 329.705208 -397.631666) (xy 329.706986 -397.619728) (xy 329.704446 -397.611346)
			(xy 329.694399 -397.580757) (xy 329.683548 -397.517298) (xy 329.682856 -397.485108) (xy 329.683325 -397.457774)
			(xy 329.691128 -397.403665) (xy 329.706576 -397.351225) (xy 329.729352 -397.301527) (xy 329.75899 -397.25559)
			(xy 329.776582 -397.234664) (xy 329.777852 -397.233394) (xy 329.782352 -397.227432) (xy 329.788021 -397.213619)
			(xy 329.789028 -397.206216) (xy 329.789282 -397.20139) (xy 329.789282 -397.133826) (xy 329.789028 -397.129)
			(xy 329.788062 -397.121587) (xy 329.782386 -397.107765) (xy 329.777852 -397.101822) (xy 329.776582 -397.100552)
			(xy 329.758993 -397.079625) (xy 329.72936 -397.033686) (xy 329.706588 -396.983988) (xy 329.691142 -396.931548)
			(xy 329.683339 -396.877441) (xy 329.682856 -396.850108) (xy 329.682856 -396.849854) (xy 329.683108 -396.831575)
			(xy 329.686671 -396.795191) (xy 329.689968 -396.77721) (xy 329.692508 -396.765018) (xy 329.692508 -396.76451)
			(xy 329.694087 -396.755582) (xy 329.691604 -396.737634) (xy 329.687682 -396.729458) (xy 329.674982 -396.705582)
			(xy 329.674982 -396.705074) (xy 329.655932 -396.670022) (xy 329.653706 -396.666054) (xy 329.648078 -396.658907)
			(xy 329.644756 -396.655798) (xy 329.63866 -396.650464) (xy 329.629516 -396.646908) (xy 329.600986 -396.635557)
			(xy 329.546646 -396.606966) (xy 329.496143 -396.57204) (xy 329.450213 -396.531287) (xy 329.409524 -396.485301)
			(xy 329.374668 -396.43475) (xy 329.346153 -396.380369) (xy 329.324393 -396.322951) (xy 329.309705 -396.263331)
			(xy 329.302303 -396.202375) (xy 329.301856 -396.171674) (xy 329.301935 -396.158952) (xy 329.303206 -396.13354)
			(xy 329.304396 -396.120874) (xy 329.304142 -396.120874) (xy 329.307596 -396.091001) (xy 329.320644 -396.032296)
			(xy 329.340531 -395.975541) (xy 329.366978 -395.921531) (xy 329.399616 -395.871021) (xy 329.418442 -395.84757)
			(xy 329.421859 -395.842842) (xy 329.426611 -395.83219) (xy 329.42784 -395.826488) (xy 329.428856 -395.816836)
			(xy 329.428856 -395.662912) (xy 329.428765 -395.658502) (xy 329.427225 -395.649818) (xy 329.425808 -395.64564)
			(xy 329.423014 -395.637766) (xy 329.41895 -395.63294) (xy 329.417172 -395.630654) (xy 329.39546 -395.603255)
			(xy 329.358961 -395.543631) (xy 329.330971 -395.479571) (xy 329.312019 -395.41228) (xy 329.302462 -395.343028)
			(xy 329.301856 -395.308074) (xy 329.302321 -395.277343) (xy 329.309732 -395.21633) (xy 329.324443 -395.156655)
			(xy 329.346239 -395.099188) (xy 329.374802 -395.044767) (xy 329.409716 -394.994185) (xy 329.450473 -394.94818)
			(xy 329.496477 -394.907423) (xy 329.547058 -394.872507) (xy 329.601479 -394.843943) (xy 329.658945 -394.822146)
			(xy 329.71862 -394.807434) (xy 329.779633 -394.800022) (xy 329.810364 -394.799566) (xy 329.810872 -394.799566)
			(xy 329.854814 -394.801344) (xy 329.8571 -394.801598) (xy 329.861926 -394.801598) (xy 329.870206 -394.801276)
			(xy 329.885887 -394.795958) (xy 329.89266 -394.791184) (xy 329.947016 -394.749274) (xy 329.95082 -394.746277)
			(xy 329.957343 -394.739119) (xy 329.95997 -394.73505) (xy 329.964542 -394.727176) (xy 329.965812 -394.71981)
			(xy 329.96632 -394.717524) (xy 329.96632 -394.71727) (xy 329.971313 -394.691027) (xy 329.98767 -394.640174)
			(xy 330.010961 -394.592099) (xy 330.040729 -394.547743) (xy 330.076393 -394.507972) (xy 330.117256 -394.473565)
			(xy 330.162518 -394.445194) (xy 330.211296 -394.423413) (xy 330.262634 -394.408648) (xy 330.31553 -394.401189)
			(xy 330.34224 -394.400786) (xy 330.36949 -394.401275) (xy 330.423433 -394.409036) (xy 330.475724 -394.424394)
			(xy 330.525296 -394.447037) (xy 330.571142 -394.476505) (xy 330.612328 -394.512196) (xy 330.648016 -394.553385)
			(xy 330.677479 -394.599234) (xy 330.700118 -394.648808) (xy 330.715472 -394.7011) (xy 330.723228 -394.755044)
			(xy 330.723748 -394.782294) (xy 330.723283 -394.809246) (xy 330.715696 -394.862612) (xy 330.700671 -394.914379)
			(xy 330.678507 -394.963515) (xy 330.649648 -395.009042) (xy 330.614666 -395.050052) (xy 330.574259 -395.085729)
			(xy 330.529232 -395.115363) (xy 330.480482 -395.138362) (xy 330.428979 -395.154269) (xy 330.402438 -395.158976)
			(xy 330.399136 -395.159484) (xy 330.392278 -395.1605) (xy 330.384404 -395.165326) (xy 330.380445 -395.167795)
			(xy 330.373412 -395.173926) (xy 330.370434 -395.177518) (xy 330.328016 -395.232128) (xy 330.323078 -395.238971)
			(xy 330.317633 -395.254935) (xy 330.317348 -395.26337) (xy 330.317348 -395.263624) (xy 330.317602 -395.266926)
			(xy 330.318618 -395.285976) (xy 330.318618 -395.286484) (xy 330.319126 -395.308074) (xy 330.318545 -395.343064)
			(xy 330.308955 -395.412383) (xy 330.289952 -395.479734) (xy 330.261895 -395.543843) (xy 330.225315 -395.6035)
			(xy 330.203556 -395.630908) (xy 330.197714 -395.63802) (xy 330.19492 -395.64564) (xy 330.193509 -395.649819)
			(xy 330.191973 -395.658503) (xy 330.191872 -395.662912) (xy 330.191872 -395.816836) (xy 330.192147 -395.824564)
			(xy 330.196817 -395.839297) (xy 330.201016 -395.845792) (xy 330.203556 -395.84884) (xy 330.225304 -395.876253)
			(xy 330.26187 -395.935915) (xy 330.289916 -396.000024) (xy 330.308914 -396.067371) (xy 330.318506 -396.136686)
			(xy 330.319126 -396.171674) (xy 330.318872 -396.171928) (xy 330.318872 -396.18031) (xy 330.317978 -396.209747)
			(xy 330.310243 -396.268132) (xy 330.295825 -396.325236) (xy 330.274917 -396.380295) (xy 330.261722 -396.406624)
			(xy 330.258928 -396.411958) (xy 330.256642 -396.421102) (xy 330.252832 -396.435834) (xy 330.254102 -396.446756)
			(xy 330.268834 -396.511526) (xy 330.269999 -396.515983) (xy 330.273712 -396.524413) (xy 330.2762 -396.52829)
			(xy 330.28128 -396.536164) (xy 330.288646 -396.541498) (xy 330.309178 -396.556942) (xy 330.346303 -396.592455)
			(xy 330.378328 -396.632629) (xy 330.404671 -396.676738) (xy 330.405925 -396.679674) (xy 332.336392 -396.679674)
			(xy 332.340463 -396.624052) (xy 332.352589 -396.569615) (xy 332.372512 -396.517524) (xy 332.399808 -396.468889)
			(xy 332.433894 -396.424746) (xy 332.474043 -396.386037) (xy 332.519401 -396.353586) (xy 332.569001 -396.328085)
			(xy 332.621785 -396.310078) (xy 332.676628 -396.299948) (xy 332.732362 -396.297911) (xy 332.787799 -396.304011)
			(xy 332.841756 -396.318117) (xy 332.893085 -396.339929) (xy 332.940691 -396.368983) (xy 332.983559 -396.404658)
			(xy 333.020776 -396.446195) (xy 333.051549 -396.492708) (xy 333.075221 -396.543205) (xy 333.091289 -396.596612)
			(xy 333.099409 -396.651788) (xy 333.099918 -396.679674) (xy 333.099471 -396.704137) (xy 333.302358 -396.704137)
			(xy 333.302358 -396.652163) (xy 333.310488 -396.600828) (xy 333.326549 -396.551398) (xy 333.350145 -396.505088)
			(xy 333.380695 -396.46304) (xy 333.417446 -396.426289) (xy 333.459494 -396.395739) (xy 333.505804 -396.372143)
			(xy 333.555234 -396.356082) (xy 333.606569 -396.347952) (xy 333.658543 -396.347952) (xy 333.709878 -396.356082)
			(xy 333.759308 -396.372143) (xy 333.805618 -396.395739) (xy 333.847666 -396.426289) (xy 333.884417 -396.46304)
			(xy 333.914967 -396.505088) (xy 333.938563 -396.551398) (xy 333.954624 -396.600828) (xy 333.962754 -396.652163)
			(xy 333.963264 -396.67815) (xy 333.962754 -396.704137) (xy 333.954624 -396.755472) (xy 333.938563 -396.804902)
			(xy 333.914967 -396.851212) (xy 333.884417 -396.89326) (xy 333.847666 -396.930011) (xy 333.805618 -396.960561)
			(xy 333.759308 -396.984157) (xy 333.709878 -397.000218) (xy 333.658543 -397.008348) (xy 333.606569 -397.008348)
			(xy 333.555234 -397.000218) (xy 333.505804 -396.984157) (xy 333.459494 -396.960561) (xy 333.417446 -396.930011)
			(xy 333.380695 -396.89326) (xy 333.350145 -396.851212) (xy 333.326549 -396.804902) (xy 333.310488 -396.755472)
			(xy 333.302358 -396.704137) (xy 333.099471 -396.704137) (xy 333.099409 -396.70756) (xy 333.091289 -396.762736)
			(xy 333.075221 -396.816143) (xy 333.051549 -396.86664) (xy 333.020776 -396.913153) (xy 332.983559 -396.95469)
			(xy 332.940691 -396.990365) (xy 332.893085 -397.019419) (xy 332.841756 -397.041231) (xy 332.787799 -397.055337)
			(xy 332.732362 -397.061437) (xy 332.676628 -397.0594) (xy 332.621785 -397.04927) (xy 332.569001 -397.031263)
			(xy 332.519401 -397.005762) (xy 332.474043 -396.973311) (xy 332.433894 -396.934602) (xy 332.399808 -396.890459)
			(xy 332.372512 -396.841824) (xy 332.352589 -396.789733) (xy 332.340463 -396.735296) (xy 332.336392 -396.679674)
			(xy 330.405925 -396.679674) (xy 330.424857 -396.723982) (xy 330.43852 -396.773508) (xy 330.445413 -396.82442)
			(xy 330.445872 -396.850108) (xy 330.445402 -396.877442) (xy 330.437597 -396.93155) (xy 330.422148 -396.983989)
			(xy 330.399372 -397.033686) (xy 330.369735 -397.079623) (xy 330.352146 -397.100552) (xy 330.350876 -397.101822)
			(xy 330.346364 -397.10778) (xy 330.34067 -397.121591) (xy 330.3397 -397.129) (xy 330.339446 -397.133826)
			(xy 330.339446 -397.20139) (xy 330.3397 -397.206216) (xy 330.340669 -397.213628) (xy 330.346351 -397.227444)
			(xy 330.350876 -397.233394) (xy 330.352146 -397.234664) (xy 330.369733 -397.255592) (xy 330.399361 -397.301532)
			(xy 330.42213 -397.35123) (xy 330.437572 -397.403669) (xy 330.445373 -397.457775) (xy 330.445872 -397.485108)
			(xy 330.445205 -397.517767) (xy 330.434096 -397.582132) (xy 330.423774 -397.613124) (xy 330.422504 -397.624808)
			(xy 330.42352 -397.631412) (xy 330.424224 -397.635717) (xy 330.426913 -397.644015) (xy 330.428854 -397.647922)
			(xy 330.429108 -397.64843) (xy 330.43241 -397.654018) (xy 330.480416 -397.72082) (xy 330.485355 -397.727261)
			(xy 330.498437 -397.736857) (xy 330.50607 -397.739616) (xy 330.513944 -397.742156) (xy 331.606652 -397.742156)
			(xy 331.63052 -397.742551) (xy 331.677715 -397.749698) (xy 331.700632 -397.75638) (xy 331.711427 -397.759901)
			(xy 331.73253 -397.768292) (xy 331.742796 -397.773144) (xy 331.74559 -397.774414) (xy 331.750098 -397.776143)
			(xy 331.75956 -397.77806) (xy 331.764386 -397.778224) (xy 333.201772 -397.778224) (xy 333.211424 -397.777208)
			(xy 333.218671 -397.775585) (xy 333.231849 -397.768753) (xy 333.237332 -397.763746) (xy 334.640174 -396.360904)
			(xy 334.647576 -396.354069) (xy 334.666175 -396.346361) (xy 334.676242 -396.345918) (xy 335.512918 -396.345918)
			(xy 335.522366 -396.345434) (xy 335.539965 -396.338539) (xy 335.547208 -396.332456) (xy 335.55305 -396.326106)
			(xy 335.553558 -396.325598) (xy 335.602072 -396.259304) (xy 335.608272 -396.249933) (xy 335.61261 -396.227915)
			(xy 335.610454 -396.216886) (xy 335.609438 -396.212822) (xy 335.609184 -396.21206) (xy 335.599473 -396.178799)
			(xy 335.589021 -396.110305) (xy 335.588356 -396.075662) (xy 335.588356 -396.075154) (xy 335.588926 -396.0429)
			(xy 335.598023 -395.979037) (xy 335.616002 -395.917085) (xy 335.628742 -395.887448) (xy 335.630774 -395.88313)
			(xy 335.633492 -395.873685) (xy 335.632311 -395.854085) (xy 335.628488 -395.84503) (xy 335.622138 -395.831314)
			(xy 335.618836 -395.826996) (xy 335.609184 -395.814296) (xy 335.605628 -395.811248) (xy 335.581404 -395.789415)
			(xy 335.538774 -395.740064) (xy 335.503589 -395.685157) (xy 335.476561 -395.625809) (xy 335.458238 -395.563223)
			(xy 335.448993 -395.498669) (xy 335.448402 -395.466062) (xy 335.448825 -395.437766) (xy 335.455801 -395.381607)
			(xy 335.469641 -395.326734) (xy 335.490134 -395.273984) (xy 335.51697 -395.22416) (xy 335.549738 -395.178021)
			(xy 335.58794 -395.136269) (xy 335.609184 -395.117574) (xy 335.616042 -395.111732) (xy 335.634076 -395.080236)
			(xy 335.635346 -395.07033) (xy 335.638394 -395.04874) (xy 335.638394 -395.047978) (xy 335.639097 -395.039748)
			(xy 335.635844 -395.023563) (xy 335.632044 -395.016228) (xy 335.63052 -395.013688) (xy 335.630266 -395.013434)
			(xy 335.61731 -394.993039) (xy 335.596809 -394.949287) (xy 335.582887 -394.90302) (xy 335.575839 -394.85522)
			(xy 335.575402 -394.831062) (xy 335.575402 -394.822934) (xy 335.576276 -394.801421) (xy 335.5829 -394.758878)
			(xy 335.594977 -394.717551) (xy 335.603342 -394.697712) (xy 335.605374 -394.692886) (xy 335.608168 -394.680694)
			(xy 335.609184 -394.668502) (xy 335.607406 -394.656056) (xy 335.606136 -394.651992) (xy 335.584546 -394.594588)
			(xy 335.582514 -394.589508) (xy 335.580779 -394.586181) (xy 335.576443 -394.580056) (xy 335.573878 -394.577316)
			(xy 335.555336 -394.558774) (xy 335.551272 -394.556742) (xy 335.547462 -394.554964) (xy 335.523942 -394.542918)
			(xy 335.480732 -394.512504) (xy 335.442901 -394.475612) (xy 335.41141 -394.43318) (xy 335.38706 -394.386285)
			(xy 335.370467 -394.336117) (xy 335.362053 -394.28395) (xy 335.361534 -394.25753) (xy 335.362015 -394.23154)
			(xy 335.370143 -394.180201) (xy 335.386203 -394.130765) (xy 335.4098 -394.08445) (xy 335.440352 -394.042398)
			(xy 335.477108 -394.005644) (xy 335.519161 -393.975093) (xy 335.565476 -393.951498) (xy 335.614912 -393.93544)
			(xy 335.666252 -393.927314) (xy 335.692242 -393.926822) (xy 335.69275 -393.926822) (xy 335.706468 -393.926978)
			(xy 335.733807 -393.92927) (xy 335.74736 -393.931394) (xy 335.751678 -393.932156) (xy 335.772252 -393.932156)
			(xy 335.779538 -393.931585) (xy 335.793339 -393.926798) (xy 335.79943 -393.922758) (xy 335.801716 -393.92098)
			(xy 335.805272 -393.917932) (xy 335.849468 -393.871196) (xy 335.863946 -393.855956) (xy 335.868307 -393.851087)
			(xy 335.874611 -393.83964) (xy 335.876392 -393.83335) (xy 335.877916 -393.827) (xy 335.877916 -393.814808)
			(xy 335.876138 -393.808204) (xy 335.871579 -393.789981) (xy 335.865096 -393.752977) (xy 335.863184 -393.73429)
			(xy 335.861914 -393.722606) (xy 335.860898 -393.69238) (xy 335.861445 -393.661485) (xy 335.869829 -393.600264)
			(xy 335.886361 -393.540725) (xy 335.910741 -393.483946) (xy 335.926176 -393.457176) (xy 335.926176 -393.456668)
			(xy 335.92643 -393.456414) (xy 335.929093 -393.451704) (xy 335.932554 -393.441455) (xy 335.933288 -393.436094)
			(xy 335.934304 -393.425172) (xy 335.90484 -393.34059) (xy 335.900662 -393.330311) (xy 335.885255 -393.314377)
			(xy 335.875122 -393.309856) (xy 335.872836 -393.30884) (xy 335.869026 -393.30757) (xy 335.867248 -393.306808)
			(xy 335.866994 -393.306808) (xy 335.865216 -393.306046) (xy 335.842702 -393.296401) (xy 335.800562 -393.271444)
			(xy 335.762563 -393.240543) (xy 335.729538 -393.204376) (xy 335.70221 -393.163732) (xy 335.681175 -393.119502)
			(xy 335.666896 -393.072653) (xy 335.659683 -393.024211) (xy 335.659222 -392.999722) (xy 335.659732 -392.973735)
			(xy 335.667862 -392.9224) (xy 335.683923 -392.87297) (xy 335.707519 -392.82666) (xy 335.738069 -392.784612)
			(xy 335.77482 -392.747861) (xy 335.816868 -392.717311) (xy 335.863178 -392.693715) (xy 335.912608 -392.677654)
			(xy 335.963943 -392.669524) (xy 336.015917 -392.669524) (xy 336.067252 -392.677654) (xy 336.116682 -392.693715)
			(xy 336.162992 -392.717311) (xy 336.20504 -392.747861) (xy 336.241791 -392.784612) (xy 336.272341 -392.82666)
			(xy 336.295937 -392.87297) (xy 336.311998 -392.9224) (xy 336.320128 -392.973735) (xy 336.320638 -392.999722)
			(xy 336.320638 -393.000484) (xy 336.32015 -393.026518) (xy 336.311979 -393.07794) (xy 336.304382 -393.102846)
			(xy 336.303112 -393.106656) (xy 336.301588 -393.11453) (xy 336.300893 -393.119145) (xy 336.301025 -393.128477)
			(xy 336.301842 -393.133072) (xy 336.30362 -393.142216) (xy 336.308446 -393.15009) (xy 336.347816 -393.215114)
			(xy 336.348324 -393.21613) (xy 336.356452 -393.225782) (xy 336.359525 -393.228563) (xy 336.36642 -393.233157)
			(xy 336.370168 -393.234926) (xy 336.377788 -393.238482) (xy 336.3849 -393.239498) (xy 336.413842 -393.244198)
			(xy 336.470304 -393.260012) (xy 336.524286 -393.282904) (xy 336.574903 -393.3125) (xy 336.621329 -393.348315)
			(xy 336.662802 -393.389764) (xy 336.698645 -393.436168) (xy 336.728272 -393.486768) (xy 336.751196 -393.540735)
			(xy 336.767044 -393.597188) (xy 336.775556 -393.655202) (xy 336.776568 -393.684506) (xy 336.776568 -393.692634)
			(xy 336.776118 -393.721986) (xy 336.7686 -393.780208) (xy 336.761582 -393.808712) (xy 336.761074 -393.81049)
			(xy 336.761074 -393.810998) (xy 336.759804 -393.815062) (xy 336.759042 -393.817348) (xy 336.757336 -393.826563)
			(xy 336.760078 -393.845088) (xy 336.764376 -393.853416) (xy 336.76463 -393.853924) (xy 336.796634 -393.909296)
			(xy 336.799251 -393.913596) (xy 336.805901 -393.921151) (xy 336.809842 -393.924282) (xy 336.832956 -393.941808)
			(xy 336.842354 -393.944602) (xy 336.870829 -393.953074) (xy 336.925479 -393.976374) (xy 336.976655 -394.006548)
			(xy 337.023499 -394.043089) (xy 337.065221 -394.085382) (xy 337.101122 -394.132718) (xy 337.130597 -394.1843)
			(xy 337.153152 -394.239261) (xy 337.168407 -394.296679) (xy 337.176107 -394.355587) (xy 337.176618 -394.385292)
			(xy 337.176511 -394.399554) (xy 337.174735 -394.428024) (xy 337.173062 -394.442188) (xy 337.171792 -394.451586)
			(xy 337.173824 -394.459968) (xy 337.174911 -394.464058) (xy 337.178235 -394.471842) (xy 337.180428 -394.475462)
			(xy 337.192112 -394.493496) (xy 337.198462 -394.501624) (xy 337.202526 -394.505434) (xy 337.221322 -394.520928)
			(xy 337.225894 -394.522706) (xy 337.228942 -394.523976) (xy 337.251623 -394.533541) (xy 337.294105 -394.558405)
			(xy 337.332431 -394.589294) (xy 337.365753 -394.625523) (xy 337.393334 -394.666293) (xy 337.414566 -394.710701)
			(xy 337.428979 -394.757767) (xy 337.436254 -394.80645) (xy 337.436714 -394.831062) (xy 337.436281 -394.85518)
			(xy 337.429285 -394.902905) (xy 337.415437 -394.949109) (xy 337.39503 -394.992815) (xy 337.382104 -395.01318)
			(xy 337.37804 -395.01953) (xy 337.373722 -395.0335) (xy 337.373722 -395.045438) (xy 337.37423 -395.05255)
			(xy 337.37677 -395.07033) (xy 337.37804 -395.080236) (xy 337.396074 -395.111732) (xy 337.402932 -395.117574)
			(xy 337.424189 -395.136255) (xy 337.462396 -395.178004) (xy 337.495165 -395.224143) (xy 337.521997 -395.273971)
			(xy 337.542482 -395.326725) (xy 337.556308 -395.381603) (xy 337.563264 -395.437766) (xy 337.563714 -395.466062)
			(xy 337.563714 -395.46657) (xy 337.563142 -395.498823) (xy 337.554041 -395.562685) (xy 337.536058 -395.624635)
			(xy 337.523328 -395.654276) (xy 337.521296 -395.658594) (xy 337.518583 -395.668039) (xy 337.519773 -395.687634)
			(xy 337.523582 -395.696694) (xy 337.529932 -395.71041) (xy 337.533234 -395.714728) (xy 337.542886 -395.727428)
			(xy 337.546442 -395.730476) (xy 337.570667 -395.75231) (xy 337.613298 -395.801661) (xy 337.648488 -395.856567)
			(xy 337.675521 -395.915914) (xy 337.693851 -395.9785) (xy 337.703105 -396.043055) (xy 337.703668 -396.075662)
			(xy 337.702994 -396.110769) (xy 337.692278 -396.180162) (xy 337.682332 -396.213838) (xy 337.681316 -396.216886)
			(xy 337.679265 -396.227469) (xy 337.683218 -396.248641) (xy 337.688936 -396.25778) (xy 337.689698 -396.25905)
			(xy 337.738212 -396.32509) (xy 337.738974 -396.326106) (xy 337.739482 -396.326614) (xy 337.747008 -396.335289)
			(xy 337.767636 -396.345338) (xy 337.779106 -396.345918) (xy 337.912964 -396.345918) (xy 337.922408 -396.345426)
			(xy 337.939996 -396.33852) (xy 337.947254 -396.332456) (xy 337.953096 -396.326106) (xy 337.953604 -396.325598)
			(xy 338.002118 -396.259304) (xy 338.008323 -396.249934) (xy 338.012666 -396.227914) (xy 338.0105 -396.216886)
			(xy 338.009484 -396.212822) (xy 338.00923 -396.21206) (xy 337.999518 -396.178799) (xy 337.989065 -396.110305)
			(xy 337.988402 -396.075662) (xy 337.988402 -396.075154) (xy 337.988973 -396.0429) (xy 337.99807 -395.979037)
			(xy 338.016051 -395.917086) (xy 338.028788 -395.887448) (xy 338.03082 -395.88313) (xy 338.033537 -395.873685)
			(xy 338.032356 -395.854085) (xy 338.028534 -395.84503) (xy 338.022184 -395.831314) (xy 338.018882 -395.826996)
			(xy 338.00923 -395.814296) (xy 338.005674 -395.811248) (xy 337.981452 -395.789413) (xy 337.938828 -395.740061)
			(xy 337.903646 -395.685153) (xy 337.876621 -395.625806) (xy 337.858301 -395.563221) (xy 337.849057 -395.498668)
			(xy 337.848448 -395.466062) (xy 337.848871 -395.437766) (xy 337.855846 -395.381605) (xy 337.869685 -395.326732)
			(xy 337.890177 -395.27398) (xy 337.91701 -395.224154) (xy 337.949775 -395.178012) (xy 337.987975 -395.136257)
			(xy 338.00923 -395.117574) (xy 338.016088 -395.111732) (xy 338.034122 -395.080236) (xy 338.035392 -395.07033)
			(xy 338.03844 -395.04874) (xy 338.03844 -395.048486) (xy 338.03971 -395.039088) (xy 338.035646 -395.021562)
			(xy 338.03463 -395.019784) (xy 338.030566 -395.013688) (xy 338.016799 -394.992132) (xy 337.99536 -394.945695)
			(xy 337.987894 -394.921232) (xy 337.983068 -394.902182) (xy 337.983068 -394.901928) (xy 337.981036 -394.893292)
			(xy 337.976972 -394.886434) (xy 337.97461 -394.882789) (xy 337.968866 -394.876275) (xy 337.965542 -394.87348)
			(xy 337.949032 -394.860018) (xy 337.942174 -394.854176) (xy 337.91144 -394.843) (xy 337.903312 -394.842746)
			(xy 337.874023 -394.841286) (xy 337.816146 -394.831831) (xy 337.759951 -394.815062) (xy 337.706358 -394.791252)
			(xy 337.656246 -394.760791) (xy 337.610435 -394.724179) (xy 337.569675 -394.682015) (xy 337.534635 -394.634991)
			(xy 337.505889 -394.583876) (xy 337.483907 -394.529508) (xy 337.469049 -394.472778) (xy 337.46156 -394.414614)
			(xy 337.461098 -394.385292) (xy 337.461098 -394.385038) (xy 337.461098 -394.384022) (xy 337.461566 -394.355522)
			(xy 337.4687 -394.29897) (xy 337.475322 -394.271246) (xy 337.476084 -394.268452) (xy 337.477862 -394.255752)
			(xy 337.477862 -394.245846) (xy 337.477643 -394.239242) (xy 337.474172 -394.226498) (xy 337.471004 -394.2207)
			(xy 337.441032 -394.168376) (xy 337.438411 -394.164079) (xy 337.431757 -394.15653) (xy 337.427824 -394.15339)
			(xy 337.40471 -394.135864) (xy 337.395312 -394.13307) (xy 337.366835 -394.124601) (xy 337.31218 -394.101305)
			(xy 337.260999 -394.071135) (xy 337.214151 -394.034596) (xy 337.172425 -393.992302) (xy 337.136521 -393.944966)
			(xy 337.107044 -393.893382) (xy 337.084488 -393.838418) (xy 337.069234 -393.780997) (xy 337.061536 -393.722086)
			(xy 337.061048 -393.69238) (xy 337.061048 -393.679934) (xy 337.062329 -393.650621) (xy 337.071437 -393.592658)
			(xy 337.087878 -393.536335) (xy 337.111384 -393.482575) (xy 337.126072 -393.457176) (xy 337.126072 -393.456668)
			(xy 337.126326 -393.456414) (xy 337.12899 -393.451704) (xy 337.132451 -393.441455) (xy 337.133184 -393.436094)
			(xy 337.1342 -393.425172) (xy 337.104736 -393.34059) (xy 337.100557 -393.330312) (xy 337.08515 -393.314379)
			(xy 337.075018 -393.309856) (xy 337.072732 -393.30884) (xy 337.068922 -393.30757) (xy 337.067144 -393.306808)
			(xy 337.06689 -393.306808) (xy 337.065112 -393.306046) (xy 337.042599 -393.296401) (xy 337.000458 -393.271443)
			(xy 336.96246 -393.240543) (xy 336.929436 -393.204375) (xy 336.902108 -393.163732) (xy 336.881074 -393.119502)
			(xy 336.866794 -393.072653) (xy 336.859581 -393.02421) (xy 336.859118 -392.999722) (xy 336.859628 -392.973735)
			(xy 336.867758 -392.9224) (xy 336.883819 -392.87297) (xy 336.907415 -392.82666) (xy 336.937965 -392.784612)
			(xy 336.974716 -392.747861) (xy 337.016764 -392.717311) (xy 337.063074 -392.693715) (xy 337.112504 -392.677654)
			(xy 337.163839 -392.669524) (xy 337.215813 -392.669524) (xy 337.267148 -392.677654) (xy 337.316578 -392.693715)
			(xy 337.362888 -392.717311) (xy 337.404936 -392.747861) (xy 337.441687 -392.784612) (xy 337.472237 -392.82666)
			(xy 337.495833 -392.87297) (xy 337.511894 -392.9224) (xy 337.520024 -392.973735) (xy 337.520534 -392.999722)
			(xy 337.520534 -393.000484) (xy 337.520046 -393.026518) (xy 337.511875 -393.07794) (xy 337.504278 -393.102846)
			(xy 337.503008 -393.106656) (xy 337.501484 -393.11453) (xy 337.500789 -393.119145) (xy 337.500921 -393.128477)
			(xy 337.501738 -393.133072) (xy 337.503516 -393.142216) (xy 337.508342 -393.15009) (xy 337.547712 -393.215114)
			(xy 337.54822 -393.21613) (xy 337.556348 -393.225782) (xy 337.559421 -393.228563) (xy 337.566316 -393.233158)
			(xy 337.570064 -393.234926) (xy 337.577684 -393.238482) (xy 337.584796 -393.239498) (xy 337.613738 -393.244198)
			(xy 337.670201 -393.260012) (xy 337.724183 -393.282904) (xy 337.774801 -393.312499) (xy 337.821226 -393.348314)
			(xy 337.8627 -393.389763) (xy 337.898544 -393.436167) (xy 337.928171 -393.486767) (xy 337.951095 -393.540735)
			(xy 337.966943 -393.597188) (xy 337.975455 -393.655202) (xy 337.976464 -393.684506) (xy 337.976464 -393.692634)
			(xy 337.976014 -393.721986) (xy 337.968496 -393.780207) (xy 337.961478 -393.808712) (xy 337.96097 -393.81049)
			(xy 337.96097 -393.810998) (xy 337.9597 -393.815062) (xy 337.958938 -393.817348) (xy 337.957232 -393.826563)
			(xy 337.959974 -393.845088) (xy 337.964272 -393.853416) (xy 337.964526 -393.853924) (xy 337.99653 -393.909296)
			(xy 337.999147 -393.913596) (xy 338.005796 -393.921152) (xy 338.009738 -393.924282) (xy 338.032852 -393.941808)
			(xy 338.04225 -393.944602) (xy 338.070725 -393.953074) (xy 338.125375 -393.976374) (xy 338.176552 -394.006547)
			(xy 338.223396 -394.043088) (xy 338.265119 -394.085381) (xy 338.30102 -394.132717) (xy 338.330496 -394.184299)
			(xy 338.353051 -394.239261) (xy 338.368306 -394.296678) (xy 338.376006 -394.355587) (xy 338.376514 -394.385292)
			(xy 338.376399 -394.399491) (xy 338.37462 -394.427832) (xy 338.372958 -394.441934) (xy 338.372512 -394.446456)
			(xy 338.373018 -394.455526) (xy 338.373974 -394.459968) (xy 338.375752 -394.467842) (xy 338.380324 -394.475208)
			(xy 338.395818 -394.5001) (xy 338.40052 -394.507168) (xy 338.413624 -394.517947) (xy 338.421472 -394.521182)
			(xy 338.444841 -394.530383) (xy 338.488713 -394.554825) (xy 338.528387 -394.585617) (xy 338.562952 -394.622051)
			(xy 338.591612 -394.663292) (xy 338.613709 -394.70839) (xy 338.628737 -394.75631) (xy 338.636348 -394.805952)
			(xy 338.636864 -394.831062) (xy 338.636431 -394.855179) (xy 338.629434 -394.902904) (xy 338.615584 -394.949108)
			(xy 338.595174 -394.992811) (xy 338.582254 -395.01318) (xy 338.57819 -395.01953) (xy 338.573872 -395.0335)
			(xy 338.573872 -395.045438) (xy 338.57438 -395.05255) (xy 338.57692 -395.07033) (xy 338.57819 -395.080236)
			(xy 338.596224 -395.111732) (xy 338.603082 -395.117574) (xy 338.624341 -395.136254) (xy 338.662552 -395.178001)
			(xy 338.695325 -395.22414) (xy 338.722159 -395.273967) (xy 338.742647 -395.326722) (xy 338.756475 -395.3816)
			(xy 338.763432 -395.437765) (xy 338.763864 -395.466062) (xy 338.763864 -395.46657) (xy 338.763292 -395.498823)
			(xy 338.754193 -395.562686) (xy 338.736212 -395.624637) (xy 338.723478 -395.654276) (xy 338.721446 -395.658594)
			(xy 338.718735 -395.668039) (xy 338.719923 -395.687634) (xy 338.723732 -395.696694) (xy 338.730082 -395.71041)
			(xy 338.733384 -395.714728) (xy 338.743036 -395.727428) (xy 338.746592 -395.730476) (xy 338.770819 -395.752309)
			(xy 338.813455 -395.801658) (xy 338.848648 -395.856563) (xy 338.875685 -395.915911) (xy 338.894017 -395.978498)
			(xy 338.903272 -396.043054) (xy 338.903818 -396.075662) (xy 338.903144 -396.11077) (xy 338.892429 -396.180162)
			(xy 338.882482 -396.213838) (xy 338.881466 -396.216886) (xy 338.879414 -396.227468) (xy 338.883371 -396.248639)
			(xy 338.889086 -396.25778) (xy 338.889848 -396.25905) (xy 338.938362 -396.32509) (xy 338.939124 -396.326106)
			(xy 338.939632 -396.326614) (xy 338.947155 -396.335297) (xy 338.967782 -396.345366) (xy 338.979256 -396.345918)
			(xy 339.11286 -396.345918) (xy 339.122305 -396.345427) (xy 339.139894 -396.338521) (xy 339.14715 -396.332456)
			(xy 339.152992 -396.326106) (xy 339.1535 -396.325598) (xy 339.202014 -396.259304) (xy 339.208219 -396.249934)
			(xy 339.212562 -396.227914) (xy 339.210396 -396.216886) (xy 339.20938 -396.212822) (xy 339.209126 -396.21206)
			(xy 339.199414 -396.178799) (xy 339.188961 -396.110305) (xy 339.188298 -396.075662) (xy 339.188298 -396.075154)
			(xy 339.188869 -396.0429) (xy 339.197966 -395.979037) (xy 339.215947 -395.917086) (xy 339.228684 -395.887448)
			(xy 339.230716 -395.88313) (xy 339.233433 -395.873685) (xy 339.232252 -395.854085) (xy 339.22843 -395.84503)
			(xy 339.22208 -395.831314) (xy 339.218778 -395.826996) (xy 339.209126 -395.814296) (xy 339.20557 -395.811248)
			(xy 339.181348 -395.789413) (xy 339.138724 -395.74006) (xy 339.103543 -395.685153) (xy 339.076519 -395.625805)
			(xy 339.058198 -395.56322) (xy 339.048954 -395.498668) (xy 339.048344 -395.466062) (xy 339.048767 -395.437766)
			(xy 339.055742 -395.381605) (xy 339.069581 -395.326731) (xy 339.090072 -395.27398) (xy 339.116905 -395.224153)
			(xy 339.149671 -395.178011) (xy 339.18787 -395.136256) (xy 339.209126 -395.117574) (xy 339.215984 -395.111732)
			(xy 339.234018 -395.080236) (xy 339.235288 -395.07033) (xy 339.238336 -395.04874) (xy 339.238336 -395.048486)
			(xy 339.239606 -395.039088) (xy 339.235542 -395.021562) (xy 339.234526 -395.019784) (xy 339.230462 -395.013688)
			(xy 339.216695 -394.992132) (xy 339.195257 -394.945695) (xy 339.18779 -394.921232) (xy 339.182964 -394.902182)
			(xy 339.182964 -394.901928) (xy 339.180932 -394.893292) (xy 339.176868 -394.886434) (xy 339.174506 -394.882789)
			(xy 339.168762 -394.876275) (xy 339.165438 -394.87348) (xy 339.148928 -394.860018) (xy 339.14207 -394.854176)
			(xy 339.111336 -394.843) (xy 339.103208 -394.842746) (xy 339.073919 -394.841286) (xy 339.016043 -394.831831)
			(xy 338.959848 -394.815061) (xy 338.906256 -394.79125) (xy 338.856144 -394.76079) (xy 338.810333 -394.724178)
			(xy 338.769574 -394.682014) (xy 338.734534 -394.63499) (xy 338.705788 -394.583875) (xy 338.683806 -394.529507)
			(xy 338.668949 -394.472777) (xy 338.661459 -394.414614) (xy 338.660994 -394.385292) (xy 338.660994 -394.384784)
			(xy 338.660994 -394.383768) (xy 338.66146 -394.355268) (xy 338.668593 -394.298715) (xy 338.675218 -394.270992)
			(xy 338.67598 -394.268198) (xy 338.677758 -394.255498) (xy 338.677758 -394.245338) (xy 338.6776 -394.240653)
			(xy 338.675809 -394.231453) (xy 338.674202 -394.22705) (xy 338.671154 -394.220192) (xy 338.660994 -394.202666)
			(xy 338.635848 -394.159232) (xy 338.633225 -394.154937) (xy 338.626568 -394.147392) (xy 338.62264 -394.144246)
			(xy 338.614766 -394.13815) (xy 338.604606 -394.13561) (xy 338.575497 -394.127604) (xy 338.519528 -394.104975)
			(xy 338.46702 -394.075184) (xy 338.418883 -394.038748) (xy 338.375955 -393.996301) (xy 338.338979 -393.948578)
			(xy 338.308598 -393.896409) (xy 338.285339 -393.840698) (xy 338.269606 -393.782413) (xy 338.261672 -393.722566)
			(xy 338.261198 -393.69238) (xy 338.261198 -393.679934) (xy 338.262479 -393.650621) (xy 338.271588 -393.592659)
			(xy 338.288031 -393.536337) (xy 338.311538 -393.482578) (xy 338.326222 -393.457176) (xy 338.326222 -393.456668)
			(xy 338.326476 -393.456414) (xy 338.329142 -393.451705) (xy 338.332607 -393.441456) (xy 338.333334 -393.436094)
			(xy 338.33435 -393.425172) (xy 338.304886 -393.34059) (xy 338.300704 -393.330316) (xy 338.28529 -393.314397)
			(xy 338.275168 -393.309856) (xy 338.272882 -393.30884) (xy 338.269072 -393.30757) (xy 338.267294 -393.306808)
			(xy 338.26704 -393.306808) (xy 338.265262 -393.306046) (xy 338.242746 -393.296404) (xy 338.2006 -393.271449)
			(xy 338.162596 -393.240551) (xy 338.129567 -393.204384) (xy 338.102234 -393.16374) (xy 338.081196 -393.119508)
			(xy 338.066914 -393.072657) (xy 338.0597 -393.024212) (xy 338.059268 -392.999722) (xy 338.059778 -392.973735)
			(xy 338.067908 -392.9224) (xy 338.083969 -392.87297) (xy 338.107565 -392.82666) (xy 338.138115 -392.784612)
			(xy 338.174866 -392.747861) (xy 338.216914 -392.717311) (xy 338.263224 -392.693715) (xy 338.312654 -392.677654)
			(xy 338.363989 -392.669524) (xy 338.415963 -392.669524) (xy 338.467298 -392.677654) (xy 338.516728 -392.693715)
			(xy 338.563038 -392.717311) (xy 338.605086 -392.747861) (xy 338.641837 -392.784612) (xy 338.672387 -392.82666)
			(xy 338.695983 -392.87297) (xy 338.712044 -392.9224) (xy 338.720174 -392.973735) (xy 338.720684 -392.999722)
			(xy 338.720684 -393.000484) (xy 338.720196 -393.026518) (xy 338.712024 -393.07794) (xy 338.704428 -393.102846)
			(xy 338.703158 -393.106656) (xy 338.701634 -393.11453) (xy 338.700939 -393.119145) (xy 338.701071 -393.128477)
			(xy 338.701888 -393.133072) (xy 338.703666 -393.142216) (xy 338.708492 -393.15009) (xy 338.747862 -393.215114)
			(xy 338.74837 -393.21613) (xy 338.756498 -393.225782) (xy 338.759569 -393.228565) (xy 338.766461 -393.233167)
			(xy 338.770214 -393.234926) (xy 338.777834 -393.238482) (xy 338.781136 -393.23899) (xy 338.784946 -393.239498)
			(xy 338.81389 -393.244196) (xy 338.870358 -393.260004) (xy 338.924345 -393.282893) (xy 338.974968 -393.312486)
			(xy 339.021399 -393.3483) (xy 339.062878 -393.389749) (xy 339.098726 -393.436154) (xy 339.128357 -393.486755)
			(xy 339.151285 -393.540726) (xy 339.167135 -393.597182) (xy 339.175648 -393.655199) (xy 339.176614 -393.684506)
			(xy 339.176614 -393.692634) (xy 339.176164 -393.721986) (xy 339.168645 -393.780207) (xy 339.161628 -393.808712)
			(xy 339.16112 -393.81049) (xy 339.16112 -393.810998) (xy 339.15985 -393.815062) (xy 339.159088 -393.817348)
			(xy 339.157383 -393.826563) (xy 339.160122 -393.845089) (xy 339.164422 -393.853416) (xy 339.164676 -393.853924)
			(xy 339.19668 -393.909296) (xy 339.199299 -393.913594) (xy 339.205952 -393.921145) (xy 339.209888 -393.924282)
			(xy 339.233002 -393.941808) (xy 339.23986 -393.94384) (xy 339.242654 -393.944602) (xy 339.271106 -393.953092)
			(xy 339.325706 -393.976422) (xy 339.37683 -394.006618) (xy 339.423619 -394.043174) (xy 339.465286 -394.085474)
			(xy 339.501131 -394.132809) (xy 339.530553 -394.184383) (xy 339.553056 -394.239329) (xy 339.568264 -394.296724)
			(xy 339.575919 -394.355604) (xy 339.57641 -394.385292) (xy 339.576295 -394.399491) (xy 339.574516 -394.427832)
			(xy 339.572854 -394.441934) (xy 339.572408 -394.446456) (xy 339.572914 -394.455526) (xy 339.57387 -394.459968)
			(xy 339.575648 -394.467842) (xy 339.58022 -394.475208) (xy 339.595714 -394.5001) (xy 339.600422 -394.50716)
			(xy 339.613535 -394.517916) (xy 339.621368 -394.521182) (xy 339.644737 -394.530383) (xy 339.68861 -394.554824)
			(xy 339.728285 -394.585616) (xy 339.762849 -394.62205) (xy 339.79151 -394.663291) (xy 339.813608 -394.70839)
			(xy 339.828635 -394.75631) (xy 339.836247 -394.805951) (xy 339.83676 -394.831062) (xy 339.836327 -394.855179)
			(xy 339.82933 -394.902904) (xy 339.81548 -394.949107) (xy 339.79507 -394.992811) (xy 339.78215 -395.01318)
			(xy 339.778086 -395.01953) (xy 339.773768 -395.0335) (xy 339.773768 -395.045438) (xy 339.774276 -395.05255)
			(xy 339.776816 -395.07033) (xy 339.778086 -395.080236) (xy 339.79612 -395.111732) (xy 339.802978 -395.117574)
			(xy 339.824233 -395.136256) (xy 339.862436 -395.178006) (xy 339.895202 -395.224147) (xy 339.922031 -395.273974)
			(xy 339.942514 -395.326728) (xy 339.956339 -395.381604) (xy 339.963294 -395.437766) (xy 339.96376 -395.466062)
			(xy 339.96376 -395.46657) (xy 339.963188 -395.498823) (xy 339.954089 -395.562686) (xy 339.936107 -395.624637)
			(xy 339.923374 -395.654276) (xy 339.921342 -395.658594) (xy 339.918631 -395.668039) (xy 339.919819 -395.687634)
			(xy 339.923628 -395.696694) (xy 339.929978 -395.71041) (xy 339.93328 -395.714728) (xy 339.942932 -395.727428)
			(xy 339.946488 -395.730476) (xy 339.970715 -395.752309) (xy 340.013352 -395.801658) (xy 340.048545 -395.856563)
			(xy 340.075582 -395.915911) (xy 340.093914 -395.978498) (xy 340.10317 -396.043054) (xy 340.103714 -396.075662)
			(xy 340.10304 -396.11077) (xy 340.092325 -396.180162) (xy 340.082378 -396.213838) (xy 340.081362 -396.216886)
			(xy 340.07931 -396.227468) (xy 340.083267 -396.248639) (xy 340.088982 -396.25778) (xy 340.089744 -396.25905)
			(xy 340.138258 -396.32509) (xy 340.13902 -396.326106) (xy 340.139528 -396.326614) (xy 340.147051 -396.335298)
			(xy 340.167678 -396.345369) (xy 340.179152 -396.345918) (xy 340.312756 -396.345918) (xy 340.322201 -396.345427)
			(xy 340.339791 -396.338523) (xy 340.347046 -396.332456) (xy 340.352888 -396.326106) (xy 340.353396 -396.325598)
			(xy 340.40191 -396.259304) (xy 340.408115 -396.249934) (xy 340.412459 -396.227914) (xy 340.410292 -396.216886)
			(xy 340.409276 -396.212822) (xy 340.409022 -396.21206) (xy 340.39931 -396.178799) (xy 340.388857 -396.110305)
			(xy 340.388194 -396.075662) (xy 340.388194 -396.075154) (xy 340.388765 -396.0429) (xy 340.397862 -395.979037)
			(xy 340.415843 -395.917086) (xy 340.42858 -395.887448) (xy 340.430612 -395.88313) (xy 340.433329 -395.873685)
			(xy 340.432148 -395.854085) (xy 340.428326 -395.84503) (xy 340.421976 -395.831314) (xy 340.418674 -395.826996)
			(xy 340.409022 -395.814296) (xy 340.405466 -395.811248) (xy 340.381245 -395.789413) (xy 340.338621 -395.74006)
			(xy 340.30344 -395.685153) (xy 340.276416 -395.625805) (xy 340.258096 -395.56322) (xy 340.248852 -395.498668)
			(xy 340.24824 -395.466062) (xy 340.248663 -395.437766) (xy 340.255638 -395.381605) (xy 340.269476 -395.326731)
			(xy 340.289968 -395.273979) (xy 340.316801 -395.224153) (xy 340.349566 -395.178011) (xy 340.387765 -395.136255)
			(xy 340.409022 -395.117574) (xy 340.41588 -395.111732) (xy 340.433914 -395.080236) (xy 340.435184 -395.07033)
			(xy 340.438232 -395.04874) (xy 340.438232 -395.048486) (xy 340.439502 -395.039088) (xy 340.435438 -395.021562)
			(xy 340.434422 -395.019784) (xy 340.430358 -395.013688) (xy 340.416591 -394.992131) (xy 340.395153 -394.945695)
			(xy 340.387686 -394.921232) (xy 340.38286 -394.901928) (xy 340.381082 -394.893546) (xy 340.376764 -394.886434)
			(xy 340.374416 -394.882722) (xy 340.368677 -394.876075) (xy 340.365334 -394.873226) (xy 340.348824 -394.859764)
			(xy 340.341712 -394.854176) (xy 340.311486 -394.843) (xy 340.303104 -394.842746) (xy 340.273824 -394.841273)
			(xy 340.215967 -394.831797) (xy 340.159794 -394.815011) (xy 340.106224 -394.791189) (xy 340.056135 -394.760722)
			(xy 340.010347 -394.724108) (xy 339.969608 -394.681947) (xy 339.934587 -394.634929) (xy 339.905856 -394.583824)
			(xy 339.883886 -394.529469) (xy 339.869037 -394.472753) (xy 339.861552 -394.414606) (xy 339.861144 -394.385292)
			(xy 339.861144 -394.385038) (xy 339.861144 -394.384022) (xy 339.861612 -394.355522) (xy 339.868746 -394.29897)
			(xy 339.875368 -394.271246) (xy 339.87613 -394.268452) (xy 339.877908 -394.255752) (xy 339.877908 -394.245846)
			(xy 339.877688 -394.239243) (xy 339.874214 -394.2265) (xy 339.87105 -394.2207) (xy 339.841078 -394.168376)
			(xy 339.838459 -394.164077) (xy 339.831809 -394.156524) (xy 339.82787 -394.15339) (xy 339.804756 -394.135864)
			(xy 339.795358 -394.13307) (xy 339.766883 -394.124598) (xy 339.712234 -394.101298) (xy 339.661058 -394.071125)
			(xy 339.614216 -394.034584) (xy 339.572495 -393.99229) (xy 339.536596 -393.944954) (xy 339.507123 -393.893372)
			(xy 339.48457 -393.83841) (xy 339.469318 -393.780993) (xy 339.461622 -393.722084) (xy 339.461094 -393.69238)
			(xy 339.461094 -393.679934) (xy 339.462375 -393.650621) (xy 339.471484 -393.592659) (xy 339.487926 -393.536337)
			(xy 339.511434 -393.482578) (xy 339.526118 -393.457176) (xy 339.526118 -393.456668) (xy 339.526372 -393.456414)
			(xy 339.529038 -393.451705) (xy 339.532503 -393.441456) (xy 339.53323 -393.436094) (xy 339.534246 -393.425172)
			(xy 339.504782 -393.34059) (xy 339.5006 -393.330316) (xy 339.485186 -393.314398) (xy 339.475064 -393.309856)
			(xy 339.472778 -393.30884) (xy 339.468968 -393.30757) (xy 339.46719 -393.306808) (xy 339.466936 -393.306808)
			(xy 339.465158 -393.306046) (xy 339.442642 -393.296403) (xy 339.400497 -393.271449) (xy 339.362493 -393.24055)
			(xy 339.329464 -393.204383) (xy 339.302132 -393.163739) (xy 339.281095 -393.119508) (xy 339.266813 -393.072657)
			(xy 339.259599 -393.024212) (xy 339.259164 -392.999722) (xy 339.259674 -392.973735) (xy 339.267804 -392.9224)
			(xy 339.283865 -392.87297) (xy 339.307461 -392.82666) (xy 339.338011 -392.784612) (xy 339.374762 -392.747861)
			(xy 339.41681 -392.717311) (xy 339.46312 -392.693715) (xy 339.51255 -392.677654) (xy 339.563885 -392.669524)
			(xy 339.615859 -392.669524) (xy 339.667194 -392.677654) (xy 339.716624 -392.693715) (xy 339.762934 -392.717311)
			(xy 339.804982 -392.747861) (xy 339.841733 -392.784612) (xy 339.872283 -392.82666) (xy 339.895879 -392.87297)
			(xy 339.91194 -392.9224) (xy 339.92007 -392.973735) (xy 339.92058 -392.999722) (xy 339.92058 -393.000484)
			(xy 339.920092 -393.026518) (xy 339.91192 -393.07794) (xy 339.904324 -393.102846) (xy 339.903054 -393.106656)
			(xy 339.90153 -393.11453) (xy 339.900835 -393.119145) (xy 339.900967 -393.128477) (xy 339.901784 -393.133072)
			(xy 339.903562 -393.142216) (xy 339.908388 -393.15009) (xy 339.947758 -393.215114) (xy 339.948266 -393.21613)
			(xy 339.956394 -393.225782) (xy 339.959468 -393.22856) (xy 339.966366 -393.23315) (xy 339.97011 -393.234926)
			(xy 339.97773 -393.238482) (xy 339.981032 -393.23899) (xy 339.984842 -393.239498) (xy 340.013787 -393.244195)
			(xy 340.070254 -393.260004) (xy 340.124242 -393.282892) (xy 340.174866 -393.312485) (xy 340.221297 -393.348299)
			(xy 340.262777 -393.389748) (xy 340.298625 -393.436153) (xy 340.328256 -393.486755) (xy 340.351184 -393.540725)
			(xy 340.367034 -393.597181) (xy 340.375547 -393.655199) (xy 340.37651 -393.684506) (xy 340.37651 -393.692634)
			(xy 340.37606 -393.721986) (xy 340.368541 -393.780207) (xy 340.361524 -393.808712) (xy 340.361016 -393.81049)
			(xy 340.361016 -393.810998) (xy 340.359746 -393.815062) (xy 340.358984 -393.817348) (xy 340.357279 -393.826563)
			(xy 340.360018 -393.845089) (xy 340.364318 -393.853416) (xy 340.364572 -393.853924) (xy 340.396576 -393.909296)
			(xy 340.399195 -393.913594) (xy 340.405848 -393.921145) (xy 340.409784 -393.924282) (xy 340.432898 -393.941808)
			(xy 340.442296 -393.944602) (xy 340.470774 -393.953071) (xy 340.525429 -393.976367) (xy 340.576612 -394.006537)
			(xy 340.623461 -394.043076) (xy 340.665189 -394.085369) (xy 340.701095 -394.132705) (xy 340.730574 -394.184289)
			(xy 340.753133 -394.239253) (xy 340.76839 -394.296674) (xy 340.776091 -394.355586) (xy 340.77656 -394.385292)
			(xy 340.776453 -394.399554) (xy 340.774676 -394.428024) (xy 340.773004 -394.442188) (xy 340.771734 -394.451586)
			(xy 340.773766 -394.459968) (xy 340.774852 -394.464059) (xy 340.778172 -394.471844) (xy 340.78037 -394.475462)
			(xy 340.792054 -394.493496) (xy 340.798404 -394.501624) (xy 340.802468 -394.505434) (xy 340.821264 -394.520928)
			(xy 340.825836 -394.522706) (xy 340.828884 -394.523976) (xy 340.851568 -394.533539) (xy 340.894057 -394.558398)
			(xy 340.932389 -394.589284) (xy 340.965717 -394.625513) (xy 340.993304 -394.666283) (xy 341.01454 -394.710694)
			(xy 341.028956 -394.757762) (xy 341.036232 -394.806448) (xy 341.036656 -394.831062) (xy 341.036223 -394.855179)
			(xy 341.029226 -394.902904) (xy 341.015376 -394.949107) (xy 340.994966 -394.992811) (xy 340.982046 -395.01318)
			(xy 340.977982 -395.01953) (xy 340.973664 -395.0335) (xy 340.973664 -395.045438) (xy 340.974172 -395.05255)
			(xy 340.976712 -395.07033) (xy 340.977982 -395.080236) (xy 340.996016 -395.111732) (xy 341.002874 -395.117574)
			(xy 341.024129 -395.136256) (xy 341.062333 -395.178006) (xy 341.095099 -395.224146) (xy 341.121928 -395.273974)
			(xy 341.142411 -395.326728) (xy 341.156236 -395.381604) (xy 341.163191 -395.437766) (xy 341.163656 -395.466062)
			(xy 341.163656 -395.46657) (xy 341.163084 -395.498823) (xy 341.153984 -395.562686) (xy 341.136003 -395.624637)
			(xy 341.12327 -395.654276) (xy 341.121238 -395.658594) (xy 341.118524 -395.668038) (xy 341.119714 -395.687634)
			(xy 341.123524 -395.696694) (xy 341.129874 -395.71041) (xy 341.133176 -395.714728) (xy 341.142828 -395.727428)
			(xy 341.146384 -395.730476) (xy 341.170612 -395.752308) (xy 341.213248 -395.801657) (xy 341.248442 -395.856563)
			(xy 341.275479 -395.91591) (xy 341.293812 -395.978497) (xy 341.303067 -396.043054) (xy 341.30361 -396.075662)
			(xy 341.302936 -396.11077) (xy 341.292221 -396.180162) (xy 341.282274 -396.213838) (xy 341.281258 -396.216886)
			(xy 341.279206 -396.227468) (xy 341.283163 -396.248639) (xy 341.288878 -396.25778) (xy 341.28964 -396.25905)
			(xy 341.338154 -396.32509) (xy 341.338916 -396.326106) (xy 341.339424 -396.326614) (xy 341.346947 -396.335299)
			(xy 341.367573 -396.345371) (xy 341.379048 -396.345918) (xy 341.512906 -396.345918) (xy 341.522355 -396.345436)
			(xy 341.539956 -396.338544) (xy 341.547196 -396.332456) (xy 341.553038 -396.326106) (xy 341.553546 -396.325598)
			(xy 341.60206 -396.259304) (xy 341.60826 -396.249933) (xy 341.6126 -396.227915) (xy 341.610442 -396.216886)
			(xy 341.609426 -396.212822) (xy 341.609172 -396.21206) (xy 341.599461 -396.178799) (xy 341.589009 -396.110305)
			(xy 341.588344 -396.075662) (xy 341.588344 -396.075154) (xy 341.588914 -396.0429) (xy 341.598011 -395.979037)
			(xy 341.615989 -395.917084) (xy 341.62873 -395.887448) (xy 341.630762 -395.88313) (xy 341.633481 -395.873685)
			(xy 341.632299 -395.854085) (xy 341.628476 -395.84503) (xy 341.622126 -395.831314) (xy 341.618824 -395.826996)
			(xy 341.609172 -395.814296) (xy 341.605616 -395.811248) (xy 341.581392 -395.789414) (xy 341.538764 -395.740063)
			(xy 341.503579 -395.685157) (xy 341.476552 -395.625808) (xy 341.45823 -395.563223) (xy 341.448985 -395.498669)
			(xy 341.44839 -395.466062) (xy 341.448813 -395.437766) (xy 341.455788 -395.381606) (xy 341.469628 -395.326733)
			(xy 341.490122 -395.273983) (xy 341.516956 -395.224158) (xy 341.549724 -395.178019) (xy 341.587925 -395.136266)
			(xy 341.609172 -395.117574) (xy 341.61603 -395.111732) (xy 341.634064 -395.080236) (xy 341.635334 -395.07033)
			(xy 341.638382 -395.04874) (xy 341.638382 -395.048486) (xy 341.639652 -395.039088) (xy 341.635588 -395.021562)
			(xy 341.634572 -395.019784) (xy 341.630508 -395.013688) (xy 341.616739 -394.992132) (xy 341.595298 -394.945697)
			(xy 341.587836 -394.921232) (xy 341.58301 -394.902182) (xy 341.58301 -394.901928) (xy 341.580978 -394.893292)
			(xy 341.576914 -394.886434) (xy 341.57455 -394.882791) (xy 341.568802 -394.876282) (xy 341.565484 -394.87348)
			(xy 341.548974 -394.860018) (xy 341.542116 -394.854176) (xy 341.511382 -394.843) (xy 341.503254 -394.842746)
			(xy 341.473963 -394.841288) (xy 341.416082 -394.831838) (xy 341.359883 -394.815072) (xy 341.306285 -394.791264)
			(xy 341.256168 -394.760805) (xy 341.210353 -394.724193) (xy 341.169589 -394.682029) (xy 341.134545 -394.635003)
			(xy 341.105795 -394.583887) (xy 341.083811 -394.529516) (xy 341.068952 -394.472782) (xy 341.061461 -394.414616)
			(xy 341.06104 -394.385292) (xy 341.06104 -394.385038) (xy 341.06104 -394.384022) (xy 341.061508 -394.355522)
			(xy 341.068642 -394.29897) (xy 341.075264 -394.271246) (xy 341.076026 -394.268452) (xy 341.077804 -394.255752)
			(xy 341.077804 -394.245846) (xy 341.077584 -394.239243) (xy 341.07411 -394.2265) (xy 341.070946 -394.2207)
			(xy 341.040974 -394.168376) (xy 341.038355 -394.164078) (xy 341.031704 -394.156524) (xy 341.027766 -394.15339)
			(xy 341.004652 -394.135864) (xy 340.995254 -394.13307) (xy 340.967169 -394.124711) (xy 340.913225 -394.101823)
			(xy 340.862642 -394.07224) (xy 340.816245 -394.036448) (xy 340.774794 -393.995029) (xy 340.738964 -393.948661)
			(xy 340.709341 -393.898101) (xy 340.68641 -393.844176) (xy 340.670544 -393.787766) (xy 340.662004 -393.729794)
			(xy 340.66099 -393.700508) (xy 340.66099 -393.691872) (xy 340.661516 -393.661016) (xy 340.669845 -393.599867)
			(xy 340.686308 -393.54039) (xy 340.710606 -393.483662) (xy 340.726014 -393.456922) (xy 340.726014 -393.456668)
			(xy 340.726268 -393.456414) (xy 340.731124 -393.447087) (xy 340.733633 -393.426231) (xy 340.731094 -393.416028)
			(xy 340.72195 -393.389612) (xy 340.704932 -393.340844) (xy 340.703154 -393.336526) (xy 340.699228 -393.328781)
			(xy 340.68714 -393.316332) (xy 340.679532 -393.312142) (xy 340.675214 -393.31011) (xy 340.672928 -393.309094)
			(xy 340.649714 -393.299797) (xy 340.60616 -393.275229) (xy 340.566796 -393.244392) (xy 340.532516 -393.207986)
			(xy 340.504099 -393.16684) (xy 340.482193 -393.121889) (xy 340.467294 -393.074156) (xy 340.459742 -393.024724)
			(xy 340.459314 -392.999722) (xy 340.459824 -392.973735) (xy 340.467954 -392.9224) (xy 340.484015 -392.87297)
			(xy 340.507611 -392.82666) (xy 340.538161 -392.784612) (xy 340.574912 -392.747861) (xy 340.61696 -392.717311)
			(xy 340.66327 -392.693715) (xy 340.7127 -392.677654) (xy 340.764035 -392.669524) (xy 340.816009 -392.669524)
			(xy 340.867344 -392.677654) (xy 340.916774 -392.693715) (xy 340.963084 -392.717311) (xy 341.005132 -392.747861)
			(xy 341.041883 -392.784612) (xy 341.072433 -392.82666) (xy 341.096029 -392.87297) (xy 341.11209 -392.9224)
			(xy 341.12022 -392.973735) (xy 341.12073 -392.999722) (xy 341.12073 -393.00023) (xy 341.120128 -393.027278)
			(xy 341.111193 -393.080634) (xy 341.10295 -393.106402) (xy 341.099394 -393.11707) (xy 341.10041 -393.127738)
			(xy 341.10113 -393.133457) (xy 341.104839 -393.144369) (xy 341.107776 -393.149328) (xy 341.128096 -393.182348)
			(xy 341.14867 -393.215876) (xy 341.151672 -393.220576) (xy 341.15936 -393.228652) (xy 341.16391 -393.231878)
			(xy 341.173054 -393.23772) (xy 341.182452 -393.239244) (xy 341.184738 -393.239498) (xy 341.212118 -393.243905)
			(xy 341.265627 -393.258483) (xy 341.316985 -393.279413) (xy 341.365443 -393.306386) (xy 341.410291 -393.33901)
			(xy 341.430864 -393.357608) (xy 341.452941 -393.378871) (xy 341.491788 -393.426285) (xy 341.523962 -393.478457)
			(xy 341.54889 -393.534454) (xy 341.566126 -393.593276) (xy 341.575361 -393.653872) (xy 341.576406 -393.684506)
			(xy 341.576406 -393.692634) (xy 341.575956 -393.721986) (xy 341.568437 -393.780207) (xy 341.56142 -393.808712)
			(xy 341.560912 -393.81049) (xy 341.560912 -393.810998) (xy 341.559642 -393.815062) (xy 341.55888 -393.817348)
			(xy 341.557232 -393.826565) (xy 341.559968 -393.845071) (xy 341.564214 -393.853416) (xy 341.564468 -393.853924)
			(xy 341.596472 -393.909296) (xy 341.599091 -393.913594) (xy 341.605743 -393.921146) (xy 341.60968 -393.924282)
			(xy 341.632794 -393.941808) (xy 341.642192 -393.944602) (xy 341.67067 -393.953071) (xy 341.725326 -393.976366)
			(xy 341.776509 -394.006537) (xy 341.823358 -394.043075) (xy 341.865087 -394.085368) (xy 341.900993 -394.132704)
			(xy 341.930473 -394.184288) (xy 341.953031 -394.239252) (xy 341.968289 -394.296673) (xy 341.97599 -394.355585)
			(xy 341.976456 -394.385292) (xy 341.976341 -394.399491) (xy 341.974563 -394.427832) (xy 341.9729 -394.441934)
			(xy 341.972454 -394.446456) (xy 341.97296 -394.455526) (xy 341.973916 -394.459968) (xy 341.975694 -394.467842)
			(xy 341.980266 -394.475208) (xy 341.99576 -394.5001) (xy 342.000465 -394.507164) (xy 342.013573 -394.517933)
			(xy 342.021414 -394.521182) (xy 342.044786 -394.53038) (xy 342.088665 -394.554817) (xy 342.128346 -394.585606)
			(xy 342.162917 -394.62204) (xy 342.191582 -394.663281) (xy 342.213684 -394.708382) (xy 342.228715 -394.756305)
			(xy 342.236328 -394.80595) (xy 342.236806 -394.831062) (xy 342.236373 -394.85518) (xy 342.229377 -394.902905)
			(xy 342.215529 -394.949109) (xy 342.195121 -394.992814) (xy 342.182196 -395.01318) (xy 342.178132 -395.01953)
			(xy 342.173814 -395.0335) (xy 342.173814 -395.045438) (xy 342.174322 -395.05255) (xy 342.176862 -395.07033)
			(xy 342.178132 -395.080236) (xy 342.196166 -395.111732) (xy 342.203024 -395.117574) (xy 342.224281 -395.136255)
			(xy 342.262489 -395.178003) (xy 342.295259 -395.224143) (xy 342.322091 -395.27397) (xy 342.342576 -395.326725)
			(xy 342.356403 -395.381602) (xy 342.363359 -395.437766) (xy 342.363806 -395.466062) (xy 342.363806 -395.46657)
			(xy 342.363234 -395.498823) (xy 342.354133 -395.562685) (xy 342.33615 -395.624635) (xy 342.32342 -395.654276)
			(xy 342.321388 -395.658594) (xy 342.318675 -395.668039) (xy 342.319865 -395.687634) (xy 342.323674 -395.696694)
			(xy 342.330024 -395.71041) (xy 342.333326 -395.714728) (xy 342.342978 -395.727428) (xy 342.346534 -395.730476)
			(xy 342.370759 -395.75231) (xy 342.413391 -395.80166) (xy 342.448581 -395.856566) (xy 342.475615 -395.915914)
			(xy 342.493946 -395.9785) (xy 342.5032 -396.043054) (xy 342.50376 -396.075662) (xy 342.503086 -396.110769)
			(xy 342.49237 -396.180162) (xy 342.482424 -396.213838) (xy 342.481408 -396.216886) (xy 342.479357 -396.227469)
			(xy 342.48331 -396.248641) (xy 342.489028 -396.25778) (xy 342.48979 -396.25905) (xy 342.538304 -396.32509)
			(xy 342.539066 -396.326106) (xy 342.539574 -396.326614) (xy 342.5471 -396.33529) (xy 342.567727 -396.345342)
			(xy 342.579198 -396.345918) (xy 342.712802 -396.345918) (xy 342.722251 -396.345437) (xy 342.739853 -396.338546)
			(xy 342.747092 -396.332456) (xy 342.752934 -396.326106) (xy 342.753442 -396.325598) (xy 342.801956 -396.259304)
			(xy 342.808157 -396.249933) (xy 342.812497 -396.227915) (xy 342.810338 -396.216886) (xy 342.809322 -396.212822)
			(xy 342.809068 -396.21206) (xy 342.799358 -396.178799) (xy 342.788906 -396.110305) (xy 342.78824 -396.075662)
			(xy 342.78824 -396.075154) (xy 342.78881 -396.0429) (xy 342.797907 -395.979037) (xy 342.815885 -395.917084)
			(xy 342.828626 -395.887448) (xy 342.830658 -395.88313) (xy 342.833374 -395.873685) (xy 342.832194 -395.854085)
			(xy 342.828372 -395.84503) (xy 342.822022 -395.831314) (xy 342.81872 -395.826996) (xy 342.809068 -395.814296)
			(xy 342.805512 -395.811248) (xy 342.781288 -395.789414) (xy 342.738661 -395.740063) (xy 342.703476 -395.685156)
			(xy 342.676449 -395.625808) (xy 342.658127 -395.563222) (xy 342.648882 -395.498668) (xy 342.648286 -395.466062)
			(xy 342.648709 -395.437766) (xy 342.655684 -395.381606) (xy 342.669524 -395.326733) (xy 342.690017 -395.273983)
			(xy 342.716852 -395.224158) (xy 342.749619 -395.178018) (xy 342.78782 -395.136266) (xy 342.809068 -395.117574)
			(xy 342.815926 -395.111732) (xy 342.83396 -395.080236) (xy 342.83523 -395.07033) (xy 342.838278 -395.04874)
			(xy 342.838278 -395.048486) (xy 342.839548 -395.039088) (xy 342.835484 -395.021562) (xy 342.834468 -395.019784)
			(xy 342.830404 -395.013688) (xy 342.816635 -394.992132) (xy 342.795194 -394.945697) (xy 342.787732 -394.921232)
			(xy 342.782906 -394.901928) (xy 342.781128 -394.893546) (xy 342.77681 -394.886434) (xy 342.77446 -394.882724)
			(xy 342.768717 -394.876081) (xy 342.76538 -394.873226) (xy 342.74887 -394.859764) (xy 342.741758 -394.854176)
			(xy 342.711532 -394.843) (xy 342.70315 -394.842746) (xy 342.673872 -394.84127) (xy 342.616021 -394.831789)
			(xy 342.559853 -394.814998) (xy 342.50629 -394.791173) (xy 342.456207 -394.760704) (xy 342.410424 -394.72409)
			(xy 342.369691 -394.68193) (xy 342.334674 -394.634913) (xy 342.305948 -394.583811) (xy 342.283981 -394.529459)
			(xy 342.269134 -394.472747) (xy 342.26165 -394.414604) (xy 342.26119 -394.385292) (xy 342.26119 -394.385038)
			(xy 342.26119 -394.384022) (xy 342.261658 -394.355522) (xy 342.268791 -394.29897) (xy 342.275414 -394.271246)
			(xy 342.276176 -394.268452) (xy 342.277954 -394.255752) (xy 342.277954 -394.245846) (xy 342.277735 -394.239242)
			(xy 342.274264 -394.226498) (xy 342.271096 -394.2207) (xy 342.241124 -394.168376) (xy 342.238503 -394.164079)
			(xy 342.231848 -394.156531) (xy 342.227916 -394.15339) (xy 342.204802 -394.135864) (xy 342.195404 -394.13307)
			(xy 342.166927 -394.1246) (xy 342.112273 -394.101304) (xy 342.061093 -394.071133) (xy 342.014246 -394.034594)
			(xy 341.97252 -393.992301) (xy 341.936617 -393.944964) (xy 341.907141 -393.893381) (xy 341.884585 -393.838417)
			(xy 341.869331 -393.780997) (xy 341.861634 -393.722086) (xy 341.86114 -393.69238) (xy 341.86114 -393.679934)
			(xy 341.862421 -393.650621) (xy 341.871528 -393.592658) (xy 341.887969 -393.536335) (xy 341.911475 -393.482575)
			(xy 341.926164 -393.457176) (xy 341.926164 -393.456668) (xy 341.926418 -393.456414) (xy 341.929082 -393.451704)
			(xy 341.932544 -393.441455) (xy 341.933276 -393.436094) (xy 341.934292 -393.425172) (xy 341.904828 -393.34059)
			(xy 341.900649 -393.330312) (xy 341.88524 -393.314382) (xy 341.87511 -393.309856) (xy 341.872824 -393.30884)
			(xy 341.869014 -393.30757) (xy 341.867236 -393.306808) (xy 341.866982 -393.306808) (xy 341.865204 -393.306046)
			(xy 341.842691 -393.296401) (xy 341.800552 -393.271442) (xy 341.762554 -393.240541) (xy 341.729531 -393.204374)
			(xy 341.702203 -393.16373) (xy 341.68117 -393.119501) (xy 341.666891 -393.072652) (xy 341.659678 -393.02421)
			(xy 341.65921 -392.999722) (xy 341.65972 -392.973735) (xy 341.66785 -392.9224) (xy 341.683911 -392.87297)
			(xy 341.707507 -392.82666) (xy 341.738057 -392.784612) (xy 341.774808 -392.747861) (xy 341.816856 -392.717311)
			(xy 341.863166 -392.693715) (xy 341.912596 -392.677654) (xy 341.963931 -392.669524) (xy 342.015905 -392.669524)
			(xy 342.06724 -392.677654) (xy 342.11667 -392.693715) (xy 342.16298 -392.717311) (xy 342.205028 -392.747861)
			(xy 342.241779 -392.784612) (xy 342.272329 -392.82666) (xy 342.295925 -392.87297) (xy 342.311986 -392.9224)
			(xy 342.320116 -392.973735) (xy 342.320626 -392.999722) (xy 342.320626 -393.000484) (xy 342.320138 -393.026518)
			(xy 342.311967 -393.07794) (xy 342.30437 -393.102846) (xy 342.3031 -393.106656) (xy 342.301576 -393.11453)
			(xy 342.300881 -393.119145) (xy 342.301013 -393.128477) (xy 342.30183 -393.133072) (xy 342.303608 -393.142216)
			(xy 342.308434 -393.15009) (xy 342.347804 -393.215114) (xy 342.348312 -393.21613) (xy 342.35644 -393.225782)
			(xy 342.359512 -393.228563) (xy 342.366407 -393.23316) (xy 342.370156 -393.234926) (xy 342.377776 -393.238482)
			(xy 342.384888 -393.239498) (xy 342.41383 -393.244198) (xy 342.470294 -393.260011) (xy 342.524277 -393.282902)
			(xy 342.574895 -393.312497) (xy 342.621322 -393.348312) (xy 342.662797 -393.389761) (xy 342.698641 -393.436165)
			(xy 342.728268 -393.486765) (xy 342.751194 -393.540733) (xy 342.767042 -393.597187) (xy 342.775554 -393.655201)
			(xy 342.776556 -393.684506) (xy 342.776556 -393.692634) (xy 342.776106 -393.721986) (xy 342.768588 -393.780207)
			(xy 342.76157 -393.808712) (xy 342.761062 -393.81049) (xy 342.761062 -393.810998) (xy 342.759792 -393.815062)
			(xy 342.75903 -393.817348) (xy 342.757324 -393.826563) (xy 342.760065 -393.845089) (xy 342.764364 -393.853416)
			(xy 342.764618 -393.853924) (xy 342.796622 -393.909296) (xy 342.799239 -393.913596) (xy 342.805887 -393.921153)
			(xy 342.80983 -393.924282) (xy 342.832944 -393.941808) (xy 342.842342 -393.944602) (xy 342.870817 -393.953074)
			(xy 342.925469 -393.976373) (xy 342.976646 -394.006546) (xy 343.023491 -394.043086) (xy 343.065214 -394.085379)
			(xy 343.101116 -394.132715) (xy 343.130592 -394.184297) (xy 343.153148 -394.239259) (xy 343.168404 -394.296678)
			(xy 343.176103 -394.355587) (xy 343.176606 -394.385292) (xy 343.176499 -394.399554) (xy 343.174723 -394.428024)
			(xy 343.17305 -394.442188) (xy 343.17178 -394.451586) (xy 343.173812 -394.459968) (xy 343.174899 -394.464059)
			(xy 343.178222 -394.471842) (xy 343.180416 -394.475462) (xy 343.1921 -394.493496) (xy 343.19845 -394.501624)
			(xy 343.202514 -394.505434) (xy 343.22131 -394.520928) (xy 343.225882 -394.522706) (xy 343.22893 -394.523976)
			(xy 343.251612 -394.533541) (xy 343.294095 -394.558404) (xy 343.332422 -394.589292) (xy 343.365745 -394.625521)
			(xy 343.393328 -394.666291) (xy 343.414561 -394.7107) (xy 343.428974 -394.757766) (xy 343.436249 -394.80645)
			(xy 343.436702 -394.831062) (xy 343.436269 -394.85518) (xy 343.429273 -394.902905) (xy 343.415425 -394.949109)
			(xy 343.395017 -394.992814) (xy 343.382092 -395.01318) (xy 343.378028 -395.01953) (xy 343.37371 -395.0335)
			(xy 343.37371 -395.045438) (xy 343.374218 -395.05255) (xy 343.376758 -395.07033) (xy 343.378028 -395.080236)
			(xy 343.396062 -395.111732) (xy 343.40292 -395.117574) (xy 343.424177 -395.136255) (xy 343.462385 -395.178003)
			(xy 343.495155 -395.224142) (xy 343.521988 -395.27397) (xy 343.542474 -395.326724) (xy 343.5563 -395.381602)
			(xy 343.563256 -395.437766) (xy 343.563702 -395.466062) (xy 343.563702 -395.46657) (xy 343.56313 -395.498823)
			(xy 343.554029 -395.562685) (xy 343.536046 -395.624635) (xy 343.523316 -395.654276) (xy 343.521284 -395.658594)
			(xy 343.518572 -395.668039) (xy 343.519761 -395.687634) (xy 343.52357 -395.696694) (xy 343.52992 -395.71041)
			(xy 343.533222 -395.714728) (xy 343.542874 -395.727428) (xy 343.54643 -395.730476) (xy 343.570656 -395.75231)
			(xy 343.613288 -395.80166) (xy 343.648478 -395.856566) (xy 343.675513 -395.915914) (xy 343.693843 -395.978499)
			(xy 343.703097 -396.043054) (xy 343.703656 -396.075662) (xy 343.702982 -396.110769) (xy 343.692266 -396.180162)
			(xy 343.68232 -396.213838) (xy 343.681304 -396.216886) (xy 343.679253 -396.227469) (xy 343.683206 -396.248641)
			(xy 343.688924 -396.25778) (xy 343.689686 -396.25905) (xy 343.7382 -396.32509) (xy 343.738962 -396.326106)
			(xy 343.73947 -396.326614) (xy 343.746996 -396.335291) (xy 343.767623 -396.345345) (xy 343.779094 -396.345918)
			(xy 343.912952 -396.345918) (xy 343.922397 -396.345428) (xy 343.939988 -396.338525) (xy 343.947242 -396.332456)
			(xy 343.953084 -396.326106) (xy 343.953592 -396.325598) (xy 344.002106 -396.259304) (xy 344.008312 -396.249934)
			(xy 344.012656 -396.227914) (xy 344.010488 -396.216886) (xy 344.009472 -396.212822) (xy 344.009218 -396.21206)
			(xy 343.999507 -396.178799) (xy 343.989053 -396.110305) (xy 343.98839 -396.075662) (xy 343.98839 -396.075154)
			(xy 343.98896 -396.0429) (xy 343.998058 -395.979037) (xy 344.016038 -395.917086) (xy 344.028776 -395.887448)
			(xy 344.030808 -395.88313) (xy 344.033525 -395.873685) (xy 344.032344 -395.854085) (xy 344.028522 -395.84503)
			(xy 344.022172 -395.831314) (xy 344.01887 -395.826996) (xy 344.009218 -395.814296) (xy 344.005662 -395.811248)
			(xy 343.981441 -395.789413) (xy 343.938817 -395.74006) (xy 343.903637 -395.685153) (xy 343.876613 -395.625805)
			(xy 343.858293 -395.56322) (xy 343.849049 -395.498668) (xy 343.848436 -395.466062) (xy 343.848859 -395.437766)
			(xy 343.855834 -395.381605) (xy 343.869672 -395.326731) (xy 343.890164 -395.273979) (xy 343.916996 -395.224152)
			(xy 343.949762 -395.17801) (xy 343.98796 -395.136254) (xy 344.009218 -395.117574) (xy 344.016076 -395.111732)
			(xy 344.03411 -395.080236) (xy 344.03538 -395.07033) (xy 344.038428 -395.04874) (xy 344.038428 -395.048486)
			(xy 344.039698 -395.039088) (xy 344.035634 -395.021562) (xy 344.034618 -395.019784) (xy 344.030554 -395.013688)
			(xy 344.016787 -394.992131) (xy 343.995349 -394.945695) (xy 343.987882 -394.921232) (xy 343.983056 -394.902182)
			(xy 343.983056 -394.901928) (xy 343.981024 -394.893292) (xy 343.97696 -394.886434) (xy 343.974598 -394.882789)
			(xy 343.968853 -394.876276) (xy 343.96553 -394.87348) (xy 343.94902 -394.860018) (xy 343.942162 -394.854176)
			(xy 343.911428 -394.843) (xy 343.9033 -394.842746) (xy 343.874011 -394.841285) (xy 343.816136 -394.831829)
			(xy 343.759942 -394.815059) (xy 343.706351 -394.791248) (xy 343.65624 -394.760787) (xy 343.61043 -394.724175)
			(xy 343.569671 -394.682012) (xy 343.534633 -394.634987) (xy 343.505887 -394.583873) (xy 343.483906 -394.529506)
			(xy 343.469049 -394.472776) (xy 343.461559 -394.414613) (xy 343.461086 -394.385292) (xy 343.461086 -394.385038)
			(xy 343.461086 -394.384022) (xy 343.461554 -394.355522) (xy 343.468687 -394.29897) (xy 343.47531 -394.271246)
			(xy 343.476072 -394.268452) (xy 343.47785 -394.255752) (xy 343.47785 -394.245846) (xy 343.477631 -394.239242)
			(xy 343.474159 -394.226499) (xy 343.470992 -394.2207) (xy 343.44102 -394.168376) (xy 343.438399 -394.16408)
			(xy 343.431744 -394.156532) (xy 343.427812 -394.15339) (xy 343.404698 -394.135864) (xy 343.3953 -394.13307)
			(xy 343.366823 -394.1246) (xy 343.31217 -394.101304) (xy 343.26099 -394.071132) (xy 343.214143 -394.034593)
			(xy 343.172418 -393.9923) (xy 343.136516 -393.944963) (xy 343.107039 -393.89338) (xy 343.084484 -393.838416)
			(xy 343.06923 -393.780996) (xy 343.061533 -393.722086) (xy 343.061036 -393.69238) (xy 343.061036 -393.679934)
			(xy 343.062317 -393.650621) (xy 343.071424 -393.592658) (xy 343.087865 -393.536335) (xy 343.11137 -393.482575)
			(xy 343.12606 -393.457176) (xy 343.12606 -393.456668) (xy 343.126314 -393.456414) (xy 343.128978 -393.451704)
			(xy 343.13244 -393.441455) (xy 343.133172 -393.436094) (xy 343.134188 -393.425172) (xy 343.104724 -393.34059)
			(xy 343.100545 -393.330313) (xy 343.085136 -393.314383) (xy 343.075006 -393.309856) (xy 343.07272 -393.30884)
			(xy 343.06891 -393.30757) (xy 343.067132 -393.306808) (xy 343.066878 -393.306808) (xy 343.0651 -393.306046)
			(xy 343.042587 -393.296401) (xy 343.000448 -393.271442) (xy 342.962451 -393.240541) (xy 342.929428 -393.204373)
			(xy 342.902101 -393.16373) (xy 342.881068 -393.1195) (xy 342.866789 -393.072652) (xy 342.859576 -393.02421)
			(xy 342.859106 -392.999722) (xy 342.859616 -392.973735) (xy 342.867746 -392.9224) (xy 342.883807 -392.87297)
			(xy 342.907403 -392.82666) (xy 342.937953 -392.784612) (xy 342.974704 -392.747861) (xy 343.016752 -392.717311)
			(xy 343.063062 -392.693715) (xy 343.112492 -392.677654) (xy 343.163827 -392.669524) (xy 343.215801 -392.669524)
			(xy 343.267136 -392.677654) (xy 343.316566 -392.693715) (xy 343.362876 -392.717311) (xy 343.404924 -392.747861)
			(xy 343.441675 -392.784612) (xy 343.472225 -392.82666) (xy 343.495821 -392.87297) (xy 343.511882 -392.9224)
			(xy 343.520012 -392.973735) (xy 343.520522 -392.999722) (xy 343.520522 -393.000484) (xy 343.520034 -393.026518)
			(xy 343.511863 -393.07794) (xy 343.504266 -393.102846) (xy 343.502996 -393.106656) (xy 343.501472 -393.11453)
			(xy 343.500777 -393.119145) (xy 343.500909 -393.128477) (xy 343.501726 -393.133072) (xy 343.503504 -393.142216)
			(xy 343.50833 -393.15009) (xy 343.5477 -393.215114) (xy 343.548208 -393.21613) (xy 343.556336 -393.225782)
			(xy 343.559408 -393.228563) (xy 343.566303 -393.23316) (xy 343.570052 -393.234926) (xy 343.577672 -393.238482)
			(xy 343.584784 -393.239498) (xy 343.613727 -393.244198) (xy 343.67019 -393.26001) (xy 343.724174 -393.282901)
			(xy 343.774793 -393.312496) (xy 343.82122 -393.348311) (xy 343.862695 -393.38976) (xy 343.89854 -393.436164)
			(xy 343.928167 -393.486764) (xy 343.951093 -393.540733) (xy 343.966941 -393.597186) (xy 343.975453 -393.655201)
			(xy 343.976452 -393.684506) (xy 343.976452 -393.692634) (xy 343.976002 -393.721986) (xy 343.968484 -393.780207)
			(xy 343.961466 -393.808712) (xy 343.960958 -393.81049) (xy 343.960958 -393.810998) (xy 343.959688 -393.815062)
			(xy 343.958926 -393.817348) (xy 343.95722 -393.826563) (xy 343.959961 -393.845089) (xy 343.96426 -393.853416)
			(xy 343.964514 -393.853924) (xy 343.996518 -393.909296) (xy 343.999135 -393.913596) (xy 344.005783 -393.921154)
			(xy 344.009726 -393.924282) (xy 344.03284 -393.941808) (xy 344.042238 -393.944602) (xy 344.070714 -393.953074)
			(xy 344.125365 -393.976372) (xy 344.176543 -394.006545) (xy 344.223388 -394.043085) (xy 344.265112 -394.085379)
			(xy 344.301014 -394.132714) (xy 344.330491 -394.184297) (xy 344.353047 -394.239259) (xy 344.368303 -394.296677)
			(xy 344.376002 -394.355587) (xy 344.376502 -394.385292) (xy 344.376387 -394.399491) (xy 344.374608 -394.427832)
			(xy 344.372946 -394.441934) (xy 344.372506 -394.446456) (xy 344.373011 -394.455526) (xy 344.373962 -394.459968)
			(xy 344.37574 -394.467842) (xy 344.380312 -394.475208) (xy 344.395806 -394.5001) (xy 344.400514 -394.50716)
			(xy 344.413626 -394.517918) (xy 344.42146 -394.521182) (xy 344.444829 -394.530383) (xy 344.488703 -394.554823)
			(xy 344.528379 -394.585614) (xy 344.562944 -394.622049) (xy 344.591606 -394.663289) (xy 344.613704 -394.708388)
			(xy 344.628732 -394.756309) (xy 344.636344 -394.805951) (xy 344.636852 -394.831062) (xy 344.636419 -394.855179)
			(xy 344.629422 -394.902904) (xy 344.615572 -394.949107) (xy 344.595161 -394.992811) (xy 344.582242 -395.01318)
			(xy 344.578178 -395.01953) (xy 344.57386 -395.0335) (xy 344.57386 -395.045438) (xy 344.574368 -395.05255)
			(xy 344.576908 -395.07033) (xy 344.578178 -395.080236) (xy 344.596212 -395.111732) (xy 344.60307 -395.117574)
			(xy 344.624325 -395.136256) (xy 344.662529 -395.178006) (xy 344.695296 -395.224146) (xy 344.722125 -395.273973)
			(xy 344.742609 -395.326727) (xy 344.756433 -395.381604) (xy 344.763389 -395.437766) (xy 344.763852 -395.466062)
			(xy 344.763852 -395.46657) (xy 344.76328 -395.498823) (xy 344.75418 -395.562686) (xy 344.736199 -395.624636)
			(xy 344.723466 -395.654276) (xy 344.721434 -395.658594) (xy 344.71872 -395.668038) (xy 344.71991 -395.687634)
			(xy 344.72372 -395.696694) (xy 344.73007 -395.71041) (xy 344.733372 -395.714728) (xy 344.743024 -395.727428)
			(xy 344.74658 -395.730476) (xy 344.770808 -395.752308) (xy 344.813445 -395.801657) (xy 344.848639 -395.856562)
			(xy 344.875676 -395.91591) (xy 344.894009 -395.978497) (xy 344.903265 -396.043054) (xy 344.903806 -396.075662)
			(xy 344.903132 -396.110769) (xy 344.892417 -396.180162) (xy 344.88247 -396.213838) (xy 344.881454 -396.216886)
			(xy 344.879402 -396.227468) (xy 344.883358 -396.248639) (xy 344.889074 -396.25778) (xy 344.889836 -396.25905)
			(xy 344.93835 -396.32509) (xy 344.939112 -396.326106) (xy 344.93962 -396.326614) (xy 344.947149 -396.335283)
			(xy 344.967777 -396.345316) (xy 344.979244 -396.345918) (xy 345.112848 -396.345918) (xy 345.122294 -396.345429)
			(xy 345.139885 -396.338526) (xy 345.147138 -396.332456) (xy 345.15298 -396.326106) (xy 345.153488 -396.325598)
			(xy 345.202002 -396.259304) (xy 345.208208 -396.249934) (xy 345.212553 -396.227914) (xy 345.210384 -396.216886)
			(xy 345.209368 -396.212822) (xy 345.209114 -396.21206) (xy 345.199403 -396.178799) (xy 345.18895 -396.110305)
			(xy 345.188286 -396.075662) (xy 345.188286 -396.075154) (xy 345.188856 -396.0429) (xy 345.197954 -395.979037)
			(xy 345.215934 -395.917086) (xy 345.228672 -395.887448) (xy 345.230704 -395.88313) (xy 345.233422 -395.873685)
			(xy 345.23224 -395.854085) (xy 345.228418 -395.84503) (xy 345.222068 -395.831314) (xy 345.218766 -395.826996)
			(xy 345.209114 -395.814296) (xy 345.205558 -395.811248) (xy 345.181337 -395.789413) (xy 345.138714 -395.74006)
			(xy 345.103534 -395.685152) (xy 345.07651 -395.625805) (xy 345.05819 -395.56322) (xy 345.048947 -395.498668)
			(xy 345.048332 -395.466062) (xy 345.048755 -395.437766) (xy 345.05573 -395.381605) (xy 345.069568 -395.326731)
			(xy 345.09006 -395.273979) (xy 345.116892 -395.224152) (xy 345.149657 -395.178009) (xy 345.187855 -395.136253)
			(xy 345.209114 -395.117574) (xy 345.215972 -395.111732) (xy 345.234006 -395.080236) (xy 345.235276 -395.07033)
			(xy 345.238324 -395.04874) (xy 345.238324 -395.048486) (xy 345.239594 -395.039088) (xy 345.23553 -395.021562)
			(xy 345.234514 -395.019784) (xy 345.23045 -395.013688) (xy 345.216683 -394.992131) (xy 345.195246 -394.945695)
			(xy 345.187778 -394.921232) (xy 345.182952 -394.902182) (xy 345.182952 -394.901928) (xy 345.18092 -394.893292)
			(xy 345.176856 -394.886434) (xy 345.174494 -394.88279) (xy 345.168749 -394.876277) (xy 345.165426 -394.87348)
			(xy 345.148916 -394.860018) (xy 345.142058 -394.854176) (xy 345.111324 -394.843) (xy 345.103196 -394.842746)
			(xy 345.073907 -394.841285) (xy 345.016032 -394.831829) (xy 344.959839 -394.815058) (xy 344.906248 -394.791247)
			(xy 344.856137 -394.760786) (xy 344.810328 -394.724174) (xy 344.76957 -394.68201) (xy 344.734532 -394.634986)
			(xy 344.705786 -394.583872) (xy 344.683805 -394.529505) (xy 344.668948 -394.472776) (xy 344.661459 -394.414613)
			(xy 344.660982 -394.385292) (xy 344.660982 -394.384784) (xy 344.660982 -394.383768) (xy 344.661448 -394.355268)
			(xy 344.668581 -394.298715) (xy 344.675206 -394.270992) (xy 344.675968 -394.268198) (xy 344.677746 -394.255498)
			(xy 344.677746 -394.245338) (xy 344.677587 -394.240653) (xy 344.675796 -394.231454) (xy 344.67419 -394.22705)
			(xy 344.671142 -394.220192) (xy 344.660982 -394.202666) (xy 344.635836 -394.159232) (xy 344.633213 -394.154937)
			(xy 344.626555 -394.147394) (xy 344.622628 -394.144246) (xy 344.614754 -394.13815) (xy 344.604594 -394.13561)
			(xy 344.575486 -394.127604) (xy 344.519518 -394.104973) (xy 344.467011 -394.075182) (xy 344.418876 -394.038746)
			(xy 344.375948 -393.996298) (xy 344.338974 -393.948575) (xy 344.308594 -393.896406) (xy 344.285335 -393.840696)
			(xy 344.269603 -393.782412) (xy 344.261669 -393.722565) (xy 344.261186 -393.69238) (xy 344.261186 -393.679934)
			(xy 344.262467 -393.650621) (xy 344.271575 -393.592659) (xy 344.288018 -393.536336) (xy 344.311525 -393.482578)
			(xy 344.32621 -393.457176) (xy 344.32621 -393.456668) (xy 344.326464 -393.456414) (xy 344.329131 -393.451705)
			(xy 344.332596 -393.441456) (xy 344.333322 -393.436094) (xy 344.334338 -393.425172) (xy 344.304874 -393.34059)
			(xy 344.300698 -393.330308) (xy 344.285295 -393.314365) (xy 344.275156 -393.309856) (xy 344.27287 -393.30884)
			(xy 344.26906 -393.30757) (xy 344.267282 -393.306808) (xy 344.267028 -393.306808) (xy 344.26525 -393.306046)
			(xy 344.242735 -393.296403) (xy 344.20059 -393.271448) (xy 344.162588 -393.240549) (xy 344.129559 -393.204382)
			(xy 344.102228 -393.163738) (xy 344.081191 -393.119507) (xy 344.066909 -393.072656) (xy 344.059695 -393.024212)
			(xy 344.059256 -392.999722) (xy 344.059766 -392.973735) (xy 344.067896 -392.9224) (xy 344.083957 -392.87297)
			(xy 344.107553 -392.82666) (xy 344.138103 -392.784612) (xy 344.174854 -392.747861) (xy 344.216902 -392.717311)
			(xy 344.263212 -392.693715) (xy 344.312642 -392.677654) (xy 344.363977 -392.669524) (xy 344.415951 -392.669524)
			(xy 344.467286 -392.677654) (xy 344.516716 -392.693715) (xy 344.563026 -392.717311) (xy 344.605074 -392.747861)
			(xy 344.641825 -392.784612) (xy 344.672375 -392.82666) (xy 344.695971 -392.87297) (xy 344.712032 -392.9224)
			(xy 344.720162 -392.973735) (xy 344.720672 -392.999722) (xy 344.720672 -393.000484) (xy 344.720184 -393.026518)
			(xy 344.712014 -393.077941) (xy 344.704416 -393.102846) (xy 344.703146 -393.106656) (xy 344.701622 -393.11453)
			(xy 344.700927 -393.119145) (xy 344.701059 -393.128477) (xy 344.701876 -393.133072) (xy 344.703654 -393.142216)
			(xy 344.70848 -393.15009) (xy 344.74785 -393.215114) (xy 344.748358 -393.21613) (xy 344.756486 -393.225782)
			(xy 344.75956 -393.228561) (xy 344.766457 -393.233151) (xy 344.770202 -393.234926) (xy 344.777822 -393.238482)
			(xy 344.781124 -393.23899) (xy 344.784934 -393.239498) (xy 344.813879 -393.244195) (xy 344.870348 -393.260003)
			(xy 344.924336 -393.28289) (xy 344.974961 -393.312483) (xy 345.021393 -393.348297) (xy 345.062873 -393.389745)
			(xy 345.098722 -393.436151) (xy 345.128353 -393.486753) (xy 345.151282 -393.540724) (xy 345.167133 -393.59718)
			(xy 345.175646 -393.655199) (xy 345.176602 -393.684506) (xy 345.176602 -393.692634) (xy 345.176152 -393.721986)
			(xy 345.168633 -393.780207) (xy 345.161616 -393.808712) (xy 345.161108 -393.81049) (xy 345.161108 -393.810998)
			(xy 345.159838 -393.815062) (xy 345.159076 -393.817348) (xy 345.157428 -393.826565) (xy 345.160164 -393.845071)
			(xy 345.16441 -393.853416) (xy 345.164664 -393.853924) (xy 345.196668 -393.909296) (xy 345.199287 -393.913594)
			(xy 345.205939 -393.921147) (xy 345.209876 -393.924282) (xy 345.23299 -393.941808) (xy 345.239848 -393.94384)
			(xy 345.242642 -393.944602) (xy 345.271094 -393.953092) (xy 345.325696 -393.97642) (xy 345.376821 -394.006616)
			(xy 345.423611 -394.043171) (xy 345.465279 -394.085472) (xy 345.501126 -394.132806) (xy 345.530548 -394.18438)
			(xy 345.553052 -394.239327) (xy 345.56826 -394.296723) (xy 345.575916 -394.355604) (xy 345.576398 -394.385292)
			(xy 345.576283 -394.399491) (xy 345.574504 -394.427832) (xy 345.572842 -394.441934) (xy 345.572402 -394.446456)
			(xy 345.572907 -394.455526) (xy 345.573858 -394.459968) (xy 345.575636 -394.467842) (xy 345.580208 -394.475208)
			(xy 345.595702 -394.5001) (xy 345.60041 -394.507161) (xy 345.613521 -394.517919) (xy 345.621356 -394.521182)
			(xy 345.644726 -394.530383) (xy 345.6886 -394.554823) (xy 345.728276 -394.585614) (xy 345.762842 -394.622048)
			(xy 345.791504 -394.663289) (xy 345.813603 -394.708388) (xy 345.828631 -394.756309) (xy 345.836243 -394.805951)
			(xy 345.836748 -394.831062) (xy 345.836315 -394.855179) (xy 345.829318 -394.902904) (xy 345.815468 -394.949107)
			(xy 345.795057 -394.99281) (xy 345.782138 -395.01318) (xy 345.778074 -395.01953) (xy 345.773756 -395.0335)
			(xy 345.773756 -395.045438) (xy 345.774264 -395.05255) (xy 345.776804 -395.07033) (xy 345.778074 -395.080236)
			(xy 345.796108 -395.111732) (xy 345.802966 -395.117574) (xy 345.824222 -395.136256) (xy 345.862426 -395.178006)
			(xy 345.895193 -395.224146) (xy 345.922022 -395.273973) (xy 345.942506 -395.326727) (xy 345.956331 -395.381604)
			(xy 345.963286 -395.437766) (xy 345.963748 -395.466062) (xy 345.963748 -395.46657) (xy 345.963176 -395.498823)
			(xy 345.954076 -395.562686) (xy 345.936095 -395.624636) (xy 345.923362 -395.654276) (xy 345.92133 -395.658594)
			(xy 345.918616 -395.668038) (xy 345.919806 -395.687634) (xy 345.923616 -395.696694) (xy 345.929966 -395.71041)
			(xy 345.933268 -395.714728) (xy 345.94292 -395.727428) (xy 345.946476 -395.730476) (xy 345.970704 -395.752308)
			(xy 346.013341 -395.801657) (xy 346.048536 -395.856562) (xy 346.075573 -395.91591) (xy 346.093906 -395.978497)
			(xy 346.103162 -396.043054) (xy 346.103702 -396.075662) (xy 346.103028 -396.110769) (xy 346.092313 -396.180162)
			(xy 346.082366 -396.213838) (xy 346.08135 -396.216886) (xy 346.079298 -396.227468) (xy 346.083254 -396.248639)
			(xy 346.08897 -396.25778) (xy 346.089732 -396.25905) (xy 346.138246 -396.32509) (xy 346.139008 -396.326106)
			(xy 346.139516 -396.326614) (xy 346.147045 -396.335283) (xy 346.167672 -396.345319) (xy 346.17914 -396.345918)
			(xy 346.312744 -396.345918) (xy 346.32219 -396.345429) (xy 346.339782 -396.338528) (xy 346.347034 -396.332456)
			(xy 346.352876 -396.326106) (xy 346.353384 -396.325598) (xy 346.401898 -396.259304) (xy 346.408095 -396.249932)
			(xy 346.412431 -396.227916) (xy 346.41028 -396.216886) (xy 346.409264 -396.212822) (xy 346.40901 -396.21206)
			(xy 346.399299 -396.178799) (xy 346.388846 -396.110305) (xy 346.388182 -396.075662) (xy 346.388182 -396.075154)
			(xy 346.388752 -396.0429) (xy 346.39785 -395.979037) (xy 346.41583 -395.917085) (xy 346.428568 -395.887448)
			(xy 346.4306 -395.88313) (xy 346.433318 -395.873685) (xy 346.432136 -395.854085) (xy 346.428314 -395.84503)
			(xy 346.421964 -395.831314) (xy 346.418662 -395.826996) (xy 346.40901 -395.814296) (xy 346.405454 -395.811248)
			(xy 346.381233 -395.789413) (xy 346.33861 -395.740059) (xy 346.303431 -395.685152) (xy 346.276407 -395.625804)
			(xy 346.258088 -395.56322) (xy 346.248844 -395.498668) (xy 346.248228 -395.466062) (xy 346.248651 -395.437766)
			(xy 346.255626 -395.381605) (xy 346.269464 -395.326731) (xy 346.289955 -395.273978) (xy 346.316788 -395.224151)
			(xy 346.349552 -395.178009) (xy 346.387751 -395.136252) (xy 346.40901 -395.117574) (xy 346.415868 -395.111732)
			(xy 346.433902 -395.080236) (xy 346.435172 -395.07033) (xy 346.43822 -395.04874) (xy 346.43822 -395.048486)
			(xy 346.43949 -395.039088) (xy 346.435426 -395.021562) (xy 346.43441 -395.019784) (xy 346.430346 -395.013688)
			(xy 346.41658 -394.992131) (xy 346.395142 -394.945695) (xy 346.387674 -394.921232) (xy 346.382848 -394.901928)
			(xy 346.38107 -394.893546) (xy 346.376752 -394.886434) (xy 346.374404 -394.882722) (xy 346.368663 -394.876076)
			(xy 346.365322 -394.873226) (xy 346.348812 -394.859764) (xy 346.3417 -394.854176) (xy 346.311474 -394.843)
			(xy 346.303092 -394.842746) (xy 346.273812 -394.841273) (xy 346.215957 -394.831795) (xy 346.159785 -394.815008)
			(xy 346.106217 -394.791186) (xy 346.056129 -394.760718) (xy 346.010342 -394.724104) (xy 345.969604 -394.681943)
			(xy 345.934584 -394.634926) (xy 345.905854 -394.583821) (xy 345.883885 -394.529467) (xy 345.869037 -394.472752)
			(xy 345.861552 -394.414605) (xy 345.861132 -394.385292) (xy 345.861132 -394.385038) (xy 345.861132 -394.384022)
			(xy 345.8616 -394.355522) (xy 345.868734 -394.29897) (xy 345.875356 -394.271246) (xy 345.876118 -394.268452)
			(xy 345.877896 -394.255752) (xy 345.877896 -394.245846) (xy 345.877676 -394.239243) (xy 345.874201 -394.226501)
			(xy 345.871038 -394.2207) (xy 345.841066 -394.168376) (xy 345.838447 -394.164078) (xy 345.831795 -394.156526)
			(xy 345.827858 -394.15339) (xy 345.804744 -394.135864) (xy 345.795346 -394.13307) (xy 345.766872 -394.124597)
			(xy 345.712224 -394.101297) (xy 345.661049 -394.071123) (xy 345.614208 -394.034581) (xy 345.572488 -393.992288)
			(xy 345.53659 -393.944952) (xy 345.507118 -393.89337) (xy 345.484566 -393.838409) (xy 345.469314 -393.780992)
			(xy 345.461618 -393.722084) (xy 345.461082 -393.69238) (xy 345.461082 -393.679934) (xy 345.462363 -393.650621)
			(xy 345.471471 -393.592659) (xy 345.487914 -393.536336) (xy 345.511421 -393.482577) (xy 345.526106 -393.457176)
			(xy 345.526106 -393.456668) (xy 345.52636 -393.456414) (xy 345.529027 -393.451705) (xy 345.532492 -393.441456)
			(xy 345.533218 -393.436094) (xy 345.534234 -393.425172) (xy 345.50477 -393.34059) (xy 345.500594 -393.330309)
			(xy 345.48519 -393.314367) (xy 345.475052 -393.309856) (xy 345.472766 -393.30884) (xy 345.468956 -393.30757)
			(xy 345.467178 -393.306808) (xy 345.466924 -393.306808) (xy 345.465146 -393.306046) (xy 345.442631 -393.296403)
			(xy 345.400487 -393.271447) (xy 345.362485 -393.240548) (xy 345.329457 -393.204381) (xy 345.302126 -393.163737)
			(xy 345.281089 -393.119506) (xy 345.266808 -393.072656) (xy 345.259594 -393.024211) (xy 345.259152 -392.999722)
			(xy 345.259662 -392.973735) (xy 345.267792 -392.9224) (xy 345.283853 -392.87297) (xy 345.307449 -392.82666)
			(xy 345.337999 -392.784612) (xy 345.37475 -392.747861) (xy 345.416798 -392.717311) (xy 345.463108 -392.693715)
			(xy 345.512538 -392.677654) (xy 345.563873 -392.669524) (xy 345.615847 -392.669524) (xy 345.667182 -392.677654)
			(xy 345.716612 -392.693715) (xy 345.762922 -392.717311) (xy 345.80497 -392.747861) (xy 345.841721 -392.784612)
			(xy 345.872271 -392.82666) (xy 345.895867 -392.87297) (xy 345.911928 -392.9224) (xy 345.920058 -392.973735)
			(xy 345.920568 -392.999722) (xy 345.920568 -393.000484) (xy 345.92008 -393.026518) (xy 345.91191 -393.077941)
			(xy 345.904312 -393.102846) (xy 345.903042 -393.106656) (xy 345.901518 -393.11453) (xy 345.900823 -393.119145)
			(xy 345.900955 -393.128477) (xy 345.901772 -393.133072) (xy 345.90355 -393.142216) (xy 345.908376 -393.15009)
			(xy 345.947746 -393.215114) (xy 345.948254 -393.21613) (xy 345.956382 -393.225782) (xy 345.959456 -393.228561)
			(xy 345.966353 -393.233152) (xy 345.970098 -393.234926) (xy 345.977718 -393.238482) (xy 345.98102 -393.23899)
			(xy 345.98483 -393.239498) (xy 346.013775 -393.244195) (xy 346.070244 -393.260002) (xy 346.124233 -393.282889)
			(xy 346.174858 -393.312482) (xy 346.221291 -393.348296) (xy 346.262771 -393.389744) (xy 346.298621 -393.43615)
			(xy 346.328252 -393.486752) (xy 346.351181 -393.540723) (xy 346.367032 -393.59718) (xy 346.375545 -393.655198)
			(xy 346.376498 -393.684506) (xy 346.376498 -393.692634) (xy 346.376048 -393.721986) (xy 346.368529 -393.780207)
			(xy 346.361512 -393.808712) (xy 346.361004 -393.81049) (xy 346.361004 -393.810998) (xy 346.359734 -393.815062)
			(xy 346.358972 -393.817348) (xy 346.357324 -393.826565) (xy 346.36006 -393.845071) (xy 346.364306 -393.853416)
			(xy 346.36456 -393.853924) (xy 346.396564 -393.909296) (xy 346.399183 -393.913595) (xy 346.405834 -393.921147)
			(xy 346.409772 -393.924282) (xy 346.432886 -393.941808) (xy 346.442284 -393.944602) (xy 346.470762 -393.953071)
			(xy 346.525419 -393.976365) (xy 346.576603 -394.006535) (xy 346.623453 -394.043074) (xy 346.665182 -394.085366)
			(xy 346.701089 -394.132703) (xy 346.73057 -394.184287) (xy 346.753129 -394.239251) (xy 346.768387 -394.296672)
			(xy 346.776088 -394.355585) (xy 346.776548 -394.385292) (xy 346.776441 -394.399554) (xy 346.774664 -394.428024)
			(xy 346.772992 -394.442188) (xy 346.771722 -394.451586) (xy 346.773754 -394.459968) (xy 346.774842 -394.464058)
			(xy 346.778167 -394.471841) (xy 346.780358 -394.475462) (xy 346.792042 -394.493496) (xy 346.798392 -394.501624)
			(xy 346.802456 -394.505434) (xy 346.821252 -394.520928) (xy 346.825824 -394.522706) (xy 346.828872 -394.523976)
			(xy 346.851557 -394.533538) (xy 346.894047 -394.558397) (xy 346.93238 -394.589282) (xy 346.96571 -394.62551)
			(xy 346.993298 -394.666281) (xy 347.014535 -394.710692) (xy 347.028951 -394.757761) (xy 347.036227 -394.806448)
			(xy 347.036644 -394.831062) (xy 347.036211 -394.85518) (xy 347.029216 -394.902905) (xy 347.015369 -394.94911)
			(xy 346.994963 -394.992817) (xy 346.982034 -395.01318) (xy 346.97797 -395.01953) (xy 346.973652 -395.0335)
			(xy 346.973652 -395.045438) (xy 346.97416 -395.05255) (xy 346.9767 -395.07033) (xy 346.97797 -395.080236)
			(xy 346.996004 -395.111732) (xy 347.002862 -395.117574) (xy 347.024118 -395.136256) (xy 347.062322 -395.178005)
			(xy 347.095089 -395.224146) (xy 347.121919 -395.273973) (xy 347.142403 -395.326727) (xy 347.156228 -395.381604)
			(xy 347.163184 -395.437766) (xy 347.163644 -395.466062) (xy 347.163644 -395.46657) (xy 347.163072 -395.498823)
			(xy 347.153972 -395.562686) (xy 347.13599 -395.624636) (xy 347.123258 -395.654276) (xy 347.121226 -395.658594)
			(xy 347.118512 -395.668038) (xy 347.119702 -395.687634) (xy 347.123512 -395.696694) (xy 347.129862 -395.71041)
			(xy 347.133164 -395.714728) (xy 347.142816 -395.727428) (xy 347.146372 -395.730476) (xy 347.1706 -395.752308)
			(xy 347.213238 -395.801657) (xy 347.248432 -395.856562) (xy 347.27547 -395.91591) (xy 347.293803 -395.978497)
			(xy 347.303059 -396.043053) (xy 347.303598 -396.075662) (xy 347.302924 -396.110769) (xy 347.292209 -396.180162)
			(xy 347.282262 -396.213838) (xy 347.281246 -396.216886) (xy 347.279194 -396.227469) (xy 347.28315 -396.24864)
			(xy 347.288866 -396.25778) (xy 347.289628 -396.25905) (xy 347.338142 -396.32509) (xy 347.338904 -396.326106)
			(xy 347.339412 -396.326614) (xy 347.34694 -396.335284) (xy 347.367568 -396.345321) (xy 347.379036 -396.345918)
			(xy 347.512894 -396.345918) (xy 347.522336 -396.345421) (xy 347.539917 -396.338507) (xy 347.547184 -396.332456)
			(xy 347.553026 -396.326106) (xy 347.553534 -396.325598) (xy 347.602048 -396.259304) (xy 347.60825 -396.249933)
			(xy 347.61259 -396.227915) (xy 347.61043 -396.216886) (xy 347.609414 -396.212822) (xy 347.60916 -396.21206)
			(xy 347.59945 -396.178799) (xy 347.588998 -396.110305) (xy 347.588332 -396.075662) (xy 347.588332 -396.075154)
			(xy 347.588902 -396.0429) (xy 347.597998 -395.979037) (xy 347.615977 -395.917084) (xy 347.628718 -395.887448)
			(xy 347.63075 -395.88313) (xy 347.633466 -395.873685) (xy 347.632286 -395.854085) (xy 347.628464 -395.84503)
			(xy 347.622114 -395.831314) (xy 347.618812 -395.826996) (xy 347.60916 -395.814296) (xy 347.605604 -395.811248)
			(xy 347.581381 -395.789414) (xy 347.538754 -395.740062) (xy 347.50357 -395.685156) (xy 347.476543 -395.625808)
			(xy 347.458222 -395.563222) (xy 347.448977 -395.498668) (xy 347.448378 -395.466062) (xy 347.448801 -395.437766)
			(xy 347.455776 -395.381606) (xy 347.469616 -395.326733) (xy 347.490109 -395.273982) (xy 347.516943 -395.224157)
			(xy 347.54971 -395.178017) (xy 347.587911 -395.136264) (xy 347.60916 -395.117574) (xy 347.616018 -395.111732)
			(xy 347.634052 -395.080236) (xy 347.635322 -395.07033) (xy 347.63837 -395.04874) (xy 347.63837 -395.048486)
			(xy 347.63964 -395.039088) (xy 347.635576 -395.021562) (xy 347.63456 -395.019784) (xy 347.630496 -395.013688)
			(xy 347.616728 -394.992132) (xy 347.595287 -394.945696) (xy 347.587824 -394.921232) (xy 347.582998 -394.902182)
			(xy 347.582998 -394.901928) (xy 347.580966 -394.893292) (xy 347.576902 -394.886434) (xy 347.574537 -394.882792)
			(xy 347.568789 -394.876284) (xy 347.565472 -394.87348) (xy 347.548962 -394.860018) (xy 347.542104 -394.854176)
			(xy 347.51137 -394.843) (xy 347.503242 -394.842746) (xy 347.473951 -394.841288) (xy 347.416072 -394.831836)
			(xy 347.359874 -394.815069) (xy 347.306278 -394.791261) (xy 347.256162 -394.760801) (xy 347.210347 -394.724189)
			(xy 347.169585 -394.682025) (xy 347.134542 -394.635) (xy 347.105794 -394.583884) (xy 347.08381 -394.529514)
			(xy 347.068951 -394.472781) (xy 347.061461 -394.414615) (xy 347.061028 -394.385292) (xy 347.061028 -394.385038)
			(xy 347.061028 -394.384022) (xy 347.061496 -394.355522) (xy 347.06863 -394.29897) (xy 347.075252 -394.271246)
			(xy 347.076014 -394.268452) (xy 347.077792 -394.255752) (xy 347.077792 -394.245846) (xy 347.077572 -394.239243)
			(xy 347.074097 -394.226501) (xy 347.070934 -394.2207) (xy 347.040962 -394.168376) (xy 347.038343 -394.164078)
			(xy 347.031691 -394.156526) (xy 347.027754 -394.15339) (xy 347.00464 -394.135864) (xy 346.995242 -394.13307)
			(xy 346.967157 -394.124711) (xy 346.913215 -394.101821) (xy 346.862633 -394.072238) (xy 346.816238 -394.036445)
			(xy 346.774787 -393.995026) (xy 346.738958 -393.948658) (xy 346.709336 -393.898099) (xy 346.686406 -393.844174)
			(xy 346.670541 -393.787765) (xy 346.662 -393.729793) (xy 346.660978 -393.700508) (xy 346.660978 -393.691872)
			(xy 346.661504 -393.661016) (xy 346.669833 -393.599867) (xy 346.686295 -393.54039) (xy 346.710593 -393.483661)
			(xy 346.726002 -393.456922) (xy 346.726002 -393.456668) (xy 346.726256 -393.456414) (xy 346.731106 -393.447086)
			(xy 346.73361 -393.426232) (xy 346.731082 -393.416028) (xy 346.721938 -393.389612) (xy 346.70492 -393.340844)
			(xy 346.703142 -393.336526) (xy 346.699222 -393.328774) (xy 346.687143 -393.316307) (xy 346.67952 -393.312142)
			(xy 346.675202 -393.31011) (xy 346.672916 -393.309094) (xy 346.649703 -393.299796) (xy 346.60615 -393.275228)
			(xy 346.566787 -393.24439) (xy 346.532508 -393.207984) (xy 346.504093 -393.166838) (xy 346.482187 -393.121888)
			(xy 346.467289 -393.074154) (xy 346.459738 -393.024724) (xy 346.459302 -392.999722) (xy 346.459812 -392.973735)
			(xy 346.467942 -392.9224) (xy 346.484003 -392.87297) (xy 346.507599 -392.82666) (xy 346.538149 -392.784612)
			(xy 346.5749 -392.747861) (xy 346.616948 -392.717311) (xy 346.663258 -392.693715) (xy 346.712688 -392.677654)
			(xy 346.764023 -392.669524) (xy 346.815997 -392.669524) (xy 346.867332 -392.677654) (xy 346.916762 -392.693715)
			(xy 346.963072 -392.717311) (xy 347.00512 -392.747861) (xy 347.041871 -392.784612) (xy 347.072421 -392.82666)
			(xy 347.096017 -392.87297) (xy 347.112078 -392.9224) (xy 347.120208 -392.973735) (xy 347.120718 -392.999722)
			(xy 347.120718 -393.00023) (xy 347.120116 -393.027278) (xy 347.11118 -393.080633) (xy 347.102938 -393.106402)
			(xy 347.099382 -393.11707) (xy 347.100398 -393.127738) (xy 347.10112 -393.133457) (xy 347.104834 -393.144365)
			(xy 347.107764 -393.149328) (xy 347.128084 -393.182348) (xy 347.148658 -393.215876) (xy 347.151659 -393.220577)
			(xy 347.159347 -393.228654) (xy 347.163898 -393.231878) (xy 347.173042 -393.23772) (xy 347.18244 -393.239244)
			(xy 347.184726 -393.239498) (xy 347.212106 -393.243904) (xy 347.265616 -393.258482) (xy 347.316975 -393.27941)
			(xy 347.365434 -393.306383) (xy 347.410283 -393.339006) (xy 347.430852 -393.357608) (xy 347.45293 -393.378871)
			(xy 347.491777 -393.426284) (xy 347.523953 -393.478456) (xy 347.548881 -393.534453) (xy 347.566117 -393.593276)
			(xy 347.575353 -393.653872) (xy 347.576394 -393.684506) (xy 347.576394 -393.692634) (xy 347.575944 -393.721986)
			(xy 347.568425 -393.780207) (xy 347.561408 -393.808712) (xy 347.5609 -393.81049) (xy 347.5609 -393.810998)
			(xy 347.55963 -393.815062) (xy 347.558868 -393.817348) (xy 347.557221 -393.826565) (xy 347.559956 -393.845071)
			(xy 347.564202 -393.853416) (xy 347.564456 -393.853924) (xy 347.59646 -393.909296) (xy 347.599079 -393.913595)
			(xy 347.60573 -393.921148) (xy 347.609668 -393.924282) (xy 347.632782 -393.941808) (xy 347.64218 -393.944602)
			(xy 347.670658 -393.953071) (xy 347.725316 -393.976365) (xy 347.7765 -394.006534) (xy 347.823351 -394.043073)
			(xy 347.86508 -394.085366) (xy 347.900987 -394.132702) (xy 347.930468 -394.184286) (xy 347.953027 -394.239251)
			(xy 347.968286 -394.296672) (xy 347.975987 -394.355585) (xy 347.976444 -394.385292) (xy 347.976329 -394.399491)
			(xy 347.974551 -394.427832) (xy 347.972888 -394.441934) (xy 347.972442 -394.446456) (xy 347.972948 -394.455526)
			(xy 347.973904 -394.459968) (xy 347.975682 -394.467842) (xy 347.980254 -394.475208) (xy 347.995748 -394.5001)
			(xy 348.000452 -394.507166) (xy 348.013558 -394.517937) (xy 348.021402 -394.521182) (xy 348.044774 -394.53038)
			(xy 348.088655 -394.554816) (xy 348.128337 -394.585605) (xy 348.162909 -394.622038) (xy 348.191576 -394.663279)
			(xy 348.213679 -394.70838) (xy 348.22871 -394.756304) (xy 348.236323 -394.805949) (xy 348.236794 -394.831062)
			(xy 348.236361 -394.85518) (xy 348.229365 -394.902904) (xy 348.215516 -394.949109) (xy 348.195108 -394.992813)
			(xy 348.182184 -395.01318) (xy 348.17812 -395.01953) (xy 348.173802 -395.0335) (xy 348.173802 -395.045438)
			(xy 348.17431 -395.05255) (xy 348.17685 -395.07033) (xy 348.17812 -395.080236) (xy 348.196154 -395.111732)
			(xy 348.203012 -395.117574) (xy 348.22427 -395.136255) (xy 348.262478 -395.178003) (xy 348.295249 -395.224142)
			(xy 348.322082 -395.273969) (xy 348.342568 -395.326724) (xy 348.356395 -395.381602) (xy 348.363351 -395.437765)
			(xy 348.363794 -395.466062) (xy 348.363794 -395.46657) (xy 348.363222 -395.498823) (xy 348.354121 -395.562685)
			(xy 348.336137 -395.624635) (xy 348.323408 -395.654276) (xy 348.321376 -395.658594) (xy 348.318664 -395.668039)
			(xy 348.319853 -395.687634) (xy 348.323662 -395.696694) (xy 348.330012 -395.71041) (xy 348.333314 -395.714728)
			(xy 348.342966 -395.727428) (xy 348.346522 -395.730476) (xy 348.370748 -395.752309) (xy 348.413381 -395.80166)
			(xy 348.448572 -395.856565) (xy 348.475607 -395.915913) (xy 348.493937 -395.978499) (xy 348.503192 -396.043054)
			(xy 348.503748 -396.075662) (xy 348.503074 -396.11077) (xy 348.49236 -396.180163) (xy 348.482412 -396.213838)
			(xy 348.481396 -396.216886) (xy 348.479345 -396.227469) (xy 348.483298 -396.248641) (xy 348.489016 -396.25778)
			(xy 348.489778 -396.25905) (xy 348.538292 -396.32509) (xy 348.539054 -396.326106) (xy 348.539562 -396.326614)
			(xy 348.547087 -396.335292) (xy 348.567714 -396.345349) (xy 348.579186 -396.345918) (xy 348.71279 -396.345918)
			(xy 348.722233 -396.345422) (xy 348.739814 -396.338509) (xy 348.74708 -396.332456) (xy 348.752922 -396.326106)
			(xy 348.75343 -396.325598) (xy 348.801944 -396.259304) (xy 348.808146 -396.249933) (xy 348.812487 -396.227915)
			(xy 348.810326 -396.216886) (xy 348.80931 -396.212822) (xy 348.809056 -396.21206) (xy 348.799346 -396.178799)
			(xy 348.788894 -396.110305) (xy 348.788228 -396.075662) (xy 348.788228 -396.075154) (xy 348.788798 -396.0429)
			(xy 348.797894 -395.979036) (xy 348.815872 -395.917084) (xy 348.828614 -395.887448) (xy 348.830646 -395.88313)
			(xy 348.833362 -395.873685) (xy 348.832182 -395.854085) (xy 348.82836 -395.84503) (xy 348.82201 -395.831314)
			(xy 348.818708 -395.826996) (xy 348.809056 -395.814296) (xy 348.8055 -395.811248) (xy 348.781277 -395.789414)
			(xy 348.73865 -395.740062) (xy 348.703467 -395.685155) (xy 348.67644 -395.625807) (xy 348.658119 -395.563222)
			(xy 348.648874 -395.498668) (xy 348.648274 -395.466062) (xy 348.648697 -395.437766) (xy 348.655672 -395.381606)
			(xy 348.669512 -395.326733) (xy 348.690004 -395.273982) (xy 348.716839 -395.224157) (xy 348.749605 -395.178016)
			(xy 348.787806 -395.136263) (xy 348.809056 -395.117574) (xy 348.815914 -395.111732) (xy 348.833948 -395.080236)
			(xy 348.835218 -395.07033) (xy 348.838266 -395.04874) (xy 348.838266 -395.048486) (xy 348.839536 -395.039088)
			(xy 348.835472 -395.021562) (xy 348.834456 -395.019784) (xy 348.830392 -395.013688) (xy 348.816624 -394.992132)
			(xy 348.795184 -394.945696) (xy 348.78772 -394.921232) (xy 348.782894 -394.901928) (xy 348.781116 -394.893546)
			(xy 348.776798 -394.886434) (xy 348.774448 -394.882724) (xy 348.768704 -394.876082) (xy 348.765368 -394.873226)
			(xy 348.748858 -394.859764) (xy 348.741746 -394.854176) (xy 348.71152 -394.843) (xy 348.703138 -394.842746)
			(xy 348.67386 -394.841269) (xy 348.61601 -394.831787) (xy 348.559844 -394.814995) (xy 348.506282 -394.79117)
			(xy 348.4562 -394.7607) (xy 348.410419 -394.724086) (xy 348.369687 -394.681926) (xy 348.334671 -394.63491)
			(xy 348.305946 -394.583808) (xy 348.28398 -394.529457) (xy 348.269133 -394.472746) (xy 348.26165 -394.414603)
			(xy 348.261178 -394.385292) (xy 348.261178 -394.385038) (xy 348.261178 -394.384022) (xy 348.261646 -394.355522)
			(xy 348.268779 -394.29897) (xy 348.275402 -394.271246) (xy 348.276164 -394.268452) (xy 348.277942 -394.255752)
			(xy 348.277942 -394.245846) (xy 348.277722 -394.239243) (xy 348.27425 -394.226499) (xy 348.271084 -394.2207)
			(xy 348.241112 -394.168376) (xy 348.238491 -394.16408) (xy 348.231835 -394.156533) (xy 348.227904 -394.15339)
			(xy 348.20479 -394.135864) (xy 348.195392 -394.13307) (xy 348.166916 -394.1246) (xy 348.112263 -394.101303)
			(xy 348.061084 -394.071131) (xy 348.014238 -394.034591) (xy 347.972514 -393.992298) (xy 347.936612 -393.944962)
			(xy 347.907136 -393.893378) (xy 347.884582 -393.838415) (xy 347.869328 -393.780996) (xy 347.861631 -393.722085)
			(xy 347.861128 -393.69238) (xy 347.861128 -393.679934) (xy 347.862409 -393.650621) (xy 347.871516 -393.592658)
			(xy 347.887957 -393.536335) (xy 347.911462 -393.482574) (xy 347.926152 -393.457176) (xy 347.926152 -393.456668)
			(xy 347.926406 -393.456414) (xy 347.929071 -393.451704) (xy 347.932533 -393.441455) (xy 347.933264 -393.436094)
			(xy 347.93428 -393.425172) (xy 347.904816 -393.34059) (xy 347.900636 -393.330313) (xy 347.885226 -393.314386)
			(xy 347.875098 -393.309856) (xy 347.872812 -393.30884) (xy 347.869002 -393.30757) (xy 347.867224 -393.306808)
			(xy 347.86697 -393.306808) (xy 347.865192 -393.306046) (xy 347.842674 -393.296405) (xy 347.800525 -393.271453)
			(xy 347.762518 -393.240556) (xy 347.729485 -393.204389) (xy 347.70215 -393.163745) (xy 347.68111 -393.119512)
			(xy 347.666826 -393.07266) (xy 347.659611 -393.024213) (xy 347.659198 -392.999722) (xy 347.659708 -392.973735)
			(xy 347.667838 -392.9224) (xy 347.683899 -392.87297) (xy 347.707495 -392.82666) (xy 347.738045 -392.784612)
			(xy 347.774796 -392.747861) (xy 347.816844 -392.717311) (xy 347.863154 -392.693715) (xy 347.912584 -392.677654)
			(xy 347.963919 -392.669524) (xy 348.015893 -392.669524) (xy 348.067228 -392.677654) (xy 348.116658 -392.693715)
			(xy 348.162968 -392.717311) (xy 348.205016 -392.747861) (xy 348.241767 -392.784612) (xy 348.272317 -392.82666)
			(xy 348.295913 -392.87297) (xy 348.311974 -392.9224) (xy 348.320104 -392.973735) (xy 348.320614 -392.999722)
			(xy 348.320614 -393.000484) (xy 348.320126 -393.026518) (xy 348.311955 -393.07794) (xy 348.304358 -393.102846)
			(xy 348.303088 -393.106656) (xy 348.301564 -393.11453) (xy 348.300869 -393.119145) (xy 348.301001 -393.128477)
			(xy 348.301818 -393.133072) (xy 348.303596 -393.142216) (xy 348.308422 -393.15009) (xy 348.347792 -393.215114)
			(xy 348.3483 -393.21613) (xy 348.356428 -393.225782) (xy 348.3595 -393.228564) (xy 348.366394 -393.233162)
			(xy 348.370144 -393.234926) (xy 348.377764 -393.238482) (xy 348.384876 -393.239498) (xy 348.413819 -393.244197)
			(xy 348.470284 -393.260009) (xy 348.524268 -393.282899) (xy 348.574888 -393.312494) (xy 348.621316 -393.348309)
			(xy 348.662792 -393.389757) (xy 348.698637 -393.436162) (xy 348.728265 -393.486762) (xy 348.751191 -393.540731)
			(xy 348.76704 -393.597185) (xy 348.775552 -393.655201) (xy 348.776544 -393.684506) (xy 348.776544 -393.692634)
			(xy 348.776094 -393.721986) (xy 348.768576 -393.780207) (xy 348.761558 -393.808712) (xy 348.76105 -393.81049)
			(xy 348.76105 -393.810998) (xy 348.75978 -393.815062) (xy 348.759018 -393.817348) (xy 348.757312 -393.826563)
			(xy 348.760053 -393.845089) (xy 348.764352 -393.853416) (xy 348.764606 -393.853924) (xy 348.79661 -393.909296)
			(xy 348.799227 -393.913597) (xy 348.805874 -393.921155) (xy 348.809818 -393.924282) (xy 348.832932 -393.941808)
			(xy 348.84233 -393.944602) (xy 348.870806 -393.953073) (xy 348.925458 -393.976371) (xy 348.976637 -394.006544)
			(xy 349.023483 -394.043084) (xy 349.065208 -394.085377) (xy 349.101111 -394.132712) (xy 349.130588 -394.184295)
			(xy 349.153144 -394.239258) (xy 349.1684 -394.296677) (xy 349.1761 -394.355587) (xy 349.176594 -394.385292)
			(xy 349.176487 -394.399554) (xy 349.174711 -394.428024) (xy 349.173038 -394.442188) (xy 349.171768 -394.451586)
			(xy 349.1738 -394.459968) (xy 349.174887 -394.464059) (xy 349.178209 -394.471843) (xy 349.180404 -394.475462)
			(xy 349.192088 -394.493496) (xy 349.198438 -394.501624) (xy 349.202502 -394.505434) (xy 349.221298 -394.520928)
			(xy 349.22587 -394.522706) (xy 349.228918 -394.523976) (xy 349.251601 -394.53354) (xy 349.294085 -394.558403)
			(xy 349.332413 -394.58929) (xy 349.365738 -394.625519) (xy 349.393322 -394.666289) (xy 349.414556 -394.710698)
			(xy 349.428969 -394.757765) (xy 349.436245 -394.806449) (xy 349.43669 -394.831062) (xy 349.436257 -394.85518)
			(xy 349.429261 -394.902904) (xy 349.415412 -394.949108) (xy 349.395003 -394.992813) (xy 349.38208 -395.01318)
			(xy 349.378016 -395.01953) (xy 349.373698 -395.0335) (xy 349.373698 -395.045438) (xy 349.374206 -395.05255)
			(xy 349.376746 -395.07033) (xy 349.378016 -395.080236) (xy 349.39605 -395.111732) (xy 349.402908 -395.117574)
			(xy 349.424166 -395.136255) (xy 349.462375 -395.178002) (xy 349.495146 -395.224142) (xy 349.521979 -395.273969)
			(xy 349.542465 -395.326724) (xy 349.556292 -395.381602) (xy 349.563249 -395.437765) (xy 349.56369 -395.466062)
			(xy 349.56369 -395.46657) (xy 349.563119 -395.498823) (xy 349.554019 -395.562686) (xy 349.536039 -395.624637)
			(xy 349.523304 -395.654276) (xy 349.521272 -395.658594) (xy 349.51856 -395.668039) (xy 349.519749 -395.687634)
			(xy 349.523558 -395.696694) (xy 349.529908 -395.71041) (xy 349.53321 -395.714728) (xy 349.542862 -395.727428)
			(xy 349.546418 -395.730476) (xy 349.570644 -395.752309) (xy 349.613278 -395.801659) (xy 349.648469 -395.856565)
			(xy 349.675504 -395.915913) (xy 349.693835 -395.978499) (xy 349.70309 -396.043054) (xy 349.703644 -396.075662)
			(xy 349.70297 -396.11077) (xy 349.692256 -396.180163) (xy 349.682308 -396.213838) (xy 349.681292 -396.216886)
			(xy 349.67924 -396.227468) (xy 349.683198 -396.248638) (xy 349.688912 -396.25778) (xy 349.689674 -396.25905)
			(xy 349.738188 -396.32509) (xy 349.73895 -396.326106) (xy 349.739458 -396.326614) (xy 349.746983 -396.335293)
			(xy 349.76761 -396.345351) (xy 349.779082 -396.345918) (xy 349.91294 -396.345918) (xy 349.922386 -396.34543)
			(xy 349.93998 -396.33853) (xy 349.94723 -396.332456) (xy 349.953072 -396.326106) (xy 349.95358 -396.325598)
			(xy 350.002094 -396.259304) (xy 350.008291 -396.249932) (xy 350.012628 -396.227915) (xy 350.010476 -396.216886)
			(xy 350.00946 -396.212822) (xy 350.009206 -396.21206) (xy 349.999495 -396.178799) (xy 349.989042 -396.110305)
			(xy 349.988378 -396.075662) (xy 349.988378 -396.075154) (xy 349.988948 -396.0429) (xy 349.998046 -395.979037)
			(xy 350.016026 -395.917085) (xy 350.028764 -395.887448) (xy 350.030796 -395.88313) (xy 350.033514 -395.873685)
			(xy 350.032333 -395.854085) (xy 350.02851 -395.84503) (xy 350.02216 -395.831314) (xy 350.018858 -395.826996)
			(xy 350.009206 -395.814296) (xy 350.00565 -395.811248) (xy 349.981425 -395.789415) (xy 349.938793 -395.740065)
			(xy 349.903606 -395.685159) (xy 349.876576 -395.625811) (xy 349.858253 -395.563224) (xy 349.849007 -395.498669)
			(xy 349.848424 -395.466062) (xy 349.848847 -395.437766) (xy 349.855822 -395.381605) (xy 349.86966 -395.32673)
			(xy 349.890151 -395.273978) (xy 349.916983 -395.224151) (xy 349.949748 -395.178008) (xy 349.987946 -395.136251)
			(xy 350.009206 -395.117574) (xy 350.016064 -395.111732) (xy 350.034098 -395.080236) (xy 350.035368 -395.07033)
			(xy 350.038416 -395.04874) (xy 350.038416 -395.048486) (xy 350.039686 -395.039088) (xy 350.035622 -395.021562)
			(xy 350.034606 -395.019784) (xy 350.030542 -395.013688) (xy 350.016776 -394.992131) (xy 349.995339 -394.945695)
			(xy 349.98787 -394.921232) (xy 349.983044 -394.902182) (xy 349.983044 -394.901928) (xy 349.981012 -394.893292)
			(xy 349.976948 -394.886434) (xy 349.974585 -394.88279) (xy 349.96884 -394.876278) (xy 349.965518 -394.87348)
			(xy 349.949008 -394.860018) (xy 349.94215 -394.854176) (xy 349.911416 -394.843) (xy 349.903288 -394.842746)
			(xy 349.874 -394.841284) (xy 349.816125 -394.831827) (xy 349.759933 -394.815056) (xy 349.706343 -394.791244)
			(xy 349.656233 -394.760783) (xy 349.610425 -394.724171) (xy 349.569668 -394.682008) (xy 349.53463 -394.634984)
			(xy 349.505885 -394.58387) (xy 349.483904 -394.529504) (xy 349.469048 -394.472775) (xy 349.461559 -394.414613)
			(xy 349.461074 -394.385292) (xy 349.461074 -394.385038) (xy 349.461074 -394.384022) (xy 349.461542 -394.355522)
			(xy 349.468675 -394.29897) (xy 349.475298 -394.271246) (xy 349.47606 -394.268452) (xy 349.477838 -394.255752)
			(xy 349.477838 -394.245846) (xy 349.477618 -394.239243) (xy 349.474146 -394.226499) (xy 349.47098 -394.2207)
			(xy 349.441008 -394.168376) (xy 349.438386 -394.16408) (xy 349.43173 -394.156534) (xy 349.4278 -394.15339)
			(xy 349.404686 -394.135864) (xy 349.395288 -394.13307) (xy 349.366812 -394.124599) (xy 349.31216 -394.101302)
			(xy 349.260981 -394.07113) (xy 349.214136 -394.03459) (xy 349.172412 -393.992297) (xy 349.13651 -393.944961)
			(xy 349.107034 -393.893378) (xy 349.08448 -393.838415) (xy 349.069227 -393.780995) (xy 349.06153 -393.722085)
			(xy 349.061024 -393.69238) (xy 349.061024 -393.679934) (xy 349.062305 -393.650621) (xy 349.071412 -393.592658)
			(xy 349.087853 -393.536335) (xy 349.111357 -393.482574) (xy 349.126048 -393.457176) (xy 349.126048 -393.456668)
			(xy 349.126302 -393.456414) (xy 349.128967 -393.451705) (xy 349.13243 -393.441455) (xy 349.13316 -393.436094)
			(xy 349.134176 -393.425172) (xy 349.104712 -393.34059) (xy 349.100532 -393.330314) (xy 349.085121 -393.314387)
			(xy 349.074994 -393.309856) (xy 349.072708 -393.30884) (xy 349.068898 -393.30757) (xy 349.06712 -393.306808)
			(xy 349.066866 -393.306808) (xy 349.065088 -393.306046) (xy 349.042571 -393.296405) (xy 349.000422 -393.271453)
			(xy 348.962415 -393.240555) (xy 348.929383 -393.204388) (xy 348.902048 -393.163744) (xy 348.881008 -393.119512)
			(xy 348.866725 -393.07266) (xy 348.85951 -393.024213) (xy 348.859094 -392.999722) (xy 348.859604 -392.973735)
			(xy 348.867734 -392.9224) (xy 348.883795 -392.87297) (xy 348.907391 -392.82666) (xy 348.937941 -392.784612)
			(xy 348.974692 -392.747861) (xy 349.01674 -392.717311) (xy 349.06305 -392.693715) (xy 349.11248 -392.677654)
			(xy 349.163815 -392.669524) (xy 349.215789 -392.669524) (xy 349.267124 -392.677654) (xy 349.316554 -392.693715)
			(xy 349.362864 -392.717311) (xy 349.404912 -392.747861) (xy 349.441663 -392.784612) (xy 349.472213 -392.82666)
			(xy 349.495809 -392.87297) (xy 349.51187 -392.9224) (xy 349.52 -392.973735) (xy 349.52051 -392.999722)
			(xy 349.52051 -393.000484) (xy 349.520022 -393.026518) (xy 349.511851 -393.07794) (xy 349.504254 -393.102846)
			(xy 349.502984 -393.106656) (xy 349.50146 -393.11453) (xy 349.500765 -393.119145) (xy 349.500897 -393.128477)
			(xy 349.501714 -393.133072) (xy 349.503492 -393.142216) (xy 349.508318 -393.15009) (xy 349.547688 -393.215114)
			(xy 349.548196 -393.21613) (xy 349.556324 -393.225782) (xy 349.559396 -393.228564) (xy 349.56629 -393.233163)
			(xy 349.57004 -393.234926) (xy 349.57766 -393.238482) (xy 349.584772 -393.239498) (xy 349.613715 -393.244197)
			(xy 349.67018 -393.260008) (xy 349.724165 -393.282898) (xy 349.774785 -393.312493) (xy 349.821213 -393.348308)
			(xy 349.86269 -393.389756) (xy 349.898536 -393.436161) (xy 349.928164 -393.486761) (xy 349.95109 -393.54073)
			(xy 349.966939 -393.597185) (xy 349.975452 -393.6552) (xy 349.97644 -393.684506) (xy 349.97644 -393.692634)
			(xy 349.97599 -393.721986) (xy 349.968472 -393.780207) (xy 349.961454 -393.808712) (xy 349.960946 -393.81049)
			(xy 349.960946 -393.810998) (xy 349.959676 -393.815062) (xy 349.958914 -393.817348) (xy 349.957208 -393.826563)
			(xy 349.959949 -393.845089) (xy 349.964248 -393.853416) (xy 349.964502 -393.853924) (xy 349.996506 -393.909296)
			(xy 349.999122 -393.913597) (xy 350.005769 -393.921155) (xy 350.009714 -393.924282) (xy 350.032828 -393.941808)
			(xy 350.042226 -393.944602) (xy 350.070702 -393.953073) (xy 350.125355 -393.976371) (xy 350.176534 -394.006543)
			(xy 350.22338 -394.043083) (xy 350.265106 -394.085376) (xy 350.301009 -394.132712) (xy 350.330486 -394.184294)
			(xy 350.353043 -394.239257) (xy 350.368299 -394.296676) (xy 350.375999 -394.355586) (xy 350.37649 -394.385292)
			(xy 350.376376 -394.399491) (xy 350.374597 -394.427833) (xy 350.372934 -394.441934) (xy 350.372494 -394.446456)
			(xy 350.372999 -394.455526) (xy 350.37395 -394.459968) (xy 350.375728 -394.467842) (xy 350.3803 -394.475208)
			(xy 350.395794 -394.5001) (xy 350.400501 -394.507161) (xy 350.413612 -394.517922) (xy 350.421448 -394.521182)
			(xy 350.444818 -394.530382) (xy 350.488693 -394.554822) (xy 350.52837 -394.585612) (xy 350.562937 -394.622047)
			(xy 350.5916 -394.663287) (xy 350.613699 -394.708387) (xy 350.628728 -394.756308) (xy 350.63634 -394.805951)
			(xy 350.63684 -394.831062) (xy 350.636407 -394.85518) (xy 350.629412 -394.902905) (xy 350.615565 -394.94911)
			(xy 350.595159 -394.992816) (xy 350.58223 -395.01318) (xy 350.578166 -395.01953) (xy 350.573848 -395.0335)
			(xy 350.573848 -395.045438) (xy 350.574356 -395.05255) (xy 350.576896 -395.07033) (xy 350.578166 -395.080236)
			(xy 350.5962 -395.111732) (xy 350.603058 -395.117574) (xy 350.624314 -395.136256) (xy 350.662519 -395.178005)
			(xy 350.695286 -395.224145) (xy 350.722116 -395.273972) (xy 350.7426 -395.326727) (xy 350.756425 -395.381604)
			(xy 350.763381 -395.437766) (xy 350.76384 -395.466062) (xy 350.76384 -395.46657) (xy 350.763268 -395.498823)
			(xy 350.754168 -395.562686) (xy 350.736186 -395.624636) (xy 350.723454 -395.654276) (xy 350.721422 -395.658594)
			(xy 350.718708 -395.668039) (xy 350.719899 -395.687634) (xy 350.723708 -395.696694) (xy 350.730058 -395.71041)
			(xy 350.73336 -395.714728) (xy 350.743012 -395.727428) (xy 350.746568 -395.730476) (xy 350.770796 -395.752308)
			(xy 350.813434 -395.801656) (xy 350.848629 -395.856561) (xy 350.875668 -395.915909) (xy 350.894001 -395.978497)
			(xy 350.903257 -396.043053) (xy 350.903794 -396.075662) (xy 350.90312 -396.110769) (xy 350.892405 -396.180162)
			(xy 350.882458 -396.213838) (xy 350.881442 -396.216886) (xy 350.87939 -396.227469) (xy 350.883346 -396.24864)
			(xy 350.889062 -396.25778) (xy 350.889824 -396.25905) (xy 350.938338 -396.32509) (xy 350.9391 -396.326106)
			(xy 350.939608 -396.326614) (xy 350.947136 -396.335285) (xy 350.967764 -396.345323) (xy 350.979232 -396.345918)
			(xy 351.112836 -396.345918) (xy 351.122282 -396.345431) (xy 351.139877 -396.338531) (xy 351.147126 -396.332456)
			(xy 351.152968 -396.326106) (xy 351.153476 -396.325598) (xy 351.20199 -396.259304) (xy 351.208188 -396.249932)
			(xy 351.212524 -396.227915) (xy 351.210372 -396.216886) (xy 351.209356 -396.212822) (xy 351.209102 -396.21206)
			(xy 351.199391 -396.178799) (xy 351.188938 -396.110305) (xy 351.188274 -396.075662) (xy 351.188274 -396.075154)
			(xy 351.188844 -396.0429) (xy 351.197942 -395.979037) (xy 351.215921 -395.917085) (xy 351.22866 -395.887448)
			(xy 351.230692 -395.88313) (xy 351.23341 -395.873685) (xy 351.232229 -395.854085) (xy 351.228406 -395.84503)
			(xy 351.222056 -395.831314) (xy 351.218754 -395.826996) (xy 351.209102 -395.814296) (xy 351.205546 -395.811248)
			(xy 351.181321 -395.789415) (xy 351.13869 -395.740065) (xy 351.103503 -395.685159) (xy 351.076474 -395.62581)
			(xy 351.05815 -395.563224) (xy 351.048905 -395.498669) (xy 351.04832 -395.466062) (xy 351.048743 -395.437766)
			(xy 351.055718 -395.381605) (xy 351.069556 -395.32673) (xy 351.090047 -395.273978) (xy 351.116879 -395.224151)
			(xy 351.149643 -395.178007) (xy 351.187841 -395.136251) (xy 351.209102 -395.117574) (xy 351.21596 -395.111732)
			(xy 351.233994 -395.080236) (xy 351.235264 -395.07033) (xy 351.238312 -395.04874) (xy 351.238312 -395.048486)
			(xy 351.239582 -395.039088) (xy 351.235518 -395.021562) (xy 351.234502 -395.019784) (xy 351.230438 -395.013688)
			(xy 351.216672 -394.992131) (xy 351.195235 -394.945694) (xy 351.187766 -394.921232) (xy 351.18294 -394.902182)
			(xy 351.18294 -394.901928) (xy 351.180908 -394.893292) (xy 351.176844 -394.886434) (xy 351.174481 -394.88279)
			(xy 351.168735 -394.876279) (xy 351.165414 -394.87348) (xy 351.148904 -394.860018) (xy 351.142046 -394.854176)
			(xy 351.111312 -394.843) (xy 351.103184 -394.842746) (xy 351.073896 -394.841284) (xy 351.016022 -394.831827)
			(xy 350.95983 -394.815055) (xy 350.90624 -394.791243) (xy 350.856131 -394.760782) (xy 350.810323 -394.72417)
			(xy 350.769566 -394.682006) (xy 350.734529 -394.634983) (xy 350.705784 -394.583869) (xy 350.683804 -394.529503)
			(xy 350.668948 -394.472774) (xy 350.661459 -394.414613) (xy 350.66097 -394.385292) (xy 350.66097 -394.384784)
			(xy 350.66097 -394.383768) (xy 350.661436 -394.355268) (xy 350.668568 -394.298715) (xy 350.675194 -394.270992)
			(xy 350.675956 -394.268198) (xy 350.677734 -394.255498) (xy 350.677734 -394.245338) (xy 350.677575 -394.240653)
			(xy 350.675784 -394.231454) (xy 350.674178 -394.22705) (xy 350.67113 -394.220192) (xy 350.66097 -394.202666)
			(xy 350.635824 -394.159232) (xy 350.6332 -394.154938) (xy 350.626541 -394.147395) (xy 350.622616 -394.144246)
			(xy 350.614742 -394.13815) (xy 350.604582 -394.13561) (xy 350.57547 -394.127608) (xy 350.519493 -394.104985)
			(xy 350.466976 -394.075198) (xy 350.418832 -394.038765) (xy 350.375896 -393.996318) (xy 350.338913 -393.948595)
			(xy 350.308527 -393.896423) (xy 350.285263 -393.840709) (xy 350.269527 -393.78242) (xy 350.261591 -393.722568)
			(xy 350.261174 -393.69238) (xy 350.261174 -393.679934) (xy 350.262455 -393.650621) (xy 350.271563 -393.592659)
			(xy 350.288005 -393.536336) (xy 350.311512 -393.482577) (xy 350.326198 -393.457176) (xy 350.326198 -393.456668)
			(xy 350.326452 -393.456414) (xy 350.329119 -393.451705) (xy 350.332585 -393.441456) (xy 350.33331 -393.436094)
			(xy 350.334326 -393.425172) (xy 350.304862 -393.34059) (xy 350.300685 -393.330309) (xy 350.285281 -393.314369)
			(xy 350.275144 -393.309856) (xy 350.272858 -393.30884) (xy 350.269048 -393.30757) (xy 350.26727 -393.306808)
			(xy 350.267016 -393.306808) (xy 350.265238 -393.306046) (xy 350.242723 -393.296402) (xy 350.20058 -393.271447)
			(xy 350.162579 -393.240547) (xy 350.129552 -393.20438) (xy 350.102221 -393.163736) (xy 350.081186 -393.119505)
			(xy 350.066905 -393.072655) (xy 350.059691 -393.024211) (xy 350.059244 -392.999722) (xy 350.059754 -392.973735)
			(xy 350.067884 -392.9224) (xy 350.083945 -392.87297) (xy 350.107541 -392.82666) (xy 350.138091 -392.784612)
			(xy 350.174842 -392.747861) (xy 350.21689 -392.717311) (xy 350.2632 -392.693715) (xy 350.31263 -392.677654)
			(xy 350.363965 -392.669524) (xy 350.415939 -392.669524) (xy 350.467274 -392.677654) (xy 350.516704 -392.693715)
			(xy 350.563014 -392.717311) (xy 350.605062 -392.747861) (xy 350.641813 -392.784612) (xy 350.672363 -392.82666)
			(xy 350.695959 -392.87297) (xy 350.71202 -392.9224) (xy 350.72015 -392.973735) (xy 350.72066 -392.999722)
			(xy 350.72066 -393.000484) (xy 350.720172 -393.026518) (xy 350.712002 -393.077941) (xy 350.704404 -393.102846)
			(xy 350.703134 -393.106656) (xy 350.70161 -393.11453) (xy 350.700915 -393.119145) (xy 350.701047 -393.128477)
			(xy 350.701864 -393.133072) (xy 350.703642 -393.142216) (xy 350.708468 -393.15009) (xy 350.747838 -393.215114)
			(xy 350.748346 -393.21613) (xy 350.756474 -393.225782) (xy 350.759547 -393.228561) (xy 350.766444 -393.233153)
			(xy 350.77019 -393.234926) (xy 350.77781 -393.238482) (xy 350.781112 -393.23899) (xy 350.784922 -393.239498)
			(xy 350.813867 -393.244194) (xy 350.870337 -393.260001) (xy 350.924327 -393.282888) (xy 350.974953 -393.31248)
			(xy 351.021386 -393.348293) (xy 351.062868 -393.389742) (xy 351.098718 -393.436147) (xy 351.12835 -393.48675)
			(xy 351.151279 -393.540722) (xy 351.167131 -393.597179) (xy 351.175644 -393.655198) (xy 351.17659 -393.684506)
			(xy 351.17659 -393.692634) (xy 351.17614 -393.721986) (xy 351.168621 -393.780207) (xy 351.161604 -393.808712)
			(xy 351.161096 -393.81049) (xy 351.161096 -393.810998) (xy 351.159826 -393.815062) (xy 351.159064 -393.817348)
			(xy 351.157417 -393.826565) (xy 351.160152 -393.845071) (xy 351.164398 -393.853416) (xy 351.164652 -393.853924)
			(xy 351.196656 -393.909296) (xy 351.199274 -393.913595) (xy 351.205925 -393.921148) (xy 351.209864 -393.924282)
			(xy 351.232978 -393.941808) (xy 351.239836 -393.94384) (xy 351.24263 -393.944602) (xy 351.271083 -393.953091)
			(xy 351.325686 -393.976419) (xy 351.376812 -394.006614) (xy 351.423603 -394.043169) (xy 351.465272 -394.085469)
			(xy 351.50112 -394.132804) (xy 351.530543 -394.184378) (xy 351.553048 -394.239325) (xy 351.568257 -394.296722)
			(xy 351.575913 -394.355603) (xy 351.576386 -394.385292) (xy 351.576272 -394.399491) (xy 351.574493 -394.427833)
			(xy 351.57283 -394.441934) (xy 351.57239 -394.446456) (xy 351.572895 -394.455526) (xy 351.573846 -394.459968)
			(xy 351.575624 -394.467842) (xy 351.580196 -394.475208) (xy 351.59569 -394.5001) (xy 351.600397 -394.507162)
			(xy 351.613507 -394.517923) (xy 351.621344 -394.521182) (xy 351.644714 -394.530382) (xy 351.68859 -394.554821)
			(xy 351.728267 -394.585612) (xy 351.762835 -394.622046) (xy 351.791498 -394.663287) (xy 351.813597 -394.708386)
			(xy 351.828626 -394.756308) (xy 351.836238 -394.805951) (xy 351.836736 -394.831062) (xy 351.836303 -394.85518)
			(xy 351.829308 -394.902905) (xy 351.815461 -394.94911) (xy 351.795054 -394.992816) (xy 351.782126 -395.01318)
			(xy 351.778062 -395.01953) (xy 351.773744 -395.0335) (xy 351.773744 -395.045438) (xy 351.774252 -395.05255)
			(xy 351.776792 -395.07033) (xy 351.778062 -395.080236) (xy 351.796096 -395.111732) (xy 351.802954 -395.117574)
			(xy 351.82421 -395.136256) (xy 351.862415 -395.178005) (xy 351.895183 -395.224145) (xy 351.922013 -395.273972)
			(xy 351.942497 -395.326726) (xy 351.956323 -395.381603) (xy 351.963278 -395.437766) (xy 351.963736 -395.466062)
			(xy 351.963736 -395.46657) (xy 351.963164 -395.498823) (xy 351.954064 -395.562686) (xy 351.936082 -395.624636)
			(xy 351.92335 -395.654276) (xy 351.921318 -395.658594) (xy 351.918605 -395.668039) (xy 351.919795 -395.687634)
			(xy 351.923604 -395.696694) (xy 351.929954 -395.71041) (xy 351.933256 -395.714728) (xy 351.942908 -395.727428)
			(xy 351.946464 -395.730476) (xy 351.970693 -395.752308) (xy 352.013331 -395.801656) (xy 352.048526 -395.856561)
			(xy 352.075565 -395.915909) (xy 352.093898 -395.978496) (xy 352.103154 -396.043053) (xy 352.10369 -396.075662)
			(xy 352.103016 -396.110769) (xy 352.0923 -396.180162) (xy 352.082354 -396.213838) (xy 352.081338 -396.216886)
			(xy 352.079287 -396.227469) (xy 352.083242 -396.24864) (xy 352.088958 -396.25778) (xy 352.08972 -396.25905)
			(xy 352.138234 -396.32509) (xy 352.138996 -396.326106) (xy 352.139504 -396.326614) (xy 352.147032 -396.335285)
			(xy 352.167659 -396.345325) (xy 352.179128 -396.345918) (xy 352.312986 -396.345918) (xy 352.322429 -396.345422)
			(xy 352.340012 -396.33851) (xy 352.347276 -396.332456) (xy 352.353118 -396.326106) (xy 352.353626 -396.325598)
			(xy 352.40214 -396.259304) (xy 352.408343 -396.249933) (xy 352.412684 -396.227915) (xy 352.410522 -396.216886)
			(xy 352.409506 -396.212822) (xy 352.409252 -396.21206) (xy 352.399542 -396.178799) (xy 352.38909 -396.110305)
			(xy 352.388424 -396.075662) (xy 352.388424 -396.075154) (xy 352.388994 -396.0429) (xy 352.39809 -395.979036)
			(xy 352.416068 -395.917084) (xy 352.42881 -395.887448) (xy 352.430842 -395.88313) (xy 352.433558 -395.873685)
			(xy 352.432378 -395.854085) (xy 352.428556 -395.84503) (xy 352.422206 -395.831314) (xy 352.418904 -395.826996)
			(xy 352.409252 -395.814296) (xy 352.405696 -395.811248) (xy 352.381473 -395.789414) (xy 352.338847 -395.740062)
			(xy 352.303664 -395.685155) (xy 352.276637 -395.625807) (xy 352.258316 -395.563222) (xy 352.249072 -395.498668)
			(xy 352.24847 -395.466062) (xy 352.248893 -395.437766) (xy 352.255868 -395.381606) (xy 352.269707 -395.326732)
			(xy 352.2902 -395.273981) (xy 352.317034 -395.224156) (xy 352.349801 -395.178015) (xy 352.388001 -395.136262)
			(xy 352.409252 -395.117574) (xy 352.41611 -395.111732) (xy 352.434144 -395.080236) (xy 352.435414 -395.07033)
			(xy 352.438462 -395.04874) (xy 352.438462 -395.048486) (xy 352.439732 -395.039088) (xy 352.435668 -395.021562)
			(xy 352.434652 -395.019784) (xy 352.430588 -395.013688) (xy 352.41682 -394.992132) (xy 352.39538 -394.945696)
			(xy 352.387916 -394.921232) (xy 352.38309 -394.902182) (xy 352.38309 -394.901928) (xy 352.381058 -394.893292)
			(xy 352.376994 -394.886434) (xy 352.374633 -394.882788) (xy 352.368891 -394.876272) (xy 352.365564 -394.87348)
			(xy 352.349054 -394.860018) (xy 352.342196 -394.854176) (xy 352.311462 -394.843) (xy 352.303334 -394.842746)
			(xy 352.274044 -394.841287) (xy 352.216165 -394.831835) (xy 352.159968 -394.815067) (xy 352.106373 -394.791258)
			(xy 352.056258 -394.760798) (xy 352.010444 -394.724187) (xy 351.969682 -394.682023) (xy 351.93464 -394.634998)
			(xy 351.905892 -394.583882) (xy 351.883909 -394.529512) (xy 351.86905 -394.47278) (xy 351.86156 -394.414615)
			(xy 351.86112 -394.385292) (xy 351.86112 -394.385038) (xy 351.86112 -394.384022) (xy 351.861588 -394.355522)
			(xy 351.868722 -394.29897) (xy 351.875344 -394.271246) (xy 351.876106 -394.268452) (xy 351.877884 -394.255752)
			(xy 351.877884 -394.245846) (xy 351.877665 -394.239242) (xy 351.874196 -394.226497) (xy 351.871026 -394.2207)
			(xy 351.841054 -394.168376) (xy 351.838434 -394.164078) (xy 351.831782 -394.156527) (xy 351.827846 -394.15339)
			(xy 351.804732 -394.135864) (xy 351.795334 -394.13307) (xy 351.766861 -394.124597) (xy 351.712214 -394.101295)
			(xy 351.66104 -394.07112) (xy 351.614201 -394.034579) (xy 351.572482 -393.992285) (xy 351.536585 -393.944949)
			(xy 351.507113 -393.893368) (xy 351.484562 -393.838407) (xy 351.469311 -393.78099) (xy 351.461615 -393.722084)
			(xy 351.46107 -393.69238) (xy 351.46107 -393.679934) (xy 351.462351 -393.650621) (xy 351.471459 -393.592659)
			(xy 351.487901 -393.536336) (xy 351.511408 -393.482577) (xy 351.526094 -393.457176) (xy 351.526094 -393.456668)
			(xy 351.526348 -393.456414) (xy 351.529015 -393.451705) (xy 351.532482 -393.441457) (xy 351.533206 -393.436094)
			(xy 351.534222 -393.425172) (xy 351.504758 -393.34059) (xy 351.500581 -393.33031) (xy 351.485176 -393.314371)
			(xy 351.47504 -393.309856) (xy 351.472754 -393.30884) (xy 351.468944 -393.30757) (xy 351.467166 -393.306808)
			(xy 351.466912 -393.306808) (xy 351.465134 -393.306046) (xy 351.442619 -393.296402) (xy 351.400477 -393.271446)
			(xy 351.362476 -393.240546) (xy 351.329449 -393.204379) (xy 351.302119 -393.163735) (xy 351.281084 -393.119505)
			(xy 351.266803 -393.072655) (xy 351.259589 -393.024211) (xy 351.25914 -392.999722) (xy 351.25965 -392.973735)
			(xy 351.26778 -392.9224) (xy 351.283841 -392.87297) (xy 351.307437 -392.82666) (xy 351.337987 -392.784612)
			(xy 351.374738 -392.747861) (xy 351.416786 -392.717311) (xy 351.463096 -392.693715) (xy 351.512526 -392.677654)
			(xy 351.563861 -392.669524) (xy 351.615835 -392.669524) (xy 351.66717 -392.677654) (xy 351.7166 -392.693715)
			(xy 351.76291 -392.717311) (xy 351.804958 -392.747861) (xy 351.841709 -392.784612) (xy 351.872259 -392.82666)
			(xy 351.895855 -392.87297) (xy 351.911916 -392.9224) (xy 351.920046 -392.973735) (xy 351.920556 -392.999722)
			(xy 351.920556 -393.000484) (xy 351.920068 -393.026518) (xy 351.911898 -393.077941) (xy 351.9043 -393.102846)
			(xy 351.90303 -393.106656) (xy 351.901506 -393.11453) (xy 351.900811 -393.119145) (xy 351.900943 -393.128477)
			(xy 351.90176 -393.133072) (xy 351.903538 -393.142216) (xy 351.908364 -393.15009) (xy 351.947734 -393.215114)
			(xy 351.948242 -393.21613) (xy 351.95637 -393.225782) (xy 351.959443 -393.228562) (xy 351.96634 -393.233154)
			(xy 351.970086 -393.234926) (xy 351.977706 -393.238482) (xy 351.981008 -393.23899) (xy 351.984818 -393.239498)
			(xy 352.013764 -393.244194) (xy 352.070234 -393.26) (xy 352.124224 -393.282887) (xy 352.17485 -393.312479)
			(xy 352.221284 -393.348292) (xy 352.262766 -393.389741) (xy 352.298617 -393.436146) (xy 352.328249 -393.486749)
			(xy 352.351179 -393.540721) (xy 352.36703 -393.597178) (xy 352.375544 -393.655198) (xy 352.376486 -393.684506)
			(xy 352.376486 -393.692634) (xy 352.376036 -393.721986) (xy 352.368517 -393.780207) (xy 352.3615 -393.808712)
			(xy 352.360992 -393.81049) (xy 352.360992 -393.810998) (xy 352.359722 -393.815062) (xy 352.35896 -393.817348)
			(xy 352.357254 -393.826563) (xy 352.359997 -393.845088) (xy 352.364294 -393.853416) (xy 352.364548 -393.853924)
			(xy 352.396552 -393.909296) (xy 352.39917 -393.913595) (xy 352.405821 -393.921149) (xy 352.40976 -393.924282)
			(xy 352.432874 -393.941808) (xy 352.442272 -393.944602) (xy 352.470746 -393.953075) (xy 352.525394 -393.976377)
			(xy 352.576569 -394.006551) (xy 352.62341 -394.043093) (xy 352.665131 -394.085386) (xy 352.70103 -394.132721)
			(xy 352.730504 -394.184303) (xy 352.753058 -394.239264) (xy 352.768313 -394.29668) (xy 352.776012 -394.355588)
			(xy 352.776536 -394.385292) (xy 352.776421 -394.399491) (xy 352.774643 -394.427832) (xy 352.77298 -394.441934)
			(xy 352.772534 -394.446456) (xy 352.77304 -394.455526) (xy 352.773996 -394.459968) (xy 352.775774 -394.467842)
			(xy 352.780346 -394.475208) (xy 352.79584 -394.5001) (xy 352.800544 -394.507166) (xy 352.813649 -394.51794)
			(xy 352.821494 -394.521182) (xy 352.844867 -394.53038) (xy 352.888748 -394.554815) (xy 352.928431 -394.585603)
			(xy 352.963004 -394.622037) (xy 352.991672 -394.663278) (xy 353.013775 -394.708379) (xy 353.028807 -394.756303)
			(xy 353.03642 -394.805949) (xy 353.036886 -394.831062) (xy 353.036453 -394.855179) (xy 353.029457 -394.902904)
			(xy 353.015608 -394.949108) (xy 352.995199 -394.992813) (xy 352.982276 -395.01318) (xy 352.978212 -395.01953)
			(xy 352.973894 -395.0335) (xy 352.973894 -395.045438) (xy 352.974402 -395.05255) (xy 352.976942 -395.07033)
			(xy 352.978212 -395.080236) (xy 352.996246 -395.111732) (xy 353.003104 -395.117574) (xy 353.024362 -395.136255)
			(xy 353.062571 -395.178002) (xy 353.095342 -395.224141) (xy 353.122176 -395.273968) (xy 353.142662 -395.326723)
			(xy 353.156489 -395.381601) (xy 353.163446 -395.437765) (xy 353.163886 -395.466062) (xy 353.163886 -395.46657)
			(xy 353.163315 -395.498823) (xy 353.154215 -395.562686) (xy 353.136235 -395.624637) (xy 353.1235 -395.654276)
			(xy 353.121468 -395.658594) (xy 353.118756 -395.668039) (xy 353.119945 -395.687634) (xy 353.123754 -395.696694)
			(xy 353.130104 -395.71041) (xy 353.133406 -395.714728) (xy 353.143058 -395.727428) (xy 353.146614 -395.730476)
			(xy 353.17084 -395.752309) (xy 353.213474 -395.801659) (xy 353.248666 -395.856565) (xy 353.275701 -395.915912)
			(xy 353.294032 -395.978499) (xy 353.303287 -396.043054) (xy 353.30384 -396.075662) (xy 353.303166 -396.11077)
			(xy 353.292452 -396.180163) (xy 353.282504 -396.213838) (xy 353.281488 -396.216886) (xy 353.279436 -396.227468)
			(xy 353.283394 -396.248638) (xy 353.289108 -396.25778) (xy 353.28987 -396.25905) (xy 353.338384 -396.32509)
			(xy 353.339146 -396.326106) (xy 353.339654 -396.326614) (xy 353.347179 -396.335294) (xy 353.367806 -396.345354)
			(xy 353.379278 -396.345918) (xy 353.512882 -396.345918) (xy 353.522325 -396.345423) (xy 353.539909 -396.338512)
			(xy 353.547172 -396.332456) (xy 353.553014 -396.326106) (xy 353.553522 -396.325598) (xy 353.602036 -396.259304)
			(xy 353.608239 -396.249934) (xy 353.612581 -396.227915) (xy 353.610418 -396.216886) (xy 353.609402 -396.212822)
			(xy 353.609148 -396.21206) (xy 353.599438 -396.178799) (xy 353.588986 -396.110305) (xy 353.58832 -396.075662)
			(xy 353.58832 -396.075154) (xy 353.58889 -396.0429) (xy 353.597986 -395.979036) (xy 353.615964 -395.917084)
			(xy 353.628706 -395.887448) (xy 353.630738 -395.88313) (xy 353.633455 -395.873685) (xy 353.632274 -395.854085)
			(xy 353.628452 -395.84503) (xy 353.622102 -395.831314) (xy 353.6188 -395.826996) (xy 353.609148 -395.814296)
			(xy 353.605592 -395.811248) (xy 353.581369 -395.789414) (xy 353.538743 -395.740062) (xy 353.50356 -395.685155)
			(xy 353.476534 -395.625807) (xy 353.458213 -395.563221) (xy 353.448969 -395.498668) (xy 353.448366 -395.466062)
			(xy 353.448789 -395.437766) (xy 353.455764 -395.381606) (xy 353.469603 -395.326732) (xy 353.490096 -395.273981)
			(xy 353.51693 -395.224156) (xy 353.549696 -395.178015) (xy 353.587896 -395.136261) (xy 353.609148 -395.117574)
			(xy 353.616006 -395.111732) (xy 353.63404 -395.080236) (xy 353.63531 -395.07033) (xy 353.638358 -395.04874)
			(xy 353.638358 -395.048486) (xy 353.639628 -395.039088) (xy 353.635564 -395.021562) (xy 353.634548 -395.019784)
			(xy 353.630484 -395.013688) (xy 353.616716 -394.992132) (xy 353.595276 -394.945696) (xy 353.587812 -394.921232)
			(xy 353.582986 -394.902182) (xy 353.582986 -394.901928) (xy 353.580954 -394.893292) (xy 353.57689 -394.886434)
			(xy 353.574529 -394.882788) (xy 353.568786 -394.876273) (xy 353.56546 -394.87348) (xy 353.54895 -394.860018)
			(xy 353.542092 -394.854176) (xy 353.511358 -394.843) (xy 353.50323 -394.842746) (xy 353.47394 -394.841287)
			(xy 353.416062 -394.831834) (xy 353.359865 -394.815066) (xy 353.30627 -394.791257) (xy 353.256156 -394.760797)
			(xy 353.210342 -394.724185) (xy 353.169581 -394.682021) (xy 353.13454 -394.634996) (xy 353.105792 -394.583881)
			(xy 353.083809 -394.529511) (xy 353.06895 -394.47278) (xy 353.06146 -394.414615) (xy 353.061016 -394.385292)
			(xy 353.061016 -394.384784) (xy 353.061016 -394.383768) (xy 353.061482 -394.355268) (xy 353.068615 -394.298715)
			(xy 353.07524 -394.270992) (xy 353.076002 -394.268198) (xy 353.07778 -394.255498) (xy 353.07778 -394.245338)
			(xy 353.077621 -394.240654) (xy 353.075828 -394.231454) (xy 353.074224 -394.22705) (xy 353.071176 -394.220192)
			(xy 353.061016 -394.202666) (xy 353.03587 -394.159232) (xy 353.033248 -394.154936) (xy 353.026593 -394.147389)
			(xy 353.022662 -394.144246) (xy 353.014788 -394.13815) (xy 353.004628 -394.13561) (xy 352.975518 -394.127606)
			(xy 352.919547 -394.104978) (xy 352.867036 -394.075188) (xy 352.818897 -394.038753) (xy 352.775967 -393.996306)
			(xy 352.738989 -393.948583) (xy 352.708606 -393.896413) (xy 352.685346 -393.840701) (xy 352.669612 -393.782415)
			(xy 352.661678 -393.722566) (xy 352.66122 -393.69238) (xy 352.66122 -393.679934) (xy 352.662501 -393.650621)
			(xy 352.671608 -393.592658) (xy 352.688048 -393.536334) (xy 352.711553 -393.482574) (xy 352.726244 -393.457176)
			(xy 352.726244 -393.456668) (xy 352.726498 -393.456414) (xy 352.729163 -393.451705) (xy 352.732626 -393.441455)
			(xy 352.733356 -393.436094) (xy 352.734372 -393.425172) (xy 352.704908 -393.34059) (xy 352.700728 -393.330314)
			(xy 352.685317 -393.314388) (xy 352.67519 -393.309856) (xy 352.672904 -393.30884) (xy 352.669094 -393.30757)
			(xy 352.667316 -393.306808) (xy 352.667062 -393.306808) (xy 352.665284 -393.306046) (xy 352.642767 -393.296405)
			(xy 352.600618 -393.271452) (xy 352.562612 -393.240554) (xy 352.52958 -393.204388) (xy 352.502246 -393.163743)
			(xy 352.481207 -393.119511) (xy 352.466923 -393.072659) (xy 352.459708 -393.024213) (xy 352.45929 -392.999722)
			(xy 352.4598 -392.973735) (xy 352.46793 -392.9224) (xy 352.483991 -392.87297) (xy 352.507587 -392.82666)
			(xy 352.538137 -392.784612) (xy 352.574888 -392.747861) (xy 352.616936 -392.717311) (xy 352.663246 -392.693715)
			(xy 352.712676 -392.677654) (xy 352.764011 -392.669524) (xy 352.815985 -392.669524) (xy 352.86732 -392.677654)
			(xy 352.91675 -392.693715) (xy 352.96306 -392.717311) (xy 353.005108 -392.747861) (xy 353.041859 -392.784612)
			(xy 353.072409 -392.82666) (xy 353.096005 -392.87297) (xy 353.112066 -392.9224) (xy 353.120196 -392.973735)
			(xy 353.120706 -392.999722) (xy 353.659186 -392.999722) (xy 353.659696 -392.973735) (xy 353.667826 -392.9224)
			(xy 353.683887 -392.87297) (xy 353.707483 -392.82666) (xy 353.738033 -392.784612) (xy 353.774784 -392.747861)
			(xy 353.816832 -392.717311) (xy 353.863142 -392.693715) (xy 353.912572 -392.677654) (xy 353.963907 -392.669524)
			(xy 354.015881 -392.669524) (xy 354.067216 -392.677654) (xy 354.116646 -392.693715) (xy 354.162956 -392.717311)
			(xy 354.205004 -392.747861) (xy 354.241755 -392.784612) (xy 354.272305 -392.82666) (xy 354.295901 -392.87297)
			(xy 354.311962 -392.9224) (xy 354.320092 -392.973735) (xy 354.320602 -392.999722) (xy 354.320602 -393.00023)
			(xy 354.320038 -393.027204) (xy 354.311231 -393.08043) (xy 354.303076 -393.106148) (xy 354.299266 -393.11707)
			(xy 354.301806 -393.139422) (xy 354.348542 -393.215876) (xy 354.354851 -393.225063) (xy 354.373426 -393.237326)
			(xy 354.384356 -393.239498) (xy 354.38461 -393.239498) (xy 354.413925 -393.244222) (xy 354.471096 -393.260268)
			(xy 354.52571 -393.283575) (xy 354.57685 -393.313752) (xy 354.623656 -393.350291) (xy 354.665341 -393.392579)
			(xy 354.701206 -393.439904) (xy 354.730646 -393.491471) (xy 354.746991 -393.531344) (xy 355.82987 -393.531344)
			(xy 355.830305 -393.502709) (xy 355.837461 -393.445887) (xy 355.851641 -393.3904) (xy 355.872626 -393.337112)
			(xy 355.900087 -393.286854) (xy 355.916484 -393.263374) (xy 355.922164 -393.254858) (xy 355.926778 -393.23493)
			(xy 355.923207 -393.21479) (xy 355.918008 -393.20597) (xy 355.900541 -393.178017) (xy 355.872928 -393.118168)
			(xy 355.854181 -393.054977) (xy 355.844689 -392.989752) (xy 355.844094 -392.956796) (xy 355.844094 -392.956542)
			(xy 355.84451 -392.927299) (xy 355.851944 -392.869288) (xy 355.866707 -392.812697) (xy 355.888561 -392.758448)
			(xy 355.917147 -392.707425) (xy 355.952002 -392.66046) (xy 355.992556 -392.618319) (xy 356.038148 -392.581687)
			(xy 356.088036 -392.551163) (xy 356.141406 -392.527244) (xy 356.197389 -392.510319) (xy 356.255072 -392.500664)
			(xy 356.284276 -392.499088) (xy 356.293928 -392.498834) (xy 356.3112 -392.491214) (xy 356.36708 -392.43508)
			(xy 356.373489 -392.428102) (xy 356.381054 -392.410743) (xy 356.381812 -392.401298) (xy 356.381812 -392.401044)
			(xy 356.383453 -392.368497) (xy 356.393941 -392.30418) (xy 356.412559 -392.24173) (xy 356.439003 -392.18217)
			(xy 356.472839 -392.126476) (xy 356.513512 -392.07556) (xy 356.560357 -392.030258) (xy 356.612605 -391.991312)
			(xy 356.6694 -391.959359) (xy 356.729812 -391.934924) (xy 356.792851 -391.918406) (xy 356.857483 -391.910077)
			(xy 356.890066 -391.909554) (xy 356.92365 -391.910082) (xy 356.990235 -391.918913) (xy 357.055076 -391.93644)
			(xy 357.117043 -391.962357) (xy 357.175055 -391.996211) (xy 357.228101 -392.037414) (xy 357.275257 -392.085245)
			(xy 357.3157 -392.138873) (xy 357.348726 -392.197361) (xy 357.361744 -392.228324) (xy 357.361744 -392.228578)
			(xy 357.365698 -392.237274) (xy 357.378861 -392.251097) (xy 357.396181 -392.25912) (xy 357.405686 -392.260074)
			(xy 357.512112 -392.266678) (xy 357.537766 -392.252454) (xy 357.544878 -392.2395) (xy 357.561786 -392.210149)
			(xy 357.602198 -392.155787) (xy 357.649466 -392.107267) (xy 357.702753 -392.065448) (xy 357.761117 -392.031069)
			(xy 357.823527 -392.004738) (xy 357.888879 -391.98692) (xy 357.956017 -391.977931) (xy 357.989886 -391.977372)
			(xy 358.029139 -391.978128) (xy 358.106704 -391.990254) (xy 358.144318 -392.001502) (xy 358.144572 -392.001502)
			(xy 358.152823 -392.003723) (xy 358.169889 -392.003197) (xy 358.185838 -391.9971) (xy 358.192578 -391.99185)
			(xy 358.258364 -391.93597) (xy 358.264676 -391.930163) (xy 358.273311 -391.915355) (xy 358.276558 -391.898524)
			(xy 358.275636 -391.889996) (xy 358.275636 -391.889742) (xy 358.273744 -391.875977) (xy 358.271709 -391.848264)
			(xy 358.271572 -391.83437) (xy 358.271572 -391.834116) (xy 358.272058 -391.806865) (xy 358.279814 -391.752917)
			(xy 358.295169 -391.700622) (xy 358.317811 -391.651045) (xy 358.347277 -391.605195) (xy 358.382968 -391.564004)
			(xy 358.424159 -391.528313) (xy 358.470009 -391.498847) (xy 358.519586 -391.476205) (xy 358.571881 -391.46085)
			(xy 358.625829 -391.453094) (xy 358.680331 -391.453094) (xy 358.734279 -391.46085) (xy 358.786574 -391.476205)
			(xy 358.836151 -391.498847) (xy 358.882001 -391.528313) (xy 358.923192 -391.564004) (xy 358.958883 -391.605195)
			(xy 358.988349 -391.651045) (xy 359.010991 -391.700622) (xy 359.026346 -391.752917) (xy 359.034102 -391.806865)
			(xy 359.034588 -391.834116) (xy 359.033887 -391.865698) (xy 359.023422 -391.927992) (xy 359.01376 -391.958068)
			(xy 359.011251 -391.966404) (xy 359.011389 -391.983803) (xy 359.014014 -391.992104) (xy 359.024682 -392.020552)
			(xy 359.028038 -392.028603) (xy 359.039196 -392.041989) (xy 359.046526 -392.046714) (xy 359.07485 -392.063915)
			(xy 359.127233 -392.104503) (xy 359.147764 -392.1252) (xy 366.783872 -392.1252) (xy 366.787943 -392.069578)
			(xy 366.800069 -392.015141) (xy 366.819992 -391.96305) (xy 366.847288 -391.914415) (xy 366.881374 -391.870272)
			(xy 366.921523 -391.831563) (xy 366.966881 -391.799112) (xy 367.016481 -391.773611) (xy 367.069265 -391.755604)
			(xy 367.124108 -391.745474) (xy 367.179842 -391.743437) (xy 367.235279 -391.749537) (xy 367.289236 -391.763643)
			(xy 367.340565 -391.785455) (xy 367.388171 -391.814509) (xy 367.431039 -391.850184) (xy 367.468256 -391.891721)
			(xy 367.499029 -391.938234) (xy 367.522701 -391.988731) (xy 367.538769 -392.042138) (xy 367.546889 -392.097314)
			(xy 367.547398 -392.1252) (xy 367.546889 -392.153086) (xy 367.538769 -392.208262) (xy 367.522701 -392.261669)
			(xy 367.499029 -392.312166) (xy 367.468256 -392.358679) (xy 367.431039 -392.400216) (xy 367.388171 -392.435891)
			(xy 367.340565 -392.464945) (xy 367.289236 -392.486757) (xy 367.235279 -392.500863) (xy 367.179842 -392.506963)
			(xy 367.124108 -392.504926) (xy 367.069265 -392.494796) (xy 367.016481 -392.476789) (xy 366.966881 -392.451288)
			(xy 366.921523 -392.418837) (xy 366.881374 -392.380128) (xy 366.847288 -392.335985) (xy 366.819992 -392.28735)
			(xy 366.800069 -392.235259) (xy 366.787943 -392.180822) (xy 366.783872 -392.1252) (xy 359.147764 -392.1252)
			(xy 359.173902 -392.151549) (xy 359.214067 -392.204258) (xy 359.247047 -392.261735) (xy 359.272284 -392.323009)
			(xy 359.289351 -392.38704) (xy 359.297959 -392.452746) (xy 359.298494 -392.48588) (xy 359.298057 -392.51599)
			(xy 359.290926 -392.575786) (xy 359.276785 -392.634321) (xy 359.255831 -392.690778) (xy 359.228359 -392.744366)
			(xy 359.194752 -392.794336) (xy 359.155481 -392.839988) (xy 359.111094 -392.880684) (xy 359.086912 -392.89863)
			(xy 359.077456 -392.906265) (xy 359.066449 -392.927894) (xy 359.06583 -392.940032) (xy 359.06583 -393.022328)
			(xy 359.066457 -393.03446) (xy 359.07167 -393.04468) (xy 366.783872 -393.04468) (xy 366.787943 -392.989058)
			(xy 366.800069 -392.934621) (xy 366.819992 -392.88253) (xy 366.847288 -392.833895) (xy 366.881374 -392.789752)
			(xy 366.921523 -392.751043) (xy 366.966881 -392.718592) (xy 367.016481 -392.693091) (xy 367.069265 -392.675084)
			(xy 367.124108 -392.664954) (xy 367.179842 -392.662917) (xy 367.235279 -392.669017) (xy 367.289236 -392.683123)
			(xy 367.340565 -392.704935) (xy 367.388171 -392.733989) (xy 367.43065 -392.76934) (xy 368.04395 -392.76934)
			(xy 368.04395 -392.709404) (xy 368.051773 -392.649982) (xy 368.067286 -392.592089) (xy 368.090222 -392.536716)
			(xy 368.120189 -392.48481) (xy 368.156676 -392.43726) (xy 368.199056 -392.39488) (xy 368.246606 -392.358393)
			(xy 368.298512 -392.328426) (xy 368.353885 -392.30549) (xy 368.411778 -392.289977) (xy 368.4712 -392.282154)
			(xy 368.531136 -392.282154) (xy 368.590558 -392.289977) (xy 368.648451 -392.30549) (xy 368.703824 -392.328426)
			(xy 368.75573 -392.358393) (xy 368.80328 -392.39488) (xy 368.84566 -392.43726) (xy 368.882147 -392.48481)
			(xy 368.912114 -392.536716) (xy 368.93505 -392.592089) (xy 368.950563 -392.649982) (xy 368.958386 -392.709404)
			(xy 368.958876 -392.739372) (xy 368.958386 -392.76934) (xy 368.950563 -392.828762) (xy 368.93505 -392.886655)
			(xy 368.912114 -392.942028) (xy 368.882147 -392.993934) (xy 368.84566 -393.041484) (xy 368.80328 -393.083864)
			(xy 368.75573 -393.120351) (xy 368.703824 -393.150318) (xy 368.648451 -393.173254) (xy 368.590558 -393.188767)
			(xy 368.531136 -393.19659) (xy 368.4712 -393.19659) (xy 368.411778 -393.188767) (xy 368.353885 -393.173254)
			(xy 368.298512 -393.150318) (xy 368.246606 -393.120351) (xy 368.199056 -393.083864) (xy 368.156676 -393.041484)
			(xy 368.120189 -392.993934) (xy 368.090222 -392.942028) (xy 368.067286 -392.886655) (xy 368.051773 -392.828762)
			(xy 368.04395 -392.76934) (xy 367.43065 -392.76934) (xy 367.431039 -392.769664) (xy 367.468256 -392.811201)
			(xy 367.499029 -392.857714) (xy 367.522701 -392.908211) (xy 367.538769 -392.961618) (xy 367.546889 -393.016794)
			(xy 367.547398 -393.04468) (xy 367.546889 -393.072566) (xy 367.538769 -393.127742) (xy 367.522701 -393.181149)
			(xy 367.499029 -393.231646) (xy 367.468256 -393.278159) (xy 367.431039 -393.319696) (xy 367.388171 -393.355371)
			(xy 367.340565 -393.384425) (xy 367.289236 -393.406237) (xy 367.235279 -393.420343) (xy 367.179842 -393.426443)
			(xy 367.124108 -393.424406) (xy 367.069265 -393.414276) (xy 367.016481 -393.396269) (xy 366.966881 -393.370768)
			(xy 366.921523 -393.338317) (xy 366.881374 -393.299608) (xy 366.847288 -393.255465) (xy 366.819992 -393.20683)
			(xy 366.800069 -393.154739) (xy 366.787943 -393.100302) (xy 366.783872 -393.04468) (xy 359.07167 -393.04468)
			(xy 359.07748 -393.056072) (xy 359.086912 -393.06373) (xy 359.111117 -393.081647) (xy 359.155517 -393.122337)
			(xy 359.194797 -393.167987) (xy 359.228408 -393.21796) (xy 359.255878 -393.271555) (xy 359.276822 -393.32802)
			(xy 359.290946 -393.386564) (xy 359.298054 -393.446368) (xy 359.298494 -393.47648) (xy 359.298044 -393.507212)
			(xy 359.290637 -393.568229) (xy 359.275929 -393.627908) (xy 359.254135 -393.685378) (xy 359.225572 -393.739803)
			(xy 359.190657 -393.790388) (xy 359.149899 -393.836395) (xy 359.103892 -393.877153) (xy 359.053308 -393.912069)
			(xy 358.998884 -393.940633) (xy 358.941413 -393.962427) (xy 358.881735 -393.977136) (xy 358.820718 -393.984543)
			(xy 358.789986 -393.984988) (xy 358.757862 -393.984487) (xy 358.694127 -393.976382) (xy 358.63192 -393.960317)
			(xy 358.572231 -393.936546) (xy 358.516011 -393.905448) (xy 358.464153 -393.867518) (xy 358.440482 -393.845796)
			(xy 358.433153 -393.839429) (xy 358.41513 -393.832252) (xy 358.40543 -393.831826) (xy 358.374442 -393.831826)
			(xy 358.364738 -393.832225) (xy 358.346712 -393.839414) (xy 358.33939 -393.845796) (xy 358.323642 -393.860274)
			(xy 358.315006 -393.86764) (xy 358.305862 -393.888722) (xy 358.308656 -393.978892) (xy 358.309622 -393.99022)
			(xy 358.31026 -393.991454) (xy 366.784838 -393.991454) (xy 366.784838 -393.936946) (xy 366.792595 -393.882994)
			(xy 366.807951 -393.830694) (xy 366.830594 -393.781113) (xy 366.860062 -393.735258) (xy 366.895757 -393.694064)
			(xy 366.93695 -393.658368) (xy 366.982804 -393.628899) (xy 367.032385 -393.606255) (xy 367.084684 -393.590897)
			(xy 367.138636 -393.583139) (xy 367.16589 -393.582652) (xy 367.194525 -393.583129) (xy 367.251151 -393.591702)
			(xy 367.30586 -393.60864) (xy 367.357424 -393.633564) (xy 367.404683 -393.665913) (xy 367.446577 -393.704963)
			(xy 367.482166 -393.749834) (xy 367.496852 -393.774422) (xy 367.50168 -393.78212) (xy 367.515614 -393.793763)
			(xy 367.532727 -393.799836) (xy 367.54181 -393.800076) (xy 367.644934 -393.798044) (xy 367.668302 -393.783566)
			(xy 367.674906 -393.771374) (xy 367.689842 -393.744121) (xy 367.725972 -393.693556) (xy 367.768616 -393.648348)
			(xy 367.816987 -393.609329) (xy 367.870195 -393.577217) (xy 367.92726 -393.552604) (xy 367.987132 -393.535943)
			(xy 368.048708 -393.527541) (xy 368.079782 -393.527026) (xy 368.109752 -393.527478) (xy 368.169179 -393.5353)
			(xy 368.227077 -393.550812) (xy 368.282455 -393.57375) (xy 368.334365 -393.60372) (xy 368.381918 -393.640209)
			(xy 368.424301 -393.682594) (xy 368.460789 -393.730149) (xy 368.490757 -393.782059) (xy 368.513693 -393.837438)
			(xy 368.529203 -393.895336) (xy 368.537023 -393.954764) (xy 368.53749 -393.984734) (xy 368.536981 -394.015614)
			(xy 368.528666 -394.076811) (xy 368.512191 -394.136333) (xy 368.487858 -394.193096) (xy 368.456107 -394.246069)
			(xy 368.417517 -394.294288) (xy 368.395504 -394.31595) (xy 368.387355 -394.324555) (xy 368.379267 -394.346796)
			(xy 368.38001 -394.358622) (xy 368.389408 -394.43914) (xy 368.391261 -394.450803) (xy 368.403978 -394.47067)
			(xy 368.413792 -394.47724) (xy 368.414046 -394.47724) (xy 368.439381 -394.492755) (xy 368.486235 -394.529279)
			(xy 368.527968 -394.57156) (xy 368.563877 -394.618887) (xy 368.593358 -394.670463) (xy 368.615916 -394.725421)
			(xy 368.631172 -394.782837) (xy 368.638867 -394.841744) (xy 368.639344 -394.871448) (xy 368.638873 -394.902107)
			(xy 368.630681 -394.962875) (xy 368.61445 -395.022006) (xy 368.590471 -395.078441) (xy 368.559173 -395.13117)
			(xy 368.521116 -395.179248) (xy 368.49939 -395.200886) (xy 368.491653 -395.209199) (xy 368.483656 -395.23042)
			(xy 368.485563 -395.253017) (xy 368.490754 -395.263116) (xy 368.504888 -395.288587) (xy 368.52496 -395.343265)
			(xy 368.535123 -395.400617) (xy 368.535712 -395.42974) (xy 368.535202 -395.455727) (xy 368.527072 -395.507062)
			(xy 368.511011 -395.556492) (xy 368.487415 -395.602802) (xy 368.456865 -395.64485) (xy 368.420114 -395.681601)
			(xy 368.378066 -395.712151) (xy 368.331756 -395.735747) (xy 368.282326 -395.751808) (xy 368.230991 -395.759938)
			(xy 368.179017 -395.759938) (xy 368.127682 -395.751808) (xy 368.078252 -395.735747) (xy 368.031942 -395.712151)
			(xy 367.989894 -395.681601) (xy 367.953143 -395.64485) (xy 367.922593 -395.602802) (xy 367.898997 -395.556492)
			(xy 367.882936 -395.507062) (xy 367.874806 -395.455727) (xy 367.874296 -395.42974) (xy 367.874296 -395.429486)
			(xy 367.874732 -395.405015) (xy 367.881929 -395.356606) (xy 367.896192 -395.30979) (xy 367.9063 -395.2875)
			(xy 367.910644 -395.277031) (xy 367.910648 -395.254389) (xy 367.90096 -395.233925) (xy 367.892584 -395.226286)
			(xy 367.87037 -395.207613) (xy 367.83036 -395.165579) (xy 367.795987 -395.118822) (xy 367.767803 -395.068094)
			(xy 367.746261 -395.014208) (xy 367.731707 -394.958031) (xy 367.724374 -394.900464) (xy 367.723928 -394.871448)
			(xy 367.72442 -394.840568) (xy 367.732738 -394.779369) (xy 367.749215 -394.719847) (xy 367.773552 -394.663083)
			(xy 367.805306 -394.610111) (xy 367.843899 -394.561893) (xy 367.865914 -394.540232) (xy 367.874061 -394.531625)
			(xy 367.882154 -394.509386) (xy 367.881408 -394.49756) (xy 367.87201 -394.417042) (xy 367.870158 -394.405378)
			(xy 367.857439 -394.385513) (xy 367.847626 -394.378942) (xy 367.847372 -394.378942) (xy 367.823982 -394.364729)
			(xy 367.780472 -394.331521) (xy 367.74124 -394.293355) (xy 367.706846 -394.250776) (xy 367.677783 -394.204395)
			(xy 367.665762 -394.179806) (xy 367.665762 -394.179552) (xy 367.661583 -394.171544) (xy 367.648614 -394.158985)
			(xy 367.632081 -394.151734) (xy 367.62309 -394.15085) (xy 367.53419 -394.145008) (xy 367.525096 -394.144768)
			(xy 367.507675 -394.149963) (xy 367.493164 -394.160913) (xy 367.487962 -394.168376) (xy 367.487962 -394.16863)
			(xy 367.472878 -394.191514) (xy 367.437187 -394.233106) (xy 367.395911 -394.269163) (xy 367.349899 -394.298941)
			(xy 367.300099 -394.321828) (xy 367.247537 -394.337352) (xy 367.193294 -394.345194) (xy 367.16589 -394.345668)
			(xy 367.138636 -394.345261) (xy 367.084684 -394.337503) (xy 367.032385 -394.322145) (xy 366.982804 -394.299501)
			(xy 366.93695 -394.270032) (xy 366.895757 -394.234336) (xy 366.860062 -394.193142) (xy 366.830594 -394.147287)
			(xy 366.807951 -394.097706) (xy 366.792595 -394.045406) (xy 366.784838 -393.991454) (xy 358.31026 -393.991454)
			(xy 358.320056 -394.010392) (xy 358.328722 -394.017754) (xy 358.355053 -394.038421) (xy 358.402588 -394.085549)
			(xy 358.443527 -394.138508) (xy 358.477161 -394.196382) (xy 358.502909 -394.25817) (xy 358.520324 -394.322802)
			(xy 358.529105 -394.389161) (xy 358.529636 -394.42263) (xy 358.529172 -394.453361) (xy 358.521761 -394.514373)
			(xy 358.50705 -394.574048) (xy 358.486738 -394.6276) (xy 362.130076 -394.6276) (xy 362.13409 -394.563802)
			(xy 362.146068 -394.501011) (xy 362.165822 -394.440216) (xy 362.19304 -394.382375) (xy 362.227292 -394.328403)
			(xy 362.268038 -394.279149) (xy 362.314637 -394.23539) (xy 362.366353 -394.197817) (xy 362.42237 -394.167021)
			(xy 362.481805 -394.143489) (xy 362.54372 -394.127592) (xy 362.60714 -394.119581) (xy 362.639102 -394.1191)
			(xy 362.669822 -394.119571) (xy 362.730816 -394.12697) (xy 362.790475 -394.141661) (xy 362.84793 -394.16343)
			(xy 362.902346 -394.191959) (xy 362.9279 -394.209016) (xy 362.936585 -394.214409) (xy 362.956602 -394.21847)
			(xy 362.976619 -394.214409) (xy 362.985304 -394.209016) (xy 363.010861 -394.191963) (xy 363.065275 -394.163428)
			(xy 363.122729 -394.141656) (xy 363.182387 -394.126963) (xy 363.243381 -394.119562) (xy 363.274102 -394.1191)
			(xy 363.306063 -394.119586) (xy 363.369482 -394.127598) (xy 363.431397 -394.143495) (xy 363.490831 -394.167027)
			(xy 363.546847 -394.197822) (xy 363.598561 -394.235395) (xy 363.645159 -394.279154) (xy 363.685905 -394.328407)
			(xy 363.720157 -394.382379) (xy 363.747374 -394.440218) (xy 363.767127 -394.501013) (xy 363.779105 -394.563803)
			(xy 363.783119 -394.6276) (xy 363.779105 -394.691397) (xy 363.767127 -394.754187) (xy 363.747374 -394.814982)
			(xy 363.720157 -394.872821) (xy 363.685905 -394.926793) (xy 363.645159 -394.976046) (xy 363.598561 -395.019805)
			(xy 363.546847 -395.057378) (xy 363.490831 -395.088173) (xy 363.431397 -395.111705) (xy 363.369482 -395.127602)
			(xy 363.306063 -395.135614) (xy 363.274102 -395.136116) (xy 363.243382 -395.135641) (xy 363.182388 -395.128242)
			(xy 363.12273 -395.113552) (xy 363.065274 -395.091784) (xy 363.010859 -395.063256) (xy 362.985304 -395.0462)
			(xy 362.976619 -395.040807) (xy 362.956602 -395.036746) (xy 362.936585 -395.040807) (xy 362.9279 -395.0462)
			(xy 362.902343 -395.063254) (xy 362.847929 -395.091787) (xy 362.790475 -395.113559) (xy 362.730817 -395.128253)
			(xy 362.669823 -395.135653) (xy 362.639102 -395.136116) (xy 362.60714 -395.135619) (xy 362.54372 -395.127608)
			(xy 362.481805 -395.111711) (xy 362.42237 -395.088179) (xy 362.366353 -395.057383) (xy 362.314637 -395.01981)
			(xy 362.268038 -394.976051) (xy 362.227292 -394.926797) (xy 362.19304 -394.872825) (xy 362.165822 -394.814984)
			(xy 362.146068 -394.754189) (xy 362.13409 -394.691398) (xy 362.130076 -394.6276) (xy 358.486738 -394.6276)
			(xy 358.485253 -394.631514) (xy 358.45669 -394.685935) (xy 358.421775 -394.736516) (xy 358.381018 -394.78252)
			(xy 358.335014 -394.823276) (xy 358.284433 -394.858191) (xy 358.230012 -394.886754) (xy 358.172546 -394.90855)
			(xy 358.112871 -394.923261) (xy 358.051859 -394.930672) (xy 358.021128 -394.931138) (xy 357.989625 -394.930679)
			(xy 357.927103 -394.922884) (xy 357.866023 -394.907422) (xy 357.807323 -394.88453) (xy 357.751901 -394.854559)
			(xy 357.72598 -394.83665) (xy 357.718762 -394.831941) (xy 357.702206 -394.8272) (xy 357.685017 -394.828262)
			(xy 357.676958 -394.831316) (xy 357.584756 -394.870178) (xy 357.568754 -394.890752) (xy 357.566722 -394.90396)
			(xy 357.56124 -394.9363) (xy 357.543012 -394.999311) (xy 357.516835 -395.059456) (xy 357.483144 -395.115737)
			(xy 357.442497 -395.16722) (xy 357.395569 -395.213051) (xy 357.343138 -395.252468) (xy 357.286076 -395.284819)
			(xy 357.225328 -395.309565) (xy 357.161903 -395.326297) (xy 357.096853 -395.334737) (xy 357.064056 -395.335252)
			(xy 357.032651 -395.334768) (xy 356.97032 -395.327027) (xy 356.909417 -395.311669) (xy 356.850869 -395.288928)
			(xy 356.795568 -395.259149) (xy 356.744354 -395.222787) (xy 356.698009 -395.180394) (xy 356.657237 -395.132616)
			(xy 356.62266 -395.080181) (xy 356.594803 -395.023887) (xy 356.574092 -394.96459) (xy 356.56084 -394.903195)
			(xy 356.55758 -394.871956) (xy 356.556818 -394.86205) (xy 356.547928 -394.844778) (xy 356.487476 -394.791946)
			(xy 356.479799 -394.785808) (xy 356.461237 -394.779402) (xy 356.451408 -394.7795) (xy 356.427278 -394.780008)
			(xy 356.396547 -394.779565) (xy 356.335532 -394.772154) (xy 356.275856 -394.757442) (xy 356.218387 -394.735645)
			(xy 356.163966 -394.707081) (xy 356.113383 -394.672164) (xy 356.067379 -394.631406) (xy 356.026622 -394.585399)
			(xy 355.991708 -394.534816) (xy 355.963146 -394.480392) (xy 355.941351 -394.422923) (xy 355.926642 -394.363246)
			(xy 355.919234 -394.302231) (xy 355.91877 -394.2715) (xy 355.919216 -394.240718) (xy 355.926608 -394.179601)
			(xy 355.941331 -394.119825) (xy 355.96317 -394.062267) (xy 355.991805 -394.007769) (xy 356.00894 -393.982194)
			(xy 356.014014 -393.974197) (xy 356.018467 -393.955807) (xy 356.017576 -393.94638) (xy 356.013258 -393.915646)
			(xy 356.011611 -393.906378) (xy 356.002478 -393.889935) (xy 355.995478 -393.883642) (xy 355.973642 -393.864965)
			(xy 355.934339 -393.823048) (xy 355.900593 -393.77654) (xy 355.872935 -393.726174) (xy 355.851801 -393.672741)
			(xy 355.837521 -393.617083) (xy 355.830322 -393.560074) (xy 355.82987 -393.531344) (xy 354.746991 -393.531344)
			(xy 354.753168 -393.546414) (xy 354.768393 -393.603808) (xy 354.776065 -393.66269) (xy 354.776532 -393.69238)
			(xy 354.776006 -393.723443) (xy 354.767593 -393.784996) (xy 354.759768 -393.815062) (xy 354.756974 -393.824968)
			(xy 354.759514 -393.845288) (xy 354.801678 -393.918186) (xy 354.807086 -393.926782) (xy 354.823205 -393.939105)
			(xy 354.83292 -393.942062) (xy 354.833174 -393.942062) (xy 354.862288 -393.950047) (xy 354.918254 -393.972684)
			(xy 354.970759 -394.002481) (xy 355.018892 -394.03892) (xy 355.061817 -394.081371) (xy 355.09879 -394.129095)
			(xy 355.12917 -394.181265) (xy 355.152428 -394.236975) (xy 355.168162 -394.29526) (xy 355.176099 -394.355107)
			(xy 355.176582 -394.385292) (xy 355.176482 -394.399042) (xy 355.174828 -394.426493) (xy 355.17328 -394.440156)
			(xy 355.172531 -394.448845) (xy 355.176312 -394.46586) (xy 355.180646 -394.47343) (xy 355.196648 -394.49883)
			(xy 355.201434 -394.505854) (xy 355.214665 -394.516502) (xy 355.222556 -394.519658) (xy 355.246319 -394.528611)
			(xy 355.29097 -394.552797) (xy 355.331397 -394.583526) (xy 355.366651 -394.620075) (xy 355.395901 -394.661584)
			(xy 355.41846 -394.707079) (xy 355.433798 -394.755487) (xy 355.441553 -394.805672) (xy 355.442012 -394.831062)
			(xy 355.44149 -394.85705) (xy 355.433364 -394.908387) (xy 355.417308 -394.957821) (xy 355.393715 -395.004133)
			(xy 355.363167 -395.046185) (xy 355.326417 -395.08294) (xy 355.284369 -395.113493) (xy 355.238059 -395.137092)
			(xy 355.188628 -395.153155) (xy 355.137292 -395.161287) (xy 355.111304 -395.16177) (xy 355.086406 -395.161315)
			(xy 355.037175 -395.153844) (xy 354.989621 -395.139072) (xy 354.944822 -395.117332) (xy 354.903792 -395.089117)
			(xy 354.867459 -395.055066) (xy 354.836647 -395.015949) (xy 354.812052 -394.972651) (xy 354.794232 -394.926154)
			(xy 354.78847 -394.901928) (xy 354.786315 -394.89366) (xy 354.777363 -394.879119) (xy 354.770944 -394.87348)
			(xy 354.733352 -394.842746) (xy 354.718874 -394.843) (xy 354.688905 -394.842542) (xy 354.629481 -394.834716)
			(xy 354.571587 -394.8192) (xy 354.516214 -394.79626) (xy 354.464308 -394.766289) (xy 354.416758 -394.7298)
			(xy 354.374377 -394.687417) (xy 354.337892 -394.639864) (xy 354.307925 -394.587956) (xy 354.284989 -394.53258)
			(xy 354.269478 -394.474685) (xy 354.261656 -394.415261) (xy 354.261166 -394.385292) (xy 354.261687 -394.354229)
			(xy 354.270103 -394.292675) (xy 354.27793 -394.26261) (xy 354.280724 -394.252704) (xy 354.278184 -394.232384)
			(xy 354.23602 -394.159486) (xy 354.230593 -394.150903) (xy 354.214489 -394.138572) (xy 354.204778 -394.13561)
			(xy 354.204524 -394.13561) (xy 354.175402 -394.127652) (xy 354.119435 -394.105013) (xy 354.066929 -394.075213)
			(xy 354.018795 -394.038771) (xy 353.97587 -393.996318) (xy 353.938897 -393.94859) (xy 353.908519 -393.896417)
			(xy 353.885262 -393.840703) (xy 353.869531 -393.782416) (xy 353.861597 -393.722566) (xy 353.861116 -393.69238)
			(xy 353.86164 -393.661492) (xy 353.869945 -393.600276) (xy 353.886402 -393.540732) (xy 353.910713 -393.483941)
			(xy 353.92614 -393.457176) (xy 353.931523 -393.447255) (xy 353.933879 -393.424832) (xy 353.930712 -393.413996)
			(xy 353.904804 -393.340336) (xy 353.900574 -393.329966) (xy 353.884868 -393.314029) (xy 353.874578 -393.309602)
			(xy 353.851193 -393.300428) (xy 353.807296 -393.276007) (xy 353.7676 -393.245224) (xy 353.73302 -393.208789)
			(xy 353.704351 -393.167541) (xy 353.682254 -393.12243) (xy 353.667237 -393.074494) (xy 353.659648 -393.024838)
			(xy 353.659186 -392.999722) (xy 353.120706 -392.999722) (xy 353.120706 -393.000484) (xy 353.120218 -393.026518)
			(xy 353.112046 -393.07794) (xy 353.10445 -393.102846) (xy 353.10318 -393.106656) (xy 353.101656 -393.11453)
			(xy 353.100961 -393.119145) (xy 353.101093 -393.128477) (xy 353.10191 -393.133072) (xy 353.103688 -393.142216)
			(xy 353.108514 -393.15009) (xy 353.147884 -393.215114) (xy 353.148392 -393.21613) (xy 353.15652 -393.225782)
			(xy 353.159592 -393.228564) (xy 353.166485 -393.233163) (xy 353.170236 -393.234926) (xy 353.177856 -393.238482)
			(xy 353.184968 -393.239498) (xy 353.213911 -393.244197) (xy 353.270377 -393.260008) (xy 353.324362 -393.282898)
			(xy 353.374983 -393.312492) (xy 353.421411 -393.348306) (xy 353.462888 -393.389755) (xy 353.498734 -393.43616)
			(xy 353.528363 -393.48676) (xy 353.551289 -393.54073) (xy 353.567139 -393.597184) (xy 353.575651 -393.6552)
			(xy 353.576636 -393.684506) (xy 353.576636 -393.692634) (xy 353.576186 -393.721986) (xy 353.568668 -393.780207)
			(xy 353.56165 -393.808712) (xy 353.561142 -393.81049) (xy 353.561142 -393.810998) (xy 353.559872 -393.815062)
			(xy 353.55911 -393.817348) (xy 353.557405 -393.826563) (xy 353.560145 -393.845089) (xy 353.564444 -393.853416)
			(xy 353.564698 -393.853924) (xy 353.596702 -393.909296) (xy 353.599318 -393.913597) (xy 353.605965 -393.921156)
			(xy 353.60991 -393.924282) (xy 353.633024 -393.941808) (xy 353.639882 -393.94384) (xy 353.642676 -393.944602)
			(xy 353.671127 -393.953093) (xy 353.725725 -393.976425) (xy 353.776847 -394.006622) (xy 353.823633 -394.043179)
			(xy 353.865298 -394.085479) (xy 353.901141 -394.132814) (xy 353.930561 -394.184387) (xy 353.953064 -394.239332)
			(xy 353.96827 -394.296726) (xy 353.975925 -394.355605) (xy 353.976432 -394.385292) (xy 353.976317 -394.399491)
			(xy 353.974538 -394.427832) (xy 353.972876 -394.441934) (xy 353.97243 -394.446456) (xy 353.972936 -394.455526)
			(xy 353.973892 -394.459968) (xy 353.97567 -394.467842) (xy 353.980242 -394.475208) (xy 353.995736 -394.5001)
			(xy 354.000439 -394.507167) (xy 354.013545 -394.517941) (xy 354.02139 -394.521182) (xy 354.044763 -394.53038)
			(xy 354.088645 -394.554815) (xy 354.128329 -394.585603) (xy 354.162902 -394.622036) (xy 354.19157 -394.663277)
			(xy 354.213674 -394.708379) (xy 354.228705 -394.756303) (xy 354.236319 -394.805949) (xy 354.236782 -394.831062)
			(xy 354.236349 -394.855179) (xy 354.229353 -394.902904) (xy 354.215504 -394.949108) (xy 354.195094 -394.992813)
			(xy 354.182172 -395.01318) (xy 354.178108 -395.01953) (xy 354.17379 -395.0335) (xy 354.17379 -395.045438)
			(xy 354.174298 -395.05255) (xy 354.176838 -395.07033) (xy 354.178108 -395.080236) (xy 354.196142 -395.111732)
			(xy 354.203 -395.117574) (xy 354.224258 -395.136255) (xy 354.262468 -395.178002) (xy 354.295239 -395.224141)
			(xy 354.322073 -395.273968) (xy 354.34256 -395.326723) (xy 354.356387 -395.381601) (xy 354.363343 -395.437765)
			(xy 354.363782 -395.466062) (xy 358.41127 -395.466062) (xy 358.415341 -395.41044) (xy 358.427467 -395.356003)
			(xy 358.44739 -395.303912) (xy 358.474686 -395.255277) (xy 358.508772 -395.211134) (xy 358.548921 -395.172425)
			(xy 358.594279 -395.139974) (xy 358.643879 -395.114473) (xy 358.696663 -395.096466) (xy 358.751506 -395.086336)
			(xy 358.80724 -395.084299) (xy 358.862677 -395.090399) (xy 358.916634 -395.104505) (xy 358.967963 -395.126317)
			(xy 359.015569 -395.155371) (xy 359.058437 -395.191046) (xy 359.095654 -395.232583) (xy 359.126427 -395.279096)
			(xy 359.150099 -395.329593) (xy 359.166167 -395.383) (xy 359.174287 -395.438176) (xy 359.174796 -395.466062)
			(xy 359.174287 -395.493948) (xy 359.166167 -395.549124) (xy 359.150099 -395.602531) (xy 359.126427 -395.653028)
			(xy 359.095654 -395.699541) (xy 359.058437 -395.741078) (xy 359.015569 -395.776753) (xy 358.967963 -395.805807)
			(xy 358.916634 -395.827619) (xy 358.862677 -395.841725) (xy 358.80724 -395.847825) (xy 358.751506 -395.845788)
			(xy 358.696663 -395.835658) (xy 358.643879 -395.817651) (xy 358.594279 -395.79215) (xy 358.548921 -395.759699)
			(xy 358.508772 -395.72099) (xy 358.474686 -395.676847) (xy 358.44739 -395.628212) (xy 358.427467 -395.576121)
			(xy 358.415341 -395.521684) (xy 358.41127 -395.466062) (xy 354.363782 -395.466062) (xy 354.363782 -395.46657)
			(xy 354.363211 -395.498823) (xy 354.354111 -395.562686) (xy 354.336131 -395.624637) (xy 354.323396 -395.654276)
			(xy 354.321364 -395.658594) (xy 354.318652 -395.668039) (xy 354.319841 -395.687634) (xy 354.32365 -395.696694)
			(xy 354.33 -395.71041) (xy 354.333302 -395.714728) (xy 354.342954 -395.727428) (xy 354.34651 -395.730476)
			(xy 354.370736 -395.752309) (xy 354.413371 -395.801659) (xy 354.448562 -395.856564) (xy 354.475598 -395.915912)
			(xy 354.493929 -395.978499) (xy 354.503184 -396.043054) (xy 354.503736 -396.075662) (xy 354.503062 -396.11077)
			(xy 354.492914 -396.1765) (xy 360.484672 -396.1765) (xy 360.488743 -396.120878) (xy 360.500869 -396.066441)
			(xy 360.520792 -396.01435) (xy 360.548088 -395.965715) (xy 360.582174 -395.921572) (xy 360.622323 -395.882863)
			(xy 360.667681 -395.850412) (xy 360.717281 -395.824911) (xy 360.770065 -395.806904) (xy 360.824908 -395.796774)
			(xy 360.880642 -395.794737) (xy 360.936079 -395.800837) (xy 360.990036 -395.814943) (xy 361.041365 -395.836755)
			(xy 361.088971 -395.865809) (xy 361.131839 -395.901484) (xy 361.169056 -395.943021) (xy 361.199829 -395.989534)
			(xy 361.223501 -396.040031) (xy 361.239569 -396.093438) (xy 361.247689 -396.148614) (xy 361.24811 -396.171674)
			(xy 363.874304 -396.171674) (xy 363.874864 -396.136708) (xy 363.88447 -396.067437) (xy 363.903483 -396.000138)
			(xy 363.931543 -395.936081) (xy 363.968121 -395.876477) (xy 363.989874 -395.849094) (xy 363.995155 -395.842102)
			(xy 364.000994 -395.825594) (xy 364.001304 -395.816836) (xy 364.001304 -395.662912) (xy 364.000933 -395.654166)
			(xy 363.995101 -395.637675) (xy 363.989874 -395.630654) (xy 363.968111 -395.603282) (xy 363.931562 -395.543664)
			(xy 363.903521 -395.479602) (xy 363.884515 -395.412305) (xy 363.874902 -395.343039) (xy 363.874304 -395.308074)
			(xy 363.874732 -395.277342) (xy 363.882143 -395.216326) (xy 363.896855 -395.156649) (xy 363.918653 -395.09918)
			(xy 363.94722 -395.044758) (xy 363.982137 -394.994175) (xy 364.022897 -394.94817) (xy 364.068905 -394.907414)
			(xy 364.11949 -394.8725) (xy 364.173915 -394.843938) (xy 364.231385 -394.822144) (xy 364.291064 -394.807436)
			(xy 364.35208 -394.800029) (xy 364.382812 -394.799566) (xy 364.408585 -394.799879) (xy 364.459866 -394.805098)
			(xy 364.485174 -394.80998) (xy 364.495371 -394.811544) (xy 364.515553 -394.80734) (xy 364.52429 -394.801852)
			(xy 364.593632 -394.753846) (xy 364.6043 -394.737082) (xy 364.606078 -394.726668) (xy 364.606078 -394.72616)
			(xy 364.610732 -394.699608) (xy 364.626642 -394.648101) (xy 364.649646 -394.599348) (xy 364.679285 -394.554319)
			(xy 364.714968 -394.513911) (xy 364.755985 -394.47893) (xy 364.801518 -394.450072) (xy 364.850661 -394.427913)
			(xy 364.902434 -394.412892) (xy 364.955806 -394.405311) (xy 364.98276 -394.40485) (xy 365.010008 -394.405415)
			(xy 365.063951 -394.413165) (xy 365.116242 -394.428513) (xy 365.165816 -394.451147) (xy 365.211664 -394.480605)
			(xy 365.252854 -394.516288) (xy 365.288546 -394.55747) (xy 365.318014 -394.603312) (xy 365.340658 -394.652881)
			(xy 365.356017 -394.705169) (xy 365.363779 -394.75911) (xy 365.364268 -394.786358) (xy 365.363778 -394.813289)
			(xy 365.35622 -394.866619) (xy 365.341236 -394.918355) (xy 365.319122 -394.967468) (xy 365.290319 -395.012982)
			(xy 365.255399 -395.053991) (xy 365.215057 -395.08968) (xy 365.170096 -395.119339) (xy 365.12141 -395.142378)
			(xy 365.069967 -395.158338) (xy 365.01679 -395.166903) (xy 364.989872 -395.167866) (xy 364.979458 -395.167866)
			(xy 364.960408 -395.176502) (xy 364.903512 -395.238478) (xy 364.896984 -395.246347) (xy 364.890155 -395.265595)
			(xy 364.890304 -395.275816) (xy 364.89132 -395.30782) (xy 364.89132 -395.308074) (xy 364.890725 -395.343039)
			(xy 364.881127 -395.412308) (xy 364.862122 -395.479606) (xy 364.834069 -395.543664) (xy 364.797499 -395.60327)
			(xy 364.77575 -395.630654) (xy 364.770493 -395.637662) (xy 364.764639 -395.654158) (xy 364.76432 -395.662912)
			(xy 364.76432 -395.816836) (xy 364.764664 -395.825585) (xy 364.770514 -395.842076) (xy 364.77575 -395.849094)
			(xy 364.797477 -395.876493) (xy 364.834034 -395.936103) (xy 364.862084 -396.000157) (xy 364.881097 -396.067449)
			(xy 364.890717 -396.136711) (xy 364.89132 -396.171674) (xy 364.89132 -396.172182) (xy 364.890843 -396.203336)
			(xy 364.883196 -396.265172) (xy 364.868051 -396.325611) (xy 364.845636 -396.383747) (xy 364.831376 -396.41145)
			(xy 364.827058 -396.419578) (xy 364.824518 -396.437866) (xy 364.843568 -396.520924) (xy 364.853728 -396.53591)
			(xy 364.861094 -396.541498) (xy 364.88164 -396.556926) (xy 364.918772 -396.592439) (xy 364.950802 -396.632614)
			(xy 364.977151 -396.676724) (xy 364.978412 -396.679674) (xy 366.90884 -396.679674) (xy 366.912911 -396.624052)
			(xy 366.925037 -396.569615) (xy 366.94496 -396.517524) (xy 366.972256 -396.468889) (xy 367.006342 -396.424746)
			(xy 367.046491 -396.386037) (xy 367.091849 -396.353586) (xy 367.141449 -396.328085) (xy 367.194233 -396.310078)
			(xy 367.249076 -396.299948) (xy 367.30481 -396.297911) (xy 367.360247 -396.304011) (xy 367.414204 -396.318117)
			(xy 367.465533 -396.339929) (xy 367.513139 -396.368983) (xy 367.556007 -396.404658) (xy 367.593224 -396.446195)
			(xy 367.623997 -396.492708) (xy 367.647669 -396.543205) (xy 367.663737 -396.596612) (xy 367.671857 -396.651788)
			(xy 367.672366 -396.679674) (xy 367.671919 -396.704137) (xy 367.874806 -396.704137) (xy 367.874806 -396.652163)
			(xy 367.882936 -396.600828) (xy 367.898997 -396.551398) (xy 367.922593 -396.505088) (xy 367.953143 -396.46304)
			(xy 367.989894 -396.426289) (xy 368.031942 -396.395739) (xy 368.078252 -396.372143) (xy 368.127682 -396.356082)
			(xy 368.179017 -396.347952) (xy 368.230991 -396.347952) (xy 368.282326 -396.356082) (xy 368.331756 -396.372143)
			(xy 368.378066 -396.395739) (xy 368.420114 -396.426289) (xy 368.456865 -396.46304) (xy 368.487415 -396.505088)
			(xy 368.511011 -396.551398) (xy 368.527072 -396.600828) (xy 368.535202 -396.652163) (xy 368.535712 -396.67815)
			(xy 368.535202 -396.704137) (xy 368.527072 -396.755472) (xy 368.511011 -396.804902) (xy 368.487415 -396.851212)
			(xy 368.456865 -396.89326) (xy 368.420114 -396.930011) (xy 368.378066 -396.960561) (xy 368.331756 -396.984157)
			(xy 368.282326 -397.000218) (xy 368.230991 -397.008348) (xy 368.179017 -397.008348) (xy 368.127682 -397.000218)
			(xy 368.078252 -396.984157) (xy 368.031942 -396.960561) (xy 367.989894 -396.930011) (xy 367.953143 -396.89326)
			(xy 367.922593 -396.851212) (xy 367.898997 -396.804902) (xy 367.882936 -396.755472) (xy 367.874806 -396.704137)
			(xy 367.671919 -396.704137) (xy 367.671857 -396.70756) (xy 367.663737 -396.762736) (xy 367.647669 -396.816143)
			(xy 367.623997 -396.86664) (xy 367.593224 -396.913153) (xy 367.556007 -396.95469) (xy 367.513139 -396.990365)
			(xy 367.465533 -397.019419) (xy 367.414204 -397.041231) (xy 367.360247 -397.055337) (xy 367.30481 -397.061437)
			(xy 367.249076 -397.0594) (xy 367.194233 -397.04927) (xy 367.141449 -397.031263) (xy 367.091849 -397.005762)
			(xy 367.046491 -396.973311) (xy 367.006342 -396.934602) (xy 366.972256 -396.890459) (xy 366.94496 -396.841824)
			(xy 366.925037 -396.789733) (xy 366.912911 -396.735296) (xy 366.90884 -396.679674) (xy 364.978412 -396.679674)
			(xy 364.99734 -396.723972) (xy 365.011006 -396.773502) (xy 365.017901 -396.824418) (xy 365.01832 -396.850108)
			(xy 365.017878 -396.877479) (xy 365.010057 -396.93166) (xy 364.994564 -396.984164) (xy 364.971716 -397.033911)
			(xy 364.941985 -397.079876) (xy 364.92434 -397.100806) (xy 364.924086 -397.10106) (xy 364.918508 -397.108153)
			(xy 364.912257 -397.125065) (xy 364.911894 -397.13408) (xy 364.911894 -397.201136) (xy 364.912235 -397.210154)
			(xy 364.918494 -397.227071) (xy 364.924086 -397.234156) (xy 364.92434 -397.234156) (xy 364.92434 -397.23441)
			(xy 364.942004 -397.255322) (xy 364.971711 -397.301301) (xy 364.994541 -397.351054) (xy 365.010027 -397.403558)
			(xy 365.017849 -397.457738) (xy 365.01832 -397.485108) (xy 365.017834 -397.512359) (xy 365.010078 -397.566307)
			(xy 364.994723 -397.618602) (xy 364.972081 -397.668179) (xy 364.942615 -397.714029) (xy 364.906924 -397.75522)
			(xy 364.865733 -397.790911) (xy 364.819883 -397.820377) (xy 364.770306 -397.843019) (xy 364.718011 -397.858374)
			(xy 364.664063 -397.86613) (xy 364.609561 -397.86613) (xy 364.555613 -397.858374) (xy 364.503318 -397.843019)
			(xy 364.453741 -397.820377) (xy 364.407891 -397.790911) (xy 364.3667 -397.75522) (xy 364.331009 -397.714029)
			(xy 364.301543 -397.668179) (xy 364.278901 -397.618602) (xy 364.263546 -397.566307) (xy 364.25579 -397.512359)
			(xy 364.255304 -397.485108) (xy 364.255774 -397.457738) (xy 364.263591 -397.403559) (xy 364.279079 -397.351056)
			(xy 364.30192 -397.301309) (xy 364.331643 -397.255342) (xy 364.349284 -397.23441) (xy 364.349538 -397.234156)
			(xy 364.355112 -397.227061) (xy 364.361365 -397.21015) (xy 364.36173 -397.201136) (xy 364.36173 -397.13408)
			(xy 364.361376 -397.125063) (xy 364.355126 -397.108146) (xy 364.349538 -397.10106) (xy 364.349284 -397.10106)
			(xy 364.349284 -397.100806) (xy 364.331632 -397.079885) (xy 364.301922 -397.033909) (xy 364.279089 -396.984158)
			(xy 364.263601 -396.931655) (xy 364.255776 -396.877478) (xy 364.255304 -396.850108) (xy 364.255304 -396.849854)
			(xy 364.255602 -396.828393) (xy 364.260439 -396.785746) (xy 364.264956 -396.764764) (xy 364.266988 -396.75562)
			(xy 364.264702 -396.73784) (xy 364.228634 -396.670276) (xy 364.224044 -396.662481) (xy 364.21052 -396.650494)
			(xy 364.202218 -396.646908) (xy 364.201964 -396.646908) (xy 364.17344 -396.635542) (xy 364.119094 -396.60696)
			(xy 364.068587 -396.57204) (xy 364.022654 -396.531291) (xy 363.981963 -396.485307) (xy 363.947108 -396.434755)
			(xy 363.918594 -396.380374) (xy 363.896839 -396.322954) (xy 363.882158 -396.263332) (xy 363.874765 -396.202376)
			(xy 363.874304 -396.171674) (xy 361.24811 -396.171674) (xy 361.248198 -396.1765) (xy 361.247689 -396.204386)
			(xy 361.239569 -396.259562) (xy 361.223501 -396.312969) (xy 361.199829 -396.363466) (xy 361.169056 -396.409979)
			(xy 361.131839 -396.451516) (xy 361.088971 -396.487191) (xy 361.041365 -396.516245) (xy 360.990036 -396.538057)
			(xy 360.936079 -396.552163) (xy 360.880642 -396.558263) (xy 360.824908 -396.556226) (xy 360.770065 -396.546096)
			(xy 360.717281 -396.528089) (xy 360.667681 -396.502588) (xy 360.622323 -396.470137) (xy 360.582174 -396.431428)
			(xy 360.548088 -396.387285) (xy 360.520792 -396.33865) (xy 360.500869 -396.286559) (xy 360.488743 -396.232122)
			(xy 360.484672 -396.1765) (xy 354.492914 -396.1765) (xy 354.492348 -396.180163) (xy 354.4824 -396.213838)
			(xy 354.481384 -396.216886) (xy 354.479332 -396.227468) (xy 354.48329 -396.248638) (xy 354.489004 -396.25778)
			(xy 354.489766 -396.25905) (xy 354.53828 -396.32509) (xy 354.539042 -396.326106) (xy 354.53955 -396.326614)
			(xy 354.547074 -396.335294) (xy 354.567701 -396.345356) (xy 354.579174 -396.345918) (xy 354.685854 -396.345918)
			(xy 354.695919 -396.346351) (xy 354.714508 -396.354082) (xy 354.721922 -396.360904) (xy 355.753416 -397.392398)
			(xy 355.76029 -397.398636) (xy 355.777237 -397.406173) (xy 355.795754 -397.407234) (xy 355.804724 -397.404844)
			(xy 355.89083 -397.377412) (xy 355.899203 -397.374434) (xy 355.913309 -397.363641) (xy 355.922865 -397.34867)
			(xy 355.92512 -397.340074) (xy 355.925628 -397.33728) (xy 355.925628 -397.337026) (xy 355.931724 -397.307054)
			(xy 355.940508 -397.272938) (xy 355.967118 -397.207713) (xy 356.003402 -397.147332) (xy 356.02545 -397.119856)
			(xy 356.031546 -397.11249) (xy 356.037134 -397.095472) (xy 356.037134 -397.086074) (xy 356.036626 -397.07185)
			(xy 356.035102 -397.018764) (xy 356.034514 -397.010414) (xy 356.028689 -396.99473) (xy 356.023672 -396.98803)
			(xy 356.020116 -396.983966) (xy 356.0191 -396.98295) (xy 355.999972 -396.961715) (xy 355.966587 -396.915328)
			(xy 355.939231 -396.865148) (xy 355.91833 -396.811955) (xy 355.904209 -396.756575) (xy 355.897088 -396.699868)
			(xy 355.896672 -396.671292) (xy 355.897162 -396.641324) (xy 355.904985 -396.581902) (xy 355.920498 -396.524009)
			(xy 355.943434 -396.468636) (xy 355.973401 -396.41673) (xy 356.009888 -396.36918) (xy 356.052268 -396.3268)
			(xy 356.099818 -396.290313) (xy 356.151724 -396.260346) (xy 356.207097 -396.23741) (xy 356.26499 -396.221897)
			(xy 356.324412 -396.214074) (xy 356.384348 -396.214074) (xy 356.44377 -396.221897) (xy 356.501663 -396.23741)
			(xy 356.557036 -396.260346) (xy 356.608942 -396.290313) (xy 356.656492 -396.3268) (xy 356.698872 -396.36918)
			(xy 356.735359 -396.41673) (xy 356.765326 -396.468636) (xy 356.788262 -396.524009) (xy 356.803775 -396.581902)
			(xy 356.811598 -396.641324) (xy 356.812088 -396.671292) (xy 356.812088 -396.6718) (xy 356.811994 -396.684399)
			(xy 356.810596 -396.70956) (xy 356.809294 -396.722092) (xy 356.804479 -396.758697) (xy 356.784568 -396.829789)
			(xy 356.76967 -396.86357) (xy 356.756718 -396.890449) (xy 356.724864 -396.9409) (xy 356.70617 -396.964154)
			(xy 356.705154 -396.96517) (xy 356.69982 -396.971774) (xy 356.697026 -396.980156) (xy 356.695784 -396.984042)
			(xy 356.694384 -396.99208) (xy 356.694232 -396.996158) (xy 356.695248 -397.029432) (xy 356.696264 -397.065754)
			(xy 356.696933 -397.074689) (xy 356.703559 -397.09132) (xy 356.709218 -397.098266) (xy 356.70998 -397.099028)
			(xy 356.722478 -397.112545) (xy 356.745492 -397.141284) (xy 356.755954 -397.156432) (xy 356.760272 -397.162782)
			(xy 356.76967 -397.17091) (xy 356.777798 -397.174466) (xy 356.782936 -397.176581) (xy 356.793831 -397.178752)
			(xy 356.799388 -397.178784) (xy 356.803452 -397.17853) (xy 356.882192 -397.169386) (xy 356.888034 -397.168116)
			(xy 356.892606 -397.166338) (xy 356.902766 -397.161004) (xy 356.924102 -397.144494) (xy 356.9335 -397.135096)
			(xy 356.936548 -397.131032) (xy 356.939596 -397.124428) (xy 356.939596 -397.124174) (xy 356.951032 -397.098815)
			(xy 356.980165 -397.051426) (xy 357.015868 -397.008766) (xy 357.057384 -396.97174) (xy 357.103834 -396.941131)
			(xy 357.154234 -396.917588) (xy 357.207517 -396.901608) (xy 357.262556 -396.893531) (xy 357.29037 -396.893034)
			(xy 357.315987 -396.893447) (xy 357.36676 -396.900304) (xy 357.416158 -396.913899) (xy 357.46329 -396.933987)
			(xy 357.507307 -396.960206) (xy 357.527606 -396.975838) (xy 357.52786 -396.976092) (xy 357.529638 -396.977616)
			(xy 357.536166 -396.981914) (xy 357.551038 -396.986694) (xy 357.558848 -396.987014) (xy 357.592122 -396.987014)
			(xy 357.592122 -396.99819) (xy 357.642922 -396.99819) (xy 357.647471 -396.99807) (xy 357.656417 -396.996418)
			(xy 357.660702 -396.994888) (xy 357.669084 -396.99184) (xy 357.676196 -396.985744) (xy 357.697074 -396.968354)
			(xy 357.742826 -396.939045) (xy 357.792274 -396.916526) (xy 357.844419 -396.901253) (xy 357.898203 -396.893537)
			(xy 357.92537 -396.893034) (xy 357.925624 -396.893034) (xy 357.950292 -396.893421) (xy 357.999215 -396.899792)
			(xy 358.02316 -396.905734) (xy 358.048374 -396.912895) (xy 358.096707 -396.933178) (xy 358.141816 -396.959875)
			(xy 358.162606 -396.975838) (xy 358.16286 -396.976092) (xy 358.164638 -396.977616) (xy 358.171166 -396.981914)
			(xy 358.186038 -396.986694) (xy 358.193848 -396.987014) (xy 358.227122 -396.987014) (xy 358.227122 -396.99819)
			(xy 358.277922 -396.99819) (xy 358.282471 -396.99807) (xy 358.291417 -396.996418) (xy 358.295702 -396.994888)
			(xy 358.304084 -396.99184) (xy 358.311196 -396.985744) (xy 358.332074 -396.968354) (xy 358.377826 -396.939045)
			(xy 358.427274 -396.916526) (xy 358.479419 -396.901253) (xy 358.533203 -396.893537) (xy 358.56037 -396.893034)
			(xy 358.587621 -396.893495) (xy 358.641569 -396.901248) (xy 358.693865 -396.9166) (xy 358.743444 -396.939238)
			(xy 358.789295 -396.968702) (xy 358.830487 -397.004392) (xy 358.86618 -397.04558) (xy 358.895648 -397.09143)
			(xy 358.91829 -397.141007) (xy 358.933646 -397.193301) (xy 358.941403 -397.247249) (xy 358.941403 -397.301751)
			(xy 358.933646 -397.355699) (xy 358.91829 -397.407993) (xy 358.895648 -397.45757) (xy 358.86618 -397.50342)
			(xy 358.830487 -397.544608) (xy 358.789295 -397.580298) (xy 358.743444 -397.609762) (xy 358.693865 -397.6324)
			(xy 358.641569 -397.647752) (xy 358.587621 -397.655505) (xy 358.56037 -397.65605) (xy 358.534754 -397.655633)
			(xy 358.483985 -397.648768) (xy 358.434592 -397.635166) (xy 358.387466 -397.615072) (xy 358.343455 -397.588848)
			(xy 358.323134 -397.573246) (xy 358.32288 -397.572992) (xy 358.321102 -397.571468) (xy 358.314575 -397.567166)
			(xy 358.299703 -397.562375) (xy 358.291892 -397.56207) (xy 358.258618 -397.56207) (xy 358.258618 -397.550894)
			(xy 358.207818 -397.550894) (xy 358.203271 -397.551019) (xy 358.194327 -397.552681) (xy 358.190038 -397.554196)
			(xy 358.181656 -397.557244) (xy 358.174544 -397.56334) (xy 358.153667 -397.580733) (xy 358.107917 -397.610048)
			(xy 358.058468 -397.632574) (xy 358.006324 -397.647852) (xy 357.952538 -397.655574) (xy 357.92537 -397.65605)
			(xy 357.925116 -397.65605) (xy 357.900448 -397.655665) (xy 357.851523 -397.649299) (xy 357.82758 -397.64335)
			(xy 357.802366 -397.636187) (xy 357.754035 -397.615902) (xy 357.708928 -397.589204) (xy 357.688134 -397.573246)
			(xy 357.68788 -397.572992) (xy 357.686102 -397.571468) (xy 357.679575 -397.567166) (xy 357.664703 -397.562375)
			(xy 357.656892 -397.56207) (xy 357.623618 -397.56207) (xy 357.623618 -397.550894) (xy 357.572818 -397.550894)
			(xy 357.568271 -397.551019) (xy 357.559327 -397.552681) (xy 357.555038 -397.554196) (xy 357.546656 -397.557244)
			(xy 357.539544 -397.56334) (xy 357.518667 -397.580733) (xy 357.472917 -397.610048) (xy 357.423468 -397.632574)
			(xy 357.371324 -397.647852) (xy 357.317538 -397.655574) (xy 357.29037 -397.65605) (xy 357.261916 -397.655532)
			(xy 357.205637 -397.647103) (xy 357.15123 -397.630422) (xy 357.099898 -397.605857) (xy 357.052777 -397.573952)
			(xy 357.010907 -397.535412) (xy 356.992682 -397.513556) (xy 356.991412 -397.512032) (xy 356.99065 -397.511016)
			(xy 356.987348 -397.507714) (xy 356.978052 -397.499526) (xy 356.954426 -397.492208) (xy 356.942136 -397.493744)
			(xy 356.868222 -397.507968) (xy 356.861505 -397.509472) (xy 356.849147 -397.515524) (xy 356.843838 -397.519906)
			(xy 356.82047 -397.540734) (xy 356.813358 -397.55191) (xy 356.811326 -397.558006) (xy 356.801083 -397.587094)
			(xy 356.773874 -397.642436) (xy 356.739478 -397.693622) (xy 356.719378 -397.71701) (xy 356.719124 -397.717264)
			(xy 356.713028 -397.724122) (xy 356.709726 -397.732758) (xy 356.708188 -397.737106) (xy 356.706535 -397.74618)
			(xy 356.706424 -397.750792) (xy 356.706424 -397.817848) (xy 356.706816 -397.827039) (xy 356.713338 -397.844223)
			(xy 356.719124 -397.851376) (xy 356.740739 -397.876628) (xy 356.777203 -397.932202) (xy 356.805242 -397.992467)
			(xy 356.824266 -398.056155) (xy 356.833874 -398.121926) (xy 356.83444 -398.15516) (xy 356.83444 -398.155414)
			(xy 356.834033 -398.183242) (xy 356.827284 -398.238488) (xy 356.813877 -398.292505) (xy 356.79401 -398.344495)
			(xy 356.781354 -398.369282) (xy 356.778814 -398.374108) (xy 356.775815 -398.382563) (xy 356.775324 -398.400485)
			(xy 356.78106 -398.417471) (xy 356.786434 -398.424654) (xy 356.789482 -398.428464) (xy 358.105456 -399.744438)
			(xy 358.111204 -399.749639) (xy 358.125036 -399.75662) (xy 358.132634 -399.758154) (xy 358.141016 -399.758916)
			(xy 361.098592 -399.758916) (xy 361.099608 -399.758916) (xy 361.111277 -399.758091) (xy 361.132039 -399.747365)
			(xy 361.139486 -399.738342) (xy 361.14101 -399.735802) (xy 361.142026 -399.734024) (xy 361.151677 -399.718446)
			(xy 361.172906 -399.688571) (xy 361.184444 -399.674334) (xy 361.206022 -399.648975) (xy 361.254725 -399.603568)
			(xy 361.308948 -399.564921) (xy 361.338114 -399.548858) (xy 361.346242 -399.54454) (xy 361.363768 -399.524728)
			(xy 361.366607 -399.521418) (xy 361.371199 -399.514006) (xy 361.372912 -399.509996) (xy 361.381294 -399.488152)
			(xy 361.382774 -399.483215) (xy 361.383919 -399.472975) (xy 361.38358 -399.467832) (xy 361.380786 -399.452592)
			(xy 361.379516 -399.449036) (xy 361.379008 -399.447766) (xy 361.368489 -399.41913) (xy 361.353589 -399.35997)
			(xy 361.345889 -399.29945) (xy 361.345226 -399.26895) (xy 361.345226 -399.261584) (xy 361.345913 -399.230903)
			(xy 361.353752 -399.170037) (xy 361.368868 -399.110557) (xy 361.391039 -399.053333) (xy 361.419943 -398.999196)
			(xy 361.437174 -398.973802) (xy 361.441491 -398.965791) (xy 361.444717 -398.947895) (xy 361.441487 -398.929999)
			(xy 361.437174 -398.921986) (xy 361.419734 -398.896274) (xy 361.390559 -398.841418) (xy 361.368292 -398.783415)
			(xy 361.353265 -398.723128) (xy 361.345701 -398.66146) (xy 361.345226 -398.630394) (xy 361.345678 -398.599848)
			(xy 361.352996 -398.539197) (xy 361.367526 -398.479858) (xy 361.389058 -398.422687) (xy 361.417283 -398.368507)
			(xy 361.451794 -398.318097) (xy 361.492094 -398.272184) (xy 361.537603 -398.231428) (xy 361.562396 -398.21358)
			(xy 361.569508 -398.2085) (xy 361.584748 -398.187418) (xy 361.590336 -398.179798) (xy 361.597448 -398.153382)
			(xy 361.597448 -398.152874) (xy 361.598972 -398.147794) (xy 361.59948 -398.134586) (xy 361.595416 -398.116806)
			(xy 361.593384 -398.112234) (xy 361.583169 -398.087919) (xy 361.568791 -398.037177) (xy 361.561562 -397.984934)
			(xy 361.561126 -397.958564) (xy 361.561126 -397.958056) (xy 361.561591 -397.93072) (xy 361.569388 -397.876608)
			(xy 361.58483 -397.824163) (xy 361.6076 -397.77446) (xy 361.637233 -397.728516) (xy 361.654852 -397.707612)
			(xy 361.656122 -397.706342) (xy 361.66063 -397.700382) (xy 361.666315 -397.686571) (xy 361.667298 -397.679164)
			(xy 361.667552 -397.674338) (xy 361.667552 -397.606774) (xy 361.667298 -397.601948) (xy 361.666324 -397.594539)
			(xy 361.660634 -397.580728) (xy 361.656122 -397.57477) (xy 361.654852 -397.5735) (xy 361.637261 -397.552573)
			(xy 361.607625 -397.506635) (xy 361.584849 -397.456937) (xy 361.569398 -397.404498) (xy 361.561588 -397.35039)
			(xy 361.561126 -397.323056) (xy 361.561615 -397.295808) (xy 361.569377 -397.241867) (xy 361.584736 -397.189579)
			(xy 361.60738 -397.14001) (xy 361.636848 -397.094167) (xy 361.67254 -397.052985) (xy 361.71373 -397.017302)
			(xy 361.759578 -396.987843) (xy 361.809152 -396.965209) (xy 361.861443 -396.94986) (xy 361.915386 -396.94211)
			(xy 361.942634 -396.941548) (xy 361.968565 -396.941977) (xy 362.019952 -396.948984) (xy 362.069918 -396.962878)
			(xy 362.117545 -396.983403) (xy 362.161959 -397.010182) (xy 362.18241 -397.02613) (xy 362.189014 -397.031464)
			(xy 362.20781 -397.038322) (xy 362.210858 -397.039338) (xy 362.216658 -397.041076) (xy 362.228721 -397.042092)
			(xy 362.234734 -397.04137) (xy 362.313982 -397.023844) (xy 362.323983 -397.020609) (xy 362.34038 -397.007491)
			(xy 362.345732 -396.998444) (xy 362.347002 -396.99565) (xy 362.358709 -396.970962) (xy 362.388138 -396.924926)
			(xy 362.423833 -396.88356) (xy 362.465063 -396.847708) (xy 362.510986 -396.818104) (xy 362.560663 -396.795353)
			(xy 362.613076 -396.779922) (xy 362.667155 -396.772124) (xy 362.694474 -396.771622) (xy 362.720091 -396.772035)
			(xy 362.770864 -396.778893) (xy 362.820262 -396.792488) (xy 362.867394 -396.812576) (xy 362.911411 -396.838794)
			(xy 362.93171 -396.854426) (xy 362.931964 -396.85468) (xy 362.933742 -396.856204) (xy 362.940272 -396.860495)
			(xy 362.955144 -396.865266) (xy 362.962952 -396.865602) (xy 362.996226 -396.865602) (xy 362.996226 -396.876778)
			(xy 363.047026 -396.876778) (xy 363.051574 -396.876658) (xy 363.060521 -396.875004) (xy 363.064806 -396.873476)
			(xy 363.073188 -396.870428) (xy 363.0803 -396.864332) (xy 363.101179 -396.846943) (xy 363.14693 -396.817635)
			(xy 363.196379 -396.795117) (xy 363.248523 -396.779846) (xy 363.302307 -396.77213) (xy 363.329474 -396.771622)
			(xy 363.356726 -396.772083) (xy 363.410675 -396.779837) (xy 363.462972 -396.795189) (xy 363.512552 -396.817829)
			(xy 363.558405 -396.847294) (xy 363.599597 -396.882984) (xy 363.635291 -396.924175) (xy 363.664759 -396.970025)
			(xy 363.687401 -397.019603) (xy 363.702758 -397.071899) (xy 363.710515 -397.125848) (xy 363.710515 -397.180352)
			(xy 363.702758 -397.234301) (xy 363.687401 -397.286597) (xy 363.664759 -397.336175) (xy 363.635291 -397.382025)
			(xy 363.599597 -397.423216) (xy 363.558405 -397.458906) (xy 363.512552 -397.488371) (xy 363.462972 -397.511011)
			(xy 363.410675 -397.526363) (xy 363.356726 -397.534117) (xy 363.329474 -397.534638) (xy 363.303858 -397.534221)
			(xy 363.253089 -397.527357) (xy 363.203696 -397.513755) (xy 363.156569 -397.493661) (xy 363.112559 -397.467436)
			(xy 363.092238 -397.451834) (xy 363.091984 -397.45158) (xy 363.090206 -397.450056) (xy 363.083679 -397.445754)
			(xy 363.068807 -397.440964) (xy 363.060996 -397.440658) (xy 363.027722 -397.440658) (xy 363.027722 -397.429482)
			(xy 362.976922 -397.429482) (xy 362.972375 -397.429607) (xy 362.963432 -397.431271) (xy 362.959142 -397.432784)
			(xy 362.95076 -397.435832) (xy 362.943648 -397.441928) (xy 362.922771 -397.459321) (xy 362.877021 -397.488638)
			(xy 362.827573 -397.511165) (xy 362.775428 -397.526444) (xy 362.721643 -397.534168) (xy 362.694474 -397.534638)
			(xy 362.668543 -397.534209) (xy 362.617156 -397.527203) (xy 362.567189 -397.51331) (xy 362.519561 -397.492785)
			(xy 362.475148 -397.466005) (xy 362.454698 -397.450056) (xy 362.448094 -397.444722) (xy 362.429298 -397.437864)
			(xy 362.42625 -397.436848) (xy 362.42045 -397.435109) (xy 362.408386 -397.434092) (xy 362.402374 -397.434816)
			(xy 362.323126 -397.452342) (xy 362.312525 -397.45578) (xy 362.295527 -397.470152) (xy 362.29036 -397.480028)
			(xy 362.290106 -397.480536) (xy 362.278166 -397.505667) (xy 362.248077 -397.552466) (xy 362.230162 -397.573754)
			(xy 362.224066 -397.580866) (xy 362.221018 -397.588486) (xy 362.219456 -397.592895) (xy 362.217792 -397.602098)
			(xy 362.217716 -397.606774) (xy 362.217716 -397.674338) (xy 362.21797 -397.679164) (xy 362.218931 -397.686579)
			(xy 362.224599 -397.700407) (xy 362.229146 -397.706342) (xy 362.230416 -397.707612) (xy 362.248007 -397.728539)
			(xy 362.277644 -397.774477) (xy 362.300421 -397.824174) (xy 362.315872 -397.876614) (xy 362.323681 -397.930722)
			(xy 362.324142 -397.958056) (xy 362.32373 -397.983602) (xy 362.316907 -398.034237) (xy 362.303392 -398.08351)
			(xy 362.283425 -398.13054) (xy 362.257363 -398.174486) (xy 362.241846 -398.194784) (xy 362.236766 -398.201388)
			(xy 362.226098 -398.230852) (xy 362.225082 -398.239996) (xy 362.225336 -398.266412) (xy 362.226078 -398.274674)
			(xy 362.232182 -398.290088) (xy 362.237274 -398.296638) (xy 362.237782 -398.297146) (xy 362.26294 -398.327195)
			(xy 362.304663 -398.393531) (xy 362.32084 -398.429226) (xy 362.32338 -398.435322) (xy 362.32973 -398.443704)
			(xy 362.334048 -398.447768) (xy 362.337659 -398.450678) (xy 362.34571 -398.455278) (xy 362.35005 -398.456912)
			(xy 362.395516 -398.473422) (xy 362.420408 -398.482312) (xy 362.425319 -398.483934) (xy 362.435562 -398.485343)
			(xy 362.440728 -398.485106) (xy 362.450888 -398.484598) (xy 362.460794 -398.479518) (xy 362.48796 -398.465954)
			(xy 362.544826 -398.444665) (xy 362.603824 -398.430305) (xy 362.664114 -398.423077) (xy 362.694474 -398.422622)
			(xy 362.725538 -398.423093) (xy 362.787203 -398.430673) (xy 362.847483 -398.445711) (xy 362.905482 -398.467984)
			(xy 362.960335 -398.497159) (xy 362.986066 -398.51457) (xy 362.994077 -398.518887) (xy 363.011974 -398.522114)
			(xy 363.029871 -398.518887) (xy 363.037882 -398.51457) (xy 363.063594 -398.497128) (xy 363.118449 -398.467951)
			(xy 363.176452 -398.44568) (xy 363.236739 -398.430649) (xy 363.298408 -398.423081) (xy 363.329474 -398.422622)
			(xy 363.360839 -398.423091) (xy 363.423092 -398.430813) (xy 363.483922 -398.446132) (xy 363.542408 -398.468814)
			(xy 363.59766 -398.498516) (xy 363.648841 -398.534787) (xy 363.695174 -398.577076) (xy 363.735955 -398.624741)
			(xy 363.770565 -398.677059) (xy 363.79848 -398.733236) (xy 363.819275 -398.792419) (xy 363.832635 -398.853709)
			(xy 363.83595 -398.884902) (xy 363.837474 -398.902682) (xy 363.838236 -398.93113) (xy 363.837714 -398.964525)
			(xy 363.828985 -399.030742) (xy 363.811668 -399.095247) (xy 363.78606 -399.156933) (xy 363.752603 -399.214737)
			(xy 363.71187 -399.267668) (xy 363.664562 -399.314815) (xy 363.638338 -399.335498) (xy 363.633258 -399.339562)
			(xy 363.629956 -399.343372) (xy 363.625384 -399.349976) (xy 363.61497 -399.370042) (xy 363.611794 -399.377017)
			(xy 363.60934 -399.392138) (xy 363.610144 -399.39976) (xy 363.613954 -399.427192) (xy 363.621574 -399.480786)
			(xy 363.623466 -399.489391) (xy 363.632241 -399.504653) (xy 363.645701 -399.516001) (xy 363.653832 -399.519394)
			(xy 363.65434 -399.519648) (xy 363.654594 -399.519648) (xy 363.681413 -399.529752) (xy 363.732787 -399.555155)
			(xy 363.780985 -399.586167) (xy 363.803438 -399.603976) (xy 363.825963 -399.622904) (xy 363.866946 -399.665122)
			(xy 363.902781 -399.711788) (xy 363.918246 -399.736818) (xy 363.925716 -399.746488) (xy 363.947207 -399.75804)
			(xy 363.959394 -399.758916) (xy 364.113318 -399.758916) (xy 364.125294 -399.758265) (xy 364.146627 -399.747381)
			(xy 364.154212 -399.738088) (xy 364.157006 -399.734278) (xy 364.157768 -399.733008) (xy 364.158276 -399.732246)
			(xy 364.177326 -399.70329) (xy 364.19946 -399.673209) (xy 364.251102 -399.619263) (xy 364.280196 -399.595848)
			(xy 364.287054 -399.590514) (xy 364.302294 -399.567146) (xy 364.3041 -399.563965) (xy 364.306909 -399.55721)
			(xy 364.307882 -399.553684) (xy 364.311946 -399.53438) (xy 364.312984 -399.528633) (xy 364.312732 -399.51696)
			(xy 364.311438 -399.511266) (xy 364.309152 -399.502122) (xy 364.304834 -399.4912) (xy 364.291465 -399.4642)
			(xy 364.27246 -399.407029) (xy 364.262666 -399.347584) (xy 364.261908 -399.317464) (xy 364.261908 -399.311114)
			(xy 364.262609 -399.285293) (xy 364.270122 -399.234187) (xy 364.276894 -399.20926) (xy 364.285045 -399.182784)
			(xy 364.30792 -399.132331) (xy 364.337833 -399.085706) (xy 364.355634 -399.06448) (xy 364.356904 -399.06321)
			(xy 364.361402 -399.057246) (xy 364.367069 -399.043434) (xy 364.36808 -399.036032) (xy 364.368334 -399.031206)
			(xy 364.368334 -398.963642) (xy 364.36808 -398.958816) (xy 364.367115 -398.951403) (xy 364.361438 -398.937582)
			(xy 364.356904 -398.931638) (xy 364.355634 -398.930368) (xy 364.338046 -398.90944) (xy 364.308415 -398.8635)
			(xy 364.285644 -398.813803) (xy 364.270198 -398.761364) (xy 364.262393 -398.707257) (xy 364.261908 -398.679924)
			(xy 364.262394 -398.652673) (xy 364.27015 -398.598725) (xy 364.285505 -398.54643) (xy 364.308147 -398.496853)
			(xy 364.337613 -398.451003) (xy 364.373304 -398.409812) (xy 364.414495 -398.374121) (xy 364.460345 -398.344655)
			(xy 364.509922 -398.322013) (xy 364.562217 -398.306658) (xy 364.616165 -398.298902) (xy 364.670667 -398.298902)
			(xy 364.724615 -398.306658) (xy 364.77691 -398.322013) (xy 364.826487 -398.344655) (xy 364.872337 -398.374121)
			(xy 364.913528 -398.409812) (xy 364.949219 -398.451003) (xy 364.978685 -398.496853) (xy 365.001327 -398.54643)
			(xy 365.016682 -398.598725) (xy 365.024438 -398.652673) (xy 365.024924 -398.679924) (xy 365.024453 -398.707257)
			(xy 365.016645 -398.761363) (xy 365.001193 -398.8138) (xy 364.978413 -398.863494) (xy 364.948772 -398.909427)
			(xy 364.931198 -398.930368) (xy 364.929928 -398.931638) (xy 364.925422 -398.937598) (xy 364.919737 -398.951409)
			(xy 364.918752 -398.958816) (xy 364.918498 -398.963642) (xy 364.918498 -399.031206) (xy 364.918752 -399.036032)
			(xy 364.919724 -399.043442) (xy 364.925415 -399.057253) (xy 364.929928 -399.06321) (xy 364.931198 -399.06448)
			(xy 364.948792 -399.085406) (xy 364.978434 -399.131343) (xy 365.001216 -399.18104) (xy 365.016672 -399.23348)
			(xy 365.024486 -399.287589) (xy 365.024924 -399.314924) (xy 365.024794 -399.330231) (xy 365.02238 -399.360748)
			(xy 365.020098 -399.375884) (xy 365.019336 -399.379948) (xy 365.019336 -399.3896) (xy 365.019688 -399.398022)
			(xy 365.025132 -399.413963) (xy 365.030004 -399.420842) (xy 365.034322 -399.425668) (xy 365.06912 -399.460212)
			(xy 365.094012 -399.48485) (xy 365.1017 -399.491296) (xy 365.120556 -399.498102) (xy 365.130588 -399.498058)
			(xy 365.138462 -399.497042) (xy 365.139986 -399.496788) (xy 365.161533 -399.493303) (xy 365.205028 -399.489614)
			(xy 365.226854 -399.489422) (xy 365.228378 -399.489422) (xy 365.25929 -399.489969) (xy 365.320638 -399.497649)
			(xy 365.380602 -399.512714) (xy 365.438294 -399.534944) (xy 365.492864 -399.564009) (xy 365.518446 -399.58137)
			(xy 365.526457 -399.585687) (xy 365.544354 -399.588914) (xy 365.562251 -399.585687) (xy 365.570262 -399.58137)
			(xy 365.595981 -399.563945) (xy 365.650844 -399.534798) (xy 365.708848 -399.51255) (xy 365.769129 -399.497531)
			(xy 365.830792 -399.489965) (xy 365.892916 -399.489965) (xy 365.954579 -399.497531) (xy 366.01486 -399.51255)
			(xy 366.072864 -399.534798) (xy 366.127727 -399.563945) (xy 366.153446 -399.58137) (xy 366.161457 -399.585687)
			(xy 366.179354 -399.588914) (xy 366.197251 -399.585687) (xy 366.205262 -399.58137) (xy 366.230973 -399.563927)
			(xy 366.285828 -399.534747) (xy 366.343831 -399.512474) (xy 366.404118 -399.49744) (xy 366.465788 -399.48987)
			(xy 366.496854 -399.489422) (xy 366.530831 -399.489985) (xy 366.59818 -399.499026) (xy 366.663725 -399.516954)
			(xy 366.726301 -399.543449) (xy 366.784791 -399.578039) (xy 366.811814 -399.598642) (xy 366.818164 -399.603722)
			(xy 366.842294 -399.612358) (xy 366.846198 -399.613474) (xy 366.854236 -399.614623) (xy 366.858296 -399.614644)
			(xy 366.859312 -399.614644) (xy 366.883696 -399.613882) (xy 366.892558 -399.612775) (xy 366.908792 -399.605362)
			(xy 366.915446 -399.599404) (xy 366.9157 -399.59915) (xy 367.784126 -398.730724) (xy 367.791486 -398.722572)
			(xy 367.799069 -398.701985) (xy 367.797388 -398.68011) (xy 367.792508 -398.670272) (xy 367.77897 -398.644806)
			(xy 367.757692 -398.5912) (xy 367.743313 -398.535346) (xy 367.73606 -398.478129) (xy 367.735612 -398.449292)
			(xy 367.736082 -398.419324) (xy 367.743906 -398.3599) (xy 367.75942 -398.302006) (xy 367.782358 -398.246633)
			(xy 367.812328 -398.194727) (xy 367.848816 -398.147178) (xy 367.891199 -398.104797) (xy 367.938751 -398.068312)
			(xy 367.990658 -398.038346) (xy 368.046033 -398.015411) (xy 368.103928 -397.999901) (xy 368.163352 -397.99208)
			(xy 368.19332 -397.991584) (xy 368.222158 -397.992023) (xy 368.279375 -397.999274) (xy 368.335228 -398.013659)
			(xy 368.388829 -398.03495) (xy 368.4143 -398.04848) (xy 368.424146 -398.053323) (xy 368.446002 -398.054991)
			(xy 368.466571 -398.047414) (xy 368.474752 -398.040098) (xy 369.985544 -396.529306) (xy 369.992945 -396.522466)
			(xy 370.011543 -396.514746) (xy 370.021612 -396.51432) (xy 370.172234 -396.51432) (xy 370.174266 -396.51432)
			(xy 370.182857 -396.513634) (xy 370.198862 -396.507274) (xy 370.211856 -396.495971) (xy 370.21643 -396.488666)
			(xy 370.256816 -396.408148) (xy 370.257578 -396.40637) (xy 370.261006 -396.397688) (xy 370.262031 -396.379065)
			(xy 370.25961 -396.370048) (xy 370.25326 -396.352014) (xy 370.248688 -396.345664) (xy 370.232189 -396.322297)
			(xy 370.204502 -396.272241) (xy 370.183273 -396.219124) (xy 370.168833 -396.163773) (xy 370.161408 -396.107055)
			(xy 370.160804 -396.078456) (xy 370.160804 -396.065248) (xy 370.161987 -396.034661) (xy 370.171526 -395.974197)
			(xy 370.189047 -395.915546) (xy 370.20119 -395.887448) (xy 370.203222 -395.88313) (xy 370.205939 -395.873685)
			(xy 370.204758 -395.854085) (xy 370.200936 -395.84503) (xy 370.194586 -395.831314) (xy 370.191284 -395.826996)
			(xy 370.181632 -395.814296) (xy 370.178076 -395.811248) (xy 370.153854 -395.789413) (xy 370.111229 -395.740061)
			(xy 370.076048 -395.685154) (xy 370.049023 -395.625806) (xy 370.030703 -395.563221) (xy 370.021458 -395.498668)
			(xy 370.02085 -395.466062) (xy 370.021273 -395.437766) (xy 370.028248 -395.381605) (xy 370.042087 -395.326732)
			(xy 370.062579 -395.27398) (xy 370.089412 -395.224154) (xy 370.122178 -395.178012) (xy 370.160377 -395.136257)
			(xy 370.181632 -395.117574) (xy 370.18849 -395.111732) (xy 370.206524 -395.080236) (xy 370.207794 -395.07033)
			(xy 370.210842 -395.04874) (xy 370.210842 -395.047978) (xy 370.211546 -395.039748) (xy 370.208295 -395.023562)
			(xy 370.204492 -395.016228) (xy 370.202968 -395.013688) (xy 370.202714 -395.013434) (xy 370.189757 -394.993039)
			(xy 370.169253 -394.949288) (xy 370.155328 -394.903021) (xy 370.14828 -394.85522) (xy 370.14785 -394.831062)
			(xy 370.14785 -394.822934) (xy 370.148724 -394.801421) (xy 370.155349 -394.758879) (xy 370.167427 -394.717552)
			(xy 370.17579 -394.697712) (xy 370.177822 -394.692886) (xy 370.180616 -394.680694) (xy 370.181632 -394.668502)
			(xy 370.179854 -394.656056) (xy 370.178584 -394.651992) (xy 370.156994 -394.594588) (xy 370.154962 -394.589508)
			(xy 370.153228 -394.586179) (xy 370.148895 -394.580052) (xy 370.146326 -394.577316) (xy 370.127784 -394.558774)
			(xy 370.12372 -394.556742) (xy 370.11991 -394.554964) (xy 370.096393 -394.542916) (xy 370.053189 -394.512498)
			(xy 370.015364 -394.475605) (xy 369.983879 -394.433172) (xy 369.959532 -394.386278) (xy 369.942942 -394.336112)
			(xy 369.93453 -394.283949) (xy 369.933982 -394.25753) (xy 369.934463 -394.231539) (xy 369.94259 -394.180196)
			(xy 369.95865 -394.130757) (xy 369.982246 -394.084439) (xy 370.012797 -394.042382) (xy 370.049552 -394.005623)
			(xy 370.091605 -393.975067) (xy 370.13792 -393.951465) (xy 370.187357 -393.9354) (xy 370.238699 -393.927266)
			(xy 370.26469 -393.926822) (xy 370.265198 -393.926822) (xy 370.278916 -393.926976) (xy 370.306256 -393.929263)
			(xy 370.319808 -393.931394) (xy 370.324126 -393.932156) (xy 370.3447 -393.932156) (xy 370.351988 -393.931593)
			(xy 370.365798 -393.926817) (xy 370.371878 -393.922758) (xy 370.374164 -393.92098) (xy 370.37772 -393.917932)
			(xy 370.421916 -393.871196) (xy 370.436394 -393.855956) (xy 370.440752 -393.851085) (xy 370.44705 -393.839637)
			(xy 370.44884 -393.83335) (xy 370.450364 -393.827) (xy 370.450364 -393.814808) (xy 370.448586 -393.808204)
			(xy 370.444028 -393.789981) (xy 370.437545 -393.752977) (xy 370.435632 -393.73429) (xy 370.434362 -393.722606)
			(xy 370.433346 -393.69238) (xy 370.433893 -393.661485) (xy 370.442276 -393.600263) (xy 370.458806 -393.540723)
			(xy 370.483184 -393.483943) (xy 370.498624 -393.457176) (xy 370.498624 -393.456668) (xy 370.498878 -393.456414)
			(xy 370.501544 -393.451705) (xy 370.505008 -393.441456) (xy 370.505736 -393.436094) (xy 370.506752 -393.425172)
			(xy 370.477288 -393.34059) (xy 370.473106 -393.330316) (xy 370.457693 -393.314396) (xy 370.44757 -393.309856)
			(xy 370.445284 -393.30884) (xy 370.441474 -393.30757) (xy 370.439696 -393.306808) (xy 370.439442 -393.306808)
			(xy 370.437664 -393.306046) (xy 370.415148 -393.296404) (xy 370.373002 -393.27145) (xy 370.334998 -393.240551)
			(xy 370.301968 -393.204384) (xy 370.274635 -393.16374) (xy 370.253597 -393.119509) (xy 370.239315 -393.072657)
			(xy 370.232101 -393.024212) (xy 370.23167 -392.999722) (xy 370.23218 -392.973735) (xy 370.24031 -392.9224)
			(xy 370.256371 -392.87297) (xy 370.279967 -392.82666) (xy 370.310517 -392.784612) (xy 370.347268 -392.747861)
			(xy 370.389316 -392.717311) (xy 370.435626 -392.693715) (xy 370.485056 -392.677654) (xy 370.536391 -392.669524)
			(xy 370.588365 -392.669524) (xy 370.6397 -392.677654) (xy 370.68913 -392.693715) (xy 370.73544 -392.717311)
			(xy 370.777488 -392.747861) (xy 370.814239 -392.784612) (xy 370.844789 -392.82666) (xy 370.868385 -392.87297)
			(xy 370.884446 -392.9224) (xy 370.892576 -392.973735) (xy 370.893086 -392.999722) (xy 370.893086 -393.000484)
			(xy 370.892598 -393.026518) (xy 370.884426 -393.07794) (xy 370.87683 -393.102846) (xy 370.87556 -393.106656)
			(xy 370.874036 -393.11453) (xy 370.873341 -393.119145) (xy 370.873473 -393.128477) (xy 370.87429 -393.133072)
			(xy 370.876068 -393.142216) (xy 370.880894 -393.15009) (xy 370.920264 -393.215114) (xy 370.920772 -393.21613)
			(xy 370.9289 -393.225782) (xy 370.931971 -393.228565) (xy 370.938863 -393.233167) (xy 370.942616 -393.234926)
			(xy 370.950236 -393.238482) (xy 370.957348 -393.239498) (xy 370.986292 -393.244196) (xy 371.04276 -393.260005)
			(xy 371.096746 -393.282893) (xy 371.14737 -393.312487) (xy 371.1938 -393.348301) (xy 371.235279 -393.389749)
			(xy 371.271127 -393.436154) (xy 371.300757 -393.486756) (xy 371.323685 -393.540726) (xy 371.339535 -393.597182)
			(xy 371.348048 -393.655199) (xy 371.349016 -393.684506) (xy 371.349016 -393.692634) (xy 371.348566 -393.721986)
			(xy 371.341047 -393.780207) (xy 371.33403 -393.808712) (xy 371.333522 -393.81049) (xy 371.333522 -393.810998)
			(xy 371.332252 -393.815062) (xy 371.33149 -393.817348) (xy 371.329785 -393.826563) (xy 371.332524 -393.845089)
			(xy 371.336824 -393.853416) (xy 371.337078 -393.853924) (xy 371.369082 -393.909296) (xy 371.371701 -393.913594)
			(xy 371.378354 -393.921145) (xy 371.38229 -393.924282) (xy 371.405404 -393.941808) (xy 371.414802 -393.944602)
			(xy 371.443279 -393.953072) (xy 371.497934 -393.976367) (xy 371.549116 -394.006538) (xy 371.595965 -394.043077)
			(xy 371.637692 -394.08537) (xy 371.673598 -394.132707) (xy 371.703077 -394.18429) (xy 371.725635 -394.239254)
			(xy 371.740892 -394.296674) (xy 371.748593 -394.355586) (xy 371.749066 -394.385292) (xy 371.748959 -394.399554)
			(xy 371.747182 -394.428024) (xy 371.74551 -394.442188) (xy 371.74424 -394.451586) (xy 371.746272 -394.459968)
			(xy 371.747358 -394.464059) (xy 371.750679 -394.471844) (xy 371.752876 -394.475462) (xy 371.76456 -394.493496)
			(xy 371.77091 -394.501624) (xy 371.774974 -394.505434) (xy 371.79377 -394.520928) (xy 371.798342 -394.522706)
			(xy 371.80139 -394.523976) (xy 371.824074 -394.533539) (xy 371.866562 -394.558399) (xy 371.904893 -394.589285)
			(xy 371.938221 -394.625514) (xy 371.965807 -394.666284) (xy 371.987043 -394.710694) (xy 372.001458 -394.757763)
			(xy 372.008734 -394.806449) (xy 372.009162 -394.831062) (xy 372.008729 -394.855179) (xy 372.001732 -394.902904)
			(xy 371.987882 -394.949108) (xy 371.967472 -394.992811) (xy 371.954552 -395.01318) (xy 371.950488 -395.01953)
			(xy 371.94617 -395.0335) (xy 371.94617 -395.045438) (xy 371.946678 -395.05255) (xy 371.949218 -395.07033)
			(xy 371.950488 -395.080236) (xy 371.968522 -395.111732) (xy 371.97538 -395.117574) (xy 371.996639 -395.136254)
			(xy 372.03485 -395.178001) (xy 372.067623 -395.22414) (xy 372.094458 -395.273967) (xy 372.114946 -395.326722)
			(xy 372.128773 -395.3816) (xy 372.13573 -395.437765) (xy 372.136162 -395.466062) (xy 372.136162 -395.46657)
			(xy 372.13559 -395.498823) (xy 372.126491 -395.562686) (xy 372.108509 -395.624637) (xy 372.095776 -395.654276)
			(xy 372.093744 -395.658594) (xy 372.091033 -395.668039) (xy 372.092221 -395.687634) (xy 372.09603 -395.696694)
			(xy 372.10238 -395.71041) (xy 372.105682 -395.714728) (xy 372.115334 -395.727428) (xy 372.11889 -395.730476)
			(xy 372.143131 -395.752351) (xy 372.185784 -395.801788) (xy 372.220984 -395.856781) (xy 372.248018 -395.916215)
			(xy 372.266337 -395.978886) (xy 372.275572 -396.043523) (xy 372.276116 -396.07617) (xy 372.276116 -396.085822)
			(xy 372.274582 -396.122796) (xy 372.261046 -396.195546) (xy 372.249192 -396.230602) (xy 372.237596 -396.261158)
			(xy 372.206994 -396.318904) (xy 372.188232 -396.345664) (xy 372.18366 -396.352014) (xy 372.17731 -396.370048)
			(xy 372.174876 -396.379059) (xy 372.175934 -396.397679) (xy 372.179342 -396.40637) (xy 372.180104 -396.408148)
			(xy 372.22049 -396.488666) (xy 372.225044 -396.495986) (xy 372.238047 -396.50729) (xy 372.25406 -396.513647)
			(xy 372.262654 -396.51432) (xy 372.57228 -396.51432) (xy 372.574312 -396.51432) (xy 372.582907 -396.513643)
			(xy 372.598926 -396.507293) (xy 372.611935 -396.495994) (xy 372.616476 -396.488666) (xy 372.656862 -396.408148)
			(xy 372.657624 -396.40637) (xy 372.661054 -396.397688) (xy 372.662081 -396.379064) (xy 372.659656 -396.370048)
			(xy 372.653306 -396.352014) (xy 372.648734 -396.345664) (xy 372.632237 -396.322296) (xy 372.604553 -396.27224)
			(xy 372.583326 -396.219122) (xy 372.568888 -396.163772) (xy 372.561464 -396.107054) (xy 372.56085 -396.078456)
			(xy 372.56085 -396.065248) (xy 372.562033 -396.034661) (xy 372.571573 -395.974197) (xy 372.589095 -395.915547)
			(xy 372.601236 -395.887448) (xy 372.603268 -395.88313) (xy 372.605987 -395.873685) (xy 372.604805 -395.854085)
			(xy 372.600982 -395.84503) (xy 372.594632 -395.831314) (xy 372.59133 -395.826996) (xy 372.581678 -395.814296)
			(xy 372.578122 -395.811248) (xy 372.553898 -395.789414) (xy 372.511269 -395.740063) (xy 372.476084 -395.685157)
			(xy 372.449056 -395.625809) (xy 372.430734 -395.563223) (xy 372.421489 -395.498669) (xy 372.420896 -395.466062)
			(xy 372.421319 -395.437766) (xy 372.428295 -395.381607) (xy 372.442134 -395.326734) (xy 372.462628 -395.273983)
			(xy 372.489463 -395.224159) (xy 372.522231 -395.17802) (xy 372.560432 -395.136268) (xy 372.581678 -395.117574)
			(xy 372.588536 -395.111732) (xy 372.60657 -395.080236) (xy 372.60784 -395.07033) (xy 372.610888 -395.04874)
			(xy 372.610888 -395.048486) (xy 372.612158 -395.039088) (xy 372.608094 -395.021562) (xy 372.607078 -395.019784)
			(xy 372.603014 -395.013688) (xy 372.589245 -394.992132) (xy 372.567803 -394.945697) (xy 372.560342 -394.921232)
			(xy 372.555516 -394.902182) (xy 372.555516 -394.901928) (xy 372.553484 -394.893292) (xy 372.54942 -394.886434)
			(xy 372.547056 -394.882791) (xy 372.541309 -394.876281) (xy 372.53799 -394.87348) (xy 372.52148 -394.860018)
			(xy 372.514622 -394.854176) (xy 372.483888 -394.843) (xy 372.47576 -394.842746) (xy 372.446469 -394.841289)
			(xy 372.388587 -394.831839) (xy 372.332387 -394.815073) (xy 372.278789 -394.791266) (xy 372.228671 -394.760807)
			(xy 372.182855 -394.724195) (xy 372.142091 -394.682031) (xy 372.107047 -394.635005) (xy 372.078296 -394.583888)
			(xy 372.056311 -394.529517) (xy 372.041452 -394.472783) (xy 372.033961 -394.414616) (xy 372.033546 -394.385292)
			(xy 372.033546 -394.385038) (xy 372.033546 -394.384022) (xy 372.034014 -394.355522) (xy 372.041148 -394.29897)
			(xy 372.04777 -394.271246) (xy 372.048532 -394.268452) (xy 372.05031 -394.255752) (xy 372.05031 -394.245846)
			(xy 372.05009 -394.239243) (xy 372.046616 -394.2265) (xy 372.043452 -394.2207) (xy 372.01348 -394.168376)
			(xy 372.010861 -394.164077) (xy 372.004211 -394.156524) (xy 372.000272 -394.15339) (xy 371.977158 -394.135864)
			(xy 371.96776 -394.13307) (xy 371.939285 -394.124598) (xy 371.884636 -394.101299) (xy 371.83346 -394.071125)
			(xy 371.786617 -394.034584) (xy 371.744896 -393.992291) (xy 371.708997 -393.944955) (xy 371.679523 -393.893372)
			(xy 371.656971 -393.838411) (xy 371.641718 -393.780993) (xy 371.634022 -393.722084) (xy 371.633496 -393.69238)
			(xy 371.633496 -393.679934) (xy 371.634777 -393.650621) (xy 371.643886 -393.592659) (xy 371.660328 -393.536337)
			(xy 371.683836 -393.482578) (xy 371.69852 -393.457176) (xy 371.69852 -393.456668) (xy 371.698774 -393.456414)
			(xy 371.70144 -393.451705) (xy 371.704905 -393.441456) (xy 371.705632 -393.436094) (xy 371.706648 -393.425172)
			(xy 371.677184 -393.34059) (xy 371.673002 -393.330316) (xy 371.657588 -393.314397) (xy 371.647466 -393.309856)
			(xy 371.64518 -393.30884) (xy 371.64137 -393.30757) (xy 371.639592 -393.306808) (xy 371.639338 -393.306808)
			(xy 371.63756 -393.306046) (xy 371.615044 -393.296403) (xy 371.572898 -393.271449) (xy 371.534895 -393.24055)
			(xy 371.501865 -393.204383) (xy 371.474533 -393.16374) (xy 371.453496 -393.119508) (xy 371.439213 -393.072657)
			(xy 371.431999 -393.024212) (xy 371.431566 -392.999722) (xy 371.432076 -392.973735) (xy 371.440206 -392.9224)
			(xy 371.456267 -392.87297) (xy 371.479863 -392.82666) (xy 371.510413 -392.784612) (xy 371.547164 -392.747861)
			(xy 371.589212 -392.717311) (xy 371.635522 -392.693715) (xy 371.684952 -392.677654) (xy 371.736287 -392.669524)
			(xy 371.788261 -392.669524) (xy 371.839596 -392.677654) (xy 371.889026 -392.693715) (xy 371.935336 -392.717311)
			(xy 371.977384 -392.747861) (xy 372.014135 -392.784612) (xy 372.044685 -392.82666) (xy 372.068281 -392.87297)
			(xy 372.084342 -392.9224) (xy 372.092472 -392.973735) (xy 372.092982 -392.999722) (xy 372.092982 -393.000484)
			(xy 372.092494 -393.026518) (xy 372.084322 -393.07794) (xy 372.076726 -393.102846) (xy 372.075456 -393.106656)
			(xy 372.073932 -393.11453) (xy 372.073237 -393.119145) (xy 372.073369 -393.128477) (xy 372.074186 -393.133072)
			(xy 372.075964 -393.142216) (xy 372.08079 -393.15009) (xy 372.12016 -393.215114) (xy 372.120668 -393.21613)
			(xy 372.128796 -393.225782) (xy 372.13187 -393.22856) (xy 372.138768 -393.233149) (xy 372.142512 -393.234926)
			(xy 372.150132 -393.238482) (xy 372.157244 -393.239498) (xy 372.186188 -393.244195) (xy 372.242656 -393.260004)
			(xy 372.296643 -393.282892) (xy 372.347267 -393.312486) (xy 372.393698 -393.3483) (xy 372.435177 -393.389748)
			(xy 372.471026 -393.436153) (xy 372.500656 -393.486755) (xy 372.523584 -393.540726) (xy 372.539434 -393.597182)
			(xy 372.547948 -393.655199) (xy 372.548912 -393.684506) (xy 372.548912 -393.692634) (xy 372.548462 -393.721986)
			(xy 372.540943 -393.780207) (xy 372.533926 -393.808712) (xy 372.533418 -393.81049) (xy 372.533418 -393.810998)
			(xy 372.532148 -393.815062) (xy 372.531386 -393.817348) (xy 372.529681 -393.826563) (xy 372.53242 -393.845089)
			(xy 372.53672 -393.853416) (xy 372.536974 -393.853924) (xy 372.568978 -393.909296) (xy 372.571597 -393.913594)
			(xy 372.57825 -393.921145) (xy 372.582186 -393.924282) (xy 372.6053 -393.941808) (xy 372.614698 -393.944602)
			(xy 372.643175 -393.953072) (xy 372.697831 -393.976367) (xy 372.749013 -394.006538) (xy 372.795862 -394.043077)
			(xy 372.83759 -394.08537) (xy 372.873496 -394.132706) (xy 372.902975 -394.184289) (xy 372.925533 -394.239253)
			(xy 372.940791 -394.296674) (xy 372.948491 -394.355586) (xy 372.948962 -394.385292) (xy 372.948847 -394.399491)
			(xy 372.947069 -394.427832) (xy 372.945406 -394.441934) (xy 372.94496 -394.446456) (xy 372.945466 -394.455526)
			(xy 372.946422 -394.459968) (xy 372.9482 -394.467842) (xy 372.952772 -394.475208) (xy 372.968266 -394.5001)
			(xy 372.972971 -394.507164) (xy 372.986079 -394.517931) (xy 372.99392 -394.521182) (xy 373.017292 -394.530381)
			(xy 373.06117 -394.554818) (xy 373.10085 -394.585607) (xy 373.13542 -394.622041) (xy 373.164085 -394.663282)
			(xy 373.186187 -394.708383) (xy 373.201217 -394.756306) (xy 373.20883 -394.80595) (xy 373.209312 -394.831062)
			(xy 373.208879 -394.85518) (xy 373.201883 -394.902905) (xy 373.188035 -394.949109) (xy 373.167628 -394.992815)
			(xy 373.154702 -395.01318) (xy 373.150638 -395.01953) (xy 373.14632 -395.0335) (xy 373.14632 -395.045438)
			(xy 373.146828 -395.05255) (xy 373.149368 -395.07033) (xy 373.150638 -395.080236) (xy 373.168672 -395.111732)
			(xy 373.17553 -395.117574) (xy 373.196787 -395.136255) (xy 373.234994 -395.178004) (xy 373.267763 -395.224143)
			(xy 373.294595 -395.27397) (xy 373.315081 -395.326725) (xy 373.328907 -395.381602) (xy 373.335863 -395.437766)
			(xy 373.336312 -395.466062) (xy 373.336312 -395.46657) (xy 373.33574 -395.498823) (xy 373.326639 -395.562685)
			(xy 373.308656 -395.624635) (xy 373.295926 -395.654276) (xy 373.293894 -395.658594) (xy 373.291181 -395.668039)
			(xy 373.292371 -395.687634) (xy 373.29618 -395.696694) (xy 373.30253 -395.71041) (xy 373.305832 -395.714728)
			(xy 373.315484 -395.727428) (xy 373.31904 -395.730476) (xy 373.343283 -395.75235) (xy 373.38594 -395.801785)
			(xy 373.421144 -395.856777) (xy 373.448181 -395.916212) (xy 373.466503 -395.978883) (xy 373.475739 -396.043522)
			(xy 373.476266 -396.07617) (xy 373.476266 -396.085822) (xy 373.474733 -396.122796) (xy 373.461198 -396.195546)
			(xy 373.449342 -396.230602) (xy 373.437748 -396.261158) (xy 373.407149 -396.318907) (xy 373.388382 -396.345664)
			(xy 373.38381 -396.352014) (xy 373.37746 -396.370048) (xy 373.375024 -396.379059) (xy 373.376083 -396.397679)
			(xy 373.379492 -396.40637) (xy 373.380254 -396.408148) (xy 373.42064 -396.488666) (xy 373.425197 -396.495981)
			(xy 373.438202 -396.507272) (xy 373.454214 -396.513614) (xy 373.462804 -396.51432) (xy 373.772176 -396.51432)
			(xy 373.774208 -396.51432) (xy 373.782804 -396.513643) (xy 373.798823 -396.507295) (xy 373.811833 -396.495996)
			(xy 373.816372 -396.488666) (xy 373.856758 -396.408148) (xy 373.85752 -396.40637) (xy 373.860951 -396.397688)
			(xy 373.861977 -396.379064) (xy 373.859552 -396.370048) (xy 373.853202 -396.352014) (xy 373.84863 -396.345664)
			(xy 373.83213 -396.322298) (xy 373.80444 -396.272242) (xy 373.783209 -396.219125) (xy 373.768768 -396.163774)
			(xy 373.761342 -396.107055) (xy 373.760746 -396.078456) (xy 373.760746 -396.065248) (xy 373.761929 -396.034661)
			(xy 373.771469 -395.974197) (xy 373.788991 -395.915547) (xy 373.801132 -395.887448) (xy 373.803164 -395.88313)
			(xy 373.805883 -395.873685) (xy 373.804701 -395.854085) (xy 373.800878 -395.84503) (xy 373.794528 -395.831314)
			(xy 373.791226 -395.826996) (xy 373.781574 -395.814296) (xy 373.778018 -395.811248) (xy 373.753794 -395.789414)
			(xy 373.711166 -395.740063) (xy 373.675981 -395.685157) (xy 373.648953 -395.625809) (xy 373.630631 -395.563223)
			(xy 373.621386 -395.498669) (xy 373.620792 -395.466062) (xy 373.621215 -395.437766) (xy 373.628191 -395.381606)
			(xy 373.64203 -395.326733) (xy 373.662524 -395.273983) (xy 373.689359 -395.224159) (xy 373.722126 -395.178019)
			(xy 373.760328 -395.136267) (xy 373.781574 -395.117574) (xy 373.788432 -395.111732) (xy 373.806466 -395.080236)
			(xy 373.807736 -395.07033) (xy 373.810784 -395.04874) (xy 373.810784 -395.048486) (xy 373.812054 -395.039088)
			(xy 373.80799 -395.021562) (xy 373.806974 -395.019784) (xy 373.80291 -395.013688) (xy 373.789141 -394.992132)
			(xy 373.7677 -394.945697) (xy 373.760238 -394.921232) (xy 373.755412 -394.902182) (xy 373.755412 -394.901928)
			(xy 373.75338 -394.893292) (xy 373.749316 -394.886434) (xy 373.746952 -394.882791) (xy 373.741204 -394.876282)
			(xy 373.737886 -394.87348) (xy 373.721376 -394.860018) (xy 373.714518 -394.854176) (xy 373.683784 -394.843)
			(xy 373.675656 -394.842746) (xy 373.646365 -394.841288) (xy 373.588484 -394.831839) (xy 373.532284 -394.815072)
			(xy 373.478687 -394.791265) (xy 373.428569 -394.760806) (xy 373.382753 -394.724194) (xy 373.34199 -394.68203)
			(xy 373.306946 -394.635004) (xy 373.278196 -394.583887) (xy 373.256211 -394.529516) (xy 373.241352 -394.472783)
			(xy 373.233861 -394.414616) (xy 373.233442 -394.385292) (xy 373.233442 -394.385038) (xy 373.233442 -394.384022)
			(xy 373.23391 -394.355522) (xy 373.241044 -394.29897) (xy 373.247666 -394.271246) (xy 373.248428 -394.268452)
			(xy 373.250206 -394.255752) (xy 373.250206 -394.245846) (xy 373.249986 -394.239243) (xy 373.246512 -394.2265)
			(xy 373.243348 -394.2207) (xy 373.213376 -394.168376) (xy 373.210757 -394.164077) (xy 373.204106 -394.156524)
			(xy 373.200168 -394.15339) (xy 373.17934 -394.137642) (xy 373.169942 -394.134848) (xy 373.141221 -394.126482)
			(xy 373.086068 -394.103317) (xy 373.034394 -394.073179) (xy 372.987075 -394.03658) (xy 372.944916 -393.994141)
			(xy 372.908631 -393.946582) (xy 372.878835 -393.894709) (xy 372.856036 -393.839404) (xy 372.840618 -393.781604)
			(xy 372.832845 -393.72229) (xy 372.832376 -393.69238) (xy 372.832902 -393.66109) (xy 372.841399 -393.599089)
			(xy 372.858245 -393.538818) (xy 372.883129 -393.481398) (xy 372.898924 -393.454382) (xy 372.90172 -393.44951)
			(xy 372.905322 -393.438872) (xy 372.906036 -393.4333) (xy 372.906798 -393.425172) (xy 372.877334 -393.34059)
			(xy 372.873155 -393.330312) (xy 372.857747 -393.314379) (xy 372.847616 -393.309856) (xy 372.84533 -393.30884)
			(xy 372.84152 -393.30757) (xy 372.839742 -393.306808) (xy 372.839488 -393.306808) (xy 372.83771 -393.306046)
			(xy 372.815197 -393.296401) (xy 372.773057 -393.271443) (xy 372.735059 -393.240542) (xy 372.702035 -393.204375)
			(xy 372.674707 -393.163731) (xy 372.653673 -393.119501) (xy 372.639393 -393.072653) (xy 372.63218 -393.02421)
			(xy 372.631716 -392.999722) (xy 372.632226 -392.973735) (xy 372.640356 -392.9224) (xy 372.656417 -392.87297)
			(xy 372.680013 -392.82666) (xy 372.710563 -392.784612) (xy 372.747314 -392.747861) (xy 372.789362 -392.717311)
			(xy 372.835672 -392.693715) (xy 372.885102 -392.677654) (xy 372.936437 -392.669524) (xy 372.988411 -392.669524)
			(xy 373.039746 -392.677654) (xy 373.089176 -392.693715) (xy 373.135486 -392.717311) (xy 373.177534 -392.747861)
			(xy 373.214285 -392.784612) (xy 373.244835 -392.82666) (xy 373.268431 -392.87297) (xy 373.284492 -392.9224)
			(xy 373.292622 -392.973735) (xy 373.293132 -392.999722) (xy 373.293132 -393.000484) (xy 373.292644 -393.026518)
			(xy 373.284473 -393.07794) (xy 373.276876 -393.102846) (xy 373.275606 -393.106656) (xy 373.274082 -393.11453)
			(xy 373.273387 -393.119145) (xy 373.273519 -393.128477) (xy 373.274336 -393.133072) (xy 373.276114 -393.142216)
			(xy 373.28094 -393.15009) (xy 373.320056 -393.214352) (xy 373.323056 -393.219055) (xy 373.330741 -393.227135)
			(xy 373.335296 -393.230354) (xy 373.344694 -393.23645) (xy 373.356124 -393.237974) (xy 373.385588 -393.242653)
			(xy 373.443061 -393.25865) (xy 373.497977 -393.281959) (xy 373.54941 -393.312189) (xy 373.596491 -393.348828)
			(xy 373.638428 -393.39126) (xy 373.674512 -393.438768) (xy 373.704136 -393.490551) (xy 373.7268 -393.545737)
			(xy 373.742121 -393.603394) (xy 373.749841 -393.662551) (xy 373.750332 -393.69238) (xy 373.749815 -393.723644)
			(xy 373.741282 -393.785588) (xy 373.733314 -393.815824) (xy 373.73306 -393.81684) (xy 373.732298 -393.81938)
			(xy 373.73052 -393.83335) (xy 373.73052 -393.83589) (xy 373.730774 -393.84351) (xy 373.760492 -393.894818)
			(xy 373.761 -393.895834) (xy 373.768874 -393.909296) (xy 373.771493 -393.913594) (xy 373.778145 -393.921146)
			(xy 373.782082 -393.924282) (xy 373.805196 -393.941808) (xy 373.814594 -393.944602) (xy 373.843072 -393.953071)
			(xy 373.897728 -393.976366) (xy 373.94891 -394.006537) (xy 373.99576 -394.043076) (xy 374.037488 -394.085369)
			(xy 374.073394 -394.132705) (xy 374.102874 -394.184288) (xy 374.125432 -394.239253) (xy 374.14069 -394.296673)
			(xy 374.14839 -394.355585) (xy 374.148858 -394.385292) (xy 374.148743 -394.399491) (xy 374.146965 -394.427832)
			(xy 374.145302 -394.441934) (xy 374.144856 -394.446456) (xy 374.145362 -394.455526) (xy 374.146318 -394.459968)
			(xy 374.148096 -394.467842) (xy 374.152668 -394.475208) (xy 374.168162 -394.5001) (xy 374.172867 -394.507164)
			(xy 374.185975 -394.517932) (xy 374.193816 -394.521182) (xy 374.217188 -394.53038) (xy 374.261067 -394.554817)
			(xy 374.300748 -394.585607) (xy 374.335318 -394.622041) (xy 374.363983 -394.663282) (xy 374.386085 -394.708382)
			(xy 374.401115 -394.756305) (xy 374.408728 -394.80595) (xy 374.409208 -394.831062) (xy 374.408775 -394.85518)
			(xy 374.401779 -394.902905) (xy 374.387931 -394.949109) (xy 374.367523 -394.992814) (xy 374.354598 -395.01318)
			(xy 374.350534 -395.01953) (xy 374.346216 -395.0335) (xy 374.346216 -395.045438) (xy 374.346724 -395.05255)
			(xy 374.349264 -395.07033) (xy 374.350534 -395.080236) (xy 374.368568 -395.111732) (xy 374.375426 -395.117574)
			(xy 374.396683 -395.136255) (xy 374.43489 -395.178003) (xy 374.46766 -395.224143) (xy 374.494492 -395.27397)
			(xy 374.514978 -395.326725) (xy 374.528804 -395.381602) (xy 374.53576 -395.437766) (xy 374.536208 -395.466062)
			(xy 374.536208 -395.46657) (xy 374.535636 -395.498823) (xy 374.526535 -395.562685) (xy 374.508552 -395.624635)
			(xy 374.495822 -395.654276) (xy 374.49379 -395.658594) (xy 374.491077 -395.668039) (xy 374.492267 -395.687634)
			(xy 374.496076 -395.696694) (xy 374.502426 -395.71041) (xy 374.505728 -395.714728) (xy 374.51538 -395.727428)
			(xy 374.518936 -395.730476) (xy 374.543179 -395.75235) (xy 374.585837 -395.801785) (xy 374.621041 -395.856777)
			(xy 374.648079 -395.916211) (xy 374.666401 -395.978883) (xy 374.675636 -396.043522) (xy 374.676162 -396.07617)
			(xy 374.676162 -396.085822) (xy 374.674628 -396.122796) (xy 374.661094 -396.195546) (xy 374.649238 -396.230602)
			(xy 374.637644 -396.261158) (xy 374.607044 -396.318907) (xy 374.588278 -396.345664) (xy 374.583706 -396.352014)
			(xy 374.577356 -396.370048) (xy 374.57492 -396.379059) (xy 374.575979 -396.397679) (xy 374.579388 -396.40637)
			(xy 374.58015 -396.408148) (xy 374.620536 -396.488666) (xy 374.625092 -396.495981) (xy 374.638097 -396.507273)
			(xy 374.65411 -396.513616) (xy 374.6627 -396.51432) (xy 374.972072 -396.51432) (xy 374.974104 -396.51432)
			(xy 374.9827 -396.513644) (xy 374.998721 -396.507296) (xy 375.011732 -396.495998) (xy 375.016268 -396.488666)
			(xy 375.056654 -396.408148) (xy 375.057416 -396.40637) (xy 375.060847 -396.397688) (xy 375.061874 -396.379064)
			(xy 375.059448 -396.370048) (xy 375.053098 -396.352014) (xy 375.048526 -396.345664) (xy 375.032026 -396.322298)
			(xy 375.004336 -396.272242) (xy 374.983105 -396.219125) (xy 374.968664 -396.163774) (xy 374.961238 -396.107055)
			(xy 374.960642 -396.078456) (xy 374.960642 -396.065248) (xy 374.961825 -396.034661) (xy 374.971365 -395.974197)
			(xy 374.988887 -395.915547) (xy 375.001028 -395.887448) (xy 375.00306 -395.88313) (xy 375.005779 -395.873685)
			(xy 375.004597 -395.854085) (xy 375.000774 -395.84503) (xy 374.994424 -395.831314) (xy 374.991122 -395.826996)
			(xy 374.98147 -395.814296) (xy 374.977914 -395.811248) (xy 374.95369 -395.789414) (xy 374.911062 -395.740063)
			(xy 374.875878 -395.685156) (xy 374.84885 -395.625808) (xy 374.830528 -395.563222) (xy 374.821283 -395.498668)
			(xy 374.820688 -395.466062) (xy 374.821111 -395.437766) (xy 374.828086 -395.381606) (xy 374.841926 -395.326733)
			(xy 374.862419 -395.273983) (xy 374.889254 -395.224158) (xy 374.922022 -395.178018) (xy 374.960223 -395.136266)
			(xy 374.98147 -395.117574) (xy 374.988328 -395.111732) (xy 375.006362 -395.080236) (xy 375.007632 -395.07033)
			(xy 375.01068 -395.04874) (xy 375.01068 -395.048486) (xy 375.01195 -395.039088) (xy 375.007886 -395.021562)
			(xy 375.00687 -395.019784) (xy 375.002806 -395.013688) (xy 374.989037 -394.992132) (xy 374.967596 -394.945697)
			(xy 374.960134 -394.921232) (xy 374.955308 -394.901928) (xy 374.95353 -394.893546) (xy 374.949212 -394.886434)
			(xy 374.946862 -394.882724) (xy 374.941119 -394.876081) (xy 374.937782 -394.873226) (xy 374.921272 -394.859764)
			(xy 374.91416 -394.854176) (xy 374.883934 -394.843) (xy 374.875552 -394.842746) (xy 374.846274 -394.84127)
			(xy 374.788422 -394.831789) (xy 374.732255 -394.814999) (xy 374.678691 -394.791174) (xy 374.628608 -394.760705)
			(xy 374.582825 -394.724091) (xy 374.542091 -394.68193) (xy 374.507075 -394.634914) (xy 374.478348 -394.583812)
			(xy 374.456381 -394.529459) (xy 374.441534 -394.472747) (xy 374.43405 -394.414604) (xy 374.433592 -394.385292)
			(xy 374.433592 -394.385038) (xy 374.433592 -394.384022) (xy 374.43406 -394.355522) (xy 374.441194 -394.29897)
			(xy 374.447816 -394.271246) (xy 374.448578 -394.268452) (xy 374.450356 -394.255752) (xy 374.450356 -394.245846)
			(xy 374.450137 -394.239242) (xy 374.446666 -394.226498) (xy 374.443498 -394.2207) (xy 374.413526 -394.168376)
			(xy 374.410905 -394.164079) (xy 374.40425 -394.156531) (xy 374.400318 -394.15339) (xy 374.377204 -394.135864)
			(xy 374.367806 -394.13307) (xy 374.339329 -394.1246) (xy 374.284675 -394.101305) (xy 374.233494 -394.071134)
			(xy 374.186647 -394.034594) (xy 374.144921 -393.992301) (xy 374.109018 -393.944965) (xy 374.079541 -393.893381)
			(xy 374.056986 -393.838417) (xy 374.041732 -393.780997) (xy 374.034035 -393.722086) (xy 374.033542 -393.69238)
			(xy 374.033542 -393.679934) (xy 374.034823 -393.650621) (xy 374.04393 -393.592658) (xy 374.060372 -393.536335)
			(xy 374.083877 -393.482575) (xy 374.098566 -393.457176) (xy 374.098566 -393.456668) (xy 374.09882 -393.456414)
			(xy 374.101484 -393.451704) (xy 374.104945 -393.441455) (xy 374.105678 -393.436094) (xy 374.106694 -393.425172)
			(xy 374.07723 -393.34059) (xy 374.073051 -393.330312) (xy 374.057643 -393.314381) (xy 374.047512 -393.309856)
			(xy 374.045226 -393.30884) (xy 374.041416 -393.30757) (xy 374.039638 -393.306808) (xy 374.039384 -393.306808)
			(xy 374.037606 -393.306046) (xy 374.015093 -393.296401) (xy 373.972953 -393.271443) (xy 373.934956 -393.240542)
			(xy 373.901932 -393.204374) (xy 373.874604 -393.163731) (xy 373.853571 -393.119501) (xy 373.839292 -393.072652)
			(xy 373.832079 -393.02421) (xy 373.831612 -392.999722) (xy 373.832122 -392.973735) (xy 373.840252 -392.9224)
			(xy 373.856313 -392.87297) (xy 373.879909 -392.82666) (xy 373.910459 -392.784612) (xy 373.94721 -392.747861)
			(xy 373.989258 -392.717311) (xy 374.035568 -392.693715) (xy 374.084998 -392.677654) (xy 374.136333 -392.669524)
			(xy 374.188307 -392.669524) (xy 374.239642 -392.677654) (xy 374.289072 -392.693715) (xy 374.335382 -392.717311)
			(xy 374.37743 -392.747861) (xy 374.414181 -392.784612) (xy 374.444731 -392.82666) (xy 374.468327 -392.87297)
			(xy 374.484388 -392.9224) (xy 374.492518 -392.973735) (xy 374.493028 -392.999722) (xy 374.493028 -393.000484)
			(xy 374.49254 -393.026518) (xy 374.484369 -393.07794) (xy 374.476772 -393.102846) (xy 374.475502 -393.106656)
			(xy 374.473978 -393.11453) (xy 374.473283 -393.119145) (xy 374.473415 -393.128477) (xy 374.474232 -393.133072)
			(xy 374.47601 -393.142216) (xy 374.480836 -393.15009) (xy 374.520206 -393.215114) (xy 374.520714 -393.21613)
			(xy 374.528842 -393.225782) (xy 374.531914 -393.228563) (xy 374.538809 -393.233159) (xy 374.542558 -393.234926)
			(xy 374.550178 -393.238482) (xy 374.55348 -393.23899) (xy 374.55729 -393.239498) (xy 374.586232 -393.244198)
			(xy 374.642696 -393.260011) (xy 374.696678 -393.282902) (xy 374.747297 -393.312498) (xy 374.793723 -393.348313)
			(xy 374.835198 -393.389761) (xy 374.871042 -393.436165) (xy 374.900669 -393.486765) (xy 374.923594 -393.540734)
			(xy 374.939442 -393.597187) (xy 374.947954 -393.655201) (xy 374.948958 -393.684506) (xy 374.948958 -393.692634)
			(xy 374.948508 -393.721986) (xy 374.94099 -393.780207) (xy 374.933972 -393.808712) (xy 374.933464 -393.81049)
			(xy 374.933464 -393.810998) (xy 374.932194 -393.815062) (xy 374.931432 -393.817348) (xy 374.929726 -393.826563)
			(xy 374.932468 -393.845089) (xy 374.936766 -393.853416) (xy 374.93702 -393.853924) (xy 374.969024 -393.909296)
			(xy 374.971641 -393.913596) (xy 374.978289 -393.921153) (xy 374.982232 -393.924282) (xy 375.005346 -393.941808)
			(xy 375.014744 -393.944602) (xy 375.043219 -393.953074) (xy 375.09787 -393.976373) (xy 375.149048 -394.006546)
			(xy 375.195892 -394.043087) (xy 375.237616 -394.08538) (xy 375.273517 -394.132715) (xy 375.302993 -394.184298)
			(xy 375.325549 -394.23926) (xy 375.340804 -394.296678) (xy 375.348504 -394.355587) (xy 375.349008 -394.385292)
			(xy 375.348901 -394.399554) (xy 375.347125 -394.428024) (xy 375.345452 -394.442188) (xy 375.344182 -394.451586)
			(xy 375.346214 -394.459968) (xy 375.347301 -394.464059) (xy 375.350624 -394.471842) (xy 375.352818 -394.475462)
			(xy 375.364502 -394.493496) (xy 375.370852 -394.501624) (xy 375.374916 -394.505434) (xy 375.393712 -394.520928)
			(xy 375.398284 -394.522706) (xy 375.401332 -394.523976) (xy 375.424014 -394.533541) (xy 375.466497 -394.558404)
			(xy 375.504823 -394.589292) (xy 375.538146 -394.625521) (xy 375.565729 -394.666291) (xy 375.586962 -394.7107)
			(xy 375.601375 -394.757767) (xy 375.60865 -394.80645) (xy 375.609104 -394.831062) (xy 375.608671 -394.85518)
			(xy 375.601675 -394.902905) (xy 375.587827 -394.949109) (xy 375.567419 -394.992814) (xy 375.554494 -395.01318)
			(xy 375.55043 -395.01953) (xy 375.546112 -395.0335) (xy 375.546112 -395.045438) (xy 375.54662 -395.05255)
			(xy 375.54916 -395.07033) (xy 375.55043 -395.080236) (xy 375.568464 -395.111732) (xy 375.575322 -395.117574)
			(xy 375.596579 -395.136255) (xy 375.634787 -395.178003) (xy 375.667557 -395.224143) (xy 375.694389 -395.27397)
			(xy 375.714875 -395.326724) (xy 375.728701 -395.381602) (xy 375.735658 -395.437766) (xy 375.736104 -395.466062)
			(xy 375.736104 -395.46657) (xy 375.735532 -395.498823) (xy 375.726431 -395.562685) (xy 375.708448 -395.624635)
			(xy 375.695718 -395.654276) (xy 375.693686 -395.658594) (xy 375.690974 -395.668039) (xy 375.692163 -395.687634)
			(xy 375.695972 -395.696694) (xy 375.702322 -395.71041) (xy 375.705624 -395.714728) (xy 375.715276 -395.727428)
			(xy 375.718832 -395.730476) (xy 375.743075 -395.75235) (xy 375.785733 -395.801784) (xy 375.820938 -395.856776)
			(xy 375.847976 -395.916211) (xy 375.866298 -395.978883) (xy 375.875533 -396.043522) (xy 375.876058 -396.07617)
			(xy 375.876058 -396.085822) (xy 375.874524 -396.122796) (xy 375.86099 -396.195546) (xy 375.849134 -396.230602)
			(xy 375.837539 -396.261158) (xy 375.80694 -396.318906) (xy 375.788174 -396.345664) (xy 375.783602 -396.352014)
			(xy 375.777252 -396.370048) (xy 375.774817 -396.379059) (xy 375.775875 -396.397679) (xy 375.779284 -396.40637)
			(xy 375.780046 -396.408148) (xy 375.820432 -396.488666) (xy 375.824988 -396.495982) (xy 375.837993 -396.507274)
			(xy 375.854005 -396.513619) (xy 375.862596 -396.51432) (xy 376.172222 -396.51432) (xy 376.174254 -396.51432)
			(xy 376.182846 -396.513636) (xy 376.198854 -396.507278) (xy 376.211852 -396.495976) (xy 376.216418 -396.488666)
			(xy 376.256804 -396.408148) (xy 376.257566 -396.40637) (xy 376.260994 -396.397688) (xy 376.26202 -396.379065)
			(xy 376.259598 -396.370048) (xy 376.253248 -396.352014) (xy 376.248676 -396.345664) (xy 376.232177 -396.322297)
			(xy 376.204491 -396.272241) (xy 376.183262 -396.219123) (xy 376.168823 -396.163773) (xy 376.161398 -396.107055)
			(xy 376.160792 -396.078456) (xy 376.160792 -396.065248) (xy 376.161975 -396.034661) (xy 376.171514 -395.974197)
			(xy 376.189034 -395.915546) (xy 376.201178 -395.887448) (xy 376.20321 -395.88313) (xy 376.205927 -395.873685)
			(xy 376.204746 -395.854085) (xy 376.200924 -395.84503) (xy 376.194574 -395.831314) (xy 376.191272 -395.826996)
			(xy 376.18162 -395.814296) (xy 376.178064 -395.811248) (xy 376.153843 -395.789413) (xy 376.111219 -395.74006)
			(xy 376.076038 -395.685153) (xy 376.049014 -395.625805) (xy 376.030694 -395.56322) (xy 376.021451 -395.498668)
			(xy 376.020838 -395.466062) (xy 376.021261 -395.437766) (xy 376.028236 -395.381605) (xy 376.042074 -395.326731)
			(xy 376.062566 -395.273979) (xy 376.089399 -395.224153) (xy 376.122164 -395.17801) (xy 376.160363 -395.136255)
			(xy 376.18162 -395.117574) (xy 376.188478 -395.111732) (xy 376.206512 -395.080236) (xy 376.207782 -395.07033)
			(xy 376.21083 -395.04874) (xy 376.21083 -395.048486) (xy 376.2121 -395.039088) (xy 376.208036 -395.021562)
			(xy 376.20702 -395.019784) (xy 376.202956 -395.013688) (xy 376.189189 -394.992131) (xy 376.167751 -394.945695)
			(xy 376.160284 -394.921232) (xy 376.155458 -394.902182) (xy 376.155458 -394.901928) (xy 376.153426 -394.893292)
			(xy 376.149362 -394.886434) (xy 376.147 -394.882789) (xy 376.141255 -394.876276) (xy 376.137932 -394.87348)
			(xy 376.121422 -394.860018) (xy 376.114564 -394.854176) (xy 376.08383 -394.843) (xy 376.075702 -394.842746)
			(xy 376.046413 -394.841285) (xy 375.988537 -394.83183) (xy 375.932343 -394.815059) (xy 375.878752 -394.791249)
			(xy 375.828641 -394.760788) (xy 375.782831 -394.724176) (xy 375.742072 -394.682012) (xy 375.707033 -394.634988)
			(xy 375.678287 -394.583874) (xy 375.656306 -394.529506) (xy 375.641449 -394.472776) (xy 375.633959 -394.414614)
			(xy 375.633488 -394.385292) (xy 375.633488 -394.385038) (xy 375.633488 -394.384022) (xy 375.633956 -394.355522)
			(xy 375.641089 -394.29897) (xy 375.647712 -394.271246) (xy 375.648474 -394.268452) (xy 375.650252 -394.255752)
			(xy 375.650252 -394.245846) (xy 375.650033 -394.239242) (xy 375.646561 -394.226498) (xy 375.643394 -394.2207)
			(xy 375.613422 -394.168376) (xy 375.610801 -394.16408) (xy 375.604146 -394.156532) (xy 375.600214 -394.15339)
			(xy 375.5771 -394.135864) (xy 375.567702 -394.13307) (xy 375.539614 -394.124714) (xy 375.485666 -394.101829)
			(xy 375.435078 -394.072249) (xy 375.388677 -394.036458) (xy 375.34722 -393.99504) (xy 375.311386 -393.948671)
			(xy 375.28176 -393.89811) (xy 375.258826 -393.844183) (xy 375.242958 -393.787771) (xy 375.234417 -393.729796)
			(xy 375.233438 -393.700508) (xy 375.233438 -393.691872) (xy 375.233964 -393.661016) (xy 375.242294 -393.599868)
			(xy 375.258758 -393.540391) (xy 375.283059 -393.483664) (xy 375.298462 -393.456922) (xy 375.298462 -393.456668)
			(xy 375.298716 -393.456414) (xy 375.303569 -393.447086) (xy 375.306075 -393.426231) (xy 375.303542 -393.416028)
			(xy 375.294398 -393.389612) (xy 375.27738 -393.340844) (xy 375.275602 -393.336526) (xy 375.271679 -393.328777)
			(xy 375.259596 -393.316318) (xy 375.25198 -393.312142) (xy 375.247662 -393.31011) (xy 375.245376 -393.309094)
			(xy 375.222164 -393.299795) (xy 375.178617 -393.275223) (xy 375.139258 -393.244383) (xy 375.104984 -393.207977)
			(xy 375.076572 -393.166832) (xy 375.05467 -393.121882) (xy 375.039774 -393.074151) (xy 375.032223 -393.024723)
			(xy 375.031762 -392.999722) (xy 375.032272 -392.973735) (xy 375.040402 -392.9224) (xy 375.056463 -392.87297)
			(xy 375.080059 -392.82666) (xy 375.110609 -392.784612) (xy 375.14736 -392.747861) (xy 375.189408 -392.717311)
			(xy 375.235718 -392.693715) (xy 375.285148 -392.677654) (xy 375.336483 -392.669524) (xy 375.388457 -392.669524)
			(xy 375.439792 -392.677654) (xy 375.489222 -392.693715) (xy 375.535532 -392.717311) (xy 375.57758 -392.747861)
			(xy 375.614331 -392.784612) (xy 375.644881 -392.82666) (xy 375.668477 -392.87297) (xy 375.684538 -392.9224)
			(xy 375.692668 -392.973735) (xy 375.693178 -392.999722) (xy 375.693178 -393.00023) (xy 375.692576 -393.027278)
			(xy 375.683639 -393.080633) (xy 375.675398 -393.106402) (xy 375.671842 -393.11707) (xy 375.672858 -393.127738)
			(xy 375.673579 -393.133457) (xy 375.67729 -393.144367) (xy 375.680224 -393.149328) (xy 375.700544 -393.182348)
			(xy 375.721118 -393.215876) (xy 375.724122 -393.220574) (xy 375.731815 -393.228644) (xy 375.736358 -393.231878)
			(xy 375.745502 -393.23772) (xy 375.7549 -393.239244) (xy 375.757186 -393.239498) (xy 375.784565 -393.243907)
			(xy 375.838071 -393.258491) (xy 375.889426 -393.279424) (xy 375.937879 -393.306401) (xy 375.982724 -393.339028)
			(xy 376.003312 -393.357608) (xy 376.025387 -393.378872) (xy 376.06423 -393.426287) (xy 376.096401 -393.47846)
			(xy 376.121326 -393.534457) (xy 376.13856 -393.593278) (xy 376.147794 -393.653873) (xy 376.148854 -393.684506)
			(xy 376.148854 -393.692634) (xy 376.148404 -393.721986) (xy 376.140886 -393.780207) (xy 376.133868 -393.808712)
			(xy 376.13336 -393.81049) (xy 376.13336 -393.810998) (xy 376.13209 -393.815062) (xy 376.131328 -393.817348)
			(xy 376.129622 -393.826563) (xy 376.132363 -393.845089) (xy 376.136662 -393.853416) (xy 376.136916 -393.853924)
			(xy 376.16892 -393.909296) (xy 376.171537 -393.913596) (xy 376.178185 -393.921153) (xy 376.182128 -393.924282)
			(xy 376.205242 -393.941808) (xy 376.21464 -393.944602) (xy 376.243116 -393.953074) (xy 376.297767 -393.976372)
			(xy 376.348945 -394.006545) (xy 376.39579 -394.043086) (xy 376.437513 -394.085379) (xy 376.473415 -394.132715)
			(xy 376.502892 -394.184297) (xy 376.525447 -394.239259) (xy 376.540703 -394.296677) (xy 376.548403 -394.355587)
			(xy 376.548904 -394.385292) (xy 376.548789 -394.399491) (xy 376.54701 -394.427832) (xy 376.545348 -394.441934)
			(xy 376.544908 -394.446456) (xy 376.545413 -394.455526) (xy 376.546364 -394.459968) (xy 376.548142 -394.467842)
			(xy 376.552714 -394.475208) (xy 376.568208 -394.5001) (xy 376.572916 -394.50716) (xy 376.586028 -394.517918)
			(xy 376.593862 -394.521182) (xy 376.617231 -394.530383) (xy 376.661105 -394.554823) (xy 376.70078 -394.585615)
			(xy 376.735346 -394.622049) (xy 376.764007 -394.66329) (xy 376.786105 -394.708389) (xy 376.801133 -394.75631)
			(xy 376.808745 -394.805951) (xy 376.809254 -394.831062) (xy 376.808821 -394.855179) (xy 376.801824 -394.902904)
			(xy 376.787974 -394.949107) (xy 376.767563 -394.992811) (xy 376.754644 -395.01318) (xy 376.75058 -395.01953)
			(xy 376.746262 -395.0335) (xy 376.746262 -395.045438) (xy 376.74677 -395.05255) (xy 376.74931 -395.07033)
			(xy 376.75058 -395.080236) (xy 376.768614 -395.111732) (xy 376.775472 -395.117574) (xy 376.796727 -395.136256)
			(xy 376.834931 -395.178006) (xy 376.867697 -395.224146) (xy 376.894527 -395.273973) (xy 376.91501 -395.326728)
			(xy 376.928835 -395.381604) (xy 376.93579 -395.437766) (xy 376.936254 -395.466062) (xy 376.936254 -395.46657)
			(xy 376.935682 -395.498823) (xy 376.926582 -395.562686) (xy 376.908601 -395.624636) (xy 376.895868 -395.654276)
			(xy 376.893836 -395.658594) (xy 376.891122 -395.668038) (xy 376.892312 -395.687634) (xy 376.896122 -395.696694)
			(xy 376.902472 -395.71041) (xy 376.905774 -395.714728) (xy 376.915426 -395.727428) (xy 376.918982 -395.730476)
			(xy 376.943223 -395.752351) (xy 376.985877 -395.801788) (xy 377.021077 -395.85678) (xy 377.048112 -395.916214)
			(xy 377.066432 -395.978885) (xy 377.075666 -396.043523) (xy 377.076208 -396.07617) (xy 377.076208 -396.085822)
			(xy 377.074675 -396.122796) (xy 377.061142 -396.195547) (xy 377.049284 -396.230602) (xy 377.037688 -396.261157)
			(xy 377.007086 -396.318904) (xy 376.988324 -396.345664) (xy 376.983752 -396.352014) (xy 376.977402 -396.370048)
			(xy 376.974968 -396.379059) (xy 376.976026 -396.397679) (xy 376.979434 -396.40637) (xy 376.980196 -396.408148)
			(xy 377.020582 -396.488666) (xy 377.025136 -396.495987) (xy 377.038138 -396.507292) (xy 377.054151 -396.513652)
			(xy 377.062746 -396.51432) (xy 377.372118 -396.51432) (xy 377.37415 -396.51432) (xy 377.382742 -396.513637)
			(xy 377.398751 -396.50728) (xy 377.41175 -396.495978) (xy 377.416314 -396.488666) (xy 377.4567 -396.408148)
			(xy 377.457462 -396.40637) (xy 377.460891 -396.397688) (xy 377.461916 -396.379065) (xy 377.459494 -396.370048)
			(xy 377.453144 -396.352014) (xy 377.448572 -396.345664) (xy 377.432073 -396.322297) (xy 377.404387 -396.272241)
			(xy 377.383159 -396.219123) (xy 377.36872 -396.163773) (xy 377.361295 -396.107055) (xy 377.360688 -396.078456)
			(xy 377.360688 -396.065248) (xy 377.361871 -396.034661) (xy 377.371409 -395.974197) (xy 377.38893 -395.915546)
			(xy 377.401074 -395.887448) (xy 377.403106 -395.88313) (xy 377.405823 -395.873685) (xy 377.404642 -395.854085)
			(xy 377.40082 -395.84503) (xy 377.39447 -395.831314) (xy 377.391168 -395.826996) (xy 377.381516 -395.814296)
			(xy 377.37796 -395.811248) (xy 377.353739 -395.789413) (xy 377.311116 -395.74006) (xy 377.275935 -395.685152)
			(xy 377.248911 -395.625805) (xy 377.230592 -395.56322) (xy 377.221348 -395.498668) (xy 377.220734 -395.466062)
			(xy 377.221157 -395.437766) (xy 377.228132 -395.381605) (xy 377.24197 -395.326731) (xy 377.262462 -395.273979)
			(xy 377.289294 -395.224152) (xy 377.322059 -395.17801) (xy 377.360258 -395.136254) (xy 377.381516 -395.117574)
			(xy 377.388374 -395.111732) (xy 377.406408 -395.080236) (xy 377.407678 -395.07033) (xy 377.410726 -395.04874)
			(xy 377.410726 -395.048486) (xy 377.411996 -395.039088) (xy 377.407932 -395.021562) (xy 377.406916 -395.019784)
			(xy 377.402852 -395.013688) (xy 377.389085 -394.992131) (xy 377.367648 -394.945695) (xy 377.36018 -394.921232)
			(xy 377.355354 -394.901928) (xy 377.353576 -394.893546) (xy 377.349258 -394.886434) (xy 377.34691 -394.882722)
			(xy 377.34117 -394.876075) (xy 377.337828 -394.873226) (xy 377.321318 -394.859764) (xy 377.314206 -394.854176)
			(xy 377.28398 -394.843) (xy 377.275598 -394.842746) (xy 377.246318 -394.841273) (xy 377.188462 -394.831796)
			(xy 377.13229 -394.81501) (xy 377.078721 -394.791188) (xy 377.028632 -394.76072) (xy 376.982844 -394.724106)
			(xy 376.942106 -394.681945) (xy 376.907085 -394.634928) (xy 376.878355 -394.583823) (xy 376.856386 -394.529468)
			(xy 376.841537 -394.472753) (xy 376.834052 -394.414605) (xy 376.833638 -394.385292) (xy 376.833638 -394.385038)
			(xy 376.833638 -394.384022) (xy 376.834106 -394.355522) (xy 376.84124 -394.29897) (xy 376.847862 -394.271246)
			(xy 376.848624 -394.268452) (xy 376.850402 -394.255752) (xy 376.850402 -394.245846) (xy 376.850182 -394.239243)
			(xy 376.846707 -394.2265) (xy 376.843544 -394.2207) (xy 376.813572 -394.168376) (xy 376.810953 -394.164078)
			(xy 376.804302 -394.156525) (xy 376.800364 -394.15339) (xy 376.77725 -394.135864) (xy 376.767852 -394.13307)
			(xy 376.739378 -394.124598) (xy 376.684729 -394.101298) (xy 376.633554 -394.071124) (xy 376.586712 -394.034583)
			(xy 376.544992 -393.992289) (xy 376.509093 -393.944953) (xy 376.47962 -393.893371) (xy 376.457068 -393.838409)
			(xy 376.441816 -393.780992) (xy 376.43412 -393.722084) (xy 376.433588 -393.69238) (xy 376.433588 -393.679934)
			(xy 376.434869 -393.650621) (xy 376.443977 -393.592659) (xy 376.46042 -393.536336) (xy 376.483927 -393.482578)
			(xy 376.498612 -393.457176) (xy 376.498612 -393.456668) (xy 376.498866 -393.456414) (xy 376.501533 -393.451705)
			(xy 376.504998 -393.441456) (xy 376.505724 -393.436094) (xy 376.50674 -393.425172) (xy 376.477276 -393.34059)
			(xy 376.4731 -393.330308) (xy 376.457697 -393.314364) (xy 376.447558 -393.309856) (xy 376.445272 -393.30884)
			(xy 376.441462 -393.30757) (xy 376.439684 -393.306808) (xy 376.43943 -393.306808) (xy 376.437652 -393.306046)
			(xy 376.415137 -393.296403) (xy 376.372992 -393.271448) (xy 376.334989 -393.240549) (xy 376.301961 -393.204382)
			(xy 376.274629 -393.163738) (xy 376.253592 -393.119507) (xy 376.23931 -393.072656) (xy 376.232096 -393.024212)
			(xy 376.231658 -392.999722) (xy 376.232168 -392.973735) (xy 376.240298 -392.9224) (xy 376.256359 -392.87297)
			(xy 376.279955 -392.82666) (xy 376.310505 -392.784612) (xy 376.347256 -392.747861) (xy 376.389304 -392.717311)
			(xy 376.435614 -392.693715) (xy 376.485044 -392.677654) (xy 376.536379 -392.669524) (xy 376.588353 -392.669524)
			(xy 376.639688 -392.677654) (xy 376.689118 -392.693715) (xy 376.735428 -392.717311) (xy 376.777476 -392.747861)
			(xy 376.814227 -392.784612) (xy 376.844777 -392.82666) (xy 376.868373 -392.87297) (xy 376.884434 -392.9224)
			(xy 376.892564 -392.973735) (xy 376.893074 -392.999722) (xy 376.893074 -393.000484) (xy 376.892586 -393.026518)
			(xy 376.884416 -393.077941) (xy 376.876818 -393.102846) (xy 376.875548 -393.106656) (xy 376.874024 -393.11453)
			(xy 376.873329 -393.119145) (xy 376.873461 -393.128477) (xy 376.874278 -393.133072) (xy 376.876056 -393.142216)
			(xy 376.880882 -393.15009) (xy 376.920252 -393.215114) (xy 376.92076 -393.21613) (xy 376.928888 -393.225782)
			(xy 376.931962 -393.228561) (xy 376.93886 -393.233151) (xy 376.942604 -393.234926) (xy 376.950224 -393.238482)
			(xy 376.957336 -393.239498) (xy 376.986281 -393.244195) (xy 377.042749 -393.260003) (xy 377.096737 -393.282891)
			(xy 377.147362 -393.312484) (xy 377.193794 -393.348297) (xy 377.235274 -393.389746) (xy 377.271123 -393.436151)
			(xy 377.300754 -393.486753) (xy 377.323683 -393.540724) (xy 377.339533 -393.597181) (xy 377.348046 -393.655199)
			(xy 377.349004 -393.684506) (xy 377.349004 -393.692634) (xy 377.348554 -393.721986) (xy 377.341035 -393.780207)
			(xy 377.334018 -393.808712) (xy 377.33351 -393.81049) (xy 377.33351 -393.810998) (xy 377.33224 -393.815062)
			(xy 377.331478 -393.817348) (xy 377.32983 -393.826565) (xy 377.332566 -393.845071) (xy 377.336812 -393.853416)
			(xy 377.337066 -393.853924) (xy 377.36907 -393.909296) (xy 377.371689 -393.913594) (xy 377.378341 -393.921146)
			(xy 377.382278 -393.924282) (xy 377.405392 -393.941808) (xy 377.41479 -393.944602) (xy 377.443268 -393.953071)
			(xy 377.497924 -393.976366) (xy 377.549107 -394.006536) (xy 377.595957 -394.043075) (xy 377.637686 -394.085368)
			(xy 377.673592 -394.132704) (xy 377.703072 -394.184288) (xy 377.725631 -394.239252) (xy 377.740889 -394.296673)
			(xy 377.748589 -394.355585) (xy 377.749054 -394.385292) (xy 377.748947 -394.399554) (xy 377.74717 -394.428024)
			(xy 377.745498 -394.442188) (xy 377.744228 -394.451586) (xy 377.74626 -394.459968) (xy 377.747346 -394.464059)
			(xy 377.750666 -394.471845) (xy 377.752864 -394.475462) (xy 377.764548 -394.493496) (xy 377.770898 -394.501624)
			(xy 377.774962 -394.505434) (xy 377.793758 -394.520928) (xy 377.79833 -394.522706) (xy 377.801378 -394.523976)
			(xy 377.824063 -394.533538) (xy 377.866552 -394.558398) (xy 377.904885 -394.589283) (xy 377.938213 -394.625512)
			(xy 377.965801 -394.666282) (xy 377.987037 -394.710693) (xy 378.001453 -394.757762) (xy 378.00873 -394.806448)
			(xy 378.00915 -394.831062) (xy 378.008717 -394.855179) (xy 378.00172 -394.902904) (xy 377.98787 -394.949107)
			(xy 377.967459 -394.99281) (xy 377.95454 -395.01318) (xy 377.950476 -395.01953) (xy 377.946158 -395.0335)
			(xy 377.946158 -395.045438) (xy 377.946666 -395.05255) (xy 377.949206 -395.07033) (xy 377.950476 -395.080236)
			(xy 377.96851 -395.111732) (xy 377.975368 -395.117574) (xy 377.996624 -395.136256) (xy 378.034827 -395.178006)
			(xy 378.067594 -395.224146) (xy 378.094424 -395.273973) (xy 378.114907 -395.326727) (xy 378.128732 -395.381604)
			(xy 378.135688 -395.437766) (xy 378.13615 -395.466062) (xy 378.13615 -395.46657) (xy 378.135578 -395.498823)
			(xy 378.126478 -395.562686) (xy 378.108497 -395.624636) (xy 378.095764 -395.654276) (xy 378.093732 -395.658594)
			(xy 378.091018 -395.668038) (xy 378.092208 -395.687634) (xy 378.096018 -395.696694) (xy 378.102368 -395.71041)
			(xy 378.10567 -395.714728) (xy 378.115322 -395.727428) (xy 378.118878 -395.730476) (xy 378.143119 -395.752351)
			(xy 378.185773 -395.801787) (xy 378.220974 -395.85678) (xy 378.248009 -395.916214) (xy 378.266329 -395.978885)
			(xy 378.275564 -396.043523) (xy 378.276104 -396.07617) (xy 378.276104 -396.085822) (xy 378.274571 -396.122796)
			(xy 378.261038 -396.195547) (xy 378.24918 -396.230602) (xy 378.237584 -396.261157) (xy 378.206982 -396.318903)
			(xy 378.18822 -396.345664) (xy 378.183648 -396.352014) (xy 378.177298 -396.370048) (xy 378.174864 -396.379059)
			(xy 378.175922 -396.397679) (xy 378.17933 -396.40637) (xy 378.180092 -396.408148) (xy 378.220478 -396.488666)
			(xy 378.225036 -396.495977) (xy 378.238043 -396.507258) (xy 378.254055 -396.513588) (xy 378.262642 -396.51432)
			(xy 378.572268 -396.51432) (xy 378.5743 -396.51432) (xy 378.582896 -396.513644) (xy 378.598918 -396.507298)
			(xy 378.61193 -396.495999) (xy 378.616464 -396.488666) (xy 378.65685 -396.408148) (xy 378.657612 -396.40637)
			(xy 378.661043 -396.397688) (xy 378.66207 -396.379064) (xy 378.659644 -396.370048) (xy 378.653294 -396.352014)
			(xy 378.648722 -396.345664) (xy 378.632222 -396.322298) (xy 378.604533 -396.272242) (xy 378.583302 -396.219125)
			(xy 378.568861 -396.163774) (xy 378.561435 -396.107055) (xy 378.560838 -396.078456) (xy 378.560838 -396.065248)
			(xy 378.562021 -396.034661) (xy 378.571561 -395.974197) (xy 378.589083 -395.915547) (xy 378.601224 -395.887448)
			(xy 378.603256 -395.88313) (xy 378.605972 -395.873685) (xy 378.604792 -395.854085) (xy 378.60097 -395.84503)
			(xy 378.59462 -395.831314) (xy 378.591318 -395.826996) (xy 378.581666 -395.814296) (xy 378.57811 -395.811248)
			(xy 378.553886 -395.789414) (xy 378.511259 -395.740063) (xy 378.476075 -395.685156) (xy 378.449047 -395.625808)
			(xy 378.430726 -395.563222) (xy 378.421481 -395.498668) (xy 378.420884 -395.466062) (xy 378.421307 -395.437766)
			(xy 378.428282 -395.381606) (xy 378.442122 -395.326733) (xy 378.462615 -395.273982) (xy 378.48945 -395.224158)
			(xy 378.522217 -395.178018) (xy 378.560418 -395.136265) (xy 378.581666 -395.117574) (xy 378.588524 -395.111732)
			(xy 378.606558 -395.080236) (xy 378.607828 -395.07033) (xy 378.610876 -395.04874) (xy 378.610876 -395.048486)
			(xy 378.612146 -395.039088) (xy 378.608082 -395.021562) (xy 378.607066 -395.019784) (xy 378.603002 -395.013688)
			(xy 378.589234 -394.992132) (xy 378.567793 -394.945697) (xy 378.56033 -394.921232) (xy 378.555504 -394.902182)
			(xy 378.555504 -394.901928) (xy 378.553472 -394.893292) (xy 378.549408 -394.886434) (xy 378.547043 -394.882791)
			(xy 378.541295 -394.876283) (xy 378.537978 -394.87348) (xy 378.521468 -394.860018) (xy 378.51461 -394.854176)
			(xy 378.483876 -394.843) (xy 378.475748 -394.842746) (xy 378.446457 -394.841288) (xy 378.388577 -394.831837)
			(xy 378.332378 -394.81507) (xy 378.278782 -394.791262) (xy 378.228665 -394.760803) (xy 378.18285 -394.724191)
			(xy 378.142087 -394.682027) (xy 378.107044 -394.635002) (xy 378.078294 -394.583885) (xy 378.05631 -394.529515)
			(xy 378.041451 -394.472782) (xy 378.033961 -394.414615) (xy 378.033534 -394.385292) (xy 378.033534 -394.385038)
			(xy 378.033534 -394.384022) (xy 378.034002 -394.355522) (xy 378.041136 -394.29897) (xy 378.047758 -394.271246)
			(xy 378.04852 -394.268452) (xy 378.050298 -394.255752) (xy 378.050298 -394.245846) (xy 378.050078 -394.239243)
			(xy 378.046603 -394.2265) (xy 378.04344 -394.2207) (xy 378.013468 -394.168376) (xy 378.010849 -394.164078)
			(xy 378.004197 -394.156525) (xy 378.00026 -394.15339) (xy 377.977146 -394.135864) (xy 377.967748 -394.13307)
			(xy 377.939274 -394.124597) (xy 377.884626 -394.101297) (xy 377.833451 -394.071123) (xy 377.78661 -394.034582)
			(xy 377.744889 -393.992288) (xy 377.708991 -393.944952) (xy 377.679519 -393.89337) (xy 377.656967 -393.838409)
			(xy 377.641715 -393.780992) (xy 377.634019 -393.722084) (xy 377.633484 -393.69238) (xy 377.633484 -393.679934)
			(xy 377.634765 -393.650621) (xy 377.643873 -393.592659) (xy 377.660316 -393.536336) (xy 377.683823 -393.482577)
			(xy 377.698508 -393.457176) (xy 377.698508 -393.456668) (xy 377.698762 -393.456414) (xy 377.701429 -393.451705)
			(xy 377.704894 -393.441456) (xy 377.70562 -393.436094) (xy 377.706636 -393.425172) (xy 377.677172 -393.34059)
			(xy 377.672996 -393.330308) (xy 377.657593 -393.314366) (xy 377.647454 -393.309856) (xy 377.645168 -393.30884)
			(xy 377.641358 -393.30757) (xy 377.63958 -393.306808) (xy 377.639326 -393.306808) (xy 377.637548 -393.306046)
			(xy 377.615033 -393.296403) (xy 377.572888 -393.271448) (xy 377.534886 -393.240549) (xy 377.501858 -393.204381)
			(xy 377.474527 -393.163738) (xy 377.45349 -393.119507) (xy 377.439209 -393.072656) (xy 377.431995 -393.024211)
			(xy 377.431554 -392.999722) (xy 377.432064 -392.973735) (xy 377.440194 -392.9224) (xy 377.456255 -392.87297)
			(xy 377.479851 -392.82666) (xy 377.510401 -392.784612) (xy 377.547152 -392.747861) (xy 377.5892 -392.717311)
			(xy 377.63551 -392.693715) (xy 377.68494 -392.677654) (xy 377.736275 -392.669524) (xy 377.788249 -392.669524)
			(xy 377.839584 -392.677654) (xy 377.889014 -392.693715) (xy 377.935324 -392.717311) (xy 377.977372 -392.747861)
			(xy 378.014123 -392.784612) (xy 378.044673 -392.82666) (xy 378.068269 -392.87297) (xy 378.08433 -392.9224)
			(xy 378.09246 -392.973735) (xy 378.09297 -392.999722) (xy 378.09297 -393.000484) (xy 378.092482 -393.026518)
			(xy 378.084312 -393.077941) (xy 378.076714 -393.102846) (xy 378.075444 -393.106656) (xy 378.07392 -393.11453)
			(xy 378.073225 -393.119145) (xy 378.073357 -393.128477) (xy 378.074174 -393.133072) (xy 378.075952 -393.142216)
			(xy 378.080778 -393.15009) (xy 378.120148 -393.215114) (xy 378.120656 -393.21613) (xy 378.128784 -393.225782)
			(xy 378.131858 -393.228561) (xy 378.138755 -393.233152) (xy 378.1425 -393.234926) (xy 378.15012 -393.238482)
			(xy 378.157232 -393.239498) (xy 378.186177 -393.244195) (xy 378.242646 -393.260002) (xy 378.296634 -393.28289)
			(xy 378.347259 -393.312483) (xy 378.393692 -393.348296) (xy 378.435172 -393.389745) (xy 378.471021 -393.43615)
			(xy 378.500653 -393.486752) (xy 378.523582 -393.540723) (xy 378.539432 -393.59718) (xy 378.547946 -393.655198)
			(xy 378.5489 -393.684506) (xy 378.5489 -393.692634) (xy 378.54845 -393.721986) (xy 378.540931 -393.780207)
			(xy 378.533914 -393.808712) (xy 378.533406 -393.81049) (xy 378.533406 -393.810998) (xy 378.532136 -393.815062)
			(xy 378.531374 -393.817348) (xy 378.529726 -393.826565) (xy 378.532462 -393.845071) (xy 378.536708 -393.853416)
			(xy 378.536962 -393.853924) (xy 378.568966 -393.909296) (xy 378.571585 -393.913595) (xy 378.578236 -393.921147)
			(xy 378.582174 -393.924282) (xy 378.605288 -393.941808) (xy 378.614686 -393.944602) (xy 378.643164 -393.953071)
			(xy 378.697821 -393.976365) (xy 378.749004 -394.006536) (xy 378.795855 -394.043074) (xy 378.837584 -394.085367)
			(xy 378.87349 -394.132703) (xy 378.902971 -394.184287) (xy 378.925529 -394.239251) (xy 378.940787 -394.296673)
			(xy 378.948488 -394.355585) (xy 378.94895 -394.385292) (xy 378.948835 -394.399491) (xy 378.947057 -394.427832)
			(xy 378.945394 -394.441934) (xy 378.944948 -394.446456) (xy 378.945454 -394.455526) (xy 378.94641 -394.459968)
			(xy 378.948188 -394.467842) (xy 378.95276 -394.475208) (xy 378.968254 -394.5001) (xy 378.972958 -394.507165)
			(xy 378.986065 -394.517935) (xy 378.993908 -394.521182) (xy 379.01728 -394.53038) (xy 379.06116 -394.554817)
			(xy 379.100841 -394.585606) (xy 379.135413 -394.622039) (xy 379.164079 -394.66328) (xy 379.186181 -394.708381)
			(xy 379.201212 -394.756305) (xy 379.208825 -394.80595) (xy 379.2093 -394.831062) (xy 379.208867 -394.85518)
			(xy 379.201871 -394.902905) (xy 379.188023 -394.949109) (xy 379.167614 -394.992814) (xy 379.15469 -395.01318)
			(xy 379.150626 -395.01953) (xy 379.146308 -395.0335) (xy 379.146308 -395.045438) (xy 379.146816 -395.05255)
			(xy 379.149356 -395.07033) (xy 379.150626 -395.080236) (xy 379.16866 -395.111732) (xy 379.175518 -395.117574)
			(xy 379.196776 -395.136255) (xy 379.234983 -395.178003) (xy 379.267754 -395.224142) (xy 379.294586 -395.273969)
			(xy 379.315072 -395.326724) (xy 379.328899 -395.381602) (xy 379.335855 -395.437765) (xy 379.3363 -395.466062)
			(xy 379.3363 -395.46657) (xy 379.335728 -395.498823) (xy 379.326627 -395.562685) (xy 379.308643 -395.624635)
			(xy 379.295914 -395.654276) (xy 379.293882 -395.658594) (xy 379.29117 -395.668039) (xy 379.292359 -395.687634)
			(xy 379.296168 -395.696694) (xy 379.302518 -395.71041) (xy 379.30582 -395.714728) (xy 379.315472 -395.727428)
			(xy 379.319028 -395.730476) (xy 379.343272 -395.75235) (xy 379.38593 -395.801784) (xy 379.421135 -395.856776)
			(xy 379.448173 -395.916211) (xy 379.466495 -395.978883) (xy 379.475731 -396.043522) (xy 379.476254 -396.07617)
			(xy 379.476254 -396.085822) (xy 379.47472 -396.122796) (xy 379.461185 -396.195546) (xy 379.44933 -396.230602)
			(xy 379.437735 -396.261158) (xy 379.407136 -396.318906) (xy 379.38837 -396.345664) (xy 379.383798 -396.352014)
			(xy 379.377448 -396.370048) (xy 379.375012 -396.379059) (xy 379.376071 -396.397679) (xy 379.37948 -396.40637)
			(xy 379.380242 -396.408148) (xy 379.420628 -396.488666) (xy 379.425184 -396.495982) (xy 379.438188 -396.507276)
			(xy 379.454201 -396.513621) (xy 379.462792 -396.51432) (xy 379.772164 -396.51432) (xy 379.774196 -396.51432)
			(xy 379.782793 -396.513645) (xy 379.798815 -396.507299) (xy 379.811828 -396.496001) (xy 379.81636 -396.488666)
			(xy 379.856746 -396.408148) (xy 379.857508 -396.40637) (xy 379.860939 -396.397688) (xy 379.861966 -396.379064)
			(xy 379.85954 -396.370048) (xy 379.85319 -396.352014) (xy 379.848618 -396.345664) (xy 379.832118 -396.322297)
			(xy 379.804429 -396.272242) (xy 379.783198 -396.219125) (xy 379.768758 -396.163774) (xy 379.761332 -396.107055)
			(xy 379.760734 -396.078456) (xy 379.760734 -396.065248) (xy 379.761917 -396.034661) (xy 379.771456 -395.974197)
			(xy 379.788978 -395.915547) (xy 379.80112 -395.887448) (xy 379.803152 -395.88313) (xy 379.805868 -395.873685)
			(xy 379.804688 -395.854085) (xy 379.800866 -395.84503) (xy 379.794516 -395.831314) (xy 379.791214 -395.826996)
			(xy 379.781562 -395.814296) (xy 379.778006 -395.811248) (xy 379.753783 -395.789414) (xy 379.711155 -395.740062)
			(xy 379.675971 -395.685156) (xy 379.648945 -395.625808) (xy 379.630623 -395.563222) (xy 379.621378 -395.498668)
			(xy 379.62078 -395.466062) (xy 379.621203 -395.437766) (xy 379.628178 -395.381606) (xy 379.642018 -395.326733)
			(xy 379.662511 -395.273982) (xy 379.689345 -395.224157) (xy 379.722112 -395.178017) (xy 379.760313 -395.136264)
			(xy 379.781562 -395.117574) (xy 379.78842 -395.111732) (xy 379.806454 -395.080236) (xy 379.807724 -395.07033)
			(xy 379.810772 -395.04874) (xy 379.810772 -395.048486) (xy 379.812042 -395.039088) (xy 379.807978 -395.021562)
			(xy 379.806962 -395.019784) (xy 379.802898 -395.013688) (xy 379.78913 -394.992132) (xy 379.767689 -394.945696)
			(xy 379.760226 -394.921232) (xy 379.7554 -394.902182) (xy 379.7554 -394.901928) (xy 379.753368 -394.893292)
			(xy 379.749304 -394.886434) (xy 379.746939 -394.882792) (xy 379.741191 -394.876283) (xy 379.737874 -394.87348)
			(xy 379.721364 -394.860018) (xy 379.714506 -394.854176) (xy 379.683772 -394.843) (xy 379.675644 -394.842746)
			(xy 379.646353 -394.841288) (xy 379.588474 -394.831837) (xy 379.532275 -394.815069) (xy 379.478679 -394.791261)
			(xy 379.428563 -394.760802) (xy 379.382748 -394.72419) (xy 379.341986 -394.682026) (xy 379.306943 -394.635001)
			(xy 379.278194 -394.583884) (xy 379.25621 -394.529514) (xy 379.241351 -394.472781) (xy 379.233861 -394.414615)
			(xy 379.23343 -394.385292) (xy 379.23343 -394.385038) (xy 379.23343 -394.384022) (xy 379.233898 -394.355522)
			(xy 379.241032 -394.29897) (xy 379.247654 -394.271246) (xy 379.248416 -394.268452) (xy 379.250194 -394.255752)
			(xy 379.250194 -394.245846) (xy 379.249974 -394.239243) (xy 379.246499 -394.226501) (xy 379.243336 -394.2207)
			(xy 379.213364 -394.168376) (xy 379.210745 -394.164078) (xy 379.204093 -394.156526) (xy 379.200156 -394.15339)
			(xy 379.179328 -394.137642) (xy 379.16993 -394.134848) (xy 379.141205 -394.126487) (xy 379.086043 -394.103329)
			(xy 379.034359 -394.073196) (xy 378.987032 -394.0366) (xy 378.944864 -393.994161) (xy 378.908571 -393.946601)
			(xy 378.878769 -393.894726) (xy 378.855964 -393.839416) (xy 378.840544 -393.781612) (xy 378.832768 -393.722293)
			(xy 378.832364 -393.69238) (xy 378.83289 -393.66109) (xy 378.841386 -393.599089) (xy 378.858233 -393.538818)
			(xy 378.883116 -393.481397) (xy 378.898912 -393.454382) (xy 378.901705 -393.449508) (xy 378.9053 -393.43887)
			(xy 378.906024 -393.4333) (xy 378.906786 -393.425172) (xy 378.877322 -393.34059) (xy 378.873142 -393.330313)
			(xy 378.857733 -393.314384) (xy 378.847604 -393.309856) (xy 378.845318 -393.30884) (xy 378.841508 -393.30757)
			(xy 378.83973 -393.306808) (xy 378.839476 -393.306808) (xy 378.837698 -393.306046) (xy 378.815185 -393.2964)
			(xy 378.773047 -393.271442) (xy 378.73505 -393.24054) (xy 378.702027 -393.204372) (xy 378.6747 -393.163729)
			(xy 378.653667 -393.1195) (xy 378.639388 -393.072652) (xy 378.632176 -393.02421) (xy 378.631704 -392.999722)
			(xy 378.632214 -392.973735) (xy 378.640344 -392.9224) (xy 378.656405 -392.87297) (xy 378.680001 -392.82666)
			(xy 378.710551 -392.784612) (xy 378.747302 -392.747861) (xy 378.78935 -392.717311) (xy 378.83566 -392.693715)
			(xy 378.88509 -392.677654) (xy 378.936425 -392.669524) (xy 378.988399 -392.669524) (xy 379.039734 -392.677654)
			(xy 379.089164 -392.693715) (xy 379.135474 -392.717311) (xy 379.177522 -392.747861) (xy 379.214273 -392.784612)
			(xy 379.244823 -392.82666) (xy 379.268419 -392.87297) (xy 379.28448 -392.9224) (xy 379.29261 -392.973735)
			(xy 379.29312 -392.999722) (xy 379.29312 -393.000484) (xy 379.292632 -393.026518) (xy 379.284461 -393.07794)
			(xy 379.276864 -393.102846) (xy 379.275594 -393.106656) (xy 379.27407 -393.11453) (xy 379.273375 -393.119145)
			(xy 379.273507 -393.128477) (xy 379.274324 -393.133072) (xy 379.276102 -393.142216) (xy 379.280928 -393.15009)
			(xy 379.320044 -393.214352) (xy 379.323047 -393.219051) (xy 379.33074 -393.227121) (xy 379.335284 -393.230354)
			(xy 379.344682 -393.23645) (xy 379.356112 -393.237974) (xy 379.385576 -393.242653) (xy 379.443051 -393.258648)
			(xy 379.497968 -393.281957) (xy 379.549402 -393.312186) (xy 379.596485 -393.348825) (xy 379.638423 -393.391256)
			(xy 379.674508 -393.438765) (xy 379.704133 -393.490549) (xy 379.726797 -393.545735) (xy 379.742119 -393.603393)
			(xy 379.74984 -393.66255) (xy 379.75032 -393.69238) (xy 379.749803 -393.723644) (xy 379.74127 -393.785588)
			(xy 379.733302 -393.815824) (xy 379.733048 -393.81684) (xy 379.732286 -393.81938) (xy 379.730508 -393.83335)
			(xy 379.730508 -393.83589) (xy 379.730762 -393.84351) (xy 379.76048 -393.894818) (xy 379.760988 -393.895834)
			(xy 379.768862 -393.909296) (xy 379.771481 -393.913595) (xy 379.778132 -393.921147) (xy 379.78207 -393.924282)
			(xy 379.805184 -393.941808) (xy 379.814582 -393.944602) (xy 379.84306 -393.953071) (xy 379.897717 -393.976365)
			(xy 379.948901 -394.006535) (xy 379.995752 -394.043073) (xy 380.037481 -394.085366) (xy 380.073388 -394.132702)
			(xy 380.102869 -394.184286) (xy 380.125428 -394.239251) (xy 380.140686 -394.296672) (xy 380.148387 -394.355585)
			(xy 380.148846 -394.385292) (xy 380.148731 -394.399491) (xy 380.146953 -394.427832) (xy 380.14529 -394.441934)
			(xy 380.144844 -394.446456) (xy 380.14535 -394.455526) (xy 380.146306 -394.459968) (xy 380.148084 -394.467842)
			(xy 380.152656 -394.475208) (xy 380.16815 -394.5001) (xy 380.172854 -394.507165) (xy 380.185961 -394.517937)
			(xy 380.193804 -394.521182) (xy 380.217176 -394.53038) (xy 380.261057 -394.554816) (xy 380.300739 -394.585605)
			(xy 380.33531 -394.622039) (xy 380.363977 -394.66328) (xy 380.38608 -394.708381) (xy 380.40111 -394.756304)
			(xy 380.408724 -394.805949) (xy 380.409196 -394.831062) (xy 380.408763 -394.85518) (xy 380.401767 -394.902905)
			(xy 380.387918 -394.949109) (xy 380.36751 -394.992813) (xy 380.354586 -395.01318) (xy 380.350522 -395.01953)
			(xy 380.346204 -395.0335) (xy 380.346204 -395.045438) (xy 380.346712 -395.05255) (xy 380.349252 -395.07033)
			(xy 380.350522 -395.080236) (xy 380.368556 -395.111732) (xy 380.375414 -395.117574) (xy 380.396672 -395.136255)
			(xy 380.43488 -395.178003) (xy 380.46765 -395.224142) (xy 380.494483 -395.273969) (xy 380.514969 -395.326724)
			(xy 380.528796 -395.381602) (xy 380.535752 -395.437765) (xy 380.536196 -395.466062) (xy 380.536196 -395.46657)
			(xy 380.535624 -395.498823) (xy 380.526523 -395.562685) (xy 380.508539 -395.624635) (xy 380.49581 -395.654276)
			(xy 380.493778 -395.658594) (xy 380.491066 -395.668039) (xy 380.492255 -395.687634) (xy 380.496064 -395.696694)
			(xy 380.502414 -395.71041) (xy 380.505716 -395.714728) (xy 380.515368 -395.727428) (xy 380.518924 -395.730476)
			(xy 380.543168 -395.75235) (xy 380.585827 -395.801784) (xy 380.621032 -395.856776) (xy 380.64807 -395.91621)
			(xy 380.666392 -395.978883) (xy 380.675628 -396.043522) (xy 380.67615 -396.07617) (xy 380.67615 -396.085822)
			(xy 380.674616 -396.122796) (xy 380.661081 -396.195546) (xy 380.649226 -396.230602) (xy 380.637631 -396.261158)
			(xy 380.607032 -396.318906) (xy 380.588266 -396.345664) (xy 380.583694 -396.352014) (xy 380.577344 -396.370048)
			(xy 380.574908 -396.379059) (xy 380.575967 -396.397679) (xy 380.579376 -396.40637) (xy 380.580138 -396.408148)
			(xy 380.620524 -396.488666) (xy 380.62508 -396.495982) (xy 380.638084 -396.507277) (xy 380.654097 -396.513624)
			(xy 380.662688 -396.51432) (xy 380.97206 -396.51432) (xy 380.974092 -396.51432) (xy 380.98268 -396.51363)
			(xy 380.998679 -396.507265) (xy 381.011667 -396.49596) (xy 381.016256 -396.488666) (xy 381.056642 -396.408148)
			(xy 381.057404 -396.40637) (xy 381.060836 -396.397688) (xy 381.061862 -396.379064) (xy 381.059436 -396.370048)
			(xy 381.053086 -396.352014) (xy 381.048514 -396.345664) (xy 381.032014 -396.322297) (xy 381.004325 -396.272242)
			(xy 380.983095 -396.219124) (xy 380.968654 -396.163774) (xy 380.961229 -396.107055) (xy 380.96063 -396.078456)
			(xy 380.96063 -396.065248) (xy 380.961813 -396.034661) (xy 380.971352 -395.974197) (xy 380.988874 -395.915547)
			(xy 381.001016 -395.887448) (xy 381.003048 -395.88313) (xy 381.005764 -395.873685) (xy 381.004584 -395.854085)
			(xy 381.000762 -395.84503) (xy 380.994412 -395.831314) (xy 380.99111 -395.826996) (xy 380.981458 -395.814296)
			(xy 380.977902 -395.811248) (xy 380.953679 -395.789414) (xy 380.911052 -395.740062) (xy 380.875868 -395.685156)
			(xy 380.848842 -395.625807) (xy 380.83052 -395.563222) (xy 380.821276 -395.498668) (xy 380.820676 -395.466062)
			(xy 380.821099 -395.437766) (xy 380.828074 -395.381606) (xy 380.841914 -395.326733) (xy 380.862407 -395.273982)
			(xy 380.889241 -395.224157) (xy 380.922008 -395.178016) (xy 380.960208 -395.136263) (xy 380.981458 -395.117574)
			(xy 380.988316 -395.111732) (xy 381.00635 -395.080236) (xy 381.00762 -395.07033) (xy 381.010668 -395.04874)
			(xy 381.010668 -395.048486) (xy 381.011938 -395.039088) (xy 381.007874 -395.021562) (xy 381.006858 -395.019784)
			(xy 381.002794 -395.013688) (xy 380.989026 -394.992132) (xy 380.967585 -394.945696) (xy 380.960122 -394.921232)
			(xy 380.955296 -394.901928) (xy 380.953518 -394.893546) (xy 380.9492 -394.886434) (xy 380.94685 -394.882724)
			(xy 380.941106 -394.876082) (xy 380.93777 -394.873226) (xy 380.92126 -394.859764) (xy 380.914148 -394.854176)
			(xy 380.883922 -394.843) (xy 380.87554 -394.842746) (xy 380.846262 -394.84127) (xy 380.788412 -394.831787)
			(xy 380.732246 -394.814996) (xy 380.678683 -394.79117) (xy 380.628601 -394.760701) (xy 380.58282 -394.724087)
			(xy 380.542088 -394.681926) (xy 380.507072 -394.634911) (xy 380.478346 -394.583809) (xy 380.45638 -394.529457)
			(xy 380.441534 -394.472746) (xy 380.43405 -394.414603) (xy 380.43358 -394.385292) (xy 380.43358 -394.385038)
			(xy 380.43358 -394.384022) (xy 380.434048 -394.355522) (xy 380.441181 -394.29897) (xy 380.447804 -394.271246)
			(xy 380.448566 -394.268452) (xy 380.450344 -394.255752) (xy 380.450344 -394.245846) (xy 380.450124 -394.239243)
			(xy 380.446652 -394.226499) (xy 380.443486 -394.2207) (xy 380.413514 -394.168376) (xy 380.410893 -394.16408)
			(xy 380.404237 -394.156533) (xy 380.400306 -394.15339) (xy 380.377192 -394.135864) (xy 380.367794 -394.13307)
			(xy 380.339318 -394.1246) (xy 380.284665 -394.101303) (xy 380.233485 -394.071131) (xy 380.186639 -394.034592)
			(xy 380.144915 -393.992298) (xy 380.109013 -393.944962) (xy 380.079537 -393.893379) (xy 380.056982 -393.838415)
			(xy 380.041728 -393.780996) (xy 380.034031 -393.722085) (xy 380.03353 -393.69238) (xy 380.03353 -393.679934)
			(xy 380.034811 -393.650621) (xy 380.043918 -393.592658) (xy 380.060359 -393.536335) (xy 380.083864 -393.482574)
			(xy 380.098554 -393.457176) (xy 380.098554 -393.456668) (xy 380.098808 -393.456414) (xy 380.101473 -393.451704)
			(xy 380.104935 -393.441455) (xy 380.105666 -393.436094) (xy 380.106682 -393.425172) (xy 380.077218 -393.34059)
			(xy 380.073038 -393.330313) (xy 380.057629 -393.314385) (xy 380.0475 -393.309856) (xy 380.045214 -393.30884)
			(xy 380.041404 -393.30757) (xy 380.039626 -393.306808) (xy 380.039372 -393.306808) (xy 380.037594 -393.306046)
			(xy 380.015076 -393.296405) (xy 379.972927 -393.271453) (xy 379.934919 -393.240556) (xy 379.901886 -393.204389)
			(xy 379.874551 -393.163745) (xy 379.853511 -393.119513) (xy 379.839227 -393.07266) (xy 379.832012 -393.024213)
			(xy 379.8316 -392.999722) (xy 379.83211 -392.973735) (xy 379.84024 -392.9224) (xy 379.856301 -392.87297)
			(xy 379.879897 -392.82666) (xy 379.910447 -392.784612) (xy 379.947198 -392.747861) (xy 379.989246 -392.717311)
			(xy 380.035556 -392.693715) (xy 380.084986 -392.677654) (xy 380.136321 -392.669524) (xy 380.188295 -392.669524)
			(xy 380.23963 -392.677654) (xy 380.28906 -392.693715) (xy 380.33537 -392.717311) (xy 380.377418 -392.747861)
			(xy 380.414169 -392.784612) (xy 380.444719 -392.82666) (xy 380.468315 -392.87297) (xy 380.484376 -392.9224)
			(xy 380.492506 -392.973735) (xy 380.493016 -392.999722) (xy 380.493016 -393.000484) (xy 380.492528 -393.026518)
			(xy 380.484357 -393.07794) (xy 380.47676 -393.102846) (xy 380.47549 -393.106656) (xy 380.473966 -393.11453)
			(xy 380.473271 -393.119145) (xy 380.473403 -393.128477) (xy 380.47422 -393.133072) (xy 380.475998 -393.142216)
			(xy 380.480824 -393.15009) (xy 380.520194 -393.215114) (xy 380.520702 -393.21613) (xy 380.52883 -393.225782)
			(xy 380.531902 -393.228564) (xy 380.538796 -393.233161) (xy 380.542546 -393.234926) (xy 380.550166 -393.238482)
			(xy 380.553468 -393.23899) (xy 380.557278 -393.239498) (xy 380.586221 -393.244197) (xy 380.642685 -393.260009)
			(xy 380.696669 -393.2829) (xy 380.747289 -393.312495) (xy 380.793717 -393.348309) (xy 380.835193 -393.389758)
			(xy 380.871038 -393.436162) (xy 380.900666 -393.486763) (xy 380.923592 -393.540732) (xy 380.93944 -393.597185)
			(xy 380.947953 -393.655201) (xy 380.948946 -393.684506) (xy 380.948946 -393.692634) (xy 380.948496 -393.721986)
			(xy 380.940978 -393.780207) (xy 380.93396 -393.808712) (xy 380.933452 -393.81049) (xy 380.933452 -393.810998)
			(xy 380.932182 -393.815062) (xy 380.93142 -393.817348) (xy 380.929714 -393.826563) (xy 380.932455 -393.845089)
			(xy 380.936754 -393.853416) (xy 380.937008 -393.853924) (xy 380.969012 -393.909296) (xy 380.971629 -393.913597)
			(xy 380.978276 -393.921154) (xy 380.98222 -393.924282) (xy 381.005334 -393.941808) (xy 381.014732 -393.944602)
			(xy 381.043208 -393.953073) (xy 381.09786 -393.976371) (xy 381.149039 -394.006544) (xy 381.195884 -394.043084)
			(xy 381.237609 -394.085377) (xy 381.273511 -394.132713) (xy 381.302989 -394.184296) (xy 381.325545 -394.239258)
			(xy 381.340801 -394.296677) (xy 381.348501 -394.355587) (xy 381.348996 -394.385292) (xy 381.348889 -394.399554)
			(xy 381.347113 -394.428024) (xy 381.34544 -394.442188) (xy 381.34417 -394.451586) (xy 381.346202 -394.459968)
			(xy 381.347289 -394.464059) (xy 381.350611 -394.471843) (xy 381.352806 -394.475462) (xy 381.36449 -394.493496)
			(xy 381.37084 -394.501624) (xy 381.374904 -394.505434) (xy 381.3937 -394.520928) (xy 381.398272 -394.522706)
			(xy 381.40132 -394.523976) (xy 381.424002 -394.53354) (xy 381.466487 -394.558403) (xy 381.504815 -394.58929)
			(xy 381.538139 -394.625519) (xy 381.565723 -394.666289) (xy 381.586956 -394.710699) (xy 381.60137 -394.757766)
			(xy 381.608645 -394.806449) (xy 381.609092 -394.831062) (xy 381.608659 -394.85518) (xy 381.601663 -394.902904)
			(xy 381.587814 -394.949109) (xy 381.567405 -394.992813) (xy 381.554482 -395.01318) (xy 381.550418 -395.01953)
			(xy 381.5461 -395.0335) (xy 381.5461 -395.045438) (xy 381.546608 -395.05255) (xy 381.549148 -395.07033)
			(xy 381.550418 -395.080236) (xy 381.568452 -395.111732) (xy 381.57531 -395.117574) (xy 381.596568 -395.136255)
			(xy 381.634776 -395.178002) (xy 381.667547 -395.224142) (xy 381.69438 -395.273969) (xy 381.714867 -395.326724)
			(xy 381.728693 -395.381602) (xy 381.73565 -395.437765) (xy 381.736092 -395.466062) (xy 381.736092 -395.46657)
			(xy 381.735521 -395.498823) (xy 381.726421 -395.562686) (xy 381.708441 -395.624637) (xy 381.695706 -395.654276)
			(xy 381.693674 -395.658594) (xy 381.690962 -395.668039) (xy 381.692151 -395.687634) (xy 381.69596 -395.696694)
			(xy 381.70231 -395.71041) (xy 381.705612 -395.714728) (xy 381.715264 -395.727428) (xy 381.71882 -395.730476)
			(xy 381.743064 -395.75235) (xy 381.785723 -395.801784) (xy 381.820929 -395.856776) (xy 381.847967 -395.91621)
			(xy 381.86629 -395.978882) (xy 381.875526 -396.043522) (xy 381.876046 -396.07617) (xy 381.876046 -396.085822)
			(xy 381.874512 -396.122796) (xy 381.860977 -396.195546) (xy 381.849122 -396.230602) (xy 381.837527 -396.261158)
			(xy 381.806927 -396.318906) (xy 381.788162 -396.345664) (xy 381.78359 -396.352014) (xy 381.77724 -396.370048)
			(xy 381.774805 -396.379059) (xy 381.775863 -396.397679) (xy 381.779272 -396.40637) (xy 381.780034 -396.408148)
			(xy 381.82042 -396.488666) (xy 381.824976 -396.495983) (xy 381.83798 -396.507279) (xy 381.853992 -396.513627)
			(xy 381.862584 -396.51432) (xy 382.17221 -396.51432) (xy 382.174242 -396.51432) (xy 382.182835 -396.513638)
			(xy 382.198846 -396.507283) (xy 382.211847 -396.495982) (xy 382.216406 -396.488666) (xy 382.256792 -396.408148)
			(xy 382.257554 -396.40637) (xy 382.260983 -396.397688) (xy 382.262009 -396.379065) (xy 382.259586 -396.370048)
			(xy 382.253236 -396.352014) (xy 382.248664 -396.345664) (xy 382.232166 -396.322297) (xy 382.20448 -396.272241)
			(xy 382.183252 -396.219123) (xy 382.168813 -396.163773) (xy 382.161388 -396.107054) (xy 382.16078 -396.078456)
			(xy 382.16078 -396.065248) (xy 382.161963 -396.034661) (xy 382.171501 -395.974197) (xy 382.189021 -395.915546)
			(xy 382.201166 -395.887448) (xy 382.203198 -395.88313) (xy 382.205916 -395.873685) (xy 382.204735 -395.854085)
			(xy 382.200912 -395.84503) (xy 382.194562 -395.831314) (xy 382.19126 -395.826996) (xy 382.181608 -395.814296)
			(xy 382.178052 -395.811248) (xy 382.153827 -395.789415) (xy 382.111195 -395.740065) (xy 382.076008 -395.685159)
			(xy 382.048978 -395.625811) (xy 382.030654 -395.563224) (xy 382.021409 -395.498669) (xy 382.020826 -395.466062)
			(xy 382.021249 -395.437766) (xy 382.028224 -395.381605) (xy 382.042062 -395.326731) (xy 382.062553 -395.273978)
			(xy 382.089385 -395.224151) (xy 382.12215 -395.178008) (xy 382.160348 -395.136252) (xy 382.181608 -395.117574)
			(xy 382.188466 -395.111732) (xy 382.2065 -395.080236) (xy 382.20777 -395.07033) (xy 382.210818 -395.04874)
			(xy 382.210818 -395.048486) (xy 382.212088 -395.039088) (xy 382.208024 -395.021562) (xy 382.207008 -395.019784)
			(xy 382.202944 -395.013688) (xy 382.189178 -394.992131) (xy 382.16774 -394.945695) (xy 382.160272 -394.921232)
			(xy 382.155446 -394.902182) (xy 382.155446 -394.901928) (xy 382.153414 -394.893292) (xy 382.14935 -394.886434)
			(xy 382.146987 -394.88279) (xy 382.141242 -394.876277) (xy 382.13792 -394.87348) (xy 382.12141 -394.860018)
			(xy 382.114552 -394.854176) (xy 382.083818 -394.843) (xy 382.07569 -394.842746) (xy 382.046402 -394.841285)
			(xy 381.988527 -394.831828) (xy 381.932334 -394.815056) (xy 381.878744 -394.791245) (xy 381.828634 -394.760784)
			(xy 381.782825 -394.724172) (xy 381.742068 -394.682008) (xy 381.70703 -394.634985) (xy 381.678285 -394.583871)
			(xy 381.656305 -394.529504) (xy 381.641448 -394.472775) (xy 381.633959 -394.414613) (xy 381.633476 -394.385292)
			(xy 381.633476 -394.385038) (xy 381.633476 -394.384022) (xy 381.633944 -394.355522) (xy 381.641077 -394.29897)
			(xy 381.6477 -394.271246) (xy 381.648462 -394.268452) (xy 381.65024 -394.255752) (xy 381.65024 -394.245846)
			(xy 381.65002 -394.239243) (xy 381.646548 -394.226499) (xy 381.643382 -394.2207) (xy 381.61341 -394.168376)
			(xy 381.610789 -394.16408) (xy 381.604132 -394.156533) (xy 381.600202 -394.15339) (xy 381.577088 -394.135864)
			(xy 381.56769 -394.13307) (xy 381.539603 -394.124713) (xy 381.485656 -394.101827) (xy 381.435069 -394.072247)
			(xy 381.388669 -394.036455) (xy 381.347214 -393.995037) (xy 381.311381 -393.948669) (xy 381.281755 -393.898108)
			(xy 381.258822 -393.844181) (xy 381.242955 -393.78777) (xy 381.234414 -393.729795) (xy 381.233426 -393.700508)
			(xy 381.233426 -393.691872) (xy 381.233952 -393.661016) (xy 381.242282 -393.599867) (xy 381.258746 -393.540391)
			(xy 381.283046 -393.483663) (xy 381.29845 -393.456922) (xy 381.29845 -393.456668) (xy 381.298704 -393.456414)
			(xy 381.303558 -393.447087) (xy 381.306064 -393.426231) (xy 381.30353 -393.416028) (xy 381.294386 -393.389612)
			(xy 381.277368 -393.340844) (xy 381.27559 -393.336526) (xy 381.271667 -393.328778) (xy 381.259582 -393.316322)
			(xy 381.251968 -393.312142) (xy 381.24765 -393.31011) (xy 381.245364 -393.309094) (xy 381.222153 -393.299794)
			(xy 381.178607 -393.275221) (xy 381.13925 -393.244381) (xy 381.104976 -393.207975) (xy 381.076566 -393.166829)
			(xy 381.054664 -393.121881) (xy 381.039769 -393.07415) (xy 381.032219 -393.024722) (xy 381.03175 -392.999722)
			(xy 381.03226 -392.973735) (xy 381.04039 -392.9224) (xy 381.056451 -392.87297) (xy 381.080047 -392.82666)
			(xy 381.110597 -392.784612) (xy 381.147348 -392.747861) (xy 381.189396 -392.717311) (xy 381.235706 -392.693715)
			(xy 381.285136 -392.677654) (xy 381.336471 -392.669524) (xy 381.388445 -392.669524) (xy 381.43978 -392.677654)
			(xy 381.48921 -392.693715) (xy 381.53552 -392.717311) (xy 381.577568 -392.747861) (xy 381.614319 -392.784612)
			(xy 381.644869 -392.82666) (xy 381.668465 -392.87297) (xy 381.684526 -392.9224) (xy 381.692656 -392.973735)
			(xy 381.693166 -392.999722) (xy 381.693166 -393.00023) (xy 381.692564 -393.027278) (xy 381.683627 -393.080633)
			(xy 381.675386 -393.106402) (xy 381.67183 -393.11707) (xy 381.672846 -393.127738) (xy 381.673567 -393.133457)
			(xy 381.677278 -393.144367) (xy 381.680212 -393.149328) (xy 381.700532 -393.182348) (xy 381.721106 -393.215876)
			(xy 381.724109 -393.220575) (xy 381.731801 -393.228646) (xy 381.736346 -393.231878) (xy 381.74549 -393.23772)
			(xy 381.754888 -393.239244) (xy 381.757174 -393.239498) (xy 381.784553 -393.243907) (xy 381.83806 -393.258489)
			(xy 381.889416 -393.279421) (xy 381.93787 -393.306398) (xy 381.982716 -393.339024) (xy 382.0033 -393.357608)
			(xy 382.025376 -393.378872) (xy 382.064219 -393.426287) (xy 382.096391 -393.478459) (xy 382.121317 -393.534456)
			(xy 382.138551 -393.593278) (xy 382.147786 -393.653873) (xy 382.148842 -393.684506) (xy 382.148842 -393.692634)
			(xy 382.148392 -393.721986) (xy 382.140874 -393.780207) (xy 382.133856 -393.808712) (xy 382.133348 -393.81049)
			(xy 382.133348 -393.810998) (xy 382.132078 -393.815062) (xy 382.131316 -393.817348) (xy 382.12961 -393.826563)
			(xy 382.132351 -393.845089) (xy 382.13665 -393.853416) (xy 382.136904 -393.853924) (xy 382.168908 -393.909296)
			(xy 382.171524 -393.913597) (xy 382.178171 -393.921155) (xy 382.182116 -393.924282) (xy 382.20523 -393.941808)
			(xy 382.214628 -393.944602) (xy 382.243104 -393.953073) (xy 382.297757 -393.976371) (xy 382.348936 -394.006543)
			(xy 382.395782 -394.043083) (xy 382.437507 -394.085376) (xy 382.47341 -394.132712) (xy 382.502887 -394.184295)
			(xy 382.525443 -394.239257) (xy 382.5407 -394.296676) (xy 382.5484 -394.355587) (xy 382.548892 -394.385292)
			(xy 382.548778 -394.399491) (xy 382.546999 -394.427833) (xy 382.545336 -394.441934) (xy 382.544896 -394.446456)
			(xy 382.545401 -394.455526) (xy 382.546352 -394.459968) (xy 382.54813 -394.467842) (xy 382.552702 -394.475208)
			(xy 382.568196 -394.5001) (xy 382.572903 -394.507161) (xy 382.586014 -394.517921) (xy 382.59385 -394.521182)
			(xy 382.61722 -394.530382) (xy 382.661095 -394.554822) (xy 382.700772 -394.585613) (xy 382.735338 -394.622047)
			(xy 382.764001 -394.663288) (xy 382.7861 -394.708387) (xy 382.801128 -394.756308) (xy 382.80874 -394.805951)
			(xy 382.809242 -394.831062) (xy 382.808809 -394.85518) (xy 382.801814 -394.902905) (xy 382.787967 -394.94911)
			(xy 382.767561 -394.992817) (xy 382.754632 -395.01318) (xy 382.750568 -395.01953) (xy 382.74625 -395.0335)
			(xy 382.74625 -395.045438) (xy 382.746758 -395.05255) (xy 382.749298 -395.07033) (xy 382.750568 -395.080236)
			(xy 382.768602 -395.111732) (xy 382.77546 -395.117574) (xy 382.796716 -395.136256) (xy 382.83492 -395.178005)
			(xy 382.867688 -395.224145) (xy 382.894518 -395.273973) (xy 382.915002 -395.326727) (xy 382.928827 -395.381604)
			(xy 382.935782 -395.437766) (xy 382.936242 -395.466062) (xy 382.936242 -395.46657) (xy 382.93567 -395.498823)
			(xy 382.92657 -395.562686) (xy 382.908588 -395.624636) (xy 382.895856 -395.654276) (xy 382.893824 -395.658594)
			(xy 382.89111 -395.668038) (xy 382.8923 -395.687634) (xy 382.89611 -395.696694) (xy 382.90246 -395.71041)
			(xy 382.905762 -395.714728) (xy 382.915414 -395.727428) (xy 382.91897 -395.730476) (xy 382.943212 -395.752351)
			(xy 382.985866 -395.801787) (xy 383.021068 -395.856779) (xy 383.048103 -395.916213) (xy 383.066424 -395.978885)
			(xy 383.075658 -396.043523) (xy 383.076196 -396.07617) (xy 383.076196 -396.085822) (xy 383.074663 -396.122796)
			(xy 383.061129 -396.195547) (xy 383.049272 -396.230602) (xy 383.037676 -396.261157) (xy 383.007073 -396.318903)
			(xy 382.988312 -396.345664) (xy 382.98374 -396.352014) (xy 382.97739 -396.370048) (xy 382.974956 -396.379059)
			(xy 382.976013 -396.397679) (xy 382.979422 -396.40637) (xy 382.980184 -396.408148) (xy 383.02057 -396.488666)
			(xy 383.025128 -396.495978) (xy 383.038134 -396.507261) (xy 383.054146 -396.513594) (xy 383.062734 -396.51432)
			(xy 383.372106 -396.51432) (xy 383.374138 -396.51432) (xy 383.382731 -396.513639) (xy 383.398743 -396.507284)
			(xy 383.411745 -396.495983) (xy 383.416302 -396.488666) (xy 383.456688 -396.408148) (xy 383.45745 -396.40637)
			(xy 383.460879 -396.397688) (xy 383.461905 -396.379065) (xy 383.459482 -396.370048) (xy 383.453132 -396.352014)
			(xy 383.44856 -396.345664) (xy 383.432062 -396.322297) (xy 383.404376 -396.27224) (xy 383.383149 -396.219123)
			(xy 383.36871 -396.163773) (xy 383.361285 -396.107054) (xy 383.360676 -396.078456) (xy 383.360676 -396.065248)
			(xy 383.361859 -396.034661) (xy 383.371399 -395.974198) (xy 383.388923 -395.915548) (xy 383.401062 -395.887448)
			(xy 383.403094 -395.88313) (xy 383.405812 -395.873685) (xy 383.404631 -395.854085) (xy 383.400808 -395.84503)
			(xy 383.394458 -395.831314) (xy 383.391156 -395.826996) (xy 383.381504 -395.814296) (xy 383.377948 -395.811248)
			(xy 383.353723 -395.789415) (xy 383.311092 -395.740065) (xy 383.275905 -395.685159) (xy 383.248875 -395.625811)
			(xy 383.230552 -395.563224) (xy 383.221306 -395.498669) (xy 383.220722 -395.466062) (xy 383.221145 -395.437766)
			(xy 383.22812 -395.381605) (xy 383.241958 -395.32673) (xy 383.262449 -395.273978) (xy 383.289281 -395.224151)
			(xy 383.322045 -395.178008) (xy 383.360243 -395.136251) (xy 383.381504 -395.117574) (xy 383.388362 -395.111732)
			(xy 383.406396 -395.080236) (xy 383.407666 -395.07033) (xy 383.410714 -395.04874) (xy 383.410714 -395.048486)
			(xy 383.411984 -395.039088) (xy 383.40792 -395.021562) (xy 383.406904 -395.019784) (xy 383.40284 -395.013688)
			(xy 383.389074 -394.992131) (xy 383.367637 -394.945695) (xy 383.360168 -394.921232) (xy 383.355342 -394.901928)
			(xy 383.353564 -394.893546) (xy 383.349246 -394.886434) (xy 383.346898 -394.882723) (xy 383.341157 -394.876077)
			(xy 383.337816 -394.873226) (xy 383.321306 -394.859764) (xy 383.314194 -394.854176) (xy 383.283968 -394.843)
			(xy 383.275586 -394.842746) (xy 383.246306 -394.841272) (xy 383.188452 -394.831795) (xy 383.13228 -394.815007)
			(xy 383.078713 -394.791184) (xy 383.028626 -394.760716) (xy 382.982839 -394.724102) (xy 382.942102 -394.681941)
			(xy 382.907083 -394.634924) (xy 382.878353 -394.58382) (xy 382.856385 -394.529466) (xy 382.841536 -394.472751)
			(xy 382.834051 -394.414605) (xy 382.833626 -394.385292) (xy 382.833626 -394.385038) (xy 382.833626 -394.384022)
			(xy 382.834094 -394.355522) (xy 382.841228 -394.29897) (xy 382.84785 -394.271246) (xy 382.848612 -394.268452)
			(xy 382.85039 -394.255752) (xy 382.85039 -394.245846) (xy 382.85017 -394.239243) (xy 382.846695 -394.226501)
			(xy 382.843532 -394.2207) (xy 382.81356 -394.168376) (xy 382.810941 -394.164078) (xy 382.804288 -394.156526)
			(xy 382.800352 -394.15339) (xy 382.777238 -394.135864) (xy 382.76784 -394.13307) (xy 382.739366 -394.124597)
			(xy 382.684719 -394.101296) (xy 382.633545 -394.071121) (xy 382.586704 -394.03458) (xy 382.544985 -393.992286)
			(xy 382.509088 -393.944951) (xy 382.479616 -393.893369) (xy 382.457064 -393.838408) (xy 382.441812 -393.780991)
			(xy 382.434117 -393.722084) (xy 382.433576 -393.69238) (xy 382.433576 -393.679934) (xy 382.434857 -393.650621)
			(xy 382.443965 -393.592659) (xy 382.460407 -393.536336) (xy 382.483914 -393.482577) (xy 382.4986 -393.457176)
			(xy 382.4986 -393.456668) (xy 382.498854 -393.456414) (xy 382.501521 -393.451705) (xy 382.504987 -393.441456)
			(xy 382.505712 -393.436094) (xy 382.506728 -393.425172) (xy 382.477264 -393.34059) (xy 382.473087 -393.330309)
			(xy 382.457683 -393.314369) (xy 382.447546 -393.309856) (xy 382.44526 -393.30884) (xy 382.44145 -393.30757)
			(xy 382.439672 -393.306808) (xy 382.439418 -393.306808) (xy 382.43764 -393.306046) (xy 382.415125 -393.296402)
			(xy 382.372982 -393.271447) (xy 382.33498 -393.240547) (xy 382.301953 -393.20438) (xy 382.274622 -393.163736)
			(xy 382.253586 -393.119505) (xy 382.239305 -393.072655) (xy 382.232092 -393.024211) (xy 382.231646 -392.999722)
			(xy 382.232156 -392.973735) (xy 382.240286 -392.9224) (xy 382.256347 -392.87297) (xy 382.279943 -392.82666)
			(xy 382.310493 -392.784612) (xy 382.347244 -392.747861) (xy 382.389292 -392.717311) (xy 382.435602 -392.693715)
			(xy 382.485032 -392.677654) (xy 382.536367 -392.669524) (xy 382.588341 -392.669524) (xy 382.639676 -392.677654)
			(xy 382.689106 -392.693715) (xy 382.735416 -392.717311) (xy 382.777464 -392.747861) (xy 382.814215 -392.784612)
			(xy 382.844765 -392.82666) (xy 382.868361 -392.87297) (xy 382.884422 -392.9224) (xy 382.892552 -392.973735)
			(xy 382.893062 -392.999722) (xy 382.893062 -393.000484) (xy 382.892574 -393.026518) (xy 382.884404 -393.077941)
			(xy 382.876806 -393.102846) (xy 382.875536 -393.106656) (xy 382.874012 -393.11453) (xy 382.873317 -393.119145)
			(xy 382.873449 -393.128477) (xy 382.874266 -393.133072) (xy 382.876044 -393.142216) (xy 382.88087 -393.15009)
			(xy 382.92024 -393.215114) (xy 382.920748 -393.21613) (xy 382.928876 -393.225782) (xy 382.93195 -393.228561)
			(xy 382.938846 -393.233153) (xy 382.942592 -393.234926) (xy 382.950212 -393.238482) (xy 382.957324 -393.239498)
			(xy 382.986269 -393.244194) (xy 383.042739 -393.260001) (xy 383.096728 -393.282888) (xy 383.147354 -393.31248)
			(xy 383.193788 -393.348294) (xy 383.235269 -393.389743) (xy 383.271119 -393.436148) (xy 383.300751 -393.48675)
			(xy 383.32368 -393.540722) (xy 383.339531 -393.597179) (xy 383.348045 -393.655198) (xy 383.348992 -393.684506)
			(xy 383.348992 -393.692634) (xy 383.348542 -393.721986) (xy 383.341023 -393.780207) (xy 383.334006 -393.808712)
			(xy 383.333498 -393.81049) (xy 383.333498 -393.810998) (xy 383.332228 -393.815062) (xy 383.331466 -393.817348)
			(xy 383.329819 -393.826565) (xy 383.332554 -393.845071) (xy 383.3368 -393.853416) (xy 383.337054 -393.853924)
			(xy 383.369058 -393.909296) (xy 383.371676 -393.913595) (xy 383.378327 -393.921148) (xy 383.382266 -393.924282)
			(xy 383.40538 -393.941808) (xy 383.414778 -393.944602) (xy 383.443256 -393.953071) (xy 383.497914 -393.976364)
			(xy 383.549098 -394.006534) (xy 383.595949 -394.043072) (xy 383.637679 -394.085365) (xy 383.673586 -394.132701)
			(xy 383.703067 -394.184286) (xy 383.725627 -394.23925) (xy 383.740885 -394.296672) (xy 383.748586 -394.355585)
			(xy 383.749042 -394.385292) (xy 383.748935 -394.399554) (xy 383.747158 -394.428024) (xy 383.745486 -394.442188)
			(xy 383.744216 -394.451586) (xy 383.746248 -394.459968) (xy 383.747336 -394.464058) (xy 383.750661 -394.471841)
			(xy 383.752852 -394.475462) (xy 383.764536 -394.493496) (xy 383.770886 -394.501624) (xy 383.77495 -394.505434)
			(xy 383.793746 -394.520928) (xy 383.798318 -394.522706) (xy 383.801366 -394.523976) (xy 383.824051 -394.533538)
			(xy 383.866542 -394.558396) (xy 383.904876 -394.589281) (xy 383.938206 -394.625509) (xy 383.965795 -394.66628)
			(xy 383.987032 -394.710691) (xy 384.001448 -394.757761) (xy 384.008725 -394.806448) (xy 384.009138 -394.831062)
			(xy 384.008705 -394.85518) (xy 384.00171 -394.902905) (xy 383.987863 -394.94911) (xy 383.967456 -394.992816)
			(xy 383.954528 -395.01318) (xy 383.950464 -395.01953) (xy 383.946146 -395.0335) (xy 383.946146 -395.045438)
			(xy 383.946654 -395.05255) (xy 383.949194 -395.07033) (xy 383.950464 -395.080236) (xy 383.968498 -395.111732)
			(xy 383.975356 -395.117574) (xy 383.996612 -395.136256) (xy 384.034817 -395.178005) (xy 384.067584 -395.224145)
			(xy 384.094415 -395.273972) (xy 384.114899 -395.326727) (xy 384.128724 -395.381603) (xy 384.13568 -395.437766)
			(xy 384.136138 -395.466062) (xy 384.136138 -395.46657) (xy 384.135566 -395.498823) (xy 384.126466 -395.562686)
			(xy 384.108484 -395.624636) (xy 384.095752 -395.654276) (xy 384.09372 -395.658594) (xy 384.091007 -395.668039)
			(xy 384.092197 -395.687634) (xy 384.096006 -395.696694) (xy 384.102356 -395.71041) (xy 384.105658 -395.714728)
			(xy 384.11531 -395.727428) (xy 384.118866 -395.730476) (xy 384.143108 -395.752351) (xy 384.185763 -395.801787)
			(xy 384.220965 -395.856779) (xy 384.248 -395.916213) (xy 384.266321 -395.978885) (xy 384.275556 -396.043523)
			(xy 384.276092 -396.07617) (xy 384.276092 -396.085822) (xy 384.274559 -396.122796) (xy 384.261025 -396.195547)
			(xy 384.249168 -396.230602) (xy 384.237571 -396.261157) (xy 384.206969 -396.318903) (xy 384.188208 -396.345664)
			(xy 384.183636 -396.352014) (xy 384.177286 -396.370048) (xy 384.174852 -396.379059) (xy 384.17591 -396.397679)
			(xy 384.179318 -396.40637) (xy 384.18008 -396.408148) (xy 384.220466 -396.488666) (xy 384.225024 -396.495978)
			(xy 384.23803 -396.507262) (xy 384.254042 -396.513596) (xy 384.26263 -396.51432) (xy 384.572256 -396.51432)
			(xy 384.574288 -396.51432) (xy 384.582877 -396.513631) (xy 384.598876 -396.507266) (xy 384.611865 -396.495962)
			(xy 384.616452 -396.488666) (xy 384.656838 -396.408148) (xy 384.6576 -396.40637) (xy 384.661032 -396.397688)
			(xy 384.662059 -396.379064) (xy 384.659632 -396.370048) (xy 384.653282 -396.352014) (xy 384.64871 -396.345664)
			(xy 384.63221 -396.322297) (xy 384.604522 -396.272242) (xy 384.583292 -396.219124) (xy 384.568851 -396.163774)
			(xy 384.561425 -396.107055) (xy 384.560826 -396.078456) (xy 384.560826 -396.065248) (xy 384.562009 -396.034661)
			(xy 384.571548 -395.974197) (xy 384.58907 -395.915547) (xy 384.601212 -395.887448) (xy 384.603244 -395.88313)
			(xy 384.60596 -395.873685) (xy 384.60478 -395.854085) (xy 384.600958 -395.84503) (xy 384.594608 -395.831314)
			(xy 384.591306 -395.826996) (xy 384.581654 -395.814296) (xy 384.578098 -395.811248) (xy 384.553875 -395.789414)
			(xy 384.511248 -395.740062) (xy 384.476065 -395.685155) (xy 384.449039 -395.625807) (xy 384.430718 -395.563222)
			(xy 384.421473 -395.498668) (xy 384.420872 -395.466062) (xy 384.421295 -395.437766) (xy 384.42827 -395.381606)
			(xy 384.44211 -395.326733) (xy 384.462602 -395.273982) (xy 384.489436 -395.224156) (xy 384.522203 -395.178016)
			(xy 384.560404 -395.136262) (xy 384.581654 -395.117574) (xy 384.588512 -395.111732) (xy 384.606546 -395.080236)
			(xy 384.607816 -395.07033) (xy 384.610864 -395.04874) (xy 384.610864 -395.048486) (xy 384.612134 -395.039088)
			(xy 384.60807 -395.021562) (xy 384.607054 -395.019784) (xy 384.60299 -395.013688) (xy 384.589222 -394.992132)
			(xy 384.567782 -394.945696) (xy 384.560318 -394.921232) (xy 384.555492 -394.902182) (xy 384.555492 -394.901928)
			(xy 384.55346 -394.893292) (xy 384.549396 -394.886434) (xy 384.547035 -394.882788) (xy 384.541293 -394.876272)
			(xy 384.537966 -394.87348) (xy 384.521456 -394.860018) (xy 384.514598 -394.854176) (xy 384.483864 -394.843)
			(xy 384.475736 -394.842746) (xy 384.446446 -394.841287) (xy 384.388567 -394.831835) (xy 384.332369 -394.815068)
			(xy 384.278774 -394.791259) (xy 384.228659 -394.760799) (xy 384.182845 -394.724187) (xy 384.142083 -394.682023)
			(xy 384.107041 -394.634998) (xy 384.078293 -394.583882) (xy 384.056309 -394.529513) (xy 384.041451 -394.47278)
			(xy 384.03396 -394.414615) (xy 384.033522 -394.385292) (xy 384.033522 -394.385038) (xy 384.033522 -394.384022)
			(xy 384.03399 -394.355522) (xy 384.041124 -394.29897) (xy 384.047746 -394.271246) (xy 384.048508 -394.268452)
			(xy 384.050286 -394.255752) (xy 384.050286 -394.245846) (xy 384.050066 -394.239243) (xy 384.04659 -394.226501)
			(xy 384.043428 -394.2207) (xy 384.013456 -394.168376) (xy 384.010836 -394.164078) (xy 384.004184 -394.156527)
			(xy 384.000248 -394.15339) (xy 383.977134 -394.135864) (xy 383.967736 -394.13307) (xy 383.939262 -394.124597)
			(xy 383.884615 -394.101296) (xy 383.833442 -394.071121) (xy 383.786602 -394.034579) (xy 383.744883 -393.992285)
			(xy 383.708986 -393.94495) (xy 383.679514 -393.893368) (xy 383.656963 -393.838407) (xy 383.641711 -393.780991)
			(xy 383.634016 -393.722084) (xy 383.633472 -393.69238) (xy 383.633472 -393.679934) (xy 383.634753 -393.650621)
			(xy 383.643861 -393.592659) (xy 383.660303 -393.536336) (xy 383.68381 -393.482577) (xy 383.698496 -393.457176)
			(xy 383.698496 -393.456668) (xy 383.69875 -393.456414) (xy 383.701417 -393.451705) (xy 383.704884 -393.441457)
			(xy 383.705608 -393.436094) (xy 383.706624 -393.425172) (xy 383.67716 -393.34059) (xy 383.672983 -393.330309)
			(xy 383.657578 -393.31437) (xy 383.647442 -393.309856) (xy 383.645156 -393.30884) (xy 383.641346 -393.30757)
			(xy 383.639568 -393.306808) (xy 383.639314 -393.306808) (xy 383.637536 -393.306046) (xy 383.615021 -393.296402)
			(xy 383.572878 -393.271446) (xy 383.534877 -393.240547) (xy 383.501851 -393.204379) (xy 383.47452 -393.163736)
			(xy 383.453485 -393.119505) (xy 383.439204 -393.072655) (xy 383.43199 -393.024211) (xy 383.431542 -392.999722)
			(xy 383.432052 -392.973735) (xy 383.440182 -392.9224) (xy 383.456243 -392.87297) (xy 383.479839 -392.82666)
			(xy 383.510389 -392.784612) (xy 383.54714 -392.747861) (xy 383.589188 -392.717311) (xy 383.635498 -392.693715)
			(xy 383.684928 -392.677654) (xy 383.736263 -392.669524) (xy 383.788237 -392.669524) (xy 383.839572 -392.677654)
			(xy 383.889002 -392.693715) (xy 383.935312 -392.717311) (xy 383.97736 -392.747861) (xy 384.014111 -392.784612)
			(xy 384.044661 -392.82666) (xy 384.068257 -392.87297) (xy 384.084318 -392.9224) (xy 384.092448 -392.973735)
			(xy 384.092958 -392.999722) (xy 384.092958 -393.000484) (xy 384.09247 -393.026518) (xy 384.0843 -393.077941)
			(xy 384.076702 -393.102846) (xy 384.075432 -393.106656) (xy 384.073908 -393.11453) (xy 384.073213 -393.119145)
			(xy 384.073345 -393.128477) (xy 384.074162 -393.133072) (xy 384.07594 -393.142216) (xy 384.080766 -393.15009)
			(xy 384.120136 -393.215114) (xy 384.120644 -393.21613) (xy 384.128772 -393.225782) (xy 384.131845 -393.228561)
			(xy 384.138742 -393.233154) (xy 384.142488 -393.234926) (xy 384.150108 -393.238482) (xy 384.15722 -393.239498)
			(xy 384.186165 -393.244194) (xy 384.242636 -393.260001) (xy 384.296625 -393.282887) (xy 384.347252 -393.312479)
			(xy 384.393685 -393.348293) (xy 384.435167 -393.389741) (xy 384.471017 -393.436147) (xy 384.50065 -393.48675)
			(xy 384.523579 -393.540721) (xy 384.53943 -393.597179) (xy 384.547944 -393.655198) (xy 384.548888 -393.684506)
			(xy 384.548888 -393.692634) (xy 384.548438 -393.721986) (xy 384.540919 -393.780207) (xy 384.533902 -393.808712)
			(xy 384.533394 -393.81049) (xy 384.533394 -393.810998) (xy 384.532124 -393.815062) (xy 384.531362 -393.817348)
			(xy 384.529715 -393.826565) (xy 384.53245 -393.845071) (xy 384.536696 -393.853416) (xy 384.53695 -393.853924)
			(xy 384.568954 -393.909296) (xy 384.571572 -393.913595) (xy 384.578223 -393.921149) (xy 384.582162 -393.924282)
			(xy 384.605276 -393.941808) (xy 384.614674 -393.944602) (xy 384.643153 -393.95307) (xy 384.697811 -393.976364)
			(xy 384.748995 -394.006533) (xy 384.795847 -394.043071) (xy 384.837577 -394.085364) (xy 384.873485 -394.132701)
			(xy 384.902966 -394.184285) (xy 384.925525 -394.23925) (xy 384.940784 -394.296672) (xy 384.948485 -394.355585)
			(xy 384.948938 -394.385292) (xy 384.948823 -394.399491) (xy 384.947045 -394.427832) (xy 384.945382 -394.441934)
			(xy 384.944936 -394.446456) (xy 384.945442 -394.455526) (xy 384.946398 -394.459968) (xy 384.948176 -394.467842)
			(xy 384.952748 -394.475208) (xy 384.968242 -394.5001) (xy 384.972946 -394.507166) (xy 384.986052 -394.517939)
			(xy 384.993896 -394.521182) (xy 385.017269 -394.53038) (xy 385.06115 -394.554815) (xy 385.100833 -394.585604)
			(xy 385.135405 -394.622037) (xy 385.164073 -394.663278) (xy 385.186176 -394.708379) (xy 385.201207 -394.756303)
			(xy 385.208821 -394.805949) (xy 385.209288 -394.831062) (xy 385.208855 -394.85518) (xy 385.201859 -394.902904)
			(xy 385.18801 -394.949108) (xy 385.167601 -394.992813) (xy 385.154678 -395.01318) (xy 385.150614 -395.01953)
			(xy 385.146296 -395.0335) (xy 385.146296 -395.045438) (xy 385.146804 -395.05255) (xy 385.149344 -395.07033)
			(xy 385.150614 -395.080236) (xy 385.168648 -395.111732) (xy 385.175506 -395.117574) (xy 385.196764 -395.136255)
			(xy 385.234973 -395.178002) (xy 385.267744 -395.224141) (xy 385.294577 -395.273969) (xy 385.315064 -395.326723)
			(xy 385.328891 -395.381601) (xy 385.335847 -395.437765) (xy 385.336288 -395.466062) (xy 385.336288 -395.46657)
			(xy 385.335717 -395.498823) (xy 385.326617 -395.562686) (xy 385.308637 -395.624637) (xy 385.295902 -395.654276)
			(xy 385.29387 -395.658594) (xy 385.291158 -395.668039) (xy 385.292347 -395.687634) (xy 385.296156 -395.696694)
			(xy 385.302506 -395.71041) (xy 385.305808 -395.714728) (xy 385.31546 -395.727428) (xy 385.319016 -395.730476)
			(xy 385.34326 -395.752349) (xy 385.38592 -395.801783) (xy 385.421126 -395.856775) (xy 385.448164 -395.91621)
			(xy 385.466487 -395.978882) (xy 385.475723 -396.043522) (xy 385.476242 -396.07617) (xy 385.476242 -396.085822)
			(xy 385.474708 -396.122796) (xy 385.461173 -396.195546) (xy 385.449318 -396.230602) (xy 385.437723 -396.261158)
			(xy 385.407122 -396.318905) (xy 385.388358 -396.345664) (xy 385.383786 -396.352014) (xy 385.377436 -396.370048)
			(xy 385.375001 -396.379059) (xy 385.376059 -396.397679) (xy 385.379468 -396.40637) (xy 385.38023 -396.408148)
			(xy 385.420616 -396.488666) (xy 385.425172 -396.495983) (xy 385.438175 -396.50728) (xy 385.454188 -396.513629)
			(xy 385.46278 -396.51432) (xy 385.772152 -396.51432) (xy 385.774184 -396.51432) (xy 385.782773 -396.513632)
			(xy 385.798774 -396.507268) (xy 385.811764 -396.495964) (xy 385.816348 -396.488666) (xy 385.856734 -396.408148)
			(xy 385.857496 -396.40637) (xy 385.860928 -396.397688) (xy 385.861955 -396.379064) (xy 385.859528 -396.370048)
			(xy 385.853178 -396.352014) (xy 385.848606 -396.345664) (xy 385.832106 -396.322297) (xy 385.804418 -396.272242)
			(xy 385.783188 -396.219124) (xy 385.768748 -396.163774) (xy 385.761322 -396.107055) (xy 385.760722 -396.078456)
			(xy 385.760722 -396.065248) (xy 385.761905 -396.034661) (xy 385.771444 -395.974197) (xy 385.788966 -395.915547)
			(xy 385.801108 -395.887448) (xy 385.80314 -395.88313) (xy 385.805856 -395.873685) (xy 385.804676 -395.854085)
			(xy 385.800854 -395.84503) (xy 385.794504 -395.831314) (xy 385.791202 -395.826996) (xy 385.78155 -395.814296)
			(xy 385.777994 -395.811248) (xy 385.753771 -395.789414) (xy 385.711145 -395.740062) (xy 385.675962 -395.685155)
			(xy 385.648936 -395.625807) (xy 385.630615 -395.563222) (xy 385.62137 -395.498668) (xy 385.620768 -395.466062)
			(xy 385.621191 -395.437766) (xy 385.628166 -395.381606) (xy 385.642005 -395.326732) (xy 385.662498 -395.273981)
			(xy 385.689332 -395.224156) (xy 385.722099 -395.178015) (xy 385.760299 -395.136261) (xy 385.78155 -395.117574)
			(xy 385.788408 -395.111732) (xy 385.806442 -395.080236) (xy 385.807712 -395.07033) (xy 385.81076 -395.04874)
			(xy 385.81076 -395.048486) (xy 385.81203 -395.039088) (xy 385.807966 -395.021562) (xy 385.80695 -395.019784)
			(xy 385.802886 -395.013688) (xy 385.789118 -394.992132) (xy 385.767678 -394.945696) (xy 385.760214 -394.921232)
			(xy 385.755388 -394.902182) (xy 385.755388 -394.901928) (xy 385.753356 -394.893292) (xy 385.749292 -394.886434)
			(xy 385.746931 -394.882788) (xy 385.741189 -394.876273) (xy 385.737862 -394.87348) (xy 385.721352 -394.860018)
			(xy 385.714494 -394.854176) (xy 385.68376 -394.843) (xy 385.675632 -394.842746) (xy 385.646342 -394.841287)
			(xy 385.588463 -394.831835) (xy 385.532266 -394.815067) (xy 385.478671 -394.791258) (xy 385.428557 -394.760798)
			(xy 385.382743 -394.724186) (xy 385.341982 -394.682022) (xy 385.30694 -394.634997) (xy 385.278192 -394.583881)
			(xy 385.256209 -394.529512) (xy 385.24135 -394.47278) (xy 385.23386 -394.414615) (xy 385.233418 -394.385292)
			(xy 385.233418 -394.385038) (xy 385.233418 -394.384022) (xy 385.233886 -394.355522) (xy 385.24102 -394.29897)
			(xy 385.247642 -394.271246) (xy 385.248404 -394.268452) (xy 385.250182 -394.255752) (xy 385.250182 -394.245846)
			(xy 385.249963 -394.239242) (xy 385.246493 -394.226497) (xy 385.243324 -394.2207) (xy 385.213352 -394.168376)
			(xy 385.210732 -394.164078) (xy 385.204079 -394.156527) (xy 385.200144 -394.15339) (xy 385.179316 -394.137642)
			(xy 385.169918 -394.134848) (xy 385.141194 -394.126486) (xy 385.086033 -394.103327) (xy 385.034351 -394.073194)
			(xy 384.987024 -394.036597) (xy 384.944858 -393.994158) (xy 384.908566 -393.946598) (xy 384.878765 -393.894723)
			(xy 384.85596 -393.839415) (xy 384.84054 -393.781611) (xy 384.832765 -393.722293) (xy 384.832352 -393.69238)
			(xy 384.832878 -393.66109) (xy 384.841374 -393.599088) (xy 384.85822 -393.538818) (xy 384.883103 -393.481397)
			(xy 384.8989 -393.454382) (xy 384.901693 -393.449509) (xy 384.905289 -393.43887) (xy 384.906012 -393.4333)
			(xy 384.906774 -393.425172) (xy 384.87731 -393.34059) (xy 384.87313 -393.330314) (xy 384.857719 -393.314388)
			(xy 384.847592 -393.309856) (xy 384.845306 -393.30884) (xy 384.841496 -393.30757) (xy 384.839718 -393.306808)
			(xy 384.839464 -393.306808) (xy 384.837686 -393.306046) (xy 384.815169 -393.296405) (xy 384.77302 -393.271452)
			(xy 384.735014 -393.240555) (xy 384.701982 -393.204388) (xy 384.674647 -393.163744) (xy 384.653607 -393.119512)
			(xy 384.639324 -393.072659) (xy 384.632109 -393.024213) (xy 384.631692 -392.999722) (xy 384.632202 -392.973735)
			(xy 384.640332 -392.9224) (xy 384.656393 -392.87297) (xy 384.679989 -392.82666) (xy 384.710539 -392.784612)
			(xy 384.74729 -392.747861) (xy 384.789338 -392.717311) (xy 384.835648 -392.693715) (xy 384.885078 -392.677654)
			(xy 384.936413 -392.669524) (xy 384.988387 -392.669524) (xy 385.039722 -392.677654) (xy 385.089152 -392.693715)
			(xy 385.135462 -392.717311) (xy 385.17751 -392.747861) (xy 385.214261 -392.784612) (xy 385.244811 -392.82666)
			(xy 385.268407 -392.87297) (xy 385.284468 -392.9224) (xy 385.292598 -392.973735) (xy 385.293108 -392.999722)
			(xy 385.293108 -393.000484) (xy 385.29262 -393.026518) (xy 385.284448 -393.07794) (xy 385.276852 -393.102846)
			(xy 385.275582 -393.106656) (xy 385.274058 -393.11453) (xy 385.273363 -393.119145) (xy 385.273495 -393.128477)
			(xy 385.274312 -393.133072) (xy 385.27609 -393.142216) (xy 385.280916 -393.15009) (xy 385.320032 -393.214352)
			(xy 385.323035 -393.219051) (xy 385.330727 -393.227123) (xy 385.335272 -393.230354) (xy 385.34467 -393.23645)
			(xy 385.3561 -393.237974) (xy 385.385565 -393.242652) (xy 385.443041 -393.258646) (xy 385.497959 -393.281954)
			(xy 385.549394 -393.312182) (xy 385.596478 -393.348821) (xy 385.638417 -393.391253) (xy 385.674504 -393.438761)
			(xy 385.70413 -393.490546) (xy 385.726795 -393.545733) (xy 385.742117 -393.603392) (xy 385.749838 -393.66255)
			(xy 385.750308 -393.69238) (xy 385.749791 -393.723644) (xy 385.741258 -393.785588) (xy 385.73329 -393.815824)
			(xy 385.733036 -393.81684) (xy 385.732274 -393.81938) (xy 385.730496 -393.83335) (xy 385.730496 -393.83589)
			(xy 385.73075 -393.84351) (xy 385.760468 -393.894818) (xy 385.760976 -393.895834) (xy 385.76885 -393.909296)
			(xy 385.771468 -393.913595) (xy 385.778118 -393.921149) (xy 385.782058 -393.924282) (xy 385.805172 -393.941808)
			(xy 385.81457 -393.944602) (xy 385.843044 -393.953075) (xy 385.897692 -393.976376) (xy 385.948867 -394.006551)
			(xy 385.995709 -394.043092) (xy 386.03743 -394.085386) (xy 386.073329 -394.132721) (xy 386.102803 -394.184303)
			(xy 386.125357 -394.239263) (xy 386.140612 -394.29668) (xy 386.148311 -394.355588) (xy 386.148834 -394.385292)
			(xy 386.148719 -394.399491) (xy 386.146941 -394.427832) (xy 386.145278 -394.441934) (xy 386.144832 -394.446456)
			(xy 386.145338 -394.455526) (xy 386.146294 -394.459968) (xy 386.148072 -394.467842) (xy 386.152644 -394.475208)
			(xy 386.168138 -394.5001) (xy 386.172841 -394.507166) (xy 386.185947 -394.51794) (xy 386.193792 -394.521182)
			(xy 386.217165 -394.53038) (xy 386.261047 -394.554815) (xy 386.30073 -394.585603) (xy 386.335303 -394.622036)
			(xy 386.363971 -394.663278) (xy 386.386074 -394.708379) (xy 386.401106 -394.756303) (xy 386.408719 -394.805949)
			(xy 386.409184 -394.831062) (xy 386.408751 -394.855179) (xy 386.401755 -394.902904) (xy 386.387906 -394.949108)
			(xy 386.367497 -394.992813) (xy 386.354574 -395.01318) (xy 386.35051 -395.01953) (xy 386.346192 -395.0335)
			(xy 386.346192 -395.045438) (xy 386.3467 -395.05255) (xy 386.34924 -395.07033) (xy 386.35051 -395.080236)
			(xy 386.368544 -395.111732) (xy 386.375402 -395.117574) (xy 386.39666 -395.136255) (xy 386.434869 -395.178002)
			(xy 386.467641 -395.224141) (xy 386.494474 -395.273968) (xy 386.514961 -395.326723) (xy 386.528788 -395.381601)
			(xy 386.535745 -395.437765) (xy 386.536184 -395.466062) (xy 386.536184 -395.46657) (xy 386.535613 -395.498823)
			(xy 386.526513 -395.562686) (xy 386.508533 -395.624637) (xy 386.495798 -395.654276) (xy 386.493766 -395.658594)
			(xy 386.491054 -395.668039) (xy 386.492243 -395.687634) (xy 386.496052 -395.696694) (xy 386.502402 -395.71041)
			(xy 386.505704 -395.714728) (xy 386.515356 -395.727428) (xy 386.518912 -395.730476) (xy 386.543156 -395.752349)
			(xy 386.585816 -395.801783) (xy 386.621022 -395.856775) (xy 386.648061 -395.91621) (xy 386.666384 -395.978882)
			(xy 386.67562 -396.043522) (xy 386.676138 -396.07617) (xy 386.676138 -396.085822) (xy 386.674604 -396.122796)
			(xy 386.661069 -396.195546) (xy 386.649214 -396.230602) (xy 386.637619 -396.261158) (xy 386.607018 -396.318905)
			(xy 386.588254 -396.345664) (xy 386.583682 -396.352014) (xy 386.577332 -396.370048) (xy 386.574897 -396.379059)
			(xy 386.575955 -396.397679) (xy 386.579364 -396.40637) (xy 386.580126 -396.408148) (xy 386.620512 -396.488666)
			(xy 386.625067 -396.495984) (xy 386.638071 -396.507281) (xy 386.654084 -396.513632) (xy 386.662676 -396.51432)
			(xy 386.972302 -396.51432) (xy 386.974334 -396.51432) (xy 386.982927 -396.513639) (xy 386.99894 -396.507286)
			(xy 387.011944 -396.495985) (xy 387.016498 -396.488666) (xy 387.056884 -396.408148) (xy 387.057646 -396.40637)
			(xy 387.061075 -396.397688) (xy 387.062101 -396.379065) (xy 387.059678 -396.370048) (xy 387.053328 -396.352014)
			(xy 387.048756 -396.345664) (xy 387.032258 -396.322297) (xy 387.004573 -396.27224) (xy 386.983345 -396.219123)
			(xy 386.968906 -396.163773) (xy 386.961482 -396.107054) (xy 386.960872 -396.078456) (xy 386.960872 -396.065248)
			(xy 386.962055 -396.034661) (xy 386.971595 -395.974198) (xy 386.989119 -395.915548) (xy 387.001258 -395.887448)
			(xy 387.00329 -395.88313) (xy 387.006008 -395.873685) (xy 387.004827 -395.854085) (xy 387.001004 -395.84503)
			(xy 386.994654 -395.831314) (xy 386.991352 -395.826996) (xy 386.9817 -395.814296) (xy 386.978144 -395.811248)
			(xy 386.953919 -395.789415) (xy 386.911288 -395.740065) (xy 386.876101 -395.685159) (xy 386.849072 -395.62581)
			(xy 386.830749 -395.563224) (xy 386.821503 -395.498669) (xy 386.820918 -395.466062) (xy 386.821341 -395.437766)
			(xy 386.828316 -395.381605) (xy 386.842154 -395.32673) (xy 386.862645 -395.273978) (xy 386.889477 -395.22415)
			(xy 386.922241 -395.178007) (xy 386.960439 -395.13625) (xy 386.9817 -395.117574) (xy 386.988558 -395.111732)
			(xy 387.006592 -395.080236) (xy 387.007862 -395.07033) (xy 387.01091 -395.04874) (xy 387.01091 -395.048486)
			(xy 387.01218 -395.039088) (xy 387.008116 -395.021562) (xy 387.0071 -395.019784) (xy 387.003036 -395.013688)
			(xy 386.98927 -394.992131) (xy 386.967833 -394.945694) (xy 386.960364 -394.921232) (xy 386.955538 -394.902182)
			(xy 386.955538 -394.901928) (xy 386.953506 -394.893292) (xy 386.949442 -394.886434) (xy 386.947079 -394.88279)
			(xy 386.941333 -394.876279) (xy 386.938012 -394.87348) (xy 386.921502 -394.860018) (xy 386.914644 -394.854176)
			(xy 386.88391 -394.843) (xy 386.875782 -394.842746) (xy 386.846494 -394.841284) (xy 386.78862 -394.831826)
			(xy 386.732428 -394.815054) (xy 386.678839 -394.791243) (xy 386.62873 -394.760781) (xy 386.582922 -394.724169)
			(xy 386.542166 -394.682006) (xy 386.507128 -394.634982) (xy 386.478384 -394.583869) (xy 386.456404 -394.529502)
			(xy 386.441547 -394.472774) (xy 386.434058 -394.414613) (xy 386.433568 -394.385292) (xy 386.433568 -394.385038)
			(xy 386.433568 -394.384022) (xy 386.434036 -394.355522) (xy 386.441169 -394.29897) (xy 386.447792 -394.271246)
			(xy 386.448554 -394.268452) (xy 386.450332 -394.255752) (xy 386.450332 -394.245846) (xy 386.450112 -394.239243)
			(xy 386.44664 -394.226499) (xy 386.443474 -394.2207) (xy 386.413502 -394.168376) (xy 386.41088 -394.16408)
			(xy 386.404224 -394.156535) (xy 386.400294 -394.15339) (xy 386.37718 -394.135864) (xy 386.367782 -394.13307)
			(xy 386.339306 -394.124599) (xy 386.284655 -394.101302) (xy 386.233476 -394.071129) (xy 386.186632 -394.034589)
			(xy 386.144908 -393.992296) (xy 386.109007 -393.94496) (xy 386.079532 -393.893377) (xy 386.056978 -393.838414)
			(xy 386.041725 -393.780995) (xy 386.034028 -393.722085) (xy 386.033518 -393.69238) (xy 386.033518 -393.679934)
			(xy 386.034799 -393.650621) (xy 386.043906 -393.592658) (xy 386.060346 -393.536334) (xy 386.083851 -393.482574)
			(xy 386.098542 -393.457176) (xy 386.098542 -393.456668) (xy 386.098796 -393.456414) (xy 386.101461 -393.451705)
			(xy 386.104924 -393.441456) (xy 386.105654 -393.436094) (xy 386.10667 -393.425172) (xy 386.077206 -393.34059)
			(xy 386.073026 -393.330314) (xy 386.057614 -393.314389) (xy 386.047488 -393.309856) (xy 386.045202 -393.30884)
			(xy 386.041392 -393.30757) (xy 386.039614 -393.306808) (xy 386.03936 -393.306808) (xy 386.037582 -393.306046)
			(xy 386.015065 -393.296405) (xy 385.972917 -393.271452) (xy 385.934911 -393.240554) (xy 385.901879 -393.204387)
			(xy 385.874545 -393.163743) (xy 385.853506 -393.119511) (xy 385.839222 -393.072659) (xy 385.832008 -393.024213)
			(xy 385.831588 -392.999722) (xy 385.832098 -392.973735) (xy 385.840228 -392.9224) (xy 385.856289 -392.87297)
			(xy 385.879885 -392.82666) (xy 385.910435 -392.784612) (xy 385.947186 -392.747861) (xy 385.989234 -392.717311)
			(xy 386.035544 -392.693715) (xy 386.084974 -392.677654) (xy 386.136309 -392.669524) (xy 386.188283 -392.669524)
			(xy 386.239618 -392.677654) (xy 386.289048 -392.693715) (xy 386.335358 -392.717311) (xy 386.377406 -392.747861)
			(xy 386.414157 -392.784612) (xy 386.444707 -392.82666) (xy 386.468303 -392.87297) (xy 386.484364 -392.9224)
			(xy 386.492494 -392.973735) (xy 386.493004 -392.999722) (xy 386.493004 -393.000484) (xy 386.492516 -393.026518)
			(xy 386.484344 -393.07794) (xy 386.476748 -393.102846) (xy 386.475478 -393.106656) (xy 386.473954 -393.11453)
			(xy 386.473259 -393.119145) (xy 386.473391 -393.128477) (xy 386.474208 -393.133072) (xy 386.475986 -393.142216)
			(xy 386.480812 -393.15009) (xy 386.520182 -393.215114) (xy 386.52069 -393.21613) (xy 386.528818 -393.225782)
			(xy 386.53189 -393.228564) (xy 386.538783 -393.233164) (xy 386.542534 -393.234926) (xy 386.550154 -393.238482)
			(xy 386.553456 -393.23899) (xy 386.557266 -393.239498) (xy 386.586209 -393.244197) (xy 386.642675 -393.260007)
			(xy 386.69666 -393.282897) (xy 386.747281 -393.312491) (xy 386.79371 -393.348306) (xy 386.835187 -393.389755)
			(xy 386.871033 -393.436159) (xy 386.900662 -393.48676) (xy 386.923589 -393.540729) (xy 386.939438 -393.597184)
			(xy 386.947951 -393.6552) (xy 386.948934 -393.684506) (xy 386.948934 -393.692634) (xy 386.948484 -393.721986)
			(xy 386.940966 -393.780207) (xy 386.933948 -393.808712) (xy 386.93344 -393.81049) (xy 386.93344 -393.810998)
			(xy 386.93217 -393.815062) (xy 386.931408 -393.817348) (xy 386.929703 -393.826563) (xy 386.932443 -393.845089)
			(xy 386.936742 -393.853416) (xy 386.936996 -393.853924) (xy 386.969 -393.909296) (xy 386.97162 -393.913593)
			(xy 386.978274 -393.921142) (xy 386.982208 -393.924282) (xy 387.005322 -393.941808) (xy 387.01472 -393.944602)
			(xy 387.043196 -393.953073) (xy 387.09785 -393.97637) (xy 387.14903 -394.006542) (xy 387.195877 -394.043081)
			(xy 387.237602 -394.085375) (xy 387.273506 -394.13271) (xy 387.302984 -394.184293) (xy 387.325541 -394.239256)
			(xy 387.340797 -394.296676) (xy 387.348497 -394.355586) (xy 387.348984 -394.385292) (xy 387.34887 -394.399491)
			(xy 387.347091 -394.427833) (xy 387.345428 -394.441934) (xy 387.344988 -394.446456) (xy 387.345493 -394.455526)
			(xy 387.346444 -394.459968) (xy 387.348222 -394.467842) (xy 387.352794 -394.475208) (xy 387.368288 -394.5001)
			(xy 387.372995 -394.507162) (xy 387.386105 -394.517924) (xy 387.393942 -394.521182) (xy 387.417312 -394.530382)
			(xy 387.461188 -394.554821) (xy 387.500866 -394.585611) (xy 387.535434 -394.622046) (xy 387.564097 -394.663286)
			(xy 387.586196 -394.708386) (xy 387.601225 -394.756308) (xy 387.608838 -394.805951) (xy 387.609334 -394.831062)
			(xy 387.608901 -394.85518) (xy 387.601906 -394.902905) (xy 387.588058 -394.94911) (xy 387.567652 -394.992816)
			(xy 387.554724 -395.01318) (xy 387.55066 -395.01953) (xy 387.546342 -395.0335) (xy 387.546342 -395.045438)
			(xy 387.54685 -395.05255) (xy 387.54939 -395.07033) (xy 387.55066 -395.080236) (xy 387.568694 -395.111732)
			(xy 387.575552 -395.117574) (xy 387.596808 -395.136256) (xy 387.635013 -395.178005) (xy 387.667781 -395.224145)
			(xy 387.694612 -395.273972) (xy 387.715096 -395.326726) (xy 387.728921 -395.381603) (xy 387.735877 -395.437766)
			(xy 387.736334 -395.466062) (xy 387.736334 -395.46657) (xy 387.735762 -395.498823) (xy 387.726662 -395.562686)
			(xy 387.708679 -395.624636) (xy 387.695948 -395.654276) (xy 387.693916 -395.658594) (xy 387.691203 -395.668039)
			(xy 387.692393 -395.687634) (xy 387.696202 -395.696694) (xy 387.702552 -395.71041) (xy 387.705854 -395.714728)
			(xy 387.715506 -395.727428) (xy 387.719062 -395.730476) (xy 387.743304 -395.752351) (xy 387.785959 -395.801786)
			(xy 387.821162 -395.856779) (xy 387.848197 -395.916213) (xy 387.866518 -395.978884) (xy 387.875753 -396.043522)
			(xy 387.876288 -396.07617) (xy 387.876288 -396.085822) (xy 387.874755 -396.122796) (xy 387.861221 -396.195547)
			(xy 387.849364 -396.230602) (xy 387.837767 -396.261157) (xy 387.807164 -396.318903) (xy 387.788404 -396.345664)
			(xy 387.783832 -396.352014) (xy 387.777482 -396.370048) (xy 387.775048 -396.379059) (xy 387.776106 -396.397679)
			(xy 387.779514 -396.40637) (xy 387.780276 -396.408148) (xy 387.820662 -396.488666) (xy 387.825219 -396.495979)
			(xy 387.838226 -396.507264) (xy 387.854238 -396.513599) (xy 387.862826 -396.51432) (xy 388.172198 -396.51432)
			(xy 388.17423 -396.51432) (xy 388.182824 -396.51364) (xy 388.198838 -396.507287) (xy 388.211842 -396.495987)
			(xy 388.216394 -396.488666) (xy 388.25678 -396.408148) (xy 388.257542 -396.40637) (xy 388.260971 -396.397688)
			(xy 388.261997 -396.379064) (xy 388.259574 -396.370048) (xy 388.253224 -396.352014) (xy 388.248652 -396.345664)
			(xy 388.232154 -396.322297) (xy 388.204469 -396.27224) (xy 388.183242 -396.219123) (xy 388.168803 -396.163773)
			(xy 388.161378 -396.107054) (xy 388.160768 -396.078456) (xy 388.160768 -396.065248) (xy 388.161951 -396.034661)
			(xy 388.171491 -395.974198) (xy 388.189014 -395.915548) (xy 388.201154 -395.887448) (xy 388.203186 -395.88313)
			(xy 388.205904 -395.873685) (xy 388.204723 -395.854085) (xy 388.2009 -395.84503) (xy 388.19455 -395.831314)
			(xy 388.191248 -395.826996) (xy 388.181596 -395.814296) (xy 388.17804 -395.811248) (xy 388.153815 -395.789415)
			(xy 388.111185 -395.740065) (xy 388.075998 -395.685158) (xy 388.048969 -395.62581) (xy 388.030646 -395.563224)
			(xy 388.021401 -395.498669) (xy 388.020814 -395.466062) (xy 388.021237 -395.437766) (xy 388.028212 -395.381605)
			(xy 388.04205 -395.32673) (xy 388.06254 -395.273977) (xy 388.089372 -395.22415) (xy 388.122136 -395.178006)
			(xy 388.160334 -395.136249) (xy 388.181596 -395.117574) (xy 388.188454 -395.111732) (xy 388.206488 -395.080236)
			(xy 388.207758 -395.07033) (xy 388.210806 -395.04874) (xy 388.210806 -395.048486) (xy 388.212076 -395.039088)
			(xy 388.208012 -395.021562) (xy 388.206996 -395.019784) (xy 388.202932 -395.013688) (xy 388.189166 -394.992131)
			(xy 388.16773 -394.945694) (xy 388.16026 -394.921232) (xy 388.155434 -394.902182) (xy 388.155434 -394.901928)
			(xy 388.153402 -394.893292) (xy 388.149338 -394.886434) (xy 388.146975 -394.88279) (xy 388.141228 -394.876279)
			(xy 388.137908 -394.87348) (xy 388.121398 -394.860018) (xy 388.11454 -394.854176) (xy 388.083806 -394.843)
			(xy 388.075678 -394.842746) (xy 388.04639 -394.841284) (xy 387.988517 -394.831826) (xy 387.932325 -394.815053)
			(xy 387.878736 -394.791241) (xy 387.828628 -394.76078) (xy 387.78282 -394.724167) (xy 387.742064 -394.682004)
			(xy 387.707027 -394.634981) (xy 387.678283 -394.583868) (xy 387.656303 -394.529502) (xy 387.641447 -394.472774)
			(xy 387.633958 -394.414613) (xy 387.633464 -394.385292) (xy 387.633464 -394.385038) (xy 387.633464 -394.384022)
			(xy 387.633932 -394.355522) (xy 387.641065 -394.29897) (xy 387.647688 -394.271246) (xy 387.64845 -394.268452)
			(xy 387.650228 -394.255752) (xy 387.650228 -394.245846) (xy 387.650008 -394.239243) (xy 387.646535 -394.226499)
			(xy 387.64337 -394.2207) (xy 387.613398 -394.168376) (xy 387.61078 -394.164077) (xy 387.604131 -394.156521)
			(xy 387.60019 -394.15339) (xy 387.579362 -394.137642) (xy 387.569964 -394.134848) (xy 387.541242 -394.126483)
			(xy 387.486087 -394.10332) (xy 387.43441 -394.073184) (xy 387.38709 -394.036585) (xy 387.344928 -393.994146)
			(xy 387.308641 -393.946586) (xy 387.278844 -393.894713) (xy 387.256043 -393.839407) (xy 387.240625 -393.781606)
			(xy 387.232851 -393.722291) (xy 387.232398 -393.69238) (xy 387.232924 -393.66109) (xy 387.241421 -393.599089)
			(xy 387.258268 -393.538819) (xy 387.283153 -393.481399) (xy 387.298946 -393.454382) (xy 387.301742 -393.44951)
			(xy 387.305342 -393.438871) (xy 387.306058 -393.4333) (xy 387.30682 -393.425172) (xy 387.277356 -393.34059)
			(xy 387.273179 -393.33031) (xy 387.257774 -393.314371) (xy 387.247638 -393.309856) (xy 387.245352 -393.30884)
			(xy 387.241542 -393.30757) (xy 387.239764 -393.306808) (xy 387.23951 -393.306808) (xy 387.237732 -393.306046)
			(xy 387.215218 -393.296402) (xy 387.173075 -393.271446) (xy 387.135075 -393.240546) (xy 387.102048 -393.204378)
			(xy 387.074718 -393.163735) (xy 387.053683 -393.119504) (xy 387.039402 -393.072655) (xy 387.032189 -393.024211)
			(xy 387.031738 -392.999722) (xy 387.032248 -392.973735) (xy 387.040378 -392.9224) (xy 387.056439 -392.87297)
			(xy 387.080035 -392.82666) (xy 387.110585 -392.784612) (xy 387.147336 -392.747861) (xy 387.189384 -392.717311)
			(xy 387.235694 -392.693715) (xy 387.285124 -392.677654) (xy 387.336459 -392.669524) (xy 387.388433 -392.669524)
			(xy 387.439768 -392.677654) (xy 387.489198 -392.693715) (xy 387.535508 -392.717311) (xy 387.577556 -392.747861)
			(xy 387.614307 -392.784612) (xy 387.644857 -392.82666) (xy 387.668453 -392.87297) (xy 387.684514 -392.9224)
			(xy 387.692644 -392.973735) (xy 387.693154 -392.999722) (xy 388.231634 -392.999722) (xy 388.232144 -392.973735)
			(xy 388.240274 -392.9224) (xy 388.256335 -392.87297) (xy 388.279931 -392.82666) (xy 388.310481 -392.784612)
			(xy 388.347232 -392.747861) (xy 388.38928 -392.717311) (xy 388.43559 -392.693715) (xy 388.48502 -392.677654)
			(xy 388.536355 -392.669524) (xy 388.588329 -392.669524) (xy 388.639664 -392.677654) (xy 388.689094 -392.693715)
			(xy 388.735404 -392.717311) (xy 388.777452 -392.747861) (xy 388.814203 -392.784612) (xy 388.844753 -392.82666)
			(xy 388.868349 -392.87297) (xy 388.88441 -392.9224) (xy 388.89254 -392.973735) (xy 388.89305 -392.999722)
			(xy 388.89305 -393.00023) (xy 388.892484 -393.027204) (xy 388.883677 -393.08043) (xy 388.875524 -393.106148)
			(xy 388.871714 -393.11707) (xy 388.874254 -393.139422) (xy 388.92099 -393.215876) (xy 388.927278 -393.22508)
			(xy 388.945868 -393.237335) (xy 388.956804 -393.239498) (xy 388.957058 -393.239498) (xy 388.98638 -393.244184)
			(xy 389.04355 -393.260236) (xy 389.098164 -393.283549) (xy 389.149303 -393.313731) (xy 389.196109 -393.350274)
			(xy 389.237793 -393.392565) (xy 389.273657 -393.439894) (xy 389.303096 -393.491464) (xy 389.319442 -393.531344)
			(xy 390.402318 -393.531344) (xy 390.402744 -393.502708) (xy 390.409901 -393.445886) (xy 390.424083 -393.390398)
			(xy 390.44507 -393.33711) (xy 390.472534 -393.286854) (xy 390.488932 -393.263374) (xy 390.494609 -393.254857)
			(xy 390.499219 -393.23493) (xy 390.495651 -393.214791) (xy 390.490456 -393.20597) (xy 390.472983 -393.178021)
			(xy 390.445373 -393.118169) (xy 390.426628 -393.054978) (xy 390.417137 -392.989752) (xy 390.416542 -392.956796)
			(xy 390.416542 -392.956542) (xy 390.417008 -392.927301) (xy 390.424441 -392.869294) (xy 390.439202 -392.812707)
			(xy 390.461052 -392.758461) (xy 390.489635 -392.70744) (xy 390.524485 -392.660477) (xy 390.565034 -392.618336)
			(xy 390.61062 -392.581704) (xy 390.660503 -392.551179) (xy 390.713867 -392.527256) (xy 390.769844 -392.510327)
			(xy 390.827522 -392.500667) (xy 390.856724 -392.499088) (xy 390.866376 -392.498834) (xy 390.883648 -392.491214)
			(xy 390.939528 -392.43508) (xy 390.945944 -392.428107) (xy 390.953504 -392.410744) (xy 390.95426 -392.401298)
			(xy 390.95426 -392.401044) (xy 390.955853 -392.368494) (xy 390.966342 -392.304173) (xy 390.984963 -392.241719)
			(xy 391.01141 -392.182156) (xy 391.04525 -392.12646) (xy 391.085928 -392.075543) (xy 391.132777 -392.030241)
			(xy 391.18503 -391.991295) (xy 391.241831 -391.959344) (xy 391.302248 -391.934911) (xy 391.365292 -391.918398)
			(xy 391.429929 -391.910074) (xy 391.462514 -391.909554) (xy 391.496097 -391.910127) (xy 391.56268 -391.918952)
			(xy 391.62752 -391.936472) (xy 391.689486 -391.962382) (xy 391.747498 -391.996231) (xy 391.800545 -392.037428)
			(xy 391.847702 -392.085255) (xy 391.888146 -392.138879) (xy 391.921173 -392.197363) (xy 391.934192 -392.228324)
			(xy 391.934192 -392.228578) (xy 391.938181 -392.237254) (xy 391.95133 -392.251079) (xy 391.968635 -392.259112)
			(xy 391.978134 -392.260074) (xy 392.08456 -392.266678) (xy 392.110214 -392.252454) (xy 392.117326 -392.2395)
			(xy 392.134272 -392.210171) (xy 392.174678 -392.15581) (xy 392.22194 -392.10729) (xy 392.275222 -392.065469)
			(xy 392.333581 -392.031087) (xy 392.395986 -392.004752) (xy 392.461333 -391.986929) (xy 392.528467 -391.977934)
			(xy 392.562334 -391.977372) (xy 392.601586 -391.978139) (xy 392.679151 -391.990257) (xy 392.716766 -392.001502)
			(xy 392.71702 -392.001502) (xy 392.725263 -392.00376) (xy 392.742336 -392.00322) (xy 392.758287 -391.997107)
			(xy 392.765026 -391.99185) (xy 392.830812 -391.93597) (xy 392.837132 -391.930171) (xy 392.845761 -391.915358)
			(xy 392.849006 -391.898524) (xy 392.848084 -391.889996) (xy 392.848084 -391.889742) (xy 392.846192 -391.875977)
			(xy 392.844157 -391.848264) (xy 392.84402 -391.83437) (xy 392.84402 -391.834116) (xy 392.844506 -391.806865)
			(xy 392.852262 -391.752917) (xy 392.867617 -391.700622) (xy 392.890259 -391.651045) (xy 392.919725 -391.605195)
			(xy 392.955416 -391.564004) (xy 392.996607 -391.528313) (xy 393.042457 -391.498847) (xy 393.092034 -391.476205)
			(xy 393.144329 -391.46085) (xy 393.198277 -391.453094) (xy 393.252779 -391.453094) (xy 393.306727 -391.46085)
			(xy 393.359022 -391.476205) (xy 393.408599 -391.498847) (xy 393.454449 -391.528313) (xy 393.49564 -391.564004)
			(xy 393.531331 -391.605195) (xy 393.560797 -391.651045) (xy 393.583439 -391.700622) (xy 393.598794 -391.752917)
			(xy 393.60655 -391.806865) (xy 393.607036 -391.834116) (xy 393.606333 -391.865698) (xy 393.595869 -391.927992)
			(xy 393.586208 -391.958068) (xy 393.583697 -391.966404) (xy 393.583834 -391.983803) (xy 393.586462 -391.992104)
			(xy 393.59713 -392.020552) (xy 393.60047 -392.028611) (xy 393.611639 -392.041993) (xy 393.618974 -392.046714)
			(xy 393.647286 -392.063935) (xy 393.699672 -392.104518) (xy 393.720191 -392.1252) (xy 399.31162 -392.1252)
			(xy 399.315691 -392.069578) (xy 399.327817 -392.015141) (xy 399.34774 -391.96305) (xy 399.375036 -391.914415)
			(xy 399.409122 -391.870272) (xy 399.449271 -391.831563) (xy 399.494629 -391.799112) (xy 399.544229 -391.773611)
			(xy 399.597013 -391.755604) (xy 399.651856 -391.745474) (xy 399.70759 -391.743437) (xy 399.763027 -391.749537)
			(xy 399.816984 -391.763643) (xy 399.868313 -391.785455) (xy 399.915919 -391.814509) (xy 399.958787 -391.850184)
			(xy 399.996004 -391.891721) (xy 400.026777 -391.938234) (xy 400.050449 -391.988731) (xy 400.066517 -392.042138)
			(xy 400.074637 -392.097314) (xy 400.075146 -392.1252) (xy 400.074637 -392.153086) (xy 400.066517 -392.208262)
			(xy 400.050449 -392.261669) (xy 400.026777 -392.312166) (xy 399.996004 -392.358679) (xy 399.958787 -392.400216)
			(xy 399.915919 -392.435891) (xy 399.868313 -392.464945) (xy 399.816984 -392.486757) (xy 399.763027 -392.500863)
			(xy 399.70759 -392.506963) (xy 399.651856 -392.504926) (xy 399.597013 -392.494796) (xy 399.544229 -392.476789)
			(xy 399.494629 -392.451288) (xy 399.449271 -392.418837) (xy 399.409122 -392.380128) (xy 399.375036 -392.335985)
			(xy 399.34774 -392.28735) (xy 399.327817 -392.235259) (xy 399.315691 -392.180822) (xy 399.31162 -392.1252)
			(xy 393.720191 -392.1252) (xy 393.746343 -392.15156) (xy 393.78651 -392.204265) (xy 393.819492 -392.26174)
			(xy 393.844731 -392.323012) (xy 393.861799 -392.387042) (xy 393.870407 -392.452747) (xy 393.870942 -392.48588)
			(xy 393.870485 -392.515989) (xy 393.863354 -392.575783) (xy 393.849215 -392.634318) (xy 393.828264 -392.690774)
			(xy 393.800794 -392.744361) (xy 393.767191 -392.794331) (xy 393.727923 -392.839985) (xy 393.68354 -392.880683)
			(xy 393.65936 -392.89863) (xy 393.649895 -392.906255) (xy 393.638895 -392.927892) (xy 393.638278 -392.940032)
			(xy 393.638278 -393.022328) (xy 393.638886 -393.034463) (xy 393.644102 -393.04468) (xy 399.31162 -393.04468)
			(xy 399.315691 -392.989058) (xy 399.327817 -392.934621) (xy 399.34774 -392.88253) (xy 399.375036 -392.833895)
			(xy 399.409122 -392.789752) (xy 399.449271 -392.751043) (xy 399.494629 -392.718592) (xy 399.544229 -392.693091)
			(xy 399.597013 -392.675084) (xy 399.651856 -392.664954) (xy 399.70759 -392.662917) (xy 399.763027 -392.669017)
			(xy 399.816984 -392.683123) (xy 399.868313 -392.704935) (xy 399.915919 -392.733989) (xy 399.958398 -392.76934)
			(xy 400.571698 -392.76934) (xy 400.571698 -392.709404) (xy 400.579521 -392.649982) (xy 400.595034 -392.592089)
			(xy 400.61797 -392.536716) (xy 400.647937 -392.48481) (xy 400.684424 -392.43726) (xy 400.726804 -392.39488)
			(xy 400.774354 -392.358393) (xy 400.82626 -392.328426) (xy 400.881633 -392.30549) (xy 400.939526 -392.289977)
			(xy 400.998948 -392.282154) (xy 401.058884 -392.282154) (xy 401.118306 -392.289977) (xy 401.176199 -392.30549)
			(xy 401.231572 -392.328426) (xy 401.283478 -392.358393) (xy 401.331028 -392.39488) (xy 401.373408 -392.43726)
			(xy 401.409895 -392.48481) (xy 401.439862 -392.536716) (xy 401.462798 -392.592089) (xy 401.478311 -392.649982)
			(xy 401.486134 -392.709404) (xy 401.486624 -392.739372) (xy 401.486134 -392.76934) (xy 401.478311 -392.828762)
			(xy 401.462798 -392.886655) (xy 401.439862 -392.942028) (xy 401.409895 -392.993934) (xy 401.373408 -393.041484)
			(xy 401.331028 -393.083864) (xy 401.283478 -393.120351) (xy 401.231572 -393.150318) (xy 401.176199 -393.173254)
			(xy 401.118306 -393.188767) (xy 401.058884 -393.19659) (xy 400.998948 -393.19659) (xy 400.939526 -393.188767)
			(xy 400.881633 -393.173254) (xy 400.82626 -393.150318) (xy 400.774354 -393.120351) (xy 400.726804 -393.083864)
			(xy 400.684424 -393.041484) (xy 400.647937 -392.993934) (xy 400.61797 -392.942028) (xy 400.595034 -392.886655)
			(xy 400.579521 -392.828762) (xy 400.571698 -392.76934) (xy 399.958398 -392.76934) (xy 399.958787 -392.769664)
			(xy 399.996004 -392.811201) (xy 400.026777 -392.857714) (xy 400.050449 -392.908211) (xy 400.066517 -392.961618)
			(xy 400.074637 -393.016794) (xy 400.075146 -393.04468) (xy 400.074637 -393.072566) (xy 400.066517 -393.127742)
			(xy 400.050449 -393.181149) (xy 400.026777 -393.231646) (xy 399.996004 -393.278159) (xy 399.958787 -393.319696)
			(xy 399.915919 -393.355371) (xy 399.868313 -393.384425) (xy 399.816984 -393.406237) (xy 399.763027 -393.420343)
			(xy 399.70759 -393.426443) (xy 399.651856 -393.424406) (xy 399.597013 -393.414276) (xy 399.544229 -393.396269)
			(xy 399.494629 -393.370768) (xy 399.449271 -393.338317) (xy 399.409122 -393.299608) (xy 399.375036 -393.255465)
			(xy 399.34774 -393.20683) (xy 399.327817 -393.154739) (xy 399.315691 -393.100302) (xy 399.31162 -393.04468)
			(xy 393.644102 -393.04468) (xy 393.64992 -393.056076) (xy 393.65936 -393.06373) (xy 393.683553 -393.081663)
			(xy 393.727956 -393.122348) (xy 393.767238 -393.167996) (xy 393.800851 -393.217966) (xy 393.828323 -393.271559)
			(xy 393.849268 -393.328022) (xy 393.863394 -393.386566) (xy 393.870502 -393.446368) (xy 393.870942 -393.47648)
			(xy 393.870425 -393.507209) (xy 393.86302 -393.56822) (xy 393.848314 -393.627893) (xy 393.826523 -393.685359)
			(xy 393.797965 -393.739779) (xy 393.763055 -393.79036) (xy 393.722303 -393.836365) (xy 393.676303 -393.877122)
			(xy 393.625725 -393.912037) (xy 393.571308 -393.940601) (xy 393.513845 -393.962398) (xy 393.454173 -393.97711)
			(xy 393.393163 -393.984522) (xy 393.362434 -393.984988) (xy 393.330309 -393.984519) (xy 393.266573 -393.976408)
			(xy 393.204365 -393.960336) (xy 393.144676 -393.936559) (xy 393.088457 -393.905456) (xy 393.036601 -393.867521)
			(xy 393.01293 -393.845796) (xy 393.005585 -393.83945) (xy 392.987574 -393.83226) (xy 392.977878 -393.831826)
			(xy 392.94689 -393.831826) (xy 392.937188 -393.83225) (xy 392.919162 -393.839421) (xy 392.911838 -393.845796)
			(xy 392.89609 -393.860274) (xy 392.887454 -393.86764) (xy 392.87831 -393.888722) (xy 392.881104 -393.978892)
			(xy 392.882088 -393.990217) (xy 392.892511 -394.010388) (xy 392.90117 -394.017754) (xy 392.92749 -394.038435)
			(xy 392.975028 -394.085559) (xy 393.015969 -394.138515) (xy 393.049606 -394.196386) (xy 393.075355 -394.258172)
			(xy 393.092771 -394.322804) (xy 393.101553 -394.389162) (xy 393.102084 -394.42263) (xy 393.101672 -394.453363)
			(xy 393.09426 -394.514379) (xy 393.079547 -394.574057) (xy 393.057748 -394.631527) (xy 393.02918 -394.68595)
			(xy 392.994261 -394.736533) (xy 392.9535 -394.782538) (xy 392.907491 -394.823295) (xy 392.856904 -394.858208)
			(xy 392.802478 -394.88677) (xy 392.745006 -394.908563) (xy 392.685326 -394.923269) (xy 392.624309 -394.930675)
			(xy 392.593576 -394.931138) (xy 392.562074 -394.930654) (xy 392.499553 -394.922865) (xy 392.438473 -394.907408)
			(xy 392.379773 -394.884522) (xy 392.32435 -394.854557) (xy 392.298428 -394.83665) (xy 392.291231 -394.831904)
			(xy 392.274663 -394.827175) (xy 392.257466 -394.828253) (xy 392.249406 -394.831316) (xy 392.157204 -394.870178)
			(xy 392.141202 -394.890752) (xy 392.13917 -394.90396) (xy 392.133738 -394.93631) (xy 392.115508 -394.999324)
			(xy 392.089327 -395.059472) (xy 392.055631 -395.115756) (xy 392.014979 -395.16724) (xy 391.968046 -395.21307)
			(xy 391.91561 -395.252487) (xy 391.858542 -395.284835) (xy 391.797788 -395.309579) (xy 391.734358 -395.326306)
			(xy 391.669303 -395.33474) (xy 391.636504 -395.335252) (xy 391.6051 -395.334723) (xy 391.542771 -395.326988)
			(xy 391.481869 -395.311636) (xy 391.423322 -395.288899) (xy 391.36802 -395.259125) (xy 391.316806 -395.222767)
			(xy 391.27046 -395.180378) (xy 391.229688 -395.132604) (xy 391.19511 -395.080172) (xy 391.167253 -395.023881)
			(xy 391.14654 -394.964587) (xy 391.133288 -394.903193) (xy 391.130028 -394.871956) (xy 391.129266 -394.86205)
			(xy 391.120376 -394.844778) (xy 391.059924 -394.791946) (xy 391.052231 -394.78583) (xy 391.033681 -394.779411)
			(xy 391.023856 -394.7795) (xy 390.999726 -394.780008) (xy 390.968994 -394.779538) (xy 390.907979 -394.772132)
			(xy 390.848301 -394.757426) (xy 390.790832 -394.735633) (xy 390.736408 -394.707072) (xy 390.685823 -394.672158)
			(xy 390.639817 -394.631402) (xy 390.599058 -394.585397) (xy 390.564142 -394.534815) (xy 390.535578 -394.480392)
			(xy 390.513782 -394.422923) (xy 390.499072 -394.363246) (xy 390.491664 -394.302232) (xy 390.491218 -394.2715)
			(xy 390.491656 -394.240718) (xy 390.499048 -394.1796) (xy 390.513773 -394.119824) (xy 390.535614 -394.062265)
			(xy 390.564251 -394.007768) (xy 390.581388 -393.982194) (xy 390.586465 -393.974199) (xy 390.590915 -393.955807)
			(xy 390.590024 -393.94638) (xy 390.585706 -393.915646) (xy 390.584045 -393.906382) (xy 390.57492 -393.889938)
			(xy 390.567926 -393.883642) (xy 390.5461 -393.864954) (xy 390.506795 -393.82304) (xy 390.473047 -393.776535)
			(xy 390.445387 -393.72617) (xy 390.42425 -393.672739) (xy 390.40997 -393.617081) (xy 390.40277 -393.560074)
			(xy 390.402318 -393.531344) (xy 389.319442 -393.531344) (xy 389.325617 -393.546409) (xy 389.340842 -393.603805)
			(xy 389.348513 -393.662689) (xy 389.34898 -393.69238) (xy 389.348453 -393.723443) (xy 389.340041 -393.784996)
			(xy 389.332216 -393.815062) (xy 389.329422 -393.824968) (xy 389.331962 -393.845288) (xy 389.374126 -393.918186)
			(xy 389.379515 -393.926796) (xy 389.395647 -393.939111) (xy 389.405368 -393.942062) (xy 389.405622 -393.942062)
			(xy 389.434726 -393.950082) (xy 389.490692 -393.972713) (xy 389.543198 -394.002504) (xy 389.591332 -394.038939)
			(xy 389.634259 -394.081385) (xy 389.671234 -394.129105) (xy 389.701615 -394.181272) (xy 389.724875 -394.236981)
			(xy 389.740609 -394.295263) (xy 389.748546 -394.355108) (xy 389.74903 -394.385292) (xy 389.748929 -394.399042)
			(xy 389.747275 -394.426493) (xy 389.745728 -394.440156) (xy 389.744986 -394.448845) (xy 389.748764 -394.465859)
			(xy 389.753094 -394.47343) (xy 389.769096 -394.49883) (xy 389.773866 -394.505866) (xy 389.787108 -394.516508)
			(xy 389.795004 -394.519658) (xy 389.818778 -394.528584) (xy 389.863427 -394.552776) (xy 389.903853 -394.58351)
			(xy 389.939104 -394.620064) (xy 389.968352 -394.661577) (xy 389.99091 -394.707074) (xy 390.006246 -394.755485)
			(xy 390.014001 -394.805671) (xy 390.01446 -394.831062) (xy 390.01399 -394.857053) (xy 390.005863 -394.908395)
			(xy 389.989803 -394.957833) (xy 389.966205 -395.004149) (xy 389.935652 -395.046203) (xy 389.898895 -395.082959)
			(xy 389.85684 -395.113511) (xy 389.810523 -395.137106) (xy 389.761085 -395.153165) (xy 389.709743 -395.16129)
			(xy 389.683752 -395.16177) (xy 389.658856 -395.161271) (xy 389.609626 -395.153807) (xy 389.562074 -395.139042)
			(xy 389.517275 -395.117308) (xy 389.476244 -395.089099) (xy 389.439911 -395.055052) (xy 389.409098 -395.015939)
			(xy 389.384502 -394.972646) (xy 389.366681 -394.926152) (xy 389.360918 -394.901928) (xy 389.35875 -394.893664)
			(xy 389.349806 -394.879122) (xy 389.343392 -394.87348) (xy 389.3058 -394.842746) (xy 389.291322 -394.843)
			(xy 389.261353 -394.842518) (xy 389.201928 -394.834697) (xy 389.144032 -394.819187) (xy 389.088656 -394.796251)
			(xy 389.036748 -394.766284) (xy 388.989195 -394.729797) (xy 388.946812 -394.687415) (xy 388.910324 -394.639864)
			(xy 388.880355 -394.587956) (xy 388.857418 -394.532581) (xy 388.841905 -394.474686) (xy 388.834083 -394.415261)
			(xy 388.833614 -394.385292) (xy 388.834136 -394.354229) (xy 388.842551 -394.292675) (xy 388.850378 -394.26261)
			(xy 388.853172 -394.252704) (xy 388.850632 -394.232384) (xy 388.808468 -394.159486) (xy 388.803063 -394.150887)
			(xy 388.786943 -394.138564) (xy 388.777226 -394.13561) (xy 388.776972 -394.13561) (xy 388.747859 -394.12762)
			(xy 388.691891 -394.104986) (xy 388.639385 -394.075192) (xy 388.59125 -394.038754) (xy 388.548323 -393.996305)
			(xy 388.511349 -393.94858) (xy 388.480969 -393.89641) (xy 388.457712 -393.840699) (xy 388.44198 -393.782413)
			(xy 388.434046 -393.722566) (xy 388.433564 -393.69238) (xy 388.434081 -393.661492) (xy 388.442387 -393.600276)
			(xy 388.458846 -393.540731) (xy 388.48316 -393.48394) (xy 388.498588 -393.457176) (xy 388.503971 -393.447255)
			(xy 388.506325 -393.424832) (xy 388.50316 -393.413996) (xy 388.477252 -393.340336) (xy 388.473001 -393.329977)
			(xy 388.45731 -393.314036) (xy 388.447026 -393.309602) (xy 388.423629 -393.300456) (xy 388.379734 -393.276028)
			(xy 388.340041 -393.24524) (xy 388.305462 -393.208801) (xy 388.276795 -393.167549) (xy 388.2547 -393.122435)
			(xy 388.239685 -393.074497) (xy 388.232096 -393.024839) (xy 388.231634 -392.999722) (xy 387.693154 -392.999722)
			(xy 387.693154 -393.000484) (xy 387.692666 -393.026518) (xy 387.684496 -393.077941) (xy 387.676898 -393.102846)
			(xy 387.675628 -393.106656) (xy 387.674104 -393.11453) (xy 387.673409 -393.119145) (xy 387.673541 -393.128477)
			(xy 387.674358 -393.133072) (xy 387.676136 -393.142216) (xy 387.680962 -393.15009) (xy 387.720078 -393.214352)
			(xy 387.723079 -393.219054) (xy 387.730766 -393.227132) (xy 387.735318 -393.230354) (xy 387.744716 -393.23645)
			(xy 387.756146 -393.237974) (xy 387.785609 -393.242654) (xy 387.84308 -393.258653) (xy 387.897994 -393.281964)
			(xy 387.949424 -393.312195) (xy 387.996503 -393.348834) (xy 388.038437 -393.391266) (xy 388.07452 -393.438773)
			(xy 388.104142 -393.490556) (xy 388.126804 -393.545741) (xy 388.142125 -393.603397) (xy 388.149845 -393.662552)
			(xy 388.150354 -393.69238) (xy 388.149838 -393.723644) (xy 388.141304 -393.785588) (xy 388.133336 -393.815824)
			(xy 388.133082 -393.81684) (xy 388.13232 -393.81938) (xy 388.130542 -393.83335) (xy 388.130542 -393.83589)
			(xy 388.130796 -393.84351) (xy 388.160514 -393.894818) (xy 388.161022 -393.895834) (xy 388.168896 -393.909296)
			(xy 388.171516 -393.913593) (xy 388.17817 -393.921143) (xy 388.182104 -393.924282) (xy 388.205218 -393.941808)
			(xy 388.214616 -393.944602) (xy 388.243093 -393.953072) (xy 388.297746 -393.976369) (xy 388.348927 -394.006541)
			(xy 388.395774 -394.043081) (xy 388.4375 -394.085374) (xy 388.473404 -394.13271) (xy 388.502882 -394.184293)
			(xy 388.525439 -394.239256) (xy 388.540696 -394.296675) (xy 388.548396 -394.355586) (xy 388.54888 -394.385292)
			(xy 388.548766 -394.399491) (xy 388.546987 -394.427833) (xy 388.545324 -394.441934) (xy 388.544884 -394.446456)
			(xy 388.545389 -394.455526) (xy 388.54634 -394.459968) (xy 388.548118 -394.467842) (xy 388.55269 -394.475208)
			(xy 388.568184 -394.5001) (xy 388.57289 -394.507162) (xy 388.586 -394.517925) (xy 388.593838 -394.521182)
			(xy 388.617209 -394.530382) (xy 388.661085 -394.55482) (xy 388.700763 -394.585611) (xy 388.735331 -394.622045)
			(xy 388.763995 -394.663286) (xy 388.786095 -394.708385) (xy 388.801124 -394.756307) (xy 388.808736 -394.80595)
			(xy 388.80923 -394.831062) (xy 388.808797 -394.85518) (xy 388.801802 -394.902905) (xy 388.787954 -394.94911)
			(xy 388.767548 -394.992816) (xy 388.75462 -395.01318) (xy 388.750556 -395.01953) (xy 388.746238 -395.0335)
			(xy 388.746238 -395.045438) (xy 388.746746 -395.05255) (xy 388.749286 -395.07033) (xy 388.750556 -395.080236)
			(xy 388.76859 -395.111732) (xy 388.775448 -395.117574) (xy 388.796704 -395.136256) (xy 388.83491 -395.178005)
			(xy 388.867678 -395.224145) (xy 388.894509 -395.273972) (xy 388.914993 -395.326726) (xy 388.928819 -395.381603)
			(xy 388.935775 -395.437766) (xy 388.93623 -395.466062) (xy 388.93623 -395.46657) (xy 388.935658 -395.498823)
			(xy 388.926557 -395.562686) (xy 388.908575 -395.624636) (xy 388.895844 -395.654276) (xy 388.893812 -395.658594)
			(xy 388.891099 -395.668039) (xy 388.892289 -395.687634) (xy 388.896098 -395.696694) (xy 388.902448 -395.71041)
			(xy 388.90575 -395.714728) (xy 388.915402 -395.727428) (xy 388.918958 -395.730476) (xy 388.9432 -395.752351)
			(xy 388.985856 -395.801786) (xy 389.021059 -395.856778) (xy 389.048095 -395.916213) (xy 389.066416 -395.978884)
			(xy 389.075651 -396.043522) (xy 389.076184 -396.07617) (xy 389.076184 -396.085822) (xy 389.074651 -396.122796)
			(xy 389.061117 -396.195547) (xy 389.04926 -396.230602) (xy 389.037666 -396.261159) (xy 389.007068 -396.318908)
			(xy 388.9883 -396.345664) (xy 388.983728 -396.352014) (xy 388.977378 -396.370048) (xy 388.974942 -396.379059)
			(xy 388.976001 -396.397679) (xy 388.97941 -396.40637) (xy 388.980172 -396.408148) (xy 389.020558 -396.488666)
			(xy 389.025115 -396.495979) (xy 389.038121 -396.507265) (xy 389.054133 -396.513602) (xy 389.062722 -396.51432)
			(xy 389.734044 -396.51432) (xy 389.74411 -396.514752) (xy 389.762701 -396.52248) (xy 389.770112 -396.529306)
			(xy 390.414002 -397.173196) (xy 390.422383 -397.180606) (xy 390.443471 -397.187994) (xy 390.454642 -397.18742)
			(xy 390.53262 -397.179546) (xy 390.537954 -397.178784) (xy 390.547279 -397.176415) (xy 390.563336 -397.165841)
			(xy 390.569196 -397.15821) (xy 390.56945 -397.157702) (xy 390.569704 -397.157448) (xy 390.576329 -397.14774)
			(xy 390.590433 -397.128934) (xy 390.597898 -397.119856) (xy 390.603994 -397.11249) (xy 390.609582 -397.095472)
			(xy 390.609582 -397.086074) (xy 390.609074 -397.07185) (xy 390.60755 -397.018764) (xy 390.606963 -397.010413)
			(xy 390.601143 -396.994727) (xy 390.59612 -396.98803) (xy 390.592564 -396.983966) (xy 390.591548 -396.98295)
			(xy 390.572422 -396.961714) (xy 390.53904 -396.915326) (xy 390.511687 -396.865146) (xy 390.490789 -396.811953)
			(xy 390.47667 -396.756573) (xy 390.46955 -396.699867) (xy 390.46912 -396.671292) (xy 390.469596 -396.641545)
			(xy 390.477304 -396.582553) (xy 390.49259 -396.525056) (xy 390.515196 -396.470024) (xy 390.54474 -396.418384)
			(xy 390.580726 -396.371007) (xy 390.622546 -396.328691) (xy 390.669495 -396.29215) (xy 390.720783 -396.261998)
			(xy 390.775544 -396.238745) (xy 390.832857 -396.222782) (xy 390.891754 -396.214379) (xy 390.921494 -396.213584)
			(xy 390.931324 -396.213021) (xy 390.949473 -396.205431) (xy 390.9568 -396.198852) (xy 391.408666 -395.746986)
			(xy 391.426369 -395.729914) (xy 391.466147 -395.700994) (xy 391.509962 -395.678659) (xy 391.556735 -395.663461)
			(xy 391.60531 -395.655776) (xy 391.6299 -395.655292) (xy 392.881866 -395.655292) (xy 392.887799 -395.655166)
			(xy 392.899352 -395.652474) (xy 392.904726 -395.649958) (xy 392.919966 -395.642338) (xy 392.924587 -395.639867)
			(xy 392.932776 -395.633332) (xy 392.936222 -395.629384) (xy 392.981434 -395.575028) (xy 392.987202 -395.566399)
			(xy 392.991914 -395.546206) (xy 392.990578 -395.535912) (xy 392.990578 -395.535404) (xy 392.989562 -395.531086)
			(xy 392.986951 -395.514957) (xy 392.984154 -395.4824) (xy 392.983974 -395.466062) (xy 392.983974 -395.463014)
			(xy 392.984482 -395.454632) (xy 392.985734 -395.427929) (xy 392.994782 -395.375242) (xy 393.011096 -395.324334)
			(xy 393.034355 -395.276201) (xy 393.064105 -395.231786) (xy 393.099762 -395.191958) (xy 393.140629 -395.157496)
			(xy 393.185906 -395.129075) (xy 393.234707 -395.107252) (xy 393.286076 -395.092454) (xy 393.339007 -395.08497)
			(xy 393.365736 -395.084554) (xy 393.392917 -395.085037) (xy 393.446729 -395.092758) (xy 393.4989 -395.108039)
			(xy 393.548374 -395.130571) (xy 393.594149 -395.159896) (xy 393.635298 -395.195422) (xy 393.670988 -395.236428)
			(xy 393.700496 -395.282086) (xy 393.723225 -395.331469) (xy 393.738714 -395.383578) (xy 393.746651 -395.437359)
			(xy 393.747244 -395.464538) (xy 393.747244 -395.466316) (xy 393.746614 -395.497361) (xy 393.736533 -395.558628)
			(xy 393.727178 -395.588236) (xy 393.724384 -395.59611) (xy 393.724384 -395.604492) (xy 393.72487 -395.614502)
			(xy 393.732528 -395.632999) (xy 393.746681 -395.647159) (xy 393.765174 -395.654825) (xy 393.775184 -395.655292)
			(xy 393.819126 -395.655292) (xy 393.829022 -395.654768) (xy 393.84731 -395.64718) (xy 393.854686 -395.64056)
			(xy 395.83487 -393.660376) (xy 395.839442 -393.656058) (xy 395.839442 -393.655804) (xy 395.99108 -393.504166)
			(xy 396.008782 -393.487091) (xy 396.048557 -393.458165) (xy 396.092373 -393.435827) (xy 396.139146 -393.420627)
			(xy 396.187723 -393.412941) (xy 396.212314 -393.412472) (xy 398.343374 -393.412472) (xy 398.367966 -393.412927)
			(xy 398.416545 -393.42062) (xy 398.463321 -393.435819) (xy 398.507143 -393.458151) (xy 398.54693 -393.487066)
			(xy 398.564608 -393.504166) (xy 399.24228 -394.182092) (xy 399.249692 -394.188776) (xy 399.268125 -394.196373)
			(xy 399.288063 -394.196373) (xy 399.306496 -394.188776) (xy 399.313908 -394.182092) (xy 399.34134 -394.15466)
			(xy 399.347182 -394.124688) (xy 399.34134 -394.110464) (xy 399.332124 -394.087184) (xy 399.319136 -394.03883)
			(xy 399.312569 -393.989194) (xy 399.31213 -393.96416) (xy 399.312619 -393.936912) (xy 399.32038 -393.88297)
			(xy 399.335739 -393.830683) (xy 399.358383 -393.781113) (xy 399.387851 -393.73527) (xy 399.423543 -393.694088)
			(xy 399.464733 -393.658404) (xy 399.510581 -393.628946) (xy 399.560156 -393.606312) (xy 399.612447 -393.590964)
			(xy 399.66639 -393.583213) (xy 399.693638 -393.582652) (xy 399.722275 -393.583161) (xy 399.778905 -393.591714)
			(xy 399.833621 -393.608638) (xy 399.885191 -393.633551) (xy 399.932457 -393.665895) (xy 399.974357 -393.704942)
			(xy 400.009948 -393.749813) (xy 400.0246 -393.774422) (xy 400.02941 -393.78214) (xy 400.043338 -393.793811)
			(xy 400.060467 -393.799876) (xy 400.069558 -393.800076) (xy 400.172682 -393.798044) (xy 400.19605 -393.783566)
			(xy 400.202654 -393.771374) (xy 400.217603 -393.744131) (xy 400.253749 -393.693584) (xy 400.2964 -393.648391)
			(xy 400.344771 -393.609381) (xy 400.397974 -393.577272) (xy 400.455031 -393.552653) (xy 400.514892 -393.535976)
			(xy 400.57646 -393.527549) (xy 400.60753 -393.527026) (xy 400.637497 -393.527497) (xy 400.696918 -393.535324)
			(xy 400.754808 -393.55084) (xy 400.810178 -393.573779) (xy 400.862081 -393.60375) (xy 400.909627 -393.640239)
			(xy 400.952004 -393.682621) (xy 400.988486 -393.730173) (xy 401.018449 -393.782079) (xy 401.041381 -393.837452)
			(xy 401.056889 -393.895345) (xy 401.064707 -393.954767) (xy 401.065238 -393.984734) (xy 401.06471 -394.015611)
			(xy 401.05637 -394.0768) (xy 401.039886 -394.136314) (xy 401.015556 -394.193074) (xy 400.983822 -394.246052)
			(xy 400.94526 -394.294286) (xy 400.923252 -394.31595) (xy 400.915108 -394.324554) (xy 400.907031 -394.346797)
			(xy 400.907758 -394.358622) (xy 400.917156 -394.43914) (xy 400.919062 -394.45078) (xy 400.931778 -394.470615)
			(xy 400.94154 -394.47724) (xy 400.941794 -394.47724) (xy 400.967152 -394.492722) (xy 401.014015 -394.529244)
			(xy 401.055755 -394.571526) (xy 401.091669 -394.618856) (xy 401.121152 -394.670438) (xy 401.143709 -394.725404)
			(xy 401.158959 -394.782827) (xy 401.166645 -394.841741) (xy 401.167092 -394.871448) (xy 401.166597 -394.902105)
			(xy 401.158404 -394.962869) (xy 401.142173 -395.021996) (xy 401.118193 -395.078426) (xy 401.086894 -395.131149)
			(xy 401.048836 -395.179222) (xy 401.027138 -395.200886) (xy 401.019406 -395.209197) (xy 401.011432 -395.230419)
			(xy 401.013331 -395.25301) (xy 401.018502 -395.263116) (xy 401.03262 -395.288593) (xy 401.052664 -395.343276)
			(xy 401.062847 -395.40062) (xy 401.06346 -395.42974) (xy 401.063331 -395.442622) (xy 401.061296 -395.468306)
			(xy 401.059396 -395.481048) (xy 401.058126 -395.489684) (xy 401.061174 -395.506702) (xy 401.102322 -395.577568)
			(xy 401.11553 -395.588744) (xy 401.123912 -395.591792) (xy 401.144445 -395.599969) (xy 401.183169 -395.621269)
			(xy 401.218513 -395.647804) (xy 401.234402 -395.663166) (xy 402.369782 -396.798546) (xy 402.386857 -396.816248)
			(xy 402.415783 -396.856024) (xy 402.438122 -396.899839) (xy 402.453325 -396.946612) (xy 402.461014 -396.995189)
			(xy 402.461476 -397.01978) (xy 402.461476 -398.067022) (xy 402.461902 -398.077091) (xy 402.46962 -398.095692)
			(xy 402.476462 -398.10309) (xy 402.679916 -398.306544) (xy 402.686985 -398.313078) (xy 402.704609 -398.32078)
			(xy 402.714206 -398.32153) (xy 402.783802 -398.323816) (xy 402.793187 -398.323724) (xy 402.810913 -398.317607)
			(xy 402.818346 -398.311878) (xy 402.8186 -398.311624) (xy 402.839602 -398.294153) (xy 402.886534 -398.266206)
			(xy 402.937691 -398.24706) (xy 402.991441 -398.237327) (xy 403.018752 -398.236694) (xy 403.042733 -398.23716)
			(xy 403.090106 -398.244652) (xy 403.135725 -398.25946) (xy 403.178467 -398.281219) (xy 403.21728 -398.309394)
			(xy 403.251211 -398.343291) (xy 403.279424 -398.382077) (xy 403.301225 -398.424798) (xy 403.316077 -398.470402)
			(xy 403.323616 -398.517767) (xy 403.32406 -398.541748) (xy 403.32406 -398.542256) (xy 403.323806 -398.556988)
			(xy 403.323298 -398.567402) (xy 403.33041 -398.587214) (xy 403.388322 -398.64792) (xy 403.395797 -398.655081)
			(xy 403.414811 -398.663213) (xy 403.425152 -398.663668) (xy 403.812248 -398.663668) (xy 403.822583 -398.663184)
			(xy 403.84159 -398.655059) (xy 403.849078 -398.64792) (xy 403.900132 -398.593818) (xy 403.903548 -398.59008)
			(xy 403.908937 -398.581508) (xy 403.9108 -398.5768) (xy 403.914356 -398.567402) (xy 403.913848 -398.556988)
			(xy 403.913594 -398.542764) (xy 403.913594 -398.541748) (xy 403.914135 -398.516506) (xy 403.922482 -398.466717)
			(xy 403.938905 -398.418979) (xy 403.962958 -398.374594) (xy 403.993985 -398.33477) (xy 404.031141 -398.300592)
			(xy 404.073413 -398.272993) (xy 404.119649 -398.252724) (xy 404.16859 -398.240338) (xy 404.218902 -398.236171)
			(xy 404.269214 -398.240338) (xy 404.318155 -398.252724) (xy 404.364391 -398.272993) (xy 404.406663 -398.300592)
			(xy 404.443819 -398.33477) (xy 404.474846 -398.374594) (xy 404.498899 -398.418979) (xy 404.515322 -398.466717)
			(xy 404.523669 -398.516506) (xy 404.52421 -398.541748) (xy 404.52421 -398.542764) (xy 404.523956 -398.556988)
			(xy 404.523448 -398.567402) (xy 404.527004 -398.5768) (xy 404.528923 -398.581481) (xy 404.534297 -398.590049)
			(xy 404.537672 -398.593818) (xy 404.588218 -398.647412) (xy 404.588472 -398.647666) (xy 404.58898 -398.648174)
			(xy 404.59643 -398.655228) (xy 404.615306 -398.663221) (xy 404.625556 -398.663668) (xy 405.012398 -398.663668)
			(xy 405.022729 -398.663175) (xy 405.041722 -398.655037) (xy 405.049228 -398.64792) (xy 405.100282 -398.593818)
			(xy 405.103688 -398.590073) (xy 405.109071 -398.581501) (xy 405.11095 -398.5768) (xy 405.114506 -398.567402)
			(xy 405.113998 -398.556988) (xy 405.113744 -398.542764) (xy 405.113744 -398.541748) (xy 405.114285 -398.516506)
			(xy 405.122632 -398.466717) (xy 405.139055 -398.418979) (xy 405.163108 -398.374594) (xy 405.194135 -398.33477)
			(xy 405.231291 -398.300592) (xy 405.273563 -398.272993) (xy 405.319799 -398.252724) (xy 405.36874 -398.240338)
			(xy 405.419052 -398.236171) (xy 405.469364 -398.240338) (xy 405.518305 -398.252724) (xy 405.564541 -398.272993)
			(xy 405.606813 -398.300592) (xy 405.643969 -398.33477) (xy 405.674996 -398.374594) (xy 405.699049 -398.418979)
			(xy 405.715472 -398.466717) (xy 405.723819 -398.516506) (xy 405.72436 -398.541748) (xy 405.72436 -398.542764)
			(xy 405.724106 -398.556988) (xy 405.723598 -398.567402) (xy 405.727154 -398.5768) (xy 405.729075 -398.581479)
			(xy 405.734453 -398.590044) (xy 405.737822 -398.593818) (xy 405.788368 -398.647412) (xy 405.788622 -398.647666)
			(xy 405.78913 -398.64792) (xy 405.789384 -398.648428) (xy 405.789892 -398.648936) (xy 405.797303 -398.655617)
			(xy 405.815739 -398.663197) (xy 405.825706 -398.663668) (xy 406.08885 -398.663668) (xy 406.112718 -398.664063)
			(xy 406.159913 -398.67121) (xy 406.18283 -398.677892) (xy 406.183338 -398.678146) (xy 406.184354 -398.6784)
			(xy 406.190194 -398.679957) (xy 406.20226 -398.680608) (xy 406.20823 -398.67967) (xy 406.220676 -398.67713)
			(xy 406.296368 -398.615916) (xy 406.301159 -398.611769) (xy 406.30874 -398.601622) (xy 406.311354 -398.59585)
			(xy 406.31618 -398.584166) (xy 406.315418 -398.574768) (xy 406.31364 -398.542256) (xy 406.31364 -398.541748)
			(xy 406.314129 -398.517771) (xy 406.321667 -398.470413) (xy 406.336517 -398.424815) (xy 406.358315 -398.382101)
			(xy 406.386524 -398.343321) (xy 406.420449 -398.309429) (xy 406.459257 -398.281258) (xy 406.501993 -398.259502)
			(xy 406.547605 -398.244697) (xy 406.594971 -398.237206) (xy 406.618948 -398.236694) (xy 406.642772 -398.237155)
			(xy 406.68984 -398.244565) (xy 406.735186 -398.259197) (xy 406.777708 -398.280695) (xy 406.816374 -398.308539)
			(xy 406.850245 -398.342051) (xy 406.878499 -398.380418) (xy 406.900449 -398.422709) (xy 406.915563 -398.467896)
			(xy 406.923473 -398.514883) (xy 406.924256 -398.5387) (xy 406.924256 -398.542256) (xy 406.923815 -398.56527)
			(xy 406.916874 -398.610772) (xy 406.903202 -398.654723) (xy 406.893522 -398.675606) (xy 406.890474 -398.681702)
			(xy 406.888188 -398.694148) (xy 406.888442 -398.700752) (xy 406.889015 -398.707068) (xy 406.892872 -398.719146)
			(xy 406.896062 -398.724628) (xy 406.939496 -398.794224) (xy 406.94229 -398.798542) (xy 406.947119 -398.805451)
			(xy 406.960369 -398.815854) (xy 406.976285 -398.821373) (xy 406.984708 -398.821656) (xy 407.453338 -398.821656)
			(xy 407.459697 -398.821492) (xy 407.472034 -398.818407) (xy 407.477722 -398.81556) (xy 407.48331 -398.812258)
			(xy 407.492708 -398.803622) (xy 407.538428 -398.73047) (xy 407.541222 -398.724374) (xy 407.542515 -398.720811)
			(xy 407.544175 -398.713416) (xy 407.544524 -398.709642) (xy 407.544524 -398.686274) (xy 407.543 -398.674336)
			(xy 407.54046 -398.666462) (xy 407.540206 -398.665954) (xy 407.5319 -398.646398) (xy 407.520165 -398.605565)
			(xy 407.514201 -398.563499) (xy 407.51379 -398.542256) (xy 407.51379 -398.542002) (xy 407.51426 -398.518011)
			(xy 407.521766 -398.470619) (xy 407.536594 -398.424984) (xy 407.558377 -398.382231) (xy 407.58658 -398.343412)
			(xy 407.620509 -398.309483) (xy 407.659328 -398.281279) (xy 407.70208 -398.259495) (xy 407.747715 -398.244667)
			(xy 407.795107 -398.237161) (xy 407.819098 -398.236694) (xy 407.842924 -398.237152) (xy 407.889999 -398.244555)
			(xy 407.935351 -398.259182) (xy 407.97788 -398.280678) (xy 408.016553 -398.308521) (xy 408.05043 -398.342034)
			(xy 408.078689 -398.380403) (xy 408.100644 -398.422697) (xy 408.115761 -398.467889) (xy 408.123673 -398.51488)
			(xy 408.124406 -398.5387) (xy 408.124406 -398.542256) (xy 408.123965 -398.56527) (xy 408.117023 -398.610771)
			(xy 408.103349 -398.654721) (xy 408.093672 -398.675606) (xy 408.090624 -398.681702) (xy 408.088338 -398.694148)
			(xy 408.088592 -398.700752) (xy 408.089166 -398.707068) (xy 408.093026 -398.719144) (xy 408.096212 -398.724628)
			(xy 408.139646 -398.794224) (xy 408.14244 -398.798542) (xy 408.147271 -398.805445) (xy 408.160523 -398.815836)
			(xy 408.176438 -398.821338) (xy 408.184858 -398.821656) (xy 408.653234 -398.821656) (xy 408.659593 -398.821493)
			(xy 408.67193 -398.818409) (xy 408.677618 -398.81556) (xy 408.683206 -398.812258) (xy 408.692604 -398.803622)
			(xy 408.738324 -398.73047) (xy 408.741118 -398.724374) (xy 408.742411 -398.720811) (xy 408.744071 -398.713416)
			(xy 408.74442 -398.709642) (xy 408.74442 -398.686274) (xy 408.742896 -398.674336) (xy 408.740356 -398.666462)
			(xy 408.740102 -398.665954) (xy 408.731796 -398.646398) (xy 408.720061 -398.605565) (xy 408.714097 -398.563499)
			(xy 408.713686 -398.542256) (xy 408.713686 -398.542002) (xy 408.714156 -398.518011) (xy 408.721662 -398.470618)
			(xy 408.736489 -398.424984) (xy 408.758273 -398.38223) (xy 408.786476 -398.343411) (xy 408.820405 -398.309481)
			(xy 408.859223 -398.281277) (xy 408.901976 -398.259492) (xy 408.94761 -398.244664) (xy 408.995003 -398.237157)
			(xy 409.018994 -398.236694) (xy 409.042821 -398.237151) (xy 409.089895 -398.244554) (xy 409.135248 -398.259181)
			(xy 409.177778 -398.280677) (xy 409.216451 -398.308519) (xy 409.250329 -398.342032) (xy 409.278589 -398.380402)
			(xy 409.300544 -398.422696) (xy 409.315661 -398.467888) (xy 409.323573 -398.51488) (xy 409.324302 -398.5387)
			(xy 409.324302 -398.542256) (xy 409.323861 -398.56527) (xy 409.316919 -398.610771) (xy 409.303244 -398.654721)
			(xy 409.293568 -398.675606) (xy 409.29052 -398.681702) (xy 409.288234 -398.694148) (xy 409.288488 -398.700752)
			(xy 409.289062 -398.707068) (xy 409.292921 -398.719144) (xy 409.296108 -398.724628) (xy 409.339542 -398.794224)
			(xy 409.342336 -398.798542) (xy 409.347167 -398.805445) (xy 409.360419 -398.815837) (xy 409.376334 -398.821341)
			(xy 409.384754 -398.821656) (xy 409.85313 -398.821656) (xy 409.859489 -398.821493) (xy 409.871827 -398.81841)
			(xy 409.877514 -398.81556) (xy 409.883102 -398.812258) (xy 409.8925 -398.803622) (xy 409.93822 -398.73047)
			(xy 409.941014 -398.724374) (xy 409.942307 -398.720811) (xy 409.943968 -398.713416) (xy 409.944316 -398.709642)
			(xy 409.944316 -398.686274) (xy 409.942792 -398.674336) (xy 409.940252 -398.666462) (xy 409.939998 -398.665954)
			(xy 409.931692 -398.646398) (xy 409.919957 -398.605565) (xy 409.913994 -398.563499) (xy 409.913582 -398.542256)
			(xy 409.913582 -398.542002) (xy 409.914052 -398.51801) (xy 409.921558 -398.470618) (xy 409.936385 -398.424983)
			(xy 409.958169 -398.382229) (xy 409.986372 -398.34341) (xy 410.0203 -398.30948) (xy 410.059119 -398.281275)
			(xy 410.101872 -398.25949) (xy 410.147506 -398.244661) (xy 410.194898 -398.237153) (xy 410.21889 -398.236694)
			(xy 410.242717 -398.237151) (xy 410.289792 -398.244553) (xy 410.335145 -398.25918) (xy 410.377676 -398.280675)
			(xy 410.416349 -398.308518) (xy 410.450228 -398.342031) (xy 410.478488 -398.380401) (xy 410.500443 -398.422695)
			(xy 410.515561 -398.467887) (xy 410.523473 -398.51488) (xy 410.524198 -398.5387) (xy 410.524198 -398.542256)
			(xy 410.523757 -398.56527) (xy 410.516815 -398.610771) (xy 410.50314 -398.654721) (xy 410.493464 -398.675606)
			(xy 410.490416 -398.681702) (xy 410.48813 -398.694148) (xy 410.488384 -398.700752) (xy 410.488958 -398.707068)
			(xy 410.492817 -398.719145) (xy 410.496004 -398.724628) (xy 410.539438 -398.794224) (xy 410.542232 -398.798542)
			(xy 410.547063 -398.805446) (xy 410.560314 -398.815838) (xy 410.57623 -398.821344) (xy 410.58465 -398.821656)
			(xy 411.05328 -398.821656) (xy 411.059638 -398.821487) (xy 411.071969 -398.818393) (xy 411.077664 -398.81556)
			(xy 411.083252 -398.812258) (xy 411.09265 -398.803622) (xy 411.13837 -398.73047) (xy 411.141164 -398.724374)
			(xy 411.142458 -398.720811) (xy 411.14412 -398.713416) (xy 411.144466 -398.709642) (xy 411.144466 -398.686274)
			(xy 411.142942 -398.674336) (xy 411.140402 -398.666462) (xy 411.140148 -398.665954) (xy 411.131841 -398.646399)
			(xy 411.120104 -398.605565) (xy 411.11414 -398.563499) (xy 411.113732 -398.542256) (xy 411.113732 -398.542002)
			(xy 411.114254 -398.516747) (xy 411.122567 -398.466925) (xy 411.138968 -398.419151) (xy 411.163009 -398.374728)
			(xy 411.194033 -398.334868) (xy 411.231195 -398.300658) (xy 411.273481 -398.273032) (xy 411.319737 -398.252742)
			(xy 411.368702 -398.240342) (xy 411.41904 -398.236171) (xy 411.469378 -398.240342) (xy 411.518343 -398.252742)
			(xy 411.564599 -398.273032) (xy 411.606885 -398.300658) (xy 411.644047 -398.334868) (xy 411.675071 -398.374728)
			(xy 411.699112 -398.419151) (xy 411.715513 -398.466925) (xy 411.723826 -398.516747) (xy 411.724348 -398.542002)
			(xy 412.313132 -398.542002) (xy 412.317092 -398.492948) (xy 412.328869 -398.445164) (xy 412.34816 -398.399888)
			(xy 412.374463 -398.358292) (xy 412.407098 -398.321455) (xy 412.445219 -398.29033) (xy 412.48784 -398.265723)
			(xy 412.533856 -398.248271) (xy 412.582075 -398.238427) (xy 412.63125 -398.236446) (xy 412.680105 -398.242378)
			(xy 412.727376 -398.25607) (xy 412.771838 -398.277168) (xy 412.812341 -398.305124) (xy 412.847834 -398.339216)
			(xy 412.877399 -398.37856) (xy 412.90027 -398.422137) (xy 412.915854 -398.468818) (xy 412.923749 -398.517395)
			(xy 412.924244 -398.542002) (xy 413.513282 -398.542002) (xy 413.517242 -398.492948) (xy 413.529019 -398.445164)
			(xy 413.54831 -398.399888) (xy 413.574613 -398.358292) (xy 413.607248 -398.321455) (xy 413.645369 -398.29033)
			(xy 413.68799 -398.265723) (xy 413.734006 -398.248271) (xy 413.782225 -398.238427) (xy 413.8314 -398.236446)
			(xy 413.880255 -398.242378) (xy 413.927526 -398.25607) (xy 413.971988 -398.277168) (xy 414.012491 -398.305124)
			(xy 414.047984 -398.339216) (xy 414.077549 -398.37856) (xy 414.10042 -398.422137) (xy 414.116004 -398.468818)
			(xy 414.123899 -398.517395) (xy 414.124394 -398.542002) (xy 414.713178 -398.542002) (xy 414.717138 -398.492948)
			(xy 414.728915 -398.445164) (xy 414.748206 -398.399888) (xy 414.774509 -398.358292) (xy 414.807144 -398.321455)
			(xy 414.845265 -398.29033) (xy 414.887886 -398.265723) (xy 414.933902 -398.248271) (xy 414.982121 -398.238427)
			(xy 415.031296 -398.236446) (xy 415.080151 -398.242378) (xy 415.127422 -398.25607) (xy 415.171884 -398.277168)
			(xy 415.212387 -398.305124) (xy 415.24788 -398.339216) (xy 415.277445 -398.37856) (xy 415.300316 -398.422137)
			(xy 415.3159 -398.468818) (xy 415.323795 -398.517395) (xy 415.32429 -398.542002) (xy 415.913074 -398.542002)
			(xy 415.917034 -398.492948) (xy 415.928811 -398.445164) (xy 415.948102 -398.399888) (xy 415.974405 -398.358292)
			(xy 416.00704 -398.321455) (xy 416.045161 -398.29033) (xy 416.087782 -398.265723) (xy 416.133798 -398.248271)
			(xy 416.182017 -398.238427) (xy 416.231192 -398.236446) (xy 416.280047 -398.242378) (xy 416.327318 -398.25607)
			(xy 416.37178 -398.277168) (xy 416.412283 -398.305124) (xy 416.447776 -398.339216) (xy 416.477341 -398.37856)
			(xy 416.500212 -398.422137) (xy 416.515796 -398.468818) (xy 416.523691 -398.517395) (xy 416.524186 -398.542002)
			(xy 417.113224 -398.542002) (xy 417.117184 -398.492948) (xy 417.128961 -398.445164) (xy 417.148252 -398.399888)
			(xy 417.174555 -398.358292) (xy 417.20719 -398.321455) (xy 417.245311 -398.29033) (xy 417.287932 -398.265723)
			(xy 417.333948 -398.248271) (xy 417.382167 -398.238427) (xy 417.431342 -398.236446) (xy 417.480197 -398.242378)
			(xy 417.527468 -398.25607) (xy 417.57193 -398.277168) (xy 417.612433 -398.305124) (xy 417.647926 -398.339216)
			(xy 417.677491 -398.37856) (xy 417.700362 -398.422137) (xy 417.715946 -398.468818) (xy 417.723841 -398.517395)
			(xy 417.724336 -398.542002) (xy 418.31312 -398.542002) (xy 418.31708 -398.492948) (xy 418.328857 -398.445164)
			(xy 418.348148 -398.399888) (xy 418.374451 -398.358292) (xy 418.407086 -398.321455) (xy 418.445207 -398.29033)
			(xy 418.487828 -398.265723) (xy 418.533844 -398.248271) (xy 418.582063 -398.238427) (xy 418.631238 -398.236446)
			(xy 418.680093 -398.242378) (xy 418.727364 -398.25607) (xy 418.771826 -398.277168) (xy 418.812329 -398.305124)
			(xy 418.847822 -398.339216) (xy 418.877387 -398.37856) (xy 418.900258 -398.422137) (xy 418.915842 -398.468818)
			(xy 418.923737 -398.517395) (xy 418.924232 -398.542002) (xy 419.51327 -398.542002) (xy 419.51723 -398.492948)
			(xy 419.529007 -398.445164) (xy 419.548298 -398.399888) (xy 419.574601 -398.358292) (xy 419.607236 -398.321455)
			(xy 419.645357 -398.29033) (xy 419.687978 -398.265723) (xy 419.733994 -398.248271) (xy 419.782213 -398.238427)
			(xy 419.831388 -398.236446) (xy 419.880243 -398.242378) (xy 419.927514 -398.25607) (xy 419.971976 -398.277168)
			(xy 420.012479 -398.305124) (xy 420.047972 -398.339216) (xy 420.077537 -398.37856) (xy 420.100408 -398.422137)
			(xy 420.115992 -398.468818) (xy 420.123887 -398.517395) (xy 420.124382 -398.542002) (xy 420.713166 -398.542002)
			(xy 420.717126 -398.492948) (xy 420.728903 -398.445164) (xy 420.748194 -398.399888) (xy 420.774497 -398.358292)
			(xy 420.807132 -398.321455) (xy 420.845253 -398.29033) (xy 420.887874 -398.265723) (xy 420.93389 -398.248271)
			(xy 420.982109 -398.238427) (xy 421.031284 -398.236446) (xy 421.080139 -398.242378) (xy 421.12741 -398.25607)
			(xy 421.171872 -398.277168) (xy 421.212375 -398.305124) (xy 421.247868 -398.339216) (xy 421.277433 -398.37856)
			(xy 421.300304 -398.422137) (xy 421.315888 -398.468818) (xy 421.323783 -398.517395) (xy 421.324278 -398.542002)
			(xy 421.323783 -398.566609) (xy 421.323559 -398.567989) (xy 422.042846 -398.567989) (xy 422.042846 -398.516015)
			(xy 422.050976 -398.46468) (xy 422.067037 -398.41525) (xy 422.090633 -398.36894) (xy 422.121183 -398.326892)
			(xy 422.157934 -398.290141) (xy 422.199982 -398.259591) (xy 422.246292 -398.235995) (xy 422.295722 -398.219934)
			(xy 422.347057 -398.211804) (xy 422.399031 -398.211804) (xy 422.450366 -398.219934) (xy 422.499796 -398.235995)
			(xy 422.546106 -398.259591) (xy 422.588154 -398.290141) (xy 422.624905 -398.326892) (xy 422.655455 -398.36894)
			(xy 422.679051 -398.41525) (xy 422.695112 -398.46468) (xy 422.703242 -398.516015) (xy 422.703752 -398.542002)
			(xy 422.703242 -398.567989) (xy 422.695112 -398.619324) (xy 422.679051 -398.668754) (xy 422.655455 -398.715064)
			(xy 422.624905 -398.757112) (xy 422.588154 -398.793863) (xy 422.546106 -398.824413) (xy 422.499796 -398.848009)
			(xy 422.450366 -398.86407) (xy 422.399031 -398.8722) (xy 422.347057 -398.8722) (xy 422.295722 -398.86407)
			(xy 422.246292 -398.848009) (xy 422.199982 -398.824413) (xy 422.157934 -398.793863) (xy 422.121183 -398.757112)
			(xy 422.090633 -398.715064) (xy 422.067037 -398.668754) (xy 422.050976 -398.619324) (xy 422.042846 -398.567989)
			(xy 421.323559 -398.567989) (xy 421.315888 -398.615186) (xy 421.300304 -398.661867) (xy 421.277433 -398.705444)
			(xy 421.247868 -398.744788) (xy 421.212375 -398.77888) (xy 421.171872 -398.806836) (xy 421.12741 -398.827934)
			(xy 421.080139 -398.841626) (xy 421.031284 -398.847558) (xy 420.982109 -398.845577) (xy 420.93389 -398.835733)
			(xy 420.887874 -398.818281) (xy 420.845253 -398.793674) (xy 420.807132 -398.762549) (xy 420.774497 -398.725712)
			(xy 420.748194 -398.684116) (xy 420.728903 -398.63884) (xy 420.717126 -398.591056) (xy 420.713166 -398.542002)
			(xy 420.124382 -398.542002) (xy 420.123887 -398.566609) (xy 420.115992 -398.615186) (xy 420.100408 -398.661867)
			(xy 420.077537 -398.705444) (xy 420.047972 -398.744788) (xy 420.012479 -398.77888) (xy 419.971976 -398.806836)
			(xy 419.927514 -398.827934) (xy 419.880243 -398.841626) (xy 419.831388 -398.847558) (xy 419.782213 -398.845577)
			(xy 419.733994 -398.835733) (xy 419.687978 -398.818281) (xy 419.645357 -398.793674) (xy 419.607236 -398.762549)
			(xy 419.574601 -398.725712) (xy 419.548298 -398.684116) (xy 419.529007 -398.63884) (xy 419.51723 -398.591056)
			(xy 419.51327 -398.542002) (xy 418.924232 -398.542002) (xy 418.923737 -398.566609) (xy 418.915842 -398.615186)
			(xy 418.900258 -398.661867) (xy 418.877387 -398.705444) (xy 418.847822 -398.744788) (xy 418.812329 -398.77888)
			(xy 418.771826 -398.806836) (xy 418.727364 -398.827934) (xy 418.680093 -398.841626) (xy 418.631238 -398.847558)
			(xy 418.582063 -398.845577) (xy 418.533844 -398.835733) (xy 418.487828 -398.818281) (xy 418.445207 -398.793674)
			(xy 418.407086 -398.762549) (xy 418.374451 -398.725712) (xy 418.348148 -398.684116) (xy 418.328857 -398.63884)
			(xy 418.31708 -398.591056) (xy 418.31312 -398.542002) (xy 417.724336 -398.542002) (xy 417.723841 -398.566609)
			(xy 417.715946 -398.615186) (xy 417.700362 -398.661867) (xy 417.677491 -398.705444) (xy 417.647926 -398.744788)
			(xy 417.612433 -398.77888) (xy 417.57193 -398.806836) (xy 417.527468 -398.827934) (xy 417.480197 -398.841626)
			(xy 417.431342 -398.847558) (xy 417.382167 -398.845577) (xy 417.333948 -398.835733) (xy 417.287932 -398.818281)
			(xy 417.245311 -398.793674) (xy 417.20719 -398.762549) (xy 417.174555 -398.725712) (xy 417.148252 -398.684116)
			(xy 417.128961 -398.63884) (xy 417.117184 -398.591056) (xy 417.113224 -398.542002) (xy 416.524186 -398.542002)
			(xy 416.523691 -398.566609) (xy 416.515796 -398.615186) (xy 416.500212 -398.661867) (xy 416.477341 -398.705444)
			(xy 416.447776 -398.744788) (xy 416.412283 -398.77888) (xy 416.37178 -398.806836) (xy 416.327318 -398.827934)
			(xy 416.280047 -398.841626) (xy 416.231192 -398.847558) (xy 416.182017 -398.845577) (xy 416.133798 -398.835733)
			(xy 416.087782 -398.818281) (xy 416.045161 -398.793674) (xy 416.00704 -398.762549) (xy 415.974405 -398.725712)
			(xy 415.948102 -398.684116) (xy 415.928811 -398.63884) (xy 415.917034 -398.591056) (xy 415.913074 -398.542002)
			(xy 415.32429 -398.542002) (xy 415.323795 -398.566609) (xy 415.3159 -398.615186) (xy 415.300316 -398.661867)
			(xy 415.277445 -398.705444) (xy 415.24788 -398.744788) (xy 415.212387 -398.77888) (xy 415.171884 -398.806836)
			(xy 415.127422 -398.827934) (xy 415.080151 -398.841626) (xy 415.031296 -398.847558) (xy 414.982121 -398.845577)
			(xy 414.933902 -398.835733) (xy 414.887886 -398.818281) (xy 414.845265 -398.793674) (xy 414.807144 -398.762549)
			(xy 414.774509 -398.725712) (xy 414.748206 -398.684116) (xy 414.728915 -398.63884) (xy 414.717138 -398.591056)
			(xy 414.713178 -398.542002) (xy 414.124394 -398.542002) (xy 414.123899 -398.566609) (xy 414.116004 -398.615186)
			(xy 414.10042 -398.661867) (xy 414.077549 -398.705444) (xy 414.047984 -398.744788) (xy 414.012491 -398.77888)
			(xy 413.971988 -398.806836) (xy 413.927526 -398.827934) (xy 413.880255 -398.841626) (xy 413.8314 -398.847558)
			(xy 413.782225 -398.845577) (xy 413.734006 -398.835733) (xy 413.68799 -398.818281) (xy 413.645369 -398.793674)
			(xy 413.607248 -398.762549) (xy 413.574613 -398.725712) (xy 413.54831 -398.684116) (xy 413.529019 -398.63884)
			(xy 413.517242 -398.591056) (xy 413.513282 -398.542002) (xy 412.924244 -398.542002) (xy 412.923749 -398.566609)
			(xy 412.915854 -398.615186) (xy 412.90027 -398.661867) (xy 412.877399 -398.705444) (xy 412.847834 -398.744788)
			(xy 412.812341 -398.77888) (xy 412.771838 -398.806836) (xy 412.727376 -398.827934) (xy 412.680105 -398.841626)
			(xy 412.63125 -398.847558) (xy 412.582075 -398.845577) (xy 412.533856 -398.835733) (xy 412.48784 -398.818281)
			(xy 412.445219 -398.793674) (xy 412.407098 -398.762549) (xy 412.374463 -398.725712) (xy 412.34816 -398.684116)
			(xy 412.328869 -398.63884) (xy 412.317092 -398.591056) (xy 412.313132 -398.542002) (xy 411.724348 -398.542002)
			(xy 411.724194 -398.554764) (xy 411.722034 -398.580197) (xy 411.72003 -398.592802) (xy 411.720284 -398.592802)
			(xy 411.71552 -398.618046) (xy 411.698673 -398.666574) (xy 411.673939 -398.711596) (xy 411.642017 -398.751842)
			(xy 411.603806 -398.786175) (xy 411.582362 -398.80032) (xy 411.579568 -398.802098) (xy 411.571347 -398.808737)
			(xy 411.560728 -398.826979) (xy 411.558994 -398.837404) (xy 411.555438 -398.869662) (xy 411.550104 -398.919192)
			(xy 411.549966 -398.926135) (xy 411.553058 -398.939669) (xy 411.5562 -398.945862) (xy 411.55799 -398.949039)
			(xy 411.562322 -398.954905) (xy 411.564836 -398.957546) (xy 412.64713 -400.03984) (xy 412.654714 -400.046731)
			(xy 412.673717 -400.054344) (xy 412.68396 -400.054572) (xy 412.742888 -400.050508) (xy 412.7627 -400.049238)
			(xy 412.771741 -400.048234) (xy 412.788269 -400.040672) (xy 412.794958 -400.034506) (xy 412.800038 -400.029426)
			(xy 412.80207 -400.026886) (xy 412.816607 -400.008657) (xy 412.850278 -399.976411) (xy 412.888465 -399.949664)
			(xy 412.930277 -399.92904) (xy 412.974741 -399.91502) (xy 413.020821 -399.907929) (xy 413.044132 -399.907506)
			(xy 413.068121 -399.907979) (xy 413.115508 -399.915489) (xy 413.161137 -399.93032) (xy 413.203884 -399.952105)
			(xy 413.242697 -399.980309) (xy 413.276621 -400.014238) (xy 413.304819 -400.053055) (xy 413.326598 -400.095806)
			(xy 413.341422 -400.141437) (xy 413.348925 -400.188825) (xy 413.34944 -400.212814) (xy 413.348969 -400.236828)
			(xy 413.341463 -400.284265) (xy 413.326635 -400.329947) (xy 413.304852 -400.37275) (xy 413.276648 -400.411624)
			(xy 413.260032 -400.428968) (xy 413.257492 -400.431508) (xy 413.253936 -400.440398) (xy 413.252264 -400.445173)
			(xy 413.250602 -400.455151) (xy 413.250634 -400.46021) (xy 413.250888 -400.46529) (xy 413.251761 -400.476744)
			(xy 413.262334 -400.497112) (xy 413.271208 -400.504406) (xy 413.271462 -400.504406) (xy 413.294222 -400.521895)
			(xy 413.334725 -400.562564) (xy 413.368682 -400.608839) (xy 413.395326 -400.659677) (xy 413.414058 -400.713931)
			(xy 413.424456 -400.770379) (xy 413.425894 -400.799046) (xy 413.426148 -400.808698) (xy 413.433768 -400.826478)
			(xy 413.775906 -401.168616) (xy 413.783335 -401.175423) (xy 413.801952 -401.18309) (xy 413.822086 -401.183043)
			(xy 413.831532 -401.179538) (xy 413.845756 -401.173696) (xy 413.86252 -401.148296) (xy 413.86252 -400.811238)
			(xy 413.862963 -400.78488) (xy 413.870218 -400.732664) (xy 413.884596 -400.681946) (xy 413.905822 -400.633692)
			(xy 413.933492 -400.58882) (xy 413.967078 -400.548188) (xy 413.986218 -400.53006) (xy 413.993076 -400.52371)
			(xy 414.001458 -400.506946) (xy 414.008824 -400.429476) (xy 414.009317 -400.420301) (xy 414.004511 -400.402583)
			(xy 413.999426 -400.394932) (xy 413.999172 -400.394678) (xy 413.985014 -400.374834) (xy 413.962526 -400.331586)
			(xy 413.947207 -400.28531) (xy 413.939448 -400.237187) (xy 413.938974 -400.212814) (xy 413.939496 -400.187559)
			(xy 413.947809 -400.137737) (xy 413.96421 -400.089963) (xy 413.988251 -400.04554) (xy 414.019275 -400.00568)
			(xy 414.056437 -399.97147) (xy 414.098723 -399.943844) (xy 414.144979 -399.923554) (xy 414.193944 -399.911154)
			(xy 414.244282 -399.906983) (xy 414.29462 -399.911154) (xy 414.343585 -399.923554) (xy 414.389841 -399.943844)
			(xy 414.432127 -399.97147) (xy 414.469289 -400.00568) (xy 414.500313 -400.04554) (xy 414.524354 -400.089963)
			(xy 414.540755 -400.137737) (xy 414.549068 -400.187559) (xy 414.54959 -400.212814) (xy 414.549122 -400.237145)
			(xy 414.541406 -400.28519) (xy 414.526157 -400.3314) (xy 414.503762 -400.374602) (xy 414.489646 -400.394424)
			(xy 414.489138 -400.394932) (xy 414.483804 -400.402298) (xy 414.478978 -400.420332) (xy 414.486344 -400.497548)
			(xy 414.48759 -400.506769) (xy 414.4958 -400.523447) (xy 414.502346 -400.53006) (xy 414.521469 -400.548202)
			(xy 414.555043 -400.588839) (xy 414.582704 -400.63371) (xy 414.603926 -400.681961) (xy 414.618306 -400.732673)
			(xy 414.625569 -400.784882) (xy 414.626044 -400.811238) (xy 414.626044 -401.674838) (xy 414.625496 -401.703698)
			(xy 414.616763 -401.760756) (xy 414.599534 -401.815846) (xy 414.5742 -401.867711) (xy 414.558226 -401.891754)
			(xy 414.553475 -401.899272) (xy 414.54893 -401.916451) (xy 414.550511 -401.93415) (xy 414.55803 -401.950251)
			(xy 414.564068 -401.956778) (xy 414.942782 -402.335492) (xy 414.949846 -402.341936) (xy 414.96738 -402.349527)
			(xy 414.986474 -402.350231) (xy 414.995614 -402.34743) (xy 415.068004 -402.32203) (xy 415.074651 -402.319464)
			(xy 415.086258 -402.311211) (xy 415.090864 -402.305774) (xy 415.115248 -402.27504) (xy 415.116264 -402.269198)
			(xy 415.120841 -402.237854) (xy 415.140409 -402.177615) (xy 415.155126 -402.149564) (xy 415.169466 -402.124958)
			(xy 415.205218 -402.080633) (xy 415.226246 -402.061426) (xy 415.230818 -402.05279) (xy 415.235136 -402.041106)
			(xy 415.236406 -402.029676) (xy 415.236406 -402.021294) (xy 415.235786 -402.009448) (xy 415.22519 -401.988258)
			(xy 415.216086 -401.980654) (xy 415.192748 -401.96252) (xy 415.151427 -401.920266) (xy 415.117112 -401.872147)
			(xy 415.090624 -401.819315) (xy 415.072595 -401.763032) (xy 415.063457 -401.704642) (xy 415.062924 -401.675092)
			(xy 415.062924 -400.810984) (xy 415.06336 -400.784686) (xy 415.07058 -400.732587) (xy 415.084894 -400.681976)
			(xy 415.106031 -400.633813) (xy 415.133589 -400.589014) (xy 415.167045 -400.548429) (xy 415.186114 -400.530314)
			(xy 415.192734 -400.523654) (xy 415.20108 -400.506849) (xy 415.20237 -400.497548) (xy 415.209736 -400.420586)
			(xy 415.204656 -400.402298) (xy 415.199068 -400.394932) (xy 415.184905 -400.375054) (xy 415.162412 -400.33174)
			(xy 415.147091 -400.285402) (xy 415.13933 -400.237217) (xy 415.13887 -400.212814) (xy 415.139392 -400.187559)
			(xy 415.147705 -400.137737) (xy 415.164106 -400.089963) (xy 415.188147 -400.04554) (xy 415.219171 -400.00568)
			(xy 415.256333 -399.97147) (xy 415.298619 -399.943844) (xy 415.344875 -399.923554) (xy 415.39384 -399.911154)
			(xy 415.444178 -399.906983) (xy 415.494516 -399.911154) (xy 415.543481 -399.923554) (xy 415.589737 -399.943844)
			(xy 415.632023 -399.97147) (xy 415.669185 -400.00568) (xy 415.700209 -400.04554) (xy 415.72425 -400.089963)
			(xy 415.740651 -400.137737) (xy 415.748964 -400.187559) (xy 415.749486 -400.212814) (xy 415.749486 -400.213068)
			(xy 415.749014 -400.237397) (xy 415.741291 -400.285439) (xy 415.726035 -400.331644) (xy 415.703634 -400.374839)
			(xy 415.689542 -400.394678) (xy 415.683954 -400.402044) (xy 415.678874 -400.420332) (xy 415.68624 -400.497294)
			(xy 415.687458 -400.506617) (xy 415.695815 -400.523444) (xy 415.702496 -400.53006) (xy 415.721587 -400.54822)
			(xy 415.755097 -400.588881) (xy 415.782704 -400.63376) (xy 415.803882 -400.682006) (xy 415.818232 -400.732704)
			(xy 415.825479 -400.784893) (xy 415.82594 -400.811238) (xy 415.82594 -401.674838) (xy 416.26282 -401.674838)
			(xy 416.26282 -400.811238) (xy 416.263262 -400.784892) (xy 416.27051 -400.732702) (xy 416.284862 -400.682002)
			(xy 416.306044 -400.633756) (xy 416.333655 -400.588877) (xy 416.367171 -400.548219) (xy 416.386264 -400.53006)
			(xy 416.392812 -400.523449) (xy 416.401021 -400.506769) (xy 416.402266 -400.497548) (xy 416.409632 -400.420332)
			(xy 416.404806 -400.402298) (xy 416.399472 -400.394932) (xy 416.398964 -400.394424) (xy 416.384849 -400.374601)
			(xy 416.362453 -400.3314) (xy 416.347204 -400.28519) (xy 416.339488 -400.237145) (xy 416.33902 -400.212814)
			(xy 416.339542 -400.187559) (xy 416.347855 -400.137737) (xy 416.364256 -400.089963) (xy 416.388297 -400.04554)
			(xy 416.419321 -400.00568) (xy 416.456483 -399.97147) (xy 416.498769 -399.943844) (xy 416.545025 -399.923554)
			(xy 416.59399 -399.911154) (xy 416.644328 -399.906983) (xy 416.694666 -399.911154) (xy 416.743631 -399.923554)
			(xy 416.789887 -399.943844) (xy 416.832173 -399.97147) (xy 416.869335 -400.00568) (xy 416.900359 -400.04554)
			(xy 416.9244 -400.089963) (xy 416.940801 -400.137737) (xy 416.949114 -400.187559) (xy 416.949636 -400.212814)
			(xy 416.94916 -400.237186) (xy 416.941401 -400.28531) (xy 416.926083 -400.331585) (xy 416.903596 -400.374833)
			(xy 416.889438 -400.394678) (xy 416.889184 -400.394932) (xy 416.8841 -400.402583) (xy 416.879293 -400.420302)
			(xy 416.879786 -400.429476) (xy 416.887152 -400.506946) (xy 416.895534 -400.52371) (xy 416.902392 -400.53006)
			(xy 416.921503 -400.548201) (xy 416.955022 -400.588861) (xy 416.982633 -400.633742) (xy 417.003813 -400.681992)
			(xy 417.018158 -400.732696) (xy 417.025396 -400.784891) (xy 417.025836 -400.811238) (xy 417.025836 -401.674838)
			(xy 417.025832 -401.675092) (xy 417.462716 -401.675092) (xy 417.462716 -400.811238) (xy 417.463159 -400.784892)
			(xy 417.470408 -400.732702) (xy 417.484759 -400.682002) (xy 417.505941 -400.633756) (xy 417.533552 -400.588878)
			(xy 417.567067 -400.548219) (xy 417.58616 -400.53006) (xy 417.592707 -400.523448) (xy 417.600917 -400.506769)
			(xy 417.602162 -400.497548) (xy 417.609528 -400.420332) (xy 417.604702 -400.402298) (xy 417.599368 -400.394932)
			(xy 417.59886 -400.394424) (xy 417.584745 -400.374601) (xy 417.562349 -400.3314) (xy 417.5471 -400.28519)
			(xy 417.539384 -400.237145) (xy 417.538916 -400.212814) (xy 417.539438 -400.187559) (xy 417.547751 -400.137737)
			(xy 417.564152 -400.089963) (xy 417.588193 -400.04554) (xy 417.619217 -400.00568) (xy 417.656379 -399.97147)
			(xy 417.698665 -399.943844) (xy 417.744921 -399.923554) (xy 417.793886 -399.911154) (xy 417.844224 -399.906983)
			(xy 417.894562 -399.911154) (xy 417.943527 -399.923554) (xy 417.989783 -399.943844) (xy 418.032069 -399.97147)
			(xy 418.069231 -400.00568) (xy 418.100255 -400.04554) (xy 418.124296 -400.089963) (xy 418.140697 -400.137737)
			(xy 418.14901 -400.187559) (xy 418.149532 -400.212814) (xy 418.149057 -400.237186) (xy 418.141298 -400.28531)
			(xy 418.125979 -400.331585) (xy 418.103492 -400.374833) (xy 418.089334 -400.394678) (xy 418.08908 -400.394932)
			(xy 418.083996 -400.402583) (xy 418.079189 -400.420302) (xy 418.079682 -400.429476) (xy 418.087048 -400.506946)
			(xy 418.09543 -400.52371) (xy 418.102288 -400.53006) (xy 418.121398 -400.548202) (xy 418.154917 -400.588861)
			(xy 418.182529 -400.633742) (xy 418.203708 -400.681992) (xy 418.218054 -400.732696) (xy 418.225292 -400.784891)
			(xy 418.225732 -400.811238) (xy 418.225732 -401.674838) (xy 418.662612 -401.674838) (xy 418.662612 -400.811238)
			(xy 418.663056 -400.784892) (xy 418.670305 -400.732702) (xy 418.684656 -400.682003) (xy 418.705838 -400.633756)
			(xy 418.733448 -400.588878) (xy 418.766963 -400.548219) (xy 418.786056 -400.53006) (xy 418.792603 -400.523448)
			(xy 418.800813 -400.506769) (xy 418.802058 -400.497548) (xy 418.809424 -400.420332) (xy 418.804598 -400.402298)
			(xy 418.799264 -400.394932) (xy 418.798756 -400.394424) (xy 418.78464 -400.374602) (xy 418.762245 -400.3314)
			(xy 418.746996 -400.28519) (xy 418.73928 -400.237145) (xy 418.738812 -400.212814) (xy 418.739334 -400.187559)
			(xy 418.747647 -400.137737) (xy 418.764048 -400.089963) (xy 418.788089 -400.04554) (xy 418.819113 -400.00568)
			(xy 418.856275 -399.97147) (xy 418.898561 -399.943844) (xy 418.944817 -399.923554) (xy 418.993782 -399.911154)
			(xy 419.04412 -399.906983) (xy 419.094458 -399.911154) (xy 419.143423 -399.923554) (xy 419.189679 -399.943844)
			(xy 419.231965 -399.97147) (xy 419.269127 -400.00568) (xy 419.300151 -400.04554) (xy 419.324192 -400.089963)
			(xy 419.340593 -400.137737) (xy 419.348906 -400.187559) (xy 419.349428 -400.212814) (xy 419.348954 -400.237187)
			(xy 419.341195 -400.28531) (xy 419.325876 -400.331586) (xy 419.303388 -400.374834) (xy 419.28923 -400.394678)
			(xy 419.288976 -400.394932) (xy 419.283891 -400.402583) (xy 419.279085 -400.420301) (xy 419.279578 -400.429476)
			(xy 419.286944 -400.506946) (xy 419.295326 -400.52371) (xy 419.302184 -400.53006) (xy 419.321294 -400.548203)
			(xy 419.354813 -400.588862) (xy 419.382425 -400.633742) (xy 419.403604 -400.681993) (xy 419.41795 -400.732696)
			(xy 419.425188 -400.784891) (xy 419.425628 -400.811238) (xy 419.425628 -401.674838) (xy 419.862508 -401.674838)
			(xy 419.862508 -400.811238) (xy 419.862966 -400.784881) (xy 419.87023 -400.732671) (xy 419.884612 -400.681957)
			(xy 419.905837 -400.633706) (xy 419.933502 -400.588836) (xy 419.96708 -400.548201) (xy 419.986206 -400.53006)
			(xy 419.992745 -400.523441) (xy 420.000961 -400.506768) (xy 420.002208 -400.497548) (xy 420.009574 -400.420332)
			(xy 420.004748 -400.402298) (xy 419.999414 -400.394932) (xy 419.998906 -400.394424) (xy 419.984796 -400.374597)
			(xy 419.962398 -400.331398) (xy 419.947147 -400.285189) (xy 419.93943 -400.237144) (xy 419.938962 -400.212814)
			(xy 419.939484 -400.187559) (xy 419.947797 -400.137737) (xy 419.964198 -400.089963) (xy 419.988239 -400.04554)
			(xy 420.019263 -400.00568) (xy 420.056425 -399.97147) (xy 420.098711 -399.943844) (xy 420.144967 -399.923554)
			(xy 420.193932 -399.911154) (xy 420.24427 -399.906983) (xy 420.294608 -399.911154) (xy 420.343573 -399.923554)
			(xy 420.389829 -399.943844) (xy 420.432115 -399.97147) (xy 420.469277 -400.00568) (xy 420.500301 -400.04554)
			(xy 420.524342 -400.089963) (xy 420.540743 -400.137737) (xy 420.549056 -400.187559) (xy 420.549578 -400.212814)
			(xy 420.549114 -400.237187) (xy 420.541353 -400.285311) (xy 420.526032 -400.331587) (xy 420.50354 -400.374834)
			(xy 420.48938 -400.394678) (xy 420.489126 -400.394932) (xy 420.484045 -400.402585) (xy 420.479235 -400.420302)
			(xy 420.479728 -400.429476) (xy 420.487094 -400.506946) (xy 420.495476 -400.52371) (xy 420.502334 -400.53006)
			(xy 420.521465 -400.548197) (xy 420.555054 -400.588827) (xy 420.582726 -400.633696) (xy 420.603954 -400.681949)
			(xy 420.618333 -400.732666) (xy 420.625589 -400.78488) (xy 420.626032 -400.811238) (xy 420.626032 -401.674838)
			(xy 421.062404 -401.674838) (xy 421.062404 -400.811238) (xy 421.062863 -400.784881) (xy 421.070127 -400.732671)
			(xy 421.084509 -400.681958) (xy 421.105734 -400.633706) (xy 421.133399 -400.588836) (xy 421.166977 -400.548201)
			(xy 421.186102 -400.53006) (xy 421.19264 -400.52344) (xy 421.200857 -400.506768) (xy 421.202104 -400.497548)
			(xy 421.20947 -400.420332) (xy 421.204644 -400.402298) (xy 421.19931 -400.394932) (xy 421.198802 -400.394424)
			(xy 421.184692 -400.374598) (xy 421.162294 -400.331398) (xy 421.147043 -400.285189) (xy 421.139326 -400.237144)
			(xy 421.138858 -400.212814) (xy 421.13938 -400.187559) (xy 421.147693 -400.137737) (xy 421.164094 -400.089963)
			(xy 421.188135 -400.04554) (xy 421.219159 -400.00568) (xy 421.256321 -399.97147) (xy 421.298607 -399.943844)
			(xy 421.344863 -399.923554) (xy 421.393828 -399.911154) (xy 421.444166 -399.906983) (xy 421.494504 -399.911154)
			(xy 421.543469 -399.923554) (xy 421.589725 -399.943844) (xy 421.632011 -399.97147) (xy 421.669173 -400.00568)
			(xy 421.700197 -400.04554) (xy 421.724238 -400.089963) (xy 421.740639 -400.137737) (xy 421.748952 -400.187559)
			(xy 421.749474 -400.212814) (xy 421.748991 -400.237186) (xy 421.741233 -400.285309) (xy 421.725916 -400.331584)
			(xy 421.703432 -400.374833) (xy 421.689276 -400.394678) (xy 421.689022 -400.394932) (xy 421.683941 -400.402585)
			(xy 421.679131 -400.420302) (xy 421.679624 -400.429476) (xy 421.68699 -400.506946) (xy 421.695372 -400.52371)
			(xy 421.70223 -400.53006) (xy 421.72136 -400.548198) (xy 421.754949 -400.588827) (xy 421.782622 -400.633696)
			(xy 421.80385 -400.681949) (xy 421.818229 -400.732666) (xy 421.825485 -400.78488) (xy 421.825928 -400.811238)
			(xy 421.825928 -401.461986) (xy 421.826311 -401.470962) (xy 421.832546 -401.487798) (xy 421.844191 -401.501464)
			(xy 421.851836 -401.506182) (xy 421.941244 -401.55622) (xy 421.96893 -401.555712) (xy 421.980614 -401.548346)
			(xy 422.003261 -401.534941) (xy 422.051447 -401.513786) (xy 422.102079 -401.499438) (xy 422.1542 -401.492169)
			(xy 422.180512 -401.491704) (xy 422.180766 -401.491704) (xy 422.208021 -401.492141) (xy 422.261978 -401.499894)
			(xy 422.314281 -401.515247) (xy 422.363867 -401.537889) (xy 422.409726 -401.567357) (xy 422.450924 -401.603052)
			(xy 422.486623 -401.644247) (xy 422.516095 -401.690103) (xy 422.52838 -401.717002) (xy 423.860974 -401.717002)
			(xy 423.865045 -401.66138) (xy 423.877171 -401.606943) (xy 423.897094 -401.554852) (xy 423.92439 -401.506217)
			(xy 423.958476 -401.462074) (xy 423.998625 -401.423365) (xy 424.043983 -401.390914) (xy 424.093583 -401.365413)
			(xy 424.146367 -401.347406) (xy 424.20121 -401.337276) (xy 424.256944 -401.335239) (xy 424.312381 -401.341339)
			(xy 424.366338 -401.355445) (xy 424.417667 -401.377257) (xy 424.465273 -401.406311) (xy 424.508141 -401.441986)
			(xy 424.545358 -401.483523) (xy 424.576131 -401.530036) (xy 424.599803 -401.580533) (xy 424.615871 -401.63394)
			(xy 424.623991 -401.689116) (xy 424.6245 -401.717002) (xy 424.623991 -401.744888) (xy 424.615871 -401.800064)
			(xy 424.599803 -401.853471) (xy 424.576131 -401.903968) (xy 424.545358 -401.950481) (xy 424.508141 -401.992018)
			(xy 424.465273 -402.027693) (xy 424.417667 -402.056747) (xy 424.374379 -402.075142) (xy 424.921934 -402.075142)
			(xy 424.922416 -402.042998) (xy 424.930503 -401.979221) (xy 424.946567 -401.916972) (xy 424.970351 -401.857245)
			(xy 425.001475 -401.800994) (xy 425.039443 -401.749115) (xy 425.083648 -401.702437) (xy 425.133386 -401.661705)
			(xy 425.187862 -401.627569) (xy 425.216828 -401.613624) (xy 425.226453 -401.608516) (xy 425.24064 -401.592011)
			(xy 425.246783 -401.571132) (xy 425.245784 -401.560284) (xy 425.243165 -401.541598) (xy 425.240368 -401.503967)
			(xy 425.240196 -401.4851) (xy 425.240698 -401.453139) (xy 425.248709 -401.389721) (xy 425.264606 -401.327807)
			(xy 425.288138 -401.268374) (xy 425.318932 -401.212359) (xy 425.356505 -401.160644) (xy 425.400262 -401.114047)
			(xy 425.449515 -401.073302) (xy 425.503486 -401.039051) (xy 425.561325 -401.011834) (xy 425.622118 -400.992081)
			(xy 425.684908 -400.980103) (xy 425.748704 -400.97609) (xy 425.8125 -400.980103) (xy 425.87529 -400.992081)
			(xy 425.936083 -401.011834) (xy 425.993922 -401.039051) (xy 426.047893 -401.073302) (xy 426.097146 -401.114047)
			(xy 426.140903 -401.160644) (xy 426.178476 -401.212359) (xy 426.20927 -401.268374) (xy 426.232802 -401.327807)
			(xy 426.248699 -401.389721) (xy 426.25671 -401.453139) (xy 426.257212 -401.4851) (xy 426.256739 -401.517244)
			(xy 426.248647 -401.581021) (xy 426.23258 -401.643268) (xy 426.208794 -401.702994) (xy 426.177669 -401.759245)
			(xy 426.139701 -401.811123) (xy 426.095495 -401.857801) (xy 426.045758 -401.898534) (xy 425.991283 -401.932672)
			(xy 425.962318 -401.946618) (xy 425.952661 -401.951674) (xy 425.938483 -401.968205) (xy 425.932354 -401.989104)
			(xy 425.933362 -401.999958) (xy 425.935986 -402.018643) (xy 425.93878 -402.056274) (xy 425.93895 -402.075142)
			(xy 425.938448 -402.107103) (xy 425.930437 -402.170521) (xy 425.91454 -402.232435) (xy 425.891008 -402.291868)
			(xy 425.860214 -402.347883) (xy 425.822641 -402.399598) (xy 425.778884 -402.446195) (xy 425.729631 -402.48694)
			(xy 425.67566 -402.521191) (xy 425.617821 -402.548408) (xy 425.557028 -402.568161) (xy 425.494238 -402.580139)
			(xy 425.430442 -402.584153) (xy 425.366646 -402.580139) (xy 425.303856 -402.568161) (xy 425.243063 -402.548408)
			(xy 425.185224 -402.521191) (xy 425.131253 -402.48694) (xy 425.082 -402.446195) (xy 425.038243 -402.399598)
			(xy 425.00067 -402.347883) (xy 424.969876 -402.291868) (xy 424.946344 -402.232435) (xy 424.930447 -402.170521)
			(xy 424.922436 -402.107103) (xy 424.921934 -402.075142) (xy 424.374379 -402.075142) (xy 424.366338 -402.078559)
			(xy 424.312381 -402.092665) (xy 424.256944 -402.098765) (xy 424.20121 -402.096728) (xy 424.146367 -402.086598)
			(xy 424.093583 -402.068591) (xy 424.043983 -402.04309) (xy 423.998625 -402.010639) (xy 423.958476 -401.97193)
			(xy 423.92439 -401.927787) (xy 423.897094 -401.879152) (xy 423.877171 -401.827061) (xy 423.865045 -401.772624)
			(xy 423.860974 -401.717002) (xy 422.52838 -401.717002) (xy 422.538741 -401.739687) (xy 422.554099 -401.791989)
			(xy 422.561857 -401.845945) (xy 422.561857 -401.900455) (xy 422.554099 -401.954411) (xy 422.538741 -402.006713)
			(xy 422.516095 -402.056297) (xy 422.486623 -402.102153) (xy 422.450924 -402.143348) (xy 422.409726 -402.179043)
			(xy 422.363867 -402.208511) (xy 422.314281 -402.231153) (xy 422.261978 -402.246506) (xy 422.208021 -402.254259)
			(xy 422.180766 -402.25472) (xy 422.153811 -402.25425) (xy 422.100439 -402.246644) (xy 422.048669 -402.231603)
			(xy 421.999531 -402.209425) (xy 421.954003 -402.180553) (xy 421.912992 -402.14556) (xy 421.877313 -402.105144)
			(xy 421.847678 -402.060109) (xy 421.824676 -402.011352) (xy 421.816276 -401.985734) (xy 421.813444 -401.977653)
			(xy 421.803283 -401.963883) (xy 421.789148 -401.954237) (xy 421.78097 -401.951698) (xy 421.72255 -401.93595)
			(xy 421.712898 -401.945856) (xy 421.706294 -401.95246) (xy 421.698674 -401.969224) (xy 421.693848 -402.045932)
			(xy 421.693682 -402.055208) (xy 421.699132 -402.072923) (xy 421.704516 -402.080476) (xy 421.721017 -402.102469)
			(xy 421.747294 -402.15076) (xy 421.765228 -402.20273) (xy 421.774325 -402.256949) (xy 421.774874 -402.284438)
			(xy 421.774364 -402.310425) (xy 421.766234 -402.36176) (xy 421.750173 -402.41119) (xy 421.726577 -402.4575)
			(xy 421.696027 -402.499548) (xy 421.659276 -402.536299) (xy 421.617228 -402.566849) (xy 421.570918 -402.590445)
			(xy 421.521488 -402.606506) (xy 421.470153 -402.614636) (xy 421.418179 -402.614636) (xy 421.366844 -402.606506)
			(xy 421.317414 -402.590445) (xy 421.271104 -402.566849) (xy 421.229056 -402.536299) (xy 421.192305 -402.499548)
			(xy 421.161755 -402.4575) (xy 421.138159 -402.41119) (xy 421.122098 -402.36176) (xy 421.113968 -402.310425)
			(xy 421.113458 -402.284438) (xy 421.11402 -402.256948) (xy 421.123094 -402.202723) (xy 421.141017 -402.150747)
			(xy 421.167293 -402.102453) (xy 421.183816 -402.080476) (xy 421.189195 -402.072916) (xy 421.194674 -402.055207)
			(xy 421.194484 -402.045932) (xy 421.189658 -401.969224) (xy 421.182038 -401.95246) (xy 421.175434 -401.945856)
			(xy 421.154383 -401.924248) (xy 421.11874 -401.875581) (xy 421.091203 -401.82191) (xy 421.072457 -401.764573)
			(xy 421.062971 -401.705) (xy 421.062404 -401.674838) (xy 420.626032 -401.674838) (xy 420.625607 -401.701012)
			(xy 420.61841 -401.752864) (xy 420.604197 -401.803247) (xy 420.583236 -401.851216) (xy 420.555918 -401.895872)
			(xy 420.522757 -401.936378) (xy 420.503858 -401.954492) (xy 420.496992 -401.96144) (xy 420.488624 -401.979069)
			(xy 420.487602 -401.988782) (xy 420.48303 -402.069046) (xy 420.48938 -402.087334) (xy 420.49573 -402.094954)
			(xy 420.510635 -402.112995) (xy 420.535697 -402.152514) (xy 420.554944 -402.195169) (xy 420.56799 -402.240109)
			(xy 420.574576 -402.28644) (xy 420.574978 -402.309838) (xy 420.574468 -402.335825) (xy 420.566338 -402.38716)
			(xy 420.550277 -402.43659) (xy 420.526681 -402.4829) (xy 420.496131 -402.524948) (xy 420.45938 -402.561699)
			(xy 420.417332 -402.592249) (xy 420.371022 -402.615845) (xy 420.321592 -402.631906) (xy 420.270257 -402.640036)
			(xy 420.218283 -402.640036) (xy 420.166948 -402.631906) (xy 420.117518 -402.615845) (xy 420.071208 -402.592249)
			(xy 420.02916 -402.561699) (xy 419.992409 -402.524948) (xy 419.961859 -402.4829) (xy 419.938263 -402.43659)
			(xy 419.922202 -402.38716) (xy 419.914072 -402.335825) (xy 419.913562 -402.309838) (xy 419.913984 -402.286442)
			(xy 419.92057 -402.240114) (xy 419.933617 -402.195177) (xy 419.952864 -402.152526) (xy 419.977928 -402.113012)
			(xy 419.99281 -402.094954) (xy 419.99916 -402.087334) (xy 420.00551 -402.069046) (xy 420.000938 -401.988782)
			(xy 419.999889 -401.979074) (xy 419.991541 -401.961441) (xy 419.984682 -401.954492) (xy 419.965782 -401.936379)
			(xy 419.93262 -401.895875) (xy 419.905304 -401.851219) (xy 419.884347 -401.803249) (xy 419.870142 -401.752865)
			(xy 419.862956 -401.701012) (xy 419.862508 -401.674838) (xy 419.425628 -401.674838) (xy 419.425147 -401.701)
			(xy 419.417998 -401.752834) (xy 419.403839 -401.803207) (xy 419.382935 -401.851175) (xy 419.355677 -401.895839)
			(xy 419.322577 -401.936364) (xy 419.303708 -401.954492) (xy 419.296834 -401.961433) (xy 419.288473 -401.979067)
			(xy 419.287452 -401.988782) (xy 419.28288 -402.069046) (xy 419.28923 -402.087334) (xy 419.29558 -402.094954)
			(xy 419.310477 -402.113001) (xy 419.335542 -402.152517) (xy 419.354791 -402.195171) (xy 419.367839 -402.24011)
			(xy 419.374426 -402.28644) (xy 419.374828 -402.309838) (xy 419.374318 -402.335825) (xy 419.366188 -402.38716)
			(xy 419.350127 -402.43659) (xy 419.326531 -402.4829) (xy 419.295981 -402.524948) (xy 419.25923 -402.561699)
			(xy 419.217182 -402.592249) (xy 419.170872 -402.615845) (xy 419.121442 -402.631906) (xy 419.070107 -402.640036)
			(xy 419.018133 -402.640036) (xy 418.966798 -402.631906) (xy 418.917368 -402.615845) (xy 418.871058 -402.592249)
			(xy 418.82901 -402.561699) (xy 418.792259 -402.524948) (xy 418.761709 -402.4829) (xy 418.738113 -402.43659)
			(xy 418.722052 -402.38716) (xy 418.713922 -402.335825) (xy 418.713412 -402.309838) (xy 418.713846 -402.286442)
			(xy 418.720431 -402.240116) (xy 418.733476 -402.195179) (xy 418.75272 -402.152528) (xy 418.77778 -402.113013)
			(xy 418.79266 -402.094954) (xy 418.79901 -402.087334) (xy 418.80536 -402.069046) (xy 418.800788 -401.988782)
			(xy 418.799725 -401.979076) (xy 418.791386 -401.961444) (xy 418.784532 -401.954492) (xy 418.765644 -401.93638)
			(xy 418.732525 -401.895861) (xy 418.705254 -401.851197) (xy 418.684342 -401.803225) (xy 418.670182 -401.752846)
			(xy 418.663039 -401.701004) (xy 418.662612 -401.674838) (xy 418.225732 -401.674838) (xy 418.225732 -401.675092)
			(xy 418.225182 -401.703971) (xy 418.216454 -401.761066) (xy 418.199226 -401.816196) (xy 418.173891 -401.868101)
			(xy 418.141028 -401.915599) (xy 418.121592 -401.936966) (xy 418.121338 -401.93722) (xy 418.115563 -401.943853)
			(xy 418.108551 -401.959969) (xy 418.107622 -401.968716) (xy 418.102796 -402.042122) (xy 418.107622 -402.058632)
			(xy 418.112702 -402.065744) (xy 418.112702 -402.066252) (xy 418.127352 -402.087435) (xy 418.150577 -402.133402)
			(xy 418.166394 -402.182415) (xy 418.17442 -402.233288) (xy 418.174932 -402.259038) (xy 418.174422 -402.285025)
			(xy 418.166292 -402.33636) (xy 418.150231 -402.38579) (xy 418.126635 -402.4321) (xy 418.096085 -402.474148)
			(xy 418.059334 -402.510899) (xy 418.017286 -402.541449) (xy 417.970976 -402.565045) (xy 417.921546 -402.581106)
			(xy 417.870211 -402.589236) (xy 417.818237 -402.589236) (xy 417.766902 -402.581106) (xy 417.717472 -402.565045)
			(xy 417.671162 -402.541449) (xy 417.629114 -402.510899) (xy 417.592363 -402.474148) (xy 417.561813 -402.4321)
			(xy 417.538217 -402.38579) (xy 417.522156 -402.33636) (xy 417.514026 -402.285025) (xy 417.513516 -402.259038)
			(xy 417.513986 -402.233254) (xy 417.521994 -402.182313) (xy 417.537821 -402.133234) (xy 417.561083 -402.087212)
			(xy 417.575746 -402.065998) (xy 417.580472 -402.058688) (xy 417.585147 -402.041933) (xy 417.58489 -402.033232)
			(xy 417.580826 -401.968716) (xy 417.579866 -401.959979) (xy 417.57285 -401.943877) (xy 417.56711 -401.93722)
			(xy 417.566856 -401.936966) (xy 417.547382 -401.915629) (xy 417.514499 -401.868136) (xy 417.489159 -401.816224)
			(xy 417.471941 -401.761083) (xy 417.463241 -401.703975) (xy 417.462716 -401.675092) (xy 417.025832 -401.675092)
			(xy 417.025384 -401.701002) (xy 417.018233 -401.752838) (xy 417.00407 -401.803212) (xy 416.983161 -401.851181)
			(xy 416.955897 -401.895844) (xy 416.922789 -401.936366) (xy 416.903916 -401.954492) (xy 416.897044 -401.961434)
			(xy 416.888681 -401.979067) (xy 416.88766 -401.988782) (xy 416.883088 -402.069046) (xy 416.889438 -402.087334)
			(xy 416.895788 -402.094954) (xy 416.910686 -402.113) (xy 416.935751 -402.152517) (xy 416.955 -402.19517)
			(xy 416.968047 -402.24011) (xy 416.974634 -402.28644) (xy 416.975036 -402.309838) (xy 416.974526 -402.335825)
			(xy 416.966396 -402.38716) (xy 416.950335 -402.43659) (xy 416.926739 -402.4829) (xy 416.896189 -402.524948)
			(xy 416.859438 -402.561699) (xy 416.81739 -402.592249) (xy 416.77108 -402.615845) (xy 416.72165 -402.631906)
			(xy 416.670315 -402.640036) (xy 416.618341 -402.640036) (xy 416.567006 -402.631906) (xy 416.517576 -402.615845)
			(xy 416.471266 -402.592249) (xy 416.429218 -402.561699) (xy 416.392467 -402.524948) (xy 416.361917 -402.4829)
			(xy 416.338321 -402.43659) (xy 416.32226 -402.38716) (xy 416.31413 -402.335825) (xy 416.31362 -402.309838)
			(xy 416.314052 -402.286442) (xy 416.320637 -402.240116) (xy 416.333683 -402.195179) (xy 416.352927 -402.152528)
			(xy 416.377987 -402.113012) (xy 416.392868 -402.094954) (xy 416.399218 -402.087334) (xy 416.405568 -402.069046)
			(xy 416.400996 -401.988782) (xy 416.399959 -401.979071) (xy 416.391604 -401.961439) (xy 416.38474 -401.954492)
			(xy 416.365853 -401.936378) (xy 416.332734 -401.89586) (xy 416.305462 -401.851196) (xy 416.28455 -401.803225)
			(xy 416.27039 -401.752846) (xy 416.263247 -401.701004) (xy 416.26282 -401.674838) (xy 415.82594 -401.674838)
			(xy 415.82594 -401.675092) (xy 415.825385 -401.704641) (xy 415.816266 -401.763033) (xy 415.798247 -401.819317)
			(xy 415.771757 -401.872147) (xy 415.737432 -401.920256) (xy 415.696095 -401.962492) (xy 415.672778 -401.980654)
			(xy 415.663126 -401.98802) (xy 415.652458 -402.009102) (xy 415.652458 -402.029676) (xy 415.653728 -402.041106)
			(xy 415.658046 -402.05279) (xy 415.662364 -402.060918) (xy 415.668968 -402.067014) (xy 415.688622 -402.085947)
			(xy 415.722064 -402.129068) (xy 415.747972 -402.177095) (xy 415.765643 -402.228724) (xy 415.774596 -402.282553)
			(xy 415.77514 -402.309838) (xy 415.774612 -402.336473) (xy 415.766088 -402.389057) (xy 415.749252 -402.439597)
			(xy 415.724537 -402.486787) (xy 415.692582 -402.529409) (xy 415.654213 -402.566362) (xy 415.610419 -402.596691)
			(xy 415.562333 -402.619614) (xy 415.511196 -402.634538) (xy 415.484818 -402.63826) (xy 415.47923 -402.639022)
			(xy 415.448496 -402.663406) (xy 415.44309 -402.66804) (xy 415.434834 -402.679635) (xy 415.43224 -402.686266)
			(xy 415.40684 -402.758656) (xy 415.40684 -402.75891) (xy 415.404683 -402.765617) (xy 415.403767 -402.779671)
			(xy 415.405062 -402.786596) (xy 415.40684 -402.793962) (xy 415.413698 -402.806408) (xy 420.66337 -408.05608)
			(xy 420.670207 -408.063481) (xy 420.677917 -408.08208) (xy 420.678356 -408.092148) (xy 420.678356 -408.13482)
			(xy 420.678784 -408.144887) (xy 420.68651 -408.163481) (xy 420.693342 -408.170888) (xy 422.42994 -409.907486)
			(xy 422.446936 -409.925177) (xy 422.475759 -409.964872) (xy 422.498027 -410.008583) (xy 422.513193 -410.055235)
			(xy 422.520886 -410.103684) (xy 422.52138 -410.128212) (xy 422.52138 -413.174688) (xy 422.727127 -413.174688)
			(xy 422.731134 -412.989784) (xy 422.743147 -412.805226) (xy 422.763143 -412.621362) (xy 422.791085 -412.438538)
			(xy 422.826921 -412.257095) (xy 422.870583 -412.077374) (xy 422.92199 -411.899714) (xy 422.981044 -411.724448)
			(xy 423.047635 -411.551904) (xy 423.121638 -411.382407) (xy 423.202914 -411.216275) (xy 423.29131 -411.053819)
			(xy 423.386661 -410.895345) (xy 423.488787 -410.74115) (xy 423.597496 -410.591524) (xy 423.712585 -410.446748)
			(xy 423.833838 -410.307093) (xy 423.961027 -410.172822) (xy 424.093912 -410.044186) (xy 424.232246 -409.921427)
			(xy 424.375767 -409.804777) (xy 424.524206 -409.694453) (xy 424.677286 -409.590662) (xy 424.834717 -409.4936)
			(xy 424.996206 -409.40345) (xy 425.161448 -409.320379) (xy 425.330134 -409.244544) (xy 425.501946 -409.176088)
			(xy 425.676562 -409.115138) (xy 425.853655 -409.061811) (xy 426.032892 -409.016204) (xy 426.213936 -408.978405)
			(xy 426.396447 -408.948484) (xy 426.580084 -408.926497) (xy 426.7645 -408.912485) (xy 426.94935 -408.906475)
			(xy 427.134287 -408.908479) (xy 427.318964 -408.918492) (xy 427.503034 -408.936495) (xy 427.68615 -408.962456)
			(xy 427.867971 -408.996324) (xy 428.048154 -409.038036) (xy 428.22636 -409.087515) (xy 428.402256 -409.144667)
			(xy 428.575511 -409.209385) (xy 428.7458 -409.281548) (xy 428.912803 -409.361019) (xy 429.076207 -409.44765)
			(xy 429.235704 -409.541279) (xy 429.390996 -409.641728) (xy 429.541791 -409.748811) (xy 429.687806 -409.862325)
			(xy 429.828766 -409.982057) (xy 429.964407 -410.107784) (xy 430.094475 -410.239268) (xy 430.218725 -410.376264)
			(xy 430.336923 -410.518513) (xy 430.448849 -410.665748) (xy 430.554292 -410.817694) (xy 430.653053 -410.974065)
			(xy 430.744948 -411.134568) (xy 430.829804 -411.2989) (xy 430.907462 -411.466755) (xy 430.977775 -411.637815)
			(xy 431.040612 -411.811761) (xy 431.095856 -411.988266) (xy 431.143401 -412.166998) (xy 431.183159 -412.347622)
			(xy 431.215056 -412.529799) (xy 431.239031 -412.713186) (xy 431.255039 -412.89744) (xy 431.263051 -413.082214)
			(xy 431.263552 -413.174688) (xy 431.263051 -413.267162) (xy 431.255039 -413.451936) (xy 431.239031 -413.63619)
			(xy 431.215056 -413.819577) (xy 431.183159 -414.001754) (xy 431.143401 -414.182378) (xy 431.095856 -414.36111)
			(xy 431.040612 -414.537615) (xy 430.977775 -414.711561) (xy 430.907462 -414.882621) (xy 430.829804 -415.050476)
			(xy 430.744948 -415.214808) (xy 430.653053 -415.375311) (xy 430.554292 -415.531682) (xy 430.448849 -415.683628)
			(xy 430.336923 -415.830863) (xy 430.218725 -415.973112) (xy 430.094475 -416.110108) (xy 429.964407 -416.241592)
			(xy 429.828766 -416.367319) (xy 429.687806 -416.487051) (xy 429.541791 -416.600565) (xy 429.390996 -416.707648)
			(xy 429.235704 -416.808097) (xy 429.076207 -416.901726) (xy 428.912803 -416.988357) (xy 428.7458 -417.067828)
			(xy 428.575511 -417.139991) (xy 428.402256 -417.204709) (xy 428.22636 -417.261861) (xy 428.048154 -417.31134)
			(xy 427.867971 -417.353052) (xy 427.68615 -417.38692) (xy 427.503034 -417.412881) (xy 427.318964 -417.430884)
			(xy 427.134287 -417.440897) (xy 426.94935 -417.442901) (xy 426.7645 -417.436891) (xy 426.580084 -417.422879)
			(xy 426.396447 -417.400892) (xy 426.213936 -417.370971) (xy 426.032892 -417.333172) (xy 425.853655 -417.287565)
			(xy 425.676562 -417.234238) (xy 425.501946 -417.173288) (xy 425.330134 -417.104832) (xy 425.161448 -417.028997)
			(xy 424.996206 -416.945926) (xy 424.834717 -416.855776) (xy 424.677286 -416.758714) (xy 424.524206 -416.654923)
			(xy 424.375767 -416.544599) (xy 424.232246 -416.427949) (xy 424.093912 -416.30519) (xy 423.961027 -416.176554)
			(xy 423.833838 -416.042283) (xy 423.712585 -415.902628) (xy 423.597496 -415.757852) (xy 423.488787 -415.608226)
			(xy 423.386661 -415.454031) (xy 423.29131 -415.295557) (xy 423.202914 -415.133101) (xy 423.121638 -414.966969)
			(xy 423.047635 -414.797472) (xy 422.981044 -414.624928) (xy 422.92199 -414.449662) (xy 422.870583 -414.272002)
			(xy 422.826921 -414.092281) (xy 422.791085 -413.910838) (xy 422.763143 -413.728014) (xy 422.743147 -413.54415)
			(xy 422.731134 -413.359592) (xy 422.727127 -413.174688) (xy 422.52138 -413.174688) (xy 422.52138 -419.67658)
			(xy 422.521551 -419.682589) (xy 422.52438 -419.694268) (xy 422.526968 -419.699694) (xy 422.528805 -419.70317)
			(xy 422.533394 -419.709553) (xy 422.536112 -419.712394) (xy 423.739564 -420.915846) (xy 423.745313 -420.921045)
			(xy 423.759145 -420.928024) (xy 423.766742 -420.929562) (xy 423.775124 -420.930324) (xy 428.19955 -420.930324)
			(xy 428.228269 -420.930899) (xy 428.284762 -420.941251) (xy 428.311818 -420.950898) (xy 428.316136 -420.952676)
			(xy 428.336202 -420.956486) (xy 428.339758 -420.955978) (xy 428.35857 -420.953346) (xy 428.396456 -420.950553)
			(xy 428.41545 -420.95039) (xy 428.415704 -420.95039) (xy 428.446427 -420.950866) (xy 428.507423 -420.958295)
			(xy 428.567079 -420.97302) (xy 428.624525 -420.994827) (xy 428.678925 -421.023398) (xy 428.729486 -421.058316)
			(xy 428.775471 -421.099072) (xy 428.816209 -421.145073) (xy 428.851107 -421.195648) (xy 428.879656 -421.250059)
			(xy 428.90144 -421.307514) (xy 428.916141 -421.367176) (xy 428.923546 -421.428175) (xy 428.923958 -421.458898)
			(xy 428.923495 -421.48963) (xy 428.916087 -421.550647) (xy 428.901378 -421.610325) (xy 428.879584 -421.667796)
			(xy 428.851022 -421.722221) (xy 428.816108 -421.772807) (xy 428.775352 -421.818815) (xy 428.729347 -421.859576)
			(xy 428.678765 -421.894495) (xy 428.624343 -421.923063) (xy 428.566875 -421.944863) (xy 428.507198 -421.959577)
			(xy 428.446182 -421.966991) (xy 428.41545 -421.967406) (xy 428.382299 -421.966868) (xy 428.316559 -421.958246)
			(xy 428.252496 -421.941154) (xy 428.191199 -421.915882) (xy 428.133704 -421.882859) (xy 428.080989 -421.842646)
			(xy 428.033946 -421.795923) (xy 427.993373 -421.743483) (xy 427.959959 -421.686215) (xy 427.93427 -421.625091)
			(xy 427.924976 -421.593264) (xy 427.924214 -421.590724) (xy 427.92038 -421.580758) (xy 427.906099 -421.564917)
			(xy 427.886617 -421.556238) (xy 427.875954 -421.555672) (xy 426.743622 -421.555672) (xy 426.739412 -421.555746)
			(xy 426.731111 -421.557149) (xy 426.727112 -421.558466) (xy 426.718035 -421.561995) (xy 426.703265 -421.574662)
			(xy 426.69841 -421.583104) (xy 426.696632 -421.587422) (xy 426.693922 -421.594592) (xy 426.692494 -421.609848)
			(xy 426.693838 -421.617394) (xy 426.695108 -421.623998) (xy 426.701966 -421.636698) (xy 427.034452 -421.969184)
			(xy 427.054895 -421.990594) (xy 427.088148 -422.03956) (xy 427.100492 -422.066466) (xy 427.103032 -422.072308)
			(xy 427.106842 -422.077134) (xy 427.1137 -422.084754) (xy 427.118018 -422.088056) (xy 427.11878 -422.088818)
			(xy 427.145345 -422.109477) (xy 427.193326 -422.156664) (xy 427.234667 -422.209765) (xy 427.268645 -422.267853)
			(xy 427.294669 -422.329914) (xy 427.312282 -422.394865) (xy 427.321179 -422.46157) (xy 427.321726 -422.495218)
			(xy 427.321224 -422.527179) (xy 427.317823 -422.5541) (xy 427.608036 -422.5541) (xy 427.612049 -422.49031)
			(xy 427.624026 -422.427526) (xy 427.643777 -422.366738) (xy 427.670991 -422.308904) (xy 427.705239 -422.254938)
			(xy 427.745981 -422.20569) (xy 427.792574 -422.161936) (xy 427.844283 -422.124367) (xy 427.900293 -422.093575)
			(xy 427.959721 -422.070046) (xy 428.02163 -422.054151) (xy 428.085042 -422.04614) (xy 428.117 -422.045638)
			(xy 428.151158 -422.046203) (xy 428.218859 -422.055345) (xy 428.284728 -422.073465) (xy 428.347579 -422.100236)
			(xy 428.406282 -422.135178) (xy 428.459782 -422.177661) (xy 428.507115 -422.226922) (xy 428.527718 -422.254172)
			(xy 428.533538 -422.261463) (xy 428.549174 -422.271614) (xy 428.558198 -422.273984) (xy 428.588678 -422.280334)
			(xy 428.597794 -422.281812) (xy 428.616022 -422.278959) (xy 428.624238 -422.274746) (xy 428.645939 -422.262731)
			(xy 428.691807 -422.243844) (xy 428.739737 -422.231065) (xy 428.78892 -422.224609) (xy 428.813722 -422.2242)
			(xy 428.840973 -422.224671) (xy 428.894919 -422.232431) (xy 428.947212 -422.247788) (xy 428.996788 -422.270431)
			(xy 429.042637 -422.299898) (xy 429.083825 -422.335591) (xy 429.119515 -422.376781) (xy 429.14898 -422.422631)
			(xy 429.17162 -422.472208) (xy 429.186974 -422.524502) (xy 429.19473 -422.578449) (xy 429.19473 -422.621921)
			(xy 429.365404 -422.621921) (xy 429.365404 -422.557999) (xy 429.373415 -422.494581) (xy 429.389312 -422.432667)
			(xy 429.412844 -422.373234) (xy 429.443638 -422.317219) (xy 429.481211 -422.265504) (xy 429.524968 -422.218907)
			(xy 429.574221 -422.178162) (xy 429.628192 -422.143911) (xy 429.686031 -422.116694) (xy 429.746824 -422.096941)
			(xy 429.809614 -422.084963) (xy 429.87341 -422.08095) (xy 429.937206 -422.084963) (xy 429.999996 -422.096941)
			(xy 430.060789 -422.116694) (xy 430.118628 -422.143911) (xy 430.172599 -422.178162) (xy 430.221852 -422.218907)
			(xy 430.265609 -422.265504) (xy 430.303182 -422.317219) (xy 430.333976 -422.373234) (xy 430.357508 -422.432667)
			(xy 430.373405 -422.494581) (xy 430.381416 -422.557999) (xy 430.381918 -422.58996) (xy 430.381416 -422.621921)
			(xy 430.373405 -422.685339) (xy 430.357508 -422.747253) (xy 430.333976 -422.806686) (xy 430.303182 -422.862701)
			(xy 430.265609 -422.914416) (xy 430.221852 -422.961013) (xy 430.172599 -423.001758) (xy 430.118628 -423.036009)
			(xy 430.060789 -423.063226) (xy 429.999996 -423.082979) (xy 429.937206 -423.094957) (xy 429.87341 -423.098971)
			(xy 429.809614 -423.094957) (xy 429.746824 -423.082979) (xy 429.686031 -423.063226) (xy 429.628192 -423.036009)
			(xy 429.574221 -423.001758) (xy 429.524968 -422.961013) (xy 429.481211 -422.914416) (xy 429.443638 -422.862701)
			(xy 429.412844 -422.806686) (xy 429.389312 -422.747253) (xy 429.373415 -422.685339) (xy 429.365404 -422.621921)
			(xy 429.19473 -422.621921) (xy 429.19473 -422.632951) (xy 429.186974 -422.686898) (xy 429.17162 -422.739192)
			(xy 429.14898 -422.788769) (xy 429.119515 -422.834619) (xy 429.083825 -422.875809) (xy 429.042637 -422.911502)
			(xy 428.996788 -422.940969) (xy 428.947212 -422.963612) (xy 428.894919 -422.978969) (xy 428.840973 -422.986729)
			(xy 428.813722 -422.987216) (xy 428.788233 -422.9868) (xy 428.737709 -422.980014) (xy 428.688541 -422.966549)
			(xy 428.64161 -422.946645) (xy 428.597754 -422.920657) (xy 428.577502 -422.905174) (xy 428.56995 -422.89978)
			(xy 428.552236 -422.894305) (xy 428.542958 -422.894506) (xy 428.512224 -422.89603) (xy 428.502888 -422.897065)
			(xy 428.485823 -422.90487) (xy 428.47895 -422.91127) (xy 428.454961 -422.934772) (xy 428.401925 -422.975967)
			(xy 428.343926 -423.009818) (xy 428.281974 -423.035736) (xy 428.217148 -423.05327) (xy 428.150578 -423.062114)
			(xy 428.117 -423.062654) (xy 428.085042 -423.06206) (xy 428.02163 -423.054049) (xy 427.959721 -423.038154)
			(xy 427.900293 -423.014625) (xy 427.844283 -422.983833) (xy 427.792574 -422.946264) (xy 427.745981 -422.90251)
			(xy 427.705239 -422.853262) (xy 427.670991 -422.799296) (xy 427.643777 -422.741462) (xy 427.624026 -422.680674)
			(xy 427.612049 -422.61789) (xy 427.608036 -422.5541) (xy 427.317823 -422.5541) (xy 427.313213 -422.590597)
			(xy 427.297316 -422.652511) (xy 427.273784 -422.711944) (xy 427.24299 -422.767959) (xy 427.205417 -422.819674)
			(xy 427.16166 -422.866271) (xy 427.112407 -422.907016) (xy 427.058436 -422.941267) (xy 427.000597 -422.968484)
			(xy 426.939804 -422.988237) (xy 426.877014 -423.000215) (xy 426.813218 -423.004229) (xy 426.749422 -423.000215)
			(xy 426.686632 -422.988237) (xy 426.625839 -422.968484) (xy 426.568 -422.941267) (xy 426.514029 -422.907016)
			(xy 426.464776 -422.866271) (xy 426.421019 -422.819674) (xy 426.383446 -422.767959) (xy 426.352652 -422.711944)
			(xy 426.32912 -422.652511) (xy 426.313223 -422.590597) (xy 426.305212 -422.527179) (xy 426.30471 -422.495218)
			(xy 426.305227 -422.462325) (xy 426.313709 -422.397088) (xy 426.330534 -422.333489) (xy 426.35542 -422.272591)
			(xy 426.371258 -422.243758) (xy 426.371512 -422.243504) (xy 426.376181 -422.233974) (xy 426.378122 -422.212866)
			(xy 426.371407 -422.19276) (xy 426.364654 -422.184576) (xy 426.36313 -422.182798) (xy 426.14342 -421.963088)
			(xy 426.140568 -421.960383) (xy 426.134189 -421.955792) (xy 426.13072 -421.953944) (xy 426.125293 -421.951363)
			(xy 426.113613 -421.948545) (xy 426.107606 -421.948356) (xy 425.991528 -421.948356) (xy 425.984258 -421.948584)
			(xy 425.970316 -421.952713) (xy 425.964096 -421.956484) (xy 425.963842 -421.956484) (xy 425.958043 -421.960553)
			(xy 425.948765 -421.971251) (xy 425.945554 -421.977566) (xy 425.9453 -421.97782) (xy 425.90847 -422.057068)
			(xy 425.904718 -422.066289) (xy 425.903789 -422.086155) (xy 425.906692 -422.095676) (xy 425.91355 -422.11498)
			(xy 425.918884 -422.121584) (xy 425.940222 -422.148863) (xy 425.976097 -422.208103) (xy 426.003594 -422.271667)
			(xy 426.022202 -422.338377) (xy 426.031578 -422.406996) (xy 426.032168 -422.441624) (xy 426.032168 -422.441878)
			(xy 426.030898 -422.478454) (xy 426.030136 -422.488106) (xy 426.026822 -422.5193) (xy 426.013479 -422.580597)
			(xy 425.992696 -422.639787) (xy 425.964788 -422.695971) (xy 425.930181 -422.748294) (xy 425.889399 -422.795962)
			(xy 425.843063 -422.83825) (xy 425.791876 -422.874517) (xy 425.736616 -422.904211) (xy 425.678123 -422.926881)
			(xy 425.617285 -422.942183) (xy 425.555026 -422.949884) (xy 425.52366 -422.950386) (xy 425.492931 -422.94992)
			(xy 425.431922 -422.942507) (xy 425.372251 -422.927795) (xy 425.314788 -422.905997) (xy 425.260372 -422.877433)
			(xy 425.209795 -422.842517) (xy 425.163796 -422.80176) (xy 425.123044 -422.755756) (xy 425.088135 -422.705175)
			(xy 425.059577 -422.650755) (xy 425.037787 -422.59329) (xy 425.023082 -422.533617) (xy 425.015677 -422.472607)
			(xy 425.015152 -422.441878) (xy 425.016422 -422.405302) (xy 425.017438 -422.391332) (xy 425.013628 -422.380918)
			(xy 425.011617 -422.375824) (xy 425.00572 -422.366598) (xy 425.001944 -422.36263) (xy 424.922442 -422.283128)
			(xy 424.919592 -422.28042) (xy 424.913216 -422.275823) (xy 424.909742 -422.273984) (xy 424.904315 -422.271403)
			(xy 424.892635 -422.268584) (xy 424.886628 -422.268396) (xy 424.837352 -422.268396) (xy 424.826606 -422.268881)
			(xy 424.80701 -422.277705) (xy 424.799506 -422.285414) (xy 424.758612 -422.331134) (xy 424.74896 -422.342056)
			(xy 424.745437 -422.346145) (xy 424.74005 -422.355495) (xy 424.738292 -422.360598) (xy 424.735244 -422.370504)
			(xy 424.736514 -422.381426) (xy 424.738085 -422.396043) (xy 424.739737 -422.425399) (xy 424.739816 -422.4401)
			(xy 424.739352 -422.470831) (xy 424.731944 -422.531845) (xy 424.717235 -422.591522) (xy 424.69544 -422.64899)
			(xy 424.666877 -422.703412) (xy 424.631963 -422.753995) (xy 424.591206 -422.800001) (xy 424.545202 -422.840758)
			(xy 424.494619 -422.875673) (xy 424.440197 -422.904237) (xy 424.382729 -422.926032) (xy 424.323053 -422.940742)
			(xy 424.262039 -422.948151) (xy 424.231308 -422.948608) (xy 424.200678 -422.948151) (xy 424.139861 -422.940795)
			(xy 424.080367 -422.926188) (xy 424.023058 -422.904542) (xy 423.968764 -422.87617) (xy 423.91827 -422.841483)
			(xy 423.872307 -422.800983) (xy 423.851578 -422.778428) (xy 423.84472 -422.770554) (xy 423.817034 -422.757854)
			(xy 423.811976 -422.755646) (xy 423.801214 -422.753216) (xy 423.795698 -422.753028) (xy 422.515284 -422.753028)
			(xy 422.505267 -422.753451) (xy 422.48676 -422.761125) (xy 422.4726 -422.775297) (xy 422.464942 -422.793811)
			(xy 422.464484 -422.803828) (xy 422.464484 -423.503344) (xy 422.4655 -423.512996) (xy 422.467132 -423.520238)
			(xy 422.473979 -423.533401) (xy 422.478962 -423.538904) (xy 422.759886 -423.819828) (xy 425.568616 -423.819828)
			(xy 425.572687 -423.764206) (xy 425.584813 -423.709769) (xy 425.604736 -423.657678) (xy 425.632032 -423.609043)
			(xy 425.666118 -423.5649) (xy 425.706267 -423.526191) (xy 425.751625 -423.49374) (xy 425.801225 -423.468239)
			(xy 425.854009 -423.450232) (xy 425.908852 -423.440102) (xy 425.964586 -423.438065) (xy 426.020023 -423.444165)
			(xy 426.07398 -423.458271) (xy 426.125309 -423.480083) (xy 426.172915 -423.509137) (xy 426.215783 -423.544812)
			(xy 426.253 -423.586349) (xy 426.283773 -423.632862) (xy 426.307445 -423.683359) (xy 426.323513 -423.736766)
			(xy 426.331633 -423.791942) (xy 426.332142 -423.819828) (xy 426.331633 -423.847714) (xy 426.323513 -423.90289)
			(xy 426.307445 -423.956297) (xy 426.283773 -424.006794) (xy 426.253 -424.053307) (xy 426.215783 -424.094844)
			(xy 426.172915 -424.130519) (xy 426.125309 -424.159573) (xy 426.07398 -424.181385) (xy 426.020023 -424.195491)
			(xy 425.964586 -424.201591) (xy 425.908852 -424.199554) (xy 425.854009 -424.189424) (xy 425.801225 -424.171417)
			(xy 425.751625 -424.145916) (xy 425.706267 -424.113465) (xy 425.666118 -424.074756) (xy 425.632032 -424.030613)
			(xy 425.604736 -423.981978) (xy 425.584813 -423.929887) (xy 425.572687 -423.87545) (xy 425.568616 -423.819828)
			(xy 422.759886 -423.819828) (xy 422.93921 -423.999152) (xy 422.94048 -424.000422) (xy 422.941496 -424.001692)
			(xy 422.946068 -424.006264) (xy 422.949878 -424.015408) (xy 422.95165 -424.020036) (xy 422.953567 -424.029758)
			(xy 422.953688 -424.034712) (xy 422.953688 -424.171618) (xy 422.955466 -424.184826) (xy 422.956228 -424.188128)
			(xy 422.963265 -424.217846) (xy 423.933618 -424.217846) (xy 423.937689 -424.162224) (xy 423.949815 -424.107787)
			(xy 423.969738 -424.055696) (xy 423.997034 -424.007061) (xy 424.03112 -423.962918) (xy 424.071269 -423.924209)
			(xy 424.116627 -423.891758) (xy 424.166227 -423.866257) (xy 424.219011 -423.84825) (xy 424.273854 -423.83812)
			(xy 424.329588 -423.836083) (xy 424.385025 -423.842183) (xy 424.438982 -423.856289) (xy 424.490311 -423.878101)
			(xy 424.537917 -423.907155) (xy 424.580785 -423.94283) (xy 424.618002 -423.984367) (xy 424.648775 -424.03088)
			(xy 424.672447 -424.081377) (xy 424.688515 -424.134784) (xy 424.696635 -424.18996) (xy 424.697144 -424.217846)
			(xy 424.696635 -424.245732) (xy 424.688515 -424.300908) (xy 424.672447 -424.354315) (xy 424.648775 -424.404812)
			(xy 424.618002 -424.451325) (xy 424.580785 -424.492862) (xy 424.537917 -424.528537) (xy 424.490311 -424.557591)
			(xy 424.438982 -424.579403) (xy 424.385025 -424.593509) (xy 424.329588 -424.599609) (xy 424.273854 -424.597572)
			(xy 424.219011 -424.587442) (xy 424.166227 -424.569435) (xy 424.116627 -424.543934) (xy 424.071269 -424.511483)
			(xy 424.03112 -424.472774) (xy 423.997034 -424.428631) (xy 423.969738 -424.379996) (xy 423.949815 -424.327905)
			(xy 423.937689 -424.273468) (xy 423.933618 -424.217846) (xy 422.963265 -424.217846) (xy 422.964244 -424.221982)
			(xy 422.972905 -424.291011) (xy 422.9735 -424.325796) (xy 422.9735 -424.622933) (xy 430.272692 -424.622933)
			(xy 430.272692 -424.559011) (xy 430.280703 -424.495593) (xy 430.2966 -424.433679) (xy 430.320132 -424.374246)
			(xy 430.350926 -424.318231) (xy 430.388499 -424.266516) (xy 430.432256 -424.219919) (xy 430.481509 -424.179174)
			(xy 430.53548 -424.144923) (xy 430.593319 -424.117706) (xy 430.654112 -424.097953) (xy 430.716902 -424.085975)
			(xy 430.780698 -424.081962) (xy 430.844494 -424.085975) (xy 430.907284 -424.097953) (xy 430.968077 -424.117706)
			(xy 431.025916 -424.144923) (xy 431.079887 -424.179174) (xy 431.12914 -424.219919) (xy 431.172897 -424.266516)
			(xy 431.21047 -424.318231) (xy 431.241264 -424.374246) (xy 431.264796 -424.433679) (xy 431.280693 -424.495593)
			(xy 431.288704 -424.559011) (xy 431.289206 -424.590972) (xy 431.288704 -424.622933) (xy 431.280693 -424.686351)
			(xy 431.264796 -424.748265) (xy 431.241264 -424.807698) (xy 431.21047 -424.863713) (xy 431.172897 -424.915428)
			(xy 431.12914 -424.962025) (xy 431.079887 -425.00277) (xy 431.025916 -425.037021) (xy 430.968077 -425.064238)
			(xy 430.907284 -425.083991) (xy 430.844494 -425.095969) (xy 430.780698 -425.099983) (xy 430.716902 -425.095969)
			(xy 430.654112 -425.083991) (xy 430.593319 -425.064238) (xy 430.53548 -425.037021) (xy 430.481509 -425.00277)
			(xy 430.432256 -424.962025) (xy 430.388499 -424.915428) (xy 430.350926 -424.863713) (xy 430.320132 -424.807698)
			(xy 430.2966 -424.748265) (xy 430.280703 -424.686351) (xy 430.272692 -424.622933) (xy 422.9735 -424.622933)
			(xy 422.9735 -425.5112) (xy 423.512803 -425.5112) (xy 423.516817 -425.447409) (xy 423.528793 -425.384624)
			(xy 423.548543 -425.323835) (xy 423.575756 -425.266001) (xy 423.610003 -425.212033) (xy 423.650744 -425.162783)
			(xy 423.697335 -425.119026) (xy 423.749043 -425.081454) (xy 423.805052 -425.050659) (xy 423.864479 -425.027126)
			(xy 423.926387 -425.011226) (xy 423.9898 -425.00321) (xy 424.021758 -425.002706) (xy 424.055242 -425.00323)
			(xy 424.121631 -425.012023) (xy 424.186292 -425.029449) (xy 424.248108 -425.055207) (xy 424.306011 -425.088852)
			(xy 424.359 -425.129803) (xy 424.406158 -425.177351) (xy 424.446672 -425.230675) (xy 424.463718 -425.2595)
			(xy 424.469809 -425.269102) (xy 424.488399 -425.28215) (xy 424.510798 -425.285912) (xy 424.521884 -425.283376)
			(xy 424.55592 -425.27474) (xy 424.56572 -425.272086) (xy 424.582321 -425.260429) (xy 424.588178 -425.252134)
			(xy 424.632374 -425.181776) (xy 424.635676 -425.161964) (xy 424.63339 -425.152058) (xy 424.63339 -425.15155)
			(xy 424.628443 -425.129657) (xy 424.623093 -425.085092) (xy 424.622722 -425.06265) (xy 424.623208 -425.035399)
			(xy 424.630964 -424.981451) (xy 424.646319 -424.929156) (xy 424.668961 -424.879579) (xy 424.698427 -424.833729)
			(xy 424.734118 -424.792538) (xy 424.775309 -424.756847) (xy 424.821159 -424.727381) (xy 424.870736 -424.704739)
			(xy 424.923031 -424.689384) (xy 424.976979 -424.681628) (xy 425.031481 -424.681628) (xy 425.085429 -424.689384)
			(xy 425.137724 -424.704739) (xy 425.187301 -424.727381) (xy 425.233151 -424.756847) (xy 425.274342 -424.792538)
			(xy 425.310033 -424.833729) (xy 425.339499 -424.879579) (xy 425.362141 -424.929156) (xy 425.377496 -424.981451)
			(xy 425.385252 -425.035399) (xy 425.385738 -425.06265) (xy 425.385238 -425.089659) (xy 425.377637 -425.143139)
			(xy 425.362567 -425.195012) (xy 425.340328 -425.24424) (xy 425.311366 -425.289837) (xy 425.27626 -425.330891)
			(xy 425.235712 -425.366582) (xy 425.190535 -425.396194) (xy 425.166282 -425.40809) (xy 425.157175 -425.412817)
			(xy 425.143426 -425.428028) (xy 425.139612 -425.437554) (xy 425.112434 -425.515786) (xy 425.113704 -425.536106)
			(xy 425.118276 -425.54525) (xy 425.130973 -425.571729) (xy 425.150919 -425.626963) (xy 425.164381 -425.684125)
			(xy 425.171179 -425.742456) (xy 425.171616 -425.771818) (xy 425.171161 -425.802549) (xy 425.16375 -425.863563)
			(xy 425.14904 -425.923239) (xy 425.127244 -425.980706) (xy 425.09868 -426.035128) (xy 425.063765 -426.08571)
			(xy 425.023007 -426.131714) (xy 424.977002 -426.172471) (xy 424.926419 -426.207385) (xy 424.871997 -426.235948)
			(xy 424.814529 -426.257743) (xy 424.754853 -426.272452) (xy 424.693839 -426.279861) (xy 424.663108 -426.280326)
			(xy 424.629624 -426.279814) (xy 424.563235 -426.271017) (xy 424.498575 -426.253588) (xy 424.436759 -426.227827)
			(xy 424.378856 -426.19418) (xy 424.325868 -426.153229) (xy 424.278709 -426.105681) (xy 424.238195 -426.052357)
			(xy 424.221148 -426.023532) (xy 424.215076 -426.013914) (xy 424.196478 -426.000864) (xy 424.174071 -425.997112)
			(xy 424.162982 -425.999656) (xy 424.128494 -426.009018) (xy 424.057743 -426.019082) (xy 424.022012 -426.019722)
			(xy 424.021758 -426.019722) (xy 423.9898 -426.01919) (xy 423.926387 -426.011174) (xy 423.864479 -425.995274)
			(xy 423.805052 -425.971741) (xy 423.749043 -425.940946) (xy 423.697335 -425.903374) (xy 423.650744 -425.859617)
			(xy 423.610003 -425.810367) (xy 423.575756 -425.756399) (xy 423.548543 -425.698565) (xy 423.528793 -425.637776)
			(xy 423.516817 -425.574991) (xy 423.512803 -425.5112) (xy 422.9735 -425.5112) (xy 422.9735 -425.8056)
			(xy 422.974516 -425.815252) (xy 422.976143 -425.822496) (xy 422.982983 -425.835667) (xy 422.987978 -425.84116)
			(xy 423.794682 -426.647864) (xy 423.800181 -426.652851) (xy 423.813347 -426.659698) (xy 423.82059 -426.661326)
			(xy 423.830242 -426.662342) (xy 425.538646 -426.662342) (xy 425.548711 -426.661909) (xy 425.567298 -426.654176)
			(xy 425.574714 -426.647356) (xy 425.646088 -426.575982) (xy 425.668873 -426.553842) (xy 425.718555 -426.514242)
			(xy 425.772353 -426.480447) (xy 425.829594 -426.45288) (xy 425.889559 -426.431888) (xy 425.951495 -426.417733)
			(xy 426.014626 -426.410594) (xy 426.046392 -426.41012) (xy 426.94606 -426.41012) (xy 426.980312 -426.410634)
			(xy 427.048318 -426.418885) (xy 427.114834 -426.435272) (xy 427.17889 -426.459555) (xy 427.239553 -426.491381)
			(xy 427.295938 -426.530286) (xy 427.347224 -426.575702) (xy 427.392663 -426.626968) (xy 427.431592 -426.683336)
			(xy 427.463444 -426.743985) (xy 427.487755 -426.808031) (xy 427.50417 -426.87454) (xy 427.512451 -426.942542)
			(xy 427.512988 -426.976794) (xy 427.512494 -427.010347) (xy 427.50457 -427.076983) (xy 427.488833 -427.142218)
			(xy 427.465503 -427.205138) (xy 427.434906 -427.264863) (xy 427.397471 -427.320556) (xy 427.353721 -427.37144)
			(xy 427.304268 -427.416801) (xy 427.249805 -427.456005) (xy 427.191094 -427.488504) (xy 427.128955 -427.513842)
			(xy 427.06426 -427.531666) (xy 427.03115 -427.537118) (xy 427.02226 -427.539404) (xy 427.01337 -427.542452)
			(xy 427.006004 -427.5455) (xy 426.99559 -427.551088) (xy 426.990817 -427.553658) (xy 426.982367 -427.560445)
			(xy 426.978826 -427.56455) (xy 426.965364 -427.580806) (xy 426.965364 -427.581314) (xy 426.959268 -427.588426)
			(xy 426.95622 -427.597316) (xy 426.954839 -427.601819) (xy 426.953553 -427.61115) (xy 426.95368 -427.615858)
			(xy 426.954188 -427.633638) (xy 426.954188 -427.636432) (xy 426.953583 -427.662575) (xy 426.946094 -427.714327)
			(xy 426.94585 -427.715172) (xy 428.07966 -427.715172) (xy 428.083731 -427.65955) (xy 428.095857 -427.605113)
			(xy 428.11578 -427.553022) (xy 428.143076 -427.504387) (xy 428.177162 -427.460244) (xy 428.217311 -427.421535)
			(xy 428.262669 -427.389084) (xy 428.312269 -427.363583) (xy 428.365053 -427.345576) (xy 428.419896 -427.335446)
			(xy 428.47563 -427.333409) (xy 428.531067 -427.339509) (xy 428.585024 -427.353615) (xy 428.636353 -427.375427)
			(xy 428.683959 -427.404481) (xy 428.726827 -427.440156) (xy 428.764044 -427.481693) (xy 428.794817 -427.528206)
			(xy 428.818489 -427.578703) (xy 428.834557 -427.63211) (xy 428.842677 -427.687286) (xy 428.843186 -427.715172)
			(xy 428.842677 -427.743058) (xy 428.834557 -427.798234) (xy 428.818489 -427.851641) (xy 428.794817 -427.902138)
			(xy 428.764044 -427.948651) (xy 428.726827 -427.990188) (xy 428.683959 -428.025863) (xy 428.636353 -428.054917)
			(xy 428.585024 -428.076729) (xy 428.531067 -428.090835) (xy 428.47563 -428.096935) (xy 428.419896 -428.094898)
			(xy 428.365053 -428.084768) (xy 428.312269 -428.066761) (xy 428.262669 -428.04126) (xy 428.217311 -428.008809)
			(xy 428.177162 -427.9701) (xy 428.143076 -427.925957) (xy 428.11578 -427.877322) (xy 428.095857 -427.825231)
			(xy 428.083731 -427.770794) (xy 428.07966 -427.715172) (xy 426.94585 -427.715172) (xy 426.931602 -427.764571)
			(xy 426.91038 -427.812364) (xy 426.882827 -427.856807) (xy 426.849458 -427.897069) (xy 426.83049 -427.91507)
			(xy 426.829474 -427.915832) (xy 426.826426 -427.91888) (xy 426.819858 -427.926001) (xy 426.812161 -427.943762)
			(xy 426.81144 -427.953424) (xy 426.809408 -428.024798) (xy 426.809408 -428.028608) (xy 426.809884 -428.038575)
			(xy 426.817458 -428.057013) (xy 426.82414 -428.064422) (xy 426.941742 -428.18177) (xy 426.963882 -428.204555)
			(xy 427.003482 -428.254237) (xy 427.037277 -428.308036) (xy 427.064845 -428.365277) (xy 427.085838 -428.425241)
			(xy 427.099994 -428.487177) (xy 427.107135 -428.550308) (xy 427.107604 -428.582074) (xy 427.107604 -428.582582)
			(xy 427.107088 -428.61683) (xy 427.098834 -428.684826) (xy 427.082445 -428.751331) (xy 427.058158 -428.815376)
			(xy 427.026329 -428.876026) (xy 426.987422 -428.932398) (xy 426.942004 -428.98367) (xy 426.890736 -429.029092)
			(xy 426.834368 -429.068005) (xy 426.77372 -429.099839) (xy 426.709677 -429.12413) (xy 426.643173 -429.140526)
			(xy 426.575178 -429.148785) (xy 426.54093 -429.149256) (xy 426.540422 -429.149256) (xy 426.508656 -429.148796)
			(xy 426.445525 -429.141658) (xy 426.383589 -429.127501) (xy 426.323626 -429.106504) (xy 426.266388 -429.078931)
			(xy 426.212594 -429.045127) (xy 426.16292 -429.005517) (xy 426.140118 -428.983394) (xy 425.48302 -428.326042)
			(xy 425.475586 -428.319326) (xy 425.457086 -428.31169) (xy 425.437072 -428.31169) (xy 425.418572 -428.319326)
			(xy 425.411138 -428.326042) (xy 425.19727 -428.53991) (xy 425.189874 -428.546762) (xy 425.171275 -428.554499)
			(xy 425.161202 -428.554896) (xy 423.186098 -428.554896) (xy 423.176028 -428.554472) (xy 423.157425 -428.546757)
			(xy 423.15003 -428.53991) (xy 421.11041 -426.50029) (xy 421.107558 -426.497586) (xy 421.101178 -426.492995)
			(xy 421.09771 -426.491146) (xy 421.092283 -426.488566) (xy 421.080603 -426.48575) (xy 421.074596 -426.485558)
			(xy 417.917122 -426.485558) (xy 417.912245 -426.485657) (xy 417.902658 -426.48745) (xy 417.898072 -426.489114)
			(xy 417.888928 -426.492924) (xy 417.215574 -427.166278) (xy 417.212865 -427.169127) (xy 417.208267 -427.175503)
			(xy 417.20643 -427.178978) (xy 417.203849 -427.184405) (xy 417.201032 -427.196085) (xy 417.200842 -427.202092)
			(xy 417.200842 -428.88154) (xy 417.201604 -428.889922) (xy 417.203122 -428.897525) (xy 417.210113 -428.911354)
			(xy 417.21532 -428.9171) (xy 417.74902 -429.4508) (xy 421.416743 -429.4508) (xy 421.420757 -429.387002)
			(xy 421.432734 -429.324211) (xy 421.452487 -429.263415) (xy 421.479703 -429.205574) (xy 421.513953 -429.1516)
			(xy 421.554697 -429.102344) (xy 421.601294 -429.058583) (xy 421.653007 -429.021007) (xy 421.709022 -428.990207)
			(xy 421.768455 -428.966671) (xy 421.830369 -428.950769) (xy 421.893788 -428.942751) (xy 421.92575 -428.942246)
			(xy 421.959632 -428.942816) (xy 422.026795 -428.951829) (xy 422.092168 -428.969674) (xy 422.154595 -428.996037)
			(xy 422.212971 -429.03045) (xy 422.266264 -429.072306) (xy 422.313531 -429.120864) (xy 422.334182 -429.147732)
			(xy 422.340675 -429.155804) (xy 422.358517 -429.166291) (xy 422.368726 -429.168052) (xy 422.452038 -429.178466)
			(xy 422.47185 -429.172624) (xy 422.479978 -429.16602) (xy 422.500467 -429.149836) (xy 422.54505 -429.122662)
			(xy 422.592924 -429.101825) (xy 422.643193 -429.087715) (xy 422.694918 -429.080594) (xy 422.721024 -429.080168)
			(xy 422.748272 -429.080704) (xy 422.802214 -429.088463) (xy 422.854503 -429.103819) (xy 422.904074 -429.12646)
			(xy 422.949918 -429.155925) (xy 422.991103 -429.191614) (xy 423.026789 -429.232801) (xy 423.056252 -429.278647)
			(xy 423.07889 -429.32822) (xy 423.094242 -429.380509) (xy 423.101998 -429.434452) (xy 423.101998 -429.448214)
			(xy 424.59351 -429.448214) (xy 424.597581 -429.392592) (xy 424.609707 -429.338155) (xy 424.62963 -429.286064)
			(xy 424.656926 -429.237429) (xy 424.691012 -429.193286) (xy 424.731161 -429.154577) (xy 424.776519 -429.122126)
			(xy 424.826119 -429.096625) (xy 424.878903 -429.078618) (xy 424.933746 -429.068488) (xy 424.98948 -429.066451)
			(xy 425.044917 -429.072551) (xy 425.098874 -429.086657) (xy 425.150203 -429.108469) (xy 425.197809 -429.137523)
			(xy 425.240677 -429.173198) (xy 425.277894 -429.214735) (xy 425.308667 -429.261248) (xy 425.332339 -429.311745)
			(xy 425.348407 -429.365152) (xy 425.356527 -429.420328) (xy 425.357036 -429.448214) (xy 425.356527 -429.4761)
			(xy 425.348407 -429.531276) (xy 425.332339 -429.584683) (xy 425.308667 -429.63518) (xy 425.277894 -429.681693)
			(xy 425.240677 -429.72323) (xy 425.197809 -429.758905) (xy 425.150203 -429.787959) (xy 425.098874 -429.809771)
			(xy 425.044917 -429.823877) (xy 424.98948 -429.829977) (xy 424.933746 -429.82794) (xy 424.878903 -429.81781)
			(xy 424.826119 -429.799803) (xy 424.776519 -429.774302) (xy 424.731161 -429.741851) (xy 424.691012 -429.703142)
			(xy 424.656926 -429.658999) (xy 424.62963 -429.610364) (xy 424.609707 -429.558273) (xy 424.597581 -429.503836)
			(xy 424.59351 -429.448214) (xy 423.101998 -429.448214) (xy 423.101998 -429.488948) (xy 423.094242 -429.542891)
			(xy 423.07889 -429.59518) (xy 423.056252 -429.644753) (xy 423.026789 -429.690599) (xy 422.991103 -429.731786)
			(xy 422.949918 -429.767475) (xy 422.904074 -429.79694) (xy 422.854503 -429.819581) (xy 422.802214 -429.834937)
			(xy 422.748272 -429.842696) (xy 422.721024 -429.843184) (xy 422.72077 -429.843184) (xy 422.693638 -429.842703)
			(xy 422.639925 -429.83499) (xy 422.587845 -429.819751) (xy 422.538446 -429.797293) (xy 422.492723 -429.768068)
			(xy 422.47185 -429.750728) (xy 422.463746 -429.744313) (xy 422.444074 -429.738029) (xy 422.43375 -429.738536)
			(xy 422.350438 -429.746664) (xy 422.331896 -429.756824) (xy 422.3258 -429.764698) (xy 422.305051 -429.790234)
			(xy 422.258094 -429.836322) (xy 422.205586 -429.87597) (xy 422.148402 -429.908515) (xy 422.087499 -429.933413)
			(xy 422.023894 -429.950248) (xy 421.958648 -429.95874) (xy 421.92575 -429.959262) (xy 421.893788 -429.958849)
			(xy 421.830369 -429.950831) (xy 421.768455 -429.934929) (xy 421.709022 -429.911393) (xy 421.653007 -429.880593)
			(xy 421.601294 -429.843017) (xy 421.554697 -429.799256) (xy 421.513953 -429.75) (xy 421.479703 -429.696026)
			(xy 421.452487 -429.638185) (xy 421.432734 -429.577389) (xy 421.420757 -429.514598) (xy 421.416743 -429.4508)
			(xy 417.74902 -429.4508) (xy 419.186106 -430.887886) (xy 419.191854 -430.893088) (xy 419.205684 -430.900077)
			(xy 419.213284 -430.901602) (xy 419.221666 -430.902364) (xy 427.23054 -430.902364)
		)
		(stroke
			(width 0)
			(type solid)
		)
		(fill yes)
		(layer "In6.Cu")
		(net "P1V8_CPU0_RT_1D")
	)
	(gr_poly
		(pts
			(xy 55.890414 -337.1342) (xy 55.902076 -337.133623) (xy 55.922983 -337.123286) (xy 55.930546 -337.114388)
			(xy 55.979822 -337.050634) (xy 55.983261 -337.045896) (xy 55.988126 -337.03525) (xy 55.989474 -337.029552)
			(xy 55.99176 -337.01863) (xy 55.988712 -337.006946) (xy 55.982955 -336.983553) (xy 55.976711 -336.935783)
			(xy 55.976266 -336.911696) (xy 55.976266 -336.907632) (xy 55.977028 -336.886804) (xy 55.979431 -336.857264)
			(xy 55.992213 -336.799394) (xy 56.013779 -336.744193) (xy 56.043611 -336.692984) (xy 56.061864 -336.669634)
			(xy 56.062372 -336.668618) (xy 56.064658 -336.665824) (xy 56.070246 -336.649822) (xy 56.070246 -336.60842)
			(xy 56.082692 -336.60842) (xy 56.082692 -336.55889) (xy 56.082438 -336.554064) (xy 56.081467 -336.546653)
			(xy 56.075785 -336.532837) (xy 56.071262 -336.526886) (xy 56.070246 -336.52587) (xy 56.053029 -336.50545)
			(xy 56.023882 -336.460693) (xy 56.001268 -336.412306) (xy 55.985631 -336.361235) (xy 55.977275 -336.308481)
			(xy 55.976366 -336.255078) (xy 55.982921 -336.20207) (xy 55.996812 -336.150497) (xy 56.017766 -336.101368)
			(xy 56.045373 -336.055645) (xy 56.061864 -336.034634) (xy 56.062372 -336.033618) (xy 56.064658 -336.030824)
			(xy 56.070246 -336.014822) (xy 56.070246 -335.97342) (xy 56.082692 -335.97342) (xy 56.082692 -335.92389)
			(xy 56.082438 -335.919064) (xy 56.081467 -335.911653) (xy 56.075785 -335.897837) (xy 56.071262 -335.891886)
			(xy 56.070246 -335.89087) (xy 56.052604 -335.869939) (xy 56.022878 -335.823973) (xy 56.000036 -335.774226)
			(xy 55.984548 -335.721722) (xy 55.976732 -335.667542) (xy 55.976266 -335.640172) (xy 55.976754 -335.612921)
			(xy 55.984513 -335.558975) (xy 55.999871 -335.506682) (xy 56.022513 -335.457107) (xy 56.05198 -335.411258)
			(xy 56.087671 -335.370069) (xy 56.12886 -335.334378) (xy 56.174709 -335.304912) (xy 56.224284 -335.28227)
			(xy 56.276577 -335.266913) (xy 56.330523 -335.259154) (xy 56.357774 -335.258664) (xy 56.386513 -335.259183)
			(xy 56.443342 -335.267804) (xy 56.498234 -335.284853) (xy 56.549946 -335.309946) (xy 56.597308 -335.342513)
			(xy 56.618632 -335.361788) (xy 56.625998 -335.368646) (xy 56.634634 -335.371948) (xy 56.639097 -335.373579)
			(xy 56.648426 -335.375376) (xy 56.653176 -335.375504) (xy 56.722772 -335.375504) (xy 56.727526 -335.375408)
			(xy 56.736863 -335.373619) (xy 56.741314 -335.371948) (xy 56.74995 -335.368646) (xy 56.757316 -335.361788)
			(xy 56.778643 -335.342517) (xy 56.826006 -335.309952) (xy 56.877717 -335.284859) (xy 56.932608 -335.267807)
			(xy 56.989435 -335.259182) (xy 57.018174 -335.258664) (xy 57.045427 -335.259148) (xy 57.099379 -335.266901)
			(xy 57.151679 -335.282254) (xy 57.201261 -335.304893) (xy 57.247117 -335.334358) (xy 57.288312 -335.370049)
			(xy 57.324009 -335.41124) (xy 57.353481 -335.457092) (xy 57.376127 -335.506671) (xy 57.391487 -335.558968)
			(xy 57.399248 -335.612919) (xy 57.399682 -335.640172) (xy 57.399214 -335.666214) (xy 57.392081 -335.717808)
			(xy 57.377998 -335.767953) (xy 57.357228 -335.815716) (xy 57.330155 -335.860212) (xy 57.314084 -335.88071)
			(xy 57.313576 -335.881726) (xy 57.31129 -335.88452) (xy 57.305702 -335.900522) (xy 57.305702 -335.941924)
			(xy 57.293256 -335.941924) (xy 57.293256 -335.991454) (xy 57.29351 -335.99628) (xy 57.294475 -336.003694)
			(xy 57.30015 -336.017516) (xy 57.304686 -336.023458) (xy 57.305702 -336.024474) (xy 57.323345 -336.045405)
			(xy 57.353074 -336.091371) (xy 57.375921 -336.141117) (xy 57.391415 -336.193621) (xy 57.399237 -336.247801)
			(xy 57.399624 -336.271616) (xy 58.081926 -336.271616) (xy 58.082395 -336.244246) (xy 58.090211 -336.190067)
			(xy 58.105699 -336.137563) (xy 58.12854 -336.087816) (xy 58.158265 -336.04185) (xy 58.175906 -336.020918)
			(xy 58.17616 -336.020664) (xy 58.181733 -336.013568) (xy 58.187986 -335.996658) (xy 58.188352 -335.987644)
			(xy 58.188352 -335.920588) (xy 58.188011 -335.911569) (xy 58.181753 -335.894652) (xy 58.17616 -335.887568)
			(xy 58.175906 -335.887568) (xy 58.175906 -335.887314) (xy 58.158261 -335.866387) (xy 58.12855 -335.820413)
			(xy 58.105715 -335.770664) (xy 58.090225 -335.718162) (xy 58.082399 -335.663986) (xy 58.081926 -335.636616)
			(xy 58.08237 -335.609362) (xy 58.090126 -335.555409) (xy 58.105482 -335.503108) (xy 58.128125 -335.453526)
			(xy 58.157594 -335.407671) (xy 58.19329 -335.366477) (xy 58.234486 -335.330784) (xy 58.280342 -335.301316)
			(xy 58.329925 -335.278675) (xy 58.382226 -335.263322) (xy 58.43618 -335.255569) (xy 58.463434 -335.255108)
			(xy 58.489629 -335.255538) (xy 58.541526 -335.262706) (xy 58.591956 -335.276902) (xy 58.639971 -335.297861)
			(xy 58.68467 -335.325188) (xy 58.725212 -335.358369) (xy 58.743342 -335.377282) (xy 58.750896 -335.38461)
			(xy 58.770169 -335.393008) (xy 58.78068 -335.393538) (xy 58.854848 -335.393538) (xy 58.865371 -335.393054)
			(xy 58.884664 -335.384656) (xy 58.892186 -335.377282) (xy 58.910325 -335.358378) (xy 58.950863 -335.325193)
			(xy 58.995559 -335.297863) (xy 59.043573 -335.276903) (xy 59.094002 -335.262707) (xy 59.145899 -335.255541)
			(xy 59.172094 -335.255108) (xy 59.199347 -335.255561) (xy 59.2533 -335.263318) (xy 59.305599 -335.278674)
			(xy 59.35518 -335.301317) (xy 59.401034 -335.330785) (xy 59.442227 -335.36648) (xy 59.477921 -335.407674)
			(xy 59.507388 -335.453529) (xy 59.53003 -335.503111) (xy 59.545385 -335.55541) (xy 59.55314 -335.609363)
			(xy 59.553602 -335.636616) (xy 59.553145 -335.663987) (xy 59.545325 -335.718166) (xy 59.529834 -335.770669)
			(xy 59.50699 -335.820416) (xy 59.477264 -335.866382) (xy 59.459622 -335.887314) (xy 59.459368 -335.887568)
			(xy 59.453785 -335.894657) (xy 59.447537 -335.911572) (xy 59.447176 -335.920588) (xy 59.447176 -335.987644)
			(xy 59.447565 -335.996658) (xy 59.453791 -336.013575) (xy 59.459368 -336.020664) (xy 59.459622 -336.020664)
			(xy 59.459622 -336.020918) (xy 59.47724 -336.041867) (xy 59.506954 -336.087836) (xy 59.529794 -336.137579)
			(xy 59.54529 -336.190076) (xy 59.553124 -336.244248) (xy 59.553602 -336.271616) (xy 59.553137 -336.298868)
			(xy 59.545378 -336.352817) (xy 59.530021 -336.405112) (xy 59.507377 -336.45469) (xy 59.477909 -336.500541)
			(xy 59.442215 -336.541731) (xy 59.401023 -336.577422) (xy 59.355171 -336.606888) (xy 59.305592 -336.629528)
			(xy 59.253295 -336.644883) (xy 59.199346 -336.652639) (xy 59.172094 -336.653124) (xy 59.1459 -336.652665)
			(xy 59.094004 -336.645502) (xy 59.043575 -336.63131) (xy 58.99556 -336.610357) (xy 58.950861 -336.583036)
			(xy 58.910317 -336.54986) (xy 58.892186 -336.53095) (xy 58.884654 -336.523595) (xy 58.865364 -336.515211)
			(xy 58.854848 -336.514694) (xy 58.78068 -336.514694) (xy 58.770161 -336.515213) (xy 58.75087 -336.523588)
			(xy 58.743342 -336.53095) (xy 58.725196 -336.549846) (xy 58.684658 -336.583031) (xy 58.639964 -336.610361)
			(xy 58.591951 -336.631322) (xy 58.541524 -336.64552) (xy 58.489628 -336.652689) (xy 58.463434 -336.653124)
			(xy 58.436183 -336.652613) (xy 58.382234 -336.644861) (xy 58.329938 -336.62951) (xy 58.280359 -336.606873)
			(xy 58.234507 -336.57741) (xy 58.193314 -336.541721) (xy 58.15762 -336.500533) (xy 58.128151 -336.454685)
			(xy 58.105507 -336.405109) (xy 58.090149 -336.352815) (xy 58.08239 -336.298867) (xy 58.081926 -336.271616)
			(xy 57.399624 -336.271616) (xy 57.399682 -336.275172) (xy 57.399214 -336.301214) (xy 57.392081 -336.352808)
			(xy 57.377998 -336.402953) (xy 57.357228 -336.450716) (xy 57.330155 -336.495212) (xy 57.314084 -336.51571)
			(xy 57.313576 -336.516726) (xy 57.31129 -336.51952) (xy 57.305702 -336.535522) (xy 57.305702 -336.576924)
			(xy 57.293256 -336.576924) (xy 57.293256 -336.626454) (xy 57.29351 -336.63128) (xy 57.294475 -336.638694)
			(xy 57.30015 -336.652516) (xy 57.304686 -336.658458) (xy 57.305702 -336.659474) (xy 57.323345 -336.680405)
			(xy 57.353074 -336.726371) (xy 57.375921 -336.776117) (xy 57.391415 -336.828621) (xy 57.399237 -336.882801)
			(xy 57.399682 -336.910172) (xy 57.399682 -336.913728) (xy 57.399174 -336.931762) (xy 57.399174 -336.93227)
			(xy 57.397821 -336.951164) (xy 57.391842 -336.988572) (xy 57.387236 -337.006946) (xy 57.384188 -337.01863)
			(xy 57.386474 -337.029552) (xy 57.387761 -337.03527) (xy 57.392638 -337.045924) (xy 57.396126 -337.050634)
			(xy 57.445402 -337.114388) (xy 57.45299 -337.123244) (xy 57.473889 -337.133539) (xy 57.485534 -337.1342)
			(xy 61.391038 -337.1342) (xy 61.40069 -337.133184) (xy 61.407932 -337.131552) (xy 61.421095 -337.124705)
			(xy 61.426598 -337.119722) (xy 62.088776 -336.457544) (xy 62.098525 -336.457026) (xy 62.116551 -336.449575)
			(xy 62.123828 -336.443066) (xy 62.388242 -336.178906) (xy 62.407292 -336.159856) (xy 62.4078 -336.159348)
			(xy 62.408308 -336.15884) (xy 62.41384 -336.152517) (xy 62.420729 -336.137204) (xy 62.42177 -336.128868)
			(xy 62.422024 -336.124042) (xy 62.422024 -328.426318) (xy 62.422463 -328.416255) (xy 62.430201 -328.397674)
			(xy 62.43701 -328.39025) (xy 63.450978 -327.376282) (xy 63.458377 -327.369439) (xy 63.476976 -327.36172)
			(xy 63.487046 -327.361296) (xy 65.753234 -327.361296) (xy 65.766442 -327.359518) (xy 65.773046 -327.35774)
			(xy 65.777872 -327.354692) (xy 65.784031 -327.350942) (xy 65.797843 -327.34682) (xy 65.80505 -327.346564)
			(xy 100.100892 -327.346564) (xy 100.110962 -327.346142) (xy 100.129565 -327.338425) (xy 100.13696 -327.331578)
			(xy 100.68306 -326.785478) (xy 100.689907 -326.77808) (xy 100.69764 -326.759482) (xy 100.698046 -326.74941)
			(xy 100.698046 -326.741282) (xy 100.69703 -326.710802) (xy 100.69703 -326.710294) (xy 100.698046 -326.681338)
			(xy 100.698046 -326.107806) (xy 100.698046 -326.104758) (xy 100.69703 -326.075802) (xy 100.69703 -326.075294)
			(xy 100.698046 -326.046338) (xy 100.698046 -325.472806) (xy 100.698046 -325.469758) (xy 100.69703 -325.440802)
			(xy 100.69703 -325.440294) (xy 100.698046 -325.411338) (xy 100.698046 -324.9422) (xy 100.69576 -324.93458)
			(xy 100.684515 -324.896965) (xy 100.672396 -324.8194) (xy 100.67163 -324.780148) (xy 100.672376 -324.740894)
			(xy 100.684495 -324.663326) (xy 100.69576 -324.625716) (xy 100.698046 -324.618096) (xy 100.698046 -324.3072)
			(xy 100.69576 -324.29958) (xy 100.684515 -324.261965) (xy 100.672396 -324.1844) (xy 100.67163 -324.145148)
			(xy 100.672376 -324.105894) (xy 100.684495 -324.028326) (xy 100.69576 -323.990716) (xy 100.698046 -323.983096)
			(xy 100.698046 -323.6722) (xy 100.69576 -323.66458) (xy 100.684515 -323.626965) (xy 100.672396 -323.5494)
			(xy 100.67163 -323.510148) (xy 100.672376 -323.470894) (xy 100.684495 -323.393326) (xy 100.69576 -323.355716)
			(xy 100.698046 -323.348096) (xy 100.698046 -323.0372) (xy 100.69576 -323.02958) (xy 100.684515 -322.991965)
			(xy 100.672396 -322.9144) (xy 100.67163 -322.875148) (xy 100.672376 -322.835894) (xy 100.684495 -322.758326)
			(xy 100.69576 -322.720716) (xy 100.698046 -322.713096) (xy 100.698046 -322.4022) (xy 100.69576 -322.39458)
			(xy 100.684515 -322.356965) (xy 100.672396 -322.2794) (xy 100.67163 -322.240148) (xy 100.672376 -322.200894)
			(xy 100.684495 -322.123326) (xy 100.69576 -322.085716) (xy 100.698046 -322.078096) (xy 100.698046 -321.7672)
			(xy 100.69576 -321.75958) (xy 100.684515 -321.721965) (xy 100.672396 -321.6444) (xy 100.67163 -321.605148)
			(xy 100.672376 -321.565894) (xy 100.684495 -321.488326) (xy 100.69576 -321.450716) (xy 100.698046 -321.443096)
			(xy 100.698046 -321.267074) (xy 100.698475 -321.257007) (xy 100.706201 -321.238414) (xy 100.713032 -321.231006)
			(xy 101.840538 -320.1035) (xy 101.847391 -320.096105) (xy 101.855136 -320.077506) (xy 101.855524 -320.067432)
			(xy 101.855524 -313.084718) (xy 101.855371 -313.079483) (xy 101.853204 -313.069239) (xy 101.851206 -313.064398)
			(xy 101.79177 -312.928762) (xy 101.787452 -312.920888) (xy 100.595938 -311.137554) (xy 100.595684 -311.137554)
			(xy 100.568638 -311.096393) (xy 100.519346 -311.011114) (xy 100.475732 -310.922796) (xy 100.456492 -310.877458)
			(xy 100.456238 -310.87695) (xy 96.905826 -302.305466) (xy 96.903815 -302.300961) (xy 96.898314 -302.292775)
			(xy 96.894904 -302.28921) (xy 95.994982 -301.383446) (xy 95.99168 -301.379636) (xy 95.976694 -301.361094)
			(xy 95.961962 -301.35195) (xy 95.956882 -301.350934) (xy 95.953072 -301.350172) (xy 95.926455 -301.343986)
			(xy 95.875206 -301.325025) (xy 95.827185 -301.298949) (xy 95.783374 -301.26629) (xy 95.744669 -301.227717)
			(xy 95.71186 -301.184018) (xy 95.685619 -301.136087) (xy 95.666482 -301.084904) (xy 95.654841 -301.031514)
			(xy 95.650933 -300.97701) (xy 95.654838 -300.922505) (xy 95.666477 -300.869115) (xy 95.685611 -300.81793)
			(xy 95.71185 -300.769998) (xy 95.744656 -300.726297) (xy 95.78336 -300.687722) (xy 95.827169 -300.655062)
			(xy 95.875189 -300.628983) (xy 95.926437 -300.610019) (xy 95.953072 -300.60392) (xy 95.953326 -300.60392)
			(xy 95.961675 -300.601724) (xy 95.976344 -300.592638) (xy 95.982028 -300.58614) (xy 95.987362 -300.579536)
			(xy 95.993204 -300.56328) (xy 95.993204 -300.147228) (xy 95.991934 -300.136052) (xy 95.989394 -300.127924)
			(xy 95.894652 -299.899578) (xy 95.880695 -299.864293) (xy 95.861031 -299.791004) (xy 95.851098 -299.715776)
			(xy 95.850456 -299.677836) (xy 95.850456 -296.234358) (xy 95.850634 -296.21589) (xy 95.853048 -296.179032)
			(xy 95.855282 -296.160698) (xy 95.855282 -296.16019) (xy 95.85579 -296.153586) (xy 95.847154 -296.126154)
			(xy 95.844868 -296.122344) (xy 95.840015 -296.114707) (xy 95.831116 -296.09895) (xy 95.827088 -296.090848)
			(xy 95.818706 -296.072052) (xy 95.817944 -296.070274) (xy 95.81515 -296.064686) (xy 95.814134 -296.063162)
			(xy 95.801649 -296.041117) (xy 95.783365 -295.99387) (xy 95.773125 -295.944255) (xy 95.771208 -295.89363)
			(xy 95.777667 -295.843383) (xy 95.792326 -295.794889) (xy 95.814781 -295.749477) (xy 95.84442 -295.708391)
			(xy 95.880429 -295.672755) (xy 95.921823 -295.643547) (xy 95.944436 -295.632124) (xy 95.951548 -295.628822)
			(xy 95.972884 -295.60901) (xy 95.976948 -295.598596) (xy 95.994679 -295.556163) (xy 96.037456 -295.474746)
			(xy 96.088158 -295.398014) (xy 96.146279 -295.326737) (xy 96.17837 -295.293796) (xy 96.178624 -295.293796)
			(xy 96.250252 -295.221914) (xy 96.25711 -295.195498) (xy 96.25457 -295.1861) (xy 96.248421 -295.16452)
			(xy 96.24179 -295.120143) (xy 96.241362 -295.097708) (xy 96.241362 -295.097454) (xy 96.241904 -295.071572)
			(xy 96.250628 -295.02055) (xy 96.267836 -294.971731) (xy 96.27997 -294.948864) (xy 96.292081 -294.928003)
			(xy 96.321845 -294.890047) (xy 96.357208 -294.857245) (xy 96.376998 -294.843454) (xy 96.378522 -294.842438)
			(xy 96.383602 -294.838882) (xy 96.399604 -294.818054) (xy 96.405954 -294.809418) (xy 96.408494 -294.800274)
			(xy 96.422277 -294.752304) (xy 96.45725 -294.658818) (xy 96.478344 -294.613584) (xy 96.478598 -294.613076)
			(xy 96.481392 -294.60698) (xy 96.492691 -294.584152) (xy 96.517084 -294.539431) (xy 96.53016 -294.517572)
			(xy 96.539108 -294.502973) (xy 96.557782 -294.474267) (xy 96.567498 -294.460168) (xy 96.589128 -294.429547)
			(xy 96.635905 -294.370952) (xy 96.66097 -294.343074) (xy 96.66732 -294.335708) (xy 96.675448 -294.31615)
			(xy 96.677988 -294.309546) (xy 96.679183 -294.305909) (xy 96.680583 -294.298383) (xy 96.680782 -294.29456)
			(xy 96.66224 -294.273478) (xy 96.633083 -294.239726) (xy 96.579577 -294.168354) (xy 96.531862 -294.092988)
			(xy 96.490236 -294.014096) (xy 96.454957 -293.932168) (xy 96.426245 -293.847715) (xy 96.414844 -293.804594)
			(xy 96.41238 -293.796285) (xy 96.402758 -293.781887) (xy 96.396048 -293.7764) (xy 96.373648 -293.76004)
			(xy 96.334644 -293.720611) (xy 96.30342 -293.674773) (xy 96.291654 -293.649654) (xy 96.291654 -293.649146)
			(xy 96.288098 -293.640764) (xy 96.284542 -293.63416) (xy 96.284288 -293.633652) (xy 96.272527 -293.613045)
			(xy 96.254836 -293.569021) (xy 96.244177 -293.522788) (xy 96.240807 -293.475463) (xy 96.242378 -293.451788)
			(xy 96.245223 -293.424861) (xy 96.259207 -293.372556) (xy 96.282216 -293.323547) (xy 96.313525 -293.279376)
			(xy 96.352149 -293.241435) (xy 96.374204 -293.225728) (xy 96.377252 -293.223188) (xy 96.384618 -293.218362)
			(xy 96.397318 -293.201344) (xy 96.40189 -293.193724) (xy 96.405954 -293.185342) (xy 96.40951 -293.176452)
			(xy 96.42729 -293.119048) (xy 96.442437 -293.075652) (xy 96.478898 -292.99127) (xy 96.522163 -292.910166)
			(xy 96.571942 -292.832888) (xy 96.627897 -292.759958) (xy 96.65843 -292.725602) (xy 96.661478 -292.722046)
			(xy 96.669606 -292.708838) (xy 96.6724 -292.70325) (xy 96.677226 -292.69182) (xy 96.67748 -292.691058)
			(xy 96.677988 -292.689026) (xy 96.679146 -292.68551) (xy 96.680551 -292.678242) (xy 96.680782 -292.674548)
			(xy 96.661986 -292.652958) (xy 96.632655 -292.61896) (xy 96.578858 -292.547059) (xy 96.53093 -292.47112)
			(xy 96.489172 -292.39162) (xy 96.453847 -292.309061) (xy 96.425178 -292.223962) (xy 96.413828 -292.180518)
			(xy 96.413828 -292.180264) (xy 96.40316 -292.165024) (xy 96.400673 -292.161699) (xy 96.394801 -292.155827)
			(xy 96.391476 -292.15334) (xy 96.368983 -292.13619) (xy 96.330175 -292.095047) (xy 96.299593 -292.047471)
			(xy 96.288352 -292.021514) (xy 96.288098 -292.020752) (xy 96.284796 -292.014148) (xy 96.284288 -292.01364)
			(xy 96.271106 -291.99041) (xy 96.252194 -291.940463) (xy 96.246696 -291.914326) (xy 96.245702 -291.909546)
			(xy 96.242116 -291.900467) (xy 96.239584 -291.896292) (xy 96.23298 -291.88791) (xy 96.198972 -291.852412)
			(xy 96.136554 -291.776454) (xy 96.080961 -291.695368) (xy 96.03261 -291.609766) (xy 95.991866 -291.520292)
			(xy 95.959037 -291.427621) (xy 95.946214 -291.380164) (xy 95.941642 -291.36848) (xy 95.921594 -291.356251)
			(xy 95.885023 -291.326793) (xy 95.853222 -291.292241) (xy 95.826892 -291.253358) (xy 95.806615 -291.211003)
			(xy 95.792838 -291.16611) (xy 95.785866 -291.119671) (xy 95.785432 -291.096192) (xy 95.785859 -291.072683)
			(xy 95.792824 -291.026183) (xy 95.806613 -290.981232) (xy 95.826922 -290.938825) (xy 95.853299 -290.899903)
			(xy 95.885162 -290.865326) (xy 95.921803 -290.835862) (xy 95.941896 -290.82365) (xy 95.946468 -290.81222)
			(xy 95.95921 -290.765099) (xy 95.991753 -290.673062) (xy 96.032108 -290.584173) (xy 96.079976 -290.499093)
			(xy 96.134999 -290.418456) (xy 96.196768 -290.342862) (xy 96.23044 -290.307522) (xy 96.236991 -290.29926)
			(xy 96.243401 -290.279194) (xy 96.242886 -290.26866) (xy 96.240709 -290.241615) (xy 96.24482 -290.187519)
			(xy 96.258447 -290.135007) (xy 96.281159 -290.085738) (xy 96.296226 -290.063174) (xy 96.312495 -290.040805)
			(xy 96.351729 -290.001826) (xy 96.374204 -289.985704) (xy 96.377252 -289.983164) (xy 96.384618 -289.978338)
			(xy 96.405954 -289.949636) (xy 96.408494 -289.940492) (xy 96.420569 -289.898196) (xy 96.450497 -289.815476)
			(xy 96.486834 -289.735364) (xy 96.529356 -289.658356) (xy 96.577799 -289.584929) (xy 96.631864 -289.515536)
			(xy 96.661224 -289.482784) (xy 96.667574 -289.475672) (xy 96.67494 -289.457384) (xy 96.677226 -289.451542)
			(xy 96.677226 -289.451288) (xy 96.678744 -289.447255) (xy 96.680541 -289.438827) (xy 96.680782 -289.434524)
			(xy 96.662494 -289.413696) (xy 96.629921 -289.375898) (xy 96.570806 -289.295504) (xy 96.519002 -289.210217)
			(xy 96.47491 -289.120698) (xy 96.438874 -289.027645) (xy 96.424496 -288.979864) (xy 96.421445 -288.970713)
			(xy 96.409706 -288.955427) (xy 96.401636 -288.950146) (xy 96.379299 -288.936267) (xy 96.338936 -288.902562)
			(xy 96.304426 -288.862884) (xy 96.276643 -288.818238) (xy 96.266 -288.79419) (xy 96.26473 -288.791142)
			(xy 96.26473 -288.790888) (xy 96.26219 -288.786062) (xy 96.250206 -288.764965) (xy 96.231864 -288.720048)
			(xy 96.220268 -288.672937) (xy 96.215666 -288.624638) (xy 96.21647 -288.600388) (xy 96.218457 -288.572809)
			(xy 96.230458 -288.518838) (xy 96.251265 -288.467614) (xy 96.2803 -288.420562) (xy 96.316754 -288.378993)
			(xy 96.359613 -288.344063) (xy 96.383348 -288.329878) (xy 96.386396 -288.3281) (xy 96.391476 -288.325052)
			(xy 96.415352 -288.296096) (xy 96.4184 -288.286444) (xy 96.433469 -288.239627) (xy 96.470728 -288.148597)
			(xy 96.515842 -288.061194) (xy 96.568463 -287.978094) (xy 96.628182 -287.899939) (xy 96.66097 -287.86328)
			(xy 96.66732 -287.855914) (xy 96.674432 -287.838642) (xy 96.677226 -287.83153) (xy 96.678787 -287.827377)
			(xy 96.680584 -287.81869) (xy 96.680782 -287.814258) (xy 96.662494 -287.79343) (xy 96.633654 -287.76002)
			(xy 96.580678 -287.689416) (xy 96.533367 -287.614898) (xy 96.492008 -287.536919) (xy 96.456853 -287.455953)
			(xy 96.428116 -287.372493) (xy 96.416622 -287.32988) (xy 96.414082 -287.320482) (xy 96.402144 -287.303972)
			(xy 96.399743 -287.300811) (xy 96.394126 -287.295202) (xy 96.390968 -287.292796) (xy 96.368538 -287.275557)
			(xy 96.329817 -287.234323) (xy 96.29932 -287.186685) (xy 96.288098 -287.160716) (xy 96.284796 -287.154112)
			(xy 96.284288 -287.153604) (xy 96.271008 -287.130198) (xy 96.251978 -287.079864) (xy 96.246442 -287.053528)
			(xy 96.244853 -287.046157) (xy 96.238009 -287.03273) (xy 96.23298 -287.027112) (xy 96.197684 -286.990259)
			(xy 96.133146 -286.911205) (xy 96.075994 -286.826658) (xy 96.026694 -286.737304) (xy 96.00565 -286.690816)
			(xy 96.003643 -286.686526) (xy 95.998282 -286.678719) (xy 95.994982 -286.675322) (xy 95.772986 -286.453326)
			(xy 95.766142 -286.445928) (xy 95.758421 -286.427328) (xy 95.758 -286.417258) (xy 95.758 -286.018986)
			(xy 95.758426 -286.008917) (xy 95.766144 -285.990316) (xy 95.772986 -285.982918) (xy 96.035114 -285.72079)
			(xy 96.03867 -285.713932) (xy 96.061878 -285.67062) (xy 96.11479 -285.58781) (xy 96.174721 -285.509929)
			(xy 96.20758 -285.473394) (xy 96.214969 -285.46453) (xy 96.221578 -285.442443) (xy 96.22028 -285.430976)
			(xy 96.21767 -285.413515) (xy 96.215759 -285.378259) (xy 96.21647 -285.360618) (xy 96.218454 -285.333038)
			(xy 96.230451 -285.279064) (xy 96.251256 -285.227836) (xy 96.280289 -285.18078) (xy 96.316742 -285.139207)
			(xy 96.3596 -285.104274) (xy 96.383348 -285.090108) (xy 96.386396 -285.08833) (xy 96.391476 -285.085282)
			(xy 96.407224 -285.065978) (xy 96.410018 -285.061914) (xy 96.411034 -285.059882) (xy 96.415606 -285.0515)
			(xy 96.416114 -285.050484) (xy 96.419416 -285.042356) (xy 96.434429 -284.996353) (xy 96.471345 -284.906893)
			(xy 96.515856 -284.820959) (xy 96.567627 -284.739195) (xy 96.626273 -284.662211) (xy 96.65843 -284.62605)
			(xy 96.664018 -284.61843) (xy 96.668844 -284.610556) (xy 96.6724 -284.603444) (xy 96.677226 -284.592014)
			(xy 96.677988 -284.588966) (xy 96.678496 -284.587442) (xy 96.679258 -284.585156) (xy 96.680782 -284.572964)
			(xy 96.680782 -284.562296) (xy 96.68071 -284.557822) (xy 96.679177 -284.549006) (xy 96.677734 -284.54477)
			(xy 96.66478 -284.519116) (xy 96.664018 -284.5181) (xy 96.656906 -284.507432) (xy 96.654366 -284.504638)
			(xy 96.642152 -284.490883) (xy 96.618526 -284.462683) (xy 96.607122 -284.44825) (xy 96.576342 -284.408135)
			(xy 96.52133 -284.323289) (xy 96.474201 -284.233824) (xy 96.435341 -284.140469) (xy 96.41967 -284.092396)
			(xy 96.418373 -284.088464) (xy 96.414674 -284.081058) (xy 96.412304 -284.077664) (xy 96.397826 -284.057852)
			(xy 96.391222 -284.05328) (xy 96.368893 -284.036233) (xy 96.330306 -283.995413) (xy 96.299856 -283.948212)
			(xy 96.288606 -283.92247) (xy 96.288606 -283.921962) (xy 96.288098 -283.920946) (xy 96.284542 -283.914342)
			(xy 96.284288 -283.913834) (xy 96.272529 -283.893226) (xy 96.25484 -283.849203) (xy 96.244183 -283.80297)
			(xy 96.240816 -283.755645) (xy 96.242378 -283.73197) (xy 96.245211 -283.705192) (xy 96.259086 -283.653168)
			(xy 96.281877 -283.604387) (xy 96.312878 -283.560365) (xy 96.351126 -283.522469) (xy 96.372934 -283.506672)
			(xy 96.374204 -283.50591) (xy 96.377252 -283.50337) (xy 96.384618 -283.498544) (xy 96.405954 -283.469842)
			(xy 96.408494 -283.460698) (xy 96.420569 -283.418402) (xy 96.450496 -283.335681) (xy 96.486833 -283.255569)
			(xy 96.529354 -283.178561) (xy 96.577797 -283.105134) (xy 96.631862 -283.035741) (xy 96.661224 -283.00299)
			(xy 96.667574 -282.995878) (xy 96.677226 -282.971748) (xy 96.677226 -282.971494) (xy 96.67889 -282.967041)
			(xy 96.680672 -282.957705) (xy 96.680782 -282.952952) (xy 96.680782 -282.942284) (xy 96.680709 -282.93781)
			(xy 96.679173 -282.928995) (xy 96.677734 -282.924758) (xy 96.66478 -282.899104) (xy 96.664018 -282.898088)
			(xy 96.656906 -282.88742) (xy 96.654366 -282.884626) (xy 96.6216 -282.846526) (xy 96.591141 -282.808522)
			(xy 96.536193 -282.728098) (xy 96.488449 -282.6432) (xy 96.44827 -282.554471) (xy 96.431608 -282.508706)
			(xy 96.429982 -282.504519) (xy 96.425512 -282.496729) (xy 96.422718 -282.493212) (xy 96.406208 -282.4734)
			(xy 96.398842 -282.468828) (xy 96.376453 -282.454524) (xy 96.336125 -282.419942) (xy 96.318578 -282.399994)
			(xy 96.302626 -282.380448) (xy 96.276219 -282.337463) (xy 96.266 -282.314396) (xy 96.26473 -282.311348)
			(xy 96.26473 -282.311094) (xy 96.26219 -282.306268) (xy 96.250206 -282.285172) (xy 96.231863 -282.240255)
			(xy 96.220266 -282.193143) (xy 96.215663 -282.144844) (xy 96.21647 -282.120594) (xy 96.218456 -282.093015)
			(xy 96.230456 -282.039043) (xy 96.251263 -281.987818) (xy 96.280298 -281.940766) (xy 96.316752 -281.899196)
			(xy 96.35961 -281.864265) (xy 96.383348 -281.850084) (xy 96.386396 -281.848306) (xy 96.391476 -281.845258)
			(xy 96.415352 -281.816302) (xy 96.4184 -281.80665) (xy 96.4184 -281.806396) (xy 96.43348 -281.759545)
			(xy 96.470772 -281.668451) (xy 96.51593 -281.58099) (xy 96.568605 -281.497839) (xy 96.62839 -281.419643)
			(xy 96.661224 -281.382978) (xy 96.667574 -281.375866) (xy 96.677226 -281.351736) (xy 96.677226 -281.351482)
			(xy 96.678897 -281.34703) (xy 96.680696 -281.337694) (xy 96.680782 -281.33294) (xy 96.680782 -281.322272)
			(xy 96.680708 -281.317798) (xy 96.67917 -281.308984) (xy 96.677734 -281.304746) (xy 96.66478 -281.279092)
			(xy 96.664018 -281.278076) (xy 96.656906 -281.267408) (xy 96.654366 -281.264614) (xy 96.642152 -281.250859)
			(xy 96.618527 -281.222659) (xy 96.607122 -281.208226) (xy 96.576342 -281.168111) (xy 96.521332 -281.083264)
			(xy 96.474206 -280.993798) (xy 96.435347 -280.900443) (xy 96.41967 -280.852372) (xy 96.418372 -280.848441)
			(xy 96.41467 -280.841037) (xy 96.412304 -280.83764) (xy 96.397826 -280.817828) (xy 96.391222 -280.813256)
			(xy 96.374106 -280.800312) (xy 96.343338 -280.770401) (xy 96.317073 -280.736466) (xy 96.306132 -280.718006)
			(xy 96.301165 -280.709125) (xy 96.292271 -280.690821) (xy 96.288352 -280.68143) (xy 96.284796 -280.674826)
			(xy 96.284542 -280.674318) (xy 96.272862 -280.654012) (xy 96.2552 -280.610625) (xy 96.244393 -280.565045)
			(xy 96.242124 -280.54173) (xy 96.241362 -280.533094) (xy 96.226376 -280.49855) (xy 96.22028 -280.4922)
			(xy 96.219518 -280.491438) (xy 96.189285 -280.460113) (xy 96.133239 -280.393484) (xy 96.082546 -280.322698)
			(xy 96.037513 -280.248183) (xy 95.998413 -280.17039) (xy 95.965483 -280.089792) (xy 95.951802 -280.048462)
			(xy 95.950402 -280.044384) (xy 95.946442 -280.036725) (xy 95.943928 -280.033222) (xy 95.93961 -280.027634)
			(xy 95.917443 -280.013847) (xy 95.877597 -279.980124) (xy 95.843853 -279.940297) (xy 95.817132 -279.895455)
			(xy 95.798163 -279.846822) (xy 95.79229 -279.821386) (xy 95.790258 -279.81402) (xy 95.782006 -279.790389)
			(xy 95.772444 -279.741259) (xy 95.771025 -279.691228) (xy 95.777785 -279.641635) (xy 95.792545 -279.593809)
			(xy 95.814908 -279.549031) (xy 95.844276 -279.508501) (xy 95.879861 -279.473304) (xy 95.899986 -279.45842)
			(xy 95.903288 -279.456134) (xy 95.903542 -279.45588) (xy 95.906844 -279.453594) (xy 95.907352 -279.45334)
			(xy 95.907352 -279.453086) (xy 95.90786 -279.452832) (xy 95.914718 -279.44826) (xy 95.936308 -279.419304)
			(xy 95.938848 -279.41016) (xy 95.951941 -279.364631) (xy 95.984803 -279.275769) (xy 96.025067 -279.190006)
			(xy 96.072444 -279.107959) (xy 96.126595 -279.030216) (xy 96.187132 -278.957334) (xy 96.220026 -278.923242)
			(xy 96.22028 -278.922988) (xy 96.226884 -278.91613) (xy 96.233996 -278.89962) (xy 96.233996 -278.899112)
			(xy 96.241362 -278.882348) (xy 96.242124 -278.873966) (xy 96.244834 -278.846967) (xy 96.258567 -278.794477)
			(xy 96.28135 -278.745235) (xy 96.312469 -278.700789) (xy 96.350945 -278.662534) (xy 96.372934 -278.646636)
			(xy 96.373696 -278.646128) (xy 96.374966 -278.645112) (xy 96.377252 -278.643334) (xy 96.384618 -278.638508)
			(xy 96.405954 -278.609806) (xy 96.408494 -278.600662) (xy 96.421555 -278.555192) (xy 96.454341 -278.466441)
			(xy 96.494515 -278.380781) (xy 96.517714 -278.33955) (xy 96.541864 -278.298526) (xy 96.596154 -278.220319)
			(xy 96.656899 -278.147012) (xy 96.689926 -278.112728) (xy 96.69018 -278.112474) (xy 96.696784 -278.105616)
			(xy 96.703896 -278.089106) (xy 96.703896 -278.088598) (xy 96.711262 -278.071834) (xy 96.712024 -278.063452)
			(xy 96.714704 -278.036749) (xy 96.728225 -277.984819) (xy 96.750608 -277.936048) (xy 96.781165 -277.891937)
			(xy 96.818958 -277.853841) (xy 96.840548 -277.8379) (xy 96.844104 -277.835614) (xy 96.844358 -277.83536)
			(xy 96.846898 -277.833582) (xy 96.854518 -277.828502) (xy 96.870012 -277.807928) (xy 96.876616 -277.797006)
			(xy 96.87687 -277.795736) (xy 96.87814 -277.791164) (xy 96.883306 -277.772709) (xy 96.894739 -277.736125)
			(xy 96.901 -277.718012) (xy 96.907925 -277.698404) (xy 96.923043 -277.659659) (xy 96.931226 -277.640542)
			(xy 96.932496 -277.635208) (xy 96.934782 -277.624032) (xy 96.934782 -277.62327) (xy 96.93529 -277.617682)
			(xy 96.93529 -276.836124) (xy 96.934792 -276.826693) (xy 96.927871 -276.809139) (xy 96.915095 -276.795254)
			(xy 96.906842 -276.790658) (xy 96.887016 -276.780521) (xy 96.850276 -276.755366) (xy 96.817582 -276.725139)
			(xy 96.789628 -276.69048) (xy 96.767008 -276.652127) (xy 96.758252 -276.631654) (xy 96.754696 -276.62505)
			(xy 96.754442 -276.624542) (xy 96.74263 -276.603958) (xy 96.724826 -276.559969) (xy 96.714044 -276.513754)
			(xy 96.710543 -276.466428) (xy 96.714407 -276.41913) (xy 96.725543 -276.372999) (xy 96.743684 -276.329147)
			(xy 96.768391 -276.288631) (xy 96.79907 -276.252426) (xy 96.834982 -276.221403) (xy 96.875262 -276.196312)
			(xy 96.896936 -276.186646) (xy 96.90354 -276.183852) (xy 96.916494 -276.173438) (xy 96.918272 -276.171914)
			(xy 96.924574 -276.165839) (xy 96.933005 -276.150514) (xy 96.934782 -276.141942) (xy 96.935036 -276.139148)
			(xy 96.93529 -276.134322) (xy 96.93529 -275.942552) (xy 96.934855 -275.933075) (xy 96.927868 -275.915451)
			(xy 96.914946 -275.901578) (xy 96.906588 -275.897086) (xy 96.903794 -275.895816) (xy 96.854518 -275.875496)
			(xy 96.85401 -275.875496) (xy 96.844104 -275.871178) (xy 96.833436 -275.86686) (xy 96.809814 -275.896832)
			(xy 96.795235 -275.914399) (xy 96.76175 -275.945427) (xy 96.724022 -275.971128) (xy 96.68289 -275.99093)
			(xy 96.63927 -276.004392) (xy 96.594133 -276.011214) (xy 96.571308 -276.01164) (xy 96.571054 -276.01164)
			(xy 96.558354 -276.011386) (xy 96.532192 -276.0091) (xy 96.509382 -276.005751) (xy 96.465057 -275.993077)
			(xy 96.423143 -275.973881) (xy 96.384593 -275.948598) (xy 96.350284 -275.917805) (xy 96.320997 -275.882202)
			(xy 96.297399 -275.842599) (xy 96.288352 -275.821394) (xy 96.284796 -275.81479) (xy 96.284542 -275.814282)
			(xy 96.271006 -275.790403) (xy 96.251742 -275.739011) (xy 96.241956 -275.685006) (xy 96.241362 -275.657564)
			(xy 96.241835 -275.633574) (xy 96.249346 -275.586185) (xy 96.264176 -275.540554) (xy 96.285961 -275.497804)
			(xy 96.314164 -275.458987) (xy 96.348092 -275.42506) (xy 96.386909 -275.396858) (xy 96.429659 -275.375074)
			(xy 96.47529 -275.360244) (xy 96.52268 -275.352735) (xy 96.54667 -275.352256) (xy 96.570806 -275.352718)
			(xy 96.618474 -275.360321) (xy 96.664354 -275.375328) (xy 96.707302 -275.397364) (xy 96.746249 -275.425881)
			(xy 96.763586 -275.44268) (xy 96.76384 -275.442934) (xy 96.76889 -275.447722) (xy 96.781005 -275.454558)
			(xy 96.787716 -275.456396) (xy 96.79305 -275.457412) (xy 96.79686 -275.457666) (xy 96.801359 -275.457872)
			(xy 96.810305 -275.456853) (xy 96.81464 -275.455634) (xy 96.819212 -275.45411) (xy 96.903794 -275.419312)
			(xy 96.91243 -275.415344) (xy 96.92619 -275.402252) (xy 96.934291 -275.385073) (xy 96.93529 -275.375624)
			(xy 96.93529 -275.216112) (xy 96.93479 -275.206682) (xy 96.927866 -275.189132) (xy 96.91509 -275.17525)
			(xy 96.906842 -275.170646) (xy 96.887017 -275.160509) (xy 96.850277 -275.135353) (xy 96.817584 -275.105125)
			(xy 96.789631 -275.070466) (xy 96.767013 -275.032112) (xy 96.758252 -275.011642) (xy 96.754696 -275.005038)
			(xy 96.754442 -275.00453) (xy 96.742631 -274.983946) (xy 96.724829 -274.939958) (xy 96.714049 -274.893744)
			(xy 96.710549 -274.846419) (xy 96.714414 -274.799123) (xy 96.725551 -274.752994) (xy 96.743692 -274.709144)
			(xy 96.7684 -274.668629) (xy 96.799079 -274.632426) (xy 96.83499 -274.601405) (xy 96.875269 -274.576315)
			(xy 96.896936 -274.566634) (xy 96.90354 -274.56384) (xy 96.916494 -274.553426) (xy 96.918272 -274.551902)
			(xy 96.924572 -274.545827) (xy 96.933 -274.5305) (xy 96.934782 -274.52193) (xy 96.935036 -274.519136)
			(xy 96.93529 -274.51431) (xy 96.93529 -273.5961) (xy 96.934805 -273.586661) (xy 96.9279 -273.569086)
			(xy 96.915127 -273.555179) (xy 96.906842 -273.550634) (xy 96.887017 -273.540496) (xy 96.850278 -273.515341)
			(xy 96.817586 -273.485112) (xy 96.789635 -273.450452) (xy 96.767018 -273.412098) (xy 96.758252 -273.39163)
			(xy 96.754696 -273.385026) (xy 96.754442 -273.384518) (xy 96.742632 -273.363935) (xy 96.724832 -273.319947)
			(xy 96.714054 -273.273734) (xy 96.710555 -273.226411) (xy 96.714422 -273.179116) (xy 96.72556 -273.132989)
			(xy 96.743701 -273.089141) (xy 96.768409 -273.048628) (xy 96.799087 -273.012426) (xy 96.834998 -272.981407)
			(xy 96.875277 -272.956318) (xy 96.896936 -272.946622) (xy 96.90354 -272.943828) (xy 96.916494 -272.933414)
			(xy 96.918272 -272.93189) (xy 96.924571 -272.925814) (xy 96.932995 -272.910487) (xy 96.934782 -272.901918)
			(xy 96.935036 -272.899124) (xy 96.93529 -272.894298) (xy 96.93529 -272.702528) (xy 96.934851 -272.693053)
			(xy 96.927859 -272.675436) (xy 96.914936 -272.661571) (xy 96.906588 -272.657062) (xy 96.903794 -272.655792)
			(xy 96.854518 -272.635472) (xy 96.85401 -272.635472) (xy 96.844104 -272.631154) (xy 96.833436 -272.626836)
			(xy 96.809814 -272.656808) (xy 96.795236 -272.674377) (xy 96.761752 -272.705407) (xy 96.724024 -272.73111)
			(xy 96.682892 -272.750913) (xy 96.639272 -272.764376) (xy 96.594133 -272.771199) (xy 96.571308 -272.771616)
			(xy 96.571054 -272.771616) (xy 96.558354 -272.771362) (xy 96.532192 -272.769076) (xy 96.509383 -272.765727)
			(xy 96.465059 -272.753052) (xy 96.423146 -272.733855) (xy 96.384597 -272.708572) (xy 96.350291 -272.677778)
			(xy 96.321006 -272.642173) (xy 96.297411 -272.602569) (xy 96.288352 -272.58137) (xy 96.284796 -272.574766)
			(xy 96.284542 -272.574258) (xy 96.271008 -272.550378) (xy 96.251748 -272.498986) (xy 96.241966 -272.444982)
			(xy 96.241362 -272.41754) (xy 96.241805 -272.393544) (xy 96.249307 -272.346142) (xy 96.264131 -272.300497)
			(xy 96.285914 -272.257733) (xy 96.314119 -272.218903) (xy 96.34805 -272.184964) (xy 96.386873 -272.156751)
			(xy 96.429632 -272.134958) (xy 96.475274 -272.120123) (xy 96.522674 -272.112611) (xy 96.54667 -272.112232)
			(xy 96.570806 -272.112694) (xy 96.618475 -272.120297) (xy 96.664355 -272.135303) (xy 96.707304 -272.157337)
			(xy 96.746253 -272.185853) (xy 96.763586 -272.202656) (xy 96.76384 -272.20291) (xy 96.768888 -272.2077)
			(xy 96.781003 -272.214539) (xy 96.787716 -272.216372) (xy 96.79305 -272.217388) (xy 96.79686 -272.217642)
			(xy 96.801358 -272.217848) (xy 96.810305 -272.216828) (xy 96.81464 -272.21561) (xy 96.819212 -272.214086)
			(xy 96.903794 -272.179288) (xy 96.912428 -272.175319) (xy 96.926182 -272.162226) (xy 96.934275 -272.145047)
			(xy 96.93529 -272.1356) (xy 96.93529 -271.976088) (xy 96.934803 -271.966651) (xy 96.927895 -271.949079)
			(xy 96.915122 -271.935175) (xy 96.906842 -271.930622) (xy 96.887017 -271.920484) (xy 96.850279 -271.895328)
			(xy 96.817588 -271.865098) (xy 96.789638 -271.830438) (xy 96.767023 -271.792084) (xy 96.758252 -271.771618)
			(xy 96.754696 -271.765014) (xy 96.754442 -271.764506) (xy 96.742633 -271.743923) (xy 96.724835 -271.699936)
			(xy 96.714058 -271.653725) (xy 96.710561 -271.606402) (xy 96.714429 -271.559109) (xy 96.725568 -271.512983)
			(xy 96.74371 -271.469137) (xy 96.768417 -271.428626) (xy 96.799096 -271.392426) (xy 96.835006 -271.361409)
			(xy 96.875284 -271.336322) (xy 96.896936 -271.32661) (xy 96.90354 -271.323816) (xy 96.916494 -271.313402)
			(xy 96.918272 -271.311878) (xy 96.924582 -271.305807) (xy 96.933032 -271.290485) (xy 96.934782 -271.281906)
			(xy 96.935036 -271.279112) (xy 96.93529 -271.274286) (xy 96.93529 -270.356076) (xy 96.934801 -270.34664)
			(xy 96.92789 -270.329072) (xy 96.915117 -270.315171) (xy 96.906842 -270.31061) (xy 96.887018 -270.300472)
			(xy 96.850281 -270.275315) (xy 96.817591 -270.245085) (xy 96.789642 -270.210425) (xy 96.767028 -270.17207)
			(xy 96.758252 -270.151606) (xy 96.754696 -270.145002) (xy 96.754442 -270.144494) (xy 96.740961 -270.120729)
			(xy 96.72174 -270.069591) (xy 96.711908 -270.015852) (xy 96.711262 -269.988538) (xy 96.711262 -269.983204)
			(xy 96.712131 -269.957572) (xy 96.721378 -269.90713) (xy 96.738924 -269.858942) (xy 96.75114 -269.836392)
			(xy 96.754188 -269.831058) (xy 96.759522 -269.812516) (xy 96.761046 -269.80515) (xy 96.761046 -269.802864)
			(xy 96.7613 -269.800578) (xy 96.7613 -269.56639) (xy 96.760538 -269.557754) (xy 96.758578 -269.549028)
			(xy 96.749601 -269.533577) (xy 96.743012 -269.527528) (xy 96.729804 -269.517622) (xy 96.724573 -269.513933)
			(xy 96.712744 -269.509056) (xy 96.706436 -269.50797) (xy 96.693736 -269.506192) (xy 96.68129 -269.511018)
			(xy 96.654741 -269.52059) (xy 96.599269 -269.530939) (xy 96.571054 -269.531592) (xy 96.545214 -269.531047)
			(xy 96.494274 -269.522338) (xy 96.445528 -269.505177) (xy 96.400367 -269.480053) (xy 96.36008 -269.447684)
			(xy 96.325818 -269.408995) (xy 96.29856 -269.365089) (xy 96.288352 -269.341346) (xy 96.284796 -269.334742)
			(xy 96.284542 -269.334234) (xy 96.27101 -269.310354) (xy 96.251753 -269.258961) (xy 96.241976 -269.204957)
			(xy 96.241362 -269.177516) (xy 96.241831 -269.153523) (xy 96.249335 -269.106128) (xy 96.264161 -269.06049)
			(xy 96.285943 -269.017733) (xy 96.314146 -268.978909) (xy 96.348074 -268.944976) (xy 96.386893 -268.916767)
			(xy 96.429647 -268.894979) (xy 96.475283 -268.880146) (xy 96.522677 -268.872635) (xy 96.54667 -268.872208)
			(xy 96.546924 -268.872208) (xy 96.567896 -268.872555) (xy 96.609447 -268.878287) (xy 96.629728 -268.883638)
			(xy 96.631252 -268.884146) (xy 96.633284 -268.884654) (xy 96.641666 -268.885924) (xy 96.645844 -268.886479)
			(xy 96.654271 -268.886352) (xy 96.65843 -268.88567) (xy 96.667574 -268.883892) (xy 96.734122 -268.833854)
			(xy 96.73463 -268.833854) (xy 96.744028 -268.826742) (xy 96.749362 -268.821408) (xy 96.749362 -268.8209)
			(xy 96.754342 -268.81458) (xy 96.76042 -268.799689) (xy 96.7613 -268.79169) (xy 96.7613 -268.556232)
			(xy 96.759776 -268.54404) (xy 96.756474 -268.532356) (xy 96.754696 -268.525498) (xy 96.754442 -268.52499)
			(xy 96.752664 -268.521688) (xy 96.75114 -268.51864) (xy 96.738565 -268.495456) (xy 96.72071 -268.445832)
			(xy 96.711647 -268.393878) (xy 96.711645 -268.341139) (xy 96.720705 -268.289185) (xy 96.738558 -268.23956)
			(xy 96.75114 -268.21638) (xy 96.754442 -268.210538) (xy 96.756474 -268.202664) (xy 96.759776 -268.19098)
			(xy 96.7613 -268.178788) (xy 96.7613 -267.942568) (xy 96.761554 -267.936726) (xy 96.761758 -267.932228)
			(xy 96.760735 -267.923283) (xy 96.759522 -267.918946) (xy 96.758506 -267.916406) (xy 96.754963 -267.907684)
			(xy 96.742608 -267.893498) (xy 96.725949 -267.884759) (xy 96.707255 -267.882655) (xy 96.698054 -267.884656)
			(xy 96.697546 -267.884656) (xy 96.696784 -267.88491) (xy 96.692212 -267.886434) (xy 96.690434 -267.887196)
			(xy 96.661898 -267.898532) (xy 96.60175 -267.910822) (xy 96.571054 -267.91158) (xy 96.545803 -267.911055)
			(xy 96.495992 -267.902736) (xy 96.448229 -267.886333) (xy 96.403817 -267.862292) (xy 96.363967 -267.83127)
			(xy 96.329767 -267.794113) (xy 96.302147 -267.751833) (xy 96.281863 -267.705585) (xy 96.269467 -267.656629)
			(xy 96.265297 -267.6063) (xy 96.269467 -267.555971) (xy 96.281863 -267.507015) (xy 96.302147 -267.460767)
			(xy 96.329767 -267.418487) (xy 96.363967 -267.38133) (xy 96.403817 -267.350308) (xy 96.448229 -267.326267)
			(xy 96.495992 -267.309864) (xy 96.545803 -267.301545) (xy 96.571054 -267.300964) (xy 96.595928 -267.301451)
			(xy 96.645019 -267.309514) (xy 96.692151 -267.325433) (xy 96.736077 -267.348787) (xy 96.775633 -267.378957)
			(xy 96.80977 -267.415145) (xy 96.837586 -267.456391) (xy 96.858341 -267.501602) (xy 96.871488 -267.549582)
			(xy 96.874584 -267.574268) (xy 96.875346 -267.58011) (xy 96.876362 -267.589254) (xy 96.884744 -267.600176)
			(xy 96.889385 -267.605573) (xy 96.900986 -267.61381) (xy 96.907604 -267.616432) (xy 96.99752 -267.64869)
			(xy 97.006337 -267.650822) (xy 97.024412 -267.649439) (xy 97.040892 -267.641887) (xy 97.047558 -267.635736)
			(xy 97.178622 -267.504672) (xy 97.185988 -267.494512) (xy 97.188782 -267.489178) (xy 97.19056 -267.482828)
			(xy 97.197338 -267.458097) (xy 97.218012 -267.411176) (xy 97.246242 -267.368371) (xy 97.281231 -267.33089)
			(xy 97.301304 -267.314934) (xy 97.324753 -267.297821) (xy 97.376665 -267.271854) (xy 97.404428 -267.263372)
			(xy 97.405698 -267.263118) (xy 97.412302 -267.260832) (xy 97.413318 -267.260578) (xy 97.416366 -267.259308)
			(xy 97.423224 -267.257022) (xy 97.426478 -267.255186) (xy 97.432472 -267.250725) (xy 97.435162 -267.248132)
			(xy 97.700084 -266.98321) (xy 97.706994 -266.974833) (xy 97.71358 -266.954162) (xy 97.712784 -266.943332)
			(xy 97.709228 -266.935458) (xy 97.70618 -266.929108) (xy 97.705926 -266.928854) (xy 97.704148 -266.924536)
			(xy 97.703132 -266.922504) (xy 97.69729 -266.909296) (xy 97.695258 -266.905486) (xy 97.681628 -266.881717)
			(xy 97.66213 -266.830518) (xy 97.652061 -266.776665) (xy 97.651316 -266.749276) (xy 97.651316 -266.745466)
			(xy 97.651938 -266.72158) (xy 97.659695 -266.674435) (xy 97.674703 -266.629074) (xy 97.696593 -266.586605)
			(xy 97.724832 -266.548064) (xy 97.758731 -266.514393) (xy 97.797461 -266.486414) (xy 97.840077 -266.464811)
			(xy 97.885538 -266.45011) (xy 97.932734 -266.44267) (xy 97.956624 -266.44219) (xy 97.965514 -266.44219)
			(xy 97.993492 -266.443613) (xy 98.048255 -266.455385) (xy 98.09995 -266.476952) (xy 98.123756 -266.49172)
			(xy 98.129852 -266.495784) (xy 98.145346 -266.50061) (xy 98.15201 -266.502388) (xy 98.165795 -266.502636)
			(xy 98.172524 -266.501118) (xy 98.178874 -266.499594) (xy 98.184462 -266.496292) (xy 98.19513 -266.488164)
			(xy 98.313494 -266.3698) (xy 98.318898 -266.363917) (xy 98.326148 -266.349692) (xy 98.327718 -266.34186)
			(xy 98.328226 -266.33043) (xy 98.327972 -266.328652) (xy 98.327718 -266.32662) (xy 98.327718 -266.326112)
			(xy 98.322638 -266.294108) (xy 98.321114 -266.284202) (xy 98.320185 -266.279641) (xy 98.316864 -266.270946)
			(xy 98.31451 -266.26693) (xy 98.29673 -266.249658) (xy 98.291904 -266.246864) (xy 98.271197 -266.233636)
			(xy 98.233913 -266.201637) (xy 98.202234 -266.164081) (xy 98.176977 -266.121936) (xy 98.167444 -266.09929)
			(xy 98.165412 -266.09548) (xy 98.151629 -266.071456) (xy 98.132031 -266.019659) (xy 98.122062 -265.965182)
			(xy 98.12147 -265.937492) (xy 98.121941 -265.913501) (xy 98.129448 -265.866109) (xy 98.144276 -265.820474)
			(xy 98.16606 -265.777721) (xy 98.194263 -265.738902) (xy 98.228191 -265.704972) (xy 98.267009 -265.676767)
			(xy 98.309761 -265.654981) (xy 98.355395 -265.640151) (xy 98.402787 -265.632642) (xy 98.426778 -265.632184)
			(xy 98.452615 -265.632732) (xy 98.503548 -265.641447) (xy 98.552287 -265.658613) (xy 98.597439 -265.683742)
			(xy 98.637714 -265.716115) (xy 98.671964 -265.754808) (xy 98.699208 -265.798716) (xy 98.70948 -265.82243)
			(xy 98.713036 -265.829034) (xy 98.71329 -265.829542) (xy 98.726822 -265.853422) (xy 98.746081 -265.904815)
			(xy 98.755862 -265.958819) (xy 98.75647 -265.98626) (xy 98.756048 -266.009684) (xy 98.748901 -266.055983)
			(xy 98.73477 -266.100649) (xy 98.713984 -266.142633) (xy 98.700844 -266.162028) (xy 98.699574 -266.163806)
			(xy 98.698812 -266.164822) (xy 98.695924 -266.169994) (xy 98.692344 -266.181284) (xy 98.6917 -266.187174)
			(xy 98.6917 -266.187428) (xy 98.691391 -266.194467) (xy 98.69422 -266.208264) (xy 98.697288 -266.214606)
			(xy 98.713544 -266.246102) (xy 98.714052 -266.247118) (xy 98.718958 -266.254755) (xy 98.733008 -266.266227)
			(xy 98.741484 -266.26947) (xy 98.750882 -266.272264) (xy 99.962716 -266.272264) (xy 99.973892 -266.270994)
			(xy 99.989894 -266.267438) (xy 99.995903 -266.264435) (xy 100.00619 -266.255801) (xy 100.010214 -266.25042)
			(xy 100.05314 -266.180316) (xy 100.05695 -266.17422) (xy 100.058982 -266.170664) (xy 100.058982 -266.125198)
			(xy 100.054156 -266.115038) (xy 100.050092 -266.105132) (xy 100.049076 -266.1031) (xy 100.048568 -266.10183)
			(xy 100.048314 -266.101068) (xy 100.044758 -266.094718) (xy 100.044504 -266.09421) (xy 100.030976 -266.070329)
			(xy 100.011725 -266.018935) (xy 100.001953 -265.964932) (xy 100.001324 -265.937492) (xy 100.001771 -265.9135)
			(xy 100.009279 -265.866108) (xy 100.024108 -265.820473) (xy 100.045895 -265.77772) (xy 100.074101 -265.738902)
			(xy 100.108033 -265.704975) (xy 100.146854 -265.676774) (xy 100.18961 -265.654993) (xy 100.235246 -265.640169)
			(xy 100.28264 -265.632668) (xy 100.306632 -265.632184) (xy 100.320094 -265.632184) (xy 100.346627 -265.633935)
			(xy 100.398537 -265.645438) (xy 100.44768 -265.665736) (xy 100.492576 -265.694218) (xy 100.512626 -265.711686)
			(xy 100.519738 -265.71829) (xy 100.54463 -265.727688) (xy 100.545392 -265.727942) (xy 100.562664 -265.731244)
			(xy 100.567998 -265.731752) (xy 100.57765 -265.731752) (xy 100.62337 -265.731498) (xy 100.633182 -265.731002)
			(xy 100.651346 -265.723561) (xy 100.658676 -265.71702) (xy 101.08692 -265.288776) (xy 101.091906 -265.283276)
			(xy 101.098748 -265.270109) (xy 101.100382 -265.262868) (xy 101.101398 -265.253216) (xy 101.101398 -265.02614)
			(xy 101.10123 -265.020131) (xy 101.098404 -265.008449) (xy 101.09581 -265.003026) (xy 101.093973 -264.99955)
			(xy 101.089384 -264.993166) (xy 101.086666 -264.990326) (xy 100.847906 -264.751566) (xy 100.841064 -264.744166)
			(xy 100.833341 -264.725568) (xy 100.83292 -264.715498) (xy 100.83292 -263.955022) (xy 100.833358 -263.944959)
			(xy 100.841094 -263.926377) (xy 100.847906 -263.918954) (xy 101.90099 -262.86587) (xy 101.908505 -262.857607)
			(xy 101.916143 -262.836647) (xy 101.915722 -262.825484) (xy 101.914452 -262.818118) (xy 101.910418 -262.800422)
			(xy 101.906091 -262.764384) (xy 101.905816 -262.746236) (xy 101.90626 -262.722242) (xy 101.913762 -262.674843)
			(xy 101.928588 -262.629202) (xy 101.950371 -262.586443) (xy 101.978577 -262.547618) (xy 102.012509 -262.513685)
			(xy 102.051333 -262.485478) (xy 102.094091 -262.463692) (xy 102.139732 -262.448865) (xy 102.18713 -262.44136)
			(xy 102.211124 -262.440928) (xy 102.229208 -262.441225) (xy 102.265117 -262.445552) (xy 102.282752 -262.449564)
			(xy 102.283514 -262.449564) (xy 102.289751 -262.450855) (xy 102.30248 -262.450595) (xy 102.30866 -262.449056)
			(xy 102.31501 -262.447278) (xy 102.325932 -262.440928) (xy 102.468172 -262.298688) (xy 102.474975 -262.291206)
			(xy 102.482554 -262.272474) (xy 102.482904 -262.262366) (xy 102.482396 -262.19023) (xy 102.482253 -262.185198)
			(xy 102.480201 -262.175346) (xy 102.478332 -262.170672) (xy 102.474522 -262.161528) (xy 102.46741 -262.154416)
			(xy 102.450362 -262.137068) (xy 102.421443 -262.097964) (xy 102.399094 -262.054768) (xy 102.383882 -262.008572)
			(xy 102.376192 -261.960548) (xy 102.375716 -261.93623) (xy 102.376238 -261.910975) (xy 102.384551 -261.861153)
			(xy 102.400952 -261.813379) (xy 102.424993 -261.768956) (xy 102.456017 -261.729096) (xy 102.493179 -261.694886)
			(xy 102.535465 -261.66726) (xy 102.581721 -261.64697) (xy 102.630686 -261.63457) (xy 102.681024 -261.630399)
			(xy 102.731362 -261.63457) (xy 102.780327 -261.64697) (xy 102.826583 -261.66726) (xy 102.868869 -261.694886)
			(xy 102.906031 -261.729096) (xy 102.937055 -261.768956) (xy 102.961096 -261.813379) (xy 102.977497 -261.861153)
			(xy 102.98581 -261.910975) (xy 102.986332 -261.93623) (xy 102.986332 -261.936484) (xy 102.986592 -261.943372)
			(xy 102.990319 -261.956638) (xy 102.993698 -261.962646) (xy 102.994714 -261.964678) (xy 103.001064 -261.972298)
			(xy 103.052372 -262.023606) (xy 103.057873 -262.028588) (xy 103.071042 -262.03542) (xy 103.07828 -262.037068)
			(xy 103.087932 -262.038084) (xy 104.321102 -262.038084) (xy 104.334564 -262.036306) (xy 104.34066 -262.034528)
			(xy 104.342946 -262.033258) (xy 104.347518 -262.030464) (xy 104.353525 -262.027083) (xy 104.366791 -262.023362)
			(xy 104.37368 -262.023098) (xy 105.090468 -262.023098) (xy 105.098131 -262.022781) (xy 105.112737 -262.01813)
			(xy 105.11917 -262.013954) (xy 105.13695 -262.001508) (xy 105.146094 -261.993126) (xy 105.158032 -261.97941)
			(xy 105.160826 -261.973822) (xy 105.172695 -261.951831) (xy 105.201822 -261.911228) (xy 105.23652 -261.875268)
			(xy 105.276057 -261.844709) (xy 105.319601 -261.820194) (xy 105.366235 -261.802241) (xy 105.414977 -261.791226)
			(xy 105.464799 -261.787383) (xy 105.489756 -261.788656) (xy 105.516395 -261.790984) (xy 105.568536 -261.802839)
			(xy 105.618215 -261.822619) (xy 105.664235 -261.849846) (xy 105.705489 -261.883865) (xy 105.740983 -261.923857)
			(xy 105.769863 -261.968859) (xy 105.781094 -261.993126) (xy 105.783634 -261.998968) (xy 105.783888 -261.99973)
			(xy 105.784396 -262.000238) (xy 105.793286 -262.010906) (xy 105.799382 -262.01497) (xy 105.805543 -262.018715)
			(xy 105.819354 -262.022829) (xy 105.82656 -262.023098) (xy 106.004868 -262.023098) (xy 106.012531 -262.022781)
			(xy 106.027137 -262.01813) (xy 106.03357 -262.013954) (xy 106.05135 -262.001508) (xy 106.060494 -261.993126)
			(xy 106.072432 -261.97941) (xy 106.075226 -261.973822) (xy 106.087095 -261.951831) (xy 106.116222 -261.911228)
			(xy 106.15092 -261.875268) (xy 106.190457 -261.844709) (xy 106.234001 -261.820194) (xy 106.280635 -261.802241)
			(xy 106.329377 -261.791226) (xy 106.379199 -261.787383) (xy 106.404156 -261.788656) (xy 106.430795 -261.790984)
			(xy 106.482936 -261.802839) (xy 106.532615 -261.822619) (xy 106.578635 -261.849846) (xy 106.619889 -261.883865)
			(xy 106.655383 -261.923857) (xy 106.684263 -261.968859) (xy 106.695494 -261.993126) (xy 106.696256 -261.994904)
			(xy 106.701844 -262.004048) (xy 106.707686 -262.010906) (xy 106.713782 -262.01497) (xy 106.719943 -262.018715)
			(xy 106.733754 -262.022829) (xy 106.74096 -262.023098) (xy 107.293918 -262.023098) (xy 107.300776 -262.02259)
			(xy 107.305285 -262.021869) (xy 107.313972 -262.01906) (xy 107.318048 -262.017002) (xy 107.32135 -262.01497)
			(xy 107.324955 -262.012552) (xy 107.331345 -262.00668) (xy 107.33405 -262.003286) (xy 107.334812 -262.00227)
			(xy 107.348479 -261.981934) (xy 107.380654 -261.944983) (xy 107.417746 -261.912971) (xy 107.459004 -261.886545)
			(xy 107.503594 -261.86624) (xy 107.550614 -261.852466) (xy 107.599112 -261.845502) (xy 107.62361 -261.845044)
			(xy 107.650646 -261.84555) (xy 107.704051 -261.854022) (xy 107.755469 -261.870755) (xy 107.803632 -261.895336)
			(xy 107.825794 -261.91083) (xy 107.829096 -261.913116) (xy 107.850432 -261.920228) (xy 107.854751 -261.921555)
			(xy 107.863694 -261.922826) (xy 107.868212 -261.922768) (xy 107.892342 -261.921752) (xy 107.90047 -261.920482)
			(xy 107.907307 -261.918674) (xy 107.919688 -261.911849) (xy 107.924854 -261.90702) (xy 108.206032 -261.625842)
			(xy 108.212581 -261.618515) (xy 108.220031 -261.600351) (xy 108.22051 -261.590536) (xy 108.22051 -258.715002)
			(xy 108.220337 -258.708994) (xy 108.217504 -258.697316) (xy 108.214922 -258.691888) (xy 108.213083 -258.688413)
			(xy 108.208492 -258.682032) (xy 108.205778 -258.679188) (xy 106.920538 -257.393948) (xy 106.91876 -257.39217)
			(xy 106.911917 -257.386531) (xy 106.895497 -257.379876) (xy 106.877793 -257.379195) (xy 106.86923 -257.381502)
			(xy 106.780584 -257.414268) (xy 106.773905 -257.417049) (xy 106.762309 -257.425689) (xy 106.757724 -257.431286)
			(xy 106.753602 -257.437099) (xy 106.748451 -257.450377) (xy 106.747564 -257.457448) (xy 106.747564 -257.457956)
			(xy 106.744995 -257.483819) (xy 106.73305 -257.5344) (xy 106.713619 -257.582604) (xy 106.687145 -257.627328)
			(xy 106.654234 -257.667552) (xy 106.615637 -257.702357) (xy 106.572236 -257.730948) (xy 106.525021 -257.752672)
			(xy 106.475072 -257.767032) (xy 106.449368 -257.770884) (xy 106.437938 -257.772408) (xy 106.405172 -257.773932)
			(xy 106.380066 -257.773473) (xy 106.33039 -257.766163) (xy 106.282305 -257.751704) (xy 106.236836 -257.730402)
			(xy 106.194951 -257.702712) (xy 106.157539 -257.669223) (xy 106.125398 -257.630646) (xy 106.099212 -257.587804)
			(xy 106.088942 -257.56489) (xy 106.088688 -257.564128) (xy 106.08564 -257.557524) (xy 106.08437 -257.555492)
			(xy 106.069542 -257.528917) (xy 106.048477 -257.47183) (xy 106.037787 -257.411927) (xy 106.037126 -257.381502)
			(xy 106.037126 -257.381248) (xy 106.037607 -257.354867) (xy 106.045682 -257.302728) (xy 106.061649 -257.252441)
			(xy 106.07294 -257.228594) (xy 106.079062 -257.21514) (xy 106.084081 -257.186023) (xy 106.080562 -257.156688)
			(xy 106.0688 -257.129584) (xy 106.049777 -257.106977) (xy 106.025083 -257.090755) (xy 105.99678 -257.082275)
			(xy 105.982008 -257.081782) (xy 105.777792 -257.081782) (xy 105.772838 -257.081663) (xy 105.763117 -257.079741)
			(xy 105.758488 -257.077972) (xy 105.74147 -257.07086) (xy 105.736908 -257.069063) (xy 105.727319 -257.06702)
			(xy 105.72242 -257.066796) (xy 100.947474 -257.066796) (xy 100.937633 -257.066268) (xy 100.919461 -257.058691)
			(xy 100.912168 -257.052064) (xy 100.177346 -256.317242) (xy 100.176838 -256.317242) (xy 100.173313 -256.314261)
			(xy 100.165389 -256.309527) (xy 100.16109 -256.307844) (xy 100.160582 -256.307844) (xy 100.157074 -256.306622)
			(xy 100.149807 -256.305088) (xy 100.146104 -256.304796) (xy 99.429824 -256.304796) (xy 99.42473 -256.30493)
			(xy 99.414749 -256.306981) (xy 99.410012 -256.30886) (xy 99.403154 -256.312416) (xy 99.390962 -256.324608)
			(xy 99.384358 -256.332482) (xy 99.34194 -256.401824) (xy 99.338638 -256.408936) (xy 99.337198 -256.412663)
			(xy 99.335407 -256.420448) (xy 99.335082 -256.42443) (xy 99.33432 -256.436368) (xy 99.338892 -256.447036)
			(xy 99.339654 -256.448814) (xy 99.339908 -256.449322) (xy 99.340416 -256.450592) (xy 99.34448 -256.459228)
			(xy 99.347274 -256.46507) (xy 99.349814 -256.47142) (xy 99.353116 -256.478024) (xy 99.353624 -256.478532)
			(xy 99.367003 -256.502326) (xy 99.386033 -256.553482) (xy 99.395711 -256.607198) (xy 99.396296 -256.634488)
			(xy 99.395851 -256.658481) (xy 99.388345 -256.705878) (xy 99.373518 -256.751516) (xy 99.351733 -256.794273)
			(xy 99.323527 -256.833095) (xy 99.289595 -256.867027) (xy 99.250773 -256.895233) (xy 99.208016 -256.917018)
			(xy 99.162378 -256.931845) (xy 99.114981 -256.939351) (xy 99.090988 -256.939796) (xy 99.064976 -256.939279)
			(xy 99.013702 -256.930481) (xy 98.96466 -256.913124) (xy 98.919267 -256.887709) (xy 98.878835 -256.854972)
			(xy 98.844534 -256.815859) (xy 98.817355 -256.7715) (xy 98.80727 -256.747518) (xy 98.804984 -256.7432)
			(xy 98.79886 -256.732915) (xy 98.78805 -256.711555) (xy 98.783394 -256.700528) (xy 98.782124 -256.69748)
			(xy 98.772417 -256.676612) (xy 98.758685 -256.632687) (xy 98.751695 -256.587198) (xy 98.751607 -256.541176)
			(xy 98.758421 -256.495661) (xy 98.771984 -256.451682) (xy 98.781616 -256.43078) (xy 98.79203 -256.408936)
			(xy 98.78949 -256.400808) (xy 98.78949 -256.4003) (xy 98.786696 -256.394458) (xy 98.746818 -256.329688)
			(xy 98.746564 -256.32918) (xy 98.74631 -256.328926) (xy 98.739104 -256.318535) (xy 98.717253 -256.305866)
			(xy 98.704654 -256.304796) (xy 97.54997 -256.304796) (xy 97.544875 -256.304925) (xy 97.53489 -256.306968)
			(xy 97.530158 -256.30886) (xy 97.5233 -256.312416) (xy 97.511108 -256.324608) (xy 97.504504 -256.332482)
			(xy 97.462086 -256.401824) (xy 97.458784 -256.408936) (xy 97.457346 -256.412663) (xy 97.455556 -256.420449)
			(xy 97.455228 -256.42443) (xy 97.454466 -256.436368) (xy 97.459038 -256.447036) (xy 97.4598 -256.448814)
			(xy 97.460054 -256.449322) (xy 97.460562 -256.450592) (xy 97.464626 -256.459228) (xy 97.46742 -256.46507)
			(xy 97.46996 -256.47142) (xy 97.473262 -256.478024) (xy 97.47377 -256.478532) (xy 97.487151 -256.502325)
			(xy 97.506184 -256.553481) (xy 97.515864 -256.607197) (xy 97.516442 -256.634488) (xy 97.515972 -256.658481)
			(xy 97.508468 -256.705876) (xy 97.493642 -256.751514) (xy 97.47186 -256.794271) (xy 97.443657 -256.833094)
			(xy 97.409729 -256.867027) (xy 97.37091 -256.895236) (xy 97.328156 -256.917024) (xy 97.282521 -256.931857)
			(xy 97.235127 -256.939369) (xy 97.211134 -256.939796) (xy 97.185125 -256.939275) (xy 97.133857 -256.930469)
			(xy 97.084822 -256.913106) (xy 97.039436 -256.887688) (xy 96.999012 -256.85495) (xy 96.964718 -256.815837)
			(xy 96.937545 -256.77148) (xy 96.927416 -256.747518) (xy 96.92513 -256.7432) (xy 96.919007 -256.732914)
			(xy 96.908199 -256.711554) (xy 96.90354 -256.700528) (xy 96.90227 -256.69748) (xy 96.892561 -256.676613)
			(xy 96.878827 -256.632687) (xy 96.871837 -256.587198) (xy 96.871748 -256.541176) (xy 96.878564 -256.49566)
			(xy 96.892129 -256.451682) (xy 96.901762 -256.43078) (xy 96.912176 -256.408936) (xy 96.909636 -256.400808)
			(xy 96.909636 -256.4003) (xy 96.906842 -256.394458) (xy 96.866964 -256.329688) (xy 96.86671 -256.32918)
			(xy 96.866456 -256.328926) (xy 96.859245 -256.318544) (xy 96.837394 -256.305898) (xy 96.8248 -256.304796)
			(xy 96.289114 -256.304796) (xy 96.279278 -256.304257) (xy 96.261121 -256.296666) (xy 96.253808 -256.290064)
			(xy 96.045528 -256.081784) (xy 96.042226 -256.078736) (xy 96.033617 -256.072218) (xy 96.012833 -256.066431)
			(xy 96.002094 -256.06756) (xy 95.980709 -256.084528) (xy 95.933318 -256.111612) (xy 95.881979 -256.130153)
			(xy 95.828218 -256.139601) (xy 95.800926 -256.140204) (xy 95.776922 -256.13975) (xy 95.729468 -256.132468)
			(xy 95.683665 -256.118082) (xy 95.640569 -256.096925) (xy 95.601174 -256.069485) (xy 95.56639 -256.036396)
			(xy 95.537019 -255.998419) (xy 95.513738 -255.956432) (xy 95.497085 -255.911404) (xy 95.491808 -255.887982)
			(xy 95.489776 -255.880616) (xy 95.481112 -255.855327) (xy 95.471791 -255.802694) (xy 95.471234 -255.775968)
			(xy 95.471234 -255.775714) (xy 95.471679 -255.751721) (xy 95.479184 -255.704327) (xy 95.494012 -255.65869)
			(xy 95.515798 -255.615935) (xy 95.544004 -255.577115) (xy 95.577936 -255.543185) (xy 95.616759 -255.514983)
			(xy 95.659516 -255.493202) (xy 95.705154 -255.478378) (xy 95.752549 -255.470877) (xy 95.776542 -255.470406)
			(xy 95.77705 -255.470406) (xy 95.798957 -255.470839) (xy 95.842306 -255.477215) (xy 95.86341 -255.483106)
			(xy 95.867982 -255.484376) (xy 95.878904 -255.482344) (xy 95.880428 -255.48209) (xy 95.885744 -255.480882)
			(xy 95.89573 -255.476517) (xy 95.90024 -255.473454) (xy 95.964248 -255.424432) (xy 95.96501 -255.42367)
			(xy 95.971425 -255.418227) (xy 95.98052 -255.404084) (xy 95.98279 -255.395984) (xy 95.98406 -255.38684)
			(xy 95.98406 -255.13792) (xy 95.983806 -255.135126) (xy 95.982028 -255.11887) (xy 95.977456 -255.110234)
			(xy 95.966098 -255.087945) (xy 95.950012 -255.040582) (xy 95.941875 -254.991227) (xy 95.941388 -254.966216)
			(xy 95.941388 -254.9652) (xy 95.94186 -254.94001) (xy 95.950036 -254.8903) (xy 95.966248 -254.842602)
			(xy 95.97771 -254.820166) (xy 95.977964 -254.819912) (xy 95.981012 -254.81407) (xy 95.98406 -254.80264)
			(xy 95.98406 -254.547116) (xy 95.983876 -254.541313) (xy 95.981186 -254.530022) (xy 95.978726 -254.524764)
			(xy 95.976043 -254.519631) (xy 95.968725 -254.510659) (xy 95.964248 -254.506984) (xy 95.957898 -254.502158)
			(xy 95.956882 -254.501396) (xy 95.951652 -254.497705) (xy 95.939823 -254.492825) (xy 95.933514 -254.491744)
			(xy 95.91421 -254.49911) (xy 95.913702 -254.49911) (xy 95.886536 -254.508887) (xy 95.829789 -254.519488)
			(xy 95.800926 -254.520192) (xy 95.776922 -254.519738) (xy 95.729469 -254.512455) (xy 95.683666 -254.49807)
			(xy 95.640571 -254.476913) (xy 95.601177 -254.449472) (xy 95.566394 -254.416382) (xy 95.537024 -254.378405)
			(xy 95.513745 -254.336419) (xy 95.497093 -254.29139) (xy 95.491808 -254.26797) (xy 95.489776 -254.260604)
			(xy 95.481113 -254.235315) (xy 95.471794 -254.182682) (xy 95.471234 -254.155956) (xy 95.471234 -254.155702)
			(xy 95.47168 -254.13171) (xy 95.479187 -254.084317) (xy 95.494016 -254.038681) (xy 95.515802 -253.995928)
			(xy 95.544008 -253.95711) (xy 95.57794 -253.923182) (xy 95.616762 -253.894981) (xy 95.659518 -253.8732)
			(xy 95.705156 -253.858377) (xy 95.75255 -253.850877) (xy 95.776542 -253.850394) (xy 95.77705 -253.850394)
			(xy 95.798957 -253.850827) (xy 95.842306 -253.857203) (xy 95.86341 -253.863094) (xy 95.867982 -253.864364)
			(xy 95.878904 -253.862332) (xy 95.880428 -253.862078) (xy 95.885743 -253.860869) (xy 95.895729 -253.856504)
			(xy 95.90024 -253.853442) (xy 95.964248 -253.80442) (xy 95.96501 -253.803658) (xy 95.971424 -253.798215)
			(xy 95.980516 -253.784071) (xy 95.98279 -253.775972) (xy 95.98406 -253.766828) (xy 95.98406 -253.517908)
			(xy 95.983806 -253.515114) (xy 95.982028 -253.498858) (xy 95.977456 -253.490222) (xy 95.966099 -253.467933)
			(xy 95.950015 -253.420569) (xy 95.941879 -253.371215) (xy 95.941388 -253.346204) (xy 95.941388 -253.345188)
			(xy 95.941861 -253.319998) (xy 95.950038 -253.270289) (xy 95.966252 -253.222592) (xy 95.97771 -253.200154)
			(xy 95.977964 -253.1999) (xy 95.981012 -253.194058) (xy 95.98406 -253.182628) (xy 95.98406 -252.927104)
			(xy 95.983875 -252.921302) (xy 95.981183 -252.910012) (xy 95.978726 -252.904752) (xy 95.976042 -252.89962)
			(xy 95.968722 -252.89065) (xy 95.964248 -252.886972) (xy 95.957898 -252.882146) (xy 95.956882 -252.881384)
			(xy 95.951652 -252.877694) (xy 95.939823 -252.872815) (xy 95.933514 -252.871732) (xy 95.91421 -252.879098)
			(xy 95.913702 -252.879098) (xy 95.886536 -252.888876) (xy 95.829789 -252.899476) (xy 95.800926 -252.90018)
			(xy 95.776922 -252.899726) (xy 95.72947 -252.892443) (xy 95.683668 -252.878057) (xy 95.640573 -252.8569)
			(xy 95.60118 -252.829459) (xy 95.566398 -252.796369) (xy 95.537029 -252.758392) (xy 95.513752 -252.716405)
			(xy 95.497102 -252.671376) (xy 95.491808 -252.647958) (xy 95.489776 -252.640592) (xy 95.481114 -252.615303)
			(xy 95.471797 -252.56267) (xy 95.471234 -252.535944) (xy 95.471234 -252.53569) (xy 95.471681 -252.511699)
			(xy 95.479189 -252.464307) (xy 95.494019 -252.418673) (xy 95.515806 -252.375921) (xy 95.544012 -252.337105)
			(xy 95.577944 -252.303178) (xy 95.616766 -252.274978) (xy 95.659521 -252.253199) (xy 95.705157 -252.238377)
			(xy 95.75255 -252.230877) (xy 95.776542 -252.230382) (xy 95.77705 -252.230382) (xy 95.798957 -252.230815)
			(xy 95.842306 -252.237191) (xy 95.86341 -252.243082) (xy 95.867982 -252.244352) (xy 95.878904 -252.24232)
			(xy 95.880428 -252.242066) (xy 95.885745 -252.240859) (xy 95.895734 -252.2365) (xy 95.90024 -252.23343)
			(xy 95.964248 -252.184408) (xy 95.96501 -252.183646) (xy 95.971423 -252.178202) (xy 95.980511 -252.164057)
			(xy 95.98279 -252.15596) (xy 95.98406 -252.146816) (xy 95.98406 -251.897896) (xy 95.983806 -251.895102)
			(xy 95.982028 -251.878846) (xy 95.977456 -251.87021) (xy 95.9661 -251.847921) (xy 95.950017 -251.800557)
			(xy 95.941884 -251.751202) (xy 95.941388 -251.726192) (xy 95.941388 -251.725176) (xy 95.941862 -251.699987)
			(xy 95.950041 -251.650278) (xy 95.966257 -251.602582) (xy 95.97771 -251.580142) (xy 95.977964 -251.579888)
			(xy 95.981012 -251.574046) (xy 95.98406 -251.562616) (xy 95.98406 -251.307092) (xy 95.983873 -251.30129)
			(xy 95.981179 -251.290001) (xy 95.978726 -251.28474) (xy 95.976049 -251.279603) (xy 95.968739 -251.27062)
			(xy 95.964248 -251.26696) (xy 95.957898 -251.262134) (xy 95.956882 -251.261372) (xy 95.951652 -251.257683)
			(xy 95.939822 -251.252805) (xy 95.933514 -251.25172) (xy 95.91421 -251.259086) (xy 95.913702 -251.259086)
			(xy 95.886537 -251.268864) (xy 95.829789 -251.279465) (xy 95.800926 -251.280168) (xy 95.776922 -251.279714)
			(xy 95.72947 -251.272431) (xy 95.683669 -251.258045) (xy 95.640575 -251.236887) (xy 95.601183 -251.209446)
			(xy 95.566402 -251.176355) (xy 95.537035 -251.138378) (xy 95.513758 -251.096391) (xy 95.49711 -251.051362)
			(xy 95.491808 -251.027946) (xy 95.489776 -251.02058) (xy 95.481107 -250.995292) (xy 95.471774 -250.942659)
			(xy 95.471234 -250.915932) (xy 95.471234 -250.915678) (xy 95.471682 -250.891687) (xy 95.479192 -250.844297)
			(xy 95.494023 -250.798665) (xy 95.51581 -250.755915) (xy 95.544017 -250.7171) (xy 95.577948 -250.683175)
			(xy 95.616769 -250.654976) (xy 95.659524 -250.633198) (xy 95.705159 -250.618377) (xy 95.752551 -250.610877)
			(xy 95.776542 -250.61037) (xy 95.77705 -250.61037) (xy 95.798957 -250.610803) (xy 95.842306 -250.617178)
			(xy 95.86341 -250.62307) (xy 95.867982 -250.62434) (xy 95.878904 -250.622308) (xy 95.880428 -250.622054)
			(xy 95.885744 -250.620847) (xy 95.895734 -250.616487) (xy 95.90024 -250.613418) (xy 95.964248 -250.564396)
			(xy 95.96501 -250.563634) (xy 95.971422 -250.558189) (xy 95.980507 -250.544044) (xy 95.98279 -250.535948)
			(xy 95.98406 -250.526804) (xy 95.98406 -250.277884) (xy 95.983806 -250.27509) (xy 95.982028 -250.258834)
			(xy 95.977456 -250.250198) (xy 95.966101 -250.227909) (xy 95.95002 -250.180545) (xy 95.941889 -250.13119)
			(xy 95.941388 -250.10618) (xy 95.941388 -250.105164) (xy 95.941863 -250.079975) (xy 95.950044 -250.030267)
			(xy 95.966261 -249.982572) (xy 95.97771 -249.96013) (xy 95.977964 -249.959876) (xy 95.981012 -249.954034)
			(xy 95.98406 -249.942604) (xy 95.98406 -249.68708) (xy 95.983872 -249.681278) (xy 95.981175 -249.669991)
			(xy 95.978726 -249.664728) (xy 95.976048 -249.659591) (xy 95.968736 -249.65061) (xy 95.964248 -249.646948)
			(xy 95.957898 -249.642122) (xy 95.956882 -249.64136) (xy 95.951651 -249.637672) (xy 95.939822 -249.632795)
			(xy 95.933514 -249.631708) (xy 95.91421 -249.639074) (xy 95.913702 -249.639074) (xy 95.886537 -249.648852)
			(xy 95.82979 -249.659454) (xy 95.800926 -249.660156) (xy 95.776923 -249.659702) (xy 95.729471 -249.652419)
			(xy 95.68367 -249.638033) (xy 95.640577 -249.616875) (xy 95.601186 -249.589433) (xy 95.566406 -249.556342)
			(xy 95.53704 -249.518364) (xy 95.513765 -249.476377) (xy 95.497119 -249.431348) (xy 95.491808 -249.407934)
			(xy 95.489776 -249.400568) (xy 95.481108 -249.37528) (xy 95.471777 -249.322647) (xy 95.471234 -249.29592)
			(xy 95.471234 -249.295666) (xy 95.471683 -249.271676) (xy 95.479194 -249.224287) (xy 95.494026 -249.178656)
			(xy 95.515814 -249.135908) (xy 95.544021 -249.097095) (xy 95.577952 -249.063171) (xy 95.616773 -249.034974)
			(xy 95.659527 -249.013197) (xy 95.705161 -248.998376) (xy 95.752552 -248.990877) (xy 95.776542 -248.990358)
			(xy 95.776796 -248.990358) (xy 95.803707 -248.990928) (xy 95.856695 -249.000364) (xy 95.907207 -249.018946)
			(xy 95.953679 -249.046097) (xy 95.99467 -249.080975) (xy 96.012254 -249.101356) (xy 96.018604 -249.108976)
			(xy 96.041464 -249.121422) (xy 96.044766 -249.1232) (xy 96.048906 -249.125228) (xy 96.057724 -249.127911)
			(xy 96.062292 -249.128534) (xy 96.13011 -249.132598) (xy 96.133666 -249.132598) (xy 96.142349 -249.132027)
			(xy 96.15858 -249.12579) (xy 96.165416 -249.120406) (xy 96.16821 -249.117866) (xy 96.324166 -248.96191)
			(xy 96.32852 -248.957297) (xy 96.334957 -248.946369) (xy 96.336866 -248.94032) (xy 96.338168 -248.93535)
			(xy 96.338939 -248.925108) (xy 96.33839 -248.92) (xy 96.33839 -248.919492) (xy 96.334834 -248.90603)
			(xy 96.326198 -248.886472) (xy 96.326198 -248.885964) (xy 96.319594 -248.87047) (xy 96.316381 -248.863674)
			(xy 96.306694 -248.852188) (xy 96.300544 -248.847864) (xy 96.294448 -248.8438) (xy 96.280478 -248.839736)
			(xy 96.27108 -248.839736) (xy 96.24524 -248.839193) (xy 96.1943 -248.830486) (xy 96.145552 -248.813326)
			(xy 96.100391 -248.788202) (xy 96.060106 -248.755832) (xy 96.025847 -248.717139) (xy 95.998593 -248.673231)
			(xy 95.988378 -248.64949) (xy 95.984822 -248.642886) (xy 95.984568 -248.642378) (xy 95.971032 -248.618499)
			(xy 95.951766 -248.567107) (xy 95.94198 -248.513102) (xy 95.941388 -248.48566) (xy 95.941862 -248.461671)
			(xy 95.949373 -248.414284) (xy 95.964204 -248.368655) (xy 95.985989 -248.325907) (xy 96.014193 -248.287094)
			(xy 96.048121 -248.25317) (xy 96.086938 -248.22497) (xy 96.129688 -248.20319) (xy 96.175319 -248.188364)
			(xy 96.222707 -248.180859) (xy 96.246696 -248.180352) (xy 96.256348 -248.180352) (xy 96.278689 -248.181472)
			(xy 96.322714 -248.189388) (xy 96.365117 -248.203627) (xy 96.404997 -248.223887) (xy 96.42348 -248.236486)
			(xy 96.430338 -248.241312) (xy 96.441514 -248.245884) (xy 96.468692 -248.245884) (xy 96.476566 -248.24309)
			(xy 96.519238 -248.2215) (xy 96.559624 -248.200926) (xy 96.565606 -248.197165) (xy 96.575395 -248.18698)
			(xy 96.578928 -248.18086) (xy 96.580706 -248.177558) (xy 96.58227 -248.173849) (xy 96.584312 -248.166063)
			(xy 96.58477 -248.162064) (xy 96.58477 -247.993408) (xy 96.584262 -247.98655) (xy 96.576231 -247.98164)
			(xy 96.560727 -247.970964) (xy 96.553274 -247.965214) (xy 96.532295 -247.948161) (xy 96.496124 -247.907987)
			(xy 96.467569 -247.862085) (xy 96.457008 -247.837198) (xy 96.456754 -247.83669) (xy 96.443386 -247.814018)
			(xy 96.423782 -247.765178) (xy 96.412819 -247.713705) (xy 96.410819 -247.661115) (xy 96.417841 -247.608958)
			(xy 96.425258 -247.583706) (xy 96.433637 -247.558919) (xy 96.457636 -247.512429) (xy 96.489194 -247.470699)
			(xy 96.527391 -247.434947) (xy 96.548956 -247.42013) (xy 96.554544 -247.416574) (xy 96.56318 -247.406922)
			(xy 96.567244 -247.401334) (xy 96.57461 -247.388634) (xy 96.578166 -247.382284) (xy 96.578166 -247.38203)
			(xy 96.581078 -247.376551) (xy 96.584409 -247.364603) (xy 96.58477 -247.358408) (xy 96.58477 -246.373396)
			(xy 96.584262 -246.366538) (xy 96.576231 -246.361628) (xy 96.560727 -246.350951) (xy 96.553274 -246.345202)
			(xy 96.532296 -246.328149) (xy 96.496126 -246.287974) (xy 96.467573 -246.242071) (xy 96.457008 -246.217186)
			(xy 96.456754 -246.216678) (xy 96.443387 -246.194006) (xy 96.423785 -246.145166) (xy 96.412824 -246.093693)
			(xy 96.410826 -246.041105) (xy 96.41785 -245.988949) (xy 96.425258 -245.963694) (xy 96.433631 -245.938903)
			(xy 96.45762 -245.892403) (xy 96.489172 -245.850663) (xy 96.527366 -245.814901) (xy 96.548956 -245.800118)
			(xy 96.554544 -245.796562) (xy 96.56318 -245.78691) (xy 96.567244 -245.781322) (xy 96.57461 -245.768622)
			(xy 96.578166 -245.762272) (xy 96.578166 -245.762018) (xy 96.581088 -245.756542) (xy 96.58444 -245.744594)
			(xy 96.58477 -245.738396) (xy 96.58477 -245.572026) (xy 96.584389 -245.56668) (xy 96.581708 -245.556305)
			(xy 96.579436 -245.551452) (xy 96.562672 -245.534688) (xy 96.551496 -245.526306) (xy 96.528382 -245.514368)
			(xy 96.51929 -245.510779) (xy 96.499774 -245.51003) (xy 96.481389 -245.516621) (xy 96.473772 -245.52275)
			(xy 96.452633 -245.540701) (xy 96.405194 -245.569415) (xy 96.353351 -245.589091) (xy 96.298806 -245.599083)
			(xy 96.27108 -245.599712) (xy 96.245241 -245.599169) (xy 96.194301 -245.590462) (xy 96.145555 -245.573301)
			(xy 96.100395 -245.548176) (xy 96.060112 -245.515804) (xy 96.025856 -245.477111) (xy 95.998605 -245.433201)
			(xy 95.988378 -245.409466) (xy 95.984822 -245.402862) (xy 95.984568 -245.402354) (xy 95.971033 -245.378474)
			(xy 95.951772 -245.327082) (xy 95.94199 -245.273078) (xy 95.941388 -245.245636) (xy 95.941832 -245.221641)
			(xy 95.949334 -245.174241) (xy 95.964159 -245.128598) (xy 95.985942 -245.085837) (xy 96.014147 -245.04701)
			(xy 96.048079 -245.013073) (xy 96.086903 -244.984863) (xy 96.129661 -244.963074) (xy 96.175302 -244.948243)
			(xy 96.222701 -244.940735) (xy 96.246696 -244.940328) (xy 96.256348 -244.940328) (xy 96.278689 -244.941447)
			(xy 96.322714 -244.949363) (xy 96.365118 -244.963602) (xy 96.404999 -244.98386) (xy 96.42348 -244.996462)
			(xy 96.430338 -245.001288) (xy 96.441514 -245.00586) (xy 96.468692 -245.00586) (xy 96.476566 -245.003066)
			(xy 96.519238 -244.981476) (xy 96.559624 -244.960902) (xy 96.565611 -244.957145) (xy 96.575412 -244.946967)
			(xy 96.578928 -244.940836) (xy 96.580706 -244.937534) (xy 96.582269 -244.933825) (xy 96.584306 -244.926038)
			(xy 96.58477 -244.92204) (xy 96.58477 -244.753384) (xy 96.584262 -244.746526) (xy 96.576231 -244.741616)
			(xy 96.560727 -244.730939) (xy 96.553274 -244.72519) (xy 96.532291 -244.70814) (xy 96.496111 -244.66797)
			(xy 96.467546 -244.622072) (xy 96.457008 -244.597174) (xy 96.456754 -244.596666) (xy 96.443388 -244.573994)
			(xy 96.423788 -244.525154) (xy 96.412829 -244.473682) (xy 96.410833 -244.421094) (xy 96.417858 -244.368939)
			(xy 96.425258 -244.343682) (xy 96.433632 -244.318891) (xy 96.457622 -244.272393) (xy 96.489175 -244.230654)
			(xy 96.527369 -244.194894) (xy 96.548956 -244.180106) (xy 96.554544 -244.17655) (xy 96.56318 -244.166898)
			(xy 96.567244 -244.16131) (xy 96.57461 -244.14861) (xy 96.578166 -244.14226) (xy 96.578166 -244.142006)
			(xy 96.581086 -244.136529) (xy 96.584435 -244.124581) (xy 96.58477 -244.118384) (xy 96.58477 -243.255292)
			(xy 96.585194 -243.245222) (xy 96.592907 -243.226617) (xy 96.599756 -243.219224) (xy 96.606106 -243.212874)
			(xy 96.612768 -243.205657) (xy 96.620501 -243.187623) (xy 96.620859 -243.168004) (xy 96.613789 -243.1497)
			(xy 96.607376 -243.142262) (xy 96.601026 -243.135912) (xy 96.597978 -243.134134) (xy 96.594422 -243.132356)
			(xy 96.574156 -243.120742) (xy 96.537092 -243.09232) (xy 96.504786 -243.058589) (xy 96.477988 -243.020334)
			(xy 96.457325 -242.978447) (xy 96.443277 -242.933903) (xy 96.436171 -242.887739) (xy 96.435672 -242.864386)
			(xy 96.436122 -242.840352) (xy 96.443656 -242.792879) (xy 96.458535 -242.747172) (xy 96.480392 -242.704362)
			(xy 96.508687 -242.665504) (xy 96.542721 -242.631561) (xy 96.581653 -242.603369) (xy 96.624522 -242.581625)
			(xy 96.647254 -242.57381) (xy 96.650048 -242.572794) (xy 96.65941 -242.568708) (xy 96.674098 -242.554536)
			(xy 96.682085 -242.535754) (xy 96.68256 -242.52555) (xy 96.68256 -241.58321) (xy 96.68256 -241.582194)
			(xy 96.681701 -241.569814) (xy 96.669722 -241.548111) (xy 96.6597 -241.540792) (xy 96.635676 -241.53369)
			(xy 96.590154 -241.512779) (xy 96.548626 -241.484762) (xy 96.512192 -241.450382) (xy 96.481815 -241.410548)
			(xy 96.458301 -241.366315) (xy 96.442272 -241.318854) (xy 96.434152 -241.269421) (xy 96.43364 -241.244374)
			(xy 96.434135 -241.219351) (xy 96.442252 -241.169968) (xy 96.458268 -241.122554) (xy 96.481758 -241.078364)
			(xy 96.512101 -241.038566) (xy 96.548495 -241.004213) (xy 96.589976 -240.976215) (xy 96.635447 -240.955312)
			(xy 96.659446 -240.94821) (xy 96.66949 -240.940973) (xy 96.681593 -240.919406) (xy 96.68256 -240.907062)
			(xy 96.68256 -240.52784) (xy 96.682437 -240.523292) (xy 96.680777 -240.514348) (xy 96.679258 -240.51006)
			(xy 96.67621 -240.501678) (xy 96.670368 -240.49482) (xy 96.635986 -240.454106) (xy 96.573091 -240.36807)
			(xy 96.517255 -240.277294) (xy 96.468836 -240.182354) (xy 96.42814 -240.083857) (xy 96.411288 -240.033302)
			(xy 96.409245 -240.027638) (xy 96.402962 -240.017372) (xy 96.398842 -240.012982) (xy 96.247966 -239.862106)
			(xy 96.241111 -239.854711) (xy 96.233364 -239.836112) (xy 96.23298 -239.826038) (xy 96.23298 -239.159034)
			(xy 96.232726 -239.153446) (xy 96.23109 -239.143358) (xy 96.221035 -239.125585) (xy 96.204878 -239.113099)
			(xy 96.195134 -239.110012) (xy 96.19488 -239.110012) (xy 96.170531 -239.103226) (xy 96.124332 -239.082724)
			(xy 96.082138 -239.054895) (xy 96.045103 -239.020499) (xy 96.014237 -238.980474) (xy 95.990382 -238.935913)
			(xy 95.974189 -238.888033) (xy 95.966101 -238.83814) (xy 95.966339 -238.787596) (xy 95.974895 -238.737782)
			(xy 95.991536 -238.690055) (xy 96.015809 -238.645721) (xy 96.04705 -238.605988) (xy 96.084407 -238.571941)
			(xy 96.126859 -238.544509) (xy 96.173249 -238.524442) (xy 96.197674 -238.517938) (xy 96.206512 -238.514662)
			(xy 96.221172 -238.502845) (xy 96.23058 -238.486532) (xy 96.232472 -238.477298) (xy 96.23298 -238.469424)
			(xy 96.23298 -237.539022) (xy 96.232726 -237.533434) (xy 96.231088 -237.523348) (xy 96.221031 -237.505579)
			(xy 96.204874 -237.493096) (xy 96.195134 -237.49) (xy 96.19488 -237.49) (xy 96.170633 -237.483216)
			(xy 96.124605 -237.462817) (xy 96.082547 -237.435141) (xy 96.045601 -237.40094) (xy 96.014768 -237.36114)
			(xy 95.990883 -237.316821) (xy 95.974594 -237.269182) (xy 95.966342 -237.219517) (xy 95.965772 -237.194344)
			(xy 95.966215 -237.170348) (xy 95.973716 -237.122946) (xy 95.98854 -237.077301) (xy 96.010323 -237.034538)
			(xy 96.038528 -236.995708) (xy 96.072459 -236.961769) (xy 96.111283 -236.933557) (xy 96.154042 -236.911765)
			(xy 96.199684 -236.896931) (xy 96.247084 -236.88942) (xy 96.27108 -236.889036) (xy 96.294759 -236.889481)
			(xy 96.341548 -236.896791) (xy 96.386648 -236.911239) (xy 96.428975 -236.932479) (xy 96.467514 -236.960001)
			(xy 96.50134 -236.993144) (xy 96.529643 -237.031113) (xy 96.541082 -237.05185) (xy 96.543876 -237.057184)
			(xy 96.55175 -237.066074) (xy 96.556322 -237.069376) (xy 96.561278 -237.072682) (xy 96.572311 -237.077168)
			(xy 96.578166 -237.078266) (xy 96.660462 -237.090712) (xy 96.671689 -237.091549) (xy 96.693066 -237.084578)
			(xy 96.70161 -237.07725) (xy 96.702626 -237.076234) (xy 96.805242 -236.973618) (xy 96.810231 -236.968119)
			(xy 96.81708 -236.954954) (xy 96.818704 -236.94771) (xy 96.81972 -236.938058) (xy 96.81972 -236.790484)
			(xy 96.819254 -236.780851) (xy 96.812075 -236.762966) (xy 96.80575 -236.755686) (xy 96.775524 -236.723682)
			(xy 96.75749 -236.704886) (xy 96.750958 -236.698478) (xy 96.734549 -236.69041) (xy 96.725486 -236.689138)
			(xy 96.723708 -236.689138) (xy 96.699435 -236.687287) (xy 96.651888 -236.676854) (xy 96.606599 -236.659009)
			(xy 96.564715 -236.634205) (xy 96.527297 -236.603069) (xy 96.495293 -236.56639) (xy 96.469515 -236.525099)
			(xy 96.450614 -236.48024) (xy 96.43907 -236.432951) (xy 96.435175 -236.384429) (xy 96.439029 -236.335904)
			(xy 96.450533 -236.288605) (xy 96.469396 -236.24373) (xy 96.49514 -236.202417) (xy 96.527112 -236.165712)
			(xy 96.564504 -236.134544) (xy 96.606367 -236.109705) (xy 96.651641 -236.091822) (xy 96.699179 -236.081348)
			(xy 96.723454 -236.079538) (xy 96.725232 -236.079538) (xy 96.725486 -236.079538) (xy 96.73454 -236.078243)
			(xy 96.75094 -236.070174) (xy 96.75749 -236.06379) (xy 96.775524 -236.044994) (xy 96.80575 -236.01299)
			(xy 96.8121 -236.005724) (xy 96.819288 -235.987832) (xy 96.81972 -235.978192) (xy 96.81972 -235.170472)
			(xy 96.819252 -235.16084) (xy 96.81207 -235.142958) (xy 96.80575 -235.135674) (xy 96.775524 -235.10367)
			(xy 96.75749 -235.084874) (xy 96.750957 -235.078467) (xy 96.734548 -235.070401) (xy 96.725486 -235.069126)
			(xy 96.723708 -235.069126) (xy 96.699436 -235.067275) (xy 96.651891 -235.056842) (xy 96.606604 -235.038998)
			(xy 96.564721 -235.014194) (xy 96.527305 -234.98306) (xy 96.495303 -234.946383) (xy 96.469525 -234.905093)
			(xy 96.450625 -234.860236) (xy 96.439082 -234.812948) (xy 96.435187 -234.764428) (xy 96.439041 -234.715905)
			(xy 96.450544 -234.668608) (xy 96.469407 -234.623735) (xy 96.49515 -234.582424) (xy 96.527121 -234.54572)
			(xy 96.564512 -234.514554) (xy 96.606373 -234.489715) (xy 96.651645 -234.471833) (xy 96.699181 -234.46136)
			(xy 96.723454 -234.459526) (xy 96.725232 -234.459526) (xy 96.725486 -234.459526) (xy 96.73454 -234.45823)
			(xy 96.750939 -234.45016) (xy 96.75749 -234.443778) (xy 96.775524 -234.424982) (xy 96.80575 -234.392978)
			(xy 96.812098 -234.385711) (xy 96.819282 -234.367819) (xy 96.81972 -234.35818) (xy 96.81972 -233.55046)
			(xy 96.81925 -233.540829) (xy 96.812065 -233.52295) (xy 96.80575 -233.515662) (xy 96.775524 -233.483658)
			(xy 96.75749 -233.464862) (xy 96.750956 -233.458456) (xy 96.734547 -233.450393) (xy 96.725486 -233.449114)
			(xy 96.723708 -233.449114) (xy 96.699437 -233.447263) (xy 96.651894 -233.436831) (xy 96.606608 -233.418987)
			(xy 96.564728 -233.394184) (xy 96.527313 -233.363051) (xy 96.495312 -233.326375) (xy 96.469535 -233.285087)
			(xy 96.450636 -233.240231) (xy 96.439093 -233.192946) (xy 96.435199 -233.144428) (xy 96.439053 -233.095906)
			(xy 96.450556 -233.048611) (xy 96.469418 -233.00374) (xy 96.49516 -232.96243) (xy 96.52713 -232.925728)
			(xy 96.564519 -232.894563) (xy 96.606379 -232.869725) (xy 96.651649 -232.851844) (xy 96.699184 -232.841372)
			(xy 96.723454 -232.839514) (xy 96.725232 -232.839514) (xy 96.725486 -232.839514) (xy 96.734539 -232.838218)
			(xy 96.750937 -232.830146) (xy 96.75749 -232.823766) (xy 96.775524 -232.80497) (xy 96.80575 -232.772966)
			(xy 96.812097 -232.765699) (xy 96.819276 -232.747807) (xy 96.81972 -232.738168) (xy 96.81972 -231.930448)
			(xy 96.819248 -231.920818) (xy 96.81206 -231.902942) (xy 96.80575 -231.89565) (xy 96.775524 -231.863646)
			(xy 96.75749 -231.84485) (xy 96.750956 -231.838445) (xy 96.734546 -231.830384) (xy 96.725486 -231.829102)
			(xy 96.723708 -231.829102) (xy 96.699438 -231.827251) (xy 96.651897 -231.816819) (xy 96.606613 -231.798976)
			(xy 96.564734 -231.774174) (xy 96.527321 -231.743042) (xy 96.495321 -231.706367) (xy 96.469546 -231.665081)
			(xy 96.450647 -231.620227) (xy 96.439105 -231.572943) (xy 96.435211 -231.524427) (xy 96.439065 -231.475908)
			(xy 96.450568 -231.428614) (xy 96.469429 -231.383745) (xy 96.49517 -231.342437) (xy 96.527139 -231.305736)
			(xy 96.564526 -231.274573) (xy 96.606385 -231.249736) (xy 96.651654 -231.231855) (xy 96.699186 -231.221384)
			(xy 96.723454 -231.219502) (xy 96.725232 -231.219502) (xy 96.725486 -231.219502) (xy 96.734542 -231.218209)
			(xy 96.750948 -231.210147) (xy 96.75749 -231.203754) (xy 96.775524 -231.184958) (xy 96.80575 -231.152954)
			(xy 96.812094 -231.145686) (xy 96.819269 -231.127794) (xy 96.81972 -231.118156) (xy 96.81972 -230.310436)
			(xy 96.819246 -230.300807) (xy 96.812055 -230.282934) (xy 96.80575 -230.275638) (xy 96.775524 -230.243634)
			(xy 96.75749 -230.224838) (xy 96.750955 -230.218435) (xy 96.734546 -230.210375) (xy 96.725486 -230.20909)
			(xy 96.723708 -230.20909) (xy 96.699439 -230.207239) (xy 96.6519 -230.196807) (xy 96.606618 -230.178965)
			(xy 96.56474 -230.154164) (xy 96.527329 -230.123033) (xy 96.49533 -230.08636) (xy 96.469556 -230.045074)
			(xy 96.450658 -230.000223) (xy 96.439117 -229.952941) (xy 96.435223 -229.904426) (xy 96.439077 -229.855909)
			(xy 96.450579 -229.808617) (xy 96.46944 -229.76375) (xy 96.49518 -229.722443) (xy 96.527148 -229.685744)
			(xy 96.564534 -229.654582) (xy 96.606391 -229.629746) (xy 96.651658 -229.611867) (xy 96.699188 -229.601396)
			(xy 96.723454 -229.59949) (xy 96.725232 -229.59949) (xy 96.725486 -229.59949) (xy 96.734542 -229.598197)
			(xy 96.750947 -229.590134) (xy 96.75749 -229.583742) (xy 96.775524 -229.564946) (xy 96.80575 -229.532942)
			(xy 96.812093 -229.525673) (xy 96.819263 -229.507781) (xy 96.81972 -229.498144) (xy 96.81972 -229.144322)
			(xy 96.81955 -229.138313) (xy 96.816721 -229.126633) (xy 96.814132 -229.121208) (xy 96.812295 -229.117732)
			(xy 96.807706 -229.111349) (xy 96.804988 -229.108508) (xy 96.501712 -228.805232) (xy 96.498861 -228.802526)
			(xy 96.492483 -228.797932) (xy 96.489012 -228.796088) (xy 96.483584 -228.79351) (xy 96.471904 -228.790697)
			(xy 96.465898 -228.7905) (xy 95.688404 -228.7905) (xy 95.675819 -228.791208) (xy 95.653675 -228.803185)
			(xy 95.64624 -228.81336) (xy 95.59925 -228.893878) (xy 95.596497 -228.899524) (xy 95.593543 -228.911728)
			(xy 95.593408 -228.918008) (xy 95.604076 -228.936296) (xy 95.617462 -228.960499) (xy 95.636472 -229.012434)
			(xy 95.646148 -229.066886) (xy 95.646748 -229.094538) (xy 95.646261 -229.119348) (xy 95.638499 -229.168356)
			(xy 95.623166 -229.215546) (xy 95.600639 -229.259757) (xy 95.571474 -229.2999) (xy 95.536388 -229.334986)
			(xy 95.496245 -229.364151) (xy 95.452034 -229.386678) (xy 95.404844 -229.402011) (xy 95.355836 -229.409773)
			(xy 95.306216 -229.409773) (xy 95.257208 -229.402011) (xy 95.210018 -229.386678) (xy 95.165807 -229.364151)
			(xy 95.125664 -229.334986) (xy 95.090578 -229.2999) (xy 95.061413 -229.259757) (xy 95.038886 -229.215546)
			(xy 95.023553 -229.168356) (xy 95.015791 -229.119348) (xy 95.015304 -229.094538) (xy 95.015836 -229.069112)
			(xy 95.024029 -229.018922) (xy 95.040162 -228.970696) (xy 95.063818 -228.925679) (xy 95.094383 -228.885036)
			(xy 95.131069 -228.849818) (xy 95.151702 -228.83495) (xy 95.167704 -228.824028) (xy 95.169713 -228.819627)
			(xy 95.172261 -228.810296) (xy 95.172784 -228.805486) (xy 95.179134 -228.72827) (xy 95.179525 -228.717171)
			(xy 95.171882 -228.696347) (xy 95.164402 -228.688138) (xy 95.047562 -228.571298) (xy 95.039891 -228.564254)
			(xy 95.020577 -228.556524) (xy 94.999782 -228.557158) (xy 94.990158 -228.561138) (xy 94.969862 -228.570185)
			(xy 94.927305 -228.582964) (xy 94.883343 -228.589431) (xy 94.861126 -228.58984) (xy 94.837133 -228.589371)
			(xy 94.789736 -228.581869) (xy 94.744096 -228.567044) (xy 94.701338 -228.545262) (xy 94.662513 -228.51706)
			(xy 94.628578 -228.483131) (xy 94.600368 -228.444312) (xy 94.578578 -228.401557) (xy 94.563745 -228.355921)
			(xy 94.556233 -228.308525) (xy 94.555818 -228.284532) (xy 94.556236 -228.262315) (xy 94.562705 -228.218355)
			(xy 94.57547 -228.175794) (xy 94.58452 -228.1555) (xy 94.58452 -228.155246) (xy 94.58757 -228.148102)
			(xy 94.589639 -228.132716) (xy 94.588584 -228.12502) (xy 94.587314 -228.117654) (xy 94.579948 -228.103684)
			(xy 94.210632 -227.734368) (xy 94.20479 -227.729288) (xy 94.185392 -227.714552) (xy 94.150946 -227.680106)
			(xy 94.13621 -227.660708) (xy 94.13113 -227.654866) (xy 93.461332 -226.985068) (xy 93.458483 -226.982359)
			(xy 93.452108 -226.97776) (xy 93.448632 -226.975924) (xy 93.443205 -226.973342) (xy 93.431525 -226.970523)
			(xy 93.425518 -226.970336) (xy 92.119196 -226.970336) (xy 92.113354 -226.971606) (xy 92.095514 -226.975528)
			(xy 92.059228 -226.979731) (xy 92.040964 -226.979988) (xy 92.022698 -226.979753) (xy 91.98641 -226.975552)
			(xy 91.968574 -226.971606) (xy 91.962732 -226.970336) (xy 91.179142 -226.970336) (xy 91.1733 -226.971606)
			(xy 91.15546 -226.975525) (xy 91.119174 -226.979722) (xy 91.10091 -226.979988) (xy 91.082645 -226.97975)
			(xy 91.046358 -226.975543) (xy 91.02852 -226.971606) (xy 91.022678 -226.970336) (xy 83.843114 -226.970336)
			(xy 83.833365 -226.970855) (xy 83.81534 -226.978306) (xy 83.808062 -226.984814) (xy 83.509358 -227.283518)
			(xy 83.502794 -227.290763) (xy 83.495323 -227.308806) (xy 83.49488 -227.31857) (xy 83.49488 -227.474526)
			(xy 83.745336 -227.474526) (xy 83.749296 -227.425472) (xy 83.761073 -227.377688) (xy 83.780364 -227.332412)
			(xy 83.806667 -227.290816) (xy 83.839302 -227.253979) (xy 83.877423 -227.222854) (xy 83.920044 -227.198247)
			(xy 83.96606 -227.180795) (xy 84.014279 -227.170951) (xy 84.063454 -227.16897) (xy 84.112309 -227.174902)
			(xy 84.15958 -227.188594) (xy 84.204042 -227.209692) (xy 84.244545 -227.237648) (xy 84.280038 -227.27174)
			(xy 84.309603 -227.311084) (xy 84.332474 -227.354661) (xy 84.348058 -227.401342) (xy 84.355953 -227.449919)
			(xy 84.356448 -227.474526) (xy 84.685136 -227.474526) (xy 84.689096 -227.425472) (xy 84.700873 -227.377688)
			(xy 84.720164 -227.332412) (xy 84.746467 -227.290816) (xy 84.779102 -227.253979) (xy 84.817223 -227.222854)
			(xy 84.859844 -227.198247) (xy 84.90586 -227.180795) (xy 84.954079 -227.170951) (xy 85.003254 -227.16897)
			(xy 85.052109 -227.174902) (xy 85.09938 -227.188594) (xy 85.143842 -227.209692) (xy 85.184345 -227.237648)
			(xy 85.219838 -227.27174) (xy 85.249403 -227.311084) (xy 85.272274 -227.354661) (xy 85.287858 -227.401342)
			(xy 85.295753 -227.449919) (xy 85.296248 -227.474526) (xy 85.62519 -227.474526) (xy 85.62915 -227.425472)
			(xy 85.640927 -227.377688) (xy 85.660218 -227.332412) (xy 85.686521 -227.290816) (xy 85.719156 -227.253979)
			(xy 85.757277 -227.222854) (xy 85.799898 -227.198247) (xy 85.845914 -227.180795) (xy 85.894133 -227.170951)
			(xy 85.943308 -227.16897) (xy 85.992163 -227.174902) (xy 86.039434 -227.188594) (xy 86.083896 -227.209692)
			(xy 86.124399 -227.237648) (xy 86.159892 -227.27174) (xy 86.189457 -227.311084) (xy 86.212328 -227.354661)
			(xy 86.227912 -227.401342) (xy 86.235807 -227.449919) (xy 86.236302 -227.474526) (xy 87.505298 -227.474526)
			(xy 87.509258 -227.425472) (xy 87.521035 -227.377688) (xy 87.540326 -227.332412) (xy 87.566629 -227.290816)
			(xy 87.599264 -227.253979) (xy 87.637385 -227.222854) (xy 87.680006 -227.198247) (xy 87.726022 -227.180795)
			(xy 87.774241 -227.170951) (xy 87.823416 -227.16897) (xy 87.872271 -227.174902) (xy 87.919542 -227.188594)
			(xy 87.964004 -227.209692) (xy 88.004507 -227.237648) (xy 88.04 -227.27174) (xy 88.069565 -227.311084)
			(xy 88.092436 -227.354661) (xy 88.10802 -227.401342) (xy 88.115915 -227.449919) (xy 88.11641 -227.474526)
			(xy 88.445352 -227.474526) (xy 88.449312 -227.425472) (xy 88.461089 -227.377688) (xy 88.48038 -227.332412)
			(xy 88.506683 -227.290816) (xy 88.539318 -227.253979) (xy 88.577439 -227.222854) (xy 88.62006 -227.198247)
			(xy 88.666076 -227.180795) (xy 88.714295 -227.170951) (xy 88.76347 -227.16897) (xy 88.812325 -227.174902)
			(xy 88.859596 -227.188594) (xy 88.904058 -227.209692) (xy 88.944561 -227.237648) (xy 88.980054 -227.27174)
			(xy 89.009619 -227.311084) (xy 89.03249 -227.354661) (xy 89.048074 -227.401342) (xy 89.055969 -227.449919)
			(xy 89.056464 -227.474526) (xy 89.385152 -227.474526) (xy 89.389112 -227.425472) (xy 89.400889 -227.377688)
			(xy 89.42018 -227.332412) (xy 89.446483 -227.290816) (xy 89.479118 -227.253979) (xy 89.517239 -227.222854)
			(xy 89.55986 -227.198247) (xy 89.605876 -227.180795) (xy 89.654095 -227.170951) (xy 89.70327 -227.16897)
			(xy 89.752125 -227.174902) (xy 89.799396 -227.188594) (xy 89.843858 -227.209692) (xy 89.884361 -227.237648)
			(xy 89.919854 -227.27174) (xy 89.949419 -227.311084) (xy 89.97229 -227.354661) (xy 89.987874 -227.401342)
			(xy 89.995769 -227.449919) (xy 89.996264 -227.474526) (xy 90.314775 -227.474526) (xy 90.31887 -227.423798)
			(xy 90.331049 -227.374384) (xy 90.350997 -227.327564) (xy 90.378198 -227.28455) (xy 90.411946 -227.246456)
			(xy 90.451368 -227.214269) (xy 90.495442 -227.188823) (xy 90.543028 -227.170776) (xy 90.592892 -227.160596)
			(xy 90.643744 -227.158547) (xy 90.694265 -227.164681) (xy 90.743149 -227.178841) (xy 90.789128 -227.200658)
			(xy 90.831012 -227.229568) (xy 90.867716 -227.264823) (xy 90.898289 -227.305509) (xy 90.92194 -227.350572)
			(xy 90.938056 -227.398846) (xy 90.94622 -227.44908) (xy 90.946732 -227.474526) (xy 91.26526 -227.474526)
			(xy 91.26922 -227.425472) (xy 91.280997 -227.377688) (xy 91.300288 -227.332412) (xy 91.326591 -227.290816)
			(xy 91.359226 -227.253979) (xy 91.397347 -227.222854) (xy 91.439968 -227.198247) (xy 91.485984 -227.180795)
			(xy 91.534203 -227.170951) (xy 91.583378 -227.16897) (xy 91.632233 -227.174902) (xy 91.679504 -227.188594)
			(xy 91.723966 -227.209692) (xy 91.764469 -227.237648) (xy 91.799962 -227.27174) (xy 91.829527 -227.311084)
			(xy 91.852398 -227.354661) (xy 91.867982 -227.401342) (xy 91.875877 -227.449919) (xy 91.876372 -227.474526)
			(xy 92.194883 -227.474526) (xy 92.198978 -227.423798) (xy 92.211157 -227.374384) (xy 92.231105 -227.327564)
			(xy 92.258306 -227.28455) (xy 92.292054 -227.246456) (xy 92.331476 -227.214269) (xy 92.37555 -227.188823)
			(xy 92.423136 -227.170776) (xy 92.473 -227.160596) (xy 92.523852 -227.158547) (xy 92.574373 -227.164681)
			(xy 92.623257 -227.178841) (xy 92.669236 -227.200658) (xy 92.71112 -227.229568) (xy 92.747824 -227.264823)
			(xy 92.778397 -227.305509) (xy 92.802048 -227.350572) (xy 92.818164 -227.398846) (xy 92.826328 -227.44908)
			(xy 92.82684 -227.474526) (xy 92.826328 -227.499972) (xy 92.818164 -227.550206) (xy 92.802048 -227.59848)
			(xy 92.778397 -227.643543) (xy 92.747824 -227.684229) (xy 92.71112 -227.719484) (xy 92.669236 -227.748394)
			(xy 92.623257 -227.770211) (xy 92.574373 -227.784371) (xy 92.523852 -227.790505) (xy 92.473 -227.788456)
			(xy 92.423136 -227.778276) (xy 92.37555 -227.760229) (xy 92.331476 -227.734783) (xy 92.292054 -227.702596)
			(xy 92.258306 -227.664502) (xy 92.231105 -227.621488) (xy 92.211157 -227.574668) (xy 92.198978 -227.525254)
			(xy 92.194883 -227.474526) (xy 91.876372 -227.474526) (xy 91.875877 -227.499133) (xy 91.867982 -227.54771)
			(xy 91.852398 -227.594391) (xy 91.829527 -227.637968) (xy 91.799962 -227.677312) (xy 91.764469 -227.711404)
			(xy 91.723966 -227.73936) (xy 91.679504 -227.760458) (xy 91.632233 -227.77415) (xy 91.583378 -227.780082)
			(xy 91.534203 -227.778101) (xy 91.485984 -227.768257) (xy 91.439968 -227.750805) (xy 91.397347 -227.726198)
			(xy 91.359226 -227.695073) (xy 91.326591 -227.658236) (xy 91.300288 -227.61664) (xy 91.280997 -227.571364)
			(xy 91.26922 -227.52358) (xy 91.26526 -227.474526) (xy 90.946732 -227.474526) (xy 90.94622 -227.499972)
			(xy 90.938056 -227.550206) (xy 90.92194 -227.59848) (xy 90.898289 -227.643543) (xy 90.867716 -227.684229)
			(xy 90.831012 -227.719484) (xy 90.789128 -227.748394) (xy 90.743149 -227.770211) (xy 90.694265 -227.784371)
			(xy 90.643744 -227.790505) (xy 90.592892 -227.788456) (xy 90.543028 -227.778276) (xy 90.495442 -227.760229)
			(xy 90.451368 -227.734783) (xy 90.411946 -227.702596) (xy 90.378198 -227.664502) (xy 90.350997 -227.621488)
			(xy 90.331049 -227.574668) (xy 90.31887 -227.525254) (xy 90.314775 -227.474526) (xy 89.996264 -227.474526)
			(xy 89.995769 -227.499133) (xy 89.987874 -227.54771) (xy 89.97229 -227.594391) (xy 89.949419 -227.637968)
			(xy 89.919854 -227.677312) (xy 89.884361 -227.711404) (xy 89.843858 -227.73936) (xy 89.799396 -227.760458)
			(xy 89.752125 -227.77415) (xy 89.70327 -227.780082) (xy 89.654095 -227.778101) (xy 89.605876 -227.768257)
			(xy 89.55986 -227.750805) (xy 89.517239 -227.726198) (xy 89.479118 -227.695073) (xy 89.446483 -227.658236)
			(xy 89.42018 -227.61664) (xy 89.400889 -227.571364) (xy 89.389112 -227.52358) (xy 89.385152 -227.474526)
			(xy 89.056464 -227.474526) (xy 89.055969 -227.499133) (xy 89.048074 -227.54771) (xy 89.03249 -227.594391)
			(xy 89.009619 -227.637968) (xy 88.980054 -227.677312) (xy 88.944561 -227.711404) (xy 88.904058 -227.73936)
			(xy 88.859596 -227.760458) (xy 88.812325 -227.77415) (xy 88.76347 -227.780082) (xy 88.714295 -227.778101)
			(xy 88.666076 -227.768257) (xy 88.62006 -227.750805) (xy 88.577439 -227.726198) (xy 88.539318 -227.695073)
			(xy 88.506683 -227.658236) (xy 88.48038 -227.61664) (xy 88.461089 -227.571364) (xy 88.449312 -227.52358)
			(xy 88.445352 -227.474526) (xy 88.11641 -227.474526) (xy 88.115915 -227.499133) (xy 88.10802 -227.54771)
			(xy 88.092436 -227.594391) (xy 88.069565 -227.637968) (xy 88.04 -227.677312) (xy 88.004507 -227.711404)
			(xy 87.964004 -227.73936) (xy 87.919542 -227.760458) (xy 87.872271 -227.77415) (xy 87.823416 -227.780082)
			(xy 87.774241 -227.778101) (xy 87.726022 -227.768257) (xy 87.680006 -227.750805) (xy 87.637385 -227.726198)
			(xy 87.599264 -227.695073) (xy 87.566629 -227.658236) (xy 87.540326 -227.61664) (xy 87.521035 -227.571364)
			(xy 87.509258 -227.52358) (xy 87.505298 -227.474526) (xy 86.236302 -227.474526) (xy 86.235807 -227.499133)
			(xy 86.227912 -227.54771) (xy 86.212328 -227.594391) (xy 86.189457 -227.637968) (xy 86.159892 -227.677312)
			(xy 86.124399 -227.711404) (xy 86.083896 -227.73936) (xy 86.039434 -227.760458) (xy 85.992163 -227.77415)
			(xy 85.943308 -227.780082) (xy 85.894133 -227.778101) (xy 85.845914 -227.768257) (xy 85.799898 -227.750805)
			(xy 85.757277 -227.726198) (xy 85.719156 -227.695073) (xy 85.686521 -227.658236) (xy 85.660218 -227.61664)
			(xy 85.640927 -227.571364) (xy 85.62915 -227.52358) (xy 85.62519 -227.474526) (xy 85.296248 -227.474526)
			(xy 85.295753 -227.499133) (xy 85.287858 -227.54771) (xy 85.272274 -227.594391) (xy 85.249403 -227.637968)
			(xy 85.219838 -227.677312) (xy 85.184345 -227.711404) (xy 85.143842 -227.73936) (xy 85.09938 -227.760458)
			(xy 85.052109 -227.77415) (xy 85.003254 -227.780082) (xy 84.954079 -227.778101) (xy 84.90586 -227.768257)
			(xy 84.859844 -227.750805) (xy 84.817223 -227.726198) (xy 84.779102 -227.695073) (xy 84.746467 -227.658236)
			(xy 84.720164 -227.61664) (xy 84.700873 -227.571364) (xy 84.689096 -227.52358) (xy 84.685136 -227.474526)
			(xy 84.356448 -227.474526) (xy 84.355953 -227.499133) (xy 84.348058 -227.54771) (xy 84.332474 -227.594391)
			(xy 84.309603 -227.637968) (xy 84.280038 -227.677312) (xy 84.244545 -227.711404) (xy 84.204042 -227.73936)
			(xy 84.15958 -227.760458) (xy 84.112309 -227.77415) (xy 84.063454 -227.780082) (xy 84.014279 -227.778101)
			(xy 83.96606 -227.768257) (xy 83.920044 -227.750805) (xy 83.877423 -227.726198) (xy 83.839302 -227.695073)
			(xy 83.806667 -227.658236) (xy 83.780364 -227.61664) (xy 83.761073 -227.571364) (xy 83.749296 -227.52358)
			(xy 83.745336 -227.474526) (xy 83.49488 -227.474526) (xy 83.49488 -227.83165) (xy 83.494975 -227.8362)
			(xy 83.496644 -227.845146) (xy 83.498182 -227.84943) (xy 83.501738 -227.858828) (xy 83.537298 -227.898198)
			(xy 83.552792 -227.91547) (xy 83.559904 -227.92182) (xy 83.561936 -227.92309) (xy 83.567778 -227.926646)
			(xy 83.576414 -227.93071) (xy 83.585558 -227.931726) (xy 83.585812 -227.931726) (xy 83.60941 -227.934463)
			(xy 83.655414 -227.946304) (xy 83.699029 -227.965125) (xy 83.739204 -227.990473) (xy 83.77497 -228.021736)
			(xy 83.805464 -228.058159) (xy 83.829951 -228.098865) (xy 83.839304 -228.120702) (xy 83.84286 -228.127306)
			(xy 83.843114 -228.127814) (xy 83.856648 -228.151694) (xy 83.87591 -228.203086) (xy 83.885694 -228.25709)
			(xy 83.886294 -228.284532) (xy 84.215236 -228.284532) (xy 84.219196 -228.235478) (xy 84.230973 -228.187694)
			(xy 84.250264 -228.142418) (xy 84.276567 -228.100822) (xy 84.309202 -228.063985) (xy 84.347323 -228.03286)
			(xy 84.389944 -228.008253) (xy 84.43596 -227.990801) (xy 84.484179 -227.980957) (xy 84.533354 -227.978976)
			(xy 84.582209 -227.984908) (xy 84.62948 -227.9986) (xy 84.673942 -228.019698) (xy 84.714445 -228.047654)
			(xy 84.749938 -228.081746) (xy 84.779503 -228.12109) (xy 84.802374 -228.164667) (xy 84.817958 -228.211348)
			(xy 84.825853 -228.259925) (xy 84.826348 -228.284532) (xy 85.15529 -228.284532) (xy 85.15925 -228.235478)
			(xy 85.171027 -228.187694) (xy 85.190318 -228.142418) (xy 85.216621 -228.100822) (xy 85.249256 -228.063985)
			(xy 85.287377 -228.03286) (xy 85.329998 -228.008253) (xy 85.376014 -227.990801) (xy 85.424233 -227.980957)
			(xy 85.473408 -227.978976) (xy 85.522263 -227.984908) (xy 85.569534 -227.9986) (xy 85.613996 -228.019698)
			(xy 85.654499 -228.047654) (xy 85.689992 -228.081746) (xy 85.719557 -228.12109) (xy 85.742428 -228.164667)
			(xy 85.758012 -228.211348) (xy 85.765907 -228.259925) (xy 85.766402 -228.284532) (xy 86.095344 -228.284532)
			(xy 86.099304 -228.235478) (xy 86.111081 -228.187694) (xy 86.130372 -228.142418) (xy 86.156675 -228.100822)
			(xy 86.18931 -228.063985) (xy 86.227431 -228.03286) (xy 86.270052 -228.008253) (xy 86.316068 -227.990801)
			(xy 86.364287 -227.980957) (xy 86.413462 -227.978976) (xy 86.462317 -227.984908) (xy 86.509588 -227.9986)
			(xy 86.55405 -228.019698) (xy 86.594553 -228.047654) (xy 86.630046 -228.081746) (xy 86.659611 -228.12109)
			(xy 86.682482 -228.164667) (xy 86.698066 -228.211348) (xy 86.705961 -228.259925) (xy 86.706456 -228.284532)
			(xy 87.035144 -228.284532) (xy 87.039104 -228.235478) (xy 87.050881 -228.187694) (xy 87.070172 -228.142418)
			(xy 87.096475 -228.100822) (xy 87.12911 -228.063985) (xy 87.167231 -228.03286) (xy 87.209852 -228.008253)
			(xy 87.255868 -227.990801) (xy 87.304087 -227.980957) (xy 87.353262 -227.978976) (xy 87.402117 -227.984908)
			(xy 87.449388 -227.9986) (xy 87.49385 -228.019698) (xy 87.534353 -228.047654) (xy 87.569846 -228.081746)
			(xy 87.599411 -228.12109) (xy 87.622282 -228.164667) (xy 87.637866 -228.211348) (xy 87.645761 -228.259925)
			(xy 87.646256 -228.284532) (xy 87.975198 -228.284532) (xy 87.979158 -228.235478) (xy 87.990935 -228.187694)
			(xy 88.010226 -228.142418) (xy 88.036529 -228.100822) (xy 88.069164 -228.063985) (xy 88.107285 -228.03286)
			(xy 88.149906 -228.008253) (xy 88.195922 -227.990801) (xy 88.244141 -227.980957) (xy 88.293316 -227.978976)
			(xy 88.342171 -227.984908) (xy 88.389442 -227.9986) (xy 88.433904 -228.019698) (xy 88.474407 -228.047654)
			(xy 88.5099 -228.081746) (xy 88.539465 -228.12109) (xy 88.562336 -228.164667) (xy 88.57792 -228.211348)
			(xy 88.585815 -228.259925) (xy 88.58631 -228.284532) (xy 88.915252 -228.284532) (xy 88.919212 -228.235478)
			(xy 88.930989 -228.187694) (xy 88.95028 -228.142418) (xy 88.976583 -228.100822) (xy 89.009218 -228.063985)
			(xy 89.047339 -228.03286) (xy 89.08996 -228.008253) (xy 89.135976 -227.990801) (xy 89.184195 -227.980957)
			(xy 89.23337 -227.978976) (xy 89.282225 -227.984908) (xy 89.329496 -227.9986) (xy 89.373958 -228.019698)
			(xy 89.414461 -228.047654) (xy 89.449954 -228.081746) (xy 89.479519 -228.12109) (xy 89.50239 -228.164667)
			(xy 89.517974 -228.211348) (xy 89.525869 -228.259925) (xy 89.526364 -228.284532) (xy 89.855306 -228.284532)
			(xy 89.859266 -228.235478) (xy 89.871043 -228.187694) (xy 89.890334 -228.142418) (xy 89.916637 -228.100822)
			(xy 89.949272 -228.063985) (xy 89.987393 -228.03286) (xy 90.030014 -228.008253) (xy 90.07603 -227.990801)
			(xy 90.124249 -227.980957) (xy 90.173424 -227.978976) (xy 90.222279 -227.984908) (xy 90.26955 -227.9986)
			(xy 90.314012 -228.019698) (xy 90.354515 -228.047654) (xy 90.390008 -228.081746) (xy 90.419573 -228.12109)
			(xy 90.442444 -228.164667) (xy 90.458028 -228.211348) (xy 90.465923 -228.259925) (xy 90.466418 -228.284532)
			(xy 90.784675 -228.284532) (xy 90.78877 -228.233804) (xy 90.800949 -228.18439) (xy 90.820897 -228.13757)
			(xy 90.848098 -228.094556) (xy 90.881846 -228.056462) (xy 90.921268 -228.024275) (xy 90.965342 -227.998829)
			(xy 91.012928 -227.980782) (xy 91.062792 -227.970602) (xy 91.113644 -227.968553) (xy 91.164165 -227.974687)
			(xy 91.213049 -227.988847) (xy 91.259028 -228.010664) (xy 91.300912 -228.039574) (xy 91.337616 -228.074829)
			(xy 91.368189 -228.115515) (xy 91.39184 -228.160578) (xy 91.407956 -228.208852) (xy 91.41612 -228.259086)
			(xy 91.416632 -228.284532) (xy 91.724729 -228.284532) (xy 91.728824 -228.233804) (xy 91.741003 -228.18439)
			(xy 91.760951 -228.13757) (xy 91.788152 -228.094556) (xy 91.8219 -228.056462) (xy 91.861322 -228.024275)
			(xy 91.905396 -227.998829) (xy 91.952982 -227.980782) (xy 92.002846 -227.970602) (xy 92.053698 -227.968553)
			(xy 92.104219 -227.974687) (xy 92.153103 -227.988847) (xy 92.199082 -228.010664) (xy 92.240966 -228.039574)
			(xy 92.27767 -228.074829) (xy 92.308243 -228.115515) (xy 92.331894 -228.160578) (xy 92.34801 -228.208852)
			(xy 92.356174 -228.259086) (xy 92.356686 -228.284532) (xy 92.675214 -228.284532) (xy 92.679174 -228.235478)
			(xy 92.690951 -228.187694) (xy 92.710242 -228.142418) (xy 92.736545 -228.100822) (xy 92.76918 -228.063985)
			(xy 92.807301 -228.03286) (xy 92.849922 -228.008253) (xy 92.895938 -227.990801) (xy 92.944157 -227.980957)
			(xy 92.993332 -227.978976) (xy 93.042187 -227.984908) (xy 93.089458 -227.9986) (xy 93.13392 -228.019698)
			(xy 93.174423 -228.047654) (xy 93.209916 -228.081746) (xy 93.239481 -228.12109) (xy 93.262352 -228.164667)
			(xy 93.277936 -228.211348) (xy 93.285831 -228.259925) (xy 93.286326 -228.284532) (xy 93.604837 -228.284532)
			(xy 93.608932 -228.233804) (xy 93.621111 -228.18439) (xy 93.641059 -228.13757) (xy 93.66826 -228.094556)
			(xy 93.702008 -228.056462) (xy 93.74143 -228.024275) (xy 93.785504 -227.998829) (xy 93.83309 -227.980782)
			(xy 93.882954 -227.970602) (xy 93.933806 -227.968553) (xy 93.984327 -227.974687) (xy 94.033211 -227.988847)
			(xy 94.07919 -228.010664) (xy 94.121074 -228.039574) (xy 94.157778 -228.074829) (xy 94.188351 -228.115515)
			(xy 94.212002 -228.160578) (xy 94.228118 -228.208852) (xy 94.236282 -228.259086) (xy 94.236794 -228.284532)
			(xy 94.236282 -228.309978) (xy 94.228118 -228.360212) (xy 94.212002 -228.408486) (xy 94.188351 -228.453549)
			(xy 94.157778 -228.494235) (xy 94.121074 -228.52949) (xy 94.07919 -228.5584) (xy 94.033211 -228.580217)
			(xy 93.984327 -228.594377) (xy 93.933806 -228.600511) (xy 93.882954 -228.598462) (xy 93.83309 -228.588282)
			(xy 93.785504 -228.570235) (xy 93.74143 -228.544789) (xy 93.702008 -228.512602) (xy 93.66826 -228.474508)
			(xy 93.641059 -228.431494) (xy 93.621111 -228.384674) (xy 93.608932 -228.33526) (xy 93.604837 -228.284532)
			(xy 93.286326 -228.284532) (xy 93.285831 -228.309139) (xy 93.277936 -228.357716) (xy 93.262352 -228.404397)
			(xy 93.239481 -228.447974) (xy 93.209916 -228.487318) (xy 93.174423 -228.52141) (xy 93.13392 -228.549366)
			(xy 93.089458 -228.570464) (xy 93.042187 -228.584156) (xy 92.993332 -228.590088) (xy 92.944157 -228.588107)
			(xy 92.895938 -228.578263) (xy 92.849922 -228.560811) (xy 92.807301 -228.536204) (xy 92.76918 -228.505079)
			(xy 92.736545 -228.468242) (xy 92.710242 -228.426646) (xy 92.690951 -228.38137) (xy 92.679174 -228.333586)
			(xy 92.675214 -228.284532) (xy 92.356686 -228.284532) (xy 92.356174 -228.309978) (xy 92.34801 -228.360212)
			(xy 92.331894 -228.408486) (xy 92.308243 -228.453549) (xy 92.27767 -228.494235) (xy 92.240966 -228.52949)
			(xy 92.199082 -228.5584) (xy 92.153103 -228.580217) (xy 92.104219 -228.594377) (xy 92.053698 -228.600511)
			(xy 92.002846 -228.598462) (xy 91.952982 -228.588282) (xy 91.905396 -228.570235) (xy 91.861322 -228.544789)
			(xy 91.8219 -228.512602) (xy 91.788152 -228.474508) (xy 91.760951 -228.431494) (xy 91.741003 -228.384674)
			(xy 91.728824 -228.33526) (xy 91.724729 -228.284532) (xy 91.416632 -228.284532) (xy 91.41612 -228.309978)
			(xy 91.407956 -228.360212) (xy 91.39184 -228.408486) (xy 91.368189 -228.453549) (xy 91.337616 -228.494235)
			(xy 91.300912 -228.52949) (xy 91.259028 -228.5584) (xy 91.213049 -228.580217) (xy 91.164165 -228.594377)
			(xy 91.113644 -228.600511) (xy 91.062792 -228.598462) (xy 91.012928 -228.588282) (xy 90.965342 -228.570235)
			(xy 90.921268 -228.544789) (xy 90.881846 -228.512602) (xy 90.848098 -228.474508) (xy 90.820897 -228.431494)
			(xy 90.800949 -228.384674) (xy 90.78877 -228.33526) (xy 90.784675 -228.284532) (xy 90.466418 -228.284532)
			(xy 90.465923 -228.309139) (xy 90.458028 -228.357716) (xy 90.442444 -228.404397) (xy 90.419573 -228.447974)
			(xy 90.390008 -228.487318) (xy 90.354515 -228.52141) (xy 90.314012 -228.549366) (xy 90.26955 -228.570464)
			(xy 90.222279 -228.584156) (xy 90.173424 -228.590088) (xy 90.124249 -228.588107) (xy 90.07603 -228.578263)
			(xy 90.030014 -228.560811) (xy 89.987393 -228.536204) (xy 89.949272 -228.505079) (xy 89.916637 -228.468242)
			(xy 89.890334 -228.426646) (xy 89.871043 -228.38137) (xy 89.859266 -228.333586) (xy 89.855306 -228.284532)
			(xy 89.526364 -228.284532) (xy 89.525869 -228.309139) (xy 89.517974 -228.357716) (xy 89.50239 -228.404397)
			(xy 89.479519 -228.447974) (xy 89.449954 -228.487318) (xy 89.414461 -228.52141) (xy 89.373958 -228.549366)
			(xy 89.329496 -228.570464) (xy 89.282225 -228.584156) (xy 89.23337 -228.590088) (xy 89.184195 -228.588107)
			(xy 89.135976 -228.578263) (xy 89.08996 -228.560811) (xy 89.047339 -228.536204) (xy 89.009218 -228.505079)
			(xy 88.976583 -228.468242) (xy 88.95028 -228.426646) (xy 88.930989 -228.38137) (xy 88.919212 -228.333586)
			(xy 88.915252 -228.284532) (xy 88.58631 -228.284532) (xy 88.585815 -228.309139) (xy 88.57792 -228.357716)
			(xy 88.562336 -228.404397) (xy 88.539465 -228.447974) (xy 88.5099 -228.487318) (xy 88.474407 -228.52141)
			(xy 88.433904 -228.549366) (xy 88.389442 -228.570464) (xy 88.342171 -228.584156) (xy 88.293316 -228.590088)
			(xy 88.244141 -228.588107) (xy 88.195922 -228.578263) (xy 88.149906 -228.560811) (xy 88.107285 -228.536204)
			(xy 88.069164 -228.505079) (xy 88.036529 -228.468242) (xy 88.010226 -228.426646) (xy 87.990935 -228.38137)
			(xy 87.979158 -228.333586) (xy 87.975198 -228.284532) (xy 87.646256 -228.284532) (xy 87.645761 -228.309139)
			(xy 87.637866 -228.357716) (xy 87.622282 -228.404397) (xy 87.599411 -228.447974) (xy 87.569846 -228.487318)
			(xy 87.534353 -228.52141) (xy 87.49385 -228.549366) (xy 87.449388 -228.570464) (xy 87.402117 -228.584156)
			(xy 87.353262 -228.590088) (xy 87.304087 -228.588107) (xy 87.255868 -228.578263) (xy 87.209852 -228.560811)
			(xy 87.167231 -228.536204) (xy 87.12911 -228.505079) (xy 87.096475 -228.468242) (xy 87.070172 -228.426646)
			(xy 87.050881 -228.38137) (xy 87.039104 -228.333586) (xy 87.035144 -228.284532) (xy 86.706456 -228.284532)
			(xy 86.705961 -228.309139) (xy 86.698066 -228.357716) (xy 86.682482 -228.404397) (xy 86.659611 -228.447974)
			(xy 86.630046 -228.487318) (xy 86.594553 -228.52141) (xy 86.55405 -228.549366) (xy 86.509588 -228.570464)
			(xy 86.462317 -228.584156) (xy 86.413462 -228.590088) (xy 86.364287 -228.588107) (xy 86.316068 -228.578263)
			(xy 86.270052 -228.560811) (xy 86.227431 -228.536204) (xy 86.18931 -228.505079) (xy 86.156675 -228.468242)
			(xy 86.130372 -228.426646) (xy 86.111081 -228.38137) (xy 86.099304 -228.333586) (xy 86.095344 -228.284532)
			(xy 85.766402 -228.284532) (xy 85.765907 -228.309139) (xy 85.758012 -228.357716) (xy 85.742428 -228.404397)
			(xy 85.719557 -228.447974) (xy 85.689992 -228.487318) (xy 85.654499 -228.52141) (xy 85.613996 -228.549366)
			(xy 85.569534 -228.570464) (xy 85.522263 -228.584156) (xy 85.473408 -228.590088) (xy 85.424233 -228.588107)
			(xy 85.376014 -228.578263) (xy 85.329998 -228.560811) (xy 85.287377 -228.536204) (xy 85.249256 -228.505079)
			(xy 85.216621 -228.468242) (xy 85.190318 -228.426646) (xy 85.171027 -228.38137) (xy 85.15925 -228.333586)
			(xy 85.15529 -228.284532) (xy 84.826348 -228.284532) (xy 84.825853 -228.309139) (xy 84.817958 -228.357716)
			(xy 84.802374 -228.404397) (xy 84.779503 -228.447974) (xy 84.749938 -228.487318) (xy 84.714445 -228.52141)
			(xy 84.673942 -228.549366) (xy 84.62948 -228.570464) (xy 84.582209 -228.584156) (xy 84.533354 -228.590088)
			(xy 84.484179 -228.588107) (xy 84.43596 -228.578263) (xy 84.389944 -228.560811) (xy 84.347323 -228.536204)
			(xy 84.309202 -228.505079) (xy 84.276567 -228.468242) (xy 84.250264 -228.426646) (xy 84.230973 -228.38137)
			(xy 84.219196 -228.333586) (xy 84.215236 -228.284532) (xy 83.886294 -228.284532) (xy 83.885821 -228.308521)
			(xy 83.878311 -228.355908) (xy 83.86348 -228.401537) (xy 83.841695 -228.444284) (xy 83.813491 -228.483097)
			(xy 83.779562 -228.517021) (xy 83.740745 -228.545219) (xy 83.697994 -228.566998) (xy 83.652363 -228.581822)
			(xy 83.604975 -228.589325) (xy 83.580986 -228.58984) (xy 83.551268 -228.588316) (xy 83.551014 -228.588316)
			(xy 83.539076 -228.5873) (xy 83.528408 -228.591364) (xy 83.522869 -228.593674) (xy 83.512983 -228.600474)
			(xy 83.50885 -228.604826) (xy 83.508088 -228.605588) (xy 83.502215 -228.612572) (xy 83.495439 -228.6295)
			(xy 83.49488 -228.638608) (xy 83.49488 -229.094538) (xy 83.745336 -229.094538) (xy 83.749296 -229.045484)
			(xy 83.761073 -228.9977) (xy 83.780364 -228.952424) (xy 83.806667 -228.910828) (xy 83.839302 -228.873991)
			(xy 83.877423 -228.842866) (xy 83.920044 -228.818259) (xy 83.96606 -228.800807) (xy 84.014279 -228.790963)
			(xy 84.063454 -228.788982) (xy 84.112309 -228.794914) (xy 84.15958 -228.808606) (xy 84.204042 -228.829704)
			(xy 84.244545 -228.85766) (xy 84.280038 -228.891752) (xy 84.309603 -228.931096) (xy 84.332474 -228.974673)
			(xy 84.348058 -229.021354) (xy 84.355953 -229.069931) (xy 84.356448 -229.094538) (xy 84.685136 -229.094538)
			(xy 84.689096 -229.045484) (xy 84.700873 -228.9977) (xy 84.720164 -228.952424) (xy 84.746467 -228.910828)
			(xy 84.779102 -228.873991) (xy 84.817223 -228.842866) (xy 84.859844 -228.818259) (xy 84.90586 -228.800807)
			(xy 84.954079 -228.790963) (xy 85.003254 -228.788982) (xy 85.052109 -228.794914) (xy 85.09938 -228.808606)
			(xy 85.143842 -228.829704) (xy 85.184345 -228.85766) (xy 85.219838 -228.891752) (xy 85.249403 -228.931096)
			(xy 85.272274 -228.974673) (xy 85.287858 -229.021354) (xy 85.295753 -229.069931) (xy 85.296248 -229.094538)
			(xy 85.62519 -229.094538) (xy 85.62915 -229.045484) (xy 85.640927 -228.9977) (xy 85.660218 -228.952424)
			(xy 85.686521 -228.910828) (xy 85.719156 -228.873991) (xy 85.757277 -228.842866) (xy 85.799898 -228.818259)
			(xy 85.845914 -228.800807) (xy 85.894133 -228.790963) (xy 85.943308 -228.788982) (xy 85.992163 -228.794914)
			(xy 86.039434 -228.808606) (xy 86.083896 -228.829704) (xy 86.124399 -228.85766) (xy 86.159892 -228.891752)
			(xy 86.189457 -228.931096) (xy 86.212328 -228.974673) (xy 86.227912 -229.021354) (xy 86.235807 -229.069931)
			(xy 86.236302 -229.094538) (xy 86.565244 -229.094538) (xy 86.569204 -229.045484) (xy 86.580981 -228.9977)
			(xy 86.600272 -228.952424) (xy 86.626575 -228.910828) (xy 86.65921 -228.873991) (xy 86.697331 -228.842866)
			(xy 86.739952 -228.818259) (xy 86.785968 -228.800807) (xy 86.834187 -228.790963) (xy 86.883362 -228.788982)
			(xy 86.932217 -228.794914) (xy 86.979488 -228.808606) (xy 87.02395 -228.829704) (xy 87.064453 -228.85766)
			(xy 87.099946 -228.891752) (xy 87.129511 -228.931096) (xy 87.152382 -228.974673) (xy 87.167966 -229.021354)
			(xy 87.175861 -229.069931) (xy 87.176356 -229.094538) (xy 87.505298 -229.094538) (xy 87.509258 -229.045484)
			(xy 87.521035 -228.9977) (xy 87.540326 -228.952424) (xy 87.566629 -228.910828) (xy 87.599264 -228.873991)
			(xy 87.637385 -228.842866) (xy 87.680006 -228.818259) (xy 87.726022 -228.800807) (xy 87.774241 -228.790963)
			(xy 87.823416 -228.788982) (xy 87.872271 -228.794914) (xy 87.919542 -228.808606) (xy 87.964004 -228.829704)
			(xy 88.004507 -228.85766) (xy 88.04 -228.891752) (xy 88.069565 -228.931096) (xy 88.092436 -228.974673)
			(xy 88.10802 -229.021354) (xy 88.115915 -229.069931) (xy 88.11641 -229.094538) (xy 88.445352 -229.094538)
			(xy 88.449312 -229.045484) (xy 88.461089 -228.9977) (xy 88.48038 -228.952424) (xy 88.506683 -228.910828)
			(xy 88.539318 -228.873991) (xy 88.577439 -228.842866) (xy 88.62006 -228.818259) (xy 88.666076 -228.800807)
			(xy 88.714295 -228.790963) (xy 88.76347 -228.788982) (xy 88.812325 -228.794914) (xy 88.859596 -228.808606)
			(xy 88.904058 -228.829704) (xy 88.944561 -228.85766) (xy 88.980054 -228.891752) (xy 89.009619 -228.931096)
			(xy 89.03249 -228.974673) (xy 89.048074 -229.021354) (xy 89.055969 -229.069931) (xy 89.056464 -229.094538)
			(xy 89.385152 -229.094538) (xy 89.389112 -229.045484) (xy 89.400889 -228.9977) (xy 89.42018 -228.952424)
			(xy 89.446483 -228.910828) (xy 89.479118 -228.873991) (xy 89.517239 -228.842866) (xy 89.55986 -228.818259)
			(xy 89.605876 -228.800807) (xy 89.654095 -228.790963) (xy 89.70327 -228.788982) (xy 89.752125 -228.794914)
			(xy 89.799396 -228.808606) (xy 89.843858 -228.829704) (xy 89.884361 -228.85766) (xy 89.919854 -228.891752)
			(xy 89.949419 -228.931096) (xy 89.97229 -228.974673) (xy 89.987874 -229.021354) (xy 89.995769 -229.069931)
			(xy 89.996264 -229.094538) (xy 90.314775 -229.094538) (xy 90.31887 -229.04381) (xy 90.331049 -228.994396)
			(xy 90.350997 -228.947576) (xy 90.378198 -228.904562) (xy 90.411946 -228.866468) (xy 90.451368 -228.834281)
			(xy 90.495442 -228.808835) (xy 90.543028 -228.790788) (xy 90.592892 -228.780608) (xy 90.643744 -228.778559)
			(xy 90.694265 -228.784693) (xy 90.743149 -228.798853) (xy 90.789128 -228.82067) (xy 90.831012 -228.84958)
			(xy 90.867716 -228.884835) (xy 90.898289 -228.925521) (xy 90.92194 -228.970584) (xy 90.938056 -229.018858)
			(xy 90.94622 -229.069092) (xy 90.946732 -229.094538) (xy 91.26526 -229.094538) (xy 91.26922 -229.045484)
			(xy 91.280997 -228.9977) (xy 91.300288 -228.952424) (xy 91.326591 -228.910828) (xy 91.359226 -228.873991)
			(xy 91.397347 -228.842866) (xy 91.439968 -228.818259) (xy 91.485984 -228.800807) (xy 91.534203 -228.790963)
			(xy 91.583378 -228.788982) (xy 91.632233 -228.794914) (xy 91.679504 -228.808606) (xy 91.723966 -228.829704)
			(xy 91.764469 -228.85766) (xy 91.799962 -228.891752) (xy 91.829527 -228.931096) (xy 91.852398 -228.974673)
			(xy 91.867982 -229.021354) (xy 91.875877 -229.069931) (xy 91.876372 -229.094538) (xy 92.194883 -229.094538)
			(xy 92.198978 -229.04381) (xy 92.211157 -228.994396) (xy 92.231105 -228.947576) (xy 92.258306 -228.904562)
			(xy 92.292054 -228.866468) (xy 92.331476 -228.834281) (xy 92.37555 -228.808835) (xy 92.423136 -228.790788)
			(xy 92.473 -228.780608) (xy 92.523852 -228.778559) (xy 92.574373 -228.784693) (xy 92.623257 -228.798853)
			(xy 92.669236 -228.82067) (xy 92.71112 -228.84958) (xy 92.747824 -228.884835) (xy 92.778397 -228.925521)
			(xy 92.802048 -228.970584) (xy 92.818164 -229.018858) (xy 92.826328 -229.069092) (xy 92.82684 -229.094538)
			(xy 93.145114 -229.094538) (xy 93.149074 -229.045484) (xy 93.160851 -228.9977) (xy 93.180142 -228.952424)
			(xy 93.206445 -228.910828) (xy 93.23908 -228.873991) (xy 93.277201 -228.842866) (xy 93.319822 -228.818259)
			(xy 93.365838 -228.800807) (xy 93.414057 -228.790963) (xy 93.463232 -228.788982) (xy 93.512087 -228.794914)
			(xy 93.559358 -228.808606) (xy 93.60382 -228.829704) (xy 93.644323 -228.85766) (xy 93.679816 -228.891752)
			(xy 93.709381 -228.931096) (xy 93.732252 -228.974673) (xy 93.747836 -229.021354) (xy 93.755731 -229.069931)
			(xy 93.756226 -229.094538) (xy 94.074737 -229.094538) (xy 94.078832 -229.04381) (xy 94.091011 -228.994396)
			(xy 94.110959 -228.947576) (xy 94.13816 -228.904562) (xy 94.171908 -228.866468) (xy 94.21133 -228.834281)
			(xy 94.255404 -228.808835) (xy 94.30299 -228.790788) (xy 94.352854 -228.780608) (xy 94.403706 -228.778559)
			(xy 94.454227 -228.784693) (xy 94.503111 -228.798853) (xy 94.54909 -228.82067) (xy 94.590974 -228.84958)
			(xy 94.627678 -228.884835) (xy 94.658251 -228.925521) (xy 94.681902 -228.970584) (xy 94.698018 -229.018858)
			(xy 94.706182 -229.069092) (xy 94.706694 -229.094538) (xy 94.706182 -229.119984) (xy 94.698018 -229.170218)
			(xy 94.681902 -229.218492) (xy 94.658251 -229.263555) (xy 94.627678 -229.304241) (xy 94.590974 -229.339496)
			(xy 94.54909 -229.368406) (xy 94.503111 -229.390223) (xy 94.454227 -229.404383) (xy 94.403706 -229.410517)
			(xy 94.352854 -229.408468) (xy 94.30299 -229.398288) (xy 94.255404 -229.380241) (xy 94.21133 -229.354795)
			(xy 94.171908 -229.322608) (xy 94.13816 -229.284514) (xy 94.110959 -229.2415) (xy 94.091011 -229.19468)
			(xy 94.078832 -229.145266) (xy 94.074737 -229.094538) (xy 93.756226 -229.094538) (xy 93.755731 -229.119145)
			(xy 93.747836 -229.167722) (xy 93.732252 -229.214403) (xy 93.709381 -229.25798) (xy 93.679816 -229.297324)
			(xy 93.644323 -229.331416) (xy 93.60382 -229.359372) (xy 93.559358 -229.38047) (xy 93.512087 -229.394162)
			(xy 93.463232 -229.400094) (xy 93.414057 -229.398113) (xy 93.365838 -229.388269) (xy 93.319822 -229.370817)
			(xy 93.277201 -229.34621) (xy 93.23908 -229.315085) (xy 93.206445 -229.278248) (xy 93.180142 -229.236652)
			(xy 93.160851 -229.191376) (xy 93.149074 -229.143592) (xy 93.145114 -229.094538) (xy 92.82684 -229.094538)
			(xy 92.826328 -229.119984) (xy 92.818164 -229.170218) (xy 92.802048 -229.218492) (xy 92.778397 -229.263555)
			(xy 92.747824 -229.304241) (xy 92.71112 -229.339496) (xy 92.669236 -229.368406) (xy 92.623257 -229.390223)
			(xy 92.574373 -229.404383) (xy 92.523852 -229.410517) (xy 92.473 -229.408468) (xy 92.423136 -229.398288)
			(xy 92.37555 -229.380241) (xy 92.331476 -229.354795) (xy 92.292054 -229.322608) (xy 92.258306 -229.284514)
			(xy 92.231105 -229.2415) (xy 92.211157 -229.19468) (xy 92.198978 -229.145266) (xy 92.194883 -229.094538)
			(xy 91.876372 -229.094538) (xy 91.875877 -229.119145) (xy 91.867982 -229.167722) (xy 91.852398 -229.214403)
			(xy 91.829527 -229.25798) (xy 91.799962 -229.297324) (xy 91.764469 -229.331416) (xy 91.723966 -229.359372)
			(xy 91.679504 -229.38047) (xy 91.632233 -229.394162) (xy 91.583378 -229.400094) (xy 91.534203 -229.398113)
			(xy 91.485984 -229.388269) (xy 91.439968 -229.370817) (xy 91.397347 -229.34621) (xy 91.359226 -229.315085)
			(xy 91.326591 -229.278248) (xy 91.300288 -229.236652) (xy 91.280997 -229.191376) (xy 91.26922 -229.143592)
			(xy 91.26526 -229.094538) (xy 90.946732 -229.094538) (xy 90.94622 -229.119984) (xy 90.938056 -229.170218)
			(xy 90.92194 -229.218492) (xy 90.898289 -229.263555) (xy 90.867716 -229.304241) (xy 90.831012 -229.339496)
			(xy 90.789128 -229.368406) (xy 90.743149 -229.390223) (xy 90.694265 -229.404383) (xy 90.643744 -229.410517)
			(xy 90.592892 -229.408468) (xy 90.543028 -229.398288) (xy 90.495442 -229.380241) (xy 90.451368 -229.354795)
			(xy 90.411946 -229.322608) (xy 90.378198 -229.284514) (xy 90.350997 -229.2415) (xy 90.331049 -229.19468)
			(xy 90.31887 -229.145266) (xy 90.314775 -229.094538) (xy 89.996264 -229.094538) (xy 89.995769 -229.119145)
			(xy 89.987874 -229.167722) (xy 89.97229 -229.214403) (xy 89.949419 -229.25798) (xy 89.919854 -229.297324)
			(xy 89.884361 -229.331416) (xy 89.843858 -229.359372) (xy 89.799396 -229.38047) (xy 89.752125 -229.394162)
			(xy 89.70327 -229.400094) (xy 89.654095 -229.398113) (xy 89.605876 -229.388269) (xy 89.55986 -229.370817)
			(xy 89.517239 -229.34621) (xy 89.479118 -229.315085) (xy 89.446483 -229.278248) (xy 89.42018 -229.236652)
			(xy 89.400889 -229.191376) (xy 89.389112 -229.143592) (xy 89.385152 -229.094538) (xy 89.056464 -229.094538)
			(xy 89.055969 -229.119145) (xy 89.048074 -229.167722) (xy 89.03249 -229.214403) (xy 89.009619 -229.25798)
			(xy 88.980054 -229.297324) (xy 88.944561 -229.331416) (xy 88.904058 -229.359372) (xy 88.859596 -229.38047)
			(xy 88.812325 -229.394162) (xy 88.76347 -229.400094) (xy 88.714295 -229.398113) (xy 88.666076 -229.388269)
			(xy 88.62006 -229.370817) (xy 88.577439 -229.34621) (xy 88.539318 -229.315085) (xy 88.506683 -229.278248)
			(xy 88.48038 -229.236652) (xy 88.461089 -229.191376) (xy 88.449312 -229.143592) (xy 88.445352 -229.094538)
			(xy 88.11641 -229.094538) (xy 88.115915 -229.119145) (xy 88.10802 -229.167722) (xy 88.092436 -229.214403)
			(xy 88.069565 -229.25798) (xy 88.04 -229.297324) (xy 88.004507 -229.331416) (xy 87.964004 -229.359372)
			(xy 87.919542 -229.38047) (xy 87.872271 -229.394162) (xy 87.823416 -229.400094) (xy 87.774241 -229.398113)
			(xy 87.726022 -229.388269) (xy 87.680006 -229.370817) (xy 87.637385 -229.34621) (xy 87.599264 -229.315085)
			(xy 87.566629 -229.278248) (xy 87.540326 -229.236652) (xy 87.521035 -229.191376) (xy 87.509258 -229.143592)
			(xy 87.505298 -229.094538) (xy 87.176356 -229.094538) (xy 87.175861 -229.119145) (xy 87.167966 -229.167722)
			(xy 87.152382 -229.214403) (xy 87.129511 -229.25798) (xy 87.099946 -229.297324) (xy 87.064453 -229.331416)
			(xy 87.02395 -229.359372) (xy 86.979488 -229.38047) (xy 86.932217 -229.394162) (xy 86.883362 -229.400094)
			(xy 86.834187 -229.398113) (xy 86.785968 -229.388269) (xy 86.739952 -229.370817) (xy 86.697331 -229.34621)
			(xy 86.65921 -229.315085) (xy 86.626575 -229.278248) (xy 86.600272 -229.236652) (xy 86.580981 -229.191376)
			(xy 86.569204 -229.143592) (xy 86.565244 -229.094538) (xy 86.236302 -229.094538) (xy 86.235807 -229.119145)
			(xy 86.227912 -229.167722) (xy 86.212328 -229.214403) (xy 86.189457 -229.25798) (xy 86.159892 -229.297324)
			(xy 86.124399 -229.331416) (xy 86.083896 -229.359372) (xy 86.039434 -229.38047) (xy 85.992163 -229.394162)
			(xy 85.943308 -229.400094) (xy 85.894133 -229.398113) (xy 85.845914 -229.388269) (xy 85.799898 -229.370817)
			(xy 85.757277 -229.34621) (xy 85.719156 -229.315085) (xy 85.686521 -229.278248) (xy 85.660218 -229.236652)
			(xy 85.640927 -229.191376) (xy 85.62915 -229.143592) (xy 85.62519 -229.094538) (xy 85.296248 -229.094538)
			(xy 85.295753 -229.119145) (xy 85.287858 -229.167722) (xy 85.272274 -229.214403) (xy 85.249403 -229.25798)
			(xy 85.219838 -229.297324) (xy 85.184345 -229.331416) (xy 85.143842 -229.359372) (xy 85.09938 -229.38047)
			(xy 85.052109 -229.394162) (xy 85.003254 -229.400094) (xy 84.954079 -229.398113) (xy 84.90586 -229.388269)
			(xy 84.859844 -229.370817) (xy 84.817223 -229.34621) (xy 84.779102 -229.315085) (xy 84.746467 -229.278248)
			(xy 84.720164 -229.236652) (xy 84.700873 -229.191376) (xy 84.689096 -229.143592) (xy 84.685136 -229.094538)
			(xy 84.356448 -229.094538) (xy 84.355953 -229.119145) (xy 84.348058 -229.167722) (xy 84.332474 -229.214403)
			(xy 84.309603 -229.25798) (xy 84.280038 -229.297324) (xy 84.244545 -229.331416) (xy 84.204042 -229.359372)
			(xy 84.15958 -229.38047) (xy 84.112309 -229.394162) (xy 84.063454 -229.400094) (xy 84.014279 -229.398113)
			(xy 83.96606 -229.388269) (xy 83.920044 -229.370817) (xy 83.877423 -229.34621) (xy 83.839302 -229.315085)
			(xy 83.806667 -229.278248) (xy 83.780364 -229.236652) (xy 83.761073 -229.191376) (xy 83.749296 -229.143592)
			(xy 83.745336 -229.094538) (xy 83.49488 -229.094538) (xy 83.49488 -229.451408) (xy 83.494971 -229.455959)
			(xy 83.496633 -229.464908) (xy 83.498182 -229.469188) (xy 83.501738 -229.478586) (xy 83.537298 -229.517956)
			(xy 83.552792 -229.535228) (xy 83.559904 -229.541578) (xy 83.561936 -229.542848) (xy 83.567778 -229.546404)
			(xy 83.576414 -229.550468) (xy 83.585558 -229.551484) (xy 83.585812 -229.551484) (xy 83.609411 -229.554221)
			(xy 83.655416 -229.566061) (xy 83.699034 -229.584881) (xy 83.739212 -229.610227) (xy 83.774982 -229.641487)
			(xy 83.80548 -229.677909) (xy 83.829972 -229.718614) (xy 83.839304 -229.74046) (xy 83.84286 -229.747064)
			(xy 83.843114 -229.747572) (xy 83.856643 -229.771453) (xy 83.875895 -229.822846) (xy 83.88567 -229.876849)
			(xy 83.886294 -229.90429) (xy 84.215236 -229.90429) (xy 84.219196 -229.855236) (xy 84.230973 -229.807452)
			(xy 84.250264 -229.762176) (xy 84.276567 -229.72058) (xy 84.309202 -229.683743) (xy 84.347323 -229.652618)
			(xy 84.389944 -229.628011) (xy 84.43596 -229.610559) (xy 84.484179 -229.600715) (xy 84.533354 -229.598734)
			(xy 84.582209 -229.604666) (xy 84.62948 -229.618358) (xy 84.673942 -229.639456) (xy 84.714445 -229.667412)
			(xy 84.749938 -229.701504) (xy 84.779503 -229.740848) (xy 84.802374 -229.784425) (xy 84.817958 -229.831106)
			(xy 84.825853 -229.879683) (xy 84.826348 -229.90429) (xy 85.15529 -229.90429) (xy 85.15925 -229.855236)
			(xy 85.171027 -229.807452) (xy 85.190318 -229.762176) (xy 85.216621 -229.72058) (xy 85.249256 -229.683743)
			(xy 85.287377 -229.652618) (xy 85.329998 -229.628011) (xy 85.376014 -229.610559) (xy 85.424233 -229.600715)
			(xy 85.473408 -229.598734) (xy 85.522263 -229.604666) (xy 85.569534 -229.618358) (xy 85.613996 -229.639456)
			(xy 85.654499 -229.667412) (xy 85.689992 -229.701504) (xy 85.719557 -229.740848) (xy 85.742428 -229.784425)
			(xy 85.758012 -229.831106) (xy 85.765907 -229.879683) (xy 85.766402 -229.90429) (xy 87.035144 -229.90429)
			(xy 87.039104 -229.855236) (xy 87.050881 -229.807452) (xy 87.070172 -229.762176) (xy 87.096475 -229.72058)
			(xy 87.12911 -229.683743) (xy 87.167231 -229.652618) (xy 87.209852 -229.628011) (xy 87.255868 -229.610559)
			(xy 87.304087 -229.600715) (xy 87.353262 -229.598734) (xy 87.402117 -229.604666) (xy 87.449388 -229.618358)
			(xy 87.49385 -229.639456) (xy 87.534353 -229.667412) (xy 87.569846 -229.701504) (xy 87.599411 -229.740848)
			(xy 87.622282 -229.784425) (xy 87.637866 -229.831106) (xy 87.645761 -229.879683) (xy 87.646256 -229.90429)
			(xy 87.975198 -229.90429) (xy 87.979158 -229.855236) (xy 87.990935 -229.807452) (xy 88.010226 -229.762176)
			(xy 88.036529 -229.72058) (xy 88.069164 -229.683743) (xy 88.107285 -229.652618) (xy 88.149906 -229.628011)
			(xy 88.195922 -229.610559) (xy 88.244141 -229.600715) (xy 88.293316 -229.598734) (xy 88.342171 -229.604666)
			(xy 88.389442 -229.618358) (xy 88.433904 -229.639456) (xy 88.474407 -229.667412) (xy 88.5099 -229.701504)
			(xy 88.539465 -229.740848) (xy 88.562336 -229.784425) (xy 88.57792 -229.831106) (xy 88.585815 -229.879683)
			(xy 88.58631 -229.90429) (xy 88.915252 -229.90429) (xy 88.919212 -229.855236) (xy 88.930989 -229.807452)
			(xy 88.95028 -229.762176) (xy 88.976583 -229.72058) (xy 89.009218 -229.683743) (xy 89.047339 -229.652618)
			(xy 89.08996 -229.628011) (xy 89.135976 -229.610559) (xy 89.184195 -229.600715) (xy 89.23337 -229.598734)
			(xy 89.282225 -229.604666) (xy 89.329496 -229.618358) (xy 89.373958 -229.639456) (xy 89.414461 -229.667412)
			(xy 89.449954 -229.701504) (xy 89.479519 -229.740848) (xy 89.50239 -229.784425) (xy 89.517974 -229.831106)
			(xy 89.525869 -229.879683) (xy 89.526364 -229.90429) (xy 89.855306 -229.90429) (xy 89.859266 -229.855236)
			(xy 89.871043 -229.807452) (xy 89.890334 -229.762176) (xy 89.916637 -229.72058) (xy 89.949272 -229.683743)
			(xy 89.987393 -229.652618) (xy 90.030014 -229.628011) (xy 90.07603 -229.610559) (xy 90.124249 -229.600715)
			(xy 90.173424 -229.598734) (xy 90.222279 -229.604666) (xy 90.26955 -229.618358) (xy 90.314012 -229.639456)
			(xy 90.354515 -229.667412) (xy 90.390008 -229.701504) (xy 90.419573 -229.740848) (xy 90.442444 -229.784425)
			(xy 90.458028 -229.831106) (xy 90.465923 -229.879683) (xy 90.466418 -229.90429) (xy 90.784675 -229.90429)
			(xy 90.78877 -229.853562) (xy 90.800949 -229.804148) (xy 90.820897 -229.757328) (xy 90.848098 -229.714314)
			(xy 90.881846 -229.67622) (xy 90.921268 -229.644033) (xy 90.965342 -229.618587) (xy 91.012928 -229.60054)
			(xy 91.062792 -229.59036) (xy 91.113644 -229.588311) (xy 91.164165 -229.594445) (xy 91.213049 -229.608605)
			(xy 91.259028 -229.630422) (xy 91.300912 -229.659332) (xy 91.337616 -229.694587) (xy 91.368189 -229.735273)
			(xy 91.39184 -229.780336) (xy 91.407956 -229.82861) (xy 91.41612 -229.878844) (xy 91.416632 -229.90429)
			(xy 91.724729 -229.90429) (xy 91.728824 -229.853562) (xy 91.741003 -229.804148) (xy 91.760951 -229.757328)
			(xy 91.788152 -229.714314) (xy 91.8219 -229.67622) (xy 91.861322 -229.644033) (xy 91.905396 -229.618587)
			(xy 91.952982 -229.60054) (xy 92.002846 -229.59036) (xy 92.053698 -229.588311) (xy 92.104219 -229.594445)
			(xy 92.153103 -229.608605) (xy 92.199082 -229.630422) (xy 92.240966 -229.659332) (xy 92.27767 -229.694587)
			(xy 92.308243 -229.735273) (xy 92.331894 -229.780336) (xy 92.34801 -229.82861) (xy 92.356174 -229.878844)
			(xy 92.356686 -229.90429) (xy 93.604837 -229.90429) (xy 93.608932 -229.853562) (xy 93.621111 -229.804148)
			(xy 93.641059 -229.757328) (xy 93.66826 -229.714314) (xy 93.702008 -229.67622) (xy 93.74143 -229.644033)
			(xy 93.785504 -229.618587) (xy 93.83309 -229.60054) (xy 93.882954 -229.59036) (xy 93.933806 -229.588311)
			(xy 93.984327 -229.594445) (xy 94.033211 -229.608605) (xy 94.07919 -229.630422) (xy 94.121074 -229.659332)
			(xy 94.157778 -229.694587) (xy 94.188351 -229.735273) (xy 94.212002 -229.780336) (xy 94.228118 -229.82861)
			(xy 94.236282 -229.878844) (xy 94.236794 -229.90429) (xy 94.555322 -229.90429) (xy 94.559282 -229.855236)
			(xy 94.571059 -229.807452) (xy 94.59035 -229.762176) (xy 94.616653 -229.72058) (xy 94.649288 -229.683743)
			(xy 94.687409 -229.652618) (xy 94.73003 -229.628011) (xy 94.776046 -229.610559) (xy 94.824265 -229.600715)
			(xy 94.87344 -229.598734) (xy 94.922295 -229.604666) (xy 94.969566 -229.618358) (xy 95.014028 -229.639456)
			(xy 95.054531 -229.667412) (xy 95.090024 -229.701504) (xy 95.119589 -229.740848) (xy 95.14246 -229.784425)
			(xy 95.158044 -229.831106) (xy 95.165939 -229.879683) (xy 95.166434 -229.90429) (xy 95.484691 -229.90429)
			(xy 95.488786 -229.853562) (xy 95.500965 -229.804148) (xy 95.520913 -229.757328) (xy 95.548114 -229.714314)
			(xy 95.581862 -229.67622) (xy 95.621284 -229.644033) (xy 95.665358 -229.618587) (xy 95.712944 -229.60054)
			(xy 95.762808 -229.59036) (xy 95.81366 -229.588311) (xy 95.864181 -229.594445) (xy 95.913065 -229.608605)
			(xy 95.959044 -229.630422) (xy 96.000928 -229.659332) (xy 96.037632 -229.694587) (xy 96.068205 -229.735273)
			(xy 96.091856 -229.780336) (xy 96.107972 -229.82861) (xy 96.116136 -229.878844) (xy 96.116648 -229.90429)
			(xy 96.116136 -229.929736) (xy 96.107972 -229.97997) (xy 96.091856 -230.028244) (xy 96.068205 -230.073307)
			(xy 96.037632 -230.113993) (xy 96.000928 -230.149248) (xy 95.959044 -230.178158) (xy 95.913065 -230.199975)
			(xy 95.864181 -230.214135) (xy 95.81366 -230.220269) (xy 95.762808 -230.21822) (xy 95.712944 -230.20804)
			(xy 95.665358 -230.189993) (xy 95.621284 -230.164547) (xy 95.581862 -230.13236) (xy 95.548114 -230.094266)
			(xy 95.520913 -230.051252) (xy 95.500965 -230.004432) (xy 95.488786 -229.955018) (xy 95.484691 -229.90429)
			(xy 95.166434 -229.90429) (xy 95.165939 -229.928897) (xy 95.158044 -229.977474) (xy 95.14246 -230.024155)
			(xy 95.119589 -230.067732) (xy 95.090024 -230.107076) (xy 95.054531 -230.141168) (xy 95.014028 -230.169124)
			(xy 94.969566 -230.190222) (xy 94.922295 -230.203914) (xy 94.87344 -230.209846) (xy 94.824265 -230.207865)
			(xy 94.776046 -230.198021) (xy 94.73003 -230.180569) (xy 94.687409 -230.155962) (xy 94.649288 -230.124837)
			(xy 94.616653 -230.088) (xy 94.59035 -230.046404) (xy 94.571059 -230.001128) (xy 94.559282 -229.953344)
			(xy 94.555322 -229.90429) (xy 94.236794 -229.90429) (xy 94.236282 -229.929736) (xy 94.228118 -229.97997)
			(xy 94.212002 -230.028244) (xy 94.188351 -230.073307) (xy 94.157778 -230.113993) (xy 94.121074 -230.149248)
			(xy 94.07919 -230.178158) (xy 94.033211 -230.199975) (xy 93.984327 -230.214135) (xy 93.933806 -230.220269)
			(xy 93.882954 -230.21822) (xy 93.83309 -230.20804) (xy 93.785504 -230.189993) (xy 93.74143 -230.164547)
			(xy 93.702008 -230.13236) (xy 93.66826 -230.094266) (xy 93.641059 -230.051252) (xy 93.621111 -230.004432)
			(xy 93.608932 -229.955018) (xy 93.604837 -229.90429) (xy 92.356686 -229.90429) (xy 92.356174 -229.929736)
			(xy 92.34801 -229.97997) (xy 92.331894 -230.028244) (xy 92.308243 -230.073307) (xy 92.27767 -230.113993)
			(xy 92.240966 -230.149248) (xy 92.199082 -230.178158) (xy 92.153103 -230.199975) (xy 92.104219 -230.214135)
			(xy 92.053698 -230.220269) (xy 92.002846 -230.21822) (xy 91.952982 -230.20804) (xy 91.905396 -230.189993)
			(xy 91.861322 -230.164547) (xy 91.8219 -230.13236) (xy 91.788152 -230.094266) (xy 91.760951 -230.051252)
			(xy 91.741003 -230.004432) (xy 91.728824 -229.955018) (xy 91.724729 -229.90429) (xy 91.416632 -229.90429)
			(xy 91.41612 -229.929736) (xy 91.407956 -229.97997) (xy 91.39184 -230.028244) (xy 91.368189 -230.073307)
			(xy 91.337616 -230.113993) (xy 91.300912 -230.149248) (xy 91.259028 -230.178158) (xy 91.213049 -230.199975)
			(xy 91.164165 -230.214135) (xy 91.113644 -230.220269) (xy 91.062792 -230.21822) (xy 91.012928 -230.20804)
			(xy 90.965342 -230.189993) (xy 90.921268 -230.164547) (xy 90.881846 -230.13236) (xy 90.848098 -230.094266)
			(xy 90.820897 -230.051252) (xy 90.800949 -230.004432) (xy 90.78877 -229.955018) (xy 90.784675 -229.90429)
			(xy 90.466418 -229.90429) (xy 90.465923 -229.928897) (xy 90.458028 -229.977474) (xy 90.442444 -230.024155)
			(xy 90.419573 -230.067732) (xy 90.390008 -230.107076) (xy 90.354515 -230.141168) (xy 90.314012 -230.169124)
			(xy 90.26955 -230.190222) (xy 90.222279 -230.203914) (xy 90.173424 -230.209846) (xy 90.124249 -230.207865)
			(xy 90.07603 -230.198021) (xy 90.030014 -230.180569) (xy 89.987393 -230.155962) (xy 89.949272 -230.124837)
			(xy 89.916637 -230.088) (xy 89.890334 -230.046404) (xy 89.871043 -230.001128) (xy 89.859266 -229.953344)
			(xy 89.855306 -229.90429) (xy 89.526364 -229.90429) (xy 89.525869 -229.928897) (xy 89.517974 -229.977474)
			(xy 89.50239 -230.024155) (xy 89.479519 -230.067732) (xy 89.449954 -230.107076) (xy 89.414461 -230.141168)
			(xy 89.373958 -230.169124) (xy 89.329496 -230.190222) (xy 89.282225 -230.203914) (xy 89.23337 -230.209846)
			(xy 89.184195 -230.207865) (xy 89.135976 -230.198021) (xy 89.08996 -230.180569) (xy 89.047339 -230.155962)
			(xy 89.009218 -230.124837) (xy 88.976583 -230.088) (xy 88.95028 -230.046404) (xy 88.930989 -230.001128)
			(xy 88.919212 -229.953344) (xy 88.915252 -229.90429) (xy 88.58631 -229.90429) (xy 88.585815 -229.928897)
			(xy 88.57792 -229.977474) (xy 88.562336 -230.024155) (xy 88.539465 -230.067732) (xy 88.5099 -230.107076)
			(xy 88.474407 -230.141168) (xy 88.433904 -230.169124) (xy 88.389442 -230.190222) (xy 88.342171 -230.203914)
			(xy 88.293316 -230.209846) (xy 88.244141 -230.207865) (xy 88.195922 -230.198021) (xy 88.149906 -230.180569)
			(xy 88.107285 -230.155962) (xy 88.069164 -230.124837) (xy 88.036529 -230.088) (xy 88.010226 -230.046404)
			(xy 87.990935 -230.001128) (xy 87.979158 -229.953344) (xy 87.975198 -229.90429) (xy 87.646256 -229.90429)
			(xy 87.645761 -229.928897) (xy 87.637866 -229.977474) (xy 87.622282 -230.024155) (xy 87.599411 -230.067732)
			(xy 87.569846 -230.107076) (xy 87.534353 -230.141168) (xy 87.49385 -230.169124) (xy 87.449388 -230.190222)
			(xy 87.402117 -230.203914) (xy 87.353262 -230.209846) (xy 87.304087 -230.207865) (xy 87.255868 -230.198021)
			(xy 87.209852 -230.180569) (xy 87.167231 -230.155962) (xy 87.12911 -230.124837) (xy 87.096475 -230.088)
			(xy 87.070172 -230.046404) (xy 87.050881 -230.001128) (xy 87.039104 -229.953344) (xy 87.035144 -229.90429)
			(xy 85.766402 -229.90429) (xy 85.765907 -229.928897) (xy 85.758012 -229.977474) (xy 85.742428 -230.024155)
			(xy 85.719557 -230.067732) (xy 85.689992 -230.107076) (xy 85.654499 -230.141168) (xy 85.613996 -230.169124)
			(xy 85.569534 -230.190222) (xy 85.522263 -230.203914) (xy 85.473408 -230.209846) (xy 85.424233 -230.207865)
			(xy 85.376014 -230.198021) (xy 85.329998 -230.180569) (xy 85.287377 -230.155962) (xy 85.249256 -230.124837)
			(xy 85.216621 -230.088) (xy 85.190318 -230.046404) (xy 85.171027 -230.001128) (xy 85.15925 -229.953344)
			(xy 85.15529 -229.90429) (xy 84.826348 -229.90429) (xy 84.825853 -229.928897) (xy 84.817958 -229.977474)
			(xy 84.802374 -230.024155) (xy 84.779503 -230.067732) (xy 84.749938 -230.107076) (xy 84.714445 -230.141168)
			(xy 84.673942 -230.169124) (xy 84.62948 -230.190222) (xy 84.582209 -230.203914) (xy 84.533354 -230.209846)
			(xy 84.484179 -230.207865) (xy 84.43596 -230.198021) (xy 84.389944 -230.180569) (xy 84.347323 -230.155962)
			(xy 84.309202 -230.124837) (xy 84.276567 -230.088) (xy 84.250264 -230.046404) (xy 84.230973 -230.001128)
			(xy 84.219196 -229.953344) (xy 84.215236 -229.90429) (xy 83.886294 -229.90429) (xy 83.885849 -229.928283)
			(xy 83.878343 -229.975679) (xy 83.863515 -230.021317) (xy 83.84173 -230.064074) (xy 83.813524 -230.102896)
			(xy 83.779593 -230.136827) (xy 83.74077 -230.165032) (xy 83.698014 -230.186817) (xy 83.652375 -230.201644)
			(xy 83.604979 -230.209149) (xy 83.580986 -230.209598) (xy 83.551268 -230.208074) (xy 83.551014 -230.208074)
			(xy 83.539076 -230.207058) (xy 83.528408 -230.211122) (xy 83.522867 -230.21343) (xy 83.512978 -230.220227)
			(xy 83.50885 -230.224584) (xy 83.508088 -230.225346) (xy 83.502209 -230.232328) (xy 83.495419 -230.249256)
			(xy 83.49488 -230.258366) (xy 83.49488 -230.71455) (xy 83.745336 -230.71455) (xy 83.749296 -230.665496)
			(xy 83.761073 -230.617712) (xy 83.780364 -230.572436) (xy 83.806667 -230.53084) (xy 83.839302 -230.494003)
			(xy 83.877423 -230.462878) (xy 83.920044 -230.438271) (xy 83.96606 -230.420819) (xy 84.014279 -230.410975)
			(xy 84.063454 -230.408994) (xy 84.112309 -230.414926) (xy 84.15958 -230.428618) (xy 84.204042 -230.449716)
			(xy 84.244545 -230.477672) (xy 84.280038 -230.511764) (xy 84.309603 -230.551108) (xy 84.332474 -230.594685)
			(xy 84.348058 -230.641366) (xy 84.355953 -230.689943) (xy 84.356443 -230.714296) (xy 84.685136 -230.714296)
			(xy 84.689096 -230.665242) (xy 84.700873 -230.617458) (xy 84.720164 -230.572182) (xy 84.746467 -230.530586)
			(xy 84.779102 -230.493749) (xy 84.817223 -230.462624) (xy 84.859844 -230.438017) (xy 84.90586 -230.420565)
			(xy 84.954079 -230.410721) (xy 85.003254 -230.40874) (xy 85.052109 -230.414672) (xy 85.09938 -230.428364)
			(xy 85.143842 -230.449462) (xy 85.184345 -230.477418) (xy 85.219838 -230.51151) (xy 85.249403 -230.550854)
			(xy 85.272274 -230.594431) (xy 85.287858 -230.641112) (xy 85.295753 -230.689689) (xy 85.296248 -230.714296)
			(xy 85.296243 -230.71455) (xy 85.62519 -230.71455) (xy 85.62915 -230.665496) (xy 85.640927 -230.617712)
			(xy 85.660218 -230.572436) (xy 85.686521 -230.53084) (xy 85.719156 -230.494003) (xy 85.757277 -230.462878)
			(xy 85.799898 -230.438271) (xy 85.845914 -230.420819) (xy 85.894133 -230.410975) (xy 85.943308 -230.408994)
			(xy 85.992163 -230.414926) (xy 86.039434 -230.428618) (xy 86.083896 -230.449716) (xy 86.124399 -230.477672)
			(xy 86.159892 -230.511764) (xy 86.189457 -230.551108) (xy 86.212328 -230.594685) (xy 86.227912 -230.641366)
			(xy 86.235807 -230.689943) (xy 86.236302 -230.71455) (xy 86.565244 -230.71455) (xy 86.569204 -230.665496)
			(xy 86.580981 -230.617712) (xy 86.600272 -230.572436) (xy 86.626575 -230.53084) (xy 86.65921 -230.494003)
			(xy 86.697331 -230.462878) (xy 86.739952 -230.438271) (xy 86.785968 -230.420819) (xy 86.834187 -230.410975)
			(xy 86.883362 -230.408994) (xy 86.932217 -230.414926) (xy 86.979488 -230.428618) (xy 87.02395 -230.449716)
			(xy 87.064453 -230.477672) (xy 87.099946 -230.511764) (xy 87.129511 -230.551108) (xy 87.152382 -230.594685)
			(xy 87.167966 -230.641366) (xy 87.175861 -230.689943) (xy 87.176356 -230.71455) (xy 87.505298 -230.71455)
			(xy 87.509258 -230.665496) (xy 87.521035 -230.617712) (xy 87.540326 -230.572436) (xy 87.566629 -230.53084)
			(xy 87.599264 -230.494003) (xy 87.637385 -230.462878) (xy 87.680006 -230.438271) (xy 87.726022 -230.420819)
			(xy 87.774241 -230.410975) (xy 87.823416 -230.408994) (xy 87.872271 -230.414926) (xy 87.919542 -230.428618)
			(xy 87.964004 -230.449716) (xy 88.004507 -230.477672) (xy 88.04 -230.511764) (xy 88.069565 -230.551108)
			(xy 88.092436 -230.594685) (xy 88.10802 -230.641366) (xy 88.115915 -230.689943) (xy 88.11641 -230.71455)
			(xy 88.445352 -230.71455) (xy 88.449312 -230.665496) (xy 88.461089 -230.617712) (xy 88.48038 -230.572436)
			(xy 88.506683 -230.53084) (xy 88.539318 -230.494003) (xy 88.577439 -230.462878) (xy 88.62006 -230.438271)
			(xy 88.666076 -230.420819) (xy 88.714295 -230.410975) (xy 88.76347 -230.408994) (xy 88.812325 -230.414926)
			(xy 88.859596 -230.428618) (xy 88.904058 -230.449716) (xy 88.944561 -230.477672) (xy 88.980054 -230.511764)
			(xy 89.009619 -230.551108) (xy 89.03249 -230.594685) (xy 89.048074 -230.641366) (xy 89.055969 -230.689943)
			(xy 89.056459 -230.714296) (xy 89.385152 -230.714296) (xy 89.389112 -230.665242) (xy 89.400889 -230.617458)
			(xy 89.42018 -230.572182) (xy 89.446483 -230.530586) (xy 89.479118 -230.493749) (xy 89.517239 -230.462624)
			(xy 89.55986 -230.438017) (xy 89.605876 -230.420565) (xy 89.654095 -230.410721) (xy 89.70327 -230.40874)
			(xy 89.752125 -230.414672) (xy 89.799396 -230.428364) (xy 89.843858 -230.449462) (xy 89.884361 -230.477418)
			(xy 89.919854 -230.51151) (xy 89.949419 -230.550854) (xy 89.97229 -230.594431) (xy 89.987874 -230.641112)
			(xy 89.995769 -230.689689) (xy 89.996264 -230.714296) (xy 89.996259 -230.71455) (xy 90.314775 -230.71455)
			(xy 90.31887 -230.663822) (xy 90.331049 -230.614408) (xy 90.350997 -230.567588) (xy 90.378198 -230.524574)
			(xy 90.411946 -230.48648) (xy 90.451368 -230.454293) (xy 90.495442 -230.428847) (xy 90.543028 -230.4108)
			(xy 90.592892 -230.40062) (xy 90.643744 -230.398571) (xy 90.694265 -230.404705) (xy 90.743149 -230.418865)
			(xy 90.789128 -230.440682) (xy 90.831012 -230.469592) (xy 90.867716 -230.504847) (xy 90.898289 -230.545533)
			(xy 90.92194 -230.590596) (xy 90.938056 -230.63887) (xy 90.94622 -230.689104) (xy 90.946732 -230.71455)
			(xy 91.26526 -230.71455) (xy 91.26922 -230.665496) (xy 91.280997 -230.617712) (xy 91.300288 -230.572436)
			(xy 91.326591 -230.53084) (xy 91.359226 -230.494003) (xy 91.397347 -230.462878) (xy 91.439968 -230.438271)
			(xy 91.485984 -230.420819) (xy 91.534203 -230.410975) (xy 91.583378 -230.408994) (xy 91.632233 -230.414926)
			(xy 91.679504 -230.428618) (xy 91.723966 -230.449716) (xy 91.764469 -230.477672) (xy 91.799962 -230.511764)
			(xy 91.829527 -230.551108) (xy 91.852398 -230.594685) (xy 91.867982 -230.641366) (xy 91.875877 -230.689943)
			(xy 91.876372 -230.71455) (xy 92.194883 -230.71455) (xy 92.198978 -230.663822) (xy 92.211157 -230.614408)
			(xy 92.231105 -230.567588) (xy 92.258306 -230.524574) (xy 92.292054 -230.48648) (xy 92.331476 -230.454293)
			(xy 92.37555 -230.428847) (xy 92.423136 -230.4108) (xy 92.473 -230.40062) (xy 92.523852 -230.398571)
			(xy 92.574373 -230.404705) (xy 92.623257 -230.418865) (xy 92.669236 -230.440682) (xy 92.71112 -230.469592)
			(xy 92.747824 -230.504847) (xy 92.778397 -230.545533) (xy 92.802048 -230.590596) (xy 92.818164 -230.63887)
			(xy 92.826328 -230.689104) (xy 92.826835 -230.714296) (xy 93.145114 -230.714296) (xy 93.149074 -230.665242)
			(xy 93.160851 -230.617458) (xy 93.180142 -230.572182) (xy 93.206445 -230.530586) (xy 93.23908 -230.493749)
			(xy 93.277201 -230.462624) (xy 93.319822 -230.438017) (xy 93.365838 -230.420565) (xy 93.414057 -230.410721)
			(xy 93.463232 -230.40874) (xy 93.512087 -230.414672) (xy 93.559358 -230.428364) (xy 93.60382 -230.449462)
			(xy 93.644323 -230.477418) (xy 93.679816 -230.51151) (xy 93.709381 -230.550854) (xy 93.732252 -230.594431)
			(xy 93.747836 -230.641112) (xy 93.755731 -230.689689) (xy 93.756226 -230.714296) (xy 93.756221 -230.71455)
			(xy 94.074737 -230.71455) (xy 94.078832 -230.663822) (xy 94.091011 -230.614408) (xy 94.110959 -230.567588)
			(xy 94.13816 -230.524574) (xy 94.171908 -230.48648) (xy 94.21133 -230.454293) (xy 94.255404 -230.428847)
			(xy 94.30299 -230.4108) (xy 94.352854 -230.40062) (xy 94.403706 -230.398571) (xy 94.454227 -230.404705)
			(xy 94.503111 -230.418865) (xy 94.54909 -230.440682) (xy 94.590974 -230.469592) (xy 94.627678 -230.504847)
			(xy 94.658251 -230.545533) (xy 94.681902 -230.590596) (xy 94.698018 -230.63887) (xy 94.706182 -230.689104)
			(xy 94.706694 -230.71455) (xy 95.014791 -230.71455) (xy 95.018886 -230.663822) (xy 95.031065 -230.614408)
			(xy 95.051013 -230.567588) (xy 95.078214 -230.524574) (xy 95.111962 -230.48648) (xy 95.151384 -230.454293)
			(xy 95.195458 -230.428847) (xy 95.243044 -230.4108) (xy 95.292908 -230.40062) (xy 95.34376 -230.398571)
			(xy 95.394281 -230.404705) (xy 95.443165 -230.418865) (xy 95.489144 -230.440682) (xy 95.531028 -230.469592)
			(xy 95.567732 -230.504847) (xy 95.598305 -230.545533) (xy 95.621956 -230.590596) (xy 95.638072 -230.63887)
			(xy 95.646236 -230.689104) (xy 95.646748 -230.71455) (xy 95.965276 -230.71455) (xy 95.969236 -230.665496)
			(xy 95.981013 -230.617712) (xy 96.000304 -230.572436) (xy 96.026607 -230.53084) (xy 96.059242 -230.494003)
			(xy 96.097363 -230.462878) (xy 96.139984 -230.438271) (xy 96.186 -230.420819) (xy 96.234219 -230.410975)
			(xy 96.283394 -230.408994) (xy 96.332249 -230.414926) (xy 96.37952 -230.428618) (xy 96.423982 -230.449716)
			(xy 96.464485 -230.477672) (xy 96.499978 -230.511764) (xy 96.529543 -230.551108) (xy 96.552414 -230.594685)
			(xy 96.567998 -230.641366) (xy 96.575893 -230.689943) (xy 96.576388 -230.71455) (xy 96.575893 -230.739157)
			(xy 96.567998 -230.787734) (xy 96.552414 -230.834415) (xy 96.529543 -230.877992) (xy 96.499978 -230.917336)
			(xy 96.464485 -230.951428) (xy 96.423982 -230.979384) (xy 96.37952 -231.000482) (xy 96.332249 -231.014174)
			(xy 96.283394 -231.020106) (xy 96.234219 -231.018125) (xy 96.186 -231.008281) (xy 96.139984 -230.990829)
			(xy 96.097363 -230.966222) (xy 96.059242 -230.935097) (xy 96.026607 -230.89826) (xy 96.000304 -230.856664)
			(xy 95.981013 -230.811388) (xy 95.969236 -230.763604) (xy 95.965276 -230.71455) (xy 95.646748 -230.71455)
			(xy 95.646236 -230.739996) (xy 95.638072 -230.79023) (xy 95.621956 -230.838504) (xy 95.598305 -230.883567)
			(xy 95.567732 -230.924253) (xy 95.531028 -230.959508) (xy 95.489144 -230.988418) (xy 95.443165 -231.010235)
			(xy 95.394281 -231.024395) (xy 95.34376 -231.030529) (xy 95.292908 -231.02848) (xy 95.243044 -231.0183)
			(xy 95.195458 -231.000253) (xy 95.151384 -230.974807) (xy 95.111962 -230.94262) (xy 95.078214 -230.904526)
			(xy 95.051013 -230.861512) (xy 95.031065 -230.814692) (xy 95.018886 -230.765278) (xy 95.014791 -230.71455)
			(xy 94.706694 -230.71455) (xy 94.706182 -230.739996) (xy 94.698018 -230.79023) (xy 94.681902 -230.838504)
			(xy 94.658251 -230.883567) (xy 94.627678 -230.924253) (xy 94.590974 -230.959508) (xy 94.54909 -230.988418)
			(xy 94.503111 -231.010235) (xy 94.454227 -231.024395) (xy 94.403706 -231.030529) (xy 94.352854 -231.02848)
			(xy 94.30299 -231.0183) (xy 94.255404 -231.000253) (xy 94.21133 -230.974807) (xy 94.171908 -230.94262)
			(xy 94.13816 -230.904526) (xy 94.110959 -230.861512) (xy 94.091011 -230.814692) (xy 94.078832 -230.765278)
			(xy 94.074737 -230.71455) (xy 93.756221 -230.71455) (xy 93.755731 -230.738903) (xy 93.747836 -230.78748)
			(xy 93.732252 -230.834161) (xy 93.709381 -230.877738) (xy 93.679816 -230.917082) (xy 93.644323 -230.951174)
			(xy 93.60382 -230.97913) (xy 93.559358 -231.000228) (xy 93.512087 -231.01392) (xy 93.463232 -231.019852)
			(xy 93.414057 -231.017871) (xy 93.365838 -231.008027) (xy 93.319822 -230.990575) (xy 93.277201 -230.965968)
			(xy 93.23908 -230.934843) (xy 93.206445 -230.898006) (xy 93.180142 -230.85641) (xy 93.160851 -230.811134)
			(xy 93.149074 -230.76335) (xy 93.145114 -230.714296) (xy 92.826835 -230.714296) (xy 92.82684 -230.71455)
			(xy 92.826328 -230.739996) (xy 92.818164 -230.79023) (xy 92.802048 -230.838504) (xy 92.778397 -230.883567)
			(xy 92.747824 -230.924253) (xy 92.71112 -230.959508) (xy 92.669236 -230.988418) (xy 92.623257 -231.010235)
			(xy 92.574373 -231.024395) (xy 92.523852 -231.030529) (xy 92.473 -231.02848) (xy 92.423136 -231.0183)
			(xy 92.37555 -231.000253) (xy 92.331476 -230.974807) (xy 92.292054 -230.94262) (xy 92.258306 -230.904526)
			(xy 92.231105 -230.861512) (xy 92.211157 -230.814692) (xy 92.198978 -230.765278) (xy 92.194883 -230.71455)
			(xy 91.876372 -230.71455) (xy 91.875877 -230.739157) (xy 91.867982 -230.787734) (xy 91.852398 -230.834415)
			(xy 91.829527 -230.877992) (xy 91.799962 -230.917336) (xy 91.764469 -230.951428) (xy 91.723966 -230.979384)
			(xy 91.679504 -231.000482) (xy 91.632233 -231.014174) (xy 91.583378 -231.020106) (xy 91.534203 -231.018125)
			(xy 91.485984 -231.008281) (xy 91.439968 -230.990829) (xy 91.397347 -230.966222) (xy 91.359226 -230.935097)
			(xy 91.326591 -230.89826) (xy 91.300288 -230.856664) (xy 91.280997 -230.811388) (xy 91.26922 -230.763604)
			(xy 91.26526 -230.71455) (xy 90.946732 -230.71455) (xy 90.94622 -230.739996) (xy 90.938056 -230.79023)
			(xy 90.92194 -230.838504) (xy 90.898289 -230.883567) (xy 90.867716 -230.924253) (xy 90.831012 -230.959508)
			(xy 90.789128 -230.988418) (xy 90.743149 -231.010235) (xy 90.694265 -231.024395) (xy 90.643744 -231.030529)
			(xy 90.592892 -231.02848) (xy 90.543028 -231.0183) (xy 90.495442 -231.000253) (xy 90.451368 -230.974807)
			(xy 90.411946 -230.94262) (xy 90.378198 -230.904526) (xy 90.350997 -230.861512) (xy 90.331049 -230.814692)
			(xy 90.31887 -230.765278) (xy 90.314775 -230.71455) (xy 89.996259 -230.71455) (xy 89.995769 -230.738903)
			(xy 89.987874 -230.78748) (xy 89.97229 -230.834161) (xy 89.949419 -230.877738) (xy 89.919854 -230.917082)
			(xy 89.884361 -230.951174) (xy 89.843858 -230.97913) (xy 89.799396 -231.000228) (xy 89.752125 -231.01392)
			(xy 89.70327 -231.019852) (xy 89.654095 -231.017871) (xy 89.605876 -231.008027) (xy 89.55986 -230.990575)
			(xy 89.517239 -230.965968) (xy 89.479118 -230.934843) (xy 89.446483 -230.898006) (xy 89.42018 -230.85641)
			(xy 89.400889 -230.811134) (xy 89.389112 -230.76335) (xy 89.385152 -230.714296) (xy 89.056459 -230.714296)
			(xy 89.056464 -230.71455) (xy 89.055969 -230.739157) (xy 89.048074 -230.787734) (xy 89.03249 -230.834415)
			(xy 89.009619 -230.877992) (xy 88.980054 -230.917336) (xy 88.944561 -230.951428) (xy 88.904058 -230.979384)
			(xy 88.859596 -231.000482) (xy 88.812325 -231.014174) (xy 88.76347 -231.020106) (xy 88.714295 -231.018125)
			(xy 88.666076 -231.008281) (xy 88.62006 -230.990829) (xy 88.577439 -230.966222) (xy 88.539318 -230.935097)
			(xy 88.506683 -230.89826) (xy 88.48038 -230.856664) (xy 88.461089 -230.811388) (xy 88.449312 -230.763604)
			(xy 88.445352 -230.71455) (xy 88.11641 -230.71455) (xy 88.115915 -230.739157) (xy 88.10802 -230.787734)
			(xy 88.092436 -230.834415) (xy 88.069565 -230.877992) (xy 88.04 -230.917336) (xy 88.004507 -230.951428)
			(xy 87.964004 -230.979384) (xy 87.919542 -231.000482) (xy 87.872271 -231.014174) (xy 87.823416 -231.020106)
			(xy 87.774241 -231.018125) (xy 87.726022 -231.008281) (xy 87.680006 -230.990829) (xy 87.637385 -230.966222)
			(xy 87.599264 -230.935097) (xy 87.566629 -230.89826) (xy 87.540326 -230.856664) (xy 87.521035 -230.811388)
			(xy 87.509258 -230.763604) (xy 87.505298 -230.71455) (xy 87.176356 -230.71455) (xy 87.175861 -230.739157)
			(xy 87.167966 -230.787734) (xy 87.152382 -230.834415) (xy 87.129511 -230.877992) (xy 87.099946 -230.917336)
			(xy 87.064453 -230.951428) (xy 87.02395 -230.979384) (xy 86.979488 -231.000482) (xy 86.932217 -231.014174)
			(xy 86.883362 -231.020106) (xy 86.834187 -231.018125) (xy 86.785968 -231.008281) (xy 86.739952 -230.990829)
			(xy 86.697331 -230.966222) (xy 86.65921 -230.935097) (xy 86.626575 -230.89826) (xy 86.600272 -230.856664)
			(xy 86.580981 -230.811388) (xy 86.569204 -230.763604) (xy 86.565244 -230.71455) (xy 86.236302 -230.71455)
			(xy 86.235807 -230.739157) (xy 86.227912 -230.787734) (xy 86.212328 -230.834415) (xy 86.189457 -230.877992)
			(xy 86.159892 -230.917336) (xy 86.124399 -230.951428) (xy 86.083896 -230.979384) (xy 86.039434 -231.000482)
			(xy 85.992163 -231.014174) (xy 85.943308 -231.020106) (xy 85.894133 -231.018125) (xy 85.845914 -231.008281)
			(xy 85.799898 -230.990829) (xy 85.757277 -230.966222) (xy 85.719156 -230.935097) (xy 85.686521 -230.89826)
			(xy 85.660218 -230.856664) (xy 85.640927 -230.811388) (xy 85.62915 -230.763604) (xy 85.62519 -230.71455)
			(xy 85.296243 -230.71455) (xy 85.295753 -230.738903) (xy 85.287858 -230.78748) (xy 85.272274 -230.834161)
			(xy 85.249403 -230.877738) (xy 85.219838 -230.917082) (xy 85.184345 -230.951174) (xy 85.143842 -230.97913)
			(xy 85.09938 -231.000228) (xy 85.052109 -231.01392) (xy 85.003254 -231.019852) (xy 84.954079 -231.017871)
			(xy 84.90586 -231.008027) (xy 84.859844 -230.990575) (xy 84.817223 -230.965968) (xy 84.779102 -230.934843)
			(xy 84.746467 -230.898006) (xy 84.720164 -230.85641) (xy 84.700873 -230.811134) (xy 84.689096 -230.76335)
			(xy 84.685136 -230.714296) (xy 84.356443 -230.714296) (xy 84.356448 -230.71455) (xy 84.355953 -230.739157)
			(xy 84.348058 -230.787734) (xy 84.332474 -230.834415) (xy 84.309603 -230.877992) (xy 84.280038 -230.917336)
			(xy 84.244545 -230.951428) (xy 84.204042 -230.979384) (xy 84.15958 -231.000482) (xy 84.112309 -231.014174)
			(xy 84.063454 -231.020106) (xy 84.014279 -231.018125) (xy 83.96606 -231.008281) (xy 83.920044 -230.990829)
			(xy 83.877423 -230.966222) (xy 83.839302 -230.935097) (xy 83.806667 -230.89826) (xy 83.780364 -230.856664)
			(xy 83.761073 -230.811388) (xy 83.749296 -230.763604) (xy 83.745336 -230.71455) (xy 83.49488 -230.71455)
			(xy 83.49488 -231.07142) (xy 83.494972 -231.075971) (xy 83.496636 -231.084919) (xy 83.498182 -231.0892)
			(xy 83.501738 -231.098598) (xy 83.537298 -231.137968) (xy 83.552792 -231.15524) (xy 83.559904 -231.16159)
			(xy 83.561936 -231.16286) (xy 83.567778 -231.166416) (xy 83.576414 -231.17048) (xy 83.585558 -231.171496)
			(xy 83.585812 -231.171496) (xy 83.60941 -231.174233) (xy 83.655415 -231.186073) (xy 83.699033 -231.204893)
			(xy 83.73921 -231.23024) (xy 83.774978 -231.261501) (xy 83.805476 -231.297924) (xy 83.829966 -231.338628)
			(xy 83.839304 -231.360472) (xy 83.84286 -231.367076) (xy 83.843114 -231.367584) (xy 83.856642 -231.391465)
			(xy 83.875892 -231.442859) (xy 83.885665 -231.496862) (xy 83.886294 -231.524302) (xy 84.215236 -231.524302)
			(xy 84.219196 -231.475248) (xy 84.230973 -231.427464) (xy 84.250264 -231.382188) (xy 84.276567 -231.340592)
			(xy 84.309202 -231.303755) (xy 84.347323 -231.27263) (xy 84.389944 -231.248023) (xy 84.43596 -231.230571)
			(xy 84.484179 -231.220727) (xy 84.533354 -231.218746) (xy 84.582209 -231.224678) (xy 84.62948 -231.23837)
			(xy 84.673942 -231.259468) (xy 84.714445 -231.287424) (xy 84.749938 -231.321516) (xy 84.779503 -231.36086)
			(xy 84.802374 -231.404437) (xy 84.817958 -231.451118) (xy 84.825853 -231.499695) (xy 84.826348 -231.524302)
			(xy 85.15529 -231.524302) (xy 85.15925 -231.475248) (xy 85.171027 -231.427464) (xy 85.190318 -231.382188)
			(xy 85.216621 -231.340592) (xy 85.249256 -231.303755) (xy 85.287377 -231.27263) (xy 85.329998 -231.248023)
			(xy 85.376014 -231.230571) (xy 85.424233 -231.220727) (xy 85.473408 -231.218746) (xy 85.522263 -231.224678)
			(xy 85.569534 -231.23837) (xy 85.613996 -231.259468) (xy 85.654499 -231.287424) (xy 85.689992 -231.321516)
			(xy 85.719557 -231.36086) (xy 85.742428 -231.404437) (xy 85.758012 -231.451118) (xy 85.765907 -231.499695)
			(xy 85.766402 -231.524302) (xy 86.095344 -231.524302) (xy 86.099304 -231.475248) (xy 86.111081 -231.427464)
			(xy 86.130372 -231.382188) (xy 86.156675 -231.340592) (xy 86.18931 -231.303755) (xy 86.227431 -231.27263)
			(xy 86.270052 -231.248023) (xy 86.316068 -231.230571) (xy 86.364287 -231.220727) (xy 86.413462 -231.218746)
			(xy 86.462317 -231.224678) (xy 86.509588 -231.23837) (xy 86.55405 -231.259468) (xy 86.594553 -231.287424)
			(xy 86.630046 -231.321516) (xy 86.659611 -231.36086) (xy 86.682482 -231.404437) (xy 86.698066 -231.451118)
			(xy 86.705961 -231.499695) (xy 86.706456 -231.524302) (xy 87.035144 -231.524302) (xy 87.039104 -231.475248)
			(xy 87.050881 -231.427464) (xy 87.070172 -231.382188) (xy 87.096475 -231.340592) (xy 87.12911 -231.303755)
			(xy 87.167231 -231.27263) (xy 87.209852 -231.248023) (xy 87.255868 -231.230571) (xy 87.304087 -231.220727)
			(xy 87.353262 -231.218746) (xy 87.402117 -231.224678) (xy 87.449388 -231.23837) (xy 87.49385 -231.259468)
			(xy 87.534353 -231.287424) (xy 87.569846 -231.321516) (xy 87.599411 -231.36086) (xy 87.622282 -231.404437)
			(xy 87.637866 -231.451118) (xy 87.645761 -231.499695) (xy 87.646256 -231.524302) (xy 87.975198 -231.524302)
			(xy 87.979158 -231.475248) (xy 87.990935 -231.427464) (xy 88.010226 -231.382188) (xy 88.036529 -231.340592)
			(xy 88.069164 -231.303755) (xy 88.107285 -231.27263) (xy 88.149906 -231.248023) (xy 88.195922 -231.230571)
			(xy 88.244141 -231.220727) (xy 88.293316 -231.218746) (xy 88.342171 -231.224678) (xy 88.389442 -231.23837)
			(xy 88.433904 -231.259468) (xy 88.474407 -231.287424) (xy 88.5099 -231.321516) (xy 88.539465 -231.36086)
			(xy 88.562336 -231.404437) (xy 88.57792 -231.451118) (xy 88.585815 -231.499695) (xy 88.58631 -231.524302)
			(xy 88.915252 -231.524302) (xy 88.919212 -231.475248) (xy 88.930989 -231.427464) (xy 88.95028 -231.382188)
			(xy 88.976583 -231.340592) (xy 89.009218 -231.303755) (xy 89.047339 -231.27263) (xy 89.08996 -231.248023)
			(xy 89.135976 -231.230571) (xy 89.184195 -231.220727) (xy 89.23337 -231.218746) (xy 89.282225 -231.224678)
			(xy 89.329496 -231.23837) (xy 89.373958 -231.259468) (xy 89.414461 -231.287424) (xy 89.449954 -231.321516)
			(xy 89.479519 -231.36086) (xy 89.50239 -231.404437) (xy 89.517974 -231.451118) (xy 89.525869 -231.499695)
			(xy 89.526364 -231.524302) (xy 89.855306 -231.524302) (xy 89.859266 -231.475248) (xy 89.871043 -231.427464)
			(xy 89.890334 -231.382188) (xy 89.916637 -231.340592) (xy 89.949272 -231.303755) (xy 89.987393 -231.27263)
			(xy 90.030014 -231.248023) (xy 90.07603 -231.230571) (xy 90.124249 -231.220727) (xy 90.173424 -231.218746)
			(xy 90.222279 -231.224678) (xy 90.26955 -231.23837) (xy 90.314012 -231.259468) (xy 90.354515 -231.287424)
			(xy 90.390008 -231.321516) (xy 90.419573 -231.36086) (xy 90.442444 -231.404437) (xy 90.458028 -231.451118)
			(xy 90.465923 -231.499695) (xy 90.466418 -231.524302) (xy 90.784675 -231.524302) (xy 90.78877 -231.473574)
			(xy 90.800949 -231.42416) (xy 90.820897 -231.37734) (xy 90.848098 -231.334326) (xy 90.881846 -231.296232)
			(xy 90.921268 -231.264045) (xy 90.965342 -231.238599) (xy 91.012928 -231.220552) (xy 91.062792 -231.210372)
			(xy 91.113644 -231.208323) (xy 91.164165 -231.214457) (xy 91.213049 -231.228617) (xy 91.259028 -231.250434)
			(xy 91.300912 -231.279344) (xy 91.337616 -231.314599) (xy 91.368189 -231.355285) (xy 91.39184 -231.400348)
			(xy 91.407956 -231.448622) (xy 91.41612 -231.498856) (xy 91.416632 -231.524302) (xy 91.724729 -231.524302)
			(xy 91.728824 -231.473574) (xy 91.741003 -231.42416) (xy 91.760951 -231.37734) (xy 91.788152 -231.334326)
			(xy 91.8219 -231.296232) (xy 91.861322 -231.264045) (xy 91.905396 -231.238599) (xy 91.952982 -231.220552)
			(xy 92.002846 -231.210372) (xy 92.053698 -231.208323) (xy 92.104219 -231.214457) (xy 92.153103 -231.228617)
			(xy 92.199082 -231.250434) (xy 92.240966 -231.279344) (xy 92.27767 -231.314599) (xy 92.308243 -231.355285)
			(xy 92.331894 -231.400348) (xy 92.34801 -231.448622) (xy 92.356174 -231.498856) (xy 92.356686 -231.524302)
			(xy 92.675214 -231.524302) (xy 92.679174 -231.475248) (xy 92.690951 -231.427464) (xy 92.710242 -231.382188)
			(xy 92.736545 -231.340592) (xy 92.76918 -231.303755) (xy 92.807301 -231.27263) (xy 92.849922 -231.248023)
			(xy 92.895938 -231.230571) (xy 92.944157 -231.220727) (xy 92.993332 -231.218746) (xy 93.042187 -231.224678)
			(xy 93.089458 -231.23837) (xy 93.13392 -231.259468) (xy 93.174423 -231.287424) (xy 93.209916 -231.321516)
			(xy 93.239481 -231.36086) (xy 93.262352 -231.404437) (xy 93.277936 -231.451118) (xy 93.285831 -231.499695)
			(xy 93.286326 -231.524302) (xy 93.604837 -231.524302) (xy 93.608932 -231.473574) (xy 93.621111 -231.42416)
			(xy 93.641059 -231.37734) (xy 93.66826 -231.334326) (xy 93.702008 -231.296232) (xy 93.74143 -231.264045)
			(xy 93.785504 -231.238599) (xy 93.83309 -231.220552) (xy 93.882954 -231.210372) (xy 93.933806 -231.208323)
			(xy 93.984327 -231.214457) (xy 94.033211 -231.228617) (xy 94.07919 -231.250434) (xy 94.121074 -231.279344)
			(xy 94.157778 -231.314599) (xy 94.188351 -231.355285) (xy 94.212002 -231.400348) (xy 94.228118 -231.448622)
			(xy 94.236282 -231.498856) (xy 94.236794 -231.524302) (xy 94.555322 -231.524302) (xy 94.559282 -231.475248)
			(xy 94.571059 -231.427464) (xy 94.59035 -231.382188) (xy 94.616653 -231.340592) (xy 94.649288 -231.303755)
			(xy 94.687409 -231.27263) (xy 94.73003 -231.248023) (xy 94.776046 -231.230571) (xy 94.824265 -231.220727)
			(xy 94.87344 -231.218746) (xy 94.922295 -231.224678) (xy 94.969566 -231.23837) (xy 95.014028 -231.259468)
			(xy 95.054531 -231.287424) (xy 95.090024 -231.321516) (xy 95.119589 -231.36086) (xy 95.14246 -231.404437)
			(xy 95.158044 -231.451118) (xy 95.165939 -231.499695) (xy 95.166434 -231.524302) (xy 95.484691 -231.524302)
			(xy 95.488786 -231.473574) (xy 95.500965 -231.42416) (xy 95.520913 -231.37734) (xy 95.548114 -231.334326)
			(xy 95.581862 -231.296232) (xy 95.621284 -231.264045) (xy 95.665358 -231.238599) (xy 95.712944 -231.220552)
			(xy 95.762808 -231.210372) (xy 95.81366 -231.208323) (xy 95.864181 -231.214457) (xy 95.913065 -231.228617)
			(xy 95.959044 -231.250434) (xy 96.000928 -231.279344) (xy 96.037632 -231.314599) (xy 96.068205 -231.355285)
			(xy 96.091856 -231.400348) (xy 96.107972 -231.448622) (xy 96.116136 -231.498856) (xy 96.116648 -231.524302)
			(xy 96.116136 -231.549748) (xy 96.107972 -231.599982) (xy 96.091856 -231.648256) (xy 96.068205 -231.693319)
			(xy 96.037632 -231.734005) (xy 96.000928 -231.76926) (xy 95.959044 -231.79817) (xy 95.913065 -231.819987)
			(xy 95.864181 -231.834147) (xy 95.81366 -231.840281) (xy 95.762808 -231.838232) (xy 95.712944 -231.828052)
			(xy 95.665358 -231.810005) (xy 95.621284 -231.784559) (xy 95.581862 -231.752372) (xy 95.548114 -231.714278)
			(xy 95.520913 -231.671264) (xy 95.500965 -231.624444) (xy 95.488786 -231.57503) (xy 95.484691 -231.524302)
			(xy 95.166434 -231.524302) (xy 95.165939 -231.548909) (xy 95.158044 -231.597486) (xy 95.14246 -231.644167)
			(xy 95.119589 -231.687744) (xy 95.090024 -231.727088) (xy 95.054531 -231.76118) (xy 95.014028 -231.789136)
			(xy 94.969566 -231.810234) (xy 94.922295 -231.823926) (xy 94.87344 -231.829858) (xy 94.824265 -231.827877)
			(xy 94.776046 -231.818033) (xy 94.73003 -231.800581) (xy 94.687409 -231.775974) (xy 94.649288 -231.744849)
			(xy 94.616653 -231.708012) (xy 94.59035 -231.666416) (xy 94.571059 -231.62114) (xy 94.559282 -231.573356)
			(xy 94.555322 -231.524302) (xy 94.236794 -231.524302) (xy 94.236282 -231.549748) (xy 94.228118 -231.599982)
			(xy 94.212002 -231.648256) (xy 94.188351 -231.693319) (xy 94.157778 -231.734005) (xy 94.121074 -231.76926)
			(xy 94.07919 -231.79817) (xy 94.033211 -231.819987) (xy 93.984327 -231.834147) (xy 93.933806 -231.840281)
			(xy 93.882954 -231.838232) (xy 93.83309 -231.828052) (xy 93.785504 -231.810005) (xy 93.74143 -231.784559)
			(xy 93.702008 -231.752372) (xy 93.66826 -231.714278) (xy 93.641059 -231.671264) (xy 93.621111 -231.624444)
			(xy 93.608932 -231.57503) (xy 93.604837 -231.524302) (xy 93.286326 -231.524302) (xy 93.285831 -231.548909)
			(xy 93.277936 -231.597486) (xy 93.262352 -231.644167) (xy 93.239481 -231.687744) (xy 93.209916 -231.727088)
			(xy 93.174423 -231.76118) (xy 93.13392 -231.789136) (xy 93.089458 -231.810234) (xy 93.042187 -231.823926)
			(xy 92.993332 -231.829858) (xy 92.944157 -231.827877) (xy 92.895938 -231.818033) (xy 92.849922 -231.800581)
			(xy 92.807301 -231.775974) (xy 92.76918 -231.744849) (xy 92.736545 -231.708012) (xy 92.710242 -231.666416)
			(xy 92.690951 -231.62114) (xy 92.679174 -231.573356) (xy 92.675214 -231.524302) (xy 92.356686 -231.524302)
			(xy 92.356174 -231.549748) (xy 92.34801 -231.599982) (xy 92.331894 -231.648256) (xy 92.308243 -231.693319)
			(xy 92.27767 -231.734005) (xy 92.240966 -231.76926) (xy 92.199082 -231.79817) (xy 92.153103 -231.819987)
			(xy 92.104219 -231.834147) (xy 92.053698 -231.840281) (xy 92.002846 -231.838232) (xy 91.952982 -231.828052)
			(xy 91.905396 -231.810005) (xy 91.861322 -231.784559) (xy 91.8219 -231.752372) (xy 91.788152 -231.714278)
			(xy 91.760951 -231.671264) (xy 91.741003 -231.624444) (xy 91.728824 -231.57503) (xy 91.724729 -231.524302)
			(xy 91.416632 -231.524302) (xy 91.41612 -231.549748) (xy 91.407956 -231.599982) (xy 91.39184 -231.648256)
			(xy 91.368189 -231.693319) (xy 91.337616 -231.734005) (xy 91.300912 -231.76926) (xy 91.259028 -231.79817)
			(xy 91.213049 -231.819987) (xy 91.164165 -231.834147) (xy 91.113644 -231.840281) (xy 91.062792 -231.838232)
			(xy 91.012928 -231.828052) (xy 90.965342 -231.810005) (xy 90.921268 -231.784559) (xy 90.881846 -231.752372)
			(xy 90.848098 -231.714278) (xy 90.820897 -231.671264) (xy 90.800949 -231.624444) (xy 90.78877 -231.57503)
			(xy 90.784675 -231.524302) (xy 90.466418 -231.524302) (xy 90.465923 -231.548909) (xy 90.458028 -231.597486)
			(xy 90.442444 -231.644167) (xy 90.419573 -231.687744) (xy 90.390008 -231.727088) (xy 90.354515 -231.76118)
			(xy 90.314012 -231.789136) (xy 90.26955 -231.810234) (xy 90.222279 -231.823926) (xy 90.173424 -231.829858)
			(xy 90.124249 -231.827877) (xy 90.07603 -231.818033) (xy 90.030014 -231.800581) (xy 89.987393 -231.775974)
			(xy 89.949272 -231.744849) (xy 89.916637 -231.708012) (xy 89.890334 -231.666416) (xy 89.871043 -231.62114)
			(xy 89.859266 -231.573356) (xy 89.855306 -231.524302) (xy 89.526364 -231.524302) (xy 89.525869 -231.548909)
			(xy 89.517974 -231.597486) (xy 89.50239 -231.644167) (xy 89.479519 -231.687744) (xy 89.449954 -231.727088)
			(xy 89.414461 -231.76118) (xy 89.373958 -231.789136) (xy 89.329496 -231.810234) (xy 89.282225 -231.823926)
			(xy 89.23337 -231.829858) (xy 89.184195 -231.827877) (xy 89.135976 -231.818033) (xy 89.08996 -231.800581)
			(xy 89.047339 -231.775974) (xy 89.009218 -231.744849) (xy 88.976583 -231.708012) (xy 88.95028 -231.666416)
			(xy 88.930989 -231.62114) (xy 88.919212 -231.573356) (xy 88.915252 -231.524302) (xy 88.58631 -231.524302)
			(xy 88.585815 -231.548909) (xy 88.57792 -231.597486) (xy 88.562336 -231.644167) (xy 88.539465 -231.687744)
			(xy 88.5099 -231.727088) (xy 88.474407 -231.76118) (xy 88.433904 -231.789136) (xy 88.389442 -231.810234)
			(xy 88.342171 -231.823926) (xy 88.293316 -231.829858) (xy 88.244141 -231.827877) (xy 88.195922 -231.818033)
			(xy 88.149906 -231.800581) (xy 88.107285 -231.775974) (xy 88.069164 -231.744849) (xy 88.036529 -231.708012)
			(xy 88.010226 -231.666416) (xy 87.990935 -231.62114) (xy 87.979158 -231.573356) (xy 87.975198 -231.524302)
			(xy 87.646256 -231.524302) (xy 87.645761 -231.548909) (xy 87.637866 -231.597486) (xy 87.622282 -231.644167)
			(xy 87.599411 -231.687744) (xy 87.569846 -231.727088) (xy 87.534353 -231.76118) (xy 87.49385 -231.789136)
			(xy 87.449388 -231.810234) (xy 87.402117 -231.823926) (xy 87.353262 -231.829858) (xy 87.304087 -231.827877)
			(xy 87.255868 -231.818033) (xy 87.209852 -231.800581) (xy 87.167231 -231.775974) (xy 87.12911 -231.744849)
			(xy 87.096475 -231.708012) (xy 87.070172 -231.666416) (xy 87.050881 -231.62114) (xy 87.039104 -231.573356)
			(xy 87.035144 -231.524302) (xy 86.706456 -231.524302) (xy 86.705961 -231.548909) (xy 86.698066 -231.597486)
			(xy 86.682482 -231.644167) (xy 86.659611 -231.687744) (xy 86.630046 -231.727088) (xy 86.594553 -231.76118)
			(xy 86.55405 -231.789136) (xy 86.509588 -231.810234) (xy 86.462317 -231.823926) (xy 86.413462 -231.829858)
			(xy 86.364287 -231.827877) (xy 86.316068 -231.818033) (xy 86.270052 -231.800581) (xy 86.227431 -231.775974)
			(xy 86.18931 -231.744849) (xy 86.156675 -231.708012) (xy 86.130372 -231.666416) (xy 86.111081 -231.62114)
			(xy 86.099304 -231.573356) (xy 86.095344 -231.524302) (xy 85.766402 -231.524302) (xy 85.765907 -231.548909)
			(xy 85.758012 -231.597486) (xy 85.742428 -231.644167) (xy 85.719557 -231.687744) (xy 85.689992 -231.727088)
			(xy 85.654499 -231.76118) (xy 85.613996 -231.789136) (xy 85.569534 -231.810234) (xy 85.522263 -231.823926)
			(xy 85.473408 -231.829858) (xy 85.424233 -231.827877) (xy 85.376014 -231.818033) (xy 85.329998 -231.800581)
			(xy 85.287377 -231.775974) (xy 85.249256 -231.744849) (xy 85.216621 -231.708012) (xy 85.190318 -231.666416)
			(xy 85.171027 -231.62114) (xy 85.15925 -231.573356) (xy 85.15529 -231.524302) (xy 84.826348 -231.524302)
			(xy 84.825853 -231.548909) (xy 84.817958 -231.597486) (xy 84.802374 -231.644167) (xy 84.779503 -231.687744)
			(xy 84.749938 -231.727088) (xy 84.714445 -231.76118) (xy 84.673942 -231.789136) (xy 84.62948 -231.810234)
			(xy 84.582209 -231.823926) (xy 84.533354 -231.829858) (xy 84.484179 -231.827877) (xy 84.43596 -231.818033)
			(xy 84.389944 -231.800581) (xy 84.347323 -231.775974) (xy 84.309202 -231.744849) (xy 84.276567 -231.708012)
			(xy 84.250264 -231.666416) (xy 84.230973 -231.62114) (xy 84.219196 -231.573356) (xy 84.215236 -231.524302)
			(xy 83.886294 -231.524302) (xy 83.885848 -231.548295) (xy 83.878341 -231.595689) (xy 83.863512 -231.641326)
			(xy 83.841726 -231.68408) (xy 83.81352 -231.722901) (xy 83.779588 -231.756831) (xy 83.740767 -231.785034)
			(xy 83.698011 -231.806818) (xy 83.652373 -231.821644) (xy 83.604979 -231.829149) (xy 83.580986 -231.82961)
			(xy 83.551268 -231.828086) (xy 83.551014 -231.828086) (xy 83.539076 -231.82707) (xy 83.528408 -231.831134)
			(xy 83.522868 -231.833443) (xy 83.512979 -231.840241) (xy 83.50885 -231.844596) (xy 83.508088 -231.845358)
			(xy 83.502211 -231.852341) (xy 83.495424 -231.869269) (xy 83.49488 -231.878378) (xy 83.49488 -232.334308)
			(xy 83.745336 -232.334308) (xy 83.749296 -232.285254) (xy 83.761073 -232.23747) (xy 83.780364 -232.192194)
			(xy 83.806667 -232.150598) (xy 83.839302 -232.113761) (xy 83.877423 -232.082636) (xy 83.920044 -232.058029)
			(xy 83.96606 -232.040577) (xy 84.014279 -232.030733) (xy 84.063454 -232.028752) (xy 84.112309 -232.034684)
			(xy 84.15958 -232.048376) (xy 84.204042 -232.069474) (xy 84.244545 -232.09743) (xy 84.280038 -232.131522)
			(xy 84.309603 -232.170866) (xy 84.332474 -232.214443) (xy 84.348058 -232.261124) (xy 84.355953 -232.309701)
			(xy 84.356448 -232.334308) (xy 84.685136 -232.334308) (xy 84.689096 -232.285254) (xy 84.700873 -232.23747)
			(xy 84.720164 -232.192194) (xy 84.746467 -232.150598) (xy 84.779102 -232.113761) (xy 84.817223 -232.082636)
			(xy 84.859844 -232.058029) (xy 84.90586 -232.040577) (xy 84.954079 -232.030733) (xy 85.003254 -232.028752)
			(xy 85.052109 -232.034684) (xy 85.09938 -232.048376) (xy 85.143842 -232.069474) (xy 85.184345 -232.09743)
			(xy 85.219838 -232.131522) (xy 85.249403 -232.170866) (xy 85.272274 -232.214443) (xy 85.287858 -232.261124)
			(xy 85.295753 -232.309701) (xy 85.296248 -232.334308) (xy 85.62519 -232.334308) (xy 85.62915 -232.285254)
			(xy 85.640927 -232.23747) (xy 85.660218 -232.192194) (xy 85.686521 -232.150598) (xy 85.719156 -232.113761)
			(xy 85.757277 -232.082636) (xy 85.799898 -232.058029) (xy 85.845914 -232.040577) (xy 85.894133 -232.030733)
			(xy 85.943308 -232.028752) (xy 85.992163 -232.034684) (xy 86.039434 -232.048376) (xy 86.083896 -232.069474)
			(xy 86.124399 -232.09743) (xy 86.159892 -232.131522) (xy 86.189457 -232.170866) (xy 86.212328 -232.214443)
			(xy 86.227912 -232.261124) (xy 86.235807 -232.309701) (xy 86.236302 -232.334308) (xy 87.505298 -232.334308)
			(xy 87.509258 -232.285254) (xy 87.521035 -232.23747) (xy 87.540326 -232.192194) (xy 87.566629 -232.150598)
			(xy 87.599264 -232.113761) (xy 87.637385 -232.082636) (xy 87.680006 -232.058029) (xy 87.726022 -232.040577)
			(xy 87.774241 -232.030733) (xy 87.823416 -232.028752) (xy 87.872271 -232.034684) (xy 87.919542 -232.048376)
			(xy 87.964004 -232.069474) (xy 88.004507 -232.09743) (xy 88.04 -232.131522) (xy 88.069565 -232.170866)
			(xy 88.092436 -232.214443) (xy 88.10802 -232.261124) (xy 88.115915 -232.309701) (xy 88.11641 -232.334308)
			(xy 88.445352 -232.334308) (xy 88.449312 -232.285254) (xy 88.461089 -232.23747) (xy 88.48038 -232.192194)
			(xy 88.506683 -232.150598) (xy 88.539318 -232.113761) (xy 88.577439 -232.082636) (xy 88.62006 -232.058029)
			(xy 88.666076 -232.040577) (xy 88.714295 -232.030733) (xy 88.76347 -232.028752) (xy 88.812325 -232.034684)
			(xy 88.859596 -232.048376) (xy 88.904058 -232.069474) (xy 88.944561 -232.09743) (xy 88.980054 -232.131522)
			(xy 89.009619 -232.170866) (xy 89.03249 -232.214443) (xy 89.048074 -232.261124) (xy 89.055969 -232.309701)
			(xy 89.056464 -232.334308) (xy 89.385152 -232.334308) (xy 89.389112 -232.285254) (xy 89.400889 -232.23747)
			(xy 89.42018 -232.192194) (xy 89.446483 -232.150598) (xy 89.479118 -232.113761) (xy 89.517239 -232.082636)
			(xy 89.55986 -232.058029) (xy 89.605876 -232.040577) (xy 89.654095 -232.030733) (xy 89.70327 -232.028752)
			(xy 89.752125 -232.034684) (xy 89.799396 -232.048376) (xy 89.843858 -232.069474) (xy 89.884361 -232.09743)
			(xy 89.919854 -232.131522) (xy 89.949419 -232.170866) (xy 89.97229 -232.214443) (xy 89.987874 -232.261124)
			(xy 89.995769 -232.309701) (xy 89.996264 -232.334308) (xy 90.314775 -232.334308) (xy 90.31887 -232.28358)
			(xy 90.331049 -232.234166) (xy 90.350997 -232.187346) (xy 90.378198 -232.144332) (xy 90.411946 -232.106238)
			(xy 90.451368 -232.074051) (xy 90.495442 -232.048605) (xy 90.543028 -232.030558) (xy 90.592892 -232.020378)
			(xy 90.643744 -232.018329) (xy 90.694265 -232.024463) (xy 90.743149 -232.038623) (xy 90.789128 -232.06044)
			(xy 90.831012 -232.08935) (xy 90.867716 -232.124605) (xy 90.898289 -232.165291) (xy 90.92194 -232.210354)
			(xy 90.938056 -232.258628) (xy 90.94622 -232.308862) (xy 90.946732 -232.334308) (xy 91.26526 -232.334308)
			(xy 91.26922 -232.285254) (xy 91.280997 -232.23747) (xy 91.300288 -232.192194) (xy 91.326591 -232.150598)
			(xy 91.359226 -232.113761) (xy 91.397347 -232.082636) (xy 91.439968 -232.058029) (xy 91.485984 -232.040577)
			(xy 91.534203 -232.030733) (xy 91.583378 -232.028752) (xy 91.632233 -232.034684) (xy 91.679504 -232.048376)
			(xy 91.723966 -232.069474) (xy 91.764469 -232.09743) (xy 91.799962 -232.131522) (xy 91.829527 -232.170866)
			(xy 91.852398 -232.214443) (xy 91.867982 -232.261124) (xy 91.875877 -232.309701) (xy 91.876372 -232.334308)
			(xy 92.194883 -232.334308) (xy 92.198978 -232.28358) (xy 92.211157 -232.234166) (xy 92.231105 -232.187346)
			(xy 92.258306 -232.144332) (xy 92.292054 -232.106238) (xy 92.331476 -232.074051) (xy 92.37555 -232.048605)
			(xy 92.423136 -232.030558) (xy 92.473 -232.020378) (xy 92.523852 -232.018329) (xy 92.574373 -232.024463)
			(xy 92.623257 -232.038623) (xy 92.669236 -232.06044) (xy 92.71112 -232.08935) (xy 92.747824 -232.124605)
			(xy 92.778397 -232.165291) (xy 92.802048 -232.210354) (xy 92.818164 -232.258628) (xy 92.826328 -232.308862)
			(xy 92.82684 -232.334308) (xy 94.074737 -232.334308) (xy 94.078832 -232.28358) (xy 94.091011 -232.234166)
			(xy 94.110959 -232.187346) (xy 94.13816 -232.144332) (xy 94.171908 -232.106238) (xy 94.21133 -232.074051)
			(xy 94.255404 -232.048605) (xy 94.30299 -232.030558) (xy 94.352854 -232.020378) (xy 94.403706 -232.018329)
			(xy 94.454227 -232.024463) (xy 94.503111 -232.038623) (xy 94.54909 -232.06044) (xy 94.590974 -232.08935)
			(xy 94.627678 -232.124605) (xy 94.658251 -232.165291) (xy 94.681902 -232.210354) (xy 94.698018 -232.258628)
			(xy 94.706182 -232.308862) (xy 94.706694 -232.334308) (xy 95.014791 -232.334308) (xy 95.018886 -232.28358)
			(xy 95.031065 -232.234166) (xy 95.051013 -232.187346) (xy 95.078214 -232.144332) (xy 95.111962 -232.106238)
			(xy 95.151384 -232.074051) (xy 95.195458 -232.048605) (xy 95.243044 -232.030558) (xy 95.292908 -232.020378)
			(xy 95.34376 -232.018329) (xy 95.394281 -232.024463) (xy 95.443165 -232.038623) (xy 95.489144 -232.06044)
			(xy 95.531028 -232.08935) (xy 95.567732 -232.124605) (xy 95.598305 -232.165291) (xy 95.621956 -232.210354)
			(xy 95.638072 -232.258628) (xy 95.646236 -232.308862) (xy 95.646748 -232.334308) (xy 95.646236 -232.359754)
			(xy 95.638072 -232.409988) (xy 95.621956 -232.458262) (xy 95.598305 -232.503325) (xy 95.567732 -232.544011)
			(xy 95.531028 -232.579266) (xy 95.489144 -232.608176) (xy 95.443165 -232.629993) (xy 95.394281 -232.644153)
			(xy 95.34376 -232.650287) (xy 95.292908 -232.648238) (xy 95.243044 -232.638058) (xy 95.195458 -232.620011)
			(xy 95.151384 -232.594565) (xy 95.111962 -232.562378) (xy 95.078214 -232.524284) (xy 95.051013 -232.48127)
			(xy 95.031065 -232.43445) (xy 95.018886 -232.385036) (xy 95.014791 -232.334308) (xy 94.706694 -232.334308)
			(xy 94.706182 -232.359754) (xy 94.698018 -232.409988) (xy 94.681902 -232.458262) (xy 94.658251 -232.503325)
			(xy 94.627678 -232.544011) (xy 94.590974 -232.579266) (xy 94.54909 -232.608176) (xy 94.503111 -232.629993)
			(xy 94.454227 -232.644153) (xy 94.403706 -232.650287) (xy 94.352854 -232.648238) (xy 94.30299 -232.638058)
			(xy 94.255404 -232.620011) (xy 94.21133 -232.594565) (xy 94.171908 -232.562378) (xy 94.13816 -232.524284)
			(xy 94.110959 -232.48127) (xy 94.091011 -232.43445) (xy 94.078832 -232.385036) (xy 94.074737 -232.334308)
			(xy 92.82684 -232.334308) (xy 92.826328 -232.359754) (xy 92.818164 -232.409988) (xy 92.802048 -232.458262)
			(xy 92.778397 -232.503325) (xy 92.747824 -232.544011) (xy 92.71112 -232.579266) (xy 92.669236 -232.608176)
			(xy 92.623257 -232.629993) (xy 92.574373 -232.644153) (xy 92.523852 -232.650287) (xy 92.473 -232.648238)
			(xy 92.423136 -232.638058) (xy 92.37555 -232.620011) (xy 92.331476 -232.594565) (xy 92.292054 -232.562378)
			(xy 92.258306 -232.524284) (xy 92.231105 -232.48127) (xy 92.211157 -232.43445) (xy 92.198978 -232.385036)
			(xy 92.194883 -232.334308) (xy 91.876372 -232.334308) (xy 91.875877 -232.358915) (xy 91.867982 -232.407492)
			(xy 91.852398 -232.454173) (xy 91.829527 -232.49775) (xy 91.799962 -232.537094) (xy 91.764469 -232.571186)
			(xy 91.723966 -232.599142) (xy 91.679504 -232.62024) (xy 91.632233 -232.633932) (xy 91.583378 -232.639864)
			(xy 91.534203 -232.637883) (xy 91.485984 -232.628039) (xy 91.439968 -232.610587) (xy 91.397347 -232.58598)
			(xy 91.359226 -232.554855) (xy 91.326591 -232.518018) (xy 91.300288 -232.476422) (xy 91.280997 -232.431146)
			(xy 91.26922 -232.383362) (xy 91.26526 -232.334308) (xy 90.946732 -232.334308) (xy 90.94622 -232.359754)
			(xy 90.938056 -232.409988) (xy 90.92194 -232.458262) (xy 90.898289 -232.503325) (xy 90.867716 -232.544011)
			(xy 90.831012 -232.579266) (xy 90.789128 -232.608176) (xy 90.743149 -232.629993) (xy 90.694265 -232.644153)
			(xy 90.643744 -232.650287) (xy 90.592892 -232.648238) (xy 90.543028 -232.638058) (xy 90.495442 -232.620011)
			(xy 90.451368 -232.594565) (xy 90.411946 -232.562378) (xy 90.378198 -232.524284) (xy 90.350997 -232.48127)
			(xy 90.331049 -232.43445) (xy 90.31887 -232.385036) (xy 90.314775 -232.334308) (xy 89.996264 -232.334308)
			(xy 89.995769 -232.358915) (xy 89.987874 -232.407492) (xy 89.97229 -232.454173) (xy 89.949419 -232.49775)
			(xy 89.919854 -232.537094) (xy 89.884361 -232.571186) (xy 89.843858 -232.599142) (xy 89.799396 -232.62024)
			(xy 89.752125 -232.633932) (xy 89.70327 -232.639864) (xy 89.654095 -232.637883) (xy 89.605876 -232.628039)
			(xy 89.55986 -232.610587) (xy 89.517239 -232.58598) (xy 89.479118 -232.554855) (xy 89.446483 -232.518018)
			(xy 89.42018 -232.476422) (xy 89.400889 -232.431146) (xy 89.389112 -232.383362) (xy 89.385152 -232.334308)
			(xy 89.056464 -232.334308) (xy 89.055969 -232.358915) (xy 89.048074 -232.407492) (xy 89.03249 -232.454173)
			(xy 89.009619 -232.49775) (xy 88.980054 -232.537094) (xy 88.944561 -232.571186) (xy 88.904058 -232.599142)
			(xy 88.859596 -232.62024) (xy 88.812325 -232.633932) (xy 88.76347 -232.639864) (xy 88.714295 -232.637883)
			(xy 88.666076 -232.628039) (xy 88.62006 -232.610587) (xy 88.577439 -232.58598) (xy 88.539318 -232.554855)
			(xy 88.506683 -232.518018) (xy 88.48038 -232.476422) (xy 88.461089 -232.431146) (xy 88.449312 -232.383362)
			(xy 88.445352 -232.334308) (xy 88.11641 -232.334308) (xy 88.115915 -232.358915) (xy 88.10802 -232.407492)
			(xy 88.092436 -232.454173) (xy 88.069565 -232.49775) (xy 88.04 -232.537094) (xy 88.004507 -232.571186)
			(xy 87.964004 -232.599142) (xy 87.919542 -232.62024) (xy 87.872271 -232.633932) (xy 87.823416 -232.639864)
			(xy 87.774241 -232.637883) (xy 87.726022 -232.628039) (xy 87.680006 -232.610587) (xy 87.637385 -232.58598)
			(xy 87.599264 -232.554855) (xy 87.566629 -232.518018) (xy 87.540326 -232.476422) (xy 87.521035 -232.431146)
			(xy 87.509258 -232.383362) (xy 87.505298 -232.334308) (xy 86.236302 -232.334308) (xy 86.235807 -232.358915)
			(xy 86.227912 -232.407492) (xy 86.212328 -232.454173) (xy 86.189457 -232.49775) (xy 86.159892 -232.537094)
			(xy 86.124399 -232.571186) (xy 86.083896 -232.599142) (xy 86.039434 -232.62024) (xy 85.992163 -232.633932)
			(xy 85.943308 -232.639864) (xy 85.894133 -232.637883) (xy 85.845914 -232.628039) (xy 85.799898 -232.610587)
			(xy 85.757277 -232.58598) (xy 85.719156 -232.554855) (xy 85.686521 -232.518018) (xy 85.660218 -232.476422)
			(xy 85.640927 -232.431146) (xy 85.62915 -232.383362) (xy 85.62519 -232.334308) (xy 85.296248 -232.334308)
			(xy 85.295753 -232.358915) (xy 85.287858 -232.407492) (xy 85.272274 -232.454173) (xy 85.249403 -232.49775)
			(xy 85.219838 -232.537094) (xy 85.184345 -232.571186) (xy 85.143842 -232.599142) (xy 85.09938 -232.62024)
			(xy 85.052109 -232.633932) (xy 85.003254 -232.639864) (xy 84.954079 -232.637883) (xy 84.90586 -232.628039)
			(xy 84.859844 -232.610587) (xy 84.817223 -232.58598) (xy 84.779102 -232.554855) (xy 84.746467 -232.518018)
			(xy 84.720164 -232.476422) (xy 84.700873 -232.431146) (xy 84.689096 -232.383362) (xy 84.685136 -232.334308)
			(xy 84.356448 -232.334308) (xy 84.355953 -232.358915) (xy 84.348058 -232.407492) (xy 84.332474 -232.454173)
			(xy 84.309603 -232.49775) (xy 84.280038 -232.537094) (xy 84.244545 -232.571186) (xy 84.204042 -232.599142)
			(xy 84.15958 -232.62024) (xy 84.112309 -232.633932) (xy 84.063454 -232.639864) (xy 84.014279 -232.637883)
			(xy 83.96606 -232.628039) (xy 83.920044 -232.610587) (xy 83.877423 -232.58598) (xy 83.839302 -232.554855)
			(xy 83.806667 -232.518018) (xy 83.780364 -232.476422) (xy 83.761073 -232.431146) (xy 83.749296 -232.383362)
			(xy 83.745336 -232.334308) (xy 83.49488 -232.334308) (xy 83.49488 -232.691432) (xy 83.494973 -232.695983)
			(xy 83.49664 -232.70493) (xy 83.498182 -232.709212) (xy 83.501738 -232.71861) (xy 83.537298 -232.75798)
			(xy 83.552792 -232.775252) (xy 83.559904 -232.781602) (xy 83.561936 -232.782872) (xy 83.567778 -232.786428)
			(xy 83.576414 -232.790492) (xy 83.585558 -232.791508) (xy 83.585812 -232.791508) (xy 83.60941 -232.794245)
			(xy 83.655415 -232.806085) (xy 83.699031 -232.824906) (xy 83.739208 -232.850253) (xy 83.774975 -232.881515)
			(xy 83.805471 -232.917938) (xy 83.82996 -232.958643) (xy 83.839304 -232.980484) (xy 83.84286 -232.987088)
			(xy 83.843114 -232.987596) (xy 83.856649 -233.011476) (xy 83.875914 -233.062868) (xy 83.885702 -233.116872)
			(xy 83.886294 -233.144314) (xy 84.215236 -233.144314) (xy 84.219196 -233.09526) (xy 84.230973 -233.047476)
			(xy 84.250264 -233.0022) (xy 84.276567 -232.960604) (xy 84.309202 -232.923767) (xy 84.347323 -232.892642)
			(xy 84.389944 -232.868035) (xy 84.43596 -232.850583) (xy 84.484179 -232.840739) (xy 84.533354 -232.838758)
			(xy 84.582209 -232.84469) (xy 84.62948 -232.858382) (xy 84.673942 -232.87948) (xy 84.714445 -232.907436)
			(xy 84.749938 -232.941528) (xy 84.779503 -232.980872) (xy 84.802374 -233.024449) (xy 84.817958 -233.07113)
			(xy 84.825853 -233.119707) (xy 84.826348 -233.144314) (xy 85.15529 -233.144314) (xy 85.15925 -233.09526)
			(xy 85.171027 -233.047476) (xy 85.190318 -233.0022) (xy 85.216621 -232.960604) (xy 85.249256 -232.923767)
			(xy 85.287377 -232.892642) (xy 85.329998 -232.868035) (xy 85.376014 -232.850583) (xy 85.424233 -232.840739)
			(xy 85.473408 -232.838758) (xy 85.522263 -232.84469) (xy 85.569534 -232.858382) (xy 85.613996 -232.87948)
			(xy 85.654499 -232.907436) (xy 85.689992 -232.941528) (xy 85.719557 -232.980872) (xy 85.742428 -233.024449)
			(xy 85.758012 -233.07113) (xy 85.765907 -233.119707) (xy 85.766402 -233.144314) (xy 86.095344 -233.144314)
			(xy 86.099304 -233.09526) (xy 86.111081 -233.047476) (xy 86.130372 -233.0022) (xy 86.156675 -232.960604)
			(xy 86.18931 -232.923767) (xy 86.227431 -232.892642) (xy 86.270052 -232.868035) (xy 86.316068 -232.850583)
			(xy 86.364287 -232.840739) (xy 86.413462 -232.838758) (xy 86.462317 -232.84469) (xy 86.509588 -232.858382)
			(xy 86.55405 -232.87948) (xy 86.594553 -232.907436) (xy 86.630046 -232.941528) (xy 86.659611 -232.980872)
			(xy 86.682482 -233.024449) (xy 86.698066 -233.07113) (xy 86.705961 -233.119707) (xy 86.706456 -233.144314)
			(xy 87.035144 -233.144314) (xy 87.039104 -233.09526) (xy 87.050881 -233.047476) (xy 87.070172 -233.0022)
			(xy 87.096475 -232.960604) (xy 87.12911 -232.923767) (xy 87.167231 -232.892642) (xy 87.209852 -232.868035)
			(xy 87.255868 -232.850583) (xy 87.304087 -232.840739) (xy 87.353262 -232.838758) (xy 87.402117 -232.84469)
			(xy 87.449388 -232.858382) (xy 87.49385 -232.87948) (xy 87.534353 -232.907436) (xy 87.569846 -232.941528)
			(xy 87.599411 -232.980872) (xy 87.622282 -233.024449) (xy 87.637866 -233.07113) (xy 87.645761 -233.119707)
			(xy 87.646256 -233.144314) (xy 87.975198 -233.144314) (xy 87.979158 -233.09526) (xy 87.990935 -233.047476)
			(xy 88.010226 -233.0022) (xy 88.036529 -232.960604) (xy 88.069164 -232.923767) (xy 88.107285 -232.892642)
			(xy 88.149906 -232.868035) (xy 88.195922 -232.850583) (xy 88.244141 -232.840739) (xy 88.293316 -232.838758)
			(xy 88.342171 -232.84469) (xy 88.389442 -232.858382) (xy 88.433904 -232.87948) (xy 88.474407 -232.907436)
			(xy 88.5099 -232.941528) (xy 88.539465 -232.980872) (xy 88.562336 -233.024449) (xy 88.57792 -233.07113)
			(xy 88.585815 -233.119707) (xy 88.58631 -233.144314) (xy 88.915252 -233.144314) (xy 88.919212 -233.09526)
			(xy 88.930989 -233.047476) (xy 88.95028 -233.0022) (xy 88.976583 -232.960604) (xy 89.009218 -232.923767)
			(xy 89.047339 -232.892642) (xy 89.08996 -232.868035) (xy 89.135976 -232.850583) (xy 89.184195 -232.840739)
			(xy 89.23337 -232.838758) (xy 89.282225 -232.84469) (xy 89.329496 -232.858382) (xy 89.373958 -232.87948)
			(xy 89.414461 -232.907436) (xy 89.449954 -232.941528) (xy 89.479519 -232.980872) (xy 89.50239 -233.024449)
			(xy 89.517974 -233.07113) (xy 89.525869 -233.119707) (xy 89.526364 -233.144314) (xy 89.855306 -233.144314)
			(xy 89.859266 -233.09526) (xy 89.871043 -233.047476) (xy 89.890334 -233.0022) (xy 89.916637 -232.960604)
			(xy 89.949272 -232.923767) (xy 89.987393 -232.892642) (xy 90.030014 -232.868035) (xy 90.07603 -232.850583)
			(xy 90.124249 -232.840739) (xy 90.173424 -232.838758) (xy 90.222279 -232.84469) (xy 90.26955 -232.858382)
			(xy 90.314012 -232.87948) (xy 90.354515 -232.907436) (xy 90.390008 -232.941528) (xy 90.419573 -232.980872)
			(xy 90.442444 -233.024449) (xy 90.458028 -233.07113) (xy 90.465923 -233.119707) (xy 90.466418 -233.144314)
			(xy 90.784675 -233.144314) (xy 90.78877 -233.093586) (xy 90.800949 -233.044172) (xy 90.820897 -232.997352)
			(xy 90.848098 -232.954338) (xy 90.881846 -232.916244) (xy 90.921268 -232.884057) (xy 90.965342 -232.858611)
			(xy 91.012928 -232.840564) (xy 91.062792 -232.830384) (xy 91.113644 -232.828335) (xy 91.164165 -232.834469)
			(xy 91.213049 -232.848629) (xy 91.259028 -232.870446) (xy 91.300912 -232.899356) (xy 91.337616 -232.934611)
			(xy 91.368189 -232.975297) (xy 91.39184 -233.02036) (xy 91.407956 -233.068634) (xy 91.41612 -233.118868)
			(xy 91.416632 -233.144314) (xy 91.724729 -233.144314) (xy 91.728824 -233.093586) (xy 91.741003 -233.044172)
			(xy 91.760951 -232.997352) (xy 91.788152 -232.954338) (xy 91.8219 -232.916244) (xy 91.861322 -232.884057)
			(xy 91.905396 -232.858611) (xy 91.952982 -232.840564) (xy 92.002846 -232.830384) (xy 92.053698 -232.828335)
			(xy 92.104219 -232.834469) (xy 92.153103 -232.848629) (xy 92.199082 -232.870446) (xy 92.240966 -232.899356)
			(xy 92.27767 -232.934611) (xy 92.308243 -232.975297) (xy 92.331894 -233.02036) (xy 92.34801 -233.068634)
			(xy 92.356174 -233.118868) (xy 92.356686 -233.144314) (xy 92.675214 -233.144314) (xy 92.679174 -233.09526)
			(xy 92.690951 -233.047476) (xy 92.710242 -233.0022) (xy 92.736545 -232.960604) (xy 92.76918 -232.923767)
			(xy 92.807301 -232.892642) (xy 92.849922 -232.868035) (xy 92.895938 -232.850583) (xy 92.944157 -232.840739)
			(xy 92.993332 -232.838758) (xy 93.042187 -232.84469) (xy 93.089458 -232.858382) (xy 93.13392 -232.87948)
			(xy 93.174423 -232.907436) (xy 93.209916 -232.941528) (xy 93.239481 -232.980872) (xy 93.262352 -233.024449)
			(xy 93.277936 -233.07113) (xy 93.285831 -233.119707) (xy 93.286326 -233.144314) (xy 93.604837 -233.144314)
			(xy 93.608932 -233.093586) (xy 93.621111 -233.044172) (xy 93.641059 -232.997352) (xy 93.66826 -232.954338)
			(xy 93.702008 -232.916244) (xy 93.74143 -232.884057) (xy 93.785504 -232.858611) (xy 93.83309 -232.840564)
			(xy 93.882954 -232.830384) (xy 93.933806 -232.828335) (xy 93.984327 -232.834469) (xy 94.033211 -232.848629)
			(xy 94.07919 -232.870446) (xy 94.121074 -232.899356) (xy 94.157778 -232.934611) (xy 94.188351 -232.975297)
			(xy 94.212002 -233.02036) (xy 94.228118 -233.068634) (xy 94.236282 -233.118868) (xy 94.236794 -233.144314)
			(xy 94.555322 -233.144314) (xy 94.559282 -233.09526) (xy 94.571059 -233.047476) (xy 94.59035 -233.0022)
			(xy 94.616653 -232.960604) (xy 94.649288 -232.923767) (xy 94.687409 -232.892642) (xy 94.73003 -232.868035)
			(xy 94.776046 -232.850583) (xy 94.824265 -232.840739) (xy 94.87344 -232.838758) (xy 94.922295 -232.84469)
			(xy 94.969566 -232.858382) (xy 95.014028 -232.87948) (xy 95.054531 -232.907436) (xy 95.090024 -232.941528)
			(xy 95.119589 -232.980872) (xy 95.14246 -233.024449) (xy 95.158044 -233.07113) (xy 95.165939 -233.119707)
			(xy 95.166434 -233.144314) (xy 95.484691 -233.144314) (xy 95.488786 -233.093586) (xy 95.500965 -233.044172)
			(xy 95.520913 -232.997352) (xy 95.548114 -232.954338) (xy 95.581862 -232.916244) (xy 95.621284 -232.884057)
			(xy 95.665358 -232.858611) (xy 95.712944 -232.840564) (xy 95.762808 -232.830384) (xy 95.81366 -232.828335)
			(xy 95.864181 -232.834469) (xy 95.913065 -232.848629) (xy 95.959044 -232.870446) (xy 96.000928 -232.899356)
			(xy 96.037632 -232.934611) (xy 96.068205 -232.975297) (xy 96.091856 -233.02036) (xy 96.107972 -233.068634)
			(xy 96.116136 -233.118868) (xy 96.116648 -233.144314) (xy 96.116136 -233.16976) (xy 96.107972 -233.219994)
			(xy 96.091856 -233.268268) (xy 96.068205 -233.313331) (xy 96.037632 -233.354017) (xy 96.000928 -233.389272)
			(xy 95.959044 -233.418182) (xy 95.913065 -233.439999) (xy 95.864181 -233.454159) (xy 95.81366 -233.460293)
			(xy 95.762808 -233.458244) (xy 95.712944 -233.448064) (xy 95.665358 -233.430017) (xy 95.621284 -233.404571)
			(xy 95.581862 -233.372384) (xy 95.548114 -233.33429) (xy 95.520913 -233.291276) (xy 95.500965 -233.244456)
			(xy 95.488786 -233.195042) (xy 95.484691 -233.144314) (xy 95.166434 -233.144314) (xy 95.165939 -233.168921)
			(xy 95.158044 -233.217498) (xy 95.14246 -233.264179) (xy 95.119589 -233.307756) (xy 95.090024 -233.3471)
			(xy 95.054531 -233.381192) (xy 95.014028 -233.409148) (xy 94.969566 -233.430246) (xy 94.922295 -233.443938)
			(xy 94.87344 -233.44987) (xy 94.824265 -233.447889) (xy 94.776046 -233.438045) (xy 94.73003 -233.420593)
			(xy 94.687409 -233.395986) (xy 94.649288 -233.364861) (xy 94.616653 -233.328024) (xy 94.59035 -233.286428)
			(xy 94.571059 -233.241152) (xy 94.559282 -233.193368) (xy 94.555322 -233.144314) (xy 94.236794 -233.144314)
			(xy 94.236282 -233.16976) (xy 94.228118 -233.219994) (xy 94.212002 -233.268268) (xy 94.188351 -233.313331)
			(xy 94.157778 -233.354017) (xy 94.121074 -233.389272) (xy 94.07919 -233.418182) (xy 94.033211 -233.439999)
			(xy 93.984327 -233.454159) (xy 93.933806 -233.460293) (xy 93.882954 -233.458244) (xy 93.83309 -233.448064)
			(xy 93.785504 -233.430017) (xy 93.74143 -233.404571) (xy 93.702008 -233.372384) (xy 93.66826 -233.33429)
			(xy 93.641059 -233.291276) (xy 93.621111 -233.244456) (xy 93.608932 -233.195042) (xy 93.604837 -233.144314)
			(xy 93.286326 -233.144314) (xy 93.285831 -233.168921) (xy 93.277936 -233.217498) (xy 93.262352 -233.264179)
			(xy 93.239481 -233.307756) (xy 93.209916 -233.3471) (xy 93.174423 -233.381192) (xy 93.13392 -233.409148)
			(xy 93.089458 -233.430246) (xy 93.042187 -233.443938) (xy 92.993332 -233.44987) (xy 92.944157 -233.447889)
			(xy 92.895938 -233.438045) (xy 92.849922 -233.420593) (xy 92.807301 -233.395986) (xy 92.76918 -233.364861)
			(xy 92.736545 -233.328024) (xy 92.710242 -233.286428) (xy 92.690951 -233.241152) (xy 92.679174 -233.193368)
			(xy 92.675214 -233.144314) (xy 92.356686 -233.144314) (xy 92.356174 -233.16976) (xy 92.34801 -233.219994)
			(xy 92.331894 -233.268268) (xy 92.308243 -233.313331) (xy 92.27767 -233.354017) (xy 92.240966 -233.389272)
			(xy 92.199082 -233.418182) (xy 92.153103 -233.439999) (xy 92.104219 -233.454159) (xy 92.053698 -233.460293)
			(xy 92.002846 -233.458244) (xy 91.952982 -233.448064) (xy 91.905396 -233.430017) (xy 91.861322 -233.404571)
			(xy 91.8219 -233.372384) (xy 91.788152 -233.33429) (xy 91.760951 -233.291276) (xy 91.741003 -233.244456)
			(xy 91.728824 -233.195042) (xy 91.724729 -233.144314) (xy 91.416632 -233.144314) (xy 91.41612 -233.16976)
			(xy 91.407956 -233.219994) (xy 91.39184 -233.268268) (xy 91.368189 -233.313331) (xy 91.337616 -233.354017)
			(xy 91.300912 -233.389272) (xy 91.259028 -233.418182) (xy 91.213049 -233.439999) (xy 91.164165 -233.454159)
			(xy 91.113644 -233.460293) (xy 91.062792 -233.458244) (xy 91.012928 -233.448064) (xy 90.965342 -233.430017)
			(xy 90.921268 -233.404571) (xy 90.881846 -233.372384) (xy 90.848098 -233.33429) (xy 90.820897 -233.291276)
			(xy 90.800949 -233.244456) (xy 90.78877 -233.195042) (xy 90.784675 -233.144314) (xy 90.466418 -233.144314)
			(xy 90.465923 -233.168921) (xy 90.458028 -233.217498) (xy 90.442444 -233.264179) (xy 90.419573 -233.307756)
			(xy 90.390008 -233.3471) (xy 90.354515 -233.381192) (xy 90.314012 -233.409148) (xy 90.26955 -233.430246)
			(xy 90.222279 -233.443938) (xy 90.173424 -233.44987) (xy 90.124249 -233.447889) (xy 90.07603 -233.438045)
			(xy 90.030014 -233.420593) (xy 89.987393 -233.395986) (xy 89.949272 -233.364861) (xy 89.916637 -233.328024)
			(xy 89.890334 -233.286428) (xy 89.871043 -233.241152) (xy 89.859266 -233.193368) (xy 89.855306 -233.144314)
			(xy 89.526364 -233.144314) (xy 89.525869 -233.168921) (xy 89.517974 -233.217498) (xy 89.50239 -233.264179)
			(xy 89.479519 -233.307756) (xy 89.449954 -233.3471) (xy 89.414461 -233.381192) (xy 89.373958 -233.409148)
			(xy 89.329496 -233.430246) (xy 89.282225 -233.443938) (xy 89.23337 -233.44987) (xy 89.184195 -233.447889)
			(xy 89.135976 -233.438045) (xy 89.08996 -233.420593) (xy 89.047339 -233.395986) (xy 89.009218 -233.364861)
			(xy 88.976583 -233.328024) (xy 88.95028 -233.286428) (xy 88.930989 -233.241152) (xy 88.919212 -233.193368)
			(xy 88.915252 -233.144314) (xy 88.58631 -233.144314) (xy 88.585815 -233.168921) (xy 88.57792 -233.217498)
			(xy 88.562336 -233.264179) (xy 88.539465 -233.307756) (xy 88.5099 -233.3471) (xy 88.474407 -233.381192)
			(xy 88.433904 -233.409148) (xy 88.389442 -233.430246) (xy 88.342171 -233.443938) (xy 88.293316 -233.44987)
			(xy 88.244141 -233.447889) (xy 88.195922 -233.438045) (xy 88.149906 -233.420593) (xy 88.107285 -233.395986)
			(xy 88.069164 -233.364861) (xy 88.036529 -233.328024) (xy 88.010226 -233.286428) (xy 87.990935 -233.241152)
			(xy 87.979158 -233.193368) (xy 87.975198 -233.144314) (xy 87.646256 -233.144314) (xy 87.645761 -233.168921)
			(xy 87.637866 -233.217498) (xy 87.622282 -233.264179) (xy 87.599411 -233.307756) (xy 87.569846 -233.3471)
			(xy 87.534353 -233.381192) (xy 87.49385 -233.409148) (xy 87.449388 -233.430246) (xy 87.402117 -233.443938)
			(xy 87.353262 -233.44987) (xy 87.304087 -233.447889) (xy 87.255868 -233.438045) (xy 87.209852 -233.420593)
			(xy 87.167231 -233.395986) (xy 87.12911 -233.364861) (xy 87.096475 -233.328024) (xy 87.070172 -233.286428)
			(xy 87.050881 -233.241152) (xy 87.039104 -233.193368) (xy 87.035144 -233.144314) (xy 86.706456 -233.144314)
			(xy 86.705961 -233.168921) (xy 86.698066 -233.217498) (xy 86.682482 -233.264179) (xy 86.659611 -233.307756)
			(xy 86.630046 -233.3471) (xy 86.594553 -233.381192) (xy 86.55405 -233.409148) (xy 86.509588 -233.430246)
			(xy 86.462317 -233.443938) (xy 86.413462 -233.44987) (xy 86.364287 -233.447889) (xy 86.316068 -233.438045)
			(xy 86.270052 -233.420593) (xy 86.227431 -233.395986) (xy 86.18931 -233.364861) (xy 86.156675 -233.328024)
			(xy 86.130372 -233.286428) (xy 86.111081 -233.241152) (xy 86.099304 -233.193368) (xy 86.095344 -233.144314)
			(xy 85.766402 -233.144314) (xy 85.765907 -233.168921) (xy 85.758012 -233.217498) (xy 85.742428 -233.264179)
			(xy 85.719557 -233.307756) (xy 85.689992 -233.3471) (xy 85.654499 -233.381192) (xy 85.613996 -233.409148)
			(xy 85.569534 -233.430246) (xy 85.522263 -233.443938) (xy 85.473408 -233.44987) (xy 85.424233 -233.447889)
			(xy 85.376014 -233.438045) (xy 85.329998 -233.420593) (xy 85.287377 -233.395986) (xy 85.249256 -233.364861)
			(xy 85.216621 -233.328024) (xy 85.190318 -233.286428) (xy 85.171027 -233.241152) (xy 85.15925 -233.193368)
			(xy 85.15529 -233.144314) (xy 84.826348 -233.144314) (xy 84.825853 -233.168921) (xy 84.817958 -233.217498)
			(xy 84.802374 -233.264179) (xy 84.779503 -233.307756) (xy 84.749938 -233.3471) (xy 84.714445 -233.381192)
			(xy 84.673942 -233.409148) (xy 84.62948 -233.430246) (xy 84.582209 -233.443938) (xy 84.533354 -233.44987)
			(xy 84.484179 -233.447889) (xy 84.43596 -233.438045) (xy 84.389944 -233.420593) (xy 84.347323 -233.395986)
			(xy 84.309202 -233.364861) (xy 84.276567 -233.328024) (xy 84.250264 -233.286428) (xy 84.230973 -233.241152)
			(xy 84.219196 -233.193368) (xy 84.215236 -233.144314) (xy 83.886294 -233.144314) (xy 83.885822 -233.168304)
			(xy 83.878314 -233.215693) (xy 83.863486 -233.261325) (xy 83.841701 -233.304074) (xy 83.813497 -233.34289)
			(xy 83.779568 -233.376815) (xy 83.74075 -233.405016) (xy 83.697999 -233.426796) (xy 83.652366 -233.441621)
			(xy 83.604976 -233.449125) (xy 83.580986 -233.449622) (xy 83.551268 -233.448098) (xy 83.551014 -233.448098)
			(xy 83.539076 -233.447082) (xy 83.528408 -233.451146) (xy 83.522868 -233.453455) (xy 83.512981 -233.460254)
			(xy 83.50885 -233.464608) (xy 83.508088 -233.46537) (xy 83.502213 -233.472353) (xy 83.49543 -233.489281)
			(xy 83.49488 -233.49839) (xy 83.49488 -233.95432) (xy 83.745336 -233.95432) (xy 83.749296 -233.905266)
			(xy 83.761073 -233.857482) (xy 83.780364 -233.812206) (xy 83.806667 -233.77061) (xy 83.839302 -233.733773)
			(xy 83.877423 -233.702648) (xy 83.920044 -233.678041) (xy 83.96606 -233.660589) (xy 84.014279 -233.650745)
			(xy 84.063454 -233.648764) (xy 84.112309 -233.654696) (xy 84.15958 -233.668388) (xy 84.204042 -233.689486)
			(xy 84.244545 -233.717442) (xy 84.280038 -233.751534) (xy 84.309603 -233.790878) (xy 84.332474 -233.834455)
			(xy 84.348058 -233.881136) (xy 84.355953 -233.929713) (xy 84.356448 -233.95432) (xy 84.685136 -233.95432)
			(xy 84.689096 -233.905266) (xy 84.700873 -233.857482) (xy 84.720164 -233.812206) (xy 84.746467 -233.77061)
			(xy 84.779102 -233.733773) (xy 84.817223 -233.702648) (xy 84.859844 -233.678041) (xy 84.90586 -233.660589)
			(xy 84.954079 -233.650745) (xy 85.003254 -233.648764) (xy 85.052109 -233.654696) (xy 85.09938 -233.668388)
			(xy 85.143842 -233.689486) (xy 85.184345 -233.717442) (xy 85.219838 -233.751534) (xy 85.249403 -233.790878)
			(xy 85.272274 -233.834455) (xy 85.287858 -233.881136) (xy 85.295753 -233.929713) (xy 85.296248 -233.95432)
			(xy 85.62519 -233.95432) (xy 85.62915 -233.905266) (xy 85.640927 -233.857482) (xy 85.660218 -233.812206)
			(xy 85.686521 -233.77061) (xy 85.719156 -233.733773) (xy 85.757277 -233.702648) (xy 85.799898 -233.678041)
			(xy 85.845914 -233.660589) (xy 85.894133 -233.650745) (xy 85.943308 -233.648764) (xy 85.992163 -233.654696)
			(xy 86.039434 -233.668388) (xy 86.083896 -233.689486) (xy 86.124399 -233.717442) (xy 86.159892 -233.751534)
			(xy 86.189457 -233.790878) (xy 86.212328 -233.834455) (xy 86.227912 -233.881136) (xy 86.235807 -233.929713)
			(xy 86.236302 -233.95432) (xy 86.565244 -233.95432) (xy 86.569204 -233.905266) (xy 86.580981 -233.857482)
			(xy 86.600272 -233.812206) (xy 86.626575 -233.77061) (xy 86.65921 -233.733773) (xy 86.697331 -233.702648)
			(xy 86.739952 -233.678041) (xy 86.785968 -233.660589) (xy 86.834187 -233.650745) (xy 86.883362 -233.648764)
			(xy 86.932217 -233.654696) (xy 86.979488 -233.668388) (xy 87.02395 -233.689486) (xy 87.064453 -233.717442)
			(xy 87.099946 -233.751534) (xy 87.129511 -233.790878) (xy 87.152382 -233.834455) (xy 87.167966 -233.881136)
			(xy 87.175861 -233.929713) (xy 87.176356 -233.95432) (xy 87.505298 -233.95432) (xy 87.509258 -233.905266)
			(xy 87.521035 -233.857482) (xy 87.540326 -233.812206) (xy 87.566629 -233.77061) (xy 87.599264 -233.733773)
			(xy 87.637385 -233.702648) (xy 87.680006 -233.678041) (xy 87.726022 -233.660589) (xy 87.774241 -233.650745)
			(xy 87.823416 -233.648764) (xy 87.872271 -233.654696) (xy 87.919542 -233.668388) (xy 87.964004 -233.689486)
			(xy 88.004507 -233.717442) (xy 88.04 -233.751534) (xy 88.069565 -233.790878) (xy 88.092436 -233.834455)
			(xy 88.10802 -233.881136) (xy 88.115915 -233.929713) (xy 88.11641 -233.95432) (xy 88.445352 -233.95432)
			(xy 88.449312 -233.905266) (xy 88.461089 -233.857482) (xy 88.48038 -233.812206) (xy 88.506683 -233.77061)
			(xy 88.539318 -233.733773) (xy 88.577439 -233.702648) (xy 88.62006 -233.678041) (xy 88.666076 -233.660589)
			(xy 88.714295 -233.650745) (xy 88.76347 -233.648764) (xy 88.812325 -233.654696) (xy 88.859596 -233.668388)
			(xy 88.904058 -233.689486) (xy 88.944561 -233.717442) (xy 88.980054 -233.751534) (xy 89.009619 -233.790878)
			(xy 89.03249 -233.834455) (xy 89.048074 -233.881136) (xy 89.055969 -233.929713) (xy 89.056464 -233.95432)
			(xy 89.385152 -233.95432) (xy 89.389112 -233.905266) (xy 89.400889 -233.857482) (xy 89.42018 -233.812206)
			(xy 89.446483 -233.77061) (xy 89.479118 -233.733773) (xy 89.517239 -233.702648) (xy 89.55986 -233.678041)
			(xy 89.605876 -233.660589) (xy 89.654095 -233.650745) (xy 89.70327 -233.648764) (xy 89.752125 -233.654696)
			(xy 89.799396 -233.668388) (xy 89.843858 -233.689486) (xy 89.884361 -233.717442) (xy 89.919854 -233.751534)
			(xy 89.949419 -233.790878) (xy 89.97229 -233.834455) (xy 89.987874 -233.881136) (xy 89.995769 -233.929713)
			(xy 89.996264 -233.95432) (xy 90.314775 -233.95432) (xy 90.31887 -233.903592) (xy 90.331049 -233.854178)
			(xy 90.350997 -233.807358) (xy 90.378198 -233.764344) (xy 90.411946 -233.72625) (xy 90.451368 -233.694063)
			(xy 90.495442 -233.668617) (xy 90.543028 -233.65057) (xy 90.592892 -233.64039) (xy 90.643744 -233.638341)
			(xy 90.694265 -233.644475) (xy 90.743149 -233.658635) (xy 90.789128 -233.680452) (xy 90.831012 -233.709362)
			(xy 90.867716 -233.744617) (xy 90.898289 -233.785303) (xy 90.92194 -233.830366) (xy 90.938056 -233.87864)
			(xy 90.94622 -233.928874) (xy 90.946732 -233.95432) (xy 91.26526 -233.95432) (xy 91.26922 -233.905266)
			(xy 91.280997 -233.857482) (xy 91.300288 -233.812206) (xy 91.326591 -233.77061) (xy 91.359226 -233.733773)
			(xy 91.397347 -233.702648) (xy 91.439968 -233.678041) (xy 91.485984 -233.660589) (xy 91.534203 -233.650745)
			(xy 91.583378 -233.648764) (xy 91.632233 -233.654696) (xy 91.679504 -233.668388) (xy 91.723966 -233.689486)
			(xy 91.764469 -233.717442) (xy 91.799962 -233.751534) (xy 91.829527 -233.790878) (xy 91.852398 -233.834455)
			(xy 91.867982 -233.881136) (xy 91.875877 -233.929713) (xy 91.876372 -233.95432) (xy 92.194883 -233.95432)
			(xy 92.198978 -233.903592) (xy 92.211157 -233.854178) (xy 92.231105 -233.807358) (xy 92.258306 -233.764344)
			(xy 92.292054 -233.72625) (xy 92.331476 -233.694063) (xy 92.37555 -233.668617) (xy 92.423136 -233.65057)
			(xy 92.473 -233.64039) (xy 92.523852 -233.638341) (xy 92.574373 -233.644475) (xy 92.623257 -233.658635)
			(xy 92.669236 -233.680452) (xy 92.71112 -233.709362) (xy 92.747824 -233.744617) (xy 92.778397 -233.785303)
			(xy 92.802048 -233.830366) (xy 92.818164 -233.87864) (xy 92.826328 -233.928874) (xy 92.82684 -233.95432)
			(xy 93.145114 -233.95432) (xy 93.149074 -233.905266) (xy 93.160851 -233.857482) (xy 93.180142 -233.812206)
			(xy 93.206445 -233.77061) (xy 93.23908 -233.733773) (xy 93.277201 -233.702648) (xy 93.319822 -233.678041)
			(xy 93.365838 -233.660589) (xy 93.414057 -233.650745) (xy 93.463232 -233.648764) (xy 93.512087 -233.654696)
			(xy 93.559358 -233.668388) (xy 93.60382 -233.689486) (xy 93.644323 -233.717442) (xy 93.679816 -233.751534)
			(xy 93.709381 -233.790878) (xy 93.732252 -233.834455) (xy 93.747836 -233.881136) (xy 93.755731 -233.929713)
			(xy 93.756226 -233.95432) (xy 94.074737 -233.95432) (xy 94.078832 -233.903592) (xy 94.091011 -233.854178)
			(xy 94.110959 -233.807358) (xy 94.13816 -233.764344) (xy 94.171908 -233.72625) (xy 94.21133 -233.694063)
			(xy 94.255404 -233.668617) (xy 94.30299 -233.65057) (xy 94.352854 -233.64039) (xy 94.403706 -233.638341)
			(xy 94.454227 -233.644475) (xy 94.503111 -233.658635) (xy 94.54909 -233.680452) (xy 94.590974 -233.709362)
			(xy 94.627678 -233.744617) (xy 94.658251 -233.785303) (xy 94.681902 -233.830366) (xy 94.698018 -233.87864)
			(xy 94.706182 -233.928874) (xy 94.706694 -233.95432) (xy 95.014791 -233.95432) (xy 95.018886 -233.903592)
			(xy 95.031065 -233.854178) (xy 95.051013 -233.807358) (xy 95.078214 -233.764344) (xy 95.111962 -233.72625)
			(xy 95.151384 -233.694063) (xy 95.195458 -233.668617) (xy 95.243044 -233.65057) (xy 95.292908 -233.64039)
			(xy 95.34376 -233.638341) (xy 95.394281 -233.644475) (xy 95.443165 -233.658635) (xy 95.489144 -233.680452)
			(xy 95.531028 -233.709362) (xy 95.567732 -233.744617) (xy 95.598305 -233.785303) (xy 95.621956 -233.830366)
			(xy 95.638072 -233.87864) (xy 95.646236 -233.928874) (xy 95.646748 -233.95432) (xy 95.965276 -233.95432)
			(xy 95.969236 -233.905266) (xy 95.981013 -233.857482) (xy 96.000304 -233.812206) (xy 96.026607 -233.77061)
			(xy 96.059242 -233.733773) (xy 96.097363 -233.702648) (xy 96.139984 -233.678041) (xy 96.186 -233.660589)
			(xy 96.234219 -233.650745) (xy 96.283394 -233.648764) (xy 96.332249 -233.654696) (xy 96.37952 -233.668388)
			(xy 96.423982 -233.689486) (xy 96.464485 -233.717442) (xy 96.499978 -233.751534) (xy 96.529543 -233.790878)
			(xy 96.552414 -233.834455) (xy 96.567998 -233.881136) (xy 96.575893 -233.929713) (xy 96.576388 -233.95432)
			(xy 96.575893 -233.978927) (xy 96.567998 -234.027504) (xy 96.552414 -234.074185) (xy 96.529543 -234.117762)
			(xy 96.499978 -234.157106) (xy 96.464485 -234.191198) (xy 96.423982 -234.219154) (xy 96.37952 -234.240252)
			(xy 96.332249 -234.253944) (xy 96.283394 -234.259876) (xy 96.234219 -234.257895) (xy 96.186 -234.248051)
			(xy 96.139984 -234.230599) (xy 96.097363 -234.205992) (xy 96.059242 -234.174867) (xy 96.026607 -234.13803)
			(xy 96.000304 -234.096434) (xy 95.981013 -234.051158) (xy 95.969236 -234.003374) (xy 95.965276 -233.95432)
			(xy 95.646748 -233.95432) (xy 95.646236 -233.979766) (xy 95.638072 -234.03) (xy 95.621956 -234.078274)
			(xy 95.598305 -234.123337) (xy 95.567732 -234.164023) (xy 95.531028 -234.199278) (xy 95.489144 -234.228188)
			(xy 95.443165 -234.250005) (xy 95.394281 -234.264165) (xy 95.34376 -234.270299) (xy 95.292908 -234.26825)
			(xy 95.243044 -234.25807) (xy 95.195458 -234.240023) (xy 95.151384 -234.214577) (xy 95.111962 -234.18239)
			(xy 95.078214 -234.144296) (xy 95.051013 -234.101282) (xy 95.031065 -234.054462) (xy 95.018886 -234.005048)
			(xy 95.014791 -233.95432) (xy 94.706694 -233.95432) (xy 94.706182 -233.979766) (xy 94.698018 -234.03)
			(xy 94.681902 -234.078274) (xy 94.658251 -234.123337) (xy 94.627678 -234.164023) (xy 94.590974 -234.199278)
			(xy 94.54909 -234.228188) (xy 94.503111 -234.250005) (xy 94.454227 -234.264165) (xy 94.403706 -234.270299)
			(xy 94.352854 -234.26825) (xy 94.30299 -234.25807) (xy 94.255404 -234.240023) (xy 94.21133 -234.214577)
			(xy 94.171908 -234.18239) (xy 94.13816 -234.144296) (xy 94.110959 -234.101282) (xy 94.091011 -234.054462)
			(xy 94.078832 -234.005048) (xy 94.074737 -233.95432) (xy 93.756226 -233.95432) (xy 93.755731 -233.978927)
			(xy 93.747836 -234.027504) (xy 93.732252 -234.074185) (xy 93.709381 -234.117762) (xy 93.679816 -234.157106)
			(xy 93.644323 -234.191198) (xy 93.60382 -234.219154) (xy 93.559358 -234.240252) (xy 93.512087 -234.253944)
			(xy 93.463232 -234.259876) (xy 93.414057 -234.257895) (xy 93.365838 -234.248051) (xy 93.319822 -234.230599)
			(xy 93.277201 -234.205992) (xy 93.23908 -234.174867) (xy 93.206445 -234.13803) (xy 93.180142 -234.096434)
			(xy 93.160851 -234.051158) (xy 93.149074 -234.003374) (xy 93.145114 -233.95432) (xy 92.82684 -233.95432)
			(xy 92.826328 -233.979766) (xy 92.818164 -234.03) (xy 92.802048 -234.078274) (xy 92.778397 -234.123337)
			(xy 92.747824 -234.164023) (xy 92.71112 -234.199278) (xy 92.669236 -234.228188) (xy 92.623257 -234.250005)
			(xy 92.574373 -234.264165) (xy 92.523852 -234.270299) (xy 92.473 -234.26825) (xy 92.423136 -234.25807)
			(xy 92.37555 -234.240023) (xy 92.331476 -234.214577) (xy 92.292054 -234.18239) (xy 92.258306 -234.144296)
			(xy 92.231105 -234.101282) (xy 92.211157 -234.054462) (xy 92.198978 -234.005048) (xy 92.194883 -233.95432)
			(xy 91.876372 -233.95432) (xy 91.875877 -233.978927) (xy 91.867982 -234.027504) (xy 91.852398 -234.074185)
			(xy 91.829527 -234.117762) (xy 91.799962 -234.157106) (xy 91.764469 -234.191198) (xy 91.723966 -234.219154)
			(xy 91.679504 -234.240252) (xy 91.632233 -234.253944) (xy 91.583378 -234.259876) (xy 91.534203 -234.257895)
			(xy 91.485984 -234.248051) (xy 91.439968 -234.230599) (xy 91.397347 -234.205992) (xy 91.359226 -234.174867)
			(xy 91.326591 -234.13803) (xy 91.300288 -234.096434) (xy 91.280997 -234.051158) (xy 91.26922 -234.003374)
			(xy 91.26526 -233.95432) (xy 90.946732 -233.95432) (xy 90.94622 -233.979766) (xy 90.938056 -234.03)
			(xy 90.92194 -234.078274) (xy 90.898289 -234.123337) (xy 90.867716 -234.164023) (xy 90.831012 -234.199278)
			(xy 90.789128 -234.228188) (xy 90.743149 -234.250005) (xy 90.694265 -234.264165) (xy 90.643744 -234.270299)
			(xy 90.592892 -234.26825) (xy 90.543028 -234.25807) (xy 90.495442 -234.240023) (xy 90.451368 -234.214577)
			(xy 90.411946 -234.18239) (xy 90.378198 -234.144296) (xy 90.350997 -234.101282) (xy 90.331049 -234.054462)
			(xy 90.31887 -234.005048) (xy 90.314775 -233.95432) (xy 89.996264 -233.95432) (xy 89.995769 -233.978927)
			(xy 89.987874 -234.027504) (xy 89.97229 -234.074185) (xy 89.949419 -234.117762) (xy 89.919854 -234.157106)
			(xy 89.884361 -234.191198) (xy 89.843858 -234.219154) (xy 89.799396 -234.240252) (xy 89.752125 -234.253944)
			(xy 89.70327 -234.259876) (xy 89.654095 -234.257895) (xy 89.605876 -234.248051) (xy 89.55986 -234.230599)
			(xy 89.517239 -234.205992) (xy 89.479118 -234.174867) (xy 89.446483 -234.13803) (xy 89.42018 -234.096434)
			(xy 89.400889 -234.051158) (xy 89.389112 -234.003374) (xy 89.385152 -233.95432) (xy 89.056464 -233.95432)
			(xy 89.055969 -233.978927) (xy 89.048074 -234.027504) (xy 89.03249 -234.074185) (xy 89.009619 -234.117762)
			(xy 88.980054 -234.157106) (xy 88.944561 -234.191198) (xy 88.904058 -234.219154) (xy 88.859596 -234.240252)
			(xy 88.812325 -234.253944) (xy 88.76347 -234.259876) (xy 88.714295 -234.257895) (xy 88.666076 -234.248051)
			(xy 88.62006 -234.230599) (xy 88.577439 -234.205992) (xy 88.539318 -234.174867) (xy 88.506683 -234.13803)
			(xy 88.48038 -234.096434) (xy 88.461089 -234.051158) (xy 88.449312 -234.003374) (xy 88.445352 -233.95432)
			(xy 88.11641 -233.95432) (xy 88.115915 -233.978927) (xy 88.10802 -234.027504) (xy 88.092436 -234.074185)
			(xy 88.069565 -234.117762) (xy 88.04 -234.157106) (xy 88.004507 -234.191198) (xy 87.964004 -234.219154)
			(xy 87.919542 -234.240252) (xy 87.872271 -234.253944) (xy 87.823416 -234.259876) (xy 87.774241 -234.257895)
			(xy 87.726022 -234.248051) (xy 87.680006 -234.230599) (xy 87.637385 -234.205992) (xy 87.599264 -234.174867)
			(xy 87.566629 -234.13803) (xy 87.540326 -234.096434) (xy 87.521035 -234.051158) (xy 87.509258 -234.003374)
			(xy 87.505298 -233.95432) (xy 87.176356 -233.95432) (xy 87.175861 -233.978927) (xy 87.167966 -234.027504)
			(xy 87.152382 -234.074185) (xy 87.129511 -234.117762) (xy 87.099946 -234.157106) (xy 87.064453 -234.191198)
			(xy 87.02395 -234.219154) (xy 86.979488 -234.240252) (xy 86.932217 -234.253944) (xy 86.883362 -234.259876)
			(xy 86.834187 -234.257895) (xy 86.785968 -234.248051) (xy 86.739952 -234.230599) (xy 86.697331 -234.205992)
			(xy 86.65921 -234.174867) (xy 86.626575 -234.13803) (xy 86.600272 -234.096434) (xy 86.580981 -234.051158)
			(xy 86.569204 -234.003374) (xy 86.565244 -233.95432) (xy 86.236302 -233.95432) (xy 86.235807 -233.978927)
			(xy 86.227912 -234.027504) (xy 86.212328 -234.074185) (xy 86.189457 -234.117762) (xy 86.159892 -234.157106)
			(xy 86.124399 -234.191198) (xy 86.083896 -234.219154) (xy 86.039434 -234.240252) (xy 85.992163 -234.253944)
			(xy 85.943308 -234.259876) (xy 85.894133 -234.257895) (xy 85.845914 -234.248051) (xy 85.799898 -234.230599)
			(xy 85.757277 -234.205992) (xy 85.719156 -234.174867) (xy 85.686521 -234.13803) (xy 85.660218 -234.096434)
			(xy 85.640927 -234.051158) (xy 85.62915 -234.003374) (xy 85.62519 -233.95432) (xy 85.296248 -233.95432)
			(xy 85.295753 -233.978927) (xy 85.287858 -234.027504) (xy 85.272274 -234.074185) (xy 85.249403 -234.117762)
			(xy 85.219838 -234.157106) (xy 85.184345 -234.191198) (xy 85.143842 -234.219154) (xy 85.09938 -234.240252)
			(xy 85.052109 -234.253944) (xy 85.003254 -234.259876) (xy 84.954079 -234.257895) (xy 84.90586 -234.248051)
			(xy 84.859844 -234.230599) (xy 84.817223 -234.205992) (xy 84.779102 -234.174867) (xy 84.746467 -234.13803)
			(xy 84.720164 -234.096434) (xy 84.700873 -234.051158) (xy 84.689096 -234.003374) (xy 84.685136 -233.95432)
			(xy 84.356448 -233.95432) (xy 84.355953 -233.978927) (xy 84.348058 -234.027504) (xy 84.332474 -234.074185)
			(xy 84.309603 -234.117762) (xy 84.280038 -234.157106) (xy 84.244545 -234.191198) (xy 84.204042 -234.219154)
			(xy 84.15958 -234.240252) (xy 84.112309 -234.253944) (xy 84.063454 -234.259876) (xy 84.014279 -234.257895)
			(xy 83.96606 -234.248051) (xy 83.920044 -234.230599) (xy 83.877423 -234.205992) (xy 83.839302 -234.174867)
			(xy 83.806667 -234.13803) (xy 83.780364 -234.096434) (xy 83.761073 -234.051158) (xy 83.749296 -234.003374)
			(xy 83.745336 -233.95432) (xy 83.49488 -233.95432) (xy 83.49488 -234.311444) (xy 83.494974 -234.315994)
			(xy 83.496643 -234.324941) (xy 83.498182 -234.329224) (xy 83.501738 -234.338622) (xy 83.537298 -234.377992)
			(xy 83.552792 -234.395264) (xy 83.559904 -234.401614) (xy 83.561936 -234.402884) (xy 83.567778 -234.40644)
			(xy 83.576414 -234.410504) (xy 83.585558 -234.41152) (xy 83.585812 -234.41152) (xy 83.60941 -234.414257)
			(xy 83.655414 -234.426098) (xy 83.69903 -234.444919) (xy 83.739205 -234.470266) (xy 83.774972 -234.501529)
			(xy 83.805467 -234.537952) (xy 83.829954 -234.578658) (xy 83.839304 -234.600496) (xy 83.84286 -234.6071)
			(xy 83.843114 -234.607608) (xy 83.856648 -234.631488) (xy 83.875911 -234.68288) (xy 83.885697 -234.736884)
			(xy 83.886294 -234.764326) (xy 84.215236 -234.764326) (xy 84.219196 -234.715272) (xy 84.230973 -234.667488)
			(xy 84.250264 -234.622212) (xy 84.276567 -234.580616) (xy 84.309202 -234.543779) (xy 84.347323 -234.512654)
			(xy 84.389944 -234.488047) (xy 84.43596 -234.470595) (xy 84.484179 -234.460751) (xy 84.533354 -234.45877)
			(xy 84.582209 -234.464702) (xy 84.62948 -234.478394) (xy 84.673942 -234.499492) (xy 84.714445 -234.527448)
			(xy 84.749938 -234.56154) (xy 84.779503 -234.600884) (xy 84.802374 -234.644461) (xy 84.817958 -234.691142)
			(xy 84.825853 -234.739719) (xy 84.826348 -234.764326) (xy 85.15529 -234.764326) (xy 85.15925 -234.715272)
			(xy 85.171027 -234.667488) (xy 85.190318 -234.622212) (xy 85.216621 -234.580616) (xy 85.249256 -234.543779)
			(xy 85.287377 -234.512654) (xy 85.329998 -234.488047) (xy 85.376014 -234.470595) (xy 85.424233 -234.460751)
			(xy 85.473408 -234.45877) (xy 85.522263 -234.464702) (xy 85.569534 -234.478394) (xy 85.613996 -234.499492)
			(xy 85.654499 -234.527448) (xy 85.689992 -234.56154) (xy 85.719557 -234.600884) (xy 85.742428 -234.644461)
			(xy 85.758012 -234.691142) (xy 85.765907 -234.739719) (xy 85.766402 -234.764326) (xy 87.035144 -234.764326)
			(xy 87.039104 -234.715272) (xy 87.050881 -234.667488) (xy 87.070172 -234.622212) (xy 87.096475 -234.580616)
			(xy 87.12911 -234.543779) (xy 87.167231 -234.512654) (xy 87.209852 -234.488047) (xy 87.255868 -234.470595)
			(xy 87.304087 -234.460751) (xy 87.353262 -234.45877) (xy 87.402117 -234.464702) (xy 87.449388 -234.478394)
			(xy 87.49385 -234.499492) (xy 87.534353 -234.527448) (xy 87.569846 -234.56154) (xy 87.599411 -234.600884)
			(xy 87.622282 -234.644461) (xy 87.637866 -234.691142) (xy 87.645761 -234.739719) (xy 87.646256 -234.764326)
			(xy 87.975198 -234.764326) (xy 87.979158 -234.715272) (xy 87.990935 -234.667488) (xy 88.010226 -234.622212)
			(xy 88.036529 -234.580616) (xy 88.069164 -234.543779) (xy 88.107285 -234.512654) (xy 88.149906 -234.488047)
			(xy 88.195922 -234.470595) (xy 88.244141 -234.460751) (xy 88.293316 -234.45877) (xy 88.342171 -234.464702)
			(xy 88.389442 -234.478394) (xy 88.433904 -234.499492) (xy 88.474407 -234.527448) (xy 88.5099 -234.56154)
			(xy 88.539465 -234.600884) (xy 88.562336 -234.644461) (xy 88.57792 -234.691142) (xy 88.585815 -234.739719)
			(xy 88.58631 -234.764326) (xy 88.915252 -234.764326) (xy 88.919212 -234.715272) (xy 88.930989 -234.667488)
			(xy 88.95028 -234.622212) (xy 88.976583 -234.580616) (xy 89.009218 -234.543779) (xy 89.047339 -234.512654)
			(xy 89.08996 -234.488047) (xy 89.135976 -234.470595) (xy 89.184195 -234.460751) (xy 89.23337 -234.45877)
			(xy 89.282225 -234.464702) (xy 89.329496 -234.478394) (xy 89.373958 -234.499492) (xy 89.414461 -234.527448)
			(xy 89.449954 -234.56154) (xy 89.479519 -234.600884) (xy 89.50239 -234.644461) (xy 89.517974 -234.691142)
			(xy 89.525869 -234.739719) (xy 89.526364 -234.764326) (xy 89.855306 -234.764326) (xy 89.859266 -234.715272)
			(xy 89.871043 -234.667488) (xy 89.890334 -234.622212) (xy 89.916637 -234.580616) (xy 89.949272 -234.543779)
			(xy 89.987393 -234.512654) (xy 90.030014 -234.488047) (xy 90.07603 -234.470595) (xy 90.124249 -234.460751)
			(xy 90.173424 -234.45877) (xy 90.222279 -234.464702) (xy 90.26955 -234.478394) (xy 90.314012 -234.499492)
			(xy 90.354515 -234.527448) (xy 90.390008 -234.56154) (xy 90.419573 -234.600884) (xy 90.442444 -234.644461)
			(xy 90.458028 -234.691142) (xy 90.465923 -234.739719) (xy 90.466418 -234.764326) (xy 90.784675 -234.764326)
			(xy 90.78877 -234.713598) (xy 90.800949 -234.664184) (xy 90.820897 -234.617364) (xy 90.848098 -234.57435)
			(xy 90.881846 -234.536256) (xy 90.921268 -234.504069) (xy 90.965342 -234.478623) (xy 91.012928 -234.460576)
			(xy 91.062792 -234.450396) (xy 91.113644 -234.448347) (xy 91.164165 -234.454481) (xy 91.213049 -234.468641)
			(xy 91.259028 -234.490458) (xy 91.300912 -234.519368) (xy 91.337616 -234.554623) (xy 91.368189 -234.595309)
			(xy 91.39184 -234.640372) (xy 91.407956 -234.688646) (xy 91.41612 -234.73888) (xy 91.416632 -234.764326)
			(xy 91.724729 -234.764326) (xy 91.728824 -234.713598) (xy 91.741003 -234.664184) (xy 91.760951 -234.617364)
			(xy 91.788152 -234.57435) (xy 91.8219 -234.536256) (xy 91.861322 -234.504069) (xy 91.905396 -234.478623)
			(xy 91.952982 -234.460576) (xy 92.002846 -234.450396) (xy 92.053698 -234.448347) (xy 92.104219 -234.454481)
			(xy 92.153103 -234.468641) (xy 92.199082 -234.490458) (xy 92.240966 -234.519368) (xy 92.27767 -234.554623)
			(xy 92.308243 -234.595309) (xy 92.331894 -234.640372) (xy 92.34801 -234.688646) (xy 92.356174 -234.73888)
			(xy 92.356686 -234.764326) (xy 93.604837 -234.764326) (xy 93.608932 -234.713598) (xy 93.621111 -234.664184)
			(xy 93.641059 -234.617364) (xy 93.66826 -234.57435) (xy 93.702008 -234.536256) (xy 93.74143 -234.504069)
			(xy 93.785504 -234.478623) (xy 93.83309 -234.460576) (xy 93.882954 -234.450396) (xy 93.933806 -234.448347)
			(xy 93.984327 -234.454481) (xy 94.033211 -234.468641) (xy 94.07919 -234.490458) (xy 94.121074 -234.519368)
			(xy 94.157778 -234.554623) (xy 94.188351 -234.595309) (xy 94.212002 -234.640372) (xy 94.228118 -234.688646)
			(xy 94.236282 -234.73888) (xy 94.236794 -234.764326) (xy 94.555322 -234.764326) (xy 94.559282 -234.715272)
			(xy 94.571059 -234.667488) (xy 94.59035 -234.622212) (xy 94.616653 -234.580616) (xy 94.649288 -234.543779)
			(xy 94.687409 -234.512654) (xy 94.73003 -234.488047) (xy 94.776046 -234.470595) (xy 94.824265 -234.460751)
			(xy 94.87344 -234.45877) (xy 94.922295 -234.464702) (xy 94.969566 -234.478394) (xy 95.014028 -234.499492)
			(xy 95.054531 -234.527448) (xy 95.090024 -234.56154) (xy 95.119589 -234.600884) (xy 95.14246 -234.644461)
			(xy 95.158044 -234.691142) (xy 95.165939 -234.739719) (xy 95.166434 -234.764326) (xy 95.484691 -234.764326)
			(xy 95.488786 -234.713598) (xy 95.500965 -234.664184) (xy 95.520913 -234.617364) (xy 95.548114 -234.57435)
			(xy 95.581862 -234.536256) (xy 95.621284 -234.504069) (xy 95.665358 -234.478623) (xy 95.712944 -234.460576)
			(xy 95.762808 -234.450396) (xy 95.81366 -234.448347) (xy 95.864181 -234.454481) (xy 95.913065 -234.468641)
			(xy 95.959044 -234.490458) (xy 96.000928 -234.519368) (xy 96.037632 -234.554623) (xy 96.068205 -234.595309)
			(xy 96.091856 -234.640372) (xy 96.107972 -234.688646) (xy 96.116136 -234.73888) (xy 96.116648 -234.764326)
			(xy 96.116136 -234.789772) (xy 96.107972 -234.840006) (xy 96.091856 -234.88828) (xy 96.068205 -234.933343)
			(xy 96.037632 -234.974029) (xy 96.000928 -235.009284) (xy 95.959044 -235.038194) (xy 95.913065 -235.060011)
			(xy 95.864181 -235.074171) (xy 95.81366 -235.080305) (xy 95.762808 -235.078256) (xy 95.712944 -235.068076)
			(xy 95.665358 -235.050029) (xy 95.621284 -235.024583) (xy 95.581862 -234.992396) (xy 95.548114 -234.954302)
			(xy 95.520913 -234.911288) (xy 95.500965 -234.864468) (xy 95.488786 -234.815054) (xy 95.484691 -234.764326)
			(xy 95.166434 -234.764326) (xy 95.165939 -234.788933) (xy 95.158044 -234.83751) (xy 95.14246 -234.884191)
			(xy 95.119589 -234.927768) (xy 95.090024 -234.967112) (xy 95.054531 -235.001204) (xy 95.014028 -235.02916)
			(xy 94.969566 -235.050258) (xy 94.922295 -235.06395) (xy 94.87344 -235.069882) (xy 94.824265 -235.067901)
			(xy 94.776046 -235.058057) (xy 94.73003 -235.040605) (xy 94.687409 -235.015998) (xy 94.649288 -234.984873)
			(xy 94.616653 -234.948036) (xy 94.59035 -234.90644) (xy 94.571059 -234.861164) (xy 94.559282 -234.81338)
			(xy 94.555322 -234.764326) (xy 94.236794 -234.764326) (xy 94.236282 -234.789772) (xy 94.228118 -234.840006)
			(xy 94.212002 -234.88828) (xy 94.188351 -234.933343) (xy 94.157778 -234.974029) (xy 94.121074 -235.009284)
			(xy 94.07919 -235.038194) (xy 94.033211 -235.060011) (xy 93.984327 -235.074171) (xy 93.933806 -235.080305)
			(xy 93.882954 -235.078256) (xy 93.83309 -235.068076) (xy 93.785504 -235.050029) (xy 93.74143 -235.024583)
			(xy 93.702008 -234.992396) (xy 93.66826 -234.954302) (xy 93.641059 -234.911288) (xy 93.621111 -234.864468)
			(xy 93.608932 -234.815054) (xy 93.604837 -234.764326) (xy 92.356686 -234.764326) (xy 92.356174 -234.789772)
			(xy 92.34801 -234.840006) (xy 92.331894 -234.88828) (xy 92.308243 -234.933343) (xy 92.27767 -234.974029)
			(xy 92.240966 -235.009284) (xy 92.199082 -235.038194) (xy 92.153103 -235.060011) (xy 92.104219 -235.074171)
			(xy 92.053698 -235.080305) (xy 92.002846 -235.078256) (xy 91.952982 -235.068076) (xy 91.905396 -235.050029)
			(xy 91.861322 -235.024583) (xy 91.8219 -234.992396) (xy 91.788152 -234.954302) (xy 91.760951 -234.911288)
			(xy 91.741003 -234.864468) (xy 91.728824 -234.815054) (xy 91.724729 -234.764326) (xy 91.416632 -234.764326)
			(xy 91.41612 -234.789772) (xy 91.407956 -234.840006) (xy 91.39184 -234.88828) (xy 91.368189 -234.933343)
			(xy 91.337616 -234.974029) (xy 91.300912 -235.009284) (xy 91.259028 -235.038194) (xy 91.213049 -235.060011)
			(xy 91.164165 -235.074171) (xy 91.113644 -235.080305) (xy 91.062792 -235.078256) (xy 91.012928 -235.068076)
			(xy 90.965342 -235.050029) (xy 90.921268 -235.024583) (xy 90.881846 -234.992396) (xy 90.848098 -234.954302)
			(xy 90.820897 -234.911288) (xy 90.800949 -234.864468) (xy 90.78877 -234.815054) (xy 90.784675 -234.764326)
			(xy 90.466418 -234.764326) (xy 90.465923 -234.788933) (xy 90.458028 -234.83751) (xy 90.442444 -234.884191)
			(xy 90.419573 -234.927768) (xy 90.390008 -234.967112) (xy 90.354515 -235.001204) (xy 90.314012 -235.02916)
			(xy 90.26955 -235.050258) (xy 90.222279 -235.06395) (xy 90.173424 -235.069882) (xy 90.124249 -235.067901)
			(xy 90.07603 -235.058057) (xy 90.030014 -235.040605) (xy 89.987393 -235.015998) (xy 89.949272 -234.984873)
			(xy 89.916637 -234.948036) (xy 89.890334 -234.90644) (xy 89.871043 -234.861164) (xy 89.859266 -234.81338)
			(xy 89.855306 -234.764326) (xy 89.526364 -234.764326) (xy 89.525869 -234.788933) (xy 89.517974 -234.83751)
			(xy 89.50239 -234.884191) (xy 89.479519 -234.927768) (xy 89.449954 -234.967112) (xy 89.414461 -235.001204)
			(xy 89.373958 -235.02916) (xy 89.329496 -235.050258) (xy 89.282225 -235.06395) (xy 89.23337 -235.069882)
			(xy 89.184195 -235.067901) (xy 89.135976 -235.058057) (xy 89.08996 -235.040605) (xy 89.047339 -235.015998)
			(xy 89.009218 -234.984873) (xy 88.976583 -234.948036) (xy 88.95028 -234.90644) (xy 88.930989 -234.861164)
			(xy 88.919212 -234.81338) (xy 88.915252 -234.764326) (xy 88.58631 -234.764326) (xy 88.585815 -234.788933)
			(xy 88.57792 -234.83751) (xy 88.562336 -234.884191) (xy 88.539465 -234.927768) (xy 88.5099 -234.967112)
			(xy 88.474407 -235.001204) (xy 88.433904 -235.02916) (xy 88.389442 -235.050258) (xy 88.342171 -235.06395)
			(xy 88.293316 -235.069882) (xy 88.244141 -235.067901) (xy 88.195922 -235.058057) (xy 88.149906 -235.040605)
			(xy 88.107285 -235.015998) (xy 88.069164 -234.984873) (xy 88.036529 -234.948036) (xy 88.010226 -234.90644)
			(xy 87.990935 -234.861164) (xy 87.979158 -234.81338) (xy 87.975198 -234.764326) (xy 87.646256 -234.764326)
			(xy 87.645761 -234.788933) (xy 87.637866 -234.83751) (xy 87.622282 -234.884191) (xy 87.599411 -234.927768)
			(xy 87.569846 -234.967112) (xy 87.534353 -235.001204) (xy 87.49385 -235.02916) (xy 87.449388 -235.050258)
			(xy 87.402117 -235.06395) (xy 87.353262 -235.069882) (xy 87.304087 -235.067901) (xy 87.255868 -235.058057)
			(xy 87.209852 -235.040605) (xy 87.167231 -235.015998) (xy 87.12911 -234.984873) (xy 87.096475 -234.948036)
			(xy 87.070172 -234.90644) (xy 87.050881 -234.861164) (xy 87.039104 -234.81338) (xy 87.035144 -234.764326)
			(xy 85.766402 -234.764326) (xy 85.765907 -234.788933) (xy 85.758012 -234.83751) (xy 85.742428 -234.884191)
			(xy 85.719557 -234.927768) (xy 85.689992 -234.967112) (xy 85.654499 -235.001204) (xy 85.613996 -235.02916)
			(xy 85.569534 -235.050258) (xy 85.522263 -235.06395) (xy 85.473408 -235.069882) (xy 85.424233 -235.067901)
			(xy 85.376014 -235.058057) (xy 85.329998 -235.040605) (xy 85.287377 -235.015998) (xy 85.249256 -234.984873)
			(xy 85.216621 -234.948036) (xy 85.190318 -234.90644) (xy 85.171027 -234.861164) (xy 85.15925 -234.81338)
			(xy 85.15529 -234.764326) (xy 84.826348 -234.764326) (xy 84.825853 -234.788933) (xy 84.817958 -234.83751)
			(xy 84.802374 -234.884191) (xy 84.779503 -234.927768) (xy 84.749938 -234.967112) (xy 84.714445 -235.001204)
			(xy 84.673942 -235.02916) (xy 84.62948 -235.050258) (xy 84.582209 -235.06395) (xy 84.533354 -235.069882)
			(xy 84.484179 -235.067901) (xy 84.43596 -235.058057) (xy 84.389944 -235.040605) (xy 84.347323 -235.015998)
			(xy 84.309202 -234.984873) (xy 84.276567 -234.948036) (xy 84.250264 -234.90644) (xy 84.230973 -234.861164)
			(xy 84.219196 -234.81338) (xy 84.215236 -234.764326) (xy 83.886294 -234.764326) (xy 83.885821 -234.788315)
			(xy 83.878312 -234.835703) (xy 83.863482 -234.881333) (xy 83.841697 -234.924081) (xy 83.813493 -234.962895)
			(xy 83.779564 -234.996819) (xy 83.740747 -235.025018) (xy 83.697996 -235.046797) (xy 83.652364 -235.061621)
			(xy 83.604976 -235.069125) (xy 83.580986 -235.069634) (xy 83.551268 -235.06811) (xy 83.551014 -235.06811)
			(xy 83.539076 -235.067094) (xy 83.528408 -235.071158) (xy 83.522868 -235.073468) (xy 83.512982 -235.080268)
			(xy 83.50885 -235.08462) (xy 83.508088 -235.085382) (xy 83.502214 -235.092366) (xy 83.495436 -235.109294)
			(xy 83.49488 -235.118402) (xy 83.49488 -235.574332) (xy 83.745336 -235.574332) (xy 83.749296 -235.525278)
			(xy 83.761073 -235.477494) (xy 83.780364 -235.432218) (xy 83.806667 -235.390622) (xy 83.839302 -235.353785)
			(xy 83.877423 -235.32266) (xy 83.920044 -235.298053) (xy 83.96606 -235.280601) (xy 84.014279 -235.270757)
			(xy 84.063454 -235.268776) (xy 84.112309 -235.274708) (xy 84.15958 -235.2884) (xy 84.204042 -235.309498)
			(xy 84.244545 -235.337454) (xy 84.280038 -235.371546) (xy 84.309603 -235.41089) (xy 84.332474 -235.454467)
			(xy 84.348058 -235.501148) (xy 84.355953 -235.549725) (xy 84.356448 -235.574332) (xy 84.685136 -235.574332)
			(xy 84.689096 -235.525278) (xy 84.700873 -235.477494) (xy 84.720164 -235.432218) (xy 84.746467 -235.390622)
			(xy 84.779102 -235.353785) (xy 84.817223 -235.32266) (xy 84.859844 -235.298053) (xy 84.90586 -235.280601)
			(xy 84.954079 -235.270757) (xy 85.003254 -235.268776) (xy 85.052109 -235.274708) (xy 85.09938 -235.2884)
			(xy 85.143842 -235.309498) (xy 85.184345 -235.337454) (xy 85.219838 -235.371546) (xy 85.249403 -235.41089)
			(xy 85.272274 -235.454467) (xy 85.287858 -235.501148) (xy 85.295753 -235.549725) (xy 85.296248 -235.574332)
			(xy 85.62519 -235.574332) (xy 85.62915 -235.525278) (xy 85.640927 -235.477494) (xy 85.660218 -235.432218)
			(xy 85.686521 -235.390622) (xy 85.719156 -235.353785) (xy 85.757277 -235.32266) (xy 85.799898 -235.298053)
			(xy 85.845914 -235.280601) (xy 85.894133 -235.270757) (xy 85.943308 -235.268776) (xy 85.992163 -235.274708)
			(xy 86.039434 -235.2884) (xy 86.083896 -235.309498) (xy 86.124399 -235.337454) (xy 86.159892 -235.371546)
			(xy 86.189457 -235.41089) (xy 86.212328 -235.454467) (xy 86.227912 -235.501148) (xy 86.235807 -235.549725)
			(xy 86.236302 -235.574332) (xy 86.565244 -235.574332) (xy 86.569204 -235.525278) (xy 86.580981 -235.477494)
			(xy 86.600272 -235.432218) (xy 86.626575 -235.390622) (xy 86.65921 -235.353785) (xy 86.697331 -235.32266)
			(xy 86.739952 -235.298053) (xy 86.785968 -235.280601) (xy 86.834187 -235.270757) (xy 86.883362 -235.268776)
			(xy 86.932217 -235.274708) (xy 86.979488 -235.2884) (xy 87.02395 -235.309498) (xy 87.064453 -235.337454)
			(xy 87.099946 -235.371546) (xy 87.129511 -235.41089) (xy 87.152382 -235.454467) (xy 87.167966 -235.501148)
			(xy 87.175861 -235.549725) (xy 87.176356 -235.574332) (xy 87.505298 -235.574332) (xy 87.509258 -235.525278)
			(xy 87.521035 -235.477494) (xy 87.540326 -235.432218) (xy 87.566629 -235.390622) (xy 87.599264 -235.353785)
			(xy 87.637385 -235.32266) (xy 87.680006 -235.298053) (xy 87.726022 -235.280601) (xy 87.774241 -235.270757)
			(xy 87.823416 -235.268776) (xy 87.872271 -235.274708) (xy 87.919542 -235.2884) (xy 87.964004 -235.309498)
			(xy 88.004507 -235.337454) (xy 88.04 -235.371546) (xy 88.069565 -235.41089) (xy 88.092436 -235.454467)
			(xy 88.10802 -235.501148) (xy 88.115915 -235.549725) (xy 88.11641 -235.574332) (xy 88.445352 -235.574332)
			(xy 88.449312 -235.525278) (xy 88.461089 -235.477494) (xy 88.48038 -235.432218) (xy 88.506683 -235.390622)
			(xy 88.539318 -235.353785) (xy 88.577439 -235.32266) (xy 88.62006 -235.298053) (xy 88.666076 -235.280601)
			(xy 88.714295 -235.270757) (xy 88.76347 -235.268776) (xy 88.812325 -235.274708) (xy 88.859596 -235.2884)
			(xy 88.904058 -235.309498) (xy 88.944561 -235.337454) (xy 88.980054 -235.371546) (xy 89.009619 -235.41089)
			(xy 89.03249 -235.454467) (xy 89.048074 -235.501148) (xy 89.055969 -235.549725) (xy 89.056464 -235.574332)
			(xy 89.385152 -235.574332) (xy 89.389112 -235.525278) (xy 89.400889 -235.477494) (xy 89.42018 -235.432218)
			(xy 89.446483 -235.390622) (xy 89.479118 -235.353785) (xy 89.517239 -235.32266) (xy 89.55986 -235.298053)
			(xy 89.605876 -235.280601) (xy 89.654095 -235.270757) (xy 89.70327 -235.268776) (xy 89.752125 -235.274708)
			(xy 89.799396 -235.2884) (xy 89.843858 -235.309498) (xy 89.884361 -235.337454) (xy 89.919854 -235.371546)
			(xy 89.949419 -235.41089) (xy 89.97229 -235.454467) (xy 89.987874 -235.501148) (xy 89.995769 -235.549725)
			(xy 89.996264 -235.574332) (xy 90.314775 -235.574332) (xy 90.31887 -235.523604) (xy 90.331049 -235.47419)
			(xy 90.350997 -235.42737) (xy 90.378198 -235.384356) (xy 90.411946 -235.346262) (xy 90.451368 -235.314075)
			(xy 90.495442 -235.288629) (xy 90.543028 -235.270582) (xy 90.592892 -235.260402) (xy 90.643744 -235.258353)
			(xy 90.694265 -235.264487) (xy 90.743149 -235.278647) (xy 90.789128 -235.300464) (xy 90.831012 -235.329374)
			(xy 90.867716 -235.364629) (xy 90.898289 -235.405315) (xy 90.92194 -235.450378) (xy 90.938056 -235.498652)
			(xy 90.94622 -235.548886) (xy 90.946732 -235.574332) (xy 91.26526 -235.574332) (xy 91.26922 -235.525278)
			(xy 91.280997 -235.477494) (xy 91.300288 -235.432218) (xy 91.326591 -235.390622) (xy 91.359226 -235.353785)
			(xy 91.397347 -235.32266) (xy 91.439968 -235.298053) (xy 91.485984 -235.280601) (xy 91.534203 -235.270757)
			(xy 91.583378 -235.268776) (xy 91.632233 -235.274708) (xy 91.679504 -235.2884) (xy 91.723966 -235.309498)
			(xy 91.764469 -235.337454) (xy 91.799962 -235.371546) (xy 91.829527 -235.41089) (xy 91.852398 -235.454467)
			(xy 91.867982 -235.501148) (xy 91.875877 -235.549725) (xy 91.876372 -235.574332) (xy 92.194883 -235.574332)
			(xy 92.198978 -235.523604) (xy 92.211157 -235.47419) (xy 92.231105 -235.42737) (xy 92.258306 -235.384356)
			(xy 92.292054 -235.346262) (xy 92.331476 -235.314075) (xy 92.37555 -235.288629) (xy 92.423136 -235.270582)
			(xy 92.473 -235.260402) (xy 92.523852 -235.258353) (xy 92.574373 -235.264487) (xy 92.623257 -235.278647)
			(xy 92.669236 -235.300464) (xy 92.71112 -235.329374) (xy 92.747824 -235.364629) (xy 92.778397 -235.405315)
			(xy 92.802048 -235.450378) (xy 92.818164 -235.498652) (xy 92.826328 -235.548886) (xy 92.82684 -235.574332)
			(xy 93.145114 -235.574332) (xy 93.149074 -235.525278) (xy 93.160851 -235.477494) (xy 93.180142 -235.432218)
			(xy 93.206445 -235.390622) (xy 93.23908 -235.353785) (xy 93.277201 -235.32266) (xy 93.319822 -235.298053)
			(xy 93.365838 -235.280601) (xy 93.414057 -235.270757) (xy 93.463232 -235.268776) (xy 93.512087 -235.274708)
			(xy 93.559358 -235.2884) (xy 93.60382 -235.309498) (xy 93.644323 -235.337454) (xy 93.679816 -235.371546)
			(xy 93.709381 -235.41089) (xy 93.732252 -235.454467) (xy 93.747836 -235.501148) (xy 93.755731 -235.549725)
			(xy 93.756226 -235.574332) (xy 94.074737 -235.574332) (xy 94.078832 -235.523604) (xy 94.091011 -235.47419)
			(xy 94.110959 -235.42737) (xy 94.13816 -235.384356) (xy 94.171908 -235.346262) (xy 94.21133 -235.314075)
			(xy 94.255404 -235.288629) (xy 94.30299 -235.270582) (xy 94.352854 -235.260402) (xy 94.403706 -235.258353)
			(xy 94.454227 -235.264487) (xy 94.503111 -235.278647) (xy 94.54909 -235.300464) (xy 94.590974 -235.329374)
			(xy 94.627678 -235.364629) (xy 94.658251 -235.405315) (xy 94.681902 -235.450378) (xy 94.698018 -235.498652)
			(xy 94.706182 -235.548886) (xy 94.706694 -235.574332) (xy 95.014791 -235.574332) (xy 95.018886 -235.523604)
			(xy 95.031065 -235.47419) (xy 95.051013 -235.42737) (xy 95.078214 -235.384356) (xy 95.111962 -235.346262)
			(xy 95.151384 -235.314075) (xy 95.195458 -235.288629) (xy 95.243044 -235.270582) (xy 95.292908 -235.260402)
			(xy 95.34376 -235.258353) (xy 95.394281 -235.264487) (xy 95.443165 -235.278647) (xy 95.489144 -235.300464)
			(xy 95.531028 -235.329374) (xy 95.567732 -235.364629) (xy 95.598305 -235.405315) (xy 95.621956 -235.450378)
			(xy 95.638072 -235.498652) (xy 95.646236 -235.548886) (xy 95.646748 -235.574332) (xy 95.646236 -235.599778)
			(xy 95.638072 -235.650012) (xy 95.621956 -235.698286) (xy 95.598305 -235.743349) (xy 95.567732 -235.784035)
			(xy 95.531028 -235.81929) (xy 95.489144 -235.8482) (xy 95.443165 -235.870017) (xy 95.394281 -235.884177)
			(xy 95.34376 -235.890311) (xy 95.292908 -235.888262) (xy 95.243044 -235.878082) (xy 95.195458 -235.860035)
			(xy 95.151384 -235.834589) (xy 95.111962 -235.802402) (xy 95.078214 -235.764308) (xy 95.051013 -235.721294)
			(xy 95.031065 -235.674474) (xy 95.018886 -235.62506) (xy 95.014791 -235.574332) (xy 94.706694 -235.574332)
			(xy 94.706182 -235.599778) (xy 94.698018 -235.650012) (xy 94.681902 -235.698286) (xy 94.658251 -235.743349)
			(xy 94.627678 -235.784035) (xy 94.590974 -235.81929) (xy 94.54909 -235.8482) (xy 94.503111 -235.870017)
			(xy 94.454227 -235.884177) (xy 94.403706 -235.890311) (xy 94.352854 -235.888262) (xy 94.30299 -235.878082)
			(xy 94.255404 -235.860035) (xy 94.21133 -235.834589) (xy 94.171908 -235.802402) (xy 94.13816 -235.764308)
			(xy 94.110959 -235.721294) (xy 94.091011 -235.674474) (xy 94.078832 -235.62506) (xy 94.074737 -235.574332)
			(xy 93.756226 -235.574332) (xy 93.755731 -235.598939) (xy 93.747836 -235.647516) (xy 93.732252 -235.694197)
			(xy 93.709381 -235.737774) (xy 93.679816 -235.777118) (xy 93.644323 -235.81121) (xy 93.60382 -235.839166)
			(xy 93.559358 -235.860264) (xy 93.512087 -235.873956) (xy 93.463232 -235.879888) (xy 93.414057 -235.877907)
			(xy 93.365838 -235.868063) (xy 93.319822 -235.850611) (xy 93.277201 -235.826004) (xy 93.23908 -235.794879)
			(xy 93.206445 -235.758042) (xy 93.180142 -235.716446) (xy 93.160851 -235.67117) (xy 93.149074 -235.623386)
			(xy 93.145114 -235.574332) (xy 92.82684 -235.574332) (xy 92.826328 -235.599778) (xy 92.818164 -235.650012)
			(xy 92.802048 -235.698286) (xy 92.778397 -235.743349) (xy 92.747824 -235.784035) (xy 92.71112 -235.81929)
			(xy 92.669236 -235.8482) (xy 92.623257 -235.870017) (xy 92.574373 -235.884177) (xy 92.523852 -235.890311)
			(xy 92.473 -235.888262) (xy 92.423136 -235.878082) (xy 92.37555 -235.860035) (xy 92.331476 -235.834589)
			(xy 92.292054 -235.802402) (xy 92.258306 -235.764308) (xy 92.231105 -235.721294) (xy 92.211157 -235.674474)
			(xy 92.198978 -235.62506) (xy 92.194883 -235.574332) (xy 91.876372 -235.574332) (xy 91.875877 -235.598939)
			(xy 91.867982 -235.647516) (xy 91.852398 -235.694197) (xy 91.829527 -235.737774) (xy 91.799962 -235.777118)
			(xy 91.764469 -235.81121) (xy 91.723966 -235.839166) (xy 91.679504 -235.860264) (xy 91.632233 -235.873956)
			(xy 91.583378 -235.879888) (xy 91.534203 -235.877907) (xy 91.485984 -235.868063) (xy 91.439968 -235.850611)
			(xy 91.397347 -235.826004) (xy 91.359226 -235.794879) (xy 91.326591 -235.758042) (xy 91.300288 -235.716446)
			(xy 91.280997 -235.67117) (xy 91.26922 -235.623386) (xy 91.26526 -235.574332) (xy 90.946732 -235.574332)
			(xy 90.94622 -235.599778) (xy 90.938056 -235.650012) (xy 90.92194 -235.698286) (xy 90.898289 -235.743349)
			(xy 90.867716 -235.784035) (xy 90.831012 -235.81929) (xy 90.789128 -235.8482) (xy 90.743149 -235.870017)
			(xy 90.694265 -235.884177) (xy 90.643744 -235.890311) (xy 90.592892 -235.888262) (xy 90.543028 -235.878082)
			(xy 90.495442 -235.860035) (xy 90.451368 -235.834589) (xy 90.411946 -235.802402) (xy 90.378198 -235.764308)
			(xy 90.350997 -235.721294) (xy 90.331049 -235.674474) (xy 90.31887 -235.62506) (xy 90.314775 -235.574332)
			(xy 89.996264 -235.574332) (xy 89.995769 -235.598939) (xy 89.987874 -235.647516) (xy 89.97229 -235.694197)
			(xy 89.949419 -235.737774) (xy 89.919854 -235.777118) (xy 89.884361 -235.81121) (xy 89.843858 -235.839166)
			(xy 89.799396 -235.860264) (xy 89.752125 -235.873956) (xy 89.70327 -235.879888) (xy 89.654095 -235.877907)
			(xy 89.605876 -235.868063) (xy 89.55986 -235.850611) (xy 89.517239 -235.826004) (xy 89.479118 -235.794879)
			(xy 89.446483 -235.758042) (xy 89.42018 -235.716446) (xy 89.400889 -235.67117) (xy 89.389112 -235.623386)
			(xy 89.385152 -235.574332) (xy 89.056464 -235.574332) (xy 89.055969 -235.598939) (xy 89.048074 -235.647516)
			(xy 89.03249 -235.694197) (xy 89.009619 -235.737774) (xy 88.980054 -235.777118) (xy 88.944561 -235.81121)
			(xy 88.904058 -235.839166) (xy 88.859596 -235.860264) (xy 88.812325 -235.873956) (xy 88.76347 -235.879888)
			(xy 88.714295 -235.877907) (xy 88.666076 -235.868063) (xy 88.62006 -235.850611) (xy 88.577439 -235.826004)
			(xy 88.539318 -235.794879) (xy 88.506683 -235.758042) (xy 88.48038 -235.716446) (xy 88.461089 -235.67117)
			(xy 88.449312 -235.623386) (xy 88.445352 -235.574332) (xy 88.11641 -235.574332) (xy 88.115915 -235.598939)
			(xy 88.10802 -235.647516) (xy 88.092436 -235.694197) (xy 88.069565 -235.737774) (xy 88.04 -235.777118)
			(xy 88.004507 -235.81121) (xy 87.964004 -235.839166) (xy 87.919542 -235.860264) (xy 87.872271 -235.873956)
			(xy 87.823416 -235.879888) (xy 87.774241 -235.877907) (xy 87.726022 -235.868063) (xy 87.680006 -235.850611)
			(xy 87.637385 -235.826004) (xy 87.599264 -235.794879) (xy 87.566629 -235.758042) (xy 87.540326 -235.716446)
			(xy 87.521035 -235.67117) (xy 87.509258 -235.623386) (xy 87.505298 -235.574332) (xy 87.176356 -235.574332)
			(xy 87.175861 -235.598939) (xy 87.167966 -235.647516) (xy 87.152382 -235.694197) (xy 87.129511 -235.737774)
			(xy 87.099946 -235.777118) (xy 87.064453 -235.81121) (xy 87.02395 -235.839166) (xy 86.979488 -235.860264)
			(xy 86.932217 -235.873956) (xy 86.883362 -235.879888) (xy 86.834187 -235.877907) (xy 86.785968 -235.868063)
			(xy 86.739952 -235.850611) (xy 86.697331 -235.826004) (xy 86.65921 -235.794879) (xy 86.626575 -235.758042)
			(xy 86.600272 -235.716446) (xy 86.580981 -235.67117) (xy 86.569204 -235.623386) (xy 86.565244 -235.574332)
			(xy 86.236302 -235.574332) (xy 86.235807 -235.598939) (xy 86.227912 -235.647516) (xy 86.212328 -235.694197)
			(xy 86.189457 -235.737774) (xy 86.159892 -235.777118) (xy 86.124399 -235.81121) (xy 86.083896 -235.839166)
			(xy 86.039434 -235.860264) (xy 85.992163 -235.873956) (xy 85.943308 -235.879888) (xy 85.894133 -235.877907)
			(xy 85.845914 -235.868063) (xy 85.799898 -235.850611) (xy 85.757277 -235.826004) (xy 85.719156 -235.794879)
			(xy 85.686521 -235.758042) (xy 85.660218 -235.716446) (xy 85.640927 -235.67117) (xy 85.62915 -235.623386)
			(xy 85.62519 -235.574332) (xy 85.296248 -235.574332) (xy 85.295753 -235.598939) (xy 85.287858 -235.647516)
			(xy 85.272274 -235.694197) (xy 85.249403 -235.737774) (xy 85.219838 -235.777118) (xy 85.184345 -235.81121)
			(xy 85.143842 -235.839166) (xy 85.09938 -235.860264) (xy 85.052109 -235.873956) (xy 85.003254 -235.879888)
			(xy 84.954079 -235.877907) (xy 84.90586 -235.868063) (xy 84.859844 -235.850611) (xy 84.817223 -235.826004)
			(xy 84.779102 -235.794879) (xy 84.746467 -235.758042) (xy 84.720164 -235.716446) (xy 84.700873 -235.67117)
			(xy 84.689096 -235.623386) (xy 84.685136 -235.574332) (xy 84.356448 -235.574332) (xy 84.355953 -235.598939)
			(xy 84.348058 -235.647516) (xy 84.332474 -235.694197) (xy 84.309603 -235.737774) (xy 84.280038 -235.777118)
			(xy 84.244545 -235.81121) (xy 84.204042 -235.839166) (xy 84.15958 -235.860264) (xy 84.112309 -235.873956)
			(xy 84.063454 -235.879888) (xy 84.014279 -235.877907) (xy 83.96606 -235.868063) (xy 83.920044 -235.850611)
			(xy 83.877423 -235.826004) (xy 83.839302 -235.794879) (xy 83.806667 -235.758042) (xy 83.780364 -235.716446)
			(xy 83.761073 -235.67117) (xy 83.749296 -235.623386) (xy 83.745336 -235.574332) (xy 83.49488 -235.574332)
			(xy 83.49488 -235.931456) (xy 83.494966 -235.936008) (xy 83.49662 -235.94496) (xy 83.498182 -235.949236)
			(xy 83.501738 -235.958634) (xy 83.537298 -235.998004) (xy 83.552792 -236.015276) (xy 83.559904 -236.021626)
			(xy 83.561936 -236.022896) (xy 83.567778 -236.026452) (xy 83.576414 -236.030516) (xy 83.585558 -236.031532)
			(xy 83.585812 -236.031532) (xy 83.60941 -236.034269) (xy 83.655413 -236.04611) (xy 83.699028 -236.064932)
			(xy 83.739203 -236.09028) (xy 83.774969 -236.121542) (xy 83.805462 -236.157966) (xy 83.829948 -236.198672)
			(xy 83.839304 -236.220508) (xy 83.84286 -236.227112) (xy 83.843114 -236.22762) (xy 83.856647 -236.2515)
			(xy 83.875908 -236.302893) (xy 83.885692 -236.356896) (xy 83.886294 -236.384338) (xy 84.215236 -236.384338)
			(xy 84.219196 -236.335284) (xy 84.230973 -236.2875) (xy 84.250264 -236.242224) (xy 84.276567 -236.200628)
			(xy 84.309202 -236.163791) (xy 84.347323 -236.132666) (xy 84.389944 -236.108059) (xy 84.43596 -236.090607)
			(xy 84.484179 -236.080763) (xy 84.533354 -236.078782) (xy 84.582209 -236.084714) (xy 84.62948 -236.098406)
			(xy 84.673942 -236.119504) (xy 84.714445 -236.14746) (xy 84.749938 -236.181552) (xy 84.779503 -236.220896)
			(xy 84.802374 -236.264473) (xy 84.817958 -236.311154) (xy 84.825853 -236.359731) (xy 84.826348 -236.384338)
			(xy 85.15529 -236.384338) (xy 85.15925 -236.335284) (xy 85.171027 -236.2875) (xy 85.190318 -236.242224)
			(xy 85.216621 -236.200628) (xy 85.249256 -236.163791) (xy 85.287377 -236.132666) (xy 85.329998 -236.108059)
			(xy 85.376014 -236.090607) (xy 85.424233 -236.080763) (xy 85.473408 -236.078782) (xy 85.522263 -236.084714)
			(xy 85.569534 -236.098406) (xy 85.613996 -236.119504) (xy 85.654499 -236.14746) (xy 85.689992 -236.181552)
			(xy 85.719557 -236.220896) (xy 85.742428 -236.264473) (xy 85.758012 -236.311154) (xy 85.765907 -236.359731)
			(xy 85.766402 -236.384338) (xy 86.095344 -236.384338) (xy 86.099304 -236.335284) (xy 86.111081 -236.2875)
			(xy 86.130372 -236.242224) (xy 86.156675 -236.200628) (xy 86.18931 -236.163791) (xy 86.227431 -236.132666)
			(xy 86.270052 -236.108059) (xy 86.316068 -236.090607) (xy 86.364287 -236.080763) (xy 86.413462 -236.078782)
			(xy 86.462317 -236.084714) (xy 86.509588 -236.098406) (xy 86.55405 -236.119504) (xy 86.594553 -236.14746)
			(xy 86.630046 -236.181552) (xy 86.659611 -236.220896) (xy 86.682482 -236.264473) (xy 86.698066 -236.311154)
			(xy 86.705961 -236.359731) (xy 86.706456 -236.384338) (xy 87.035144 -236.384338) (xy 87.039104 -236.335284)
			(xy 87.050881 -236.2875) (xy 87.070172 -236.242224) (xy 87.096475 -236.200628) (xy 87.12911 -236.163791)
			(xy 87.167231 -236.132666) (xy 87.209852 -236.108059) (xy 87.255868 -236.090607) (xy 87.304087 -236.080763)
			(xy 87.353262 -236.078782) (xy 87.402117 -236.084714) (xy 87.449388 -236.098406) (xy 87.49385 -236.119504)
			(xy 87.534353 -236.14746) (xy 87.569846 -236.181552) (xy 87.599411 -236.220896) (xy 87.622282 -236.264473)
			(xy 87.637866 -236.311154) (xy 87.645761 -236.359731) (xy 87.646256 -236.384338) (xy 87.975198 -236.384338)
			(xy 87.979158 -236.335284) (xy 87.990935 -236.2875) (xy 88.010226 -236.242224) (xy 88.036529 -236.200628)
			(xy 88.069164 -236.163791) (xy 88.107285 -236.132666) (xy 88.149906 -236.108059) (xy 88.195922 -236.090607)
			(xy 88.244141 -236.080763) (xy 88.293316 -236.078782) (xy 88.342171 -236.084714) (xy 88.389442 -236.098406)
			(xy 88.433904 -236.119504) (xy 88.474407 -236.14746) (xy 88.5099 -236.181552) (xy 88.539465 -236.220896)
			(xy 88.562336 -236.264473) (xy 88.57792 -236.311154) (xy 88.585815 -236.359731) (xy 88.58631 -236.384338)
			(xy 88.915252 -236.384338) (xy 88.919212 -236.335284) (xy 88.930989 -236.2875) (xy 88.95028 -236.242224)
			(xy 88.976583 -236.200628) (xy 89.009218 -236.163791) (xy 89.047339 -236.132666) (xy 89.08996 -236.108059)
			(xy 89.135976 -236.090607) (xy 89.184195 -236.080763) (xy 89.23337 -236.078782) (xy 89.282225 -236.084714)
			(xy 89.329496 -236.098406) (xy 89.373958 -236.119504) (xy 89.414461 -236.14746) (xy 89.449954 -236.181552)
			(xy 89.479519 -236.220896) (xy 89.50239 -236.264473) (xy 89.517974 -236.311154) (xy 89.525869 -236.359731)
			(xy 89.526364 -236.384338) (xy 89.855306 -236.384338) (xy 89.859266 -236.335284) (xy 89.871043 -236.2875)
			(xy 89.890334 -236.242224) (xy 89.916637 -236.200628) (xy 89.949272 -236.163791) (xy 89.987393 -236.132666)
			(xy 90.030014 -236.108059) (xy 90.07603 -236.090607) (xy 90.124249 -236.080763) (xy 90.173424 -236.078782)
			(xy 90.222279 -236.084714) (xy 90.26955 -236.098406) (xy 90.314012 -236.119504) (xy 90.354515 -236.14746)
			(xy 90.390008 -236.181552) (xy 90.419573 -236.220896) (xy 90.442444 -236.264473) (xy 90.458028 -236.311154)
			(xy 90.465923 -236.359731) (xy 90.466418 -236.384338) (xy 90.784675 -236.384338) (xy 90.78877 -236.33361)
			(xy 90.800949 -236.284196) (xy 90.820897 -236.237376) (xy 90.848098 -236.194362) (xy 90.881846 -236.156268)
			(xy 90.921268 -236.124081) (xy 90.965342 -236.098635) (xy 91.012928 -236.080588) (xy 91.062792 -236.070408)
			(xy 91.113644 -236.068359) (xy 91.164165 -236.074493) (xy 91.213049 -236.088653) (xy 91.259028 -236.11047)
			(xy 91.300912 -236.13938) (xy 91.337616 -236.174635) (xy 91.368189 -236.215321) (xy 91.39184 -236.260384)
			(xy 91.407956 -236.308658) (xy 91.41612 -236.358892) (xy 91.416632 -236.384338) (xy 91.724729 -236.384338)
			(xy 91.728824 -236.33361) (xy 91.741003 -236.284196) (xy 91.760951 -236.237376) (xy 91.788152 -236.194362)
			(xy 91.8219 -236.156268) (xy 91.861322 -236.124081) (xy 91.905396 -236.098635) (xy 91.952982 -236.080588)
			(xy 92.002846 -236.070408) (xy 92.053698 -236.068359) (xy 92.104219 -236.074493) (xy 92.153103 -236.088653)
			(xy 92.199082 -236.11047) (xy 92.240966 -236.13938) (xy 92.27767 -236.174635) (xy 92.308243 -236.215321)
			(xy 92.331894 -236.260384) (xy 92.34801 -236.308658) (xy 92.356174 -236.358892) (xy 92.356686 -236.384338)
			(xy 92.675214 -236.384338) (xy 92.679174 -236.335284) (xy 92.690951 -236.2875) (xy 92.710242 -236.242224)
			(xy 92.736545 -236.200628) (xy 92.76918 -236.163791) (xy 92.807301 -236.132666) (xy 92.849922 -236.108059)
			(xy 92.895938 -236.090607) (xy 92.944157 -236.080763) (xy 92.993332 -236.078782) (xy 93.042187 -236.084714)
			(xy 93.089458 -236.098406) (xy 93.13392 -236.119504) (xy 93.174423 -236.14746) (xy 93.209916 -236.181552)
			(xy 93.239481 -236.220896) (xy 93.262352 -236.264473) (xy 93.277936 -236.311154) (xy 93.285831 -236.359731)
			(xy 93.286326 -236.384338) (xy 93.604837 -236.384338) (xy 93.608932 -236.33361) (xy 93.621111 -236.284196)
			(xy 93.641059 -236.237376) (xy 93.66826 -236.194362) (xy 93.702008 -236.156268) (xy 93.74143 -236.124081)
			(xy 93.785504 -236.098635) (xy 93.83309 -236.080588) (xy 93.882954 -236.070408) (xy 93.933806 -236.068359)
			(xy 93.984327 -236.074493) (xy 94.033211 -236.088653) (xy 94.07919 -236.11047) (xy 94.121074 -236.13938)
			(xy 94.157778 -236.174635) (xy 94.188351 -236.215321) (xy 94.212002 -236.260384) (xy 94.228118 -236.308658)
			(xy 94.236282 -236.358892) (xy 94.236794 -236.384338) (xy 94.555322 -236.384338) (xy 94.559282 -236.335284)
			(xy 94.571059 -236.2875) (xy 94.59035 -236.242224) (xy 94.616653 -236.200628) (xy 94.649288 -236.163791)
			(xy 94.687409 -236.132666) (xy 94.73003 -236.108059) (xy 94.776046 -236.090607) (xy 94.824265 -236.080763)
			(xy 94.87344 -236.078782) (xy 94.922295 -236.084714) (xy 94.969566 -236.098406) (xy 95.014028 -236.119504)
			(xy 95.054531 -236.14746) (xy 95.090024 -236.181552) (xy 95.119589 -236.220896) (xy 95.14246 -236.264473)
			(xy 95.158044 -236.311154) (xy 95.165939 -236.359731) (xy 95.166434 -236.384338) (xy 95.484691 -236.384338)
			(xy 95.488786 -236.33361) (xy 95.500965 -236.284196) (xy 95.520913 -236.237376) (xy 95.548114 -236.194362)
			(xy 95.581862 -236.156268) (xy 95.621284 -236.124081) (xy 95.665358 -236.098635) (xy 95.712944 -236.080588)
			(xy 95.762808 -236.070408) (xy 95.81366 -236.068359) (xy 95.864181 -236.074493) (xy 95.913065 -236.088653)
			(xy 95.959044 -236.11047) (xy 96.000928 -236.13938) (xy 96.037632 -236.174635) (xy 96.068205 -236.215321)
			(xy 96.091856 -236.260384) (xy 96.107972 -236.308658) (xy 96.116136 -236.358892) (xy 96.116648 -236.384338)
			(xy 96.116136 -236.409784) (xy 96.107972 -236.460018) (xy 96.091856 -236.508292) (xy 96.068205 -236.553355)
			(xy 96.037632 -236.594041) (xy 96.000928 -236.629296) (xy 95.959044 -236.658206) (xy 95.913065 -236.680023)
			(xy 95.864181 -236.694183) (xy 95.81366 -236.700317) (xy 95.762808 -236.698268) (xy 95.712944 -236.688088)
			(xy 95.665358 -236.670041) (xy 95.621284 -236.644595) (xy 95.581862 -236.612408) (xy 95.548114 -236.574314)
			(xy 95.520913 -236.5313) (xy 95.500965 -236.48448) (xy 95.488786 -236.435066) (xy 95.484691 -236.384338)
			(xy 95.166434 -236.384338) (xy 95.165939 -236.408945) (xy 95.158044 -236.457522) (xy 95.14246 -236.504203)
			(xy 95.119589 -236.54778) (xy 95.090024 -236.587124) (xy 95.054531 -236.621216) (xy 95.014028 -236.649172)
			(xy 94.969566 -236.67027) (xy 94.922295 -236.683962) (xy 94.87344 -236.689894) (xy 94.824265 -236.687913)
			(xy 94.776046 -236.678069) (xy 94.73003 -236.660617) (xy 94.687409 -236.63601) (xy 94.649288 -236.604885)
			(xy 94.616653 -236.568048) (xy 94.59035 -236.526452) (xy 94.571059 -236.481176) (xy 94.559282 -236.433392)
			(xy 94.555322 -236.384338) (xy 94.236794 -236.384338) (xy 94.236282 -236.409784) (xy 94.228118 -236.460018)
			(xy 94.212002 -236.508292) (xy 94.188351 -236.553355) (xy 94.157778 -236.594041) (xy 94.121074 -236.629296)
			(xy 94.07919 -236.658206) (xy 94.033211 -236.680023) (xy 93.984327 -236.694183) (xy 93.933806 -236.700317)
			(xy 93.882954 -236.698268) (xy 93.83309 -236.688088) (xy 93.785504 -236.670041) (xy 93.74143 -236.644595)
			(xy 93.702008 -236.612408) (xy 93.66826 -236.574314) (xy 93.641059 -236.5313) (xy 93.621111 -236.48448)
			(xy 93.608932 -236.435066) (xy 93.604837 -236.384338) (xy 93.286326 -236.384338) (xy 93.285831 -236.408945)
			(xy 93.277936 -236.457522) (xy 93.262352 -236.504203) (xy 93.239481 -236.54778) (xy 93.209916 -236.587124)
			(xy 93.174423 -236.621216) (xy 93.13392 -236.649172) (xy 93.089458 -236.67027) (xy 93.042187 -236.683962)
			(xy 92.993332 -236.689894) (xy 92.944157 -236.687913) (xy 92.895938 -236.678069) (xy 92.849922 -236.660617)
			(xy 92.807301 -236.63601) (xy 92.76918 -236.604885) (xy 92.736545 -236.568048) (xy 92.710242 -236.526452)
			(xy 92.690951 -236.481176) (xy 92.679174 -236.433392) (xy 92.675214 -236.384338) (xy 92.356686 -236.384338)
			(xy 92.356174 -236.409784) (xy 92.34801 -236.460018) (xy 92.331894 -236.508292) (xy 92.308243 -236.553355)
			(xy 92.27767 -236.594041) (xy 92.240966 -236.629296) (xy 92.199082 -236.658206) (xy 92.153103 -236.680023)
			(xy 92.104219 -236.694183) (xy 92.053698 -236.700317) (xy 92.002846 -236.698268) (xy 91.952982 -236.688088)
			(xy 91.905396 -236.670041) (xy 91.861322 -236.644595) (xy 91.8219 -236.612408) (xy 91.788152 -236.574314)
			(xy 91.760951 -236.5313) (xy 91.741003 -236.48448) (xy 91.728824 -236.435066) (xy 91.724729 -236.384338)
			(xy 91.416632 -236.384338) (xy 91.41612 -236.409784) (xy 91.407956 -236.460018) (xy 91.39184 -236.508292)
			(xy 91.368189 -236.553355) (xy 91.337616 -236.594041) (xy 91.300912 -236.629296) (xy 91.259028 -236.658206)
			(xy 91.213049 -236.680023) (xy 91.164165 -236.694183) (xy 91.113644 -236.700317) (xy 91.062792 -236.698268)
			(xy 91.012928 -236.688088) (xy 90.965342 -236.670041) (xy 90.921268 -236.644595) (xy 90.881846 -236.612408)
			(xy 90.848098 -236.574314) (xy 90.820897 -236.5313) (xy 90.800949 -236.48448) (xy 90.78877 -236.435066)
			(xy 90.784675 -236.384338) (xy 90.466418 -236.384338) (xy 90.465923 -236.408945) (xy 90.458028 -236.457522)
			(xy 90.442444 -236.504203) (xy 90.419573 -236.54778) (xy 90.390008 -236.587124) (xy 90.354515 -236.621216)
			(xy 90.314012 -236.649172) (xy 90.26955 -236.67027) (xy 90.222279 -236.683962) (xy 90.173424 -236.689894)
			(xy 90.124249 -236.687913) (xy 90.07603 -236.678069) (xy 90.030014 -236.660617) (xy 89.987393 -236.63601)
			(xy 89.949272 -236.604885) (xy 89.916637 -236.568048) (xy 89.890334 -236.526452) (xy 89.871043 -236.481176)
			(xy 89.859266 -236.433392) (xy 89.855306 -236.384338) (xy 89.526364 -236.384338) (xy 89.525869 -236.408945)
			(xy 89.517974 -236.457522) (xy 89.50239 -236.504203) (xy 89.479519 -236.54778) (xy 89.449954 -236.587124)
			(xy 89.414461 -236.621216) (xy 89.373958 -236.649172) (xy 89.329496 -236.67027) (xy 89.282225 -236.683962)
			(xy 89.23337 -236.689894) (xy 89.184195 -236.687913) (xy 89.135976 -236.678069) (xy 89.08996 -236.660617)
			(xy 89.047339 -236.63601) (xy 89.009218 -236.604885) (xy 88.976583 -236.568048) (xy 88.95028 -236.526452)
			(xy 88.930989 -236.481176) (xy 88.919212 -236.433392) (xy 88.915252 -236.384338) (xy 88.58631 -236.384338)
			(xy 88.585815 -236.408945) (xy 88.57792 -236.457522) (xy 88.562336 -236.504203) (xy 88.539465 -236.54778)
			(xy 88.5099 -236.587124) (xy 88.474407 -236.621216) (xy 88.433904 -236.649172) (xy 88.389442 -236.67027)
			(xy 88.342171 -236.683962) (xy 88.293316 -236.689894) (xy 88.244141 -236.687913) (xy 88.195922 -236.678069)
			(xy 88.149906 -236.660617) (xy 88.107285 -236.63601) (xy 88.069164 -236.604885) (xy 88.036529 -236.568048)
			(xy 88.010226 -236.526452) (xy 87.990935 -236.481176) (xy 87.979158 -236.433392) (xy 87.975198 -236.384338)
			(xy 87.646256 -236.384338) (xy 87.645761 -236.408945) (xy 87.637866 -236.457522) (xy 87.622282 -236.504203)
			(xy 87.599411 -236.54778) (xy 87.569846 -236.587124) (xy 87.534353 -236.621216) (xy 87.49385 -236.649172)
			(xy 87.449388 -236.67027) (xy 87.402117 -236.683962) (xy 87.353262 -236.689894) (xy 87.304087 -236.687913)
			(xy 87.255868 -236.678069) (xy 87.209852 -236.660617) (xy 87.167231 -236.63601) (xy 87.12911 -236.604885)
			(xy 87.096475 -236.568048) (xy 87.070172 -236.526452) (xy 87.050881 -236.481176) (xy 87.039104 -236.433392)
			(xy 87.035144 -236.384338) (xy 86.706456 -236.384338) (xy 86.705961 -236.408945) (xy 86.698066 -236.457522)
			(xy 86.682482 -236.504203) (xy 86.659611 -236.54778) (xy 86.630046 -236.587124) (xy 86.594553 -236.621216)
			(xy 86.55405 -236.649172) (xy 86.509588 -236.67027) (xy 86.462317 -236.683962) (xy 86.413462 -236.689894)
			(xy 86.364287 -236.687913) (xy 86.316068 -236.678069) (xy 86.270052 -236.660617) (xy 86.227431 -236.63601)
			(xy 86.18931 -236.604885) (xy 86.156675 -236.568048) (xy 86.130372 -236.526452) (xy 86.111081 -236.481176)
			(xy 86.099304 -236.433392) (xy 86.095344 -236.384338) (xy 85.766402 -236.384338) (xy 85.765907 -236.408945)
			(xy 85.758012 -236.457522) (xy 85.742428 -236.504203) (xy 85.719557 -236.54778) (xy 85.689992 -236.587124)
			(xy 85.654499 -236.621216) (xy 85.613996 -236.649172) (xy 85.569534 -236.67027) (xy 85.522263 -236.683962)
			(xy 85.473408 -236.689894) (xy 85.424233 -236.687913) (xy 85.376014 -236.678069) (xy 85.329998 -236.660617)
			(xy 85.287377 -236.63601) (xy 85.249256 -236.604885) (xy 85.216621 -236.568048) (xy 85.190318 -236.526452)
			(xy 85.171027 -236.481176) (xy 85.15925 -236.433392) (xy 85.15529 -236.384338) (xy 84.826348 -236.384338)
			(xy 84.825853 -236.408945) (xy 84.817958 -236.457522) (xy 84.802374 -236.504203) (xy 84.779503 -236.54778)
			(xy 84.749938 -236.587124) (xy 84.714445 -236.621216) (xy 84.673942 -236.649172) (xy 84.62948 -236.67027)
			(xy 84.582209 -236.683962) (xy 84.533354 -236.689894) (xy 84.484179 -236.687913) (xy 84.43596 -236.678069)
			(xy 84.389944 -236.660617) (xy 84.347323 -236.63601) (xy 84.309202 -236.604885) (xy 84.276567 -236.568048)
			(xy 84.250264 -236.526452) (xy 84.230973 -236.481176) (xy 84.219196 -236.433392) (xy 84.215236 -236.384338)
			(xy 83.886294 -236.384338) (xy 83.885821 -236.408327) (xy 83.87831 -236.455713) (xy 83.863479 -236.501341)
			(xy 83.841693 -236.544088) (xy 83.813489 -236.5829) (xy 83.77956 -236.616822) (xy 83.740743 -236.64502)
			(xy 83.697993 -236.666799) (xy 83.652363 -236.681622) (xy 83.604975 -236.689125) (xy 83.580986 -236.689646)
			(xy 83.551268 -236.688122) (xy 83.551014 -236.688122) (xy 83.539076 -236.687106) (xy 83.528408 -236.69117)
			(xy 83.522869 -236.69348) (xy 83.512984 -236.700281) (xy 83.50885 -236.704632) (xy 83.508088 -236.705394)
			(xy 83.502216 -236.712379) (xy 83.495441 -236.729307) (xy 83.49488 -236.738414) (xy 83.49488 -237.194344)
			(xy 83.745336 -237.194344) (xy 83.749296 -237.14529) (xy 83.761073 -237.097506) (xy 83.780364 -237.05223)
			(xy 83.806667 -237.010634) (xy 83.839302 -236.973797) (xy 83.877423 -236.942672) (xy 83.920044 -236.918065)
			(xy 83.96606 -236.900613) (xy 84.014279 -236.890769) (xy 84.063454 -236.888788) (xy 84.112309 -236.89472)
			(xy 84.15958 -236.908412) (xy 84.204042 -236.92951) (xy 84.244545 -236.957466) (xy 84.280038 -236.991558)
			(xy 84.309603 -237.030902) (xy 84.332474 -237.074479) (xy 84.348058 -237.12116) (xy 84.355953 -237.169737)
			(xy 84.356448 -237.194344) (xy 84.685136 -237.194344) (xy 84.689096 -237.14529) (xy 84.700873 -237.097506)
			(xy 84.720164 -237.05223) (xy 84.746467 -237.010634) (xy 84.779102 -236.973797) (xy 84.817223 -236.942672)
			(xy 84.859844 -236.918065) (xy 84.90586 -236.900613) (xy 84.954079 -236.890769) (xy 85.003254 -236.888788)
			(xy 85.052109 -236.89472) (xy 85.09938 -236.908412) (xy 85.143842 -236.92951) (xy 85.184345 -236.957466)
			(xy 85.219838 -236.991558) (xy 85.249403 -237.030902) (xy 85.272274 -237.074479) (xy 85.287858 -237.12116)
			(xy 85.295753 -237.169737) (xy 85.296248 -237.194344) (xy 85.62519 -237.194344) (xy 85.62915 -237.14529)
			(xy 85.640927 -237.097506) (xy 85.660218 -237.05223) (xy 85.686521 -237.010634) (xy 85.719156 -236.973797)
			(xy 85.757277 -236.942672) (xy 85.799898 -236.918065) (xy 85.845914 -236.900613) (xy 85.894133 -236.890769)
			(xy 85.943308 -236.888788) (xy 85.992163 -236.89472) (xy 86.039434 -236.908412) (xy 86.083896 -236.92951)
			(xy 86.124399 -236.957466) (xy 86.159892 -236.991558) (xy 86.189457 -237.030902) (xy 86.212328 -237.074479)
			(xy 86.227912 -237.12116) (xy 86.235807 -237.169737) (xy 86.236302 -237.194344) (xy 87.505298 -237.194344)
			(xy 87.509258 -237.14529) (xy 87.521035 -237.097506) (xy 87.540326 -237.05223) (xy 87.566629 -237.010634)
			(xy 87.599264 -236.973797) (xy 87.637385 -236.942672) (xy 87.680006 -236.918065) (xy 87.726022 -236.900613)
			(xy 87.774241 -236.890769) (xy 87.823416 -236.888788) (xy 87.872271 -236.89472) (xy 87.919542 -236.908412)
			(xy 87.964004 -236.92951) (xy 88.004507 -236.957466) (xy 88.04 -236.991558) (xy 88.069565 -237.030902)
			(xy 88.092436 -237.074479) (xy 88.10802 -237.12116) (xy 88.115915 -237.169737) (xy 88.11641 -237.194344)
			(xy 88.445352 -237.194344) (xy 88.449312 -237.14529) (xy 88.461089 -237.097506) (xy 88.48038 -237.05223)
			(xy 88.506683 -237.010634) (xy 88.539318 -236.973797) (xy 88.577439 -236.942672) (xy 88.62006 -236.918065)
			(xy 88.666076 -236.900613) (xy 88.714295 -236.890769) (xy 88.76347 -236.888788) (xy 88.812325 -236.89472)
			(xy 88.859596 -236.908412) (xy 88.904058 -236.92951) (xy 88.944561 -236.957466) (xy 88.980054 -236.991558)
			(xy 89.009619 -237.030902) (xy 89.03249 -237.074479) (xy 89.048074 -237.12116) (xy 89.055969 -237.169737)
			(xy 89.056464 -237.194344) (xy 89.385152 -237.194344) (xy 89.389112 -237.14529) (xy 89.400889 -237.097506)
			(xy 89.42018 -237.05223) (xy 89.446483 -237.010634) (xy 89.479118 -236.973797) (xy 89.517239 -236.942672)
			(xy 89.55986 -236.918065) (xy 89.605876 -236.900613) (xy 89.654095 -236.890769) (xy 89.70327 -236.888788)
			(xy 89.752125 -236.89472) (xy 89.799396 -236.908412) (xy 89.843858 -236.92951) (xy 89.884361 -236.957466)
			(xy 89.919854 -236.991558) (xy 89.949419 -237.030902) (xy 89.97229 -237.074479) (xy 89.987874 -237.12116)
			(xy 89.995769 -237.169737) (xy 89.996264 -237.194344) (xy 90.314775 -237.194344) (xy 90.31887 -237.143616)
			(xy 90.331049 -237.094202) (xy 90.350997 -237.047382) (xy 90.378198 -237.004368) (xy 90.411946 -236.966274)
			(xy 90.451368 -236.934087) (xy 90.495442 -236.908641) (xy 90.543028 -236.890594) (xy 90.592892 -236.880414)
			(xy 90.643744 -236.878365) (xy 90.694265 -236.884499) (xy 90.743149 -236.898659) (xy 90.789128 -236.920476)
			(xy 90.831012 -236.949386) (xy 90.867716 -236.984641) (xy 90.898289 -237.025327) (xy 90.92194 -237.07039)
			(xy 90.938056 -237.118664) (xy 90.94622 -237.168898) (xy 90.946732 -237.194344) (xy 91.26526 -237.194344)
			(xy 91.26922 -237.14529) (xy 91.280997 -237.097506) (xy 91.300288 -237.05223) (xy 91.326591 -237.010634)
			(xy 91.359226 -236.973797) (xy 91.397347 -236.942672) (xy 91.439968 -236.918065) (xy 91.485984 -236.900613)
			(xy 91.534203 -236.890769) (xy 91.583378 -236.888788) (xy 91.632233 -236.89472) (xy 91.679504 -236.908412)
			(xy 91.723966 -236.92951) (xy 91.764469 -236.957466) (xy 91.799962 -236.991558) (xy 91.829527 -237.030902)
			(xy 91.852398 -237.074479) (xy 91.867982 -237.12116) (xy 91.875877 -237.169737) (xy 91.876372 -237.194344)
			(xy 92.194883 -237.194344) (xy 92.198978 -237.143616) (xy 92.211157 -237.094202) (xy 92.231105 -237.047382)
			(xy 92.258306 -237.004368) (xy 92.292054 -236.966274) (xy 92.331476 -236.934087) (xy 92.37555 -236.908641)
			(xy 92.423136 -236.890594) (xy 92.473 -236.880414) (xy 92.523852 -236.878365) (xy 92.574373 -236.884499)
			(xy 92.623257 -236.898659) (xy 92.669236 -236.920476) (xy 92.71112 -236.949386) (xy 92.747824 -236.984641)
			(xy 92.778397 -237.025327) (xy 92.802048 -237.07039) (xy 92.818164 -237.118664) (xy 92.826328 -237.168898)
			(xy 92.82684 -237.194344) (xy 94.074737 -237.194344) (xy 94.078832 -237.143616) (xy 94.091011 -237.094202)
			(xy 94.110959 -237.047382) (xy 94.13816 -237.004368) (xy 94.171908 -236.966274) (xy 94.21133 -236.934087)
			(xy 94.255404 -236.908641) (xy 94.30299 -236.890594) (xy 94.352854 -236.880414) (xy 94.403706 -236.878365)
			(xy 94.454227 -236.884499) (xy 94.503111 -236.898659) (xy 94.54909 -236.920476) (xy 94.590974 -236.949386)
			(xy 94.627678 -236.984641) (xy 94.658251 -237.025327) (xy 94.681902 -237.07039) (xy 94.698018 -237.118664)
			(xy 94.706182 -237.168898) (xy 94.706694 -237.194344) (xy 95.014791 -237.194344) (xy 95.018886 -237.143616)
			(xy 95.031065 -237.094202) (xy 95.051013 -237.047382) (xy 95.078214 -237.004368) (xy 95.111962 -236.966274)
			(xy 95.151384 -236.934087) (xy 95.195458 -236.908641) (xy 95.243044 -236.890594) (xy 95.292908 -236.880414)
			(xy 95.34376 -236.878365) (xy 95.394281 -236.884499) (xy 95.443165 -236.898659) (xy 95.489144 -236.920476)
			(xy 95.531028 -236.949386) (xy 95.567732 -236.984641) (xy 95.598305 -237.025327) (xy 95.621956 -237.07039)
			(xy 95.638072 -237.118664) (xy 95.646236 -237.168898) (xy 95.646748 -237.194344) (xy 95.646236 -237.21979)
			(xy 95.638072 -237.270024) (xy 95.621956 -237.318298) (xy 95.598305 -237.363361) (xy 95.567732 -237.404047)
			(xy 95.531028 -237.439302) (xy 95.489144 -237.468212) (xy 95.443165 -237.490029) (xy 95.394281 -237.504189)
			(xy 95.34376 -237.510323) (xy 95.292908 -237.508274) (xy 95.243044 -237.498094) (xy 95.195458 -237.480047)
			(xy 95.151384 -237.454601) (xy 95.111962 -237.422414) (xy 95.078214 -237.38432) (xy 95.051013 -237.341306)
			(xy 95.031065 -237.294486) (xy 95.018886 -237.245072) (xy 95.014791 -237.194344) (xy 94.706694 -237.194344)
			(xy 94.706182 -237.21979) (xy 94.698018 -237.270024) (xy 94.681902 -237.318298) (xy 94.658251 -237.363361)
			(xy 94.627678 -237.404047) (xy 94.590974 -237.439302) (xy 94.54909 -237.468212) (xy 94.503111 -237.490029)
			(xy 94.454227 -237.504189) (xy 94.403706 -237.510323) (xy 94.352854 -237.508274) (xy 94.30299 -237.498094)
			(xy 94.255404 -237.480047) (xy 94.21133 -237.454601) (xy 94.171908 -237.422414) (xy 94.13816 -237.38432)
			(xy 94.110959 -237.341306) (xy 94.091011 -237.294486) (xy 94.078832 -237.245072) (xy 94.074737 -237.194344)
			(xy 92.82684 -237.194344) (xy 92.826328 -237.21979) (xy 92.818164 -237.270024) (xy 92.802048 -237.318298)
			(xy 92.778397 -237.363361) (xy 92.747824 -237.404047) (xy 92.71112 -237.439302) (xy 92.669236 -237.468212)
			(xy 92.623257 -237.490029) (xy 92.574373 -237.504189) (xy 92.523852 -237.510323) (xy 92.473 -237.508274)
			(xy 92.423136 -237.498094) (xy 92.37555 -237.480047) (xy 92.331476 -237.454601) (xy 92.292054 -237.422414)
			(xy 92.258306 -237.38432) (xy 92.231105 -237.341306) (xy 92.211157 -237.294486) (xy 92.198978 -237.245072)
			(xy 92.194883 -237.194344) (xy 91.876372 -237.194344) (xy 91.875877 -237.218951) (xy 91.867982 -237.267528)
			(xy 91.852398 -237.314209) (xy 91.829527 -237.357786) (xy 91.799962 -237.39713) (xy 91.764469 -237.431222)
			(xy 91.723966 -237.459178) (xy 91.679504 -237.480276) (xy 91.632233 -237.493968) (xy 91.583378 -237.4999)
			(xy 91.534203 -237.497919) (xy 91.485984 -237.488075) (xy 91.439968 -237.470623) (xy 91.397347 -237.446016)
			(xy 91.359226 -237.414891) (xy 91.326591 -237.378054) (xy 91.300288 -237.336458) (xy 91.280997 -237.291182)
			(xy 91.26922 -237.243398) (xy 91.26526 -237.194344) (xy 90.946732 -237.194344) (xy 90.94622 -237.21979)
			(xy 90.938056 -237.270024) (xy 90.92194 -237.318298) (xy 90.898289 -237.363361) (xy 90.867716 -237.404047)
			(xy 90.831012 -237.439302) (xy 90.789128 -237.468212) (xy 90.743149 -237.490029) (xy 90.694265 -237.504189)
			(xy 90.643744 -237.510323) (xy 90.592892 -237.508274) (xy 90.543028 -237.498094) (xy 90.495442 -237.480047)
			(xy 90.451368 -237.454601) (xy 90.411946 -237.422414) (xy 90.378198 -237.38432) (xy 90.350997 -237.341306)
			(xy 90.331049 -237.294486) (xy 90.31887 -237.245072) (xy 90.314775 -237.194344) (xy 89.996264 -237.194344)
			(xy 89.995769 -237.218951) (xy 89.987874 -237.267528) (xy 89.97229 -237.314209) (xy 89.949419 -237.357786)
			(xy 89.919854 -237.39713) (xy 89.884361 -237.431222) (xy 89.843858 -237.459178) (xy 89.799396 -237.480276)
			(xy 89.752125 -237.493968) (xy 89.70327 -237.4999) (xy 89.654095 -237.497919) (xy 89.605876 -237.488075)
			(xy 89.55986 -237.470623) (xy 89.517239 -237.446016) (xy 89.479118 -237.414891) (xy 89.446483 -237.378054)
			(xy 89.42018 -237.336458) (xy 89.400889 -237.291182) (xy 89.389112 -237.243398) (xy 89.385152 -237.194344)
			(xy 89.056464 -237.194344) (xy 89.055969 -237.218951) (xy 89.048074 -237.267528) (xy 89.03249 -237.314209)
			(xy 89.009619 -237.357786) (xy 88.980054 -237.39713) (xy 88.944561 -237.431222) (xy 88.904058 -237.459178)
			(xy 88.859596 -237.480276) (xy 88.812325 -237.493968) (xy 88.76347 -237.4999) (xy 88.714295 -237.497919)
			(xy 88.666076 -237.488075) (xy 88.62006 -237.470623) (xy 88.577439 -237.446016) (xy 88.539318 -237.414891)
			(xy 88.506683 -237.378054) (xy 88.48038 -237.336458) (xy 88.461089 -237.291182) (xy 88.449312 -237.243398)
			(xy 88.445352 -237.194344) (xy 88.11641 -237.194344) (xy 88.115915 -237.218951) (xy 88.10802 -237.267528)
			(xy 88.092436 -237.314209) (xy 88.069565 -237.357786) (xy 88.04 -237.39713) (xy 88.004507 -237.431222)
			(xy 87.964004 -237.459178) (xy 87.919542 -237.480276) (xy 87.872271 -237.493968) (xy 87.823416 -237.4999)
			(xy 87.774241 -237.497919) (xy 87.726022 -237.488075) (xy 87.680006 -237.470623) (xy 87.637385 -237.446016)
			(xy 87.599264 -237.414891) (xy 87.566629 -237.378054) (xy 87.540326 -237.336458) (xy 87.521035 -237.291182)
			(xy 87.509258 -237.243398) (xy 87.505298 -237.194344) (xy 86.236302 -237.194344) (xy 86.235807 -237.218951)
			(xy 86.227912 -237.267528) (xy 86.212328 -237.314209) (xy 86.189457 -237.357786) (xy 86.159892 -237.39713)
			(xy 86.124399 -237.431222) (xy 86.083896 -237.459178) (xy 86.039434 -237.480276) (xy 85.992163 -237.493968)
			(xy 85.943308 -237.4999) (xy 85.894133 -237.497919) (xy 85.845914 -237.488075) (xy 85.799898 -237.470623)
			(xy 85.757277 -237.446016) (xy 85.719156 -237.414891) (xy 85.686521 -237.378054) (xy 85.660218 -237.336458)
			(xy 85.640927 -237.291182) (xy 85.62915 -237.243398) (xy 85.62519 -237.194344) (xy 85.296248 -237.194344)
			(xy 85.295753 -237.218951) (xy 85.287858 -237.267528) (xy 85.272274 -237.314209) (xy 85.249403 -237.357786)
			(xy 85.219838 -237.39713) (xy 85.184345 -237.431222) (xy 85.143842 -237.459178) (xy 85.09938 -237.480276)
			(xy 85.052109 -237.493968) (xy 85.003254 -237.4999) (xy 84.954079 -237.497919) (xy 84.90586 -237.488075)
			(xy 84.859844 -237.470623) (xy 84.817223 -237.446016) (xy 84.779102 -237.414891) (xy 84.746467 -237.378054)
			(xy 84.720164 -237.336458) (xy 84.700873 -237.291182) (xy 84.689096 -237.243398) (xy 84.685136 -237.194344)
			(xy 84.356448 -237.194344) (xy 84.355953 -237.218951) (xy 84.348058 -237.267528) (xy 84.332474 -237.314209)
			(xy 84.309603 -237.357786) (xy 84.280038 -237.39713) (xy 84.244545 -237.431222) (xy 84.204042 -237.459178)
			(xy 84.15958 -237.480276) (xy 84.112309 -237.493968) (xy 84.063454 -237.4999) (xy 84.014279 -237.497919)
			(xy 83.96606 -237.488075) (xy 83.920044 -237.470623) (xy 83.877423 -237.446016) (xy 83.839302 -237.414891)
			(xy 83.806667 -237.378054) (xy 83.780364 -237.336458) (xy 83.761073 -237.291182) (xy 83.749296 -237.243398)
			(xy 83.745336 -237.194344) (xy 83.49488 -237.194344) (xy 83.49488 -237.551468) (xy 83.494968 -237.55602)
			(xy 83.496623 -237.564971) (xy 83.498182 -237.569248) (xy 83.501738 -237.578646) (xy 83.537298 -237.618016)
			(xy 83.552792 -237.635288) (xy 83.559904 -237.641638) (xy 83.561936 -237.642908) (xy 83.567778 -237.646464)
			(xy 83.576414 -237.650528) (xy 83.585558 -237.651544) (xy 83.585812 -237.651544) (xy 83.609411 -237.65428)
			(xy 83.655419 -237.666119) (xy 83.699039 -237.684938) (xy 83.73922 -237.710282) (xy 83.774993 -237.741541)
			(xy 83.805495 -237.777961) (xy 83.829992 -237.818665) (xy 83.839304 -237.84052) (xy 83.84286 -237.847124)
			(xy 83.843114 -237.847632) (xy 83.856646 -237.871512) (xy 83.875905 -237.922905) (xy 83.885687 -237.976909)
			(xy 83.886294 -238.00435) (xy 84.215236 -238.00435) (xy 84.219196 -237.955296) (xy 84.230973 -237.907512)
			(xy 84.250264 -237.862236) (xy 84.276567 -237.82064) (xy 84.309202 -237.783803) (xy 84.347323 -237.752678)
			(xy 84.389944 -237.728071) (xy 84.43596 -237.710619) (xy 84.484179 -237.700775) (xy 84.533354 -237.698794)
			(xy 84.582209 -237.704726) (xy 84.62948 -237.718418) (xy 84.673942 -237.739516) (xy 84.714445 -237.767472)
			(xy 84.749938 -237.801564) (xy 84.779503 -237.840908) (xy 84.802374 -237.884485) (xy 84.817958 -237.931166)
			(xy 84.825853 -237.979743) (xy 84.826348 -238.00435) (xy 85.15529 -238.00435) (xy 85.15925 -237.955296)
			(xy 85.171027 -237.907512) (xy 85.190318 -237.862236) (xy 85.216621 -237.82064) (xy 85.249256 -237.783803)
			(xy 85.287377 -237.752678) (xy 85.329998 -237.728071) (xy 85.376014 -237.710619) (xy 85.424233 -237.700775)
			(xy 85.473408 -237.698794) (xy 85.522263 -237.704726) (xy 85.569534 -237.718418) (xy 85.613996 -237.739516)
			(xy 85.654499 -237.767472) (xy 85.689992 -237.801564) (xy 85.719557 -237.840908) (xy 85.742428 -237.884485)
			(xy 85.758012 -237.931166) (xy 85.765907 -237.979743) (xy 85.766402 -238.00435) (xy 86.095344 -238.00435)
			(xy 86.099304 -237.955296) (xy 86.111081 -237.907512) (xy 86.130372 -237.862236) (xy 86.156675 -237.82064)
			(xy 86.18931 -237.783803) (xy 86.227431 -237.752678) (xy 86.270052 -237.728071) (xy 86.316068 -237.710619)
			(xy 86.364287 -237.700775) (xy 86.413462 -237.698794) (xy 86.462317 -237.704726) (xy 86.509588 -237.718418)
			(xy 86.55405 -237.739516) (xy 86.594553 -237.767472) (xy 86.630046 -237.801564) (xy 86.659611 -237.840908)
			(xy 86.682482 -237.884485) (xy 86.698066 -237.931166) (xy 86.705961 -237.979743) (xy 86.706456 -238.00435)
			(xy 87.035144 -238.00435) (xy 87.039104 -237.955296) (xy 87.050881 -237.907512) (xy 87.070172 -237.862236)
			(xy 87.096475 -237.82064) (xy 87.12911 -237.783803) (xy 87.167231 -237.752678) (xy 87.209852 -237.728071)
			(xy 87.255868 -237.710619) (xy 87.304087 -237.700775) (xy 87.353262 -237.698794) (xy 87.402117 -237.704726)
			(xy 87.449388 -237.718418) (xy 87.49385 -237.739516) (xy 87.534353 -237.767472) (xy 87.569846 -237.801564)
			(xy 87.599411 -237.840908) (xy 87.622282 -237.884485) (xy 87.637866 -237.931166) (xy 87.645761 -237.979743)
			(xy 87.646256 -238.00435) (xy 87.975198 -238.00435) (xy 87.979158 -237.955296) (xy 87.990935 -237.907512)
			(xy 88.010226 -237.862236) (xy 88.036529 -237.82064) (xy 88.069164 -237.783803) (xy 88.107285 -237.752678)
			(xy 88.149906 -237.728071) (xy 88.195922 -237.710619) (xy 88.244141 -237.700775) (xy 88.293316 -237.698794)
			(xy 88.342171 -237.704726) (xy 88.389442 -237.718418) (xy 88.433904 -237.739516) (xy 88.474407 -237.767472)
			(xy 88.5099 -237.801564) (xy 88.539465 -237.840908) (xy 88.562336 -237.884485) (xy 88.57792 -237.931166)
			(xy 88.585815 -237.979743) (xy 88.58631 -238.00435) (xy 88.915252 -238.00435) (xy 88.919212 -237.955296)
			(xy 88.930989 -237.907512) (xy 88.95028 -237.862236) (xy 88.976583 -237.82064) (xy 89.009218 -237.783803)
			(xy 89.047339 -237.752678) (xy 89.08996 -237.728071) (xy 89.135976 -237.710619) (xy 89.184195 -237.700775)
			(xy 89.23337 -237.698794) (xy 89.282225 -237.704726) (xy 89.329496 -237.718418) (xy 89.373958 -237.739516)
			(xy 89.414461 -237.767472) (xy 89.449954 -237.801564) (xy 89.479519 -237.840908) (xy 89.50239 -237.884485)
			(xy 89.517974 -237.931166) (xy 89.525869 -237.979743) (xy 89.526364 -238.00435) (xy 89.855306 -238.00435)
			(xy 89.859266 -237.955296) (xy 89.871043 -237.907512) (xy 89.890334 -237.862236) (xy 89.916637 -237.82064)
			(xy 89.949272 -237.783803) (xy 89.987393 -237.752678) (xy 90.030014 -237.728071) (xy 90.07603 -237.710619)
			(xy 90.124249 -237.700775) (xy 90.173424 -237.698794) (xy 90.222279 -237.704726) (xy 90.26955 -237.718418)
			(xy 90.314012 -237.739516) (xy 90.354515 -237.767472) (xy 90.390008 -237.801564) (xy 90.419573 -237.840908)
			(xy 90.442444 -237.884485) (xy 90.458028 -237.931166) (xy 90.465923 -237.979743) (xy 90.466418 -238.00435)
			(xy 90.784675 -238.00435) (xy 90.78877 -237.953622) (xy 90.800949 -237.904208) (xy 90.820897 -237.857388)
			(xy 90.848098 -237.814374) (xy 90.881846 -237.77628) (xy 90.921268 -237.744093) (xy 90.965342 -237.718647)
			(xy 91.012928 -237.7006) (xy 91.062792 -237.69042) (xy 91.113644 -237.688371) (xy 91.164165 -237.694505)
			(xy 91.213049 -237.708665) (xy 91.259028 -237.730482) (xy 91.300912 -237.759392) (xy 91.337616 -237.794647)
			(xy 91.368189 -237.835333) (xy 91.39184 -237.880396) (xy 91.407956 -237.92867) (xy 91.41612 -237.978904)
			(xy 91.416632 -238.00435) (xy 91.724729 -238.00435) (xy 91.728824 -237.953622) (xy 91.741003 -237.904208)
			(xy 91.760951 -237.857388) (xy 91.788152 -237.814374) (xy 91.8219 -237.77628) (xy 91.861322 -237.744093)
			(xy 91.905396 -237.718647) (xy 91.952982 -237.7006) (xy 92.002846 -237.69042) (xy 92.053698 -237.688371)
			(xy 92.104219 -237.694505) (xy 92.153103 -237.708665) (xy 92.199082 -237.730482) (xy 92.240966 -237.759392)
			(xy 92.27767 -237.794647) (xy 92.308243 -237.835333) (xy 92.331894 -237.880396) (xy 92.34801 -237.92867)
			(xy 92.356174 -237.978904) (xy 92.356686 -238.00435) (xy 92.675214 -238.00435) (xy 92.679174 -237.955296)
			(xy 92.690951 -237.907512) (xy 92.710242 -237.862236) (xy 92.736545 -237.82064) (xy 92.76918 -237.783803)
			(xy 92.807301 -237.752678) (xy 92.849922 -237.728071) (xy 92.895938 -237.710619) (xy 92.944157 -237.700775)
			(xy 92.993332 -237.698794) (xy 93.042187 -237.704726) (xy 93.089458 -237.718418) (xy 93.13392 -237.739516)
			(xy 93.174423 -237.767472) (xy 93.209916 -237.801564) (xy 93.239481 -237.840908) (xy 93.262352 -237.884485)
			(xy 93.277936 -237.931166) (xy 93.285831 -237.979743) (xy 93.286326 -238.00435) (xy 93.604837 -238.00435)
			(xy 93.608932 -237.953622) (xy 93.621111 -237.904208) (xy 93.641059 -237.857388) (xy 93.66826 -237.814374)
			(xy 93.702008 -237.77628) (xy 93.74143 -237.744093) (xy 93.785504 -237.718647) (xy 93.83309 -237.7006)
			(xy 93.882954 -237.69042) (xy 93.933806 -237.688371) (xy 93.984327 -237.694505) (xy 94.033211 -237.708665)
			(xy 94.07919 -237.730482) (xy 94.121074 -237.759392) (xy 94.157778 -237.794647) (xy 94.188351 -237.835333)
			(xy 94.212002 -237.880396) (xy 94.228118 -237.92867) (xy 94.236282 -237.978904) (xy 94.236794 -238.00435)
			(xy 94.555322 -238.00435) (xy 94.559282 -237.955296) (xy 94.571059 -237.907512) (xy 94.59035 -237.862236)
			(xy 94.616653 -237.82064) (xy 94.649288 -237.783803) (xy 94.687409 -237.752678) (xy 94.73003 -237.728071)
			(xy 94.776046 -237.710619) (xy 94.824265 -237.700775) (xy 94.87344 -237.698794) (xy 94.922295 -237.704726)
			(xy 94.969566 -237.718418) (xy 95.014028 -237.739516) (xy 95.054531 -237.767472) (xy 95.090024 -237.801564)
			(xy 95.119589 -237.840908) (xy 95.14246 -237.884485) (xy 95.158044 -237.931166) (xy 95.165939 -237.979743)
			(xy 95.166434 -238.00435) (xy 95.484691 -238.00435) (xy 95.488786 -237.953622) (xy 95.500965 -237.904208)
			(xy 95.520913 -237.857388) (xy 95.548114 -237.814374) (xy 95.581862 -237.77628) (xy 95.621284 -237.744093)
			(xy 95.665358 -237.718647) (xy 95.712944 -237.7006) (xy 95.762808 -237.69042) (xy 95.81366 -237.688371)
			(xy 95.864181 -237.694505) (xy 95.913065 -237.708665) (xy 95.959044 -237.730482) (xy 96.000928 -237.759392)
			(xy 96.037632 -237.794647) (xy 96.068205 -237.835333) (xy 96.091856 -237.880396) (xy 96.107972 -237.92867)
			(xy 96.116136 -237.978904) (xy 96.116648 -238.00435) (xy 96.116136 -238.029796) (xy 96.107972 -238.08003)
			(xy 96.091856 -238.128304) (xy 96.068205 -238.173367) (xy 96.037632 -238.214053) (xy 96.000928 -238.249308)
			(xy 95.959044 -238.278218) (xy 95.913065 -238.300035) (xy 95.864181 -238.314195) (xy 95.81366 -238.320329)
			(xy 95.762808 -238.31828) (xy 95.712944 -238.3081) (xy 95.665358 -238.290053) (xy 95.621284 -238.264607)
			(xy 95.581862 -238.23242) (xy 95.548114 -238.194326) (xy 95.520913 -238.151312) (xy 95.500965 -238.104492)
			(xy 95.488786 -238.055078) (xy 95.484691 -238.00435) (xy 95.166434 -238.00435) (xy 95.165939 -238.028957)
			(xy 95.158044 -238.077534) (xy 95.14246 -238.124215) (xy 95.119589 -238.167792) (xy 95.090024 -238.207136)
			(xy 95.054531 -238.241228) (xy 95.014028 -238.269184) (xy 94.969566 -238.290282) (xy 94.922295 -238.303974)
			(xy 94.87344 -238.309906) (xy 94.824265 -238.307925) (xy 94.776046 -238.298081) (xy 94.73003 -238.280629)
			(xy 94.687409 -238.256022) (xy 94.649288 -238.224897) (xy 94.616653 -238.18806) (xy 94.59035 -238.146464)
			(xy 94.571059 -238.101188) (xy 94.559282 -238.053404) (xy 94.555322 -238.00435) (xy 94.236794 -238.00435)
			(xy 94.236282 -238.029796) (xy 94.228118 -238.08003) (xy 94.212002 -238.128304) (xy 94.188351 -238.173367)
			(xy 94.157778 -238.214053) (xy 94.121074 -238.249308) (xy 94.07919 -238.278218) (xy 94.033211 -238.300035)
			(xy 93.984327 -238.314195) (xy 93.933806 -238.320329) (xy 93.882954 -238.31828) (xy 93.83309 -238.3081)
			(xy 93.785504 -238.290053) (xy 93.74143 -238.264607) (xy 93.702008 -238.23242) (xy 93.66826 -238.194326)
			(xy 93.641059 -238.151312) (xy 93.621111 -238.104492) (xy 93.608932 -238.055078) (xy 93.604837 -238.00435)
			(xy 93.286326 -238.00435) (xy 93.285831 -238.028957) (xy 93.277936 -238.077534) (xy 93.262352 -238.124215)
			(xy 93.239481 -238.167792) (xy 93.209916 -238.207136) (xy 93.174423 -238.241228) (xy 93.13392 -238.269184)
			(xy 93.089458 -238.290282) (xy 93.042187 -238.303974) (xy 92.993332 -238.309906) (xy 92.944157 -238.307925)
			(xy 92.895938 -238.298081) (xy 92.849922 -238.280629) (xy 92.807301 -238.256022) (xy 92.76918 -238.224897)
			(xy 92.736545 -238.18806) (xy 92.710242 -238.146464) (xy 92.690951 -238.101188) (xy 92.679174 -238.053404)
			(xy 92.675214 -238.00435) (xy 92.356686 -238.00435) (xy 92.356174 -238.029796) (xy 92.34801 -238.08003)
			(xy 92.331894 -238.128304) (xy 92.308243 -238.173367) (xy 92.27767 -238.214053) (xy 92.240966 -238.249308)
			(xy 92.199082 -238.278218) (xy 92.153103 -238.300035) (xy 92.104219 -238.314195) (xy 92.053698 -238.320329)
			(xy 92.002846 -238.31828) (xy 91.952982 -238.3081) (xy 91.905396 -238.290053) (xy 91.861322 -238.264607)
			(xy 91.8219 -238.23242) (xy 91.788152 -238.194326) (xy 91.760951 -238.151312) (xy 91.741003 -238.104492)
			(xy 91.728824 -238.055078) (xy 91.724729 -238.00435) (xy 91.416632 -238.00435) (xy 91.41612 -238.029796)
			(xy 91.407956 -238.08003) (xy 91.39184 -238.128304) (xy 91.368189 -238.173367) (xy 91.337616 -238.214053)
			(xy 91.300912 -238.249308) (xy 91.259028 -238.278218) (xy 91.213049 -238.300035) (xy 91.164165 -238.314195)
			(xy 91.113644 -238.320329) (xy 91.062792 -238.31828) (xy 91.012928 -238.3081) (xy 90.965342 -238.290053)
			(xy 90.921268 -238.264607) (xy 90.881846 -238.23242) (xy 90.848098 -238.194326) (xy 90.820897 -238.151312)
			(xy 90.800949 -238.104492) (xy 90.78877 -238.055078) (xy 90.784675 -238.00435) (xy 90.466418 -238.00435)
			(xy 90.465923 -238.028957) (xy 90.458028 -238.077534) (xy 90.442444 -238.124215) (xy 90.419573 -238.167792)
			(xy 90.390008 -238.207136) (xy 90.354515 -238.241228) (xy 90.314012 -238.269184) (xy 90.26955 -238.290282)
			(xy 90.222279 -238.303974) (xy 90.173424 -238.309906) (xy 90.124249 -238.307925) (xy 90.07603 -238.298081)
			(xy 90.030014 -238.280629) (xy 89.987393 -238.256022) (xy 89.949272 -238.224897) (xy 89.916637 -238.18806)
			(xy 89.890334 -238.146464) (xy 89.871043 -238.101188) (xy 89.859266 -238.053404) (xy 89.855306 -238.00435)
			(xy 89.526364 -238.00435) (xy 89.525869 -238.028957) (xy 89.517974 -238.077534) (xy 89.50239 -238.124215)
			(xy 89.479519 -238.167792) (xy 89.449954 -238.207136) (xy 89.414461 -238.241228) (xy 89.373958 -238.269184)
			(xy 89.329496 -238.290282) (xy 89.282225 -238.303974) (xy 89.23337 -238.309906) (xy 89.184195 -238.307925)
			(xy 89.135976 -238.298081) (xy 89.08996 -238.280629) (xy 89.047339 -238.256022) (xy 89.009218 -238.224897)
			(xy 88.976583 -238.18806) (xy 88.95028 -238.146464) (xy 88.930989 -238.101188) (xy 88.919212 -238.053404)
			(xy 88.915252 -238.00435) (xy 88.58631 -238.00435) (xy 88.585815 -238.028957) (xy 88.57792 -238.077534)
			(xy 88.562336 -238.124215) (xy 88.539465 -238.167792) (xy 88.5099 -238.207136) (xy 88.474407 -238.241228)
			(xy 88.433904 -238.269184) (xy 88.389442 -238.290282) (xy 88.342171 -238.303974) (xy 88.293316 -238.309906)
			(xy 88.244141 -238.307925) (xy 88.195922 -238.298081) (xy 88.149906 -238.280629) (xy 88.107285 -238.256022)
			(xy 88.069164 -238.224897) (xy 88.036529 -238.18806) (xy 88.010226 -238.146464) (xy 87.990935 -238.101188)
			(xy 87.979158 -238.053404) (xy 87.975198 -238.00435) (xy 87.646256 -238.00435) (xy 87.645761 -238.028957)
			(xy 87.637866 -238.077534) (xy 87.622282 -238.124215) (xy 87.599411 -238.167792) (xy 87.569846 -238.207136)
			(xy 87.534353 -238.241228) (xy 87.49385 -238.269184) (xy 87.449388 -238.290282) (xy 87.402117 -238.303974)
			(xy 87.353262 -238.309906) (xy 87.304087 -238.307925) (xy 87.255868 -238.298081) (xy 87.209852 -238.280629)
			(xy 87.167231 -238.256022) (xy 87.12911 -238.224897) (xy 87.096475 -238.18806) (xy 87.070172 -238.146464)
			(xy 87.050881 -238.101188) (xy 87.039104 -238.053404) (xy 87.035144 -238.00435) (xy 86.706456 -238.00435)
			(xy 86.705961 -238.028957) (xy 86.698066 -238.077534) (xy 86.682482 -238.124215) (xy 86.659611 -238.167792)
			(xy 86.630046 -238.207136) (xy 86.594553 -238.241228) (xy 86.55405 -238.269184) (xy 86.509588 -238.290282)
			(xy 86.462317 -238.303974) (xy 86.413462 -238.309906) (xy 86.364287 -238.307925) (xy 86.316068 -238.298081)
			(xy 86.270052 -238.280629) (xy 86.227431 -238.256022) (xy 86.18931 -238.224897) (xy 86.156675 -238.18806)
			(xy 86.130372 -238.146464) (xy 86.111081 -238.101188) (xy 86.099304 -238.053404) (xy 86.095344 -238.00435)
			(xy 85.766402 -238.00435) (xy 85.765907 -238.028957) (xy 85.758012 -238.077534) (xy 85.742428 -238.124215)
			(xy 85.719557 -238.167792) (xy 85.689992 -238.207136) (xy 85.654499 -238.241228) (xy 85.613996 -238.269184)
			(xy 85.569534 -238.290282) (xy 85.522263 -238.303974) (xy 85.473408 -238.309906) (xy 85.424233 -238.307925)
			(xy 85.376014 -238.298081) (xy 85.329998 -238.280629) (xy 85.287377 -238.256022) (xy 85.249256 -238.224897)
			(xy 85.216621 -238.18806) (xy 85.190318 -238.146464) (xy 85.171027 -238.101188) (xy 85.15925 -238.053404)
			(xy 85.15529 -238.00435) (xy 84.826348 -238.00435) (xy 84.825853 -238.028957) (xy 84.817958 -238.077534)
			(xy 84.802374 -238.124215) (xy 84.779503 -238.167792) (xy 84.749938 -238.207136) (xy 84.714445 -238.241228)
			(xy 84.673942 -238.269184) (xy 84.62948 -238.290282) (xy 84.582209 -238.303974) (xy 84.533354 -238.309906)
			(xy 84.484179 -238.307925) (xy 84.43596 -238.298081) (xy 84.389944 -238.280629) (xy 84.347323 -238.256022)
			(xy 84.309202 -238.224897) (xy 84.276567 -238.18806) (xy 84.250264 -238.146464) (xy 84.230973 -238.101188)
			(xy 84.219196 -238.053404) (xy 84.215236 -238.00435) (xy 83.886294 -238.00435) (xy 83.88582 -238.028338)
			(xy 83.878307 -238.075723) (xy 83.863475 -238.12135) (xy 83.841689 -238.164094) (xy 83.813484 -238.202905)
			(xy 83.779556 -238.236826) (xy 83.74074 -238.265022) (xy 83.69799 -238.2868) (xy 83.652361 -238.301622)
			(xy 83.604974 -238.309125) (xy 83.580986 -238.309658) (xy 83.551268 -238.308134) (xy 83.551014 -238.308134)
			(xy 83.539076 -238.307118) (xy 83.528408 -238.311182) (xy 83.522869 -238.313492) (xy 83.512985 -238.320295)
			(xy 83.50885 -238.324644) (xy 83.508088 -238.325406) (xy 83.502218 -238.332391) (xy 83.495447 -238.349319)
			(xy 83.49488 -238.358426) (xy 83.49488 -238.814356) (xy 83.745336 -238.814356) (xy 83.749296 -238.765302)
			(xy 83.761073 -238.717518) (xy 83.780364 -238.672242) (xy 83.806667 -238.630646) (xy 83.839302 -238.593809)
			(xy 83.877423 -238.562684) (xy 83.920044 -238.538077) (xy 83.96606 -238.520625) (xy 84.014279 -238.510781)
			(xy 84.063454 -238.5088) (xy 84.112309 -238.514732) (xy 84.15958 -238.528424) (xy 84.204042 -238.549522)
			(xy 84.244545 -238.577478) (xy 84.280038 -238.61157) (xy 84.309603 -238.650914) (xy 84.332474 -238.694491)
			(xy 84.348058 -238.741172) (xy 84.355953 -238.789749) (xy 84.356448 -238.814356) (xy 84.685136 -238.814356)
			(xy 84.689096 -238.765302) (xy 84.700873 -238.717518) (xy 84.720164 -238.672242) (xy 84.746467 -238.630646)
			(xy 84.779102 -238.593809) (xy 84.817223 -238.562684) (xy 84.859844 -238.538077) (xy 84.90586 -238.520625)
			(xy 84.954079 -238.510781) (xy 85.003254 -238.5088) (xy 85.052109 -238.514732) (xy 85.09938 -238.528424)
			(xy 85.143842 -238.549522) (xy 85.184345 -238.577478) (xy 85.219838 -238.61157) (xy 85.249403 -238.650914)
			(xy 85.272274 -238.694491) (xy 85.287858 -238.741172) (xy 85.295753 -238.789749) (xy 85.296248 -238.814356)
			(xy 85.62519 -238.814356) (xy 85.62915 -238.765302) (xy 85.640927 -238.717518) (xy 85.660218 -238.672242)
			(xy 85.686521 -238.630646) (xy 85.719156 -238.593809) (xy 85.757277 -238.562684) (xy 85.799898 -238.538077)
			(xy 85.845914 -238.520625) (xy 85.894133 -238.510781) (xy 85.943308 -238.5088) (xy 85.992163 -238.514732)
			(xy 86.039434 -238.528424) (xy 86.083896 -238.549522) (xy 86.124399 -238.577478) (xy 86.159892 -238.61157)
			(xy 86.189457 -238.650914) (xy 86.212328 -238.694491) (xy 86.227912 -238.741172) (xy 86.235807 -238.789749)
			(xy 86.236302 -238.814356) (xy 86.565244 -238.814356) (xy 86.569204 -238.765302) (xy 86.580981 -238.717518)
			(xy 86.600272 -238.672242) (xy 86.626575 -238.630646) (xy 86.65921 -238.593809) (xy 86.697331 -238.562684)
			(xy 86.739952 -238.538077) (xy 86.785968 -238.520625) (xy 86.834187 -238.510781) (xy 86.883362 -238.5088)
			(xy 86.932217 -238.514732) (xy 86.979488 -238.528424) (xy 87.02395 -238.549522) (xy 87.064453 -238.577478)
			(xy 87.099946 -238.61157) (xy 87.129511 -238.650914) (xy 87.152382 -238.694491) (xy 87.167966 -238.741172)
			(xy 87.175861 -238.789749) (xy 87.176356 -238.814356) (xy 87.505298 -238.814356) (xy 87.509258 -238.765302)
			(xy 87.521035 -238.717518) (xy 87.540326 -238.672242) (xy 87.566629 -238.630646) (xy 87.599264 -238.593809)
			(xy 87.637385 -238.562684) (xy 87.680006 -238.538077) (xy 87.726022 -238.520625) (xy 87.774241 -238.510781)
			(xy 87.823416 -238.5088) (xy 87.872271 -238.514732) (xy 87.919542 -238.528424) (xy 87.964004 -238.549522)
			(xy 88.004507 -238.577478) (xy 88.04 -238.61157) (xy 88.069565 -238.650914) (xy 88.092436 -238.694491)
			(xy 88.10802 -238.741172) (xy 88.115915 -238.789749) (xy 88.11641 -238.814356) (xy 88.445352 -238.814356)
			(xy 88.449312 -238.765302) (xy 88.461089 -238.717518) (xy 88.48038 -238.672242) (xy 88.506683 -238.630646)
			(xy 88.539318 -238.593809) (xy 88.577439 -238.562684) (xy 88.62006 -238.538077) (xy 88.666076 -238.520625)
			(xy 88.714295 -238.510781) (xy 88.76347 -238.5088) (xy 88.812325 -238.514732) (xy 88.859596 -238.528424)
			(xy 88.904058 -238.549522) (xy 88.944561 -238.577478) (xy 88.980054 -238.61157) (xy 89.009619 -238.650914)
			(xy 89.03249 -238.694491) (xy 89.048074 -238.741172) (xy 89.055969 -238.789749) (xy 89.056464 -238.814356)
			(xy 89.385152 -238.814356) (xy 89.389112 -238.765302) (xy 89.400889 -238.717518) (xy 89.42018 -238.672242)
			(xy 89.446483 -238.630646) (xy 89.479118 -238.593809) (xy 89.517239 -238.562684) (xy 89.55986 -238.538077)
			(xy 89.605876 -238.520625) (xy 89.654095 -238.510781) (xy 89.70327 -238.5088) (xy 89.752125 -238.514732)
			(xy 89.799396 -238.528424) (xy 89.843858 -238.549522) (xy 89.884361 -238.577478) (xy 89.919854 -238.61157)
			(xy 89.949419 -238.650914) (xy 89.97229 -238.694491) (xy 89.987874 -238.741172) (xy 89.995769 -238.789749)
			(xy 89.996264 -238.814356) (xy 90.314775 -238.814356) (xy 90.31887 -238.763628) (xy 90.331049 -238.714214)
			(xy 90.350997 -238.667394) (xy 90.378198 -238.62438) (xy 90.411946 -238.586286) (xy 90.451368 -238.554099)
			(xy 90.495442 -238.528653) (xy 90.543028 -238.510606) (xy 90.592892 -238.500426) (xy 90.643744 -238.498377)
			(xy 90.694265 -238.504511) (xy 90.743149 -238.518671) (xy 90.789128 -238.540488) (xy 90.831012 -238.569398)
			(xy 90.867716 -238.604653) (xy 90.898289 -238.645339) (xy 90.92194 -238.690402) (xy 90.938056 -238.738676)
			(xy 90.94622 -238.78891) (xy 90.946732 -238.814356) (xy 91.26526 -238.814356) (xy 91.26922 -238.765302)
			(xy 91.280997 -238.717518) (xy 91.300288 -238.672242) (xy 91.326591 -238.630646) (xy 91.359226 -238.593809)
			(xy 91.397347 -238.562684) (xy 91.439968 -238.538077) (xy 91.485984 -238.520625) (xy 91.534203 -238.510781)
			(xy 91.583378 -238.5088) (xy 91.632233 -238.514732) (xy 91.679504 -238.528424) (xy 91.723966 -238.549522)
			(xy 91.764469 -238.577478) (xy 91.799962 -238.61157) (xy 91.829527 -238.650914) (xy 91.852398 -238.694491)
			(xy 91.867982 -238.741172) (xy 91.875877 -238.789749) (xy 91.876372 -238.814356) (xy 92.194883 -238.814356)
			(xy 92.198978 -238.763628) (xy 92.211157 -238.714214) (xy 92.231105 -238.667394) (xy 92.258306 -238.62438)
			(xy 92.292054 -238.586286) (xy 92.331476 -238.554099) (xy 92.37555 -238.528653) (xy 92.423136 -238.510606)
			(xy 92.473 -238.500426) (xy 92.523852 -238.498377) (xy 92.574373 -238.504511) (xy 92.623257 -238.518671)
			(xy 92.669236 -238.540488) (xy 92.71112 -238.569398) (xy 92.747824 -238.604653) (xy 92.778397 -238.645339)
			(xy 92.802048 -238.690402) (xy 92.818164 -238.738676) (xy 92.826328 -238.78891) (xy 92.82684 -238.814356)
			(xy 93.145114 -238.814356) (xy 93.149074 -238.765302) (xy 93.160851 -238.717518) (xy 93.180142 -238.672242)
			(xy 93.206445 -238.630646) (xy 93.23908 -238.593809) (xy 93.277201 -238.562684) (xy 93.319822 -238.538077)
			(xy 93.365838 -238.520625) (xy 93.414057 -238.510781) (xy 93.463232 -238.5088) (xy 93.512087 -238.514732)
			(xy 93.559358 -238.528424) (xy 93.60382 -238.549522) (xy 93.644323 -238.577478) (xy 93.679816 -238.61157)
			(xy 93.709381 -238.650914) (xy 93.732252 -238.694491) (xy 93.747836 -238.741172) (xy 93.755731 -238.789749)
			(xy 93.756226 -238.814356) (xy 94.074737 -238.814356) (xy 94.078832 -238.763628) (xy 94.091011 -238.714214)
			(xy 94.110959 -238.667394) (xy 94.13816 -238.62438) (xy 94.171908 -238.586286) (xy 94.21133 -238.554099)
			(xy 94.255404 -238.528653) (xy 94.30299 -238.510606) (xy 94.352854 -238.500426) (xy 94.403706 -238.498377)
			(xy 94.454227 -238.504511) (xy 94.503111 -238.518671) (xy 94.54909 -238.540488) (xy 94.590974 -238.569398)
			(xy 94.627678 -238.604653) (xy 94.658251 -238.645339) (xy 94.681902 -238.690402) (xy 94.698018 -238.738676)
			(xy 94.706182 -238.78891) (xy 94.706694 -238.814356) (xy 95.014791 -238.814356) (xy 95.018886 -238.763628)
			(xy 95.031065 -238.714214) (xy 95.051013 -238.667394) (xy 95.078214 -238.62438) (xy 95.111962 -238.586286)
			(xy 95.151384 -238.554099) (xy 95.195458 -238.528653) (xy 95.243044 -238.510606) (xy 95.292908 -238.500426)
			(xy 95.34376 -238.498377) (xy 95.394281 -238.504511) (xy 95.443165 -238.518671) (xy 95.489144 -238.540488)
			(xy 95.531028 -238.569398) (xy 95.567732 -238.604653) (xy 95.598305 -238.645339) (xy 95.621956 -238.690402)
			(xy 95.638072 -238.738676) (xy 95.646236 -238.78891) (xy 95.646748 -238.814356) (xy 95.646236 -238.839802)
			(xy 95.638072 -238.890036) (xy 95.621956 -238.93831) (xy 95.598305 -238.983373) (xy 95.567732 -239.024059)
			(xy 95.531028 -239.059314) (xy 95.489144 -239.088224) (xy 95.443165 -239.110041) (xy 95.394281 -239.124201)
			(xy 95.34376 -239.130335) (xy 95.292908 -239.128286) (xy 95.243044 -239.118106) (xy 95.195458 -239.100059)
			(xy 95.151384 -239.074613) (xy 95.111962 -239.042426) (xy 95.078214 -239.004332) (xy 95.051013 -238.961318)
			(xy 95.031065 -238.914498) (xy 95.018886 -238.865084) (xy 95.014791 -238.814356) (xy 94.706694 -238.814356)
			(xy 94.706182 -238.839802) (xy 94.698018 -238.890036) (xy 94.681902 -238.93831) (xy 94.658251 -238.983373)
			(xy 94.627678 -239.024059) (xy 94.590974 -239.059314) (xy 94.54909 -239.088224) (xy 94.503111 -239.110041)
			(xy 94.454227 -239.124201) (xy 94.403706 -239.130335) (xy 94.352854 -239.128286) (xy 94.30299 -239.118106)
			(xy 94.255404 -239.100059) (xy 94.21133 -239.074613) (xy 94.171908 -239.042426) (xy 94.13816 -239.004332)
			(xy 94.110959 -238.961318) (xy 94.091011 -238.914498) (xy 94.078832 -238.865084) (xy 94.074737 -238.814356)
			(xy 93.756226 -238.814356) (xy 93.755731 -238.838963) (xy 93.747836 -238.88754) (xy 93.732252 -238.934221)
			(xy 93.709381 -238.977798) (xy 93.679816 -239.017142) (xy 93.644323 -239.051234) (xy 93.60382 -239.07919)
			(xy 93.559358 -239.100288) (xy 93.512087 -239.11398) (xy 93.463232 -239.119912) (xy 93.414057 -239.117931)
			(xy 93.365838 -239.108087) (xy 93.319822 -239.090635) (xy 93.277201 -239.066028) (xy 93.23908 -239.034903)
			(xy 93.206445 -238.998066) (xy 93.180142 -238.95647) (xy 93.160851 -238.911194) (xy 93.149074 -238.86341)
			(xy 93.145114 -238.814356) (xy 92.82684 -238.814356) (xy 92.826328 -238.839802) (xy 92.818164 -238.890036)
			(xy 92.802048 -238.93831) (xy 92.778397 -238.983373) (xy 92.747824 -239.024059) (xy 92.71112 -239.059314)
			(xy 92.669236 -239.088224) (xy 92.623257 -239.110041) (xy 92.574373 -239.124201) (xy 92.523852 -239.130335)
			(xy 92.473 -239.128286) (xy 92.423136 -239.118106) (xy 92.37555 -239.100059) (xy 92.331476 -239.074613)
			(xy 92.292054 -239.042426) (xy 92.258306 -239.004332) (xy 92.231105 -238.961318) (xy 92.211157 -238.914498)
			(xy 92.198978 -238.865084) (xy 92.194883 -238.814356) (xy 91.876372 -238.814356) (xy 91.875877 -238.838963)
			(xy 91.867982 -238.88754) (xy 91.852398 -238.934221) (xy 91.829527 -238.977798) (xy 91.799962 -239.017142)
			(xy 91.764469 -239.051234) (xy 91.723966 -239.07919) (xy 91.679504 -239.100288) (xy 91.632233 -239.11398)
			(xy 91.583378 -239.119912) (xy 91.534203 -239.117931) (xy 91.485984 -239.108087) (xy 91.439968 -239.090635)
			(xy 91.397347 -239.066028) (xy 91.359226 -239.034903) (xy 91.326591 -238.998066) (xy 91.300288 -238.95647)
			(xy 91.280997 -238.911194) (xy 91.26922 -238.86341) (xy 91.26526 -238.814356) (xy 90.946732 -238.814356)
			(xy 90.94622 -238.839802) (xy 90.938056 -238.890036) (xy 90.92194 -238.93831) (xy 90.898289 -238.983373)
			(xy 90.867716 -239.024059) (xy 90.831012 -239.059314) (xy 90.789128 -239.088224) (xy 90.743149 -239.110041)
			(xy 90.694265 -239.124201) (xy 90.643744 -239.130335) (xy 90.592892 -239.128286) (xy 90.543028 -239.118106)
			(xy 90.495442 -239.100059) (xy 90.451368 -239.074613) (xy 90.411946 -239.042426) (xy 90.378198 -239.004332)
			(xy 90.350997 -238.961318) (xy 90.331049 -238.914498) (xy 90.31887 -238.865084) (xy 90.314775 -238.814356)
			(xy 89.996264 -238.814356) (xy 89.995769 -238.838963) (xy 89.987874 -238.88754) (xy 89.97229 -238.934221)
			(xy 89.949419 -238.977798) (xy 89.919854 -239.017142) (xy 89.884361 -239.051234) (xy 89.843858 -239.07919)
			(xy 89.799396 -239.100288) (xy 89.752125 -239.11398) (xy 89.70327 -239.119912) (xy 89.654095 -239.117931)
			(xy 89.605876 -239.108087) (xy 89.55986 -239.090635) (xy 89.517239 -239.066028) (xy 89.479118 -239.034903)
			(xy 89.446483 -238.998066) (xy 89.42018 -238.95647) (xy 89.400889 -238.911194) (xy 89.389112 -238.86341)
			(xy 89.385152 -238.814356) (xy 89.056464 -238.814356) (xy 89.055969 -238.838963) (xy 89.048074 -238.88754)
			(xy 89.03249 -238.934221) (xy 89.009619 -238.977798) (xy 88.980054 -239.017142) (xy 88.944561 -239.051234)
			(xy 88.904058 -239.07919) (xy 88.859596 -239.100288) (xy 88.812325 -239.11398) (xy 88.76347 -239.119912)
			(xy 88.714295 -239.117931) (xy 88.666076 -239.108087) (xy 88.62006 -239.090635) (xy 88.577439 -239.066028)
			(xy 88.539318 -239.034903) (xy 88.506683 -238.998066) (xy 88.48038 -238.95647) (xy 88.461089 -238.911194)
			(xy 88.449312 -238.86341) (xy 88.445352 -238.814356) (xy 88.11641 -238.814356) (xy 88.115915 -238.838963)
			(xy 88.10802 -238.88754) (xy 88.092436 -238.934221) (xy 88.069565 -238.977798) (xy 88.04 -239.017142)
			(xy 88.004507 -239.051234) (xy 87.964004 -239.07919) (xy 87.919542 -239.100288) (xy 87.872271 -239.11398)
			(xy 87.823416 -239.119912) (xy 87.774241 -239.117931) (xy 87.726022 -239.108087) (xy 87.680006 -239.090635)
			(xy 87.637385 -239.066028) (xy 87.599264 -239.034903) (xy 87.566629 -238.998066) (xy 87.540326 -238.95647)
			(xy 87.521035 -238.911194) (xy 87.509258 -238.86341) (xy 87.505298 -238.814356) (xy 87.176356 -238.814356)
			(xy 87.175861 -238.838963) (xy 87.167966 -238.88754) (xy 87.152382 -238.934221) (xy 87.129511 -238.977798)
			(xy 87.099946 -239.017142) (xy 87.064453 -239.051234) (xy 87.02395 -239.07919) (xy 86.979488 -239.100288)
			(xy 86.932217 -239.11398) (xy 86.883362 -239.119912) (xy 86.834187 -239.117931) (xy 86.785968 -239.108087)
			(xy 86.739952 -239.090635) (xy 86.697331 -239.066028) (xy 86.65921 -239.034903) (xy 86.626575 -238.998066)
			(xy 86.600272 -238.95647) (xy 86.580981 -238.911194) (xy 86.569204 -238.86341) (xy 86.565244 -238.814356)
			(xy 86.236302 -238.814356) (xy 86.235807 -238.838963) (xy 86.227912 -238.88754) (xy 86.212328 -238.934221)
			(xy 86.189457 -238.977798) (xy 86.159892 -239.017142) (xy 86.124399 -239.051234) (xy 86.083896 -239.07919)
			(xy 86.039434 -239.100288) (xy 85.992163 -239.11398) (xy 85.943308 -239.119912) (xy 85.894133 -239.117931)
			(xy 85.845914 -239.108087) (xy 85.799898 -239.090635) (xy 85.757277 -239.066028) (xy 85.719156 -239.034903)
			(xy 85.686521 -238.998066) (xy 85.660218 -238.95647) (xy 85.640927 -238.911194) (xy 85.62915 -238.86341)
			(xy 85.62519 -238.814356) (xy 85.296248 -238.814356) (xy 85.295753 -238.838963) (xy 85.287858 -238.88754)
			(xy 85.272274 -238.934221) (xy 85.249403 -238.977798) (xy 85.219838 -239.017142) (xy 85.184345 -239.051234)
			(xy 85.143842 -239.07919) (xy 85.09938 -239.100288) (xy 85.052109 -239.11398) (xy 85.003254 -239.119912)
			(xy 84.954079 -239.117931) (xy 84.90586 -239.108087) (xy 84.859844 -239.090635) (xy 84.817223 -239.066028)
			(xy 84.779102 -239.034903) (xy 84.746467 -238.998066) (xy 84.720164 -238.95647) (xy 84.700873 -238.911194)
			(xy 84.689096 -238.86341) (xy 84.685136 -238.814356) (xy 84.356448 -238.814356) (xy 84.355953 -238.838963)
			(xy 84.348058 -238.88754) (xy 84.332474 -238.934221) (xy 84.309603 -238.977798) (xy 84.280038 -239.017142)
			(xy 84.244545 -239.051234) (xy 84.204042 -239.07919) (xy 84.15958 -239.100288) (xy 84.112309 -239.11398)
			(xy 84.063454 -239.119912) (xy 84.014279 -239.117931) (xy 83.96606 -239.108087) (xy 83.920044 -239.090635)
			(xy 83.877423 -239.066028) (xy 83.839302 -239.034903) (xy 83.806667 -238.998066) (xy 83.780364 -238.95647)
			(xy 83.761073 -238.911194) (xy 83.749296 -238.86341) (xy 83.745336 -238.814356) (xy 83.49488 -238.814356)
			(xy 83.49488 -239.17148) (xy 83.494969 -239.176032) (xy 83.496626 -239.184982) (xy 83.498182 -239.18926)
			(xy 83.501738 -239.198658) (xy 83.537298 -239.238028) (xy 83.552792 -239.2553) (xy 83.559904 -239.26165)
			(xy 83.561936 -239.26292) (xy 83.567778 -239.266476) (xy 83.576414 -239.27054) (xy 83.585558 -239.271556)
			(xy 83.585812 -239.271556) (xy 83.609411 -239.274292) (xy 83.655418 -239.286131) (xy 83.699037 -239.30495)
			(xy 83.739218 -239.330295) (xy 83.77499 -239.361555) (xy 83.805491 -239.397976) (xy 83.829986 -239.438679)
			(xy 83.839304 -239.460532) (xy 83.84286 -239.467136) (xy 83.843114 -239.467644) (xy 83.856645 -239.491525)
			(xy 83.875902 -239.542917) (xy 83.885682 -239.596921) (xy 83.886294 -239.624362) (xy 84.215236 -239.624362)
			(xy 84.219196 -239.575308) (xy 84.230973 -239.527524) (xy 84.250264 -239.482248) (xy 84.276567 -239.440652)
			(xy 84.309202 -239.403815) (xy 84.347323 -239.37269) (xy 84.389944 -239.348083) (xy 84.43596 -239.330631)
			(xy 84.484179 -239.320787) (xy 84.533354 -239.318806) (xy 84.582209 -239.324738) (xy 84.62948 -239.33843)
			(xy 84.673942 -239.359528) (xy 84.714445 -239.387484) (xy 84.749938 -239.421576) (xy 84.779503 -239.46092)
			(xy 84.802374 -239.504497) (xy 84.817958 -239.551178) (xy 84.825853 -239.599755) (xy 84.826348 -239.624362)
			(xy 85.15529 -239.624362) (xy 85.15925 -239.575308) (xy 85.171027 -239.527524) (xy 85.190318 -239.482248)
			(xy 85.216621 -239.440652) (xy 85.249256 -239.403815) (xy 85.287377 -239.37269) (xy 85.329998 -239.348083)
			(xy 85.376014 -239.330631) (xy 85.424233 -239.320787) (xy 85.473408 -239.318806) (xy 85.522263 -239.324738)
			(xy 85.569534 -239.33843) (xy 85.613996 -239.359528) (xy 85.654499 -239.387484) (xy 85.689992 -239.421576)
			(xy 85.719557 -239.46092) (xy 85.742428 -239.504497) (xy 85.758012 -239.551178) (xy 85.765907 -239.599755)
			(xy 85.766402 -239.624362) (xy 87.035144 -239.624362) (xy 87.039104 -239.575308) (xy 87.050881 -239.527524)
			(xy 87.070172 -239.482248) (xy 87.096475 -239.440652) (xy 87.12911 -239.403815) (xy 87.167231 -239.37269)
			(xy 87.209852 -239.348083) (xy 87.255868 -239.330631) (xy 87.304087 -239.320787) (xy 87.353262 -239.318806)
			(xy 87.402117 -239.324738) (xy 87.449388 -239.33843) (xy 87.49385 -239.359528) (xy 87.534353 -239.387484)
			(xy 87.569846 -239.421576) (xy 87.599411 -239.46092) (xy 87.622282 -239.504497) (xy 87.637866 -239.551178)
			(xy 87.645761 -239.599755) (xy 87.646256 -239.624362) (xy 87.975198 -239.624362) (xy 87.979158 -239.575308)
			(xy 87.990935 -239.527524) (xy 88.010226 -239.482248) (xy 88.036529 -239.440652) (xy 88.069164 -239.403815)
			(xy 88.107285 -239.37269) (xy 88.149906 -239.348083) (xy 88.195922 -239.330631) (xy 88.244141 -239.320787)
			(xy 88.293316 -239.318806) (xy 88.342171 -239.324738) (xy 88.389442 -239.33843) (xy 88.433904 -239.359528)
			(xy 88.474407 -239.387484) (xy 88.5099 -239.421576) (xy 88.539465 -239.46092) (xy 88.562336 -239.504497)
			(xy 88.57792 -239.551178) (xy 88.585815 -239.599755) (xy 88.58631 -239.624362) (xy 88.915252 -239.624362)
			(xy 88.919212 -239.575308) (xy 88.930989 -239.527524) (xy 88.95028 -239.482248) (xy 88.976583 -239.440652)
			(xy 89.009218 -239.403815) (xy 89.047339 -239.37269) (xy 89.08996 -239.348083) (xy 89.135976 -239.330631)
			(xy 89.184195 -239.320787) (xy 89.23337 -239.318806) (xy 89.282225 -239.324738) (xy 89.329496 -239.33843)
			(xy 89.373958 -239.359528) (xy 89.414461 -239.387484) (xy 89.449954 -239.421576) (xy 89.479519 -239.46092)
			(xy 89.50239 -239.504497) (xy 89.517974 -239.551178) (xy 89.525869 -239.599755) (xy 89.526364 -239.624362)
			(xy 89.855306 -239.624362) (xy 89.859266 -239.575308) (xy 89.871043 -239.527524) (xy 89.890334 -239.482248)
			(xy 89.916637 -239.440652) (xy 89.949272 -239.403815) (xy 89.987393 -239.37269) (xy 90.030014 -239.348083)
			(xy 90.07603 -239.330631) (xy 90.124249 -239.320787) (xy 90.173424 -239.318806) (xy 90.222279 -239.324738)
			(xy 90.26955 -239.33843) (xy 90.314012 -239.359528) (xy 90.354515 -239.387484) (xy 90.390008 -239.421576)
			(xy 90.419573 -239.46092) (xy 90.442444 -239.504497) (xy 90.458028 -239.551178) (xy 90.465923 -239.599755)
			(xy 90.466418 -239.624362) (xy 90.784675 -239.624362) (xy 90.78877 -239.573634) (xy 90.800949 -239.52422)
			(xy 90.820897 -239.4774) (xy 90.848098 -239.434386) (xy 90.881846 -239.396292) (xy 90.921268 -239.364105)
			(xy 90.965342 -239.338659) (xy 91.012928 -239.320612) (xy 91.062792 -239.310432) (xy 91.113644 -239.308383)
			(xy 91.164165 -239.314517) (xy 91.213049 -239.328677) (xy 91.259028 -239.350494) (xy 91.300912 -239.379404)
			(xy 91.337616 -239.414659) (xy 91.368189 -239.455345) (xy 91.39184 -239.500408) (xy 91.407956 -239.548682)
			(xy 91.41612 -239.598916) (xy 91.416632 -239.624362) (xy 91.724729 -239.624362) (xy 91.728824 -239.573634)
			(xy 91.741003 -239.52422) (xy 91.760951 -239.4774) (xy 91.788152 -239.434386) (xy 91.8219 -239.396292)
			(xy 91.861322 -239.364105) (xy 91.905396 -239.338659) (xy 91.952982 -239.320612) (xy 92.002846 -239.310432)
			(xy 92.053698 -239.308383) (xy 92.104219 -239.314517) (xy 92.153103 -239.328677) (xy 92.199082 -239.350494)
			(xy 92.240966 -239.379404) (xy 92.27767 -239.414659) (xy 92.308243 -239.455345) (xy 92.331894 -239.500408)
			(xy 92.34801 -239.548682) (xy 92.356174 -239.598916) (xy 92.356686 -239.624362) (xy 93.604837 -239.624362)
			(xy 93.608932 -239.573634) (xy 93.621111 -239.52422) (xy 93.641059 -239.4774) (xy 93.66826 -239.434386)
			(xy 93.702008 -239.396292) (xy 93.74143 -239.364105) (xy 93.785504 -239.338659) (xy 93.83309 -239.320612)
			(xy 93.882954 -239.310432) (xy 93.933806 -239.308383) (xy 93.984327 -239.314517) (xy 94.033211 -239.328677)
			(xy 94.07919 -239.350494) (xy 94.121074 -239.379404) (xy 94.157778 -239.414659) (xy 94.188351 -239.455345)
			(xy 94.212002 -239.500408) (xy 94.228118 -239.548682) (xy 94.236282 -239.598916) (xy 94.236794 -239.624362)
			(xy 94.555322 -239.624362) (xy 94.559282 -239.575308) (xy 94.571059 -239.527524) (xy 94.59035 -239.482248)
			(xy 94.616653 -239.440652) (xy 94.649288 -239.403815) (xy 94.687409 -239.37269) (xy 94.73003 -239.348083)
			(xy 94.776046 -239.330631) (xy 94.824265 -239.320787) (xy 94.87344 -239.318806) (xy 94.922295 -239.324738)
			(xy 94.969566 -239.33843) (xy 95.014028 -239.359528) (xy 95.054531 -239.387484) (xy 95.090024 -239.421576)
			(xy 95.119589 -239.46092) (xy 95.14246 -239.504497) (xy 95.158044 -239.551178) (xy 95.165939 -239.599755)
			(xy 95.166434 -239.624362) (xy 95.484691 -239.624362) (xy 95.488786 -239.573634) (xy 95.500965 -239.52422)
			(xy 95.520913 -239.4774) (xy 95.548114 -239.434386) (xy 95.581862 -239.396292) (xy 95.621284 -239.364105)
			(xy 95.665358 -239.338659) (xy 95.712944 -239.320612) (xy 95.762808 -239.310432) (xy 95.81366 -239.308383)
			(xy 95.864181 -239.314517) (xy 95.913065 -239.328677) (xy 95.959044 -239.350494) (xy 96.000928 -239.379404)
			(xy 96.037632 -239.414659) (xy 96.068205 -239.455345) (xy 96.091856 -239.500408) (xy 96.107972 -239.548682)
			(xy 96.116136 -239.598916) (xy 96.116648 -239.624362) (xy 96.116136 -239.649808) (xy 96.107972 -239.700042)
			(xy 96.091856 -239.748316) (xy 96.068205 -239.793379) (xy 96.037632 -239.834065) (xy 96.000928 -239.86932)
			(xy 95.959044 -239.89823) (xy 95.913065 -239.920047) (xy 95.864181 -239.934207) (xy 95.81366 -239.940341)
			(xy 95.762808 -239.938292) (xy 95.712944 -239.928112) (xy 95.665358 -239.910065) (xy 95.621284 -239.884619)
			(xy 95.581862 -239.852432) (xy 95.548114 -239.814338) (xy 95.520913 -239.771324) (xy 95.500965 -239.724504)
			(xy 95.488786 -239.67509) (xy 95.484691 -239.624362) (xy 95.166434 -239.624362) (xy 95.165939 -239.648969)
			(xy 95.158044 -239.697546) (xy 95.14246 -239.744227) (xy 95.119589 -239.787804) (xy 95.090024 -239.827148)
			(xy 95.054531 -239.86124) (xy 95.014028 -239.889196) (xy 94.969566 -239.910294) (xy 94.922295 -239.923986)
			(xy 94.87344 -239.929918) (xy 94.824265 -239.927937) (xy 94.776046 -239.918093) (xy 94.73003 -239.900641)
			(xy 94.687409 -239.876034) (xy 94.649288 -239.844909) (xy 94.616653 -239.808072) (xy 94.59035 -239.766476)
			(xy 94.571059 -239.7212) (xy 94.559282 -239.673416) (xy 94.555322 -239.624362) (xy 94.236794 -239.624362)
			(xy 94.236282 -239.649808) (xy 94.228118 -239.700042) (xy 94.212002 -239.748316) (xy 94.188351 -239.793379)
			(xy 94.157778 -239.834065) (xy 94.121074 -239.86932) (xy 94.07919 -239.89823) (xy 94.033211 -239.920047)
			(xy 93.984327 -239.934207) (xy 93.933806 -239.940341) (xy 93.882954 -239.938292) (xy 93.83309 -239.928112)
			(xy 93.785504 -239.910065) (xy 93.74143 -239.884619) (xy 93.702008 -239.852432) (xy 93.66826 -239.814338)
			(xy 93.641059 -239.771324) (xy 93.621111 -239.724504) (xy 93.608932 -239.67509) (xy 93.604837 -239.624362)
			(xy 92.356686 -239.624362) (xy 92.356174 -239.649808) (xy 92.34801 -239.700042) (xy 92.331894 -239.748316)
			(xy 92.308243 -239.793379) (xy 92.27767 -239.834065) (xy 92.240966 -239.86932) (xy 92.199082 -239.89823)
			(xy 92.153103 -239.920047) (xy 92.104219 -239.934207) (xy 92.053698 -239.940341) (xy 92.002846 -239.938292)
			(xy 91.952982 -239.928112) (xy 91.905396 -239.910065) (xy 91.861322 -239.884619) (xy 91.8219 -239.852432)
			(xy 91.788152 -239.814338) (xy 91.760951 -239.771324) (xy 91.741003 -239.724504) (xy 91.728824 -239.67509)
			(xy 91.724729 -239.624362) (xy 91.416632 -239.624362) (xy 91.41612 -239.649808) (xy 91.407956 -239.700042)
			(xy 91.39184 -239.748316) (xy 91.368189 -239.793379) (xy 91.337616 -239.834065) (xy 91.300912 -239.86932)
			(xy 91.259028 -239.89823) (xy 91.213049 -239.920047) (xy 91.164165 -239.934207) (xy 91.113644 -239.940341)
			(xy 91.062792 -239.938292) (xy 91.012928 -239.928112) (xy 90.965342 -239.910065) (xy 90.921268 -239.884619)
			(xy 90.881846 -239.852432) (xy 90.848098 -239.814338) (xy 90.820897 -239.771324) (xy 90.800949 -239.724504)
			(xy 90.78877 -239.67509) (xy 90.784675 -239.624362) (xy 90.466418 -239.624362) (xy 90.465923 -239.648969)
			(xy 90.458028 -239.697546) (xy 90.442444 -239.744227) (xy 90.419573 -239.787804) (xy 90.390008 -239.827148)
			(xy 90.354515 -239.86124) (xy 90.314012 -239.889196) (xy 90.26955 -239.910294) (xy 90.222279 -239.923986)
			(xy 90.173424 -239.929918) (xy 90.124249 -239.927937) (xy 90.07603 -239.918093) (xy 90.030014 -239.900641)
			(xy 89.987393 -239.876034) (xy 89.949272 -239.844909) (xy 89.916637 -239.808072) (xy 89.890334 -239.766476)
			(xy 89.871043 -239.7212) (xy 89.859266 -239.673416) (xy 89.855306 -239.624362) (xy 89.526364 -239.624362)
			(xy 89.525869 -239.648969) (xy 89.517974 -239.697546) (xy 89.50239 -239.744227) (xy 89.479519 -239.787804)
			(xy 89.449954 -239.827148) (xy 89.414461 -239.86124) (xy 89.373958 -239.889196) (xy 89.329496 -239.910294)
			(xy 89.282225 -239.923986) (xy 89.23337 -239.929918) (xy 89.184195 -239.927937) (xy 89.135976 -239.918093)
			(xy 89.08996 -239.900641) (xy 89.047339 -239.876034) (xy 89.009218 -239.844909) (xy 88.976583 -239.808072)
			(xy 88.95028 -239.766476) (xy 88.930989 -239.7212) (xy 88.919212 -239.673416) (xy 88.915252 -239.624362)
			(xy 88.58631 -239.624362) (xy 88.585815 -239.648969) (xy 88.57792 -239.697546) (xy 88.562336 -239.744227)
			(xy 88.539465 -239.787804) (xy 88.5099 -239.827148) (xy 88.474407 -239.86124) (xy 88.433904 -239.889196)
			(xy 88.389442 -239.910294) (xy 88.342171 -239.923986) (xy 88.293316 -239.929918) (xy 88.244141 -239.927937)
			(xy 88.195922 -239.918093) (xy 88.149906 -239.900641) (xy 88.107285 -239.876034) (xy 88.069164 -239.844909)
			(xy 88.036529 -239.808072) (xy 88.010226 -239.766476) (xy 87.990935 -239.7212) (xy 87.979158 -239.673416)
			(xy 87.975198 -239.624362) (xy 87.646256 -239.624362) (xy 87.645761 -239.648969) (xy 87.637866 -239.697546)
			(xy 87.622282 -239.744227) (xy 87.599411 -239.787804) (xy 87.569846 -239.827148) (xy 87.534353 -239.86124)
			(xy 87.49385 -239.889196) (xy 87.449388 -239.910294) (xy 87.402117 -239.923986) (xy 87.353262 -239.929918)
			(xy 87.304087 -239.927937) (xy 87.255868 -239.918093) (xy 87.209852 -239.900641) (xy 87.167231 -239.876034)
			(xy 87.12911 -239.844909) (xy 87.096475 -239.808072) (xy 87.070172 -239.766476) (xy 87.050881 -239.7212)
			(xy 87.039104 -239.673416) (xy 87.035144 -239.624362) (xy 85.766402 -239.624362) (xy 85.765907 -239.648969)
			(xy 85.758012 -239.697546) (xy 85.742428 -239.744227) (xy 85.719557 -239.787804) (xy 85.689992 -239.827148)
			(xy 85.654499 -239.86124) (xy 85.613996 -239.889196) (xy 85.569534 -239.910294) (xy 85.522263 -239.923986)
			(xy 85.473408 -239.929918) (xy 85.424233 -239.927937) (xy 85.376014 -239.918093) (xy 85.329998 -239.900641)
			(xy 85.287377 -239.876034) (xy 85.249256 -239.844909) (xy 85.216621 -239.808072) (xy 85.190318 -239.766476)
			(xy 85.171027 -239.7212) (xy 85.15925 -239.673416) (xy 85.15529 -239.624362) (xy 84.826348 -239.624362)
			(xy 84.825853 -239.648969) (xy 84.817958 -239.697546) (xy 84.802374 -239.744227) (xy 84.779503 -239.787804)
			(xy 84.749938 -239.827148) (xy 84.714445 -239.86124) (xy 84.673942 -239.889196) (xy 84.62948 -239.910294)
			(xy 84.582209 -239.923986) (xy 84.533354 -239.929918) (xy 84.484179 -239.927937) (xy 84.43596 -239.918093)
			(xy 84.389944 -239.900641) (xy 84.347323 -239.876034) (xy 84.309202 -239.844909) (xy 84.276567 -239.808072)
			(xy 84.250264 -239.766476) (xy 84.230973 -239.7212) (xy 84.219196 -239.673416) (xy 84.215236 -239.624362)
			(xy 83.886294 -239.624362) (xy 83.885851 -239.648357) (xy 83.878349 -239.695756) (xy 83.863523 -239.741398)
			(xy 83.84174 -239.784158) (xy 83.813534 -239.822984) (xy 83.779602 -239.856919) (xy 83.740779 -239.885127)
			(xy 83.69802 -239.906914) (xy 83.652379 -239.921743) (xy 83.604981 -239.929249) (xy 83.580986 -239.92967)
			(xy 83.551268 -239.928146) (xy 83.551014 -239.928146) (xy 83.539076 -239.92713) (xy 83.528408 -239.931194)
			(xy 83.522869 -239.933505) (xy 83.512987 -239.940308) (xy 83.50885 -239.944656) (xy 83.508088 -239.945418)
			(xy 83.502219 -239.952404) (xy 83.495453 -239.969332) (xy 83.49488 -239.978438) (xy 83.49488 -240.434368)
			(xy 83.745336 -240.434368) (xy 83.749296 -240.385314) (xy 83.761073 -240.33753) (xy 83.780364 -240.292254)
			(xy 83.806667 -240.250658) (xy 83.839302 -240.213821) (xy 83.877423 -240.182696) (xy 83.920044 -240.158089)
			(xy 83.96606 -240.140637) (xy 84.014279 -240.130793) (xy 84.063454 -240.128812) (xy 84.112309 -240.134744)
			(xy 84.15958 -240.148436) (xy 84.204042 -240.169534) (xy 84.244545 -240.19749) (xy 84.280038 -240.231582)
			(xy 84.309603 -240.270926) (xy 84.332474 -240.314503) (xy 84.348058 -240.361184) (xy 84.355953 -240.409761)
			(xy 84.356448 -240.434368) (xy 84.685136 -240.434368) (xy 84.689096 -240.385314) (xy 84.700873 -240.33753)
			(xy 84.720164 -240.292254) (xy 84.746467 -240.250658) (xy 84.779102 -240.213821) (xy 84.817223 -240.182696)
			(xy 84.859844 -240.158089) (xy 84.90586 -240.140637) (xy 84.954079 -240.130793) (xy 85.003254 -240.128812)
			(xy 85.052109 -240.134744) (xy 85.09938 -240.148436) (xy 85.143842 -240.169534) (xy 85.184345 -240.19749)
			(xy 85.219838 -240.231582) (xy 85.249403 -240.270926) (xy 85.272274 -240.314503) (xy 85.287858 -240.361184)
			(xy 85.295753 -240.409761) (xy 85.296248 -240.434368) (xy 85.62519 -240.434368) (xy 85.62915 -240.385314)
			(xy 85.640927 -240.33753) (xy 85.660218 -240.292254) (xy 85.686521 -240.250658) (xy 85.719156 -240.213821)
			(xy 85.757277 -240.182696) (xy 85.799898 -240.158089) (xy 85.845914 -240.140637) (xy 85.894133 -240.130793)
			(xy 85.943308 -240.128812) (xy 85.992163 -240.134744) (xy 86.039434 -240.148436) (xy 86.083896 -240.169534)
			(xy 86.124399 -240.19749) (xy 86.159892 -240.231582) (xy 86.189457 -240.270926) (xy 86.212328 -240.314503)
			(xy 86.227912 -240.361184) (xy 86.235807 -240.409761) (xy 86.236302 -240.434368) (xy 86.565244 -240.434368)
			(xy 86.569204 -240.385314) (xy 86.580981 -240.33753) (xy 86.600272 -240.292254) (xy 86.626575 -240.250658)
			(xy 86.65921 -240.213821) (xy 86.697331 -240.182696) (xy 86.739952 -240.158089) (xy 86.785968 -240.140637)
			(xy 86.834187 -240.130793) (xy 86.883362 -240.128812) (xy 86.932217 -240.134744) (xy 86.979488 -240.148436)
			(xy 87.02395 -240.169534) (xy 87.064453 -240.19749) (xy 87.099946 -240.231582) (xy 87.129511 -240.270926)
			(xy 87.152382 -240.314503) (xy 87.167966 -240.361184) (xy 87.175861 -240.409761) (xy 87.176356 -240.434368)
			(xy 87.505298 -240.434368) (xy 87.509258 -240.385314) (xy 87.521035 -240.33753) (xy 87.540326 -240.292254)
			(xy 87.566629 -240.250658) (xy 87.599264 -240.213821) (xy 87.637385 -240.182696) (xy 87.680006 -240.158089)
			(xy 87.726022 -240.140637) (xy 87.774241 -240.130793) (xy 87.823416 -240.128812) (xy 87.872271 -240.134744)
			(xy 87.919542 -240.148436) (xy 87.964004 -240.169534) (xy 88.004507 -240.19749) (xy 88.04 -240.231582)
			(xy 88.069565 -240.270926) (xy 88.092436 -240.314503) (xy 88.10802 -240.361184) (xy 88.115915 -240.409761)
			(xy 88.11641 -240.434368) (xy 88.445352 -240.434368) (xy 88.449312 -240.385314) (xy 88.461089 -240.33753)
			(xy 88.48038 -240.292254) (xy 88.506683 -240.250658) (xy 88.539318 -240.213821) (xy 88.577439 -240.182696)
			(xy 88.62006 -240.158089) (xy 88.666076 -240.140637) (xy 88.714295 -240.130793) (xy 88.76347 -240.128812)
			(xy 88.812325 -240.134744) (xy 88.859596 -240.148436) (xy 88.904058 -240.169534) (xy 88.944561 -240.19749)
			(xy 88.980054 -240.231582) (xy 89.009619 -240.270926) (xy 89.03249 -240.314503) (xy 89.048074 -240.361184)
			(xy 89.055969 -240.409761) (xy 89.056464 -240.434368) (xy 89.385152 -240.434368) (xy 89.389112 -240.385314)
			(xy 89.400889 -240.33753) (xy 89.42018 -240.292254) (xy 89.446483 -240.250658) (xy 89.479118 -240.213821)
			(xy 89.517239 -240.182696) (xy 89.55986 -240.158089) (xy 89.605876 -240.140637) (xy 89.654095 -240.130793)
			(xy 89.70327 -240.128812) (xy 89.752125 -240.134744) (xy 89.799396 -240.148436) (xy 89.843858 -240.169534)
			(xy 89.884361 -240.19749) (xy 89.919854 -240.231582) (xy 89.949419 -240.270926) (xy 89.97229 -240.314503)
			(xy 89.987874 -240.361184) (xy 89.995769 -240.409761) (xy 89.996264 -240.434368) (xy 90.314775 -240.434368)
			(xy 90.31887 -240.38364) (xy 90.331049 -240.334226) (xy 90.350997 -240.287406) (xy 90.378198 -240.244392)
			(xy 90.411946 -240.206298) (xy 90.451368 -240.174111) (xy 90.495442 -240.148665) (xy 90.543028 -240.130618)
			(xy 90.592892 -240.120438) (xy 90.643744 -240.118389) (xy 90.694265 -240.124523) (xy 90.743149 -240.138683)
			(xy 90.789128 -240.1605) (xy 90.831012 -240.18941) (xy 90.867716 -240.224665) (xy 90.898289 -240.265351)
			(xy 90.92194 -240.310414) (xy 90.938056 -240.358688) (xy 90.94622 -240.408922) (xy 90.946732 -240.434368)
			(xy 91.26526 -240.434368) (xy 91.26922 -240.385314) (xy 91.280997 -240.33753) (xy 91.300288 -240.292254)
			(xy 91.326591 -240.250658) (xy 91.359226 -240.213821) (xy 91.397347 -240.182696) (xy 91.439968 -240.158089)
			(xy 91.485984 -240.140637) (xy 91.534203 -240.130793) (xy 91.583378 -240.128812) (xy 91.632233 -240.134744)
			(xy 91.679504 -240.148436) (xy 91.723966 -240.169534) (xy 91.764469 -240.19749) (xy 91.799962 -240.231582)
			(xy 91.829527 -240.270926) (xy 91.852398 -240.314503) (xy 91.867982 -240.361184) (xy 91.875877 -240.409761)
			(xy 91.876372 -240.434368) (xy 92.194883 -240.434368) (xy 92.198978 -240.38364) (xy 92.211157 -240.334226)
			(xy 92.231105 -240.287406) (xy 92.258306 -240.244392) (xy 92.292054 -240.206298) (xy 92.331476 -240.174111)
			(xy 92.37555 -240.148665) (xy 92.423136 -240.130618) (xy 92.473 -240.120438) (xy 92.523852 -240.118389)
			(xy 92.574373 -240.124523) (xy 92.623257 -240.138683) (xy 92.669236 -240.1605) (xy 92.71112 -240.18941)
			(xy 92.747824 -240.224665) (xy 92.778397 -240.265351) (xy 92.802048 -240.310414) (xy 92.818164 -240.358688)
			(xy 92.826328 -240.408922) (xy 92.82684 -240.434368) (xy 93.145114 -240.434368) (xy 93.149074 -240.385314)
			(xy 93.160851 -240.33753) (xy 93.180142 -240.292254) (xy 93.206445 -240.250658) (xy 93.23908 -240.213821)
			(xy 93.277201 -240.182696) (xy 93.319822 -240.158089) (xy 93.365838 -240.140637) (xy 93.414057 -240.130793)
			(xy 93.463232 -240.128812) (xy 93.512087 -240.134744) (xy 93.559358 -240.148436) (xy 93.60382 -240.169534)
			(xy 93.644323 -240.19749) (xy 93.679816 -240.231582) (xy 93.709381 -240.270926) (xy 93.732252 -240.314503)
			(xy 93.747836 -240.361184) (xy 93.755731 -240.409761) (xy 93.756226 -240.434368) (xy 94.074737 -240.434368)
			(xy 94.078832 -240.38364) (xy 94.091011 -240.334226) (xy 94.110959 -240.287406) (xy 94.13816 -240.244392)
			(xy 94.171908 -240.206298) (xy 94.21133 -240.174111) (xy 94.255404 -240.148665) (xy 94.30299 -240.130618)
			(xy 94.352854 -240.120438) (xy 94.403706 -240.118389) (xy 94.454227 -240.124523) (xy 94.503111 -240.138683)
			(xy 94.54909 -240.1605) (xy 94.590974 -240.18941) (xy 94.627678 -240.224665) (xy 94.658251 -240.265351)
			(xy 94.681902 -240.310414) (xy 94.698018 -240.358688) (xy 94.706182 -240.408922) (xy 94.706694 -240.434368)
			(xy 95.014791 -240.434368) (xy 95.018886 -240.38364) (xy 95.031065 -240.334226) (xy 95.051013 -240.287406)
			(xy 95.078214 -240.244392) (xy 95.111962 -240.206298) (xy 95.151384 -240.174111) (xy 95.195458 -240.148665)
			(xy 95.243044 -240.130618) (xy 95.292908 -240.120438) (xy 95.34376 -240.118389) (xy 95.394281 -240.124523)
			(xy 95.443165 -240.138683) (xy 95.489144 -240.1605) (xy 95.531028 -240.18941) (xy 95.567732 -240.224665)
			(xy 95.598305 -240.265351) (xy 95.621956 -240.310414) (xy 95.638072 -240.358688) (xy 95.646236 -240.408922)
			(xy 95.646748 -240.434368) (xy 95.646236 -240.459814) (xy 95.638072 -240.510048) (xy 95.621956 -240.558322)
			(xy 95.598305 -240.603385) (xy 95.567732 -240.644071) (xy 95.531028 -240.679326) (xy 95.489144 -240.708236)
			(xy 95.443165 -240.730053) (xy 95.394281 -240.744213) (xy 95.34376 -240.750347) (xy 95.292908 -240.748298)
			(xy 95.243044 -240.738118) (xy 95.195458 -240.720071) (xy 95.151384 -240.694625) (xy 95.111962 -240.662438)
			(xy 95.078214 -240.624344) (xy 95.051013 -240.58133) (xy 95.031065 -240.53451) (xy 95.018886 -240.485096)
			(xy 95.014791 -240.434368) (xy 94.706694 -240.434368) (xy 94.706182 -240.459814) (xy 94.698018 -240.510048)
			(xy 94.681902 -240.558322) (xy 94.658251 -240.603385) (xy 94.627678 -240.644071) (xy 94.590974 -240.679326)
			(xy 94.54909 -240.708236) (xy 94.503111 -240.730053) (xy 94.454227 -240.744213) (xy 94.403706 -240.750347)
			(xy 94.352854 -240.748298) (xy 94.30299 -240.738118) (xy 94.255404 -240.720071) (xy 94.21133 -240.694625)
			(xy 94.171908 -240.662438) (xy 94.13816 -240.624344) (xy 94.110959 -240.58133) (xy 94.091011 -240.53451)
			(xy 94.078832 -240.485096) (xy 94.074737 -240.434368) (xy 93.756226 -240.434368) (xy 93.755731 -240.458975)
			(xy 93.747836 -240.507552) (xy 93.732252 -240.554233) (xy 93.709381 -240.59781) (xy 93.679816 -240.637154)
			(xy 93.644323 -240.671246) (xy 93.60382 -240.699202) (xy 93.559358 -240.7203) (xy 93.512087 -240.733992)
			(xy 93.463232 -240.739924) (xy 93.414057 -240.737943) (xy 93.365838 -240.728099) (xy 93.319822 -240.710647)
			(xy 93.277201 -240.68604) (xy 93.23908 -240.654915) (xy 93.206445 -240.618078) (xy 93.180142 -240.576482)
			(xy 93.160851 -240.531206) (xy 93.149074 -240.483422) (xy 93.145114 -240.434368) (xy 92.82684 -240.434368)
			(xy 92.826328 -240.459814) (xy 92.818164 -240.510048) (xy 92.802048 -240.558322) (xy 92.778397 -240.603385)
			(xy 92.747824 -240.644071) (xy 92.71112 -240.679326) (xy 92.669236 -240.708236) (xy 92.623257 -240.730053)
			(xy 92.574373 -240.744213) (xy 92.523852 -240.750347) (xy 92.473 -240.748298) (xy 92.423136 -240.738118)
			(xy 92.37555 -240.720071) (xy 92.331476 -240.694625) (xy 92.292054 -240.662438) (xy 92.258306 -240.624344)
			(xy 92.231105 -240.58133) (xy 92.211157 -240.53451) (xy 92.198978 -240.485096) (xy 92.194883 -240.434368)
			(xy 91.876372 -240.434368) (xy 91.875877 -240.458975) (xy 91.867982 -240.507552) (xy 91.852398 -240.554233)
			(xy 91.829527 -240.59781) (xy 91.799962 -240.637154) (xy 91.764469 -240.671246) (xy 91.723966 -240.699202)
			(xy 91.679504 -240.7203) (xy 91.632233 -240.733992) (xy 91.583378 -240.739924) (xy 91.534203 -240.737943)
			(xy 91.485984 -240.728099) (xy 91.439968 -240.710647) (xy 91.397347 -240.68604) (xy 91.359226 -240.654915)
			(xy 91.326591 -240.618078) (xy 91.300288 -240.576482) (xy 91.280997 -240.531206) (xy 91.26922 -240.483422)
			(xy 91.26526 -240.434368) (xy 90.946732 -240.434368) (xy 90.94622 -240.459814) (xy 90.938056 -240.510048)
			(xy 90.92194 -240.558322) (xy 90.898289 -240.603385) (xy 90.867716 -240.644071) (xy 90.831012 -240.679326)
			(xy 90.789128 -240.708236) (xy 90.743149 -240.730053) (xy 90.694265 -240.744213) (xy 90.643744 -240.750347)
			(xy 90.592892 -240.748298) (xy 90.543028 -240.738118) (xy 90.495442 -240.720071) (xy 90.451368 -240.694625)
			(xy 90.411946 -240.662438) (xy 90.378198 -240.624344) (xy 90.350997 -240.58133) (xy 90.331049 -240.53451)
			(xy 90.31887 -240.485096) (xy 90.314775 -240.434368) (xy 89.996264 -240.434368) (xy 89.995769 -240.458975)
			(xy 89.987874 -240.507552) (xy 89.97229 -240.554233) (xy 89.949419 -240.59781) (xy 89.919854 -240.637154)
			(xy 89.884361 -240.671246) (xy 89.843858 -240.699202) (xy 89.799396 -240.7203) (xy 89.752125 -240.733992)
			(xy 89.70327 -240.739924) (xy 89.654095 -240.737943) (xy 89.605876 -240.728099) (xy 89.55986 -240.710647)
			(xy 89.517239 -240.68604) (xy 89.479118 -240.654915) (xy 89.446483 -240.618078) (xy 89.42018 -240.576482)
			(xy 89.400889 -240.531206) (xy 89.389112 -240.483422) (xy 89.385152 -240.434368) (xy 89.056464 -240.434368)
			(xy 89.055969 -240.458975) (xy 89.048074 -240.507552) (xy 89.03249 -240.554233) (xy 89.009619 -240.59781)
			(xy 88.980054 -240.637154) (xy 88.944561 -240.671246) (xy 88.904058 -240.699202) (xy 88.859596 -240.7203)
			(xy 88.812325 -240.733992) (xy 88.76347 -240.739924) (xy 88.714295 -240.737943) (xy 88.666076 -240.728099)
			(xy 88.62006 -240.710647) (xy 88.577439 -240.68604) (xy 88.539318 -240.654915) (xy 88.506683 -240.618078)
			(xy 88.48038 -240.576482) (xy 88.461089 -240.531206) (xy 88.449312 -240.483422) (xy 88.445352 -240.434368)
			(xy 88.11641 -240.434368) (xy 88.115915 -240.458975) (xy 88.10802 -240.507552) (xy 88.092436 -240.554233)
			(xy 88.069565 -240.59781) (xy 88.04 -240.637154) (xy 88.004507 -240.671246) (xy 87.964004 -240.699202)
			(xy 87.919542 -240.7203) (xy 87.872271 -240.733992) (xy 87.823416 -240.739924) (xy 87.774241 -240.737943)
			(xy 87.726022 -240.728099) (xy 87.680006 -240.710647) (xy 87.637385 -240.68604) (xy 87.599264 -240.654915)
			(xy 87.566629 -240.618078) (xy 87.540326 -240.576482) (xy 87.521035 -240.531206) (xy 87.509258 -240.483422)
			(xy 87.505298 -240.434368) (xy 87.176356 -240.434368) (xy 87.175861 -240.458975) (xy 87.167966 -240.507552)
			(xy 87.152382 -240.554233) (xy 87.129511 -240.59781) (xy 87.099946 -240.637154) (xy 87.064453 -240.671246)
			(xy 87.02395 -240.699202) (xy 86.979488 -240.7203) (xy 86.932217 -240.733992) (xy 86.883362 -240.739924)
			(xy 86.834187 -240.737943) (xy 86.785968 -240.728099) (xy 86.739952 -240.710647) (xy 86.697331 -240.68604)
			(xy 86.65921 -240.654915) (xy 86.626575 -240.618078) (xy 86.600272 -240.576482) (xy 86.580981 -240.531206)
			(xy 86.569204 -240.483422) (xy 86.565244 -240.434368) (xy 86.236302 -240.434368) (xy 86.235807 -240.458975)
			(xy 86.227912 -240.507552) (xy 86.212328 -240.554233) (xy 86.189457 -240.59781) (xy 86.159892 -240.637154)
			(xy 86.124399 -240.671246) (xy 86.083896 -240.699202) (xy 86.039434 -240.7203) (xy 85.992163 -240.733992)
			(xy 85.943308 -240.739924) (xy 85.894133 -240.737943) (xy 85.845914 -240.728099) (xy 85.799898 -240.710647)
			(xy 85.757277 -240.68604) (xy 85.719156 -240.654915) (xy 85.686521 -240.618078) (xy 85.660218 -240.576482)
			(xy 85.640927 -240.531206) (xy 85.62915 -240.483422) (xy 85.62519 -240.434368) (xy 85.296248 -240.434368)
			(xy 85.295753 -240.458975) (xy 85.287858 -240.507552) (xy 85.272274 -240.554233) (xy 85.249403 -240.59781)
			(xy 85.219838 -240.637154) (xy 85.184345 -240.671246) (xy 85.143842 -240.699202) (xy 85.09938 -240.7203)
			(xy 85.052109 -240.733992) (xy 85.003254 -240.739924) (xy 84.954079 -240.737943) (xy 84.90586 -240.728099)
			(xy 84.859844 -240.710647) (xy 84.817223 -240.68604) (xy 84.779102 -240.654915) (xy 84.746467 -240.618078)
			(xy 84.720164 -240.576482) (xy 84.700873 -240.531206) (xy 84.689096 -240.483422) (xy 84.685136 -240.434368)
			(xy 84.356448 -240.434368) (xy 84.355953 -240.458975) (xy 84.348058 -240.507552) (xy 84.332474 -240.554233)
			(xy 84.309603 -240.59781) (xy 84.280038 -240.637154) (xy 84.244545 -240.671246) (xy 84.204042 -240.699202)
			(xy 84.15958 -240.7203) (xy 84.112309 -240.733992) (xy 84.063454 -240.739924) (xy 84.014279 -240.737943)
			(xy 83.96606 -240.728099) (xy 83.920044 -240.710647) (xy 83.877423 -240.68604) (xy 83.839302 -240.654915)
			(xy 83.806667 -240.618078) (xy 83.780364 -240.576482) (xy 83.761073 -240.531206) (xy 83.749296 -240.483422)
			(xy 83.745336 -240.434368) (xy 83.49488 -240.434368) (xy 83.49488 -240.791492) (xy 83.49497 -240.796043)
			(xy 83.496629 -240.804993) (xy 83.498182 -240.809272) (xy 83.501738 -240.81867) (xy 83.537298 -240.85804)
			(xy 83.552792 -240.875312) (xy 83.559904 -240.881662) (xy 83.561936 -240.882932) (xy 83.567778 -240.886488)
			(xy 83.576414 -240.890552) (xy 83.585558 -240.891568) (xy 83.585812 -240.891568) (xy 83.609411 -240.894304)
			(xy 83.655417 -240.906144) (xy 83.699036 -240.924963) (xy 83.739215 -240.950308) (xy 83.774986 -240.981569)
			(xy 83.805486 -241.01799) (xy 83.82998 -241.058694) (xy 83.839304 -241.080544) (xy 83.84286 -241.087148)
			(xy 83.843114 -241.087656) (xy 83.856644 -241.111537) (xy 83.875899 -241.16293) (xy 83.885677 -241.216933)
			(xy 83.886294 -241.244374) (xy 84.215236 -241.244374) (xy 84.219196 -241.19532) (xy 84.230973 -241.147536)
			(xy 84.250264 -241.10226) (xy 84.276567 -241.060664) (xy 84.309202 -241.023827) (xy 84.347323 -240.992702)
			(xy 84.389944 -240.968095) (xy 84.43596 -240.950643) (xy 84.484179 -240.940799) (xy 84.533354 -240.938818)
			(xy 84.582209 -240.94475) (xy 84.62948 -240.958442) (xy 84.673942 -240.97954) (xy 84.714445 -241.007496)
			(xy 84.749938 -241.041588) (xy 84.779503 -241.080932) (xy 84.802374 -241.124509) (xy 84.817958 -241.17119)
			(xy 84.825853 -241.219767) (xy 84.826348 -241.244374) (xy 85.15529 -241.244374) (xy 85.15925 -241.19532)
			(xy 85.171027 -241.147536) (xy 85.190318 -241.10226) (xy 85.216621 -241.060664) (xy 85.249256 -241.023827)
			(xy 85.287377 -240.992702) (xy 85.329998 -240.968095) (xy 85.376014 -240.950643) (xy 85.424233 -240.940799)
			(xy 85.473408 -240.938818) (xy 85.522263 -240.94475) (xy 85.569534 -240.958442) (xy 85.613996 -240.97954)
			(xy 85.654499 -241.007496) (xy 85.689992 -241.041588) (xy 85.719557 -241.080932) (xy 85.742428 -241.124509)
			(xy 85.758012 -241.17119) (xy 85.765907 -241.219767) (xy 85.766402 -241.244374) (xy 86.095344 -241.244374)
			(xy 86.099304 -241.19532) (xy 86.111081 -241.147536) (xy 86.130372 -241.10226) (xy 86.156675 -241.060664)
			(xy 86.18931 -241.023827) (xy 86.227431 -240.992702) (xy 86.270052 -240.968095) (xy 86.316068 -240.950643)
			(xy 86.364287 -240.940799) (xy 86.413462 -240.938818) (xy 86.462317 -240.94475) (xy 86.509588 -240.958442)
			(xy 86.55405 -240.97954) (xy 86.594553 -241.007496) (xy 86.630046 -241.041588) (xy 86.659611 -241.080932)
			(xy 86.682482 -241.124509) (xy 86.698066 -241.17119) (xy 86.705961 -241.219767) (xy 86.706456 -241.244374)
			(xy 87.035144 -241.244374) (xy 87.039104 -241.19532) (xy 87.050881 -241.147536) (xy 87.070172 -241.10226)
			(xy 87.096475 -241.060664) (xy 87.12911 -241.023827) (xy 87.167231 -240.992702) (xy 87.209852 -240.968095)
			(xy 87.255868 -240.950643) (xy 87.304087 -240.940799) (xy 87.353262 -240.938818) (xy 87.402117 -240.94475)
			(xy 87.449388 -240.958442) (xy 87.49385 -240.97954) (xy 87.534353 -241.007496) (xy 87.569846 -241.041588)
			(xy 87.599411 -241.080932) (xy 87.622282 -241.124509) (xy 87.637866 -241.17119) (xy 87.645761 -241.219767)
			(xy 87.646256 -241.244374) (xy 87.975198 -241.244374) (xy 87.979158 -241.19532) (xy 87.990935 -241.147536)
			(xy 88.010226 -241.10226) (xy 88.036529 -241.060664) (xy 88.069164 -241.023827) (xy 88.107285 -240.992702)
			(xy 88.149906 -240.968095) (xy 88.195922 -240.950643) (xy 88.244141 -240.940799) (xy 88.293316 -240.938818)
			(xy 88.342171 -240.94475) (xy 88.389442 -240.958442) (xy 88.433904 -240.97954) (xy 88.474407 -241.007496)
			(xy 88.5099 -241.041588) (xy 88.539465 -241.080932) (xy 88.562336 -241.124509) (xy 88.57792 -241.17119)
			(xy 88.585815 -241.219767) (xy 88.58631 -241.244374) (xy 88.915252 -241.244374) (xy 88.919212 -241.19532)
			(xy 88.930989 -241.147536) (xy 88.95028 -241.10226) (xy 88.976583 -241.060664) (xy 89.009218 -241.023827)
			(xy 89.047339 -240.992702) (xy 89.08996 -240.968095) (xy 89.135976 -240.950643) (xy 89.184195 -240.940799)
			(xy 89.23337 -240.938818) (xy 89.282225 -240.94475) (xy 89.329496 -240.958442) (xy 89.373958 -240.97954)
			(xy 89.414461 -241.007496) (xy 89.449954 -241.041588) (xy 89.479519 -241.080932) (xy 89.50239 -241.124509)
			(xy 89.517974 -241.17119) (xy 89.525869 -241.219767) (xy 89.526364 -241.244374) (xy 89.855306 -241.244374)
			(xy 89.859266 -241.19532) (xy 89.871043 -241.147536) (xy 89.890334 -241.10226) (xy 89.916637 -241.060664)
			(xy 89.949272 -241.023827) (xy 89.987393 -240.992702) (xy 90.030014 -240.968095) (xy 90.07603 -240.950643)
			(xy 90.124249 -240.940799) (xy 90.173424 -240.938818) (xy 90.222279 -240.94475) (xy 90.26955 -240.958442)
			(xy 90.314012 -240.97954) (xy 90.354515 -241.007496) (xy 90.390008 -241.041588) (xy 90.419573 -241.080932)
			(xy 90.442444 -241.124509) (xy 90.458028 -241.17119) (xy 90.465923 -241.219767) (xy 90.466418 -241.244374)
			(xy 90.784675 -241.244374) (xy 90.78877 -241.193646) (xy 90.800949 -241.144232) (xy 90.820897 -241.097412)
			(xy 90.848098 -241.054398) (xy 90.881846 -241.016304) (xy 90.921268 -240.984117) (xy 90.965342 -240.958671)
			(xy 91.012928 -240.940624) (xy 91.062792 -240.930444) (xy 91.113644 -240.928395) (xy 91.164165 -240.934529)
			(xy 91.213049 -240.948689) (xy 91.259028 -240.970506) (xy 91.300912 -240.999416) (xy 91.337616 -241.034671)
			(xy 91.368189 -241.075357) (xy 91.39184 -241.12042) (xy 91.407956 -241.168694) (xy 91.41612 -241.218928)
			(xy 91.416632 -241.244374) (xy 91.724729 -241.244374) (xy 91.728824 -241.193646) (xy 91.741003 -241.144232)
			(xy 91.760951 -241.097412) (xy 91.788152 -241.054398) (xy 91.8219 -241.016304) (xy 91.861322 -240.984117)
			(xy 91.905396 -240.958671) (xy 91.952982 -240.940624) (xy 92.002846 -240.930444) (xy 92.053698 -240.928395)
			(xy 92.104219 -240.934529) (xy 92.153103 -240.948689) (xy 92.199082 -240.970506) (xy 92.240966 -240.999416)
			(xy 92.27767 -241.034671) (xy 92.308243 -241.075357) (xy 92.331894 -241.12042) (xy 92.34801 -241.168694)
			(xy 92.356174 -241.218928) (xy 92.356686 -241.244374) (xy 92.675214 -241.244374) (xy 92.679174 -241.19532)
			(xy 92.690951 -241.147536) (xy 92.710242 -241.10226) (xy 92.736545 -241.060664) (xy 92.76918 -241.023827)
			(xy 92.807301 -240.992702) (xy 92.849922 -240.968095) (xy 92.895938 -240.950643) (xy 92.944157 -240.940799)
			(xy 92.993332 -240.938818) (xy 93.042187 -240.94475) (xy 93.089458 -240.958442) (xy 93.13392 -240.97954)
			(xy 93.174423 -241.007496) (xy 93.209916 -241.041588) (xy 93.239481 -241.080932) (xy 93.262352 -241.124509)
			(xy 93.277936 -241.17119) (xy 93.285831 -241.219767) (xy 93.286326 -241.244374) (xy 93.604837 -241.244374)
			(xy 93.608932 -241.193646) (xy 93.621111 -241.144232) (xy 93.641059 -241.097412) (xy 93.66826 -241.054398)
			(xy 93.702008 -241.016304) (xy 93.74143 -240.984117) (xy 93.785504 -240.958671) (xy 93.83309 -240.940624)
			(xy 93.882954 -240.930444) (xy 93.933806 -240.928395) (xy 93.984327 -240.934529) (xy 94.033211 -240.948689)
			(xy 94.07919 -240.970506) (xy 94.121074 -240.999416) (xy 94.157778 -241.034671) (xy 94.188351 -241.075357)
			(xy 94.212002 -241.12042) (xy 94.228118 -241.168694) (xy 94.236282 -241.218928) (xy 94.236794 -241.244374)
			(xy 94.555322 -241.244374) (xy 94.559282 -241.19532) (xy 94.571059 -241.147536) (xy 94.59035 -241.10226)
			(xy 94.616653 -241.060664) (xy 94.649288 -241.023827) (xy 94.687409 -240.992702) (xy 94.73003 -240.968095)
			(xy 94.776046 -240.950643) (xy 94.824265 -240.940799) (xy 94.87344 -240.938818) (xy 94.922295 -240.94475)
			(xy 94.969566 -240.958442) (xy 95.014028 -240.97954) (xy 95.054531 -241.007496) (xy 95.090024 -241.041588)
			(xy 95.119589 -241.080932) (xy 95.14246 -241.124509) (xy 95.158044 -241.17119) (xy 95.165939 -241.219767)
			(xy 95.166434 -241.244374) (xy 95.484691 -241.244374) (xy 95.488786 -241.193646) (xy 95.500965 -241.144232)
			(xy 95.520913 -241.097412) (xy 95.548114 -241.054398) (xy 95.581862 -241.016304) (xy 95.621284 -240.984117)
			(xy 95.665358 -240.958671) (xy 95.712944 -240.940624) (xy 95.762808 -240.930444) (xy 95.81366 -240.928395)
			(xy 95.864181 -240.934529) (xy 95.913065 -240.948689) (xy 95.959044 -240.970506) (xy 96.000928 -240.999416)
			(xy 96.037632 -241.034671) (xy 96.068205 -241.075357) (xy 96.091856 -241.12042) (xy 96.107972 -241.168694)
			(xy 96.116136 -241.218928) (xy 96.116648 -241.244374) (xy 96.116136 -241.26982) (xy 96.107972 -241.320054)
			(xy 96.091856 -241.368328) (xy 96.068205 -241.413391) (xy 96.037632 -241.454077) (xy 96.000928 -241.489332)
			(xy 95.959044 -241.518242) (xy 95.913065 -241.540059) (xy 95.864181 -241.554219) (xy 95.81366 -241.560353)
			(xy 95.762808 -241.558304) (xy 95.712944 -241.548124) (xy 95.665358 -241.530077) (xy 95.621284 -241.504631)
			(xy 95.581862 -241.472444) (xy 95.548114 -241.43435) (xy 95.520913 -241.391336) (xy 95.500965 -241.344516)
			(xy 95.488786 -241.295102) (xy 95.484691 -241.244374) (xy 95.166434 -241.244374) (xy 95.165939 -241.268981)
			(xy 95.158044 -241.317558) (xy 95.14246 -241.364239) (xy 95.119589 -241.407816) (xy 95.090024 -241.44716)
			(xy 95.054531 -241.481252) (xy 95.014028 -241.509208) (xy 94.969566 -241.530306) (xy 94.922295 -241.543998)
			(xy 94.87344 -241.54993) (xy 94.824265 -241.547949) (xy 94.776046 -241.538105) (xy 94.73003 -241.520653)
			(xy 94.687409 -241.496046) (xy 94.649288 -241.464921) (xy 94.616653 -241.428084) (xy 94.59035 -241.386488)
			(xy 94.571059 -241.341212) (xy 94.559282 -241.293428) (xy 94.555322 -241.244374) (xy 94.236794 -241.244374)
			(xy 94.236282 -241.26982) (xy 94.228118 -241.320054) (xy 94.212002 -241.368328) (xy 94.188351 -241.413391)
			(xy 94.157778 -241.454077) (xy 94.121074 -241.489332) (xy 94.07919 -241.518242) (xy 94.033211 -241.540059)
			(xy 93.984327 -241.554219) (xy 93.933806 -241.560353) (xy 93.882954 -241.558304) (xy 93.83309 -241.548124)
			(xy 93.785504 -241.530077) (xy 93.74143 -241.504631) (xy 93.702008 -241.472444) (xy 93.66826 -241.43435)
			(xy 93.641059 -241.391336) (xy 93.621111 -241.344516) (xy 93.608932 -241.295102) (xy 93.604837 -241.244374)
			(xy 93.286326 -241.244374) (xy 93.285831 -241.268981) (xy 93.277936 -241.317558) (xy 93.262352 -241.364239)
			(xy 93.239481 -241.407816) (xy 93.209916 -241.44716) (xy 93.174423 -241.481252) (xy 93.13392 -241.509208)
			(xy 93.089458 -241.530306) (xy 93.042187 -241.543998) (xy 92.993332 -241.54993) (xy 92.944157 -241.547949)
			(xy 92.895938 -241.538105) (xy 92.849922 -241.520653) (xy 92.807301 -241.496046) (xy 92.76918 -241.464921)
			(xy 92.736545 -241.428084) (xy 92.710242 -241.386488) (xy 92.690951 -241.341212) (xy 92.679174 -241.293428)
			(xy 92.675214 -241.244374) (xy 92.356686 -241.244374) (xy 92.356174 -241.26982) (xy 92.34801 -241.320054)
			(xy 92.331894 -241.368328) (xy 92.308243 -241.413391) (xy 92.27767 -241.454077) (xy 92.240966 -241.489332)
			(xy 92.199082 -241.518242) (xy 92.153103 -241.540059) (xy 92.104219 -241.554219) (xy 92.053698 -241.560353)
			(xy 92.002846 -241.558304) (xy 91.952982 -241.548124) (xy 91.905396 -241.530077) (xy 91.861322 -241.504631)
			(xy 91.8219 -241.472444) (xy 91.788152 -241.43435) (xy 91.760951 -241.391336) (xy 91.741003 -241.344516)
			(xy 91.728824 -241.295102) (xy 91.724729 -241.244374) (xy 91.416632 -241.244374) (xy 91.41612 -241.26982)
			(xy 91.407956 -241.320054) (xy 91.39184 -241.368328) (xy 91.368189 -241.413391) (xy 91.337616 -241.454077)
			(xy 91.300912 -241.489332) (xy 91.259028 -241.518242) (xy 91.213049 -241.540059) (xy 91.164165 -241.554219)
			(xy 91.113644 -241.560353) (xy 91.062792 -241.558304) (xy 91.012928 -241.548124) (xy 90.965342 -241.530077)
			(xy 90.921268 -241.504631) (xy 90.881846 -241.472444) (xy 90.848098 -241.43435) (xy 90.820897 -241.391336)
			(xy 90.800949 -241.344516) (xy 90.78877 -241.295102) (xy 90.784675 -241.244374) (xy 90.466418 -241.244374)
			(xy 90.465923 -241.268981) (xy 90.458028 -241.317558) (xy 90.442444 -241.364239) (xy 90.419573 -241.407816)
			(xy 90.390008 -241.44716) (xy 90.354515 -241.481252) (xy 90.314012 -241.509208) (xy 90.26955 -241.530306)
			(xy 90.222279 -241.543998) (xy 90.173424 -241.54993) (xy 90.124249 -241.547949) (xy 90.07603 -241.538105)
			(xy 90.030014 -241.520653) (xy 89.987393 -241.496046) (xy 89.949272 -241.464921) (xy 89.916637 -241.428084)
			(xy 89.890334 -241.386488) (xy 89.871043 -241.341212) (xy 89.859266 -241.293428) (xy 89.855306 -241.244374)
			(xy 89.526364 -241.244374) (xy 89.525869 -241.268981) (xy 89.517974 -241.317558) (xy 89.50239 -241.364239)
			(xy 89.479519 -241.407816) (xy 89.449954 -241.44716) (xy 89.414461 -241.481252) (xy 89.373958 -241.509208)
			(xy 89.329496 -241.530306) (xy 89.282225 -241.543998) (xy 89.23337 -241.54993) (xy 89.184195 -241.547949)
			(xy 89.135976 -241.538105) (xy 89.08996 -241.520653) (xy 89.047339 -241.496046) (xy 89.009218 -241.464921)
			(xy 88.976583 -241.428084) (xy 88.95028 -241.386488) (xy 88.930989 -241.341212) (xy 88.919212 -241.293428)
			(xy 88.915252 -241.244374) (xy 88.58631 -241.244374) (xy 88.585815 -241.268981) (xy 88.57792 -241.317558)
			(xy 88.562336 -241.364239) (xy 88.539465 -241.407816) (xy 88.5099 -241.44716) (xy 88.474407 -241.481252)
			(xy 88.433904 -241.509208) (xy 88.389442 -241.530306) (xy 88.342171 -241.543998) (xy 88.293316 -241.54993)
			(xy 88.244141 -241.547949) (xy 88.195922 -241.538105) (xy 88.149906 -241.520653) (xy 88.107285 -241.496046)
			(xy 88.069164 -241.464921) (xy 88.036529 -241.428084) (xy 88.010226 -241.386488) (xy 87.990935 -241.341212)
			(xy 87.979158 -241.293428) (xy 87.975198 -241.244374) (xy 87.646256 -241.244374) (xy 87.645761 -241.268981)
			(xy 87.637866 -241.317558) (xy 87.622282 -241.364239) (xy 87.599411 -241.407816) (xy 87.569846 -241.44716)
			(xy 87.534353 -241.481252) (xy 87.49385 -241.509208) (xy 87.449388 -241.530306) (xy 87.402117 -241.543998)
			(xy 87.353262 -241.54993) (xy 87.304087 -241.547949) (xy 87.255868 -241.538105) (xy 87.209852 -241.520653)
			(xy 87.167231 -241.496046) (xy 87.12911 -241.464921) (xy 87.096475 -241.428084) (xy 87.070172 -241.386488)
			(xy 87.050881 -241.341212) (xy 87.039104 -241.293428) (xy 87.035144 -241.244374) (xy 86.706456 -241.244374)
			(xy 86.705961 -241.268981) (xy 86.698066 -241.317558) (xy 86.682482 -241.364239) (xy 86.659611 -241.407816)
			(xy 86.630046 -241.44716) (xy 86.594553 -241.481252) (xy 86.55405 -241.509208) (xy 86.509588 -241.530306)
			(xy 86.462317 -241.543998) (xy 86.413462 -241.54993) (xy 86.364287 -241.547949) (xy 86.316068 -241.538105)
			(xy 86.270052 -241.520653) (xy 86.227431 -241.496046) (xy 86.18931 -241.464921) (xy 86.156675 -241.428084)
			(xy 86.130372 -241.386488) (xy 86.111081 -241.341212) (xy 86.099304 -241.293428) (xy 86.095344 -241.244374)
			(xy 85.766402 -241.244374) (xy 85.765907 -241.268981) (xy 85.758012 -241.317558) (xy 85.742428 -241.364239)
			(xy 85.719557 -241.407816) (xy 85.689992 -241.44716) (xy 85.654499 -241.481252) (xy 85.613996 -241.509208)
			(xy 85.569534 -241.530306) (xy 85.522263 -241.543998) (xy 85.473408 -241.54993) (xy 85.424233 -241.547949)
			(xy 85.376014 -241.538105) (xy 85.329998 -241.520653) (xy 85.287377 -241.496046) (xy 85.249256 -241.464921)
			(xy 85.216621 -241.428084) (xy 85.190318 -241.386488) (xy 85.171027 -241.341212) (xy 85.15925 -241.293428)
			(xy 85.15529 -241.244374) (xy 84.826348 -241.244374) (xy 84.825853 -241.268981) (xy 84.817958 -241.317558)
			(xy 84.802374 -241.364239) (xy 84.779503 -241.407816) (xy 84.749938 -241.44716) (xy 84.714445 -241.481252)
			(xy 84.673942 -241.509208) (xy 84.62948 -241.530306) (xy 84.582209 -241.543998) (xy 84.533354 -241.54993)
			(xy 84.484179 -241.547949) (xy 84.43596 -241.538105) (xy 84.389944 -241.520653) (xy 84.347323 -241.496046)
			(xy 84.309202 -241.464921) (xy 84.276567 -241.428084) (xy 84.250264 -241.386488) (xy 84.230973 -241.341212)
			(xy 84.219196 -241.293428) (xy 84.215236 -241.244374) (xy 83.886294 -241.244374) (xy 83.88585 -241.268368)
			(xy 83.878346 -241.315766) (xy 83.86352 -241.361406) (xy 83.841736 -241.404165) (xy 83.81353 -241.442989)
			(xy 83.779598 -241.476922) (xy 83.740775 -241.505129) (xy 83.698017 -241.526915) (xy 83.652378 -241.541743)
			(xy 83.60498 -241.549249) (xy 83.580986 -241.549682) (xy 83.551268 -241.548158) (xy 83.551014 -241.548158)
			(xy 83.539076 -241.547142) (xy 83.528408 -241.551206) (xy 83.522867 -241.553514) (xy 83.512976 -241.560309)
			(xy 83.50885 -241.564668) (xy 83.508088 -241.56543) (xy 83.502221 -241.572416) (xy 83.495459 -241.589345)
			(xy 83.49488 -241.59845) (xy 83.49488 -242.05438) (xy 83.745336 -242.05438) (xy 83.749296 -242.005326)
			(xy 83.761073 -241.957542) (xy 83.780364 -241.912266) (xy 83.806667 -241.87067) (xy 83.839302 -241.833833)
			(xy 83.877423 -241.802708) (xy 83.920044 -241.778101) (xy 83.96606 -241.760649) (xy 84.014279 -241.750805)
			(xy 84.063454 -241.748824) (xy 84.112309 -241.754756) (xy 84.15958 -241.768448) (xy 84.204042 -241.789546)
			(xy 84.244545 -241.817502) (xy 84.280038 -241.851594) (xy 84.309603 -241.890938) (xy 84.332474 -241.934515)
			(xy 84.348058 -241.981196) (xy 84.355953 -242.029773) (xy 84.356448 -242.05438) (xy 84.685136 -242.05438)
			(xy 84.689096 -242.005326) (xy 84.700873 -241.957542) (xy 84.720164 -241.912266) (xy 84.746467 -241.87067)
			(xy 84.779102 -241.833833) (xy 84.817223 -241.802708) (xy 84.859844 -241.778101) (xy 84.90586 -241.760649)
			(xy 84.954079 -241.750805) (xy 85.003254 -241.748824) (xy 85.052109 -241.754756) (xy 85.09938 -241.768448)
			(xy 85.143842 -241.789546) (xy 85.184345 -241.817502) (xy 85.219838 -241.851594) (xy 85.249403 -241.890938)
			(xy 85.272274 -241.934515) (xy 85.287858 -241.981196) (xy 85.295753 -242.029773) (xy 85.296248 -242.05438)
			(xy 85.62519 -242.05438) (xy 85.62915 -242.005326) (xy 85.640927 -241.957542) (xy 85.660218 -241.912266)
			(xy 85.686521 -241.87067) (xy 85.719156 -241.833833) (xy 85.757277 -241.802708) (xy 85.799898 -241.778101)
			(xy 85.845914 -241.760649) (xy 85.894133 -241.750805) (xy 85.943308 -241.748824) (xy 85.992163 -241.754756)
			(xy 86.039434 -241.768448) (xy 86.083896 -241.789546) (xy 86.124399 -241.817502) (xy 86.159892 -241.851594)
			(xy 86.189457 -241.890938) (xy 86.212328 -241.934515) (xy 86.227912 -241.981196) (xy 86.235807 -242.029773)
			(xy 86.236302 -242.05438) (xy 87.505298 -242.05438) (xy 87.509258 -242.005326) (xy 87.521035 -241.957542)
			(xy 87.540326 -241.912266) (xy 87.566629 -241.87067) (xy 87.599264 -241.833833) (xy 87.637385 -241.802708)
			(xy 87.680006 -241.778101) (xy 87.726022 -241.760649) (xy 87.774241 -241.750805) (xy 87.823416 -241.748824)
			(xy 87.872271 -241.754756) (xy 87.919542 -241.768448) (xy 87.964004 -241.789546) (xy 88.004507 -241.817502)
			(xy 88.04 -241.851594) (xy 88.069565 -241.890938) (xy 88.092436 -241.934515) (xy 88.10802 -241.981196)
			(xy 88.115915 -242.029773) (xy 88.11641 -242.05438) (xy 88.445352 -242.05438) (xy 88.449312 -242.005326)
			(xy 88.461089 -241.957542) (xy 88.48038 -241.912266) (xy 88.506683 -241.87067) (xy 88.539318 -241.833833)
			(xy 88.577439 -241.802708) (xy 88.62006 -241.778101) (xy 88.666076 -241.760649) (xy 88.714295 -241.750805)
			(xy 88.76347 -241.748824) (xy 88.812325 -241.754756) (xy 88.859596 -241.768448) (xy 88.904058 -241.789546)
			(xy 88.944561 -241.817502) (xy 88.980054 -241.851594) (xy 89.009619 -241.890938) (xy 89.03249 -241.934515)
			(xy 89.048074 -241.981196) (xy 89.055969 -242.029773) (xy 89.056464 -242.05438) (xy 89.385152 -242.05438)
			(xy 89.389112 -242.005326) (xy 89.400889 -241.957542) (xy 89.42018 -241.912266) (xy 89.446483 -241.87067)
			(xy 89.479118 -241.833833) (xy 89.517239 -241.802708) (xy 89.55986 -241.778101) (xy 89.605876 -241.760649)
			(xy 89.654095 -241.750805) (xy 89.70327 -241.748824) (xy 89.752125 -241.754756) (xy 89.799396 -241.768448)
			(xy 89.843858 -241.789546) (xy 89.884361 -241.817502) (xy 89.919854 -241.851594) (xy 89.949419 -241.890938)
			(xy 89.97229 -241.934515) (xy 89.987874 -241.981196) (xy 89.995769 -242.029773) (xy 89.996264 -242.05438)
			(xy 90.314775 -242.05438) (xy 90.31887 -242.003652) (xy 90.331049 -241.954238) (xy 90.350997 -241.907418)
			(xy 90.378198 -241.864404) (xy 90.411946 -241.82631) (xy 90.451368 -241.794123) (xy 90.495442 -241.768677)
			(xy 90.543028 -241.75063) (xy 90.592892 -241.74045) (xy 90.643744 -241.738401) (xy 90.694265 -241.744535)
			(xy 90.743149 -241.758695) (xy 90.789128 -241.780512) (xy 90.831012 -241.809422) (xy 90.867716 -241.844677)
			(xy 90.898289 -241.885363) (xy 90.92194 -241.930426) (xy 90.938056 -241.9787) (xy 90.94622 -242.028934)
			(xy 90.946732 -242.05438) (xy 91.26526 -242.05438) (xy 91.26922 -242.005326) (xy 91.280997 -241.957542)
			(xy 91.300288 -241.912266) (xy 91.326591 -241.87067) (xy 91.359226 -241.833833) (xy 91.397347 -241.802708)
			(xy 91.439968 -241.778101) (xy 91.485984 -241.760649) (xy 91.534203 -241.750805) (xy 91.583378 -241.748824)
			(xy 91.632233 -241.754756) (xy 91.679504 -241.768448) (xy 91.723966 -241.789546) (xy 91.764469 -241.817502)
			(xy 91.799962 -241.851594) (xy 91.829527 -241.890938) (xy 91.852398 -241.934515) (xy 91.867982 -241.981196)
			(xy 91.875877 -242.029773) (xy 91.876372 -242.05438) (xy 92.194883 -242.05438) (xy 92.198978 -242.003652)
			(xy 92.211157 -241.954238) (xy 92.231105 -241.907418) (xy 92.258306 -241.864404) (xy 92.292054 -241.82631)
			(xy 92.331476 -241.794123) (xy 92.37555 -241.768677) (xy 92.423136 -241.75063) (xy 92.473 -241.74045)
			(xy 92.523852 -241.738401) (xy 92.574373 -241.744535) (xy 92.623257 -241.758695) (xy 92.669236 -241.780512)
			(xy 92.71112 -241.809422) (xy 92.747824 -241.844677) (xy 92.778397 -241.885363) (xy 92.802048 -241.930426)
			(xy 92.818164 -241.9787) (xy 92.826328 -242.028934) (xy 92.82684 -242.05438) (xy 94.074737 -242.05438)
			(xy 94.078832 -242.003652) (xy 94.091011 -241.954238) (xy 94.110959 -241.907418) (xy 94.13816 -241.864404)
			(xy 94.171908 -241.82631) (xy 94.21133 -241.794123) (xy 94.255404 -241.768677) (xy 94.30299 -241.75063)
			(xy 94.352854 -241.74045) (xy 94.403706 -241.738401) (xy 94.454227 -241.744535) (xy 94.503111 -241.758695)
			(xy 94.54909 -241.780512) (xy 94.590974 -241.809422) (xy 94.627678 -241.844677) (xy 94.658251 -241.885363)
			(xy 94.681902 -241.930426) (xy 94.698018 -241.9787) (xy 94.706182 -242.028934) (xy 94.706694 -242.05438)
			(xy 95.014791 -242.05438) (xy 95.018886 -242.003652) (xy 95.031065 -241.954238) (xy 95.051013 -241.907418)
			(xy 95.078214 -241.864404) (xy 95.111962 -241.82631) (xy 95.151384 -241.794123) (xy 95.195458 -241.768677)
			(xy 95.243044 -241.75063) (xy 95.292908 -241.74045) (xy 95.34376 -241.738401) (xy 95.394281 -241.744535)
			(xy 95.443165 -241.758695) (xy 95.489144 -241.780512) (xy 95.531028 -241.809422) (xy 95.567732 -241.844677)
			(xy 95.598305 -241.885363) (xy 95.621956 -241.930426) (xy 95.638072 -241.9787) (xy 95.646236 -242.028934)
			(xy 95.646748 -242.05438) (xy 95.965276 -242.05438) (xy 95.969236 -242.005326) (xy 95.981013 -241.957542)
			(xy 96.000304 -241.912266) (xy 96.026607 -241.87067) (xy 96.059242 -241.833833) (xy 96.097363 -241.802708)
			(xy 96.139984 -241.778101) (xy 96.186 -241.760649) (xy 96.234219 -241.750805) (xy 96.283394 -241.748824)
			(xy 96.332249 -241.754756) (xy 96.37952 -241.768448) (xy 96.423982 -241.789546) (xy 96.464485 -241.817502)
			(xy 96.499978 -241.851594) (xy 96.529543 -241.890938) (xy 96.552414 -241.934515) (xy 96.567998 -241.981196)
			(xy 96.575893 -242.029773) (xy 96.576388 -242.05438) (xy 96.575893 -242.078987) (xy 96.567998 -242.127564)
			(xy 96.552414 -242.174245) (xy 96.529543 -242.217822) (xy 96.499978 -242.257166) (xy 96.464485 -242.291258)
			(xy 96.423982 -242.319214) (xy 96.37952 -242.340312) (xy 96.332249 -242.354004) (xy 96.283394 -242.359936)
			(xy 96.234219 -242.357955) (xy 96.186 -242.348111) (xy 96.139984 -242.330659) (xy 96.097363 -242.306052)
			(xy 96.059242 -242.274927) (xy 96.026607 -242.23809) (xy 96.000304 -242.196494) (xy 95.981013 -242.151218)
			(xy 95.969236 -242.103434) (xy 95.965276 -242.05438) (xy 95.646748 -242.05438) (xy 95.646236 -242.079826)
			(xy 95.638072 -242.13006) (xy 95.621956 -242.178334) (xy 95.598305 -242.223397) (xy 95.567732 -242.264083)
			(xy 95.531028 -242.299338) (xy 95.489144 -242.328248) (xy 95.443165 -242.350065) (xy 95.394281 -242.364225)
			(xy 95.34376 -242.370359) (xy 95.292908 -242.36831) (xy 95.243044 -242.35813) (xy 95.195458 -242.340083)
			(xy 95.151384 -242.314637) (xy 95.111962 -242.28245) (xy 95.078214 -242.244356) (xy 95.051013 -242.201342)
			(xy 95.031065 -242.154522) (xy 95.018886 -242.105108) (xy 95.014791 -242.05438) (xy 94.706694 -242.05438)
			(xy 94.706182 -242.079826) (xy 94.698018 -242.13006) (xy 94.681902 -242.178334) (xy 94.658251 -242.223397)
			(xy 94.627678 -242.264083) (xy 94.590974 -242.299338) (xy 94.54909 -242.328248) (xy 94.503111 -242.350065)
			(xy 94.454227 -242.364225) (xy 94.403706 -242.370359) (xy 94.352854 -242.36831) (xy 94.30299 -242.35813)
			(xy 94.255404 -242.340083) (xy 94.21133 -242.314637) (xy 94.171908 -242.28245) (xy 94.13816 -242.244356)
			(xy 94.110959 -242.201342) (xy 94.091011 -242.154522) (xy 94.078832 -242.105108) (xy 94.074737 -242.05438)
			(xy 92.82684 -242.05438) (xy 92.826328 -242.079826) (xy 92.818164 -242.13006) (xy 92.802048 -242.178334)
			(xy 92.778397 -242.223397) (xy 92.747824 -242.264083) (xy 92.71112 -242.299338) (xy 92.669236 -242.328248)
			(xy 92.623257 -242.350065) (xy 92.574373 -242.364225) (xy 92.523852 -242.370359) (xy 92.473 -242.36831)
			(xy 92.423136 -242.35813) (xy 92.37555 -242.340083) (xy 92.331476 -242.314637) (xy 92.292054 -242.28245)
			(xy 92.258306 -242.244356) (xy 92.231105 -242.201342) (xy 92.211157 -242.154522) (xy 92.198978 -242.105108)
			(xy 92.194883 -242.05438) (xy 91.876372 -242.05438) (xy 91.875877 -242.078987) (xy 91.867982 -242.127564)
			(xy 91.852398 -242.174245) (xy 91.829527 -242.217822) (xy 91.799962 -242.257166) (xy 91.764469 -242.291258)
			(xy 91.723966 -242.319214) (xy 91.679504 -242.340312) (xy 91.632233 -242.354004) (xy 91.583378 -242.359936)
			(xy 91.534203 -242.357955) (xy 91.485984 -242.348111) (xy 91.439968 -242.330659) (xy 91.397347 -242.306052)
			(xy 91.359226 -242.274927) (xy 91.326591 -242.23809) (xy 91.300288 -242.196494) (xy 91.280997 -242.151218)
			(xy 91.26922 -242.103434) (xy 91.26526 -242.05438) (xy 90.946732 -242.05438) (xy 90.94622 -242.079826)
			(xy 90.938056 -242.13006) (xy 90.92194 -242.178334) (xy 90.898289 -242.223397) (xy 90.867716 -242.264083)
			(xy 90.831012 -242.299338) (xy 90.789128 -242.328248) (xy 90.743149 -242.350065) (xy 90.694265 -242.364225)
			(xy 90.643744 -242.370359) (xy 90.592892 -242.36831) (xy 90.543028 -242.35813) (xy 90.495442 -242.340083)
			(xy 90.451368 -242.314637) (xy 90.411946 -242.28245) (xy 90.378198 -242.244356) (xy 90.350997 -242.201342)
			(xy 90.331049 -242.154522) (xy 90.31887 -242.105108) (xy 90.314775 -242.05438) (xy 89.996264 -242.05438)
			(xy 89.995769 -242.078987) (xy 89.987874 -242.127564) (xy 89.97229 -242.174245) (xy 89.949419 -242.217822)
			(xy 89.919854 -242.257166) (xy 89.884361 -242.291258) (xy 89.843858 -242.319214) (xy 89.799396 -242.340312)
			(xy 89.752125 -242.354004) (xy 89.70327 -242.359936) (xy 89.654095 -242.357955) (xy 89.605876 -242.348111)
			(xy 89.55986 -242.330659) (xy 89.517239 -242.306052) (xy 89.479118 -242.274927) (xy 89.446483 -242.23809)
			(xy 89.42018 -242.196494) (xy 89.400889 -242.151218) (xy 89.389112 -242.103434) (xy 89.385152 -242.05438)
			(xy 89.056464 -242.05438) (xy 89.055969 -242.078987) (xy 89.048074 -242.127564) (xy 89.03249 -242.174245)
			(xy 89.009619 -242.217822) (xy 88.980054 -242.257166) (xy 88.944561 -242.291258) (xy 88.904058 -242.319214)
			(xy 88.859596 -242.340312) (xy 88.812325 -242.354004) (xy 88.76347 -242.359936) (xy 88.714295 -242.357955)
			(xy 88.666076 -242.348111) (xy 88.62006 -242.330659) (xy 88.577439 -242.306052) (xy 88.539318 -242.274927)
			(xy 88.506683 -242.23809) (xy 88.48038 -242.196494) (xy 88.461089 -242.151218) (xy 88.449312 -242.103434)
			(xy 88.445352 -242.05438) (xy 88.11641 -242.05438) (xy 88.115915 -242.078987) (xy 88.10802 -242.127564)
			(xy 88.092436 -242.174245) (xy 88.069565 -242.217822) (xy 88.04 -242.257166) (xy 88.004507 -242.291258)
			(xy 87.964004 -242.319214) (xy 87.919542 -242.340312) (xy 87.872271 -242.354004) (xy 87.823416 -242.359936)
			(xy 87.774241 -242.357955) (xy 87.726022 -242.348111) (xy 87.680006 -242.330659) (xy 87.637385 -242.306052)
			(xy 87.599264 -242.274927) (xy 87.566629 -242.23809) (xy 87.540326 -242.196494) (xy 87.521035 -242.151218)
			(xy 87.509258 -242.103434) (xy 87.505298 -242.05438) (xy 86.236302 -242.05438) (xy 86.235807 -242.078987)
			(xy 86.227912 -242.127564) (xy 86.212328 -242.174245) (xy 86.189457 -242.217822) (xy 86.159892 -242.257166)
			(xy 86.124399 -242.291258) (xy 86.083896 -242.319214) (xy 86.039434 -242.340312) (xy 85.992163 -242.354004)
			(xy 85.943308 -242.359936) (xy 85.894133 -242.357955) (xy 85.845914 -242.348111) (xy 85.799898 -242.330659)
			(xy 85.757277 -242.306052) (xy 85.719156 -242.274927) (xy 85.686521 -242.23809) (xy 85.660218 -242.196494)
			(xy 85.640927 -242.151218) (xy 85.62915 -242.103434) (xy 85.62519 -242.05438) (xy 85.296248 -242.05438)
			(xy 85.295753 -242.078987) (xy 85.287858 -242.127564) (xy 85.272274 -242.174245) (xy 85.249403 -242.217822)
			(xy 85.219838 -242.257166) (xy 85.184345 -242.291258) (xy 85.143842 -242.319214) (xy 85.09938 -242.340312)
			(xy 85.052109 -242.354004) (xy 85.003254 -242.359936) (xy 84.954079 -242.357955) (xy 84.90586 -242.348111)
			(xy 84.859844 -242.330659) (xy 84.817223 -242.306052) (xy 84.779102 -242.274927) (xy 84.746467 -242.23809)
			(xy 84.720164 -242.196494) (xy 84.700873 -242.151218) (xy 84.689096 -242.103434) (xy 84.685136 -242.05438)
			(xy 84.356448 -242.05438) (xy 84.355953 -242.078987) (xy 84.348058 -242.127564) (xy 84.332474 -242.174245)
			(xy 84.309603 -242.217822) (xy 84.280038 -242.257166) (xy 84.244545 -242.291258) (xy 84.204042 -242.319214)
			(xy 84.15958 -242.340312) (xy 84.112309 -242.354004) (xy 84.063454 -242.359936) (xy 84.014279 -242.357955)
			(xy 83.96606 -242.348111) (xy 83.920044 -242.330659) (xy 83.877423 -242.306052) (xy 83.839302 -242.274927)
			(xy 83.806667 -242.23809) (xy 83.780364 -242.196494) (xy 83.761073 -242.151218) (xy 83.749296 -242.103434)
			(xy 83.745336 -242.05438) (xy 83.49488 -242.05438) (xy 83.49488 -242.411504) (xy 83.494971 -242.416055)
			(xy 83.496632 -242.425004) (xy 83.498182 -242.429284) (xy 83.501738 -242.438682) (xy 83.537298 -242.478052)
			(xy 83.552792 -242.495324) (xy 83.559904 -242.501674) (xy 83.561936 -242.502944) (xy 83.567778 -242.5065)
			(xy 83.576414 -242.510564) (xy 83.585558 -242.51158) (xy 83.585812 -242.51158) (xy 83.609411 -242.514317)
			(xy 83.655416 -242.526157) (xy 83.699034 -242.544976) (xy 83.739213 -242.570322) (xy 83.774983 -242.601583)
			(xy 83.805482 -242.638004) (xy 83.829974 -242.678709) (xy 83.839304 -242.700556) (xy 83.84286 -242.70716)
			(xy 83.843114 -242.707668) (xy 83.856643 -242.731549) (xy 83.875896 -242.782942) (xy 83.885672 -242.836945)
			(xy 83.886294 -242.864386) (xy 84.215236 -242.864386) (xy 84.219196 -242.815332) (xy 84.230973 -242.767548)
			(xy 84.250264 -242.722272) (xy 84.276567 -242.680676) (xy 84.309202 -242.643839) (xy 84.347323 -242.612714)
			(xy 84.389944 -242.588107) (xy 84.43596 -242.570655) (xy 84.484179 -242.560811) (xy 84.533354 -242.55883)
			(xy 84.582209 -242.564762) (xy 84.62948 -242.578454) (xy 84.673942 -242.599552) (xy 84.714445 -242.627508)
			(xy 84.749938 -242.6616) (xy 84.779503 -242.700944) (xy 84.802374 -242.744521) (xy 84.817958 -242.791202)
			(xy 84.825853 -242.839779) (xy 84.826348 -242.864386) (xy 85.15529 -242.864386) (xy 85.15925 -242.815332)
			(xy 85.171027 -242.767548) (xy 85.190318 -242.722272) (xy 85.216621 -242.680676) (xy 85.249256 -242.643839)
			(xy 85.287377 -242.612714) (xy 85.329998 -242.588107) (xy 85.376014 -242.570655) (xy 85.424233 -242.560811)
			(xy 85.473408 -242.55883) (xy 85.522263 -242.564762) (xy 85.569534 -242.578454) (xy 85.613996 -242.599552)
			(xy 85.654499 -242.627508) (xy 85.689992 -242.6616) (xy 85.719557 -242.700944) (xy 85.742428 -242.744521)
			(xy 85.758012 -242.791202) (xy 85.765907 -242.839779) (xy 85.766402 -242.864386) (xy 86.095344 -242.864386)
			(xy 86.099304 -242.815332) (xy 86.111081 -242.767548) (xy 86.130372 -242.722272) (xy 86.156675 -242.680676)
			(xy 86.18931 -242.643839) (xy 86.227431 -242.612714) (xy 86.270052 -242.588107) (xy 86.316068 -242.570655)
			(xy 86.364287 -242.560811) (xy 86.413462 -242.55883) (xy 86.462317 -242.564762) (xy 86.509588 -242.578454)
			(xy 86.55405 -242.599552) (xy 86.594553 -242.627508) (xy 86.630046 -242.6616) (xy 86.659611 -242.700944)
			(xy 86.682482 -242.744521) (xy 86.698066 -242.791202) (xy 86.705961 -242.839779) (xy 86.706456 -242.864386)
			(xy 87.035144 -242.864386) (xy 87.039104 -242.815332) (xy 87.050881 -242.767548) (xy 87.070172 -242.722272)
			(xy 87.096475 -242.680676) (xy 87.12911 -242.643839) (xy 87.167231 -242.612714) (xy 87.209852 -242.588107)
			(xy 87.255868 -242.570655) (xy 87.304087 -242.560811) (xy 87.353262 -242.55883) (xy 87.402117 -242.564762)
			(xy 87.449388 -242.578454) (xy 87.49385 -242.599552) (xy 87.534353 -242.627508) (xy 87.569846 -242.6616)
			(xy 87.599411 -242.700944) (xy 87.622282 -242.744521) (xy 87.637866 -242.791202) (xy 87.645761 -242.839779)
			(xy 87.646256 -242.864386) (xy 87.975198 -242.864386) (xy 87.979158 -242.815332) (xy 87.990935 -242.767548)
			(xy 88.010226 -242.722272) (xy 88.036529 -242.680676) (xy 88.069164 -242.643839) (xy 88.107285 -242.612714)
			(xy 88.149906 -242.588107) (xy 88.195922 -242.570655) (xy 88.244141 -242.560811) (xy 88.293316 -242.55883)
			(xy 88.342171 -242.564762) (xy 88.389442 -242.578454) (xy 88.433904 -242.599552) (xy 88.474407 -242.627508)
			(xy 88.5099 -242.6616) (xy 88.539465 -242.700944) (xy 88.562336 -242.744521) (xy 88.57792 -242.791202)
			(xy 88.585815 -242.839779) (xy 88.58631 -242.864386) (xy 88.915252 -242.864386) (xy 88.919212 -242.815332)
			(xy 88.930989 -242.767548) (xy 88.95028 -242.722272) (xy 88.976583 -242.680676) (xy 89.009218 -242.643839)
			(xy 89.047339 -242.612714) (xy 89.08996 -242.588107) (xy 89.135976 -242.570655) (xy 89.184195 -242.560811)
			(xy 89.23337 -242.55883) (xy 89.282225 -242.564762) (xy 89.329496 -242.578454) (xy 89.373958 -242.599552)
			(xy 89.414461 -242.627508) (xy 89.449954 -242.6616) (xy 89.479519 -242.700944) (xy 89.50239 -242.744521)
			(xy 89.517974 -242.791202) (xy 89.525869 -242.839779) (xy 89.526364 -242.864386) (xy 89.855306 -242.864386)
			(xy 89.859266 -242.815332) (xy 89.871043 -242.767548) (xy 89.890334 -242.722272) (xy 89.916637 -242.680676)
			(xy 89.949272 -242.643839) (xy 89.987393 -242.612714) (xy 90.030014 -242.588107) (xy 90.07603 -242.570655)
			(xy 90.124249 -242.560811) (xy 90.173424 -242.55883) (xy 90.222279 -242.564762) (xy 90.26955 -242.578454)
			(xy 90.314012 -242.599552) (xy 90.354515 -242.627508) (xy 90.390008 -242.6616) (xy 90.419573 -242.700944)
			(xy 90.442444 -242.744521) (xy 90.458028 -242.791202) (xy 90.465923 -242.839779) (xy 90.466418 -242.864386)
			(xy 90.784675 -242.864386) (xy 90.78877 -242.813658) (xy 90.800949 -242.764244) (xy 90.820897 -242.717424)
			(xy 90.848098 -242.67441) (xy 90.881846 -242.636316) (xy 90.921268 -242.604129) (xy 90.965342 -242.578683)
			(xy 91.012928 -242.560636) (xy 91.062792 -242.550456) (xy 91.113644 -242.548407) (xy 91.164165 -242.554541)
			(xy 91.213049 -242.568701) (xy 91.259028 -242.590518) (xy 91.300912 -242.619428) (xy 91.337616 -242.654683)
			(xy 91.368189 -242.695369) (xy 91.39184 -242.740432) (xy 91.407956 -242.788706) (xy 91.41612 -242.83894)
			(xy 91.416632 -242.864386) (xy 91.724729 -242.864386) (xy 91.728824 -242.813658) (xy 91.741003 -242.764244)
			(xy 91.760951 -242.717424) (xy 91.788152 -242.67441) (xy 91.8219 -242.636316) (xy 91.861322 -242.604129)
			(xy 91.905396 -242.578683) (xy 91.952982 -242.560636) (xy 92.002846 -242.550456) (xy 92.053698 -242.548407)
			(xy 92.104219 -242.554541) (xy 92.153103 -242.568701) (xy 92.199082 -242.590518) (xy 92.240966 -242.619428)
			(xy 92.27767 -242.654683) (xy 92.308243 -242.695369) (xy 92.331894 -242.740432) (xy 92.34801 -242.788706)
			(xy 92.356174 -242.83894) (xy 92.356686 -242.864386) (xy 92.675214 -242.864386) (xy 92.679174 -242.815332)
			(xy 92.690951 -242.767548) (xy 92.710242 -242.722272) (xy 92.736545 -242.680676) (xy 92.76918 -242.643839)
			(xy 92.807301 -242.612714) (xy 92.849922 -242.588107) (xy 92.895938 -242.570655) (xy 92.944157 -242.560811)
			(xy 92.993332 -242.55883) (xy 93.042187 -242.564762) (xy 93.089458 -242.578454) (xy 93.13392 -242.599552)
			(xy 93.174423 -242.627508) (xy 93.209916 -242.6616) (xy 93.239481 -242.700944) (xy 93.262352 -242.744521)
			(xy 93.277936 -242.791202) (xy 93.285831 -242.839779) (xy 93.286326 -242.864386) (xy 93.604837 -242.864386)
			(xy 93.608932 -242.813658) (xy 93.621111 -242.764244) (xy 93.641059 -242.717424) (xy 93.66826 -242.67441)
			(xy 93.702008 -242.636316) (xy 93.74143 -242.604129) (xy 93.785504 -242.578683) (xy 93.83309 -242.560636)
			(xy 93.882954 -242.550456) (xy 93.933806 -242.548407) (xy 93.984327 -242.554541) (xy 94.033211 -242.568701)
			(xy 94.07919 -242.590518) (xy 94.121074 -242.619428) (xy 94.157778 -242.654683) (xy 94.188351 -242.695369)
			(xy 94.212002 -242.740432) (xy 94.228118 -242.788706) (xy 94.236282 -242.83894) (xy 94.236794 -242.864386)
			(xy 94.555322 -242.864386) (xy 94.559282 -242.815332) (xy 94.571059 -242.767548) (xy 94.59035 -242.722272)
			(xy 94.616653 -242.680676) (xy 94.649288 -242.643839) (xy 94.687409 -242.612714) (xy 94.73003 -242.588107)
			(xy 94.776046 -242.570655) (xy 94.824265 -242.560811) (xy 94.87344 -242.55883) (xy 94.922295 -242.564762)
			(xy 94.969566 -242.578454) (xy 95.014028 -242.599552) (xy 95.054531 -242.627508) (xy 95.090024 -242.6616)
			(xy 95.119589 -242.700944) (xy 95.14246 -242.744521) (xy 95.158044 -242.791202) (xy 95.165939 -242.839779)
			(xy 95.166434 -242.864386) (xy 95.484691 -242.864386) (xy 95.488786 -242.813658) (xy 95.500965 -242.764244)
			(xy 95.520913 -242.717424) (xy 95.548114 -242.67441) (xy 95.581862 -242.636316) (xy 95.621284 -242.604129)
			(xy 95.665358 -242.578683) (xy 95.712944 -242.560636) (xy 95.762808 -242.550456) (xy 95.81366 -242.548407)
			(xy 95.864181 -242.554541) (xy 95.913065 -242.568701) (xy 95.959044 -242.590518) (xy 96.000928 -242.619428)
			(xy 96.037632 -242.654683) (xy 96.068205 -242.695369) (xy 96.091856 -242.740432) (xy 96.107972 -242.788706)
			(xy 96.116136 -242.83894) (xy 96.116648 -242.864386) (xy 96.116136 -242.889832) (xy 96.107972 -242.940066)
			(xy 96.091856 -242.98834) (xy 96.068205 -243.033403) (xy 96.037632 -243.074089) (xy 96.000928 -243.109344)
			(xy 95.959044 -243.138254) (xy 95.913065 -243.160071) (xy 95.864181 -243.174231) (xy 95.81366 -243.180365)
			(xy 95.762808 -243.178316) (xy 95.712944 -243.168136) (xy 95.665358 -243.150089) (xy 95.621284 -243.124643)
			(xy 95.581862 -243.092456) (xy 95.548114 -243.054362) (xy 95.520913 -243.011348) (xy 95.500965 -242.964528)
			(xy 95.488786 -242.915114) (xy 95.484691 -242.864386) (xy 95.166434 -242.864386) (xy 95.165939 -242.888993)
			(xy 95.158044 -242.93757) (xy 95.14246 -242.984251) (xy 95.119589 -243.027828) (xy 95.090024 -243.067172)
			(xy 95.054531 -243.101264) (xy 95.014028 -243.12922) (xy 94.969566 -243.150318) (xy 94.922295 -243.16401)
			(xy 94.87344 -243.169942) (xy 94.824265 -243.167961) (xy 94.776046 -243.158117) (xy 94.73003 -243.140665)
			(xy 94.687409 -243.116058) (xy 94.649288 -243.084933) (xy 94.616653 -243.048096) (xy 94.59035 -243.0065)
			(xy 94.571059 -242.961224) (xy 94.559282 -242.91344) (xy 94.555322 -242.864386) (xy 94.236794 -242.864386)
			(xy 94.236282 -242.889832) (xy 94.228118 -242.940066) (xy 94.212002 -242.98834) (xy 94.188351 -243.033403)
			(xy 94.157778 -243.074089) (xy 94.121074 -243.109344) (xy 94.07919 -243.138254) (xy 94.033211 -243.160071)
			(xy 93.984327 -243.174231) (xy 93.933806 -243.180365) (xy 93.882954 -243.178316) (xy 93.83309 -243.168136)
			(xy 93.785504 -243.150089) (xy 93.74143 -243.124643) (xy 93.702008 -243.092456) (xy 93.66826 -243.054362)
			(xy 93.641059 -243.011348) (xy 93.621111 -242.964528) (xy 93.608932 -242.915114) (xy 93.604837 -242.864386)
			(xy 93.286326 -242.864386) (xy 93.285831 -242.888993) (xy 93.277936 -242.93757) (xy 93.262352 -242.984251)
			(xy 93.239481 -243.027828) (xy 93.209916 -243.067172) (xy 93.174423 -243.101264) (xy 93.13392 -243.12922)
			(xy 93.089458 -243.150318) (xy 93.042187 -243.16401) (xy 92.993332 -243.169942) (xy 92.944157 -243.167961)
			(xy 92.895938 -243.158117) (xy 92.849922 -243.140665) (xy 92.807301 -243.116058) (xy 92.76918 -243.084933)
			(xy 92.736545 -243.048096) (xy 92.710242 -243.0065) (xy 92.690951 -242.961224) (xy 92.679174 -242.91344)
			(xy 92.675214 -242.864386) (xy 92.356686 -242.864386) (xy 92.356174 -242.889832) (xy 92.34801 -242.940066)
			(xy 92.331894 -242.98834) (xy 92.308243 -243.033403) (xy 92.27767 -243.074089) (xy 92.240966 -243.109344)
			(xy 92.199082 -243.138254) (xy 92.153103 -243.160071) (xy 92.104219 -243.174231) (xy 92.053698 -243.180365)
			(xy 92.002846 -243.178316) (xy 91.952982 -243.168136) (xy 91.905396 -243.150089) (xy 91.861322 -243.124643)
			(xy 91.8219 -243.092456) (xy 91.788152 -243.054362) (xy 91.760951 -243.011348) (xy 91.741003 -242.964528)
			(xy 91.728824 -242.915114) (xy 91.724729 -242.864386) (xy 91.416632 -242.864386) (xy 91.41612 -242.889832)
			(xy 91.407956 -242.940066) (xy 91.39184 -242.98834) (xy 91.368189 -243.033403) (xy 91.337616 -243.074089)
			(xy 91.300912 -243.109344) (xy 91.259028 -243.138254) (xy 91.213049 -243.160071) (xy 91.164165 -243.174231)
			(xy 91.113644 -243.180365) (xy 91.062792 -243.178316) (xy 91.012928 -243.168136) (xy 90.965342 -243.150089)
			(xy 90.921268 -243.124643) (xy 90.881846 -243.092456) (xy 90.848098 -243.054362) (xy 90.820897 -243.011348)
			(xy 90.800949 -242.964528) (xy 90.78877 -242.915114) (xy 90.784675 -242.864386) (xy 90.466418 -242.864386)
			(xy 90.465923 -242.888993) (xy 90.458028 -242.93757) (xy 90.442444 -242.984251) (xy 90.419573 -243.027828)
			(xy 90.390008 -243.067172) (xy 90.354515 -243.101264) (xy 90.314012 -243.12922) (xy 90.26955 -243.150318)
			(xy 90.222279 -243.16401) (xy 90.173424 -243.169942) (xy 90.124249 -243.167961) (xy 90.07603 -243.158117)
			(xy 90.030014 -243.140665) (xy 89.987393 -243.116058) (xy 89.949272 -243.084933) (xy 89.916637 -243.048096)
			(xy 89.890334 -243.0065) (xy 89.871043 -242.961224) (xy 89.859266 -242.91344) (xy 89.855306 -242.864386)
			(xy 89.526364 -242.864386) (xy 89.525869 -242.888993) (xy 89.517974 -242.93757) (xy 89.50239 -242.984251)
			(xy 89.479519 -243.027828) (xy 89.449954 -243.067172) (xy 89.414461 -243.101264) (xy 89.373958 -243.12922)
			(xy 89.329496 -243.150318) (xy 89.282225 -243.16401) (xy 89.23337 -243.169942) (xy 89.184195 -243.167961)
			(xy 89.135976 -243.158117) (xy 89.08996 -243.140665) (xy 89.047339 -243.116058) (xy 89.009218 -243.084933)
			(xy 88.976583 -243.048096) (xy 88.95028 -243.0065) (xy 88.930989 -242.961224) (xy 88.919212 -242.91344)
			(xy 88.915252 -242.864386) (xy 88.58631 -242.864386) (xy 88.585815 -242.888993) (xy 88.57792 -242.93757)
			(xy 88.562336 -242.984251) (xy 88.539465 -243.027828) (xy 88.5099 -243.067172) (xy 88.474407 -243.101264)
			(xy 88.433904 -243.12922) (xy 88.389442 -243.150318) (xy 88.342171 -243.16401) (xy 88.293316 -243.169942)
			(xy 88.244141 -243.167961) (xy 88.195922 -243.158117) (xy 88.149906 -243.140665) (xy 88.107285 -243.116058)
			(xy 88.069164 -243.084933) (xy 88.036529 -243.048096) (xy 88.010226 -243.0065) (xy 87.990935 -242.961224)
			(xy 87.979158 -242.91344) (xy 87.975198 -242.864386) (xy 87.646256 -242.864386) (xy 87.645761 -242.888993)
			(xy 87.637866 -242.93757) (xy 87.622282 -242.984251) (xy 87.599411 -243.027828) (xy 87.569846 -243.067172)
			(xy 87.534353 -243.101264) (xy 87.49385 -243.12922) (xy 87.449388 -243.150318) (xy 87.402117 -243.16401)
			(xy 87.353262 -243.169942) (xy 87.304087 -243.167961) (xy 87.255868 -243.158117) (xy 87.209852 -243.140665)
			(xy 87.167231 -243.116058) (xy 87.12911 -243.084933) (xy 87.096475 -243.048096) (xy 87.070172 -243.0065)
			(xy 87.050881 -242.961224) (xy 87.039104 -242.91344) (xy 87.035144 -242.864386) (xy 86.706456 -242.864386)
			(xy 86.705961 -242.888993) (xy 86.698066 -242.93757) (xy 86.682482 -242.984251) (xy 86.659611 -243.027828)
			(xy 86.630046 -243.067172) (xy 86.594553 -243.101264) (xy 86.55405 -243.12922) (xy 86.509588 -243.150318)
			(xy 86.462317 -243.16401) (xy 86.413462 -243.169942) (xy 86.364287 -243.167961) (xy 86.316068 -243.158117)
			(xy 86.270052 -243.140665) (xy 86.227431 -243.116058) (xy 86.18931 -243.084933) (xy 86.156675 -243.048096)
			(xy 86.130372 -243.0065) (xy 86.111081 -242.961224) (xy 86.099304 -242.91344) (xy 86.095344 -242.864386)
			(xy 85.766402 -242.864386) (xy 85.765907 -242.888993) (xy 85.758012 -242.93757) (xy 85.742428 -242.984251)
			(xy 85.719557 -243.027828) (xy 85.689992 -243.067172) (xy 85.654499 -243.101264) (xy 85.613996 -243.12922)
			(xy 85.569534 -243.150318) (xy 85.522263 -243.16401) (xy 85.473408 -243.169942) (xy 85.424233 -243.167961)
			(xy 85.376014 -243.158117) (xy 85.329998 -243.140665) (xy 85.287377 -243.116058) (xy 85.249256 -243.084933)
			(xy 85.216621 -243.048096) (xy 85.190318 -243.0065) (xy 85.171027 -242.961224) (xy 85.15925 -242.91344)
			(xy 85.15529 -242.864386) (xy 84.826348 -242.864386) (xy 84.825853 -242.888993) (xy 84.817958 -242.93757)
			(xy 84.802374 -242.984251) (xy 84.779503 -243.027828) (xy 84.749938 -243.067172) (xy 84.714445 -243.101264)
			(xy 84.673942 -243.12922) (xy 84.62948 -243.150318) (xy 84.582209 -243.16401) (xy 84.533354 -243.169942)
			(xy 84.484179 -243.167961) (xy 84.43596 -243.158117) (xy 84.389944 -243.140665) (xy 84.347323 -243.116058)
			(xy 84.309202 -243.084933) (xy 84.276567 -243.048096) (xy 84.250264 -243.0065) (xy 84.230973 -242.961224)
			(xy 84.219196 -242.91344) (xy 84.215236 -242.864386) (xy 83.886294 -242.864386) (xy 83.885849 -242.888379)
			(xy 83.878344 -242.935776) (xy 83.863516 -242.981414) (xy 83.841731 -243.024172) (xy 83.813526 -243.062994)
			(xy 83.779594 -243.096926) (xy 83.740772 -243.125131) (xy 83.698014 -243.146916) (xy 83.652376 -243.161744)
			(xy 83.604979 -243.169249) (xy 83.580986 -243.169694) (xy 83.551268 -243.16817) (xy 83.551014 -243.16817)
			(xy 83.539076 -243.167154) (xy 83.528408 -243.171218) (xy 83.522867 -243.173526) (xy 83.512977 -243.180322)
			(xy 83.50885 -243.18468) (xy 83.508088 -243.185442) (xy 83.502208 -243.192424) (xy 83.495416 -243.209351)
			(xy 83.49488 -243.218462) (xy 83.49488 -243.674392) (xy 83.745336 -243.674392) (xy 83.749296 -243.625338)
			(xy 83.761073 -243.577554) (xy 83.780364 -243.532278) (xy 83.806667 -243.490682) (xy 83.839302 -243.453845)
			(xy 83.877423 -243.42272) (xy 83.920044 -243.398113) (xy 83.96606 -243.380661) (xy 84.014279 -243.370817)
			(xy 84.063454 -243.368836) (xy 84.112309 -243.374768) (xy 84.15958 -243.38846) (xy 84.204042 -243.409558)
			(xy 84.244545 -243.437514) (xy 84.280038 -243.471606) (xy 84.309603 -243.51095) (xy 84.332474 -243.554527)
			(xy 84.348058 -243.601208) (xy 84.355953 -243.649785) (xy 84.356448 -243.674392) (xy 84.685136 -243.674392)
			(xy 84.689096 -243.625338) (xy 84.700873 -243.577554) (xy 84.720164 -243.532278) (xy 84.746467 -243.490682)
			(xy 84.779102 -243.453845) (xy 84.817223 -243.42272) (xy 84.859844 -243.398113) (xy 84.90586 -243.380661)
			(xy 84.954079 -243.370817) (xy 85.003254 -243.368836) (xy 85.052109 -243.374768) (xy 85.09938 -243.38846)
			(xy 85.143842 -243.409558) (xy 85.184345 -243.437514) (xy 85.219838 -243.471606) (xy 85.249403 -243.51095)
			(xy 85.272274 -243.554527) (xy 85.287858 -243.601208) (xy 85.295753 -243.649785) (xy 85.296248 -243.674392)
			(xy 85.62519 -243.674392) (xy 85.62915 -243.625338) (xy 85.640927 -243.577554) (xy 85.660218 -243.532278)
			(xy 85.686521 -243.490682) (xy 85.719156 -243.453845) (xy 85.757277 -243.42272) (xy 85.799898 -243.398113)
			(xy 85.845914 -243.380661) (xy 85.894133 -243.370817) (xy 85.943308 -243.368836) (xy 85.992163 -243.374768)
			(xy 86.039434 -243.38846) (xy 86.083896 -243.409558) (xy 86.124399 -243.437514) (xy 86.159892 -243.471606)
			(xy 86.189457 -243.51095) (xy 86.212328 -243.554527) (xy 86.227912 -243.601208) (xy 86.235807 -243.649785)
			(xy 86.236302 -243.674392) (xy 86.565244 -243.674392) (xy 86.569204 -243.625338) (xy 86.580981 -243.577554)
			(xy 86.600272 -243.532278) (xy 86.626575 -243.490682) (xy 86.65921 -243.453845) (xy 86.697331 -243.42272)
			(xy 86.739952 -243.398113) (xy 86.785968 -243.380661) (xy 86.834187 -243.370817) (xy 86.883362 -243.368836)
			(xy 86.932217 -243.374768) (xy 86.979488 -243.38846) (xy 87.02395 -243.409558) (xy 87.064453 -243.437514)
			(xy 87.099946 -243.471606) (xy 87.129511 -243.51095) (xy 87.152382 -243.554527) (xy 87.167966 -243.601208)
			(xy 87.175861 -243.649785) (xy 87.176356 -243.674392) (xy 87.505298 -243.674392) (xy 87.509258 -243.625338)
			(xy 87.521035 -243.577554) (xy 87.540326 -243.532278) (xy 87.566629 -243.490682) (xy 87.599264 -243.453845)
			(xy 87.637385 -243.42272) (xy 87.680006 -243.398113) (xy 87.726022 -243.380661) (xy 87.774241 -243.370817)
			(xy 87.823416 -243.368836) (xy 87.872271 -243.374768) (xy 87.919542 -243.38846) (xy 87.964004 -243.409558)
			(xy 88.004507 -243.437514) (xy 88.04 -243.471606) (xy 88.069565 -243.51095) (xy 88.092436 -243.554527)
			(xy 88.10802 -243.601208) (xy 88.115915 -243.649785) (xy 88.11641 -243.674392) (xy 88.445352 -243.674392)
			(xy 88.449312 -243.625338) (xy 88.461089 -243.577554) (xy 88.48038 -243.532278) (xy 88.506683 -243.490682)
			(xy 88.539318 -243.453845) (xy 88.577439 -243.42272) (xy 88.62006 -243.398113) (xy 88.666076 -243.380661)
			(xy 88.714295 -243.370817) (xy 88.76347 -243.368836) (xy 88.812325 -243.374768) (xy 88.859596 -243.38846)
			(xy 88.904058 -243.409558) (xy 88.944561 -243.437514) (xy 88.980054 -243.471606) (xy 89.009619 -243.51095)
			(xy 89.03249 -243.554527) (xy 89.048074 -243.601208) (xy 89.055969 -243.649785) (xy 89.056464 -243.674392)
			(xy 89.385152 -243.674392) (xy 89.389112 -243.625338) (xy 89.400889 -243.577554) (xy 89.42018 -243.532278)
			(xy 89.446483 -243.490682) (xy 89.479118 -243.453845) (xy 89.517239 -243.42272) (xy 89.55986 -243.398113)
			(xy 89.605876 -243.380661) (xy 89.654095 -243.370817) (xy 89.70327 -243.368836) (xy 89.752125 -243.374768)
			(xy 89.799396 -243.38846) (xy 89.843858 -243.409558) (xy 89.884361 -243.437514) (xy 89.919854 -243.471606)
			(xy 89.949419 -243.51095) (xy 89.97229 -243.554527) (xy 89.987874 -243.601208) (xy 89.995769 -243.649785)
			(xy 89.996264 -243.674392) (xy 90.314775 -243.674392) (xy 90.31887 -243.623664) (xy 90.331049 -243.57425)
			(xy 90.350997 -243.52743) (xy 90.378198 -243.484416) (xy 90.411946 -243.446322) (xy 90.451368 -243.414135)
			(xy 90.495442 -243.388689) (xy 90.543028 -243.370642) (xy 90.592892 -243.360462) (xy 90.643744 -243.358413)
			(xy 90.694265 -243.364547) (xy 90.743149 -243.378707) (xy 90.789128 -243.400524) (xy 90.831012 -243.429434)
			(xy 90.867716 -243.464689) (xy 90.898289 -243.505375) (xy 90.92194 -243.550438) (xy 90.938056 -243.598712)
			(xy 90.94622 -243.648946) (xy 90.946732 -243.674392) (xy 91.26526 -243.674392) (xy 91.26922 -243.625338)
			(xy 91.280997 -243.577554) (xy 91.300288 -243.532278) (xy 91.326591 -243.490682) (xy 91.359226 -243.453845)
			(xy 91.397347 -243.42272) (xy 91.439968 -243.398113) (xy 91.485984 -243.380661) (xy 91.534203 -243.370817)
			(xy 91.583378 -243.368836) (xy 91.632233 -243.374768) (xy 91.679504 -243.38846) (xy 91.723966 -243.409558)
			(xy 91.764469 -243.437514) (xy 91.799962 -243.471606) (xy 91.829527 -243.51095) (xy 91.852398 -243.554527)
			(xy 91.867982 -243.601208) (xy 91.875877 -243.649785) (xy 91.876372 -243.674392) (xy 92.194883 -243.674392)
			(xy 92.198978 -243.623664) (xy 92.211157 -243.57425) (xy 92.231105 -243.52743) (xy 92.258306 -243.484416)
			(xy 92.292054 -243.446322) (xy 92.331476 -243.414135) (xy 92.37555 -243.388689) (xy 92.423136 -243.370642)
			(xy 92.473 -243.360462) (xy 92.523852 -243.358413) (xy 92.574373 -243.364547) (xy 92.623257 -243.378707)
			(xy 92.669236 -243.400524) (xy 92.71112 -243.429434) (xy 92.747824 -243.464689) (xy 92.778397 -243.505375)
			(xy 92.802048 -243.550438) (xy 92.818164 -243.598712) (xy 92.826328 -243.648946) (xy 92.82684 -243.674392)
			(xy 93.145114 -243.674392) (xy 93.149074 -243.625338) (xy 93.160851 -243.577554) (xy 93.180142 -243.532278)
			(xy 93.206445 -243.490682) (xy 93.23908 -243.453845) (xy 93.277201 -243.42272) (xy 93.319822 -243.398113)
			(xy 93.365838 -243.380661) (xy 93.414057 -243.370817) (xy 93.463232 -243.368836) (xy 93.512087 -243.374768)
			(xy 93.559358 -243.38846) (xy 93.60382 -243.409558) (xy 93.644323 -243.437514) (xy 93.679816 -243.471606)
			(xy 93.709381 -243.51095) (xy 93.732252 -243.554527) (xy 93.747836 -243.601208) (xy 93.755731 -243.649785)
			(xy 93.756226 -243.674392) (xy 94.074737 -243.674392) (xy 94.078832 -243.623664) (xy 94.091011 -243.57425)
			(xy 94.110959 -243.52743) (xy 94.13816 -243.484416) (xy 94.171908 -243.446322) (xy 94.21133 -243.414135)
			(xy 94.255404 -243.388689) (xy 94.30299 -243.370642) (xy 94.352854 -243.360462) (xy 94.403706 -243.358413)
			(xy 94.454227 -243.364547) (xy 94.503111 -243.378707) (xy 94.54909 -243.400524) (xy 94.590974 -243.429434)
			(xy 94.627678 -243.464689) (xy 94.658251 -243.505375) (xy 94.681902 -243.550438) (xy 94.698018 -243.598712)
			(xy 94.706182 -243.648946) (xy 94.706694 -243.674392) (xy 95.014791 -243.674392) (xy 95.018886 -243.623664)
			(xy 95.031065 -243.57425) (xy 95.051013 -243.52743) (xy 95.078214 -243.484416) (xy 95.111962 -243.446322)
			(xy 95.151384 -243.414135) (xy 95.195458 -243.388689) (xy 95.243044 -243.370642) (xy 95.292908 -243.360462)
			(xy 95.34376 -243.358413) (xy 95.394281 -243.364547) (xy 95.443165 -243.378707) (xy 95.489144 -243.400524)
			(xy 95.531028 -243.429434) (xy 95.567732 -243.464689) (xy 95.598305 -243.505375) (xy 95.621956 -243.550438)
			(xy 95.638072 -243.598712) (xy 95.646236 -243.648946) (xy 95.646748 -243.674392) (xy 95.646236 -243.699838)
			(xy 95.638072 -243.750072) (xy 95.621956 -243.798346) (xy 95.598305 -243.843409) (xy 95.567732 -243.884095)
			(xy 95.531028 -243.91935) (xy 95.489144 -243.94826) (xy 95.443165 -243.970077) (xy 95.394281 -243.984237)
			(xy 95.34376 -243.990371) (xy 95.292908 -243.988322) (xy 95.243044 -243.978142) (xy 95.195458 -243.960095)
			(xy 95.151384 -243.934649) (xy 95.111962 -243.902462) (xy 95.078214 -243.864368) (xy 95.051013 -243.821354)
			(xy 95.031065 -243.774534) (xy 95.018886 -243.72512) (xy 95.014791 -243.674392) (xy 94.706694 -243.674392)
			(xy 94.706182 -243.699838) (xy 94.698018 -243.750072) (xy 94.681902 -243.798346) (xy 94.658251 -243.843409)
			(xy 94.627678 -243.884095) (xy 94.590974 -243.91935) (xy 94.54909 -243.94826) (xy 94.503111 -243.970077)
			(xy 94.454227 -243.984237) (xy 94.403706 -243.990371) (xy 94.352854 -243.988322) (xy 94.30299 -243.978142)
			(xy 94.255404 -243.960095) (xy 94.21133 -243.934649) (xy 94.171908 -243.902462) (xy 94.13816 -243.864368)
			(xy 94.110959 -243.821354) (xy 94.091011 -243.774534) (xy 94.078832 -243.72512) (xy 94.074737 -243.674392)
			(xy 93.756226 -243.674392) (xy 93.755731 -243.698999) (xy 93.747836 -243.747576) (xy 93.732252 -243.794257)
			(xy 93.709381 -243.837834) (xy 93.679816 -243.877178) (xy 93.644323 -243.91127) (xy 93.60382 -243.939226)
			(xy 93.559358 -243.960324) (xy 93.512087 -243.974016) (xy 93.463232 -243.979948) (xy 93.414057 -243.977967)
			(xy 93.365838 -243.968123) (xy 93.319822 -243.950671) (xy 93.277201 -243.926064) (xy 93.23908 -243.894939)
			(xy 93.206445 -243.858102) (xy 93.180142 -243.816506) (xy 93.160851 -243.77123) (xy 93.149074 -243.723446)
			(xy 93.145114 -243.674392) (xy 92.82684 -243.674392) (xy 92.826328 -243.699838) (xy 92.818164 -243.750072)
			(xy 92.802048 -243.798346) (xy 92.778397 -243.843409) (xy 92.747824 -243.884095) (xy 92.71112 -243.91935)
			(xy 92.669236 -243.94826) (xy 92.623257 -243.970077) (xy 92.574373 -243.984237) (xy 92.523852 -243.990371)
			(xy 92.473 -243.988322) (xy 92.423136 -243.978142) (xy 92.37555 -243.960095) (xy 92.331476 -243.934649)
			(xy 92.292054 -243.902462) (xy 92.258306 -243.864368) (xy 92.231105 -243.821354) (xy 92.211157 -243.774534)
			(xy 92.198978 -243.72512) (xy 92.194883 -243.674392) (xy 91.876372 -243.674392) (xy 91.875877 -243.698999)
			(xy 91.867982 -243.747576) (xy 91.852398 -243.794257) (xy 91.829527 -243.837834) (xy 91.799962 -243.877178)
			(xy 91.764469 -243.91127) (xy 91.723966 -243.939226) (xy 91.679504 -243.960324) (xy 91.632233 -243.974016)
			(xy 91.583378 -243.979948) (xy 91.534203 -243.977967) (xy 91.485984 -243.968123) (xy 91.439968 -243.950671)
			(xy 91.397347 -243.926064) (xy 91.359226 -243.894939) (xy 91.326591 -243.858102) (xy 91.300288 -243.816506)
			(xy 91.280997 -243.77123) (xy 91.26922 -243.723446) (xy 91.26526 -243.674392) (xy 90.946732 -243.674392)
			(xy 90.94622 -243.699838) (xy 90.938056 -243.750072) (xy 90.92194 -243.798346) (xy 90.898289 -243.843409)
			(xy 90.867716 -243.884095) (xy 90.831012 -243.91935) (xy 90.789128 -243.94826) (xy 90.743149 -243.970077)
			(xy 90.694265 -243.984237) (xy 90.643744 -243.990371) (xy 90.592892 -243.988322) (xy 90.543028 -243.978142)
			(xy 90.495442 -243.960095) (xy 90.451368 -243.934649) (xy 90.411946 -243.902462) (xy 90.378198 -243.864368)
			(xy 90.350997 -243.821354) (xy 90.331049 -243.774534) (xy 90.31887 -243.72512) (xy 90.314775 -243.674392)
			(xy 89.996264 -243.674392) (xy 89.995769 -243.698999) (xy 89.987874 -243.747576) (xy 89.97229 -243.794257)
			(xy 89.949419 -243.837834) (xy 89.919854 -243.877178) (xy 89.884361 -243.91127) (xy 89.843858 -243.939226)
			(xy 89.799396 -243.960324) (xy 89.752125 -243.974016) (xy 89.70327 -243.979948) (xy 89.654095 -243.977967)
			(xy 89.605876 -243.968123) (xy 89.55986 -243.950671) (xy 89.517239 -243.926064) (xy 89.479118 -243.894939)
			(xy 89.446483 -243.858102) (xy 89.42018 -243.816506) (xy 89.400889 -243.77123) (xy 89.389112 -243.723446)
			(xy 89.385152 -243.674392) (xy 89.056464 -243.674392) (xy 89.055969 -243.698999) (xy 89.048074 -243.747576)
			(xy 89.03249 -243.794257) (xy 89.009619 -243.837834) (xy 88.980054 -243.877178) (xy 88.944561 -243.91127)
			(xy 88.904058 -243.939226) (xy 88.859596 -243.960324) (xy 88.812325 -243.974016) (xy 88.76347 -243.979948)
			(xy 88.714295 -243.977967) (xy 88.666076 -243.968123) (xy 88.62006 -243.950671) (xy 88.577439 -243.926064)
			(xy 88.539318 -243.894939) (xy 88.506683 -243.858102) (xy 88.48038 -243.816506) (xy 88.461089 -243.77123)
			(xy 88.449312 -243.723446) (xy 88.445352 -243.674392) (xy 88.11641 -243.674392) (xy 88.115915 -243.698999)
			(xy 88.10802 -243.747576) (xy 88.092436 -243.794257) (xy 88.069565 -243.837834) (xy 88.04 -243.877178)
			(xy 88.004507 -243.91127) (xy 87.964004 -243.939226) (xy 87.919542 -243.960324) (xy 87.872271 -243.974016)
			(xy 87.823416 -243.979948) (xy 87.774241 -243.977967) (xy 87.726022 -243.968123) (xy 87.680006 -243.950671)
			(xy 87.637385 -243.926064) (xy 87.599264 -243.894939) (xy 87.566629 -243.858102) (xy 87.540326 -243.816506)
			(xy 87.521035 -243.77123) (xy 87.509258 -243.723446) (xy 87.505298 -243.674392) (xy 87.176356 -243.674392)
			(xy 87.175861 -243.698999) (xy 87.167966 -243.747576) (xy 87.152382 -243.794257) (xy 87.129511 -243.837834)
			(xy 87.099946 -243.877178) (xy 87.064453 -243.91127) (xy 87.02395 -243.939226) (xy 86.979488 -243.960324)
			(xy 86.932217 -243.974016) (xy 86.883362 -243.979948) (xy 86.834187 -243.977967) (xy 86.785968 -243.968123)
			(xy 86.739952 -243.950671) (xy 86.697331 -243.926064) (xy 86.65921 -243.894939) (xy 86.626575 -243.858102)
			(xy 86.600272 -243.816506) (xy 86.580981 -243.77123) (xy 86.569204 -243.723446) (xy 86.565244 -243.674392)
			(xy 86.236302 -243.674392) (xy 86.235807 -243.698999) (xy 86.227912 -243.747576) (xy 86.212328 -243.794257)
			(xy 86.189457 -243.837834) (xy 86.159892 -243.877178) (xy 86.124399 -243.91127) (xy 86.083896 -243.939226)
			(xy 86.039434 -243.960324) (xy 85.992163 -243.974016) (xy 85.943308 -243.979948) (xy 85.894133 -243.977967)
			(xy 85.845914 -243.968123) (xy 85.799898 -243.950671) (xy 85.757277 -243.926064) (xy 85.719156 -243.894939)
			(xy 85.686521 -243.858102) (xy 85.660218 -243.816506) (xy 85.640927 -243.77123) (xy 85.62915 -243.723446)
			(xy 85.62519 -243.674392) (xy 85.296248 -243.674392) (xy 85.295753 -243.698999) (xy 85.287858 -243.747576)
			(xy 85.272274 -243.794257) (xy 85.249403 -243.837834) (xy 85.219838 -243.877178) (xy 85.184345 -243.91127)
			(xy 85.143842 -243.939226) (xy 85.09938 -243.960324) (xy 85.052109 -243.974016) (xy 85.003254 -243.979948)
			(xy 84.954079 -243.977967) (xy 84.90586 -243.968123) (xy 84.859844 -243.950671) (xy 84.817223 -243.926064)
			(xy 84.779102 -243.894939) (xy 84.746467 -243.858102) (xy 84.720164 -243.816506) (xy 84.700873 -243.77123)
			(xy 84.689096 -243.723446) (xy 84.685136 -243.674392) (xy 84.356448 -243.674392) (xy 84.355953 -243.698999)
			(xy 84.348058 -243.747576) (xy 84.332474 -243.794257) (xy 84.309603 -243.837834) (xy 84.280038 -243.877178)
			(xy 84.244545 -243.91127) (xy 84.204042 -243.939226) (xy 84.15958 -243.960324) (xy 84.112309 -243.974016)
			(xy 84.063454 -243.979948) (xy 84.014279 -243.977967) (xy 83.96606 -243.968123) (xy 83.920044 -243.950671)
			(xy 83.877423 -243.926064) (xy 83.839302 -243.894939) (xy 83.806667 -243.858102) (xy 83.780364 -243.816506)
			(xy 83.761073 -243.77123) (xy 83.749296 -243.723446) (xy 83.745336 -243.674392) (xy 83.49488 -243.674392)
			(xy 83.49488 -244.031516) (xy 83.494972 -244.036067) (xy 83.496635 -244.045015) (xy 83.498182 -244.049296)
			(xy 83.501738 -244.058694) (xy 83.537298 -244.098064) (xy 83.552792 -244.115336) (xy 83.559904 -244.121686)
			(xy 83.561936 -244.122956) (xy 83.567778 -244.126512) (xy 83.576414 -244.130576) (xy 83.585558 -244.131592)
			(xy 83.585812 -244.131592) (xy 83.60941 -244.134329) (xy 83.655416 -244.146169) (xy 83.699033 -244.164989)
			(xy 83.739211 -244.190335) (xy 83.77498 -244.221597) (xy 83.805477 -244.258019) (xy 83.829968 -244.298724)
			(xy 83.839304 -244.320568) (xy 83.84286 -244.327172) (xy 83.843114 -244.32768) (xy 83.856643 -244.351561)
			(xy 83.875893 -244.402955) (xy 83.885667 -244.456958) (xy 83.886294 -244.484398) (xy 84.215236 -244.484398)
			(xy 84.219196 -244.435344) (xy 84.230973 -244.38756) (xy 84.250264 -244.342284) (xy 84.276567 -244.300688)
			(xy 84.309202 -244.263851) (xy 84.347323 -244.232726) (xy 84.389944 -244.208119) (xy 84.43596 -244.190667)
			(xy 84.484179 -244.180823) (xy 84.533354 -244.178842) (xy 84.582209 -244.184774) (xy 84.62948 -244.198466)
			(xy 84.673942 -244.219564) (xy 84.714445 -244.24752) (xy 84.749938 -244.281612) (xy 84.779503 -244.320956)
			(xy 84.802374 -244.364533) (xy 84.817958 -244.411214) (xy 84.825853 -244.459791) (xy 84.826348 -244.484398)
			(xy 85.15529 -244.484398) (xy 85.15925 -244.435344) (xy 85.171027 -244.38756) (xy 85.190318 -244.342284)
			(xy 85.216621 -244.300688) (xy 85.249256 -244.263851) (xy 85.287377 -244.232726) (xy 85.329998 -244.208119)
			(xy 85.376014 -244.190667) (xy 85.424233 -244.180823) (xy 85.473408 -244.178842) (xy 85.522263 -244.184774)
			(xy 85.569534 -244.198466) (xy 85.613996 -244.219564) (xy 85.654499 -244.24752) (xy 85.689992 -244.281612)
			(xy 85.719557 -244.320956) (xy 85.742428 -244.364533) (xy 85.758012 -244.411214) (xy 85.765907 -244.459791)
			(xy 85.766402 -244.484398) (xy 87.035144 -244.484398) (xy 87.039104 -244.435344) (xy 87.050881 -244.38756)
			(xy 87.070172 -244.342284) (xy 87.096475 -244.300688) (xy 87.12911 -244.263851) (xy 87.167231 -244.232726)
			(xy 87.209852 -244.208119) (xy 87.255868 -244.190667) (xy 87.304087 -244.180823) (xy 87.353262 -244.178842)
			(xy 87.402117 -244.184774) (xy 87.449388 -244.198466) (xy 87.49385 -244.219564) (xy 87.534353 -244.24752)
			(xy 87.569846 -244.281612) (xy 87.599411 -244.320956) (xy 87.622282 -244.364533) (xy 87.637866 -244.411214)
			(xy 87.645761 -244.459791) (xy 87.646256 -244.484398) (xy 87.975198 -244.484398) (xy 87.979158 -244.435344)
			(xy 87.990935 -244.38756) (xy 88.010226 -244.342284) (xy 88.036529 -244.300688) (xy 88.069164 -244.263851)
			(xy 88.107285 -244.232726) (xy 88.149906 -244.208119) (xy 88.195922 -244.190667) (xy 88.244141 -244.180823)
			(xy 88.293316 -244.178842) (xy 88.342171 -244.184774) (xy 88.389442 -244.198466) (xy 88.433904 -244.219564)
			(xy 88.474407 -244.24752) (xy 88.5099 -244.281612) (xy 88.539465 -244.320956) (xy 88.562336 -244.364533)
			(xy 88.57792 -244.411214) (xy 88.585815 -244.459791) (xy 88.58631 -244.484398) (xy 88.915252 -244.484398)
			(xy 88.919212 -244.435344) (xy 88.930989 -244.38756) (xy 88.95028 -244.342284) (xy 88.976583 -244.300688)
			(xy 89.009218 -244.263851) (xy 89.047339 -244.232726) (xy 89.08996 -244.208119) (xy 89.135976 -244.190667)
			(xy 89.184195 -244.180823) (xy 89.23337 -244.178842) (xy 89.282225 -244.184774) (xy 89.329496 -244.198466)
			(xy 89.373958 -244.219564) (xy 89.414461 -244.24752) (xy 89.449954 -244.281612) (xy 89.479519 -244.320956)
			(xy 89.50239 -244.364533) (xy 89.517974 -244.411214) (xy 89.525869 -244.459791) (xy 89.526364 -244.484398)
			(xy 89.855306 -244.484398) (xy 89.859266 -244.435344) (xy 89.871043 -244.38756) (xy 89.890334 -244.342284)
			(xy 89.916637 -244.300688) (xy 89.949272 -244.263851) (xy 89.987393 -244.232726) (xy 90.030014 -244.208119)
			(xy 90.07603 -244.190667) (xy 90.124249 -244.180823) (xy 90.173424 -244.178842) (xy 90.222279 -244.184774)
			(xy 90.26955 -244.198466) (xy 90.314012 -244.219564) (xy 90.354515 -244.24752) (xy 90.390008 -244.281612)
			(xy 90.419573 -244.320956) (xy 90.442444 -244.364533) (xy 90.458028 -244.411214) (xy 90.465923 -244.459791)
			(xy 90.466418 -244.484398) (xy 90.784675 -244.484398) (xy 90.78877 -244.43367) (xy 90.800949 -244.384256)
			(xy 90.820897 -244.337436) (xy 90.848098 -244.294422) (xy 90.881846 -244.256328) (xy 90.921268 -244.224141)
			(xy 90.965342 -244.198695) (xy 91.012928 -244.180648) (xy 91.062792 -244.170468) (xy 91.113644 -244.168419)
			(xy 91.164165 -244.174553) (xy 91.213049 -244.188713) (xy 91.259028 -244.21053) (xy 91.300912 -244.23944)
			(xy 91.337616 -244.274695) (xy 91.368189 -244.315381) (xy 91.39184 -244.360444) (xy 91.407956 -244.408718)
			(xy 91.41612 -244.458952) (xy 91.416632 -244.484398) (xy 91.724729 -244.484398) (xy 91.728824 -244.43367)
			(xy 91.741003 -244.384256) (xy 91.760951 -244.337436) (xy 91.788152 -244.294422) (xy 91.8219 -244.256328)
			(xy 91.861322 -244.224141) (xy 91.905396 -244.198695) (xy 91.952982 -244.180648) (xy 92.002846 -244.170468)
			(xy 92.053698 -244.168419) (xy 92.104219 -244.174553) (xy 92.153103 -244.188713) (xy 92.199082 -244.21053)
			(xy 92.240966 -244.23944) (xy 92.27767 -244.274695) (xy 92.308243 -244.315381) (xy 92.331894 -244.360444)
			(xy 92.34801 -244.408718) (xy 92.356174 -244.458952) (xy 92.356686 -244.484398) (xy 93.604837 -244.484398)
			(xy 93.608932 -244.43367) (xy 93.621111 -244.384256) (xy 93.641059 -244.337436) (xy 93.66826 -244.294422)
			(xy 93.702008 -244.256328) (xy 93.74143 -244.224141) (xy 93.785504 -244.198695) (xy 93.83309 -244.180648)
			(xy 93.882954 -244.170468) (xy 93.933806 -244.168419) (xy 93.984327 -244.174553) (xy 94.033211 -244.188713)
			(xy 94.07919 -244.21053) (xy 94.121074 -244.23944) (xy 94.157778 -244.274695) (xy 94.188351 -244.315381)
			(xy 94.212002 -244.360444) (xy 94.228118 -244.408718) (xy 94.236282 -244.458952) (xy 94.236794 -244.484398)
			(xy 94.555322 -244.484398) (xy 94.559282 -244.435344) (xy 94.571059 -244.38756) (xy 94.59035 -244.342284)
			(xy 94.616653 -244.300688) (xy 94.649288 -244.263851) (xy 94.687409 -244.232726) (xy 94.73003 -244.208119)
			(xy 94.776046 -244.190667) (xy 94.824265 -244.180823) (xy 94.87344 -244.178842) (xy 94.922295 -244.184774)
			(xy 94.969566 -244.198466) (xy 95.014028 -244.219564) (xy 95.054531 -244.24752) (xy 95.090024 -244.281612)
			(xy 95.119589 -244.320956) (xy 95.14246 -244.364533) (xy 95.158044 -244.411214) (xy 95.165939 -244.459791)
			(xy 95.166434 -244.484398) (xy 95.484691 -244.484398) (xy 95.488786 -244.43367) (xy 95.500965 -244.384256)
			(xy 95.520913 -244.337436) (xy 95.548114 -244.294422) (xy 95.581862 -244.256328) (xy 95.621284 -244.224141)
			(xy 95.665358 -244.198695) (xy 95.712944 -244.180648) (xy 95.762808 -244.170468) (xy 95.81366 -244.168419)
			(xy 95.864181 -244.174553) (xy 95.913065 -244.188713) (xy 95.959044 -244.21053) (xy 96.000928 -244.23944)
			(xy 96.037632 -244.274695) (xy 96.068205 -244.315381) (xy 96.091856 -244.360444) (xy 96.107972 -244.408718)
			(xy 96.116136 -244.458952) (xy 96.116648 -244.484398) (xy 96.116136 -244.509844) (xy 96.107972 -244.560078)
			(xy 96.091856 -244.608352) (xy 96.068205 -244.653415) (xy 96.037632 -244.694101) (xy 96.000928 -244.729356)
			(xy 95.959044 -244.758266) (xy 95.913065 -244.780083) (xy 95.864181 -244.794243) (xy 95.81366 -244.800377)
			(xy 95.762808 -244.798328) (xy 95.712944 -244.788148) (xy 95.665358 -244.770101) (xy 95.621284 -244.744655)
			(xy 95.581862 -244.712468) (xy 95.548114 -244.674374) (xy 95.520913 -244.63136) (xy 95.500965 -244.58454)
			(xy 95.488786 -244.535126) (xy 95.484691 -244.484398) (xy 95.166434 -244.484398) (xy 95.165939 -244.509005)
			(xy 95.158044 -244.557582) (xy 95.14246 -244.604263) (xy 95.119589 -244.64784) (xy 95.090024 -244.687184)
			(xy 95.054531 -244.721276) (xy 95.014028 -244.749232) (xy 94.969566 -244.77033) (xy 94.922295 -244.784022)
			(xy 94.87344 -244.789954) (xy 94.824265 -244.787973) (xy 94.776046 -244.778129) (xy 94.73003 -244.760677)
			(xy 94.687409 -244.73607) (xy 94.649288 -244.704945) (xy 94.616653 -244.668108) (xy 94.59035 -244.626512)
			(xy 94.571059 -244.581236) (xy 94.559282 -244.533452) (xy 94.555322 -244.484398) (xy 94.236794 -244.484398)
			(xy 94.236282 -244.509844) (xy 94.228118 -244.560078) (xy 94.212002 -244.608352) (xy 94.188351 -244.653415)
			(xy 94.157778 -244.694101) (xy 94.121074 -244.729356) (xy 94.07919 -244.758266) (xy 94.033211 -244.780083)
			(xy 93.984327 -244.794243) (xy 93.933806 -244.800377) (xy 93.882954 -244.798328) (xy 93.83309 -244.788148)
			(xy 93.785504 -244.770101) (xy 93.74143 -244.744655) (xy 93.702008 -244.712468) (xy 93.66826 -244.674374)
			(xy 93.641059 -244.63136) (xy 93.621111 -244.58454) (xy 93.608932 -244.535126) (xy 93.604837 -244.484398)
			(xy 92.356686 -244.484398) (xy 92.356174 -244.509844) (xy 92.34801 -244.560078) (xy 92.331894 -244.608352)
			(xy 92.308243 -244.653415) (xy 92.27767 -244.694101) (xy 92.240966 -244.729356) (xy 92.199082 -244.758266)
			(xy 92.153103 -244.780083) (xy 92.104219 -244.794243) (xy 92.053698 -244.800377) (xy 92.002846 -244.798328)
			(xy 91.952982 -244.788148) (xy 91.905396 -244.770101) (xy 91.861322 -244.744655) (xy 91.8219 -244.712468)
			(xy 91.788152 -244.674374) (xy 91.760951 -244.63136) (xy 91.741003 -244.58454) (xy 91.728824 -244.535126)
			(xy 91.724729 -244.484398) (xy 91.416632 -244.484398) (xy 91.41612 -244.509844) (xy 91.407956 -244.560078)
			(xy 91.39184 -244.608352) (xy 91.368189 -244.653415) (xy 91.337616 -244.694101) (xy 91.300912 -244.729356)
			(xy 91.259028 -244.758266) (xy 91.213049 -244.780083) (xy 91.164165 -244.794243) (xy 91.113644 -244.800377)
			(xy 91.062792 -244.798328) (xy 91.012928 -244.788148) (xy 90.965342 -244.770101) (xy 90.921268 -244.744655)
			(xy 90.881846 -244.712468) (xy 90.848098 -244.674374) (xy 90.820897 -244.63136) (xy 90.800949 -244.58454)
			(xy 90.78877 -244.535126) (xy 90.784675 -244.484398) (xy 90.466418 -244.484398) (xy 90.465923 -244.509005)
			(xy 90.458028 -244.557582) (xy 90.442444 -244.604263) (xy 90.419573 -244.64784) (xy 90.390008 -244.687184)
			(xy 90.354515 -244.721276) (xy 90.314012 -244.749232) (xy 90.26955 -244.77033) (xy 90.222279 -244.784022)
			(xy 90.173424 -244.789954) (xy 90.124249 -244.787973) (xy 90.07603 -244.778129) (xy 90.030014 -244.760677)
			(xy 89.987393 -244.73607) (xy 89.949272 -244.704945) (xy 89.916637 -244.668108) (xy 89.890334 -244.626512)
			(xy 89.871043 -244.581236) (xy 89.859266 -244.533452) (xy 89.855306 -244.484398) (xy 89.526364 -244.484398)
			(xy 89.525869 -244.509005) (xy 89.517974 -244.557582) (xy 89.50239 -244.604263) (xy 89.479519 -244.64784)
			(xy 89.449954 -244.687184) (xy 89.414461 -244.721276) (xy 89.373958 -244.749232) (xy 89.329496 -244.77033)
			(xy 89.282225 -244.784022) (xy 89.23337 -244.789954) (xy 89.184195 -244.787973) (xy 89.135976 -244.778129)
			(xy 89.08996 -244.760677) (xy 89.047339 -244.73607) (xy 89.009218 -244.704945) (xy 88.976583 -244.668108)
			(xy 88.95028 -244.626512) (xy 88.930989 -244.581236) (xy 88.919212 -244.533452) (xy 88.915252 -244.484398)
			(xy 88.58631 -244.484398) (xy 88.585815 -244.509005) (xy 88.57792 -244.557582) (xy 88.562336 -244.604263)
			(xy 88.539465 -244.64784) (xy 88.5099 -244.687184) (xy 88.474407 -244.721276) (xy 88.433904 -244.749232)
			(xy 88.389442 -244.77033) (xy 88.342171 -244.784022) (xy 88.293316 -244.789954) (xy 88.244141 -244.787973)
			(xy 88.195922 -244.778129) (xy 88.149906 -244.760677) (xy 88.107285 -244.73607) (xy 88.069164 -244.704945)
			(xy 88.036529 -244.668108) (xy 88.010226 -244.626512) (xy 87.990935 -244.581236) (xy 87.979158 -244.533452)
			(xy 87.975198 -244.484398) (xy 87.646256 -244.484398) (xy 87.645761 -244.509005) (xy 87.637866 -244.557582)
			(xy 87.622282 -244.604263) (xy 87.599411 -244.64784) (xy 87.569846 -244.687184) (xy 87.534353 -244.721276)
			(xy 87.49385 -244.749232) (xy 87.449388 -244.77033) (xy 87.402117 -244.784022) (xy 87.353262 -244.789954)
			(xy 87.304087 -244.787973) (xy 87.255868 -244.778129) (xy 87.209852 -244.760677) (xy 87.167231 -244.73607)
			(xy 87.12911 -244.704945) (xy 87.096475 -244.668108) (xy 87.070172 -244.626512) (xy 87.050881 -244.581236)
			(xy 87.039104 -244.533452) (xy 87.035144 -244.484398) (xy 85.766402 -244.484398) (xy 85.765907 -244.509005)
			(xy 85.758012 -244.557582) (xy 85.742428 -244.604263) (xy 85.719557 -244.64784) (xy 85.689992 -244.687184)
			(xy 85.654499 -244.721276) (xy 85.613996 -244.749232) (xy 85.569534 -244.77033) (xy 85.522263 -244.784022)
			(xy 85.473408 -244.789954) (xy 85.424233 -244.787973) (xy 85.376014 -244.778129) (xy 85.329998 -244.760677)
			(xy 85.287377 -244.73607) (xy 85.249256 -244.704945) (xy 85.216621 -244.668108) (xy 85.190318 -244.626512)
			(xy 85.171027 -244.581236) (xy 85.15925 -244.533452) (xy 85.15529 -244.484398) (xy 84.826348 -244.484398)
			(xy 84.825853 -244.509005) (xy 84.817958 -244.557582) (xy 84.802374 -244.604263) (xy 84.779503 -244.64784)
			(xy 84.749938 -244.687184) (xy 84.714445 -244.721276) (xy 84.673942 -244.749232) (xy 84.62948 -244.77033)
			(xy 84.582209 -244.784022) (xy 84.533354 -244.789954) (xy 84.484179 -244.787973) (xy 84.43596 -244.778129)
			(xy 84.389944 -244.760677) (xy 84.347323 -244.73607) (xy 84.309202 -244.704945) (xy 84.276567 -244.668108)
			(xy 84.250264 -244.626512) (xy 84.230973 -244.581236) (xy 84.219196 -244.533452) (xy 84.215236 -244.484398)
			(xy 83.886294 -244.484398) (xy 83.885848 -244.508391) (xy 83.878341 -244.555786) (xy 83.863513 -244.601423)
			(xy 83.841727 -244.644178) (xy 83.813522 -244.682999) (xy 83.77959 -244.716929) (xy 83.740768 -244.745134)
			(xy 83.698012 -244.766917) (xy 83.652374 -244.781744) (xy 83.604979 -244.789249) (xy 83.580986 -244.789706)
			(xy 83.551268 -244.788182) (xy 83.551014 -244.788182) (xy 83.539076 -244.787166) (xy 83.528408 -244.79123)
			(xy 83.522867 -244.793538) (xy 83.512979 -244.800336) (xy 83.50885 -244.804692) (xy 83.508088 -244.805454)
			(xy 83.50221 -244.812437) (xy 83.495422 -244.829364) (xy 83.49488 -244.838474) (xy 83.49488 -245.294404)
			(xy 83.745336 -245.294404) (xy 83.749296 -245.24535) (xy 83.761073 -245.197566) (xy 83.780364 -245.15229)
			(xy 83.806667 -245.110694) (xy 83.839302 -245.073857) (xy 83.877423 -245.042732) (xy 83.920044 -245.018125)
			(xy 83.96606 -245.000673) (xy 84.014279 -244.990829) (xy 84.063454 -244.988848) (xy 84.112309 -244.99478)
			(xy 84.15958 -245.008472) (xy 84.204042 -245.02957) (xy 84.244545 -245.057526) (xy 84.280038 -245.091618)
			(xy 84.309603 -245.130962) (xy 84.332474 -245.174539) (xy 84.348058 -245.22122) (xy 84.355953 -245.269797)
			(xy 84.356448 -245.294404) (xy 84.685136 -245.294404) (xy 84.689096 -245.24535) (xy 84.700873 -245.197566)
			(xy 84.720164 -245.15229) (xy 84.746467 -245.110694) (xy 84.779102 -245.073857) (xy 84.817223 -245.042732)
			(xy 84.859844 -245.018125) (xy 84.90586 -245.000673) (xy 84.954079 -244.990829) (xy 85.003254 -244.988848)
			(xy 85.052109 -244.99478) (xy 85.09938 -245.008472) (xy 85.143842 -245.02957) (xy 85.184345 -245.057526)
			(xy 85.219838 -245.091618) (xy 85.249403 -245.130962) (xy 85.272274 -245.174539) (xy 85.287858 -245.22122)
			(xy 85.295753 -245.269797) (xy 85.296248 -245.294404) (xy 85.62519 -245.294404) (xy 85.62915 -245.24535)
			(xy 85.640927 -245.197566) (xy 85.660218 -245.15229) (xy 85.686521 -245.110694) (xy 85.719156 -245.073857)
			(xy 85.757277 -245.042732) (xy 85.799898 -245.018125) (xy 85.845914 -245.000673) (xy 85.894133 -244.990829)
			(xy 85.943308 -244.988848) (xy 85.992163 -244.99478) (xy 86.039434 -245.008472) (xy 86.083896 -245.02957)
			(xy 86.124399 -245.057526) (xy 86.159892 -245.091618) (xy 86.189457 -245.130962) (xy 86.212328 -245.174539)
			(xy 86.227912 -245.22122) (xy 86.235807 -245.269797) (xy 86.236302 -245.294404) (xy 86.565244 -245.294404)
			(xy 86.569204 -245.24535) (xy 86.580981 -245.197566) (xy 86.600272 -245.15229) (xy 86.626575 -245.110694)
			(xy 86.65921 -245.073857) (xy 86.697331 -245.042732) (xy 86.739952 -245.018125) (xy 86.785968 -245.000673)
			(xy 86.834187 -244.990829) (xy 86.883362 -244.988848) (xy 86.932217 -244.99478) (xy 86.979488 -245.008472)
			(xy 87.02395 -245.02957) (xy 87.064453 -245.057526) (xy 87.099946 -245.091618) (xy 87.129511 -245.130962)
			(xy 87.152382 -245.174539) (xy 87.167966 -245.22122) (xy 87.175861 -245.269797) (xy 87.176356 -245.294404)
			(xy 87.505298 -245.294404) (xy 87.509258 -245.24535) (xy 87.521035 -245.197566) (xy 87.540326 -245.15229)
			(xy 87.566629 -245.110694) (xy 87.599264 -245.073857) (xy 87.637385 -245.042732) (xy 87.680006 -245.018125)
			(xy 87.726022 -245.000673) (xy 87.774241 -244.990829) (xy 87.823416 -244.988848) (xy 87.872271 -244.99478)
			(xy 87.919542 -245.008472) (xy 87.964004 -245.02957) (xy 88.004507 -245.057526) (xy 88.04 -245.091618)
			(xy 88.069565 -245.130962) (xy 88.092436 -245.174539) (xy 88.10802 -245.22122) (xy 88.115915 -245.269797)
			(xy 88.11641 -245.294404) (xy 88.445352 -245.294404) (xy 88.449312 -245.24535) (xy 88.461089 -245.197566)
			(xy 88.48038 -245.15229) (xy 88.506683 -245.110694) (xy 88.539318 -245.073857) (xy 88.577439 -245.042732)
			(xy 88.62006 -245.018125) (xy 88.666076 -245.000673) (xy 88.714295 -244.990829) (xy 88.76347 -244.988848)
			(xy 88.812325 -244.99478) (xy 88.859596 -245.008472) (xy 88.904058 -245.02957) (xy 88.944561 -245.057526)
			(xy 88.980054 -245.091618) (xy 89.009619 -245.130962) (xy 89.03249 -245.174539) (xy 89.048074 -245.22122)
			(xy 89.055969 -245.269797) (xy 89.056464 -245.294404) (xy 89.385152 -245.294404) (xy 89.389112 -245.24535)
			(xy 89.400889 -245.197566) (xy 89.42018 -245.15229) (xy 89.446483 -245.110694) (xy 89.479118 -245.073857)
			(xy 89.517239 -245.042732) (xy 89.55986 -245.018125) (xy 89.605876 -245.000673) (xy 89.654095 -244.990829)
			(xy 89.70327 -244.988848) (xy 89.752125 -244.99478) (xy 89.799396 -245.008472) (xy 89.843858 -245.02957)
			(xy 89.884361 -245.057526) (xy 89.919854 -245.091618) (xy 89.949419 -245.130962) (xy 89.97229 -245.174539)
			(xy 89.987874 -245.22122) (xy 89.995769 -245.269797) (xy 89.996264 -245.294404) (xy 90.314775 -245.294404)
			(xy 90.31887 -245.243676) (xy 90.331049 -245.194262) (xy 90.350997 -245.147442) (xy 90.378198 -245.104428)
			(xy 90.411946 -245.066334) (xy 90.451368 -245.034147) (xy 90.495442 -245.008701) (xy 90.543028 -244.990654)
			(xy 90.592892 -244.980474) (xy 90.643744 -244.978425) (xy 90.694265 -244.984559) (xy 90.743149 -244.998719)
			(xy 90.789128 -245.020536) (xy 90.831012 -245.049446) (xy 90.867716 -245.084701) (xy 90.898289 -245.125387)
			(xy 90.92194 -245.17045) (xy 90.938056 -245.218724) (xy 90.94622 -245.268958) (xy 90.946732 -245.294404)
			(xy 91.26526 -245.294404) (xy 91.26922 -245.24535) (xy 91.280997 -245.197566) (xy 91.300288 -245.15229)
			(xy 91.326591 -245.110694) (xy 91.359226 -245.073857) (xy 91.397347 -245.042732) (xy 91.439968 -245.018125)
			(xy 91.485984 -245.000673) (xy 91.534203 -244.990829) (xy 91.583378 -244.988848) (xy 91.632233 -244.99478)
			(xy 91.679504 -245.008472) (xy 91.723966 -245.02957) (xy 91.764469 -245.057526) (xy 91.799962 -245.091618)
			(xy 91.829527 -245.130962) (xy 91.852398 -245.174539) (xy 91.867982 -245.22122) (xy 91.875877 -245.269797)
			(xy 91.876372 -245.294404) (xy 92.194883 -245.294404) (xy 92.198978 -245.243676) (xy 92.211157 -245.194262)
			(xy 92.231105 -245.147442) (xy 92.258306 -245.104428) (xy 92.292054 -245.066334) (xy 92.331476 -245.034147)
			(xy 92.37555 -245.008701) (xy 92.423136 -244.990654) (xy 92.473 -244.980474) (xy 92.523852 -244.978425)
			(xy 92.574373 -244.984559) (xy 92.623257 -244.998719) (xy 92.669236 -245.020536) (xy 92.71112 -245.049446)
			(xy 92.747824 -245.084701) (xy 92.778397 -245.125387) (xy 92.802048 -245.17045) (xy 92.818164 -245.218724)
			(xy 92.826328 -245.268958) (xy 92.82684 -245.294404) (xy 93.145114 -245.294404) (xy 93.149074 -245.24535)
			(xy 93.160851 -245.197566) (xy 93.180142 -245.15229) (xy 93.206445 -245.110694) (xy 93.23908 -245.073857)
			(xy 93.277201 -245.042732) (xy 93.319822 -245.018125) (xy 93.365838 -245.000673) (xy 93.414057 -244.990829)
			(xy 93.463232 -244.988848) (xy 93.512087 -244.99478) (xy 93.559358 -245.008472) (xy 93.60382 -245.02957)
			(xy 93.644323 -245.057526) (xy 93.679816 -245.091618) (xy 93.709381 -245.130962) (xy 93.732252 -245.174539)
			(xy 93.747836 -245.22122) (xy 93.755731 -245.269797) (xy 93.756226 -245.294404) (xy 94.074737 -245.294404)
			(xy 94.078832 -245.243676) (xy 94.091011 -245.194262) (xy 94.110959 -245.147442) (xy 94.13816 -245.104428)
			(xy 94.171908 -245.066334) (xy 94.21133 -245.034147) (xy 94.255404 -245.008701) (xy 94.30299 -244.990654)
			(xy 94.352854 -244.980474) (xy 94.403706 -244.978425) (xy 94.454227 -244.984559) (xy 94.503111 -244.998719)
			(xy 94.54909 -245.020536) (xy 94.590974 -245.049446) (xy 94.627678 -245.084701) (xy 94.658251 -245.125387)
			(xy 94.681902 -245.17045) (xy 94.698018 -245.218724) (xy 94.706182 -245.268958) (xy 94.706694 -245.294404)
			(xy 95.014791 -245.294404) (xy 95.018886 -245.243676) (xy 95.031065 -245.194262) (xy 95.051013 -245.147442)
			(xy 95.078214 -245.104428) (xy 95.111962 -245.066334) (xy 95.151384 -245.034147) (xy 95.195458 -245.008701)
			(xy 95.243044 -244.990654) (xy 95.292908 -244.980474) (xy 95.34376 -244.978425) (xy 95.394281 -244.984559)
			(xy 95.443165 -244.998719) (xy 95.489144 -245.020536) (xy 95.531028 -245.049446) (xy 95.567732 -245.084701)
			(xy 95.598305 -245.125387) (xy 95.621956 -245.17045) (xy 95.638072 -245.218724) (xy 95.646236 -245.268958)
			(xy 95.646748 -245.294404) (xy 95.646236 -245.31985) (xy 95.638072 -245.370084) (xy 95.621956 -245.418358)
			(xy 95.598305 -245.463421) (xy 95.567732 -245.504107) (xy 95.531028 -245.539362) (xy 95.489144 -245.568272)
			(xy 95.443165 -245.590089) (xy 95.394281 -245.604249) (xy 95.34376 -245.610383) (xy 95.292908 -245.608334)
			(xy 95.243044 -245.598154) (xy 95.195458 -245.580107) (xy 95.151384 -245.554661) (xy 95.111962 -245.522474)
			(xy 95.078214 -245.48438) (xy 95.051013 -245.441366) (xy 95.031065 -245.394546) (xy 95.018886 -245.345132)
			(xy 95.014791 -245.294404) (xy 94.706694 -245.294404) (xy 94.706182 -245.31985) (xy 94.698018 -245.370084)
			(xy 94.681902 -245.418358) (xy 94.658251 -245.463421) (xy 94.627678 -245.504107) (xy 94.590974 -245.539362)
			(xy 94.54909 -245.568272) (xy 94.503111 -245.590089) (xy 94.454227 -245.604249) (xy 94.403706 -245.610383)
			(xy 94.352854 -245.608334) (xy 94.30299 -245.598154) (xy 94.255404 -245.580107) (xy 94.21133 -245.554661)
			(xy 94.171908 -245.522474) (xy 94.13816 -245.48438) (xy 94.110959 -245.441366) (xy 94.091011 -245.394546)
			(xy 94.078832 -245.345132) (xy 94.074737 -245.294404) (xy 93.756226 -245.294404) (xy 93.755731 -245.319011)
			(xy 93.747836 -245.367588) (xy 93.732252 -245.414269) (xy 93.709381 -245.457846) (xy 93.679816 -245.49719)
			(xy 93.644323 -245.531282) (xy 93.60382 -245.559238) (xy 93.559358 -245.580336) (xy 93.512087 -245.594028)
			(xy 93.463232 -245.59996) (xy 93.414057 -245.597979) (xy 93.365838 -245.588135) (xy 93.319822 -245.570683)
			(xy 93.277201 -245.546076) (xy 93.23908 -245.514951) (xy 93.206445 -245.478114) (xy 93.180142 -245.436518)
			(xy 93.160851 -245.391242) (xy 93.149074 -245.343458) (xy 93.145114 -245.294404) (xy 92.82684 -245.294404)
			(xy 92.826328 -245.31985) (xy 92.818164 -245.370084) (xy 92.802048 -245.418358) (xy 92.778397 -245.463421)
			(xy 92.747824 -245.504107) (xy 92.71112 -245.539362) (xy 92.669236 -245.568272) (xy 92.623257 -245.590089)
			(xy 92.574373 -245.604249) (xy 92.523852 -245.610383) (xy 92.473 -245.608334) (xy 92.423136 -245.598154)
			(xy 92.37555 -245.580107) (xy 92.331476 -245.554661) (xy 92.292054 -245.522474) (xy 92.258306 -245.48438)
			(xy 92.231105 -245.441366) (xy 92.211157 -245.394546) (xy 92.198978 -245.345132) (xy 92.194883 -245.294404)
			(xy 91.876372 -245.294404) (xy 91.875877 -245.319011) (xy 91.867982 -245.367588) (xy 91.852398 -245.414269)
			(xy 91.829527 -245.457846) (xy 91.799962 -245.49719) (xy 91.764469 -245.531282) (xy 91.723966 -245.559238)
			(xy 91.679504 -245.580336) (xy 91.632233 -245.594028) (xy 91.583378 -245.59996) (xy 91.534203 -245.597979)
			(xy 91.485984 -245.588135) (xy 91.439968 -245.570683) (xy 91.397347 -245.546076) (xy 91.359226 -245.514951)
			(xy 91.326591 -245.478114) (xy 91.300288 -245.436518) (xy 91.280997 -245.391242) (xy 91.26922 -245.343458)
			(xy 91.26526 -245.294404) (xy 90.946732 -245.294404) (xy 90.94622 -245.31985) (xy 90.938056 -245.370084)
			(xy 90.92194 -245.418358) (xy 90.898289 -245.463421) (xy 90.867716 -245.504107) (xy 90.831012 -245.539362)
			(xy 90.789128 -245.568272) (xy 90.743149 -245.590089) (xy 90.694265 -245.604249) (xy 90.643744 -245.610383)
			(xy 90.592892 -245.608334) (xy 90.543028 -245.598154) (xy 90.495442 -245.580107) (xy 90.451368 -245.554661)
			(xy 90.411946 -245.522474) (xy 90.378198 -245.48438) (xy 90.350997 -245.441366) (xy 90.331049 -245.394546)
			(xy 90.31887 -245.345132) (xy 90.314775 -245.294404) (xy 89.996264 -245.294404) (xy 89.995769 -245.319011)
			(xy 89.987874 -245.367588) (xy 89.97229 -245.414269) (xy 89.949419 -245.457846) (xy 89.919854 -245.49719)
			(xy 89.884361 -245.531282) (xy 89.843858 -245.559238) (xy 89.799396 -245.580336) (xy 89.752125 -245.594028)
			(xy 89.70327 -245.59996) (xy 89.654095 -245.597979) (xy 89.605876 -245.588135) (xy 89.55986 -245.570683)
			(xy 89.517239 -245.546076) (xy 89.479118 -245.514951) (xy 89.446483 -245.478114) (xy 89.42018 -245.436518)
			(xy 89.400889 -245.391242) (xy 89.389112 -245.343458) (xy 89.385152 -245.294404) (xy 89.056464 -245.294404)
			(xy 89.055969 -245.319011) (xy 89.048074 -245.367588) (xy 89.03249 -245.414269) (xy 89.009619 -245.457846)
			(xy 88.980054 -245.49719) (xy 88.944561 -245.531282) (xy 88.904058 -245.559238) (xy 88.859596 -245.580336)
			(xy 88.812325 -245.594028) (xy 88.76347 -245.59996) (xy 88.714295 -245.597979) (xy 88.666076 -245.588135)
			(xy 88.62006 -245.570683) (xy 88.577439 -245.546076) (xy 88.539318 -245.514951) (xy 88.506683 -245.478114)
			(xy 88.48038 -245.436518) (xy 88.461089 -245.391242) (xy 88.449312 -245.343458) (xy 88.445352 -245.294404)
			(xy 88.11641 -245.294404) (xy 88.115915 -245.319011) (xy 88.10802 -245.367588) (xy 88.092436 -245.414269)
			(xy 88.069565 -245.457846) (xy 88.04 -245.49719) (xy 88.004507 -245.531282) (xy 87.964004 -245.559238)
			(xy 87.919542 -245.580336) (xy 87.872271 -245.594028) (xy 87.823416 -245.59996) (xy 87.774241 -245.597979)
			(xy 87.726022 -245.588135) (xy 87.680006 -245.570683) (xy 87.637385 -245.546076) (xy 87.599264 -245.514951)
			(xy 87.566629 -245.478114) (xy 87.540326 -245.436518) (xy 87.521035 -245.391242) (xy 87.509258 -245.343458)
			(xy 87.505298 -245.294404) (xy 87.176356 -245.294404) (xy 87.175861 -245.319011) (xy 87.167966 -245.367588)
			(xy 87.152382 -245.414269) (xy 87.129511 -245.457846) (xy 87.099946 -245.49719) (xy 87.064453 -245.531282)
			(xy 87.02395 -245.559238) (xy 86.979488 -245.580336) (xy 86.932217 -245.594028) (xy 86.883362 -245.59996)
			(xy 86.834187 -245.597979) (xy 86.785968 -245.588135) (xy 86.739952 -245.570683) (xy 86.697331 -245.546076)
			(xy 86.65921 -245.514951) (xy 86.626575 -245.478114) (xy 86.600272 -245.436518) (xy 86.580981 -245.391242)
			(xy 86.569204 -245.343458) (xy 86.565244 -245.294404) (xy 86.236302 -245.294404) (xy 86.235807 -245.319011)
			(xy 86.227912 -245.367588) (xy 86.212328 -245.414269) (xy 86.189457 -245.457846) (xy 86.159892 -245.49719)
			(xy 86.124399 -245.531282) (xy 86.083896 -245.559238) (xy 86.039434 -245.580336) (xy 85.992163 -245.594028)
			(xy 85.943308 -245.59996) (xy 85.894133 -245.597979) (xy 85.845914 -245.588135) (xy 85.799898 -245.570683)
			(xy 85.757277 -245.546076) (xy 85.719156 -245.514951) (xy 85.686521 -245.478114) (xy 85.660218 -245.436518)
			(xy 85.640927 -245.391242) (xy 85.62915 -245.343458) (xy 85.62519 -245.294404) (xy 85.296248 -245.294404)
			(xy 85.295753 -245.319011) (xy 85.287858 -245.367588) (xy 85.272274 -245.414269) (xy 85.249403 -245.457846)
			(xy 85.219838 -245.49719) (xy 85.184345 -245.531282) (xy 85.143842 -245.559238) (xy 85.09938 -245.580336)
			(xy 85.052109 -245.594028) (xy 85.003254 -245.59996) (xy 84.954079 -245.597979) (xy 84.90586 -245.588135)
			(xy 84.859844 -245.570683) (xy 84.817223 -245.546076) (xy 84.779102 -245.514951) (xy 84.746467 -245.478114)
			(xy 84.720164 -245.436518) (xy 84.700873 -245.391242) (xy 84.689096 -245.343458) (xy 84.685136 -245.294404)
			(xy 84.356448 -245.294404) (xy 84.355953 -245.319011) (xy 84.348058 -245.367588) (xy 84.332474 -245.414269)
			(xy 84.309603 -245.457846) (xy 84.280038 -245.49719) (xy 84.244545 -245.531282) (xy 84.204042 -245.559238)
			(xy 84.15958 -245.580336) (xy 84.112309 -245.594028) (xy 84.063454 -245.59996) (xy 84.014279 -245.597979)
			(xy 83.96606 -245.588135) (xy 83.920044 -245.570683) (xy 83.877423 -245.546076) (xy 83.839302 -245.514951)
			(xy 83.806667 -245.478114) (xy 83.780364 -245.436518) (xy 83.761073 -245.391242) (xy 83.749296 -245.343458)
			(xy 83.745336 -245.294404) (xy 83.49488 -245.294404) (xy 83.49488 -245.651528) (xy 83.494973 -245.656079)
			(xy 83.496638 -245.665026) (xy 83.498182 -245.669308) (xy 83.501738 -245.678706) (xy 83.537298 -245.718076)
			(xy 83.552792 -245.735348) (xy 83.559904 -245.741698) (xy 83.561936 -245.742968) (xy 83.567778 -245.746524)
			(xy 83.576414 -245.750588) (xy 83.585558 -245.751604) (xy 83.585812 -245.751604) (xy 83.60941 -245.754341)
			(xy 83.655415 -245.766181) (xy 83.699032 -245.785002) (xy 83.739208 -245.810349) (xy 83.774976 -245.84161)
			(xy 83.805473 -245.878033) (xy 83.829962 -245.918738) (xy 83.839304 -245.94058) (xy 83.84286 -245.947184)
			(xy 83.843114 -245.947692) (xy 83.856642 -245.971574) (xy 83.87589 -246.022967) (xy 83.885662 -246.07697)
			(xy 83.886294 -246.10441) (xy 84.215236 -246.10441) (xy 84.219196 -246.055356) (xy 84.230973 -246.007572)
			(xy 84.250264 -245.962296) (xy 84.276567 -245.9207) (xy 84.309202 -245.883863) (xy 84.347323 -245.852738)
			(xy 84.389944 -245.828131) (xy 84.43596 -245.810679) (xy 84.484179 -245.800835) (xy 84.533354 -245.798854)
			(xy 84.582209 -245.804786) (xy 84.62948 -245.818478) (xy 84.673942 -245.839576) (xy 84.714445 -245.867532)
			(xy 84.749938 -245.901624) (xy 84.779503 -245.940968) (xy 84.802374 -245.984545) (xy 84.817958 -246.031226)
			(xy 84.825853 -246.079803) (xy 84.826348 -246.10441) (xy 85.15529 -246.10441) (xy 85.15925 -246.055356)
			(xy 85.171027 -246.007572) (xy 85.190318 -245.962296) (xy 85.216621 -245.9207) (xy 85.249256 -245.883863)
			(xy 85.287377 -245.852738) (xy 85.329998 -245.828131) (xy 85.376014 -245.810679) (xy 85.424233 -245.800835)
			(xy 85.473408 -245.798854) (xy 85.522263 -245.804786) (xy 85.569534 -245.818478) (xy 85.613996 -245.839576)
			(xy 85.654499 -245.867532) (xy 85.689992 -245.901624) (xy 85.719557 -245.940968) (xy 85.742428 -245.984545)
			(xy 85.758012 -246.031226) (xy 85.765907 -246.079803) (xy 85.766402 -246.10441) (xy 86.095344 -246.10441)
			(xy 86.099304 -246.055356) (xy 86.111081 -246.007572) (xy 86.130372 -245.962296) (xy 86.156675 -245.9207)
			(xy 86.18931 -245.883863) (xy 86.227431 -245.852738) (xy 86.270052 -245.828131) (xy 86.316068 -245.810679)
			(xy 86.364287 -245.800835) (xy 86.413462 -245.798854) (xy 86.462317 -245.804786) (xy 86.509588 -245.818478)
			(xy 86.55405 -245.839576) (xy 86.594553 -245.867532) (xy 86.630046 -245.901624) (xy 86.659611 -245.940968)
			(xy 86.682482 -245.984545) (xy 86.698066 -246.031226) (xy 86.705961 -246.079803) (xy 86.706456 -246.10441)
			(xy 87.035144 -246.10441) (xy 87.039104 -246.055356) (xy 87.050881 -246.007572) (xy 87.070172 -245.962296)
			(xy 87.096475 -245.9207) (xy 87.12911 -245.883863) (xy 87.167231 -245.852738) (xy 87.209852 -245.828131)
			(xy 87.255868 -245.810679) (xy 87.304087 -245.800835) (xy 87.353262 -245.798854) (xy 87.402117 -245.804786)
			(xy 87.449388 -245.818478) (xy 87.49385 -245.839576) (xy 87.534353 -245.867532) (xy 87.569846 -245.901624)
			(xy 87.599411 -245.940968) (xy 87.622282 -245.984545) (xy 87.637866 -246.031226) (xy 87.645761 -246.079803)
			(xy 87.646256 -246.10441) (xy 87.975198 -246.10441) (xy 87.979158 -246.055356) (xy 87.990935 -246.007572)
			(xy 88.010226 -245.962296) (xy 88.036529 -245.9207) (xy 88.069164 -245.883863) (xy 88.107285 -245.852738)
			(xy 88.149906 -245.828131) (xy 88.195922 -245.810679) (xy 88.244141 -245.800835) (xy 88.293316 -245.798854)
			(xy 88.342171 -245.804786) (xy 88.389442 -245.818478) (xy 88.433904 -245.839576) (xy 88.474407 -245.867532)
			(xy 88.5099 -245.901624) (xy 88.539465 -245.940968) (xy 88.562336 -245.984545) (xy 88.57792 -246.031226)
			(xy 88.585815 -246.079803) (xy 88.58631 -246.10441) (xy 88.915252 -246.10441) (xy 88.919212 -246.055356)
			(xy 88.930989 -246.007572) (xy 88.95028 -245.962296) (xy 88.976583 -245.9207) (xy 89.009218 -245.883863)
			(xy 89.047339 -245.852738) (xy 89.08996 -245.828131) (xy 89.135976 -245.810679) (xy 89.184195 -245.800835)
			(xy 89.23337 -245.798854) (xy 89.282225 -245.804786) (xy 89.329496 -245.818478) (xy 89.373958 -245.839576)
			(xy 89.414461 -245.867532) (xy 89.449954 -245.901624) (xy 89.479519 -245.940968) (xy 89.50239 -245.984545)
			(xy 89.517974 -246.031226) (xy 89.525869 -246.079803) (xy 89.526364 -246.10441) (xy 89.855306 -246.10441)
			(xy 89.859266 -246.055356) (xy 89.871043 -246.007572) (xy 89.890334 -245.962296) (xy 89.916637 -245.9207)
			(xy 89.949272 -245.883863) (xy 89.987393 -245.852738) (xy 90.030014 -245.828131) (xy 90.07603 -245.810679)
			(xy 90.124249 -245.800835) (xy 90.173424 -245.798854) (xy 90.222279 -245.804786) (xy 90.26955 -245.818478)
			(xy 90.314012 -245.839576) (xy 90.354515 -245.867532) (xy 90.390008 -245.901624) (xy 90.419573 -245.940968)
			(xy 90.442444 -245.984545) (xy 90.458028 -246.031226) (xy 90.465923 -246.079803) (xy 90.466418 -246.10441)
			(xy 90.784675 -246.10441) (xy 90.78877 -246.053682) (xy 90.800949 -246.004268) (xy 90.820897 -245.957448)
			(xy 90.848098 -245.914434) (xy 90.881846 -245.87634) (xy 90.921268 -245.844153) (xy 90.965342 -245.818707)
			(xy 91.012928 -245.80066) (xy 91.062792 -245.79048) (xy 91.113644 -245.788431) (xy 91.164165 -245.794565)
			(xy 91.213049 -245.808725) (xy 91.259028 -245.830542) (xy 91.300912 -245.859452) (xy 91.337616 -245.894707)
			(xy 91.368189 -245.935393) (xy 91.39184 -245.980456) (xy 91.407956 -246.02873) (xy 91.41612 -246.078964)
			(xy 91.416632 -246.10441) (xy 91.724729 -246.10441) (xy 91.728824 -246.053682) (xy 91.741003 -246.004268)
			(xy 91.760951 -245.957448) (xy 91.788152 -245.914434) (xy 91.8219 -245.87634) (xy 91.861322 -245.844153)
			(xy 91.905396 -245.818707) (xy 91.952982 -245.80066) (xy 92.002846 -245.79048) (xy 92.053698 -245.788431)
			(xy 92.104219 -245.794565) (xy 92.153103 -245.808725) (xy 92.199082 -245.830542) (xy 92.240966 -245.859452)
			(xy 92.27767 -245.894707) (xy 92.308243 -245.935393) (xy 92.331894 -245.980456) (xy 92.34801 -246.02873)
			(xy 92.356174 -246.078964) (xy 92.356686 -246.10441) (xy 92.675214 -246.10441) (xy 92.679174 -246.055356)
			(xy 92.690951 -246.007572) (xy 92.710242 -245.962296) (xy 92.736545 -245.9207) (xy 92.76918 -245.883863)
			(xy 92.807301 -245.852738) (xy 92.849922 -245.828131) (xy 92.895938 -245.810679) (xy 92.944157 -245.800835)
			(xy 92.993332 -245.798854) (xy 93.042187 -245.804786) (xy 93.089458 -245.818478) (xy 93.13392 -245.839576)
			(xy 93.174423 -245.867532) (xy 93.209916 -245.901624) (xy 93.239481 -245.940968) (xy 93.262352 -245.984545)
			(xy 93.277936 -246.031226) (xy 93.285831 -246.079803) (xy 93.286326 -246.10441) (xy 93.604837 -246.10441)
			(xy 93.608932 -246.053682) (xy 93.621111 -246.004268) (xy 93.641059 -245.957448) (xy 93.66826 -245.914434)
			(xy 93.702008 -245.87634) (xy 93.74143 -245.844153) (xy 93.785504 -245.818707) (xy 93.83309 -245.80066)
			(xy 93.882954 -245.79048) (xy 93.933806 -245.788431) (xy 93.984327 -245.794565) (xy 94.033211 -245.808725)
			(xy 94.07919 -245.830542) (xy 94.121074 -245.859452) (xy 94.157778 -245.894707) (xy 94.188351 -245.935393)
			(xy 94.212002 -245.980456) (xy 94.228118 -246.02873) (xy 94.236282 -246.078964) (xy 94.236794 -246.10441)
			(xy 94.555322 -246.10441) (xy 94.559282 -246.055356) (xy 94.571059 -246.007572) (xy 94.59035 -245.962296)
			(xy 94.616653 -245.9207) (xy 94.649288 -245.883863) (xy 94.687409 -245.852738) (xy 94.73003 -245.828131)
			(xy 94.776046 -245.810679) (xy 94.824265 -245.800835) (xy 94.87344 -245.798854) (xy 94.922295 -245.804786)
			(xy 94.969566 -245.818478) (xy 95.014028 -245.839576) (xy 95.054531 -245.867532) (xy 95.090024 -245.901624)
			(xy 95.119589 -245.940968) (xy 95.14246 -245.984545) (xy 95.158044 -246.031226) (xy 95.165939 -246.079803)
			(xy 95.166434 -246.10441) (xy 95.484691 -246.10441) (xy 95.488786 -246.053682) (xy 95.500965 -246.004268)
			(xy 95.520913 -245.957448) (xy 95.548114 -245.914434) (xy 95.581862 -245.87634) (xy 95.621284 -245.844153)
			(xy 95.665358 -245.818707) (xy 95.712944 -245.80066) (xy 95.762808 -245.79048) (xy 95.81366 -245.788431)
			(xy 95.864181 -245.794565) (xy 95.913065 -245.808725) (xy 95.959044 -245.830542) (xy 96.000928 -245.859452)
			(xy 96.037632 -245.894707) (xy 96.068205 -245.935393) (xy 96.091856 -245.980456) (xy 96.107972 -246.02873)
			(xy 96.116136 -246.078964) (xy 96.116648 -246.10441) (xy 96.116136 -246.129856) (xy 96.107972 -246.18009)
			(xy 96.091856 -246.228364) (xy 96.068205 -246.273427) (xy 96.037632 -246.314113) (xy 96.000928 -246.349368)
			(xy 95.959044 -246.378278) (xy 95.913065 -246.400095) (xy 95.864181 -246.414255) (xy 95.81366 -246.420389)
			(xy 95.762808 -246.41834) (xy 95.712944 -246.40816) (xy 95.665358 -246.390113) (xy 95.621284 -246.364667)
			(xy 95.581862 -246.33248) (xy 95.548114 -246.294386) (xy 95.520913 -246.251372) (xy 95.500965 -246.204552)
			(xy 95.488786 -246.155138) (xy 95.484691 -246.10441) (xy 95.166434 -246.10441) (xy 95.165939 -246.129017)
			(xy 95.158044 -246.177594) (xy 95.14246 -246.224275) (xy 95.119589 -246.267852) (xy 95.090024 -246.307196)
			(xy 95.054531 -246.341288) (xy 95.014028 -246.369244) (xy 94.969566 -246.390342) (xy 94.922295 -246.404034)
			(xy 94.87344 -246.409966) (xy 94.824265 -246.407985) (xy 94.776046 -246.398141) (xy 94.73003 -246.380689)
			(xy 94.687409 -246.356082) (xy 94.649288 -246.324957) (xy 94.616653 -246.28812) (xy 94.59035 -246.246524)
			(xy 94.571059 -246.201248) (xy 94.559282 -246.153464) (xy 94.555322 -246.10441) (xy 94.236794 -246.10441)
			(xy 94.236282 -246.129856) (xy 94.228118 -246.18009) (xy 94.212002 -246.228364) (xy 94.188351 -246.273427)
			(xy 94.157778 -246.314113) (xy 94.121074 -246.349368) (xy 94.07919 -246.378278) (xy 94.033211 -246.400095)
			(xy 93.984327 -246.414255) (xy 93.933806 -246.420389) (xy 93.882954 -246.41834) (xy 93.83309 -246.40816)
			(xy 93.785504 -246.390113) (xy 93.74143 -246.364667) (xy 93.702008 -246.33248) (xy 93.66826 -246.294386)
			(xy 93.641059 -246.251372) (xy 93.621111 -246.204552) (xy 93.608932 -246.155138) (xy 93.604837 -246.10441)
			(xy 93.286326 -246.10441) (xy 93.285831 -246.129017) (xy 93.277936 -246.177594) (xy 93.262352 -246.224275)
			(xy 93.239481 -246.267852) (xy 93.209916 -246.307196) (xy 93.174423 -246.341288) (xy 93.13392 -246.369244)
			(xy 93.089458 -246.390342) (xy 93.042187 -246.404034) (xy 92.993332 -246.409966) (xy 92.944157 -246.407985)
			(xy 92.895938 -246.398141) (xy 92.849922 -246.380689) (xy 92.807301 -246.356082) (xy 92.76918 -246.324957)
			(xy 92.736545 -246.28812) (xy 92.710242 -246.246524) (xy 92.690951 -246.201248) (xy 92.679174 -246.153464)
			(xy 92.675214 -246.10441) (xy 92.356686 -246.10441) (xy 92.356174 -246.129856) (xy 92.34801 -246.18009)
			(xy 92.331894 -246.228364) (xy 92.308243 -246.273427) (xy 92.27767 -246.314113) (xy 92.240966 -246.349368)
			(xy 92.199082 -246.378278) (xy 92.153103 -246.400095) (xy 92.104219 -246.414255) (xy 92.053698 -246.420389)
			(xy 92.002846 -246.41834) (xy 91.952982 -246.40816) (xy 91.905396 -246.390113) (xy 91.861322 -246.364667)
			(xy 91.8219 -246.33248) (xy 91.788152 -246.294386) (xy 91.760951 -246.251372) (xy 91.741003 -246.204552)
			(xy 91.728824 -246.155138) (xy 91.724729 -246.10441) (xy 91.416632 -246.10441) (xy 91.41612 -246.129856)
			(xy 91.407956 -246.18009) (xy 91.39184 -246.228364) (xy 91.368189 -246.273427) (xy 91.337616 -246.314113)
			(xy 91.300912 -246.349368) (xy 91.259028 -246.378278) (xy 91.213049 -246.400095) (xy 91.164165 -246.414255)
			(xy 91.113644 -246.420389) (xy 91.062792 -246.41834) (xy 91.012928 -246.40816) (xy 90.965342 -246.390113)
			(xy 90.921268 -246.364667) (xy 90.881846 -246.33248) (xy 90.848098 -246.294386) (xy 90.820897 -246.251372)
			(xy 90.800949 -246.204552) (xy 90.78877 -246.155138) (xy 90.784675 -246.10441) (xy 90.466418 -246.10441)
			(xy 90.465923 -246.129017) (xy 90.458028 -246.177594) (xy 90.442444 -246.224275) (xy 90.419573 -246.267852)
			(xy 90.390008 -246.307196) (xy 90.354515 -246.341288) (xy 90.314012 -246.369244) (xy 90.26955 -246.390342)
			(xy 90.222279 -246.404034) (xy 90.173424 -246.409966) (xy 90.124249 -246.407985) (xy 90.07603 -246.398141)
			(xy 90.030014 -246.380689) (xy 89.987393 -246.356082) (xy 89.949272 -246.324957) (xy 89.916637 -246.28812)
			(xy 89.890334 -246.246524) (xy 89.871043 -246.201248) (xy 89.859266 -246.153464) (xy 89.855306 -246.10441)
			(xy 89.526364 -246.10441) (xy 89.525869 -246.129017) (xy 89.517974 -246.177594) (xy 89.50239 -246.224275)
			(xy 89.479519 -246.267852) (xy 89.449954 -246.307196) (xy 89.414461 -246.341288) (xy 89.373958 -246.369244)
			(xy 89.329496 -246.390342) (xy 89.282225 -246.404034) (xy 89.23337 -246.409966) (xy 89.184195 -246.407985)
			(xy 89.135976 -246.398141) (xy 89.08996 -246.380689) (xy 89.047339 -246.356082) (xy 89.009218 -246.324957)
			(xy 88.976583 -246.28812) (xy 88.95028 -246.246524) (xy 88.930989 -246.201248) (xy 88.919212 -246.153464)
			(xy 88.915252 -246.10441) (xy 88.58631 -246.10441) (xy 88.585815 -246.129017) (xy 88.57792 -246.177594)
			(xy 88.562336 -246.224275) (xy 88.539465 -246.267852) (xy 88.5099 -246.307196) (xy 88.474407 -246.341288)
			(xy 88.433904 -246.369244) (xy 88.389442 -246.390342) (xy 88.342171 -246.404034) (xy 88.293316 -246.409966)
			(xy 88.244141 -246.407985) (xy 88.195922 -246.398141) (xy 88.149906 -246.380689) (xy 88.107285 -246.356082)
			(xy 88.069164 -246.324957) (xy 88.036529 -246.28812) (xy 88.010226 -246.246524) (xy 87.990935 -246.201248)
			(xy 87.979158 -246.153464) (xy 87.975198 -246.10441) (xy 87.646256 -246.10441) (xy 87.645761 -246.129017)
			(xy 87.637866 -246.177594) (xy 87.622282 -246.224275) (xy 87.599411 -246.267852) (xy 87.569846 -246.307196)
			(xy 87.534353 -246.341288) (xy 87.49385 -246.369244) (xy 87.449388 -246.390342) (xy 87.402117 -246.404034)
			(xy 87.353262 -246.409966) (xy 87.304087 -246.407985) (xy 87.255868 -246.398141) (xy 87.209852 -246.380689)
			(xy 87.167231 -246.356082) (xy 87.12911 -246.324957) (xy 87.096475 -246.28812) (xy 87.070172 -246.246524)
			(xy 87.050881 -246.201248) (xy 87.039104 -246.153464) (xy 87.035144 -246.10441) (xy 86.706456 -246.10441)
			(xy 86.705961 -246.129017) (xy 86.698066 -246.177594) (xy 86.682482 -246.224275) (xy 86.659611 -246.267852)
			(xy 86.630046 -246.307196) (xy 86.594553 -246.341288) (xy 86.55405 -246.369244) (xy 86.509588 -246.390342)
			(xy 86.462317 -246.404034) (xy 86.413462 -246.409966) (xy 86.364287 -246.407985) (xy 86.316068 -246.398141)
			(xy 86.270052 -246.380689) (xy 86.227431 -246.356082) (xy 86.18931 -246.324957) (xy 86.156675 -246.28812)
			(xy 86.130372 -246.246524) (xy 86.111081 -246.201248) (xy 86.099304 -246.153464) (xy 86.095344 -246.10441)
			(xy 85.766402 -246.10441) (xy 85.765907 -246.129017) (xy 85.758012 -246.177594) (xy 85.742428 -246.224275)
			(xy 85.719557 -246.267852) (xy 85.689992 -246.307196) (xy 85.654499 -246.341288) (xy 85.613996 -246.369244)
			(xy 85.569534 -246.390342) (xy 85.522263 -246.404034) (xy 85.473408 -246.409966) (xy 85.424233 -246.407985)
			(xy 85.376014 -246.398141) (xy 85.329998 -246.380689) (xy 85.287377 -246.356082) (xy 85.249256 -246.324957)
			(xy 85.216621 -246.28812) (xy 85.190318 -246.246524) (xy 85.171027 -246.201248) (xy 85.15925 -246.153464)
			(xy 85.15529 -246.10441) (xy 84.826348 -246.10441) (xy 84.825853 -246.129017) (xy 84.817958 -246.177594)
			(xy 84.802374 -246.224275) (xy 84.779503 -246.267852) (xy 84.749938 -246.307196) (xy 84.714445 -246.341288)
			(xy 84.673942 -246.369244) (xy 84.62948 -246.390342) (xy 84.582209 -246.404034) (xy 84.533354 -246.409966)
			(xy 84.484179 -246.407985) (xy 84.43596 -246.398141) (xy 84.389944 -246.380689) (xy 84.347323 -246.356082)
			(xy 84.309202 -246.324957) (xy 84.276567 -246.28812) (xy 84.250264 -246.246524) (xy 84.230973 -246.201248)
			(xy 84.219196 -246.153464) (xy 84.215236 -246.10441) (xy 83.886294 -246.10441) (xy 83.885847 -246.128402)
			(xy 83.878339 -246.175796) (xy 83.863509 -246.221431) (xy 83.841723 -246.264185) (xy 83.813517 -246.303004)
			(xy 83.779586 -246.336933) (xy 83.740764 -246.365136) (xy 83.698009 -246.386919) (xy 83.652372 -246.401745)
			(xy 83.604978 -246.409249) (xy 83.580986 -246.409718) (xy 83.551268 -246.408194) (xy 83.551014 -246.408194)
			(xy 83.539076 -246.407178) (xy 83.528408 -246.411242) (xy 83.522868 -246.413551) (xy 83.51298 -246.42035)
			(xy 83.50885 -246.424704) (xy 83.508088 -246.425466) (xy 83.502212 -246.432449) (xy 83.495428 -246.449377)
			(xy 83.49488 -246.458486) (xy 83.49488 -246.914416) (xy 83.745336 -246.914416) (xy 83.749296 -246.865362)
			(xy 83.761073 -246.817578) (xy 83.780364 -246.772302) (xy 83.806667 -246.730706) (xy 83.839302 -246.693869)
			(xy 83.877423 -246.662744) (xy 83.920044 -246.638137) (xy 83.96606 -246.620685) (xy 84.014279 -246.610841)
			(xy 84.063454 -246.60886) (xy 84.112309 -246.614792) (xy 84.15958 -246.628484) (xy 84.204042 -246.649582)
			(xy 84.244545 -246.677538) (xy 84.280038 -246.71163) (xy 84.309603 -246.750974) (xy 84.332474 -246.794551)
			(xy 84.348058 -246.841232) (xy 84.355953 -246.889809) (xy 84.356448 -246.914416) (xy 84.685136 -246.914416)
			(xy 84.689096 -246.865362) (xy 84.700873 -246.817578) (xy 84.720164 -246.772302) (xy 84.746467 -246.730706)
			(xy 84.779102 -246.693869) (xy 84.817223 -246.662744) (xy 84.859844 -246.638137) (xy 84.90586 -246.620685)
			(xy 84.954079 -246.610841) (xy 85.003254 -246.60886) (xy 85.052109 -246.614792) (xy 85.09938 -246.628484)
			(xy 85.143842 -246.649582) (xy 85.184345 -246.677538) (xy 85.219838 -246.71163) (xy 85.249403 -246.750974)
			(xy 85.272274 -246.794551) (xy 85.287858 -246.841232) (xy 85.295753 -246.889809) (xy 85.296248 -246.914416)
			(xy 85.62519 -246.914416) (xy 85.62915 -246.865362) (xy 85.640927 -246.817578) (xy 85.660218 -246.772302)
			(xy 85.686521 -246.730706) (xy 85.719156 -246.693869) (xy 85.757277 -246.662744) (xy 85.799898 -246.638137)
			(xy 85.845914 -246.620685) (xy 85.894133 -246.610841) (xy 85.943308 -246.60886) (xy 85.992163 -246.614792)
			(xy 86.039434 -246.628484) (xy 86.083896 -246.649582) (xy 86.124399 -246.677538) (xy 86.159892 -246.71163)
			(xy 86.189457 -246.750974) (xy 86.212328 -246.794551) (xy 86.227912 -246.841232) (xy 86.235807 -246.889809)
			(xy 86.236302 -246.914416) (xy 87.505298 -246.914416) (xy 87.509258 -246.865362) (xy 87.521035 -246.817578)
			(xy 87.540326 -246.772302) (xy 87.566629 -246.730706) (xy 87.599264 -246.693869) (xy 87.637385 -246.662744)
			(xy 87.680006 -246.638137) (xy 87.726022 -246.620685) (xy 87.774241 -246.610841) (xy 87.823416 -246.60886)
			(xy 87.872271 -246.614792) (xy 87.919542 -246.628484) (xy 87.964004 -246.649582) (xy 88.004507 -246.677538)
			(xy 88.04 -246.71163) (xy 88.069565 -246.750974) (xy 88.092436 -246.794551) (xy 88.10802 -246.841232)
			(xy 88.115915 -246.889809) (xy 88.11641 -246.914416) (xy 88.445352 -246.914416) (xy 88.449312 -246.865362)
			(xy 88.461089 -246.817578) (xy 88.48038 -246.772302) (xy 88.506683 -246.730706) (xy 88.539318 -246.693869)
			(xy 88.577439 -246.662744) (xy 88.62006 -246.638137) (xy 88.666076 -246.620685) (xy 88.714295 -246.610841)
			(xy 88.76347 -246.60886) (xy 88.812325 -246.614792) (xy 88.859596 -246.628484) (xy 88.904058 -246.649582)
			(xy 88.944561 -246.677538) (xy 88.980054 -246.71163) (xy 89.009619 -246.750974) (xy 89.03249 -246.794551)
			(xy 89.048074 -246.841232) (xy 89.055969 -246.889809) (xy 89.056464 -246.914416) (xy 89.385152 -246.914416)
			(xy 89.389112 -246.865362) (xy 89.400889 -246.817578) (xy 89.42018 -246.772302) (xy 89.446483 -246.730706)
			(xy 89.479118 -246.693869) (xy 89.517239 -246.662744) (xy 89.55986 -246.638137) (xy 89.605876 -246.620685)
			(xy 89.654095 -246.610841) (xy 89.70327 -246.60886) (xy 89.752125 -246.614792) (xy 89.799396 -246.628484)
			(xy 89.843858 -246.649582) (xy 89.884361 -246.677538) (xy 89.919854 -246.71163) (xy 89.949419 -246.750974)
			(xy 89.97229 -246.794551) (xy 89.987874 -246.841232) (xy 89.995769 -246.889809) (xy 89.996264 -246.914416)
			(xy 90.314775 -246.914416) (xy 90.31887 -246.863688) (xy 90.331049 -246.814274) (xy 90.350997 -246.767454)
			(xy 90.378198 -246.72444) (xy 90.411946 -246.686346) (xy 90.451368 -246.654159) (xy 90.495442 -246.628713)
			(xy 90.543028 -246.610666) (xy 90.592892 -246.600486) (xy 90.643744 -246.598437) (xy 90.694265 -246.604571)
			(xy 90.743149 -246.618731) (xy 90.789128 -246.640548) (xy 90.831012 -246.669458) (xy 90.867716 -246.704713)
			(xy 90.898289 -246.745399) (xy 90.92194 -246.790462) (xy 90.938056 -246.838736) (xy 90.94622 -246.88897)
			(xy 90.946732 -246.914416) (xy 91.26526 -246.914416) (xy 91.26922 -246.865362) (xy 91.280997 -246.817578)
			(xy 91.300288 -246.772302) (xy 91.326591 -246.730706) (xy 91.359226 -246.693869) (xy 91.397347 -246.662744)
			(xy 91.439968 -246.638137) (xy 91.485984 -246.620685) (xy 91.534203 -246.610841) (xy 91.583378 -246.60886)
			(xy 91.632233 -246.614792) (xy 91.679504 -246.628484) (xy 91.723966 -246.649582) (xy 91.764469 -246.677538)
			(xy 91.799962 -246.71163) (xy 91.829527 -246.750974) (xy 91.852398 -246.794551) (xy 91.867982 -246.841232)
			(xy 91.875877 -246.889809) (xy 91.876372 -246.914416) (xy 92.194883 -246.914416) (xy 92.198978 -246.863688)
			(xy 92.211157 -246.814274) (xy 92.231105 -246.767454) (xy 92.258306 -246.72444) (xy 92.292054 -246.686346)
			(xy 92.331476 -246.654159) (xy 92.37555 -246.628713) (xy 92.423136 -246.610666) (xy 92.473 -246.600486)
			(xy 92.523852 -246.598437) (xy 92.574373 -246.604571) (xy 92.623257 -246.618731) (xy 92.669236 -246.640548)
			(xy 92.71112 -246.669458) (xy 92.747824 -246.704713) (xy 92.778397 -246.745399) (xy 92.802048 -246.790462)
			(xy 92.818164 -246.838736) (xy 92.826328 -246.88897) (xy 92.82684 -246.914416) (xy 94.074737 -246.914416)
			(xy 94.078832 -246.863688) (xy 94.091011 -246.814274) (xy 94.110959 -246.767454) (xy 94.13816 -246.72444)
			(xy 94.171908 -246.686346) (xy 94.21133 -246.654159) (xy 94.255404 -246.628713) (xy 94.30299 -246.610666)
			(xy 94.352854 -246.600486) (xy 94.403706 -246.598437) (xy 94.454227 -246.604571) (xy 94.503111 -246.618731)
			(xy 94.54909 -246.640548) (xy 94.590974 -246.669458) (xy 94.627678 -246.704713) (xy 94.658251 -246.745399)
			(xy 94.681902 -246.790462) (xy 94.698018 -246.838736) (xy 94.706182 -246.88897) (xy 94.706694 -246.914416)
			(xy 95.014791 -246.914416) (xy 95.018886 -246.863688) (xy 95.031065 -246.814274) (xy 95.051013 -246.767454)
			(xy 95.078214 -246.72444) (xy 95.111962 -246.686346) (xy 95.151384 -246.654159) (xy 95.195458 -246.628713)
			(xy 95.243044 -246.610666) (xy 95.292908 -246.600486) (xy 95.34376 -246.598437) (xy 95.394281 -246.604571)
			(xy 95.443165 -246.618731) (xy 95.489144 -246.640548) (xy 95.531028 -246.669458) (xy 95.567732 -246.704713)
			(xy 95.598305 -246.745399) (xy 95.621956 -246.790462) (xy 95.638072 -246.838736) (xy 95.646236 -246.88897)
			(xy 95.646748 -246.914416) (xy 95.646236 -246.939862) (xy 95.638072 -246.990096) (xy 95.621956 -247.03837)
			(xy 95.598305 -247.083433) (xy 95.567732 -247.124119) (xy 95.531028 -247.159374) (xy 95.489144 -247.188284)
			(xy 95.443165 -247.210101) (xy 95.394281 -247.224261) (xy 95.34376 -247.230395) (xy 95.292908 -247.228346)
			(xy 95.243044 -247.218166) (xy 95.195458 -247.200119) (xy 95.151384 -247.174673) (xy 95.111962 -247.142486)
			(xy 95.078214 -247.104392) (xy 95.051013 -247.061378) (xy 95.031065 -247.014558) (xy 95.018886 -246.965144)
			(xy 95.014791 -246.914416) (xy 94.706694 -246.914416) (xy 94.706182 -246.939862) (xy 94.698018 -246.990096)
			(xy 94.681902 -247.03837) (xy 94.658251 -247.083433) (xy 94.627678 -247.124119) (xy 94.590974 -247.159374)
			(xy 94.54909 -247.188284) (xy 94.503111 -247.210101) (xy 94.454227 -247.224261) (xy 94.403706 -247.230395)
			(xy 94.352854 -247.228346) (xy 94.30299 -247.218166) (xy 94.255404 -247.200119) (xy 94.21133 -247.174673)
			(xy 94.171908 -247.142486) (xy 94.13816 -247.104392) (xy 94.110959 -247.061378) (xy 94.091011 -247.014558)
			(xy 94.078832 -246.965144) (xy 94.074737 -246.914416) (xy 92.82684 -246.914416) (xy 92.826328 -246.939862)
			(xy 92.818164 -246.990096) (xy 92.802048 -247.03837) (xy 92.778397 -247.083433) (xy 92.747824 -247.124119)
			(xy 92.71112 -247.159374) (xy 92.669236 -247.188284) (xy 92.623257 -247.210101) (xy 92.574373 -247.224261)
			(xy 92.523852 -247.230395) (xy 92.473 -247.228346) (xy 92.423136 -247.218166) (xy 92.37555 -247.200119)
			(xy 92.331476 -247.174673) (xy 92.292054 -247.142486) (xy 92.258306 -247.104392) (xy 92.231105 -247.061378)
			(xy 92.211157 -247.014558) (xy 92.198978 -246.965144) (xy 92.194883 -246.914416) (xy 91.876372 -246.914416)
			(xy 91.875877 -246.939023) (xy 91.867982 -246.9876) (xy 91.852398 -247.034281) (xy 91.829527 -247.077858)
			(xy 91.799962 -247.117202) (xy 91.764469 -247.151294) (xy 91.723966 -247.17925) (xy 91.679504 -247.200348)
			(xy 91.632233 -247.21404) (xy 91.583378 -247.219972) (xy 91.534203 -247.217991) (xy 91.485984 -247.208147)
			(xy 91.439968 -247.190695) (xy 91.397347 -247.166088) (xy 91.359226 -247.134963) (xy 91.326591 -247.098126)
			(xy 91.300288 -247.05653) (xy 91.280997 -247.011254) (xy 91.26922 -246.96347) (xy 91.26526 -246.914416)
			(xy 90.946732 -246.914416) (xy 90.94622 -246.939862) (xy 90.938056 -246.990096) (xy 90.92194 -247.03837)
			(xy 90.898289 -247.083433) (xy 90.867716 -247.124119) (xy 90.831012 -247.159374) (xy 90.789128 -247.188284)
			(xy 90.743149 -247.210101) (xy 90.694265 -247.224261) (xy 90.643744 -247.230395) (xy 90.592892 -247.228346)
			(xy 90.543028 -247.218166) (xy 90.495442 -247.200119) (xy 90.451368 -247.174673) (xy 90.411946 -247.142486)
			(xy 90.378198 -247.104392) (xy 90.350997 -247.061378) (xy 90.331049 -247.014558) (xy 90.31887 -246.965144)
			(xy 90.314775 -246.914416) (xy 89.996264 -246.914416) (xy 89.995769 -246.939023) (xy 89.987874 -246.9876)
			(xy 89.97229 -247.034281) (xy 89.949419 -247.077858) (xy 89.919854 -247.117202) (xy 89.884361 -247.151294)
			(xy 89.843858 -247.17925) (xy 89.799396 -247.200348) (xy 89.752125 -247.21404) (xy 89.70327 -247.219972)
			(xy 89.654095 -247.217991) (xy 89.605876 -247.208147) (xy 89.55986 -247.190695) (xy 89.517239 -247.166088)
			(xy 89.479118 -247.134963) (xy 89.446483 -247.098126) (xy 89.42018 -247.05653) (xy 89.400889 -247.011254)
			(xy 89.389112 -246.96347) (xy 89.385152 -246.914416) (xy 89.056464 -246.914416) (xy 89.055969 -246.939023)
			(xy 89.048074 -246.9876) (xy 89.03249 -247.034281) (xy 89.009619 -247.077858) (xy 88.980054 -247.117202)
			(xy 88.944561 -247.151294) (xy 88.904058 -247.17925) (xy 88.859596 -247.200348) (xy 88.812325 -247.21404)
			(xy 88.76347 -247.219972) (xy 88.714295 -247.217991) (xy 88.666076 -247.208147) (xy 88.62006 -247.190695)
			(xy 88.577439 -247.166088) (xy 88.539318 -247.134963) (xy 88.506683 -247.098126) (xy 88.48038 -247.05653)
			(xy 88.461089 -247.011254) (xy 88.449312 -246.96347) (xy 88.445352 -246.914416) (xy 88.11641 -246.914416)
			(xy 88.115915 -246.939023) (xy 88.10802 -246.9876) (xy 88.092436 -247.034281) (xy 88.069565 -247.077858)
			(xy 88.04 -247.117202) (xy 88.004507 -247.151294) (xy 87.964004 -247.17925) (xy 87.919542 -247.200348)
			(xy 87.872271 -247.21404) (xy 87.823416 -247.219972) (xy 87.774241 -247.217991) (xy 87.726022 -247.208147)
			(xy 87.680006 -247.190695) (xy 87.637385 -247.166088) (xy 87.599264 -247.134963) (xy 87.566629 -247.098126)
			(xy 87.540326 -247.05653) (xy 87.521035 -247.011254) (xy 87.509258 -246.96347) (xy 87.505298 -246.914416)
			(xy 86.236302 -246.914416) (xy 86.235807 -246.939023) (xy 86.227912 -246.9876) (xy 86.212328 -247.034281)
			(xy 86.189457 -247.077858) (xy 86.159892 -247.117202) (xy 86.124399 -247.151294) (xy 86.083896 -247.17925)
			(xy 86.039434 -247.200348) (xy 85.992163 -247.21404) (xy 85.943308 -247.219972) (xy 85.894133 -247.217991)
			(xy 85.845914 -247.208147) (xy 85.799898 -247.190695) (xy 85.757277 -247.166088) (xy 85.719156 -247.134963)
			(xy 85.686521 -247.098126) (xy 85.660218 -247.05653) (xy 85.640927 -247.011254) (xy 85.62915 -246.96347)
			(xy 85.62519 -246.914416) (xy 85.296248 -246.914416) (xy 85.295753 -246.939023) (xy 85.287858 -246.9876)
			(xy 85.272274 -247.034281) (xy 85.249403 -247.077858) (xy 85.219838 -247.117202) (xy 85.184345 -247.151294)
			(xy 85.143842 -247.17925) (xy 85.09938 -247.200348) (xy 85.052109 -247.21404) (xy 85.003254 -247.219972)
			(xy 84.954079 -247.217991) (xy 84.90586 -247.208147) (xy 84.859844 -247.190695) (xy 84.817223 -247.166088)
			(xy 84.779102 -247.134963) (xy 84.746467 -247.098126) (xy 84.720164 -247.05653) (xy 84.700873 -247.011254)
			(xy 84.689096 -246.96347) (xy 84.685136 -246.914416) (xy 84.356448 -246.914416) (xy 84.355953 -246.939023)
			(xy 84.348058 -246.9876) (xy 84.332474 -247.034281) (xy 84.309603 -247.077858) (xy 84.280038 -247.117202)
			(xy 84.244545 -247.151294) (xy 84.204042 -247.17925) (xy 84.15958 -247.200348) (xy 84.112309 -247.21404)
			(xy 84.063454 -247.219972) (xy 84.014279 -247.217991) (xy 83.96606 -247.208147) (xy 83.920044 -247.190695)
			(xy 83.877423 -247.166088) (xy 83.839302 -247.134963) (xy 83.806667 -247.098126) (xy 83.780364 -247.05653)
			(xy 83.761073 -247.011254) (xy 83.749296 -246.96347) (xy 83.745336 -246.914416) (xy 83.49488 -246.914416)
			(xy 83.49488 -247.27154) (xy 83.494974 -247.27609) (xy 83.496642 -247.285037) (xy 83.498182 -247.28932)
			(xy 83.501738 -247.298718) (xy 83.537298 -247.338088) (xy 83.552792 -247.35536) (xy 83.559904 -247.36171)
			(xy 83.561936 -247.36298) (xy 83.567778 -247.366536) (xy 83.576414 -247.3706) (xy 83.585558 -247.371616)
			(xy 83.585812 -247.371616) (xy 83.60941 -247.374353) (xy 83.655414 -247.386194) (xy 83.69903 -247.405015)
			(xy 83.739206 -247.430362) (xy 83.774973 -247.461624) (xy 83.805468 -247.498047) (xy 83.829956 -247.538753)
			(xy 83.839304 -247.560592) (xy 83.84286 -247.567196) (xy 83.843114 -247.567704) (xy 83.856649 -247.591584)
			(xy 83.875912 -247.642976) (xy 83.885699 -247.69698) (xy 83.886294 -247.724422) (xy 84.215236 -247.724422)
			(xy 84.219196 -247.675368) (xy 84.230973 -247.627584) (xy 84.250264 -247.582308) (xy 84.276567 -247.540712)
			(xy 84.309202 -247.503875) (xy 84.347323 -247.47275) (xy 84.389944 -247.448143) (xy 84.43596 -247.430691)
			(xy 84.484179 -247.420847) (xy 84.533354 -247.418866) (xy 84.582209 -247.424798) (xy 84.62948 -247.43849)
			(xy 84.673942 -247.459588) (xy 84.714445 -247.487544) (xy 84.749938 -247.521636) (xy 84.779503 -247.56098)
			(xy 84.802374 -247.604557) (xy 84.817958 -247.651238) (xy 84.825853 -247.699815) (xy 84.826348 -247.724422)
			(xy 85.15529 -247.724422) (xy 85.15925 -247.675368) (xy 85.171027 -247.627584) (xy 85.190318 -247.582308)
			(xy 85.216621 -247.540712) (xy 85.249256 -247.503875) (xy 85.287377 -247.47275) (xy 85.329998 -247.448143)
			(xy 85.376014 -247.430691) (xy 85.424233 -247.420847) (xy 85.473408 -247.418866) (xy 85.522263 -247.424798)
			(xy 85.569534 -247.43849) (xy 85.613996 -247.459588) (xy 85.654499 -247.487544) (xy 85.689992 -247.521636)
			(xy 85.719557 -247.56098) (xy 85.742428 -247.604557) (xy 85.758012 -247.651238) (xy 85.765907 -247.699815)
			(xy 85.766402 -247.724422) (xy 86.095344 -247.724422) (xy 86.099304 -247.675368) (xy 86.111081 -247.627584)
			(xy 86.130372 -247.582308) (xy 86.156675 -247.540712) (xy 86.18931 -247.503875) (xy 86.227431 -247.47275)
			(xy 86.270052 -247.448143) (xy 86.316068 -247.430691) (xy 86.364287 -247.420847) (xy 86.413462 -247.418866)
			(xy 86.462317 -247.424798) (xy 86.509588 -247.43849) (xy 86.55405 -247.459588) (xy 86.594553 -247.487544)
			(xy 86.630046 -247.521636) (xy 86.659611 -247.56098) (xy 86.682482 -247.604557) (xy 86.698066 -247.651238)
			(xy 86.705961 -247.699815) (xy 86.706456 -247.724422) (xy 87.035144 -247.724422) (xy 87.039104 -247.675368)
			(xy 87.050881 -247.627584) (xy 87.070172 -247.582308) (xy 87.096475 -247.540712) (xy 87.12911 -247.503875)
			(xy 87.167231 -247.47275) (xy 87.209852 -247.448143) (xy 87.255868 -247.430691) (xy 87.304087 -247.420847)
			(xy 87.353262 -247.418866) (xy 87.402117 -247.424798) (xy 87.449388 -247.43849) (xy 87.49385 -247.459588)
			(xy 87.534353 -247.487544) (xy 87.569846 -247.521636) (xy 87.599411 -247.56098) (xy 87.622282 -247.604557)
			(xy 87.637866 -247.651238) (xy 87.645761 -247.699815) (xy 87.646256 -247.724422) (xy 87.975198 -247.724422)
			(xy 87.979158 -247.675368) (xy 87.990935 -247.627584) (xy 88.010226 -247.582308) (xy 88.036529 -247.540712)
			(xy 88.069164 -247.503875) (xy 88.107285 -247.47275) (xy 88.149906 -247.448143) (xy 88.195922 -247.430691)
			(xy 88.244141 -247.420847) (xy 88.293316 -247.418866) (xy 88.342171 -247.424798) (xy 88.389442 -247.43849)
			(xy 88.433904 -247.459588) (xy 88.474407 -247.487544) (xy 88.5099 -247.521636) (xy 88.539465 -247.56098)
			(xy 88.562336 -247.604557) (xy 88.57792 -247.651238) (xy 88.585815 -247.699815) (xy 88.58631 -247.724422)
			(xy 88.915252 -247.724422) (xy 88.919212 -247.675368) (xy 88.930989 -247.627584) (xy 88.95028 -247.582308)
			(xy 88.976583 -247.540712) (xy 89.009218 -247.503875) (xy 89.047339 -247.47275) (xy 89.08996 -247.448143)
			(xy 89.135976 -247.430691) (xy 89.184195 -247.420847) (xy 89.23337 -247.418866) (xy 89.282225 -247.424798)
			(xy 89.329496 -247.43849) (xy 89.373958 -247.459588) (xy 89.414461 -247.487544) (xy 89.449954 -247.521636)
			(xy 89.479519 -247.56098) (xy 89.50239 -247.604557) (xy 89.517974 -247.651238) (xy 89.525869 -247.699815)
			(xy 89.526364 -247.724422) (xy 89.855306 -247.724422) (xy 89.859266 -247.675368) (xy 89.871043 -247.627584)
			(xy 89.890334 -247.582308) (xy 89.916637 -247.540712) (xy 89.949272 -247.503875) (xy 89.987393 -247.47275)
			(xy 90.030014 -247.448143) (xy 90.07603 -247.430691) (xy 90.124249 -247.420847) (xy 90.173424 -247.418866)
			(xy 90.222279 -247.424798) (xy 90.26955 -247.43849) (xy 90.314012 -247.459588) (xy 90.354515 -247.487544)
			(xy 90.390008 -247.521636) (xy 90.419573 -247.56098) (xy 90.442444 -247.604557) (xy 90.458028 -247.651238)
			(xy 90.465923 -247.699815) (xy 90.466418 -247.724422) (xy 90.784675 -247.724422) (xy 90.78877 -247.673694)
			(xy 90.800949 -247.62428) (xy 90.820897 -247.57746) (xy 90.848098 -247.534446) (xy 90.881846 -247.496352)
			(xy 90.921268 -247.464165) (xy 90.965342 -247.438719) (xy 91.012928 -247.420672) (xy 91.062792 -247.410492)
			(xy 91.113644 -247.408443) (xy 91.164165 -247.414577) (xy 91.213049 -247.428737) (xy 91.259028 -247.450554)
			(xy 91.300912 -247.479464) (xy 91.337616 -247.514719) (xy 91.368189 -247.555405) (xy 91.39184 -247.600468)
			(xy 91.407956 -247.648742) (xy 91.41612 -247.698976) (xy 91.416632 -247.724422) (xy 91.724729 -247.724422)
			(xy 91.728824 -247.673694) (xy 91.741003 -247.62428) (xy 91.760951 -247.57746) (xy 91.788152 -247.534446)
			(xy 91.8219 -247.496352) (xy 91.861322 -247.464165) (xy 91.905396 -247.438719) (xy 91.952982 -247.420672)
			(xy 92.002846 -247.410492) (xy 92.053698 -247.408443) (xy 92.104219 -247.414577) (xy 92.153103 -247.428737)
			(xy 92.199082 -247.450554) (xy 92.240966 -247.479464) (xy 92.27767 -247.514719) (xy 92.308243 -247.555405)
			(xy 92.331894 -247.600468) (xy 92.34801 -247.648742) (xy 92.356174 -247.698976) (xy 92.356686 -247.724422)
			(xy 92.675214 -247.724422) (xy 92.679174 -247.675368) (xy 92.690951 -247.627584) (xy 92.710242 -247.582308)
			(xy 92.736545 -247.540712) (xy 92.76918 -247.503875) (xy 92.807301 -247.47275) (xy 92.849922 -247.448143)
			(xy 92.895938 -247.430691) (xy 92.944157 -247.420847) (xy 92.993332 -247.418866) (xy 93.042187 -247.424798)
			(xy 93.089458 -247.43849) (xy 93.13392 -247.459588) (xy 93.174423 -247.487544) (xy 93.209916 -247.521636)
			(xy 93.239481 -247.56098) (xy 93.262352 -247.604557) (xy 93.277936 -247.651238) (xy 93.285831 -247.699815)
			(xy 93.286326 -247.724422) (xy 93.604837 -247.724422) (xy 93.608932 -247.673694) (xy 93.621111 -247.62428)
			(xy 93.641059 -247.57746) (xy 93.66826 -247.534446) (xy 93.702008 -247.496352) (xy 93.74143 -247.464165)
			(xy 93.785504 -247.438719) (xy 93.83309 -247.420672) (xy 93.882954 -247.410492) (xy 93.933806 -247.408443)
			(xy 93.984327 -247.414577) (xy 94.033211 -247.428737) (xy 94.07919 -247.450554) (xy 94.121074 -247.479464)
			(xy 94.157778 -247.514719) (xy 94.188351 -247.555405) (xy 94.212002 -247.600468) (xy 94.228118 -247.648742)
			(xy 94.236282 -247.698976) (xy 94.236794 -247.724422) (xy 94.555322 -247.724422) (xy 94.559282 -247.675368)
			(xy 94.571059 -247.627584) (xy 94.59035 -247.582308) (xy 94.616653 -247.540712) (xy 94.649288 -247.503875)
			(xy 94.687409 -247.47275) (xy 94.73003 -247.448143) (xy 94.776046 -247.430691) (xy 94.824265 -247.420847)
			(xy 94.87344 -247.418866) (xy 94.922295 -247.424798) (xy 94.969566 -247.43849) (xy 95.014028 -247.459588)
			(xy 95.054531 -247.487544) (xy 95.090024 -247.521636) (xy 95.119589 -247.56098) (xy 95.14246 -247.604557)
			(xy 95.158044 -247.651238) (xy 95.165939 -247.699815) (xy 95.166434 -247.724422) (xy 95.484691 -247.724422)
			(xy 95.488786 -247.673694) (xy 95.500965 -247.62428) (xy 95.520913 -247.57746) (xy 95.548114 -247.534446)
			(xy 95.581862 -247.496352) (xy 95.621284 -247.464165) (xy 95.665358 -247.438719) (xy 95.712944 -247.420672)
			(xy 95.762808 -247.410492) (xy 95.81366 -247.408443) (xy 95.864181 -247.414577) (xy 95.913065 -247.428737)
			(xy 95.959044 -247.450554) (xy 96.000928 -247.479464) (xy 96.037632 -247.514719) (xy 96.068205 -247.555405)
			(xy 96.091856 -247.600468) (xy 96.107972 -247.648742) (xy 96.116136 -247.698976) (xy 96.116648 -247.724422)
			(xy 96.116136 -247.749868) (xy 96.107972 -247.800102) (xy 96.091856 -247.848376) (xy 96.068205 -247.893439)
			(xy 96.037632 -247.934125) (xy 96.000928 -247.96938) (xy 95.959044 -247.99829) (xy 95.913065 -248.020107)
			(xy 95.864181 -248.034267) (xy 95.81366 -248.040401) (xy 95.762808 -248.038352) (xy 95.712944 -248.028172)
			(xy 95.665358 -248.010125) (xy 95.621284 -247.984679) (xy 95.581862 -247.952492) (xy 95.548114 -247.914398)
			(xy 95.520913 -247.871384) (xy 95.500965 -247.824564) (xy 95.488786 -247.77515) (xy 95.484691 -247.724422)
			(xy 95.166434 -247.724422) (xy 95.165939 -247.749029) (xy 95.158044 -247.797606) (xy 95.14246 -247.844287)
			(xy 95.119589 -247.887864) (xy 95.090024 -247.927208) (xy 95.054531 -247.9613) (xy 95.014028 -247.989256)
			(xy 94.969566 -248.010354) (xy 94.922295 -248.024046) (xy 94.87344 -248.029978) (xy 94.824265 -248.027997)
			(xy 94.776046 -248.018153) (xy 94.73003 -248.000701) (xy 94.687409 -247.976094) (xy 94.649288 -247.944969)
			(xy 94.616653 -247.908132) (xy 94.59035 -247.866536) (xy 94.571059 -247.82126) (xy 94.559282 -247.773476)
			(xy 94.555322 -247.724422) (xy 94.236794 -247.724422) (xy 94.236282 -247.749868) (xy 94.228118 -247.800102)
			(xy 94.212002 -247.848376) (xy 94.188351 -247.893439) (xy 94.157778 -247.934125) (xy 94.121074 -247.96938)
			(xy 94.07919 -247.99829) (xy 94.033211 -248.020107) (xy 93.984327 -248.034267) (xy 93.933806 -248.040401)
			(xy 93.882954 -248.038352) (xy 93.83309 -248.028172) (xy 93.785504 -248.010125) (xy 93.74143 -247.984679)
			(xy 93.702008 -247.952492) (xy 93.66826 -247.914398) (xy 93.641059 -247.871384) (xy 93.621111 -247.824564)
			(xy 93.608932 -247.77515) (xy 93.604837 -247.724422) (xy 93.286326 -247.724422) (xy 93.285831 -247.749029)
			(xy 93.277936 -247.797606) (xy 93.262352 -247.844287) (xy 93.239481 -247.887864) (xy 93.209916 -247.927208)
			(xy 93.174423 -247.9613) (xy 93.13392 -247.989256) (xy 93.089458 -248.010354) (xy 93.042187 -248.024046)
			(xy 92.993332 -248.029978) (xy 92.944157 -248.027997) (xy 92.895938 -248.018153) (xy 92.849922 -248.000701)
			(xy 92.807301 -247.976094) (xy 92.76918 -247.944969) (xy 92.736545 -247.908132) (xy 92.710242 -247.866536)
			(xy 92.690951 -247.82126) (xy 92.679174 -247.773476) (xy 92.675214 -247.724422) (xy 92.356686 -247.724422)
			(xy 92.356174 -247.749868) (xy 92.34801 -247.800102) (xy 92.331894 -247.848376) (xy 92.308243 -247.893439)
			(xy 92.27767 -247.934125) (xy 92.240966 -247.96938) (xy 92.199082 -247.99829) (xy 92.153103 -248.020107)
			(xy 92.104219 -248.034267) (xy 92.053698 -248.040401) (xy 92.002846 -248.038352) (xy 91.952982 -248.028172)
			(xy 91.905396 -248.010125) (xy 91.861322 -247.984679) (xy 91.8219 -247.952492) (xy 91.788152 -247.914398)
			(xy 91.760951 -247.871384) (xy 91.741003 -247.824564) (xy 91.728824 -247.77515) (xy 91.724729 -247.724422)
			(xy 91.416632 -247.724422) (xy 91.41612 -247.749868) (xy 91.407956 -247.800102) (xy 91.39184 -247.848376)
			(xy 91.368189 -247.893439) (xy 91.337616 -247.934125) (xy 91.300912 -247.96938) (xy 91.259028 -247.99829)
			(xy 91.213049 -248.020107) (xy 91.164165 -248.034267) (xy 91.113644 -248.040401) (xy 91.062792 -248.038352)
			(xy 91.012928 -248.028172) (xy 90.965342 -248.010125) (xy 90.921268 -247.984679) (xy 90.881846 -247.952492)
			(xy 90.848098 -247.914398) (xy 90.820897 -247.871384) (xy 90.800949 -247.824564) (xy 90.78877 -247.77515)
			(xy 90.784675 -247.724422) (xy 90.466418 -247.724422) (xy 90.465923 -247.749029) (xy 90.458028 -247.797606)
			(xy 90.442444 -247.844287) (xy 90.419573 -247.887864) (xy 90.390008 -247.927208) (xy 90.354515 -247.9613)
			(xy 90.314012 -247.989256) (xy 90.26955 -248.010354) (xy 90.222279 -248.024046) (xy 90.173424 -248.029978)
			(xy 90.124249 -248.027997) (xy 90.07603 -248.018153) (xy 90.030014 -248.000701) (xy 89.987393 -247.976094)
			(xy 89.949272 -247.944969) (xy 89.916637 -247.908132) (xy 89.890334 -247.866536) (xy 89.871043 -247.82126)
			(xy 89.859266 -247.773476) (xy 89.855306 -247.724422) (xy 89.526364 -247.724422) (xy 89.525869 -247.749029)
			(xy 89.517974 -247.797606) (xy 89.50239 -247.844287) (xy 89.479519 -247.887864) (xy 89.449954 -247.927208)
			(xy 89.414461 -247.9613) (xy 89.373958 -247.989256) (xy 89.329496 -248.010354) (xy 89.282225 -248.024046)
			(xy 89.23337 -248.029978) (xy 89.184195 -248.027997) (xy 89.135976 -248.018153) (xy 89.08996 -248.000701)
			(xy 89.047339 -247.976094) (xy 89.009218 -247.944969) (xy 88.976583 -247.908132) (xy 88.95028 -247.866536)
			(xy 88.930989 -247.82126) (xy 88.919212 -247.773476) (xy 88.915252 -247.724422) (xy 88.58631 -247.724422)
			(xy 88.585815 -247.749029) (xy 88.57792 -247.797606) (xy 88.562336 -247.844287) (xy 88.539465 -247.887864)
			(xy 88.5099 -247.927208) (xy 88.474407 -247.9613) (xy 88.433904 -247.989256) (xy 88.389442 -248.010354)
			(xy 88.342171 -248.024046) (xy 88.293316 -248.029978) (xy 88.244141 -248.027997) (xy 88.195922 -248.018153)
			(xy 88.149906 -248.000701) (xy 88.107285 -247.976094) (xy 88.069164 -247.944969) (xy 88.036529 -247.908132)
			(xy 88.010226 -247.866536) (xy 87.990935 -247.82126) (xy 87.979158 -247.773476) (xy 87.975198 -247.724422)
			(xy 87.646256 -247.724422) (xy 87.645761 -247.749029) (xy 87.637866 -247.797606) (xy 87.622282 -247.844287)
			(xy 87.599411 -247.887864) (xy 87.569846 -247.927208) (xy 87.534353 -247.9613) (xy 87.49385 -247.989256)
			(xy 87.449388 -248.010354) (xy 87.402117 -248.024046) (xy 87.353262 -248.029978) (xy 87.304087 -248.027997)
			(xy 87.255868 -248.018153) (xy 87.209852 -248.000701) (xy 87.167231 -247.976094) (xy 87.12911 -247.944969)
			(xy 87.096475 -247.908132) (xy 87.070172 -247.866536) (xy 87.050881 -247.82126) (xy 87.039104 -247.773476)
			(xy 87.035144 -247.724422) (xy 86.706456 -247.724422) (xy 86.705961 -247.749029) (xy 86.698066 -247.797606)
			(xy 86.682482 -247.844287) (xy 86.659611 -247.887864) (xy 86.630046 -247.927208) (xy 86.594553 -247.9613)
			(xy 86.55405 -247.989256) (xy 86.509588 -248.010354) (xy 86.462317 -248.024046) (xy 86.413462 -248.029978)
			(xy 86.364287 -248.027997) (xy 86.316068 -248.018153) (xy 86.270052 -248.000701) (xy 86.227431 -247.976094)
			(xy 86.18931 -247.944969) (xy 86.156675 -247.908132) (xy 86.130372 -247.866536) (xy 86.111081 -247.82126)
			(xy 86.099304 -247.773476) (xy 86.095344 -247.724422) (xy 85.766402 -247.724422) (xy 85.765907 -247.749029)
			(xy 85.758012 -247.797606) (xy 85.742428 -247.844287) (xy 85.719557 -247.887864) (xy 85.689992 -247.927208)
			(xy 85.654499 -247.9613) (xy 85.613996 -247.989256) (xy 85.569534 -248.010354) (xy 85.522263 -248.024046)
			(xy 85.473408 -248.029978) (xy 85.424233 -248.027997) (xy 85.376014 -248.018153) (xy 85.329998 -248.000701)
			(xy 85.287377 -247.976094) (xy 85.249256 -247.944969) (xy 85.216621 -247.908132) (xy 85.190318 -247.866536)
			(xy 85.171027 -247.82126) (xy 85.15925 -247.773476) (xy 85.15529 -247.724422) (xy 84.826348 -247.724422)
			(xy 84.825853 -247.749029) (xy 84.817958 -247.797606) (xy 84.802374 -247.844287) (xy 84.779503 -247.887864)
			(xy 84.749938 -247.927208) (xy 84.714445 -247.9613) (xy 84.673942 -247.989256) (xy 84.62948 -248.010354)
			(xy 84.582209 -248.024046) (xy 84.533354 -248.029978) (xy 84.484179 -248.027997) (xy 84.43596 -248.018153)
			(xy 84.389944 -248.000701) (xy 84.347323 -247.976094) (xy 84.309202 -247.944969) (xy 84.276567 -247.908132)
			(xy 84.250264 -247.866536) (xy 84.230973 -247.82126) (xy 84.219196 -247.773476) (xy 84.215236 -247.724422)
			(xy 83.886294 -247.724422) (xy 83.885822 -247.748412) (xy 83.878313 -247.7958) (xy 83.863483 -247.84143)
			(xy 83.841698 -247.884179) (xy 83.813494 -247.922993) (xy 83.779566 -247.956918) (xy 83.740748 -247.985117)
			(xy 83.697997 -248.006897) (xy 83.652365 -248.021721) (xy 83.604976 -248.029225) (xy 83.580986 -248.02973)
			(xy 83.551268 -248.028206) (xy 83.551014 -248.028206) (xy 83.539076 -248.02719) (xy 83.528408 -248.031254)
			(xy 83.522868 -248.033563) (xy 83.512982 -248.040363) (xy 83.50885 -248.044716) (xy 83.508088 -248.045478)
			(xy 83.502214 -248.052462) (xy 83.495434 -248.06939) (xy 83.49488 -248.078498) (xy 83.49488 -248.534428)
			(xy 83.745336 -248.534428) (xy 83.749296 -248.485374) (xy 83.761073 -248.43759) (xy 83.780364 -248.392314)
			(xy 83.806667 -248.350718) (xy 83.839302 -248.313881) (xy 83.877423 -248.282756) (xy 83.920044 -248.258149)
			(xy 83.96606 -248.240697) (xy 84.014279 -248.230853) (xy 84.063454 -248.228872) (xy 84.112309 -248.234804)
			(xy 84.15958 -248.248496) (xy 84.204042 -248.269594) (xy 84.244545 -248.29755) (xy 84.280038 -248.331642)
			(xy 84.309603 -248.370986) (xy 84.332474 -248.414563) (xy 84.348058 -248.461244) (xy 84.355953 -248.509821)
			(xy 84.356448 -248.534428) (xy 84.685136 -248.534428) (xy 84.689096 -248.485374) (xy 84.700873 -248.43759)
			(xy 84.720164 -248.392314) (xy 84.746467 -248.350718) (xy 84.779102 -248.313881) (xy 84.817223 -248.282756)
			(xy 84.859844 -248.258149) (xy 84.90586 -248.240697) (xy 84.954079 -248.230853) (xy 85.003254 -248.228872)
			(xy 85.052109 -248.234804) (xy 85.09938 -248.248496) (xy 85.143842 -248.269594) (xy 85.184345 -248.29755)
			(xy 85.219838 -248.331642) (xy 85.249403 -248.370986) (xy 85.272274 -248.414563) (xy 85.287858 -248.461244)
			(xy 85.295753 -248.509821) (xy 85.296248 -248.534428) (xy 85.62519 -248.534428) (xy 85.62915 -248.485374)
			(xy 85.640927 -248.43759) (xy 85.660218 -248.392314) (xy 85.686521 -248.350718) (xy 85.719156 -248.313881)
			(xy 85.757277 -248.282756) (xy 85.799898 -248.258149) (xy 85.845914 -248.240697) (xy 85.894133 -248.230853)
			(xy 85.943308 -248.228872) (xy 85.992163 -248.234804) (xy 86.039434 -248.248496) (xy 86.083896 -248.269594)
			(xy 86.124399 -248.29755) (xy 86.159892 -248.331642) (xy 86.189457 -248.370986) (xy 86.212328 -248.414563)
			(xy 86.227912 -248.461244) (xy 86.235807 -248.509821) (xy 86.236302 -248.534428) (xy 86.565244 -248.534428)
			(xy 86.569204 -248.485374) (xy 86.580981 -248.43759) (xy 86.600272 -248.392314) (xy 86.626575 -248.350718)
			(xy 86.65921 -248.313881) (xy 86.697331 -248.282756) (xy 86.739952 -248.258149) (xy 86.785968 -248.240697)
			(xy 86.834187 -248.230853) (xy 86.883362 -248.228872) (xy 86.932217 -248.234804) (xy 86.979488 -248.248496)
			(xy 87.02395 -248.269594) (xy 87.064453 -248.29755) (xy 87.099946 -248.331642) (xy 87.129511 -248.370986)
			(xy 87.152382 -248.414563) (xy 87.167966 -248.461244) (xy 87.175861 -248.509821) (xy 87.176356 -248.534428)
			(xy 87.505298 -248.534428) (xy 87.509258 -248.485374) (xy 87.521035 -248.43759) (xy 87.540326 -248.392314)
			(xy 87.566629 -248.350718) (xy 87.599264 -248.313881) (xy 87.637385 -248.282756) (xy 87.680006 -248.258149)
			(xy 87.726022 -248.240697) (xy 87.774241 -248.230853) (xy 87.823416 -248.228872) (xy 87.872271 -248.234804)
			(xy 87.919542 -248.248496) (xy 87.964004 -248.269594) (xy 88.004507 -248.29755) (xy 88.04 -248.331642)
			(xy 88.069565 -248.370986) (xy 88.092436 -248.414563) (xy 88.10802 -248.461244) (xy 88.115915 -248.509821)
			(xy 88.11641 -248.534428) (xy 88.445352 -248.534428) (xy 88.449312 -248.485374) (xy 88.461089 -248.43759)
			(xy 88.48038 -248.392314) (xy 88.506683 -248.350718) (xy 88.539318 -248.313881) (xy 88.577439 -248.282756)
			(xy 88.62006 -248.258149) (xy 88.666076 -248.240697) (xy 88.714295 -248.230853) (xy 88.76347 -248.228872)
			(xy 88.812325 -248.234804) (xy 88.859596 -248.248496) (xy 88.904058 -248.269594) (xy 88.944561 -248.29755)
			(xy 88.980054 -248.331642) (xy 89.009619 -248.370986) (xy 89.03249 -248.414563) (xy 89.048074 -248.461244)
			(xy 89.055969 -248.509821) (xy 89.056464 -248.534428) (xy 89.385152 -248.534428) (xy 89.389112 -248.485374)
			(xy 89.400889 -248.43759) (xy 89.42018 -248.392314) (xy 89.446483 -248.350718) (xy 89.479118 -248.313881)
			(xy 89.517239 -248.282756) (xy 89.55986 -248.258149) (xy 89.605876 -248.240697) (xy 89.654095 -248.230853)
			(xy 89.70327 -248.228872) (xy 89.752125 -248.234804) (xy 89.799396 -248.248496) (xy 89.843858 -248.269594)
			(xy 89.884361 -248.29755) (xy 89.919854 -248.331642) (xy 89.949419 -248.370986) (xy 89.97229 -248.414563)
			(xy 89.987874 -248.461244) (xy 89.995769 -248.509821) (xy 89.996264 -248.534428) (xy 90.314775 -248.534428)
			(xy 90.31887 -248.4837) (xy 90.331049 -248.434286) (xy 90.350997 -248.387466) (xy 90.378198 -248.344452)
			(xy 90.411946 -248.306358) (xy 90.451368 -248.274171) (xy 90.495442 -248.248725) (xy 90.543028 -248.230678)
			(xy 90.592892 -248.220498) (xy 90.643744 -248.218449) (xy 90.694265 -248.224583) (xy 90.743149 -248.238743)
			(xy 90.789128 -248.26056) (xy 90.831012 -248.28947) (xy 90.867716 -248.324725) (xy 90.898289 -248.365411)
			(xy 90.92194 -248.410474) (xy 90.938056 -248.458748) (xy 90.94622 -248.508982) (xy 90.946732 -248.534428)
			(xy 91.26526 -248.534428) (xy 91.26922 -248.485374) (xy 91.280997 -248.43759) (xy 91.300288 -248.392314)
			(xy 91.326591 -248.350718) (xy 91.359226 -248.313881) (xy 91.397347 -248.282756) (xy 91.439968 -248.258149)
			(xy 91.485984 -248.240697) (xy 91.534203 -248.230853) (xy 91.583378 -248.228872) (xy 91.632233 -248.234804)
			(xy 91.679504 -248.248496) (xy 91.723966 -248.269594) (xy 91.764469 -248.29755) (xy 91.799962 -248.331642)
			(xy 91.829527 -248.370986) (xy 91.852398 -248.414563) (xy 91.867982 -248.461244) (xy 91.875877 -248.509821)
			(xy 91.876372 -248.534428) (xy 92.194883 -248.534428) (xy 92.198978 -248.4837) (xy 92.211157 -248.434286)
			(xy 92.231105 -248.387466) (xy 92.258306 -248.344452) (xy 92.292054 -248.306358) (xy 92.331476 -248.274171)
			(xy 92.37555 -248.248725) (xy 92.423136 -248.230678) (xy 92.473 -248.220498) (xy 92.523852 -248.218449)
			(xy 92.574373 -248.224583) (xy 92.623257 -248.238743) (xy 92.669236 -248.26056) (xy 92.71112 -248.28947)
			(xy 92.747824 -248.324725) (xy 92.778397 -248.365411) (xy 92.802048 -248.410474) (xy 92.818164 -248.458748)
			(xy 92.826328 -248.508982) (xy 92.82684 -248.534428) (xy 93.145114 -248.534428) (xy 93.149074 -248.485374)
			(xy 93.160851 -248.43759) (xy 93.180142 -248.392314) (xy 93.206445 -248.350718) (xy 93.23908 -248.313881)
			(xy 93.277201 -248.282756) (xy 93.319822 -248.258149) (xy 93.365838 -248.240697) (xy 93.414057 -248.230853)
			(xy 93.463232 -248.228872) (xy 93.512087 -248.234804) (xy 93.559358 -248.248496) (xy 93.60382 -248.269594)
			(xy 93.644323 -248.29755) (xy 93.679816 -248.331642) (xy 93.709381 -248.370986) (xy 93.732252 -248.414563)
			(xy 93.747836 -248.461244) (xy 93.755731 -248.509821) (xy 93.756226 -248.534428) (xy 94.074737 -248.534428)
			(xy 94.078832 -248.4837) (xy 94.091011 -248.434286) (xy 94.110959 -248.387466) (xy 94.13816 -248.344452)
			(xy 94.171908 -248.306358) (xy 94.21133 -248.274171) (xy 94.255404 -248.248725) (xy 94.30299 -248.230678)
			(xy 94.352854 -248.220498) (xy 94.403706 -248.218449) (xy 94.454227 -248.224583) (xy 94.503111 -248.238743)
			(xy 94.54909 -248.26056) (xy 94.590974 -248.28947) (xy 94.627678 -248.324725) (xy 94.658251 -248.365411)
			(xy 94.681902 -248.410474) (xy 94.698018 -248.458748) (xy 94.706182 -248.508982) (xy 94.706694 -248.534428)
			(xy 95.014791 -248.534428) (xy 95.018886 -248.4837) (xy 95.031065 -248.434286) (xy 95.051013 -248.387466)
			(xy 95.078214 -248.344452) (xy 95.111962 -248.306358) (xy 95.151384 -248.274171) (xy 95.195458 -248.248725)
			(xy 95.243044 -248.230678) (xy 95.292908 -248.220498) (xy 95.34376 -248.218449) (xy 95.394281 -248.224583)
			(xy 95.443165 -248.238743) (xy 95.489144 -248.26056) (xy 95.531028 -248.28947) (xy 95.567732 -248.324725)
			(xy 95.598305 -248.365411) (xy 95.621956 -248.410474) (xy 95.638072 -248.458748) (xy 95.646236 -248.508982)
			(xy 95.646748 -248.534428) (xy 95.646236 -248.559874) (xy 95.638072 -248.610108) (xy 95.621956 -248.658382)
			(xy 95.598305 -248.703445) (xy 95.567732 -248.744131) (xy 95.531028 -248.779386) (xy 95.489144 -248.808296)
			(xy 95.443165 -248.830113) (xy 95.394281 -248.844273) (xy 95.34376 -248.850407) (xy 95.292908 -248.848358)
			(xy 95.243044 -248.838178) (xy 95.195458 -248.820131) (xy 95.151384 -248.794685) (xy 95.111962 -248.762498)
			(xy 95.078214 -248.724404) (xy 95.051013 -248.68139) (xy 95.031065 -248.63457) (xy 95.018886 -248.585156)
			(xy 95.014791 -248.534428) (xy 94.706694 -248.534428) (xy 94.706182 -248.559874) (xy 94.698018 -248.610108)
			(xy 94.681902 -248.658382) (xy 94.658251 -248.703445) (xy 94.627678 -248.744131) (xy 94.590974 -248.779386)
			(xy 94.54909 -248.808296) (xy 94.503111 -248.830113) (xy 94.454227 -248.844273) (xy 94.403706 -248.850407)
			(xy 94.352854 -248.848358) (xy 94.30299 -248.838178) (xy 94.255404 -248.820131) (xy 94.21133 -248.794685)
			(xy 94.171908 -248.762498) (xy 94.13816 -248.724404) (xy 94.110959 -248.68139) (xy 94.091011 -248.63457)
			(xy 94.078832 -248.585156) (xy 94.074737 -248.534428) (xy 93.756226 -248.534428) (xy 93.755731 -248.559035)
			(xy 93.747836 -248.607612) (xy 93.732252 -248.654293) (xy 93.709381 -248.69787) (xy 93.679816 -248.737214)
			(xy 93.644323 -248.771306) (xy 93.60382 -248.799262) (xy 93.559358 -248.82036) (xy 93.512087 -248.834052)
			(xy 93.463232 -248.839984) (xy 93.414057 -248.838003) (xy 93.365838 -248.828159) (xy 93.319822 -248.810707)
			(xy 93.277201 -248.7861) (xy 93.23908 -248.754975) (xy 93.206445 -248.718138) (xy 93.180142 -248.676542)
			(xy 93.160851 -248.631266) (xy 93.149074 -248.583482) (xy 93.145114 -248.534428) (xy 92.82684 -248.534428)
			(xy 92.826328 -248.559874) (xy 92.818164 -248.610108) (xy 92.802048 -248.658382) (xy 92.778397 -248.703445)
			(xy 92.747824 -248.744131) (xy 92.71112 -248.779386) (xy 92.669236 -248.808296) (xy 92.623257 -248.830113)
			(xy 92.574373 -248.844273) (xy 92.523852 -248.850407) (xy 92.473 -248.848358) (xy 92.423136 -248.838178)
			(xy 92.37555 -248.820131) (xy 92.331476 -248.794685) (xy 92.292054 -248.762498) (xy 92.258306 -248.724404)
			(xy 92.231105 -248.68139) (xy 92.211157 -248.63457) (xy 92.198978 -248.585156) (xy 92.194883 -248.534428)
			(xy 91.876372 -248.534428) (xy 91.875877 -248.559035) (xy 91.867982 -248.607612) (xy 91.852398 -248.654293)
			(xy 91.829527 -248.69787) (xy 91.799962 -248.737214) (xy 91.764469 -248.771306) (xy 91.723966 -248.799262)
			(xy 91.679504 -248.82036) (xy 91.632233 -248.834052) (xy 91.583378 -248.839984) (xy 91.534203 -248.838003)
			(xy 91.485984 -248.828159) (xy 91.439968 -248.810707) (xy 91.397347 -248.7861) (xy 91.359226 -248.754975)
			(xy 91.326591 -248.718138) (xy 91.300288 -248.676542) (xy 91.280997 -248.631266) (xy 91.26922 -248.583482)
			(xy 91.26526 -248.534428) (xy 90.946732 -248.534428) (xy 90.94622 -248.559874) (xy 90.938056 -248.610108)
			(xy 90.92194 -248.658382) (xy 90.898289 -248.703445) (xy 90.867716 -248.744131) (xy 90.831012 -248.779386)
			(xy 90.789128 -248.808296) (xy 90.743149 -248.830113) (xy 90.694265 -248.844273) (xy 90.643744 -248.850407)
			(xy 90.592892 -248.848358) (xy 90.543028 -248.838178) (xy 90.495442 -248.820131) (xy 90.451368 -248.794685)
			(xy 90.411946 -248.762498) (xy 90.378198 -248.724404) (xy 90.350997 -248.68139) (xy 90.331049 -248.63457)
			(xy 90.31887 -248.585156) (xy 90.314775 -248.534428) (xy 89.996264 -248.534428) (xy 89.995769 -248.559035)
			(xy 89.987874 -248.607612) (xy 89.97229 -248.654293) (xy 89.949419 -248.69787) (xy 89.919854 -248.737214)
			(xy 89.884361 -248.771306) (xy 89.843858 -248.799262) (xy 89.799396 -248.82036) (xy 89.752125 -248.834052)
			(xy 89.70327 -248.839984) (xy 89.654095 -248.838003) (xy 89.605876 -248.828159) (xy 89.55986 -248.810707)
			(xy 89.517239 -248.7861) (xy 89.479118 -248.754975) (xy 89.446483 -248.718138) (xy 89.42018 -248.676542)
			(xy 89.400889 -248.631266) (xy 89.389112 -248.583482) (xy 89.385152 -248.534428) (xy 89.056464 -248.534428)
			(xy 89.055969 -248.559035) (xy 89.048074 -248.607612) (xy 89.03249 -248.654293) (xy 89.009619 -248.69787)
			(xy 88.980054 -248.737214) (xy 88.944561 -248.771306) (xy 88.904058 -248.799262) (xy 88.859596 -248.82036)
			(xy 88.812325 -248.834052) (xy 88.76347 -248.839984) (xy 88.714295 -248.838003) (xy 88.666076 -248.828159)
			(xy 88.62006 -248.810707) (xy 88.577439 -248.7861) (xy 88.539318 -248.754975) (xy 88.506683 -248.718138)
			(xy 88.48038 -248.676542) (xy 88.461089 -248.631266) (xy 88.449312 -248.583482) (xy 88.445352 -248.534428)
			(xy 88.11641 -248.534428) (xy 88.115915 -248.559035) (xy 88.10802 -248.607612) (xy 88.092436 -248.654293)
			(xy 88.069565 -248.69787) (xy 88.04 -248.737214) (xy 88.004507 -248.771306) (xy 87.964004 -248.799262)
			(xy 87.919542 -248.82036) (xy 87.872271 -248.834052) (xy 87.823416 -248.839984) (xy 87.774241 -248.838003)
			(xy 87.726022 -248.828159) (xy 87.680006 -248.810707) (xy 87.637385 -248.7861) (xy 87.599264 -248.754975)
			(xy 87.566629 -248.718138) (xy 87.540326 -248.676542) (xy 87.521035 -248.631266) (xy 87.509258 -248.583482)
			(xy 87.505298 -248.534428) (xy 87.176356 -248.534428) (xy 87.175861 -248.559035) (xy 87.167966 -248.607612)
			(xy 87.152382 -248.654293) (xy 87.129511 -248.69787) (xy 87.099946 -248.737214) (xy 87.064453 -248.771306)
			(xy 87.02395 -248.799262) (xy 86.979488 -248.82036) (xy 86.932217 -248.834052) (xy 86.883362 -248.839984)
			(xy 86.834187 -248.838003) (xy 86.785968 -248.828159) (xy 86.739952 -248.810707) (xy 86.697331 -248.7861)
			(xy 86.65921 -248.754975) (xy 86.626575 -248.718138) (xy 86.600272 -248.676542) (xy 86.580981 -248.631266)
			(xy 86.569204 -248.583482) (xy 86.565244 -248.534428) (xy 86.236302 -248.534428) (xy 86.235807 -248.559035)
			(xy 86.227912 -248.607612) (xy 86.212328 -248.654293) (xy 86.189457 -248.69787) (xy 86.159892 -248.737214)
			(xy 86.124399 -248.771306) (xy 86.083896 -248.799262) (xy 86.039434 -248.82036) (xy 85.992163 -248.834052)
			(xy 85.943308 -248.839984) (xy 85.894133 -248.838003) (xy 85.845914 -248.828159) (xy 85.799898 -248.810707)
			(xy 85.757277 -248.7861) (xy 85.719156 -248.754975) (xy 85.686521 -248.718138) (xy 85.660218 -248.676542)
			(xy 85.640927 -248.631266) (xy 85.62915 -248.583482) (xy 85.62519 -248.534428) (xy 85.296248 -248.534428)
			(xy 85.295753 -248.559035) (xy 85.287858 -248.607612) (xy 85.272274 -248.654293) (xy 85.249403 -248.69787)
			(xy 85.219838 -248.737214) (xy 85.184345 -248.771306) (xy 85.143842 -248.799262) (xy 85.09938 -248.82036)
			(xy 85.052109 -248.834052) (xy 85.003254 -248.839984) (xy 84.954079 -248.838003) (xy 84.90586 -248.828159)
			(xy 84.859844 -248.810707) (xy 84.817223 -248.7861) (xy 84.779102 -248.754975) (xy 84.746467 -248.718138)
			(xy 84.720164 -248.676542) (xy 84.700873 -248.631266) (xy 84.689096 -248.583482) (xy 84.685136 -248.534428)
			(xy 84.356448 -248.534428) (xy 84.355953 -248.559035) (xy 84.348058 -248.607612) (xy 84.332474 -248.654293)
			(xy 84.309603 -248.69787) (xy 84.280038 -248.737214) (xy 84.244545 -248.771306) (xy 84.204042 -248.799262)
			(xy 84.15958 -248.82036) (xy 84.112309 -248.834052) (xy 84.063454 -248.839984) (xy 84.014279 -248.838003)
			(xy 83.96606 -248.828159) (xy 83.920044 -248.810707) (xy 83.877423 -248.7861) (xy 83.839302 -248.754975)
			(xy 83.806667 -248.718138) (xy 83.780364 -248.676542) (xy 83.761073 -248.631266) (xy 83.749296 -248.583482)
			(xy 83.745336 -248.534428) (xy 83.49488 -248.534428) (xy 83.49488 -248.891552) (xy 83.494975 -248.896102)
			(xy 83.496645 -248.905048) (xy 83.498182 -248.909332) (xy 83.501738 -248.91873) (xy 83.537298 -248.9581)
			(xy 83.552792 -248.975372) (xy 83.559904 -248.981722) (xy 83.561936 -248.982992) (xy 83.567778 -248.986548)
			(xy 83.576414 -248.990612) (xy 83.585558 -248.991628) (xy 83.585812 -248.991628) (xy 83.60941 -248.994365)
			(xy 83.655413 -249.006206) (xy 83.699029 -249.025027) (xy 83.739204 -249.050375) (xy 83.77497 -249.081638)
			(xy 83.805464 -249.118062) (xy 83.82995 -249.158768) (xy 83.839304 -249.180604) (xy 83.84286 -249.187208)
			(xy 83.843114 -249.187716) (xy 83.856648 -249.211596) (xy 83.875909 -249.262988) (xy 83.885694 -249.316992)
			(xy 83.886294 -249.344434) (xy 84.215236 -249.344434) (xy 84.219196 -249.29538) (xy 84.230973 -249.247596)
			(xy 84.250264 -249.20232) (xy 84.276567 -249.160724) (xy 84.309202 -249.123887) (xy 84.347323 -249.092762)
			(xy 84.389944 -249.068155) (xy 84.43596 -249.050703) (xy 84.484179 -249.040859) (xy 84.533354 -249.038878)
			(xy 84.582209 -249.04481) (xy 84.62948 -249.058502) (xy 84.673942 -249.0796) (xy 84.714445 -249.107556)
			(xy 84.749938 -249.141648) (xy 84.779503 -249.180992) (xy 84.802374 -249.224569) (xy 84.817958 -249.27125)
			(xy 84.825853 -249.319827) (xy 84.826348 -249.344434) (xy 85.15529 -249.344434) (xy 85.15925 -249.29538)
			(xy 85.171027 -249.247596) (xy 85.190318 -249.20232) (xy 85.216621 -249.160724) (xy 85.249256 -249.123887)
			(xy 85.287377 -249.092762) (xy 85.329998 -249.068155) (xy 85.376014 -249.050703) (xy 85.424233 -249.040859)
			(xy 85.473408 -249.038878) (xy 85.522263 -249.04481) (xy 85.569534 -249.058502) (xy 85.613996 -249.0796)
			(xy 85.654499 -249.107556) (xy 85.689992 -249.141648) (xy 85.719557 -249.180992) (xy 85.742428 -249.224569)
			(xy 85.758012 -249.27125) (xy 85.765907 -249.319827) (xy 85.766402 -249.344434) (xy 87.035144 -249.344434)
			(xy 87.039104 -249.29538) (xy 87.050881 -249.247596) (xy 87.070172 -249.20232) (xy 87.096475 -249.160724)
			(xy 87.12911 -249.123887) (xy 87.167231 -249.092762) (xy 87.209852 -249.068155) (xy 87.255868 -249.050703)
			(xy 87.304087 -249.040859) (xy 87.353262 -249.038878) (xy 87.402117 -249.04481) (xy 87.449388 -249.058502)
			(xy 87.49385 -249.0796) (xy 87.534353 -249.107556) (xy 87.569846 -249.141648) (xy 87.599411 -249.180992)
			(xy 87.622282 -249.224569) (xy 87.637866 -249.27125) (xy 87.645761 -249.319827) (xy 87.646256 -249.344434)
			(xy 87.975198 -249.344434) (xy 87.979158 -249.29538) (xy 87.990935 -249.247596) (xy 88.010226 -249.20232)
			(xy 88.036529 -249.160724) (xy 88.069164 -249.123887) (xy 88.107285 -249.092762) (xy 88.149906 -249.068155)
			(xy 88.195922 -249.050703) (xy 88.244141 -249.040859) (xy 88.293316 -249.038878) (xy 88.342171 -249.04481)
			(xy 88.389442 -249.058502) (xy 88.433904 -249.0796) (xy 88.474407 -249.107556) (xy 88.5099 -249.141648)
			(xy 88.539465 -249.180992) (xy 88.562336 -249.224569) (xy 88.57792 -249.27125) (xy 88.585815 -249.319827)
			(xy 88.58631 -249.344434) (xy 88.915252 -249.344434) (xy 88.919212 -249.29538) (xy 88.930989 -249.247596)
			(xy 88.95028 -249.20232) (xy 88.976583 -249.160724) (xy 89.009218 -249.123887) (xy 89.047339 -249.092762)
			(xy 89.08996 -249.068155) (xy 89.135976 -249.050703) (xy 89.184195 -249.040859) (xy 89.23337 -249.038878)
			(xy 89.282225 -249.04481) (xy 89.329496 -249.058502) (xy 89.373958 -249.0796) (xy 89.414461 -249.107556)
			(xy 89.449954 -249.141648) (xy 89.479519 -249.180992) (xy 89.50239 -249.224569) (xy 89.517974 -249.27125)
			(xy 89.525869 -249.319827) (xy 89.526364 -249.344434) (xy 89.855306 -249.344434) (xy 89.859266 -249.29538)
			(xy 89.871043 -249.247596) (xy 89.890334 -249.20232) (xy 89.916637 -249.160724) (xy 89.949272 -249.123887)
			(xy 89.987393 -249.092762) (xy 90.030014 -249.068155) (xy 90.07603 -249.050703) (xy 90.124249 -249.040859)
			(xy 90.173424 -249.038878) (xy 90.222279 -249.04481) (xy 90.26955 -249.058502) (xy 90.314012 -249.0796)
			(xy 90.354515 -249.107556) (xy 90.390008 -249.141648) (xy 90.419573 -249.180992) (xy 90.442444 -249.224569)
			(xy 90.458028 -249.27125) (xy 90.465923 -249.319827) (xy 90.466418 -249.344434) (xy 90.795106 -249.344434)
			(xy 90.799066 -249.29538) (xy 90.810843 -249.247596) (xy 90.830134 -249.20232) (xy 90.856437 -249.160724)
			(xy 90.889072 -249.123887) (xy 90.927193 -249.092762) (xy 90.969814 -249.068155) (xy 91.01583 -249.050703)
			(xy 91.064049 -249.040859) (xy 91.113224 -249.038878) (xy 91.162079 -249.04481) (xy 91.20935 -249.058502)
			(xy 91.253812 -249.0796) (xy 91.294315 -249.107556) (xy 91.329808 -249.141648) (xy 91.359373 -249.180992)
			(xy 91.382244 -249.224569) (xy 91.397828 -249.27125) (xy 91.405723 -249.319827) (xy 91.406218 -249.344434)
			(xy 91.724729 -249.344434) (xy 91.728824 -249.293706) (xy 91.741003 -249.244292) (xy 91.760951 -249.197472)
			(xy 91.788152 -249.154458) (xy 91.8219 -249.116364) (xy 91.861322 -249.084177) (xy 91.905396 -249.058731)
			(xy 91.952982 -249.040684) (xy 92.002846 -249.030504) (xy 92.053698 -249.028455) (xy 92.104219 -249.034589)
			(xy 92.153103 -249.048749) (xy 92.199082 -249.070566) (xy 92.240966 -249.099476) (xy 92.27767 -249.134731)
			(xy 92.308243 -249.175417) (xy 92.331894 -249.22048) (xy 92.34801 -249.268754) (xy 92.356174 -249.318988)
			(xy 92.356686 -249.344434) (xy 93.615268 -249.344434) (xy 93.619228 -249.29538) (xy 93.631005 -249.247596)
			(xy 93.650296 -249.20232) (xy 93.676599 -249.160724) (xy 93.709234 -249.123887) (xy 93.747355 -249.092762)
			(xy 93.789976 -249.068155) (xy 93.835992 -249.050703) (xy 93.884211 -249.040859) (xy 93.933386 -249.038878)
			(xy 93.982241 -249.04481) (xy 94.029512 -249.058502) (xy 94.073974 -249.0796) (xy 94.114477 -249.107556)
			(xy 94.14997 -249.141648) (xy 94.179535 -249.180992) (xy 94.202406 -249.224569) (xy 94.21799 -249.27125)
			(xy 94.225885 -249.319827) (xy 94.22638 -249.344434) (xy 94.555322 -249.344434) (xy 94.559282 -249.29538)
			(xy 94.571059 -249.247596) (xy 94.59035 -249.20232) (xy 94.616653 -249.160724) (xy 94.649288 -249.123887)
			(xy 94.687409 -249.092762) (xy 94.73003 -249.068155) (xy 94.776046 -249.050703) (xy 94.824265 -249.040859)
			(xy 94.87344 -249.038878) (xy 94.922295 -249.04481) (xy 94.969566 -249.058502) (xy 95.014028 -249.0796)
			(xy 95.054531 -249.107556) (xy 95.090024 -249.141648) (xy 95.119589 -249.180992) (xy 95.14246 -249.224569)
			(xy 95.158044 -249.27125) (xy 95.165939 -249.319827) (xy 95.166434 -249.344434) (xy 95.165939 -249.369041)
			(xy 95.158044 -249.417618) (xy 95.14246 -249.464299) (xy 95.119589 -249.507876) (xy 95.090024 -249.54722)
			(xy 95.054531 -249.581312) (xy 95.014028 -249.609268) (xy 94.969566 -249.630366) (xy 94.922295 -249.644058)
			(xy 94.87344 -249.64999) (xy 94.824265 -249.648009) (xy 94.776046 -249.638165) (xy 94.73003 -249.620713)
			(xy 94.687409 -249.596106) (xy 94.649288 -249.564981) (xy 94.616653 -249.528144) (xy 94.59035 -249.486548)
			(xy 94.571059 -249.441272) (xy 94.559282 -249.393488) (xy 94.555322 -249.344434) (xy 94.22638 -249.344434)
			(xy 94.225885 -249.369041) (xy 94.21799 -249.417618) (xy 94.202406 -249.464299) (xy 94.179535 -249.507876)
			(xy 94.14997 -249.54722) (xy 94.114477 -249.581312) (xy 94.073974 -249.609268) (xy 94.029512 -249.630366)
			(xy 93.982241 -249.644058) (xy 93.933386 -249.64999) (xy 93.884211 -249.648009) (xy 93.835992 -249.638165)
			(xy 93.789976 -249.620713) (xy 93.747355 -249.596106) (xy 93.709234 -249.564981) (xy 93.676599 -249.528144)
			(xy 93.650296 -249.486548) (xy 93.631005 -249.441272) (xy 93.619228 -249.393488) (xy 93.615268 -249.344434)
			(xy 92.356686 -249.344434) (xy 92.356174 -249.36988) (xy 92.34801 -249.420114) (xy 92.331894 -249.468388)
			(xy 92.308243 -249.513451) (xy 92.27767 -249.554137) (xy 92.240966 -249.589392) (xy 92.199082 -249.618302)
			(xy 92.153103 -249.640119) (xy 92.104219 -249.654279) (xy 92.053698 -249.660413) (xy 92.002846 -249.658364)
			(xy 91.952982 -249.648184) (xy 91.905396 -249.630137) (xy 91.861322 -249.604691) (xy 91.8219 -249.572504)
			(xy 91.788152 -249.53441) (xy 91.760951 -249.491396) (xy 91.741003 -249.444576) (xy 91.728824 -249.395162)
			(xy 91.724729 -249.344434) (xy 91.406218 -249.344434) (xy 91.405723 -249.369041) (xy 91.397828 -249.417618)
			(xy 91.382244 -249.464299) (xy 91.359373 -249.507876) (xy 91.329808 -249.54722) (xy 91.294315 -249.581312)
			(xy 91.253812 -249.609268) (xy 91.20935 -249.630366) (xy 91.162079 -249.644058) (xy 91.113224 -249.64999)
			(xy 91.064049 -249.648009) (xy 91.01583 -249.638165) (xy 90.969814 -249.620713) (xy 90.927193 -249.596106)
			(xy 90.889072 -249.564981) (xy 90.856437 -249.528144) (xy 90.830134 -249.486548) (xy 90.810843 -249.441272)
			(xy 90.799066 -249.393488) (xy 90.795106 -249.344434) (xy 90.466418 -249.344434) (xy 90.465923 -249.369041)
			(xy 90.458028 -249.417618) (xy 90.442444 -249.464299) (xy 90.419573 -249.507876) (xy 90.390008 -249.54722)
			(xy 90.354515 -249.581312) (xy 90.314012 -249.609268) (xy 90.26955 -249.630366) (xy 90.222279 -249.644058)
			(xy 90.173424 -249.64999) (xy 90.124249 -249.648009) (xy 90.07603 -249.638165) (xy 90.030014 -249.620713)
			(xy 89.987393 -249.596106) (xy 89.949272 -249.564981) (xy 89.916637 -249.528144) (xy 89.890334 -249.486548)
			(xy 89.871043 -249.441272) (xy 89.859266 -249.393488) (xy 89.855306 -249.344434) (xy 89.526364 -249.344434)
			(xy 89.525869 -249.369041) (xy 89.517974 -249.417618) (xy 89.50239 -249.464299) (xy 89.479519 -249.507876)
			(xy 89.449954 -249.54722) (xy 89.414461 -249.581312) (xy 89.373958 -249.609268) (xy 89.329496 -249.630366)
			(xy 89.282225 -249.644058) (xy 89.23337 -249.64999) (xy 89.184195 -249.648009) (xy 89.135976 -249.638165)
			(xy 89.08996 -249.620713) (xy 89.047339 -249.596106) (xy 89.009218 -249.564981) (xy 88.976583 -249.528144)
			(xy 88.95028 -249.486548) (xy 88.930989 -249.441272) (xy 88.919212 -249.393488) (xy 88.915252 -249.344434)
			(xy 88.58631 -249.344434) (xy 88.585815 -249.369041) (xy 88.57792 -249.417618) (xy 88.562336 -249.464299)
			(xy 88.539465 -249.507876) (xy 88.5099 -249.54722) (xy 88.474407 -249.581312) (xy 88.433904 -249.609268)
			(xy 88.389442 -249.630366) (xy 88.342171 -249.644058) (xy 88.293316 -249.64999) (xy 88.244141 -249.648009)
			(xy 88.195922 -249.638165) (xy 88.149906 -249.620713) (xy 88.107285 -249.596106) (xy 88.069164 -249.564981)
			(xy 88.036529 -249.528144) (xy 88.010226 -249.486548) (xy 87.990935 -249.441272) (xy 87.979158 -249.393488)
			(xy 87.975198 -249.344434) (xy 87.646256 -249.344434) (xy 87.645761 -249.369041) (xy 87.637866 -249.417618)
			(xy 87.622282 -249.464299) (xy 87.599411 -249.507876) (xy 87.569846 -249.54722) (xy 87.534353 -249.581312)
			(xy 87.49385 -249.609268) (xy 87.449388 -249.630366) (xy 87.402117 -249.644058) (xy 87.353262 -249.64999)
			(xy 87.304087 -249.648009) (xy 87.255868 -249.638165) (xy 87.209852 -249.620713) (xy 87.167231 -249.596106)
			(xy 87.12911 -249.564981) (xy 87.096475 -249.528144) (xy 87.070172 -249.486548) (xy 87.050881 -249.441272)
			(xy 87.039104 -249.393488) (xy 87.035144 -249.344434) (xy 85.766402 -249.344434) (xy 85.765907 -249.369041)
			(xy 85.758012 -249.417618) (xy 85.742428 -249.464299) (xy 85.719557 -249.507876) (xy 85.689992 -249.54722)
			(xy 85.654499 -249.581312) (xy 85.613996 -249.609268) (xy 85.569534 -249.630366) (xy 85.522263 -249.644058)
			(xy 85.473408 -249.64999) (xy 85.424233 -249.648009) (xy 85.376014 -249.638165) (xy 85.329998 -249.620713)
			(xy 85.287377 -249.596106) (xy 85.249256 -249.564981) (xy 85.216621 -249.528144) (xy 85.190318 -249.486548)
			(xy 85.171027 -249.441272) (xy 85.15925 -249.393488) (xy 85.15529 -249.344434) (xy 84.826348 -249.344434)
			(xy 84.825853 -249.369041) (xy 84.817958 -249.417618) (xy 84.802374 -249.464299) (xy 84.779503 -249.507876)
			(xy 84.749938 -249.54722) (xy 84.714445 -249.581312) (xy 84.673942 -249.609268) (xy 84.62948 -249.630366)
			(xy 84.582209 -249.644058) (xy 84.533354 -249.64999) (xy 84.484179 -249.648009) (xy 84.43596 -249.638165)
			(xy 84.389944 -249.620713) (xy 84.347323 -249.596106) (xy 84.309202 -249.564981) (xy 84.276567 -249.528144)
			(xy 84.250264 -249.486548) (xy 84.230973 -249.441272) (xy 84.219196 -249.393488) (xy 84.215236 -249.344434)
			(xy 83.886294 -249.344434) (xy 83.885821 -249.368423) (xy 83.87831 -249.41581) (xy 83.86348 -249.461438)
			(xy 83.841694 -249.504185) (xy 83.81349 -249.542998) (xy 83.779562 -249.576921) (xy 83.740744 -249.605119)
			(xy 83.697994 -249.626898) (xy 83.652363 -249.641722) (xy 83.604975 -249.649225) (xy 83.580986 -249.649742)
			(xy 83.551268 -249.648218) (xy 83.551014 -249.648218) (xy 83.539076 -249.647202) (xy 83.528408 -249.651266)
			(xy 83.522869 -249.653576) (xy 83.512983 -249.660377) (xy 83.50885 -249.664728) (xy 83.508088 -249.66549)
			(xy 83.502215 -249.672474) (xy 83.49544 -249.689402) (xy 83.49488 -249.69851) (xy 83.49488 -250.15444)
			(xy 83.745336 -250.15444) (xy 83.749296 -250.105386) (xy 83.761073 -250.057602) (xy 83.780364 -250.012326)
			(xy 83.806667 -249.97073) (xy 83.839302 -249.933893) (xy 83.877423 -249.902768) (xy 83.920044 -249.878161)
			(xy 83.96606 -249.860709) (xy 84.014279 -249.850865) (xy 84.063454 -249.848884) (xy 84.112309 -249.854816)
			(xy 84.15958 -249.868508) (xy 84.204042 -249.889606) (xy 84.244545 -249.917562) (xy 84.280038 -249.951654)
			(xy 84.309603 -249.990998) (xy 84.332474 -250.034575) (xy 84.348058 -250.081256) (xy 84.355953 -250.129833)
			(xy 84.356448 -250.15444) (xy 84.685136 -250.15444) (xy 84.689096 -250.105386) (xy 84.700873 -250.057602)
			(xy 84.720164 -250.012326) (xy 84.746467 -249.97073) (xy 84.779102 -249.933893) (xy 84.817223 -249.902768)
			(xy 84.859844 -249.878161) (xy 84.90586 -249.860709) (xy 84.954079 -249.850865) (xy 85.003254 -249.848884)
			(xy 85.052109 -249.854816) (xy 85.09938 -249.868508) (xy 85.143842 -249.889606) (xy 85.184345 -249.917562)
			(xy 85.219838 -249.951654) (xy 85.249403 -249.990998) (xy 85.272274 -250.034575) (xy 85.287858 -250.081256)
			(xy 85.295753 -250.129833) (xy 85.296248 -250.15444) (xy 85.62519 -250.15444) (xy 85.62915 -250.105386)
			(xy 85.640927 -250.057602) (xy 85.660218 -250.012326) (xy 85.686521 -249.97073) (xy 85.719156 -249.933893)
			(xy 85.757277 -249.902768) (xy 85.799898 -249.878161) (xy 85.845914 -249.860709) (xy 85.894133 -249.850865)
			(xy 85.943308 -249.848884) (xy 85.992163 -249.854816) (xy 86.039434 -249.868508) (xy 86.083896 -249.889606)
			(xy 86.124399 -249.917562) (xy 86.159892 -249.951654) (xy 86.189457 -249.990998) (xy 86.212328 -250.034575)
			(xy 86.227912 -250.081256) (xy 86.235807 -250.129833) (xy 86.236302 -250.15444) (xy 86.565244 -250.15444)
			(xy 86.569204 -250.105386) (xy 86.580981 -250.057602) (xy 86.600272 -250.012326) (xy 86.626575 -249.97073)
			(xy 86.65921 -249.933893) (xy 86.697331 -249.902768) (xy 86.739952 -249.878161) (xy 86.785968 -249.860709)
			(xy 86.834187 -249.850865) (xy 86.883362 -249.848884) (xy 86.932217 -249.854816) (xy 86.979488 -249.868508)
			(xy 87.02395 -249.889606) (xy 87.064453 -249.917562) (xy 87.099946 -249.951654) (xy 87.129511 -249.990998)
			(xy 87.152382 -250.034575) (xy 87.167966 -250.081256) (xy 87.175861 -250.129833) (xy 87.176356 -250.15444)
			(xy 87.505298 -250.15444) (xy 87.509258 -250.105386) (xy 87.521035 -250.057602) (xy 87.540326 -250.012326)
			(xy 87.566629 -249.97073) (xy 87.599264 -249.933893) (xy 87.637385 -249.902768) (xy 87.680006 -249.878161)
			(xy 87.726022 -249.860709) (xy 87.774241 -249.850865) (xy 87.823416 -249.848884) (xy 87.872271 -249.854816)
			(xy 87.919542 -249.868508) (xy 87.964004 -249.889606) (xy 88.004507 -249.917562) (xy 88.04 -249.951654)
			(xy 88.069565 -249.990998) (xy 88.092436 -250.034575) (xy 88.10802 -250.081256) (xy 88.115915 -250.129833)
			(xy 88.11641 -250.15444) (xy 88.445352 -250.15444) (xy 88.449312 -250.105386) (xy 88.461089 -250.057602)
			(xy 88.48038 -250.012326) (xy 88.506683 -249.97073) (xy 88.539318 -249.933893) (xy 88.577439 -249.902768)
			(xy 88.62006 -249.878161) (xy 88.666076 -249.860709) (xy 88.714295 -249.850865) (xy 88.76347 -249.848884)
			(xy 88.812325 -249.854816) (xy 88.859596 -249.868508) (xy 88.904058 -249.889606) (xy 88.944561 -249.917562)
			(xy 88.980054 -249.951654) (xy 89.009619 -249.990998) (xy 89.03249 -250.034575) (xy 89.048074 -250.081256)
			(xy 89.055969 -250.129833) (xy 89.056464 -250.15444) (xy 89.385152 -250.15444) (xy 89.389112 -250.105386)
			(xy 89.400889 -250.057602) (xy 89.42018 -250.012326) (xy 89.446483 -249.97073) (xy 89.479118 -249.933893)
			(xy 89.517239 -249.902768) (xy 89.55986 -249.878161) (xy 89.605876 -249.860709) (xy 89.654095 -249.850865)
			(xy 89.70327 -249.848884) (xy 89.752125 -249.854816) (xy 89.799396 -249.868508) (xy 89.843858 -249.889606)
			(xy 89.884361 -249.917562) (xy 89.919854 -249.951654) (xy 89.949419 -249.990998) (xy 89.97229 -250.034575)
			(xy 89.987874 -250.081256) (xy 89.995769 -250.129833) (xy 89.996264 -250.15444) (xy 90.325206 -250.15444)
			(xy 90.329166 -250.105386) (xy 90.340943 -250.057602) (xy 90.360234 -250.012326) (xy 90.386537 -249.97073)
			(xy 90.419172 -249.933893) (xy 90.457293 -249.902768) (xy 90.499914 -249.878161) (xy 90.54593 -249.860709)
			(xy 90.594149 -249.850865) (xy 90.643324 -249.848884) (xy 90.692179 -249.854816) (xy 90.73945 -249.868508)
			(xy 90.783912 -249.889606) (xy 90.824415 -249.917562) (xy 90.859908 -249.951654) (xy 90.889473 -249.990998)
			(xy 90.912344 -250.034575) (xy 90.927928 -250.081256) (xy 90.935823 -250.129833) (xy 90.936318 -250.15444)
			(xy 91.26526 -250.15444) (xy 91.26922 -250.105386) (xy 91.280997 -250.057602) (xy 91.300288 -250.012326)
			(xy 91.326591 -249.97073) (xy 91.359226 -249.933893) (xy 91.397347 -249.902768) (xy 91.439968 -249.878161)
			(xy 91.485984 -249.860709) (xy 91.534203 -249.850865) (xy 91.583378 -249.848884) (xy 91.632233 -249.854816)
			(xy 91.679504 -249.868508) (xy 91.723966 -249.889606) (xy 91.764469 -249.917562) (xy 91.799962 -249.951654)
			(xy 91.829527 -249.990998) (xy 91.852398 -250.034575) (xy 91.867982 -250.081256) (xy 91.875877 -250.129833)
			(xy 91.876372 -250.15444) (xy 92.194883 -250.15444) (xy 92.198978 -250.103712) (xy 92.211157 -250.054298)
			(xy 92.231105 -250.007478) (xy 92.258306 -249.964464) (xy 92.292054 -249.92637) (xy 92.331476 -249.894183)
			(xy 92.37555 -249.868737) (xy 92.423136 -249.85069) (xy 92.473 -249.84051) (xy 92.523852 -249.838461)
			(xy 92.574373 -249.844595) (xy 92.623257 -249.858755) (xy 92.669236 -249.880572) (xy 92.71112 -249.909482)
			(xy 92.747824 -249.944737) (xy 92.778397 -249.985423) (xy 92.802048 -250.030486) (xy 92.818164 -250.07876)
			(xy 92.826328 -250.128994) (xy 92.82684 -250.15444) (xy 93.145114 -250.15444) (xy 93.149074 -250.105386)
			(xy 93.160851 -250.057602) (xy 93.180142 -250.012326) (xy 93.206445 -249.97073) (xy 93.23908 -249.933893)
			(xy 93.277201 -249.902768) (xy 93.319822 -249.878161) (xy 93.365838 -249.860709) (xy 93.414057 -249.850865)
			(xy 93.463232 -249.848884) (xy 93.512087 -249.854816) (xy 93.559358 -249.868508) (xy 93.60382 -249.889606)
			(xy 93.644323 -249.917562) (xy 93.679816 -249.951654) (xy 93.709381 -249.990998) (xy 93.732252 -250.034575)
			(xy 93.747836 -250.081256) (xy 93.755731 -250.129833) (xy 93.756226 -250.15444) (xy 94.085168 -250.15444)
			(xy 94.089128 -250.105386) (xy 94.100905 -250.057602) (xy 94.120196 -250.012326) (xy 94.146499 -249.97073)
			(xy 94.179134 -249.933893) (xy 94.217255 -249.902768) (xy 94.259876 -249.878161) (xy 94.305892 -249.860709)
			(xy 94.354111 -249.850865) (xy 94.403286 -249.848884) (xy 94.452141 -249.854816) (xy 94.499412 -249.868508)
			(xy 94.543874 -249.889606) (xy 94.584377 -249.917562) (xy 94.61987 -249.951654) (xy 94.649435 -249.990998)
			(xy 94.672306 -250.034575) (xy 94.68789 -250.081256) (xy 94.695785 -250.129833) (xy 94.69628 -250.15444)
			(xy 95.014791 -250.15444) (xy 95.018886 -250.103712) (xy 95.031065 -250.054298) (xy 95.051013 -250.007478)
			(xy 95.078214 -249.964464) (xy 95.111962 -249.92637) (xy 95.151384 -249.894183) (xy 95.195458 -249.868737)
			(xy 95.243044 -249.85069) (xy 95.292908 -249.84051) (xy 95.34376 -249.838461) (xy 95.394281 -249.844595)
			(xy 95.443165 -249.858755) (xy 95.489144 -249.880572) (xy 95.531028 -249.909482) (xy 95.567732 -249.944737)
			(xy 95.598305 -249.985423) (xy 95.621956 -250.030486) (xy 95.638072 -250.07876) (xy 95.646236 -250.128994)
			(xy 95.646748 -250.15444) (xy 95.646236 -250.179886) (xy 95.638072 -250.23012) (xy 95.621956 -250.278394)
			(xy 95.598305 -250.323457) (xy 95.567732 -250.364143) (xy 95.531028 -250.399398) (xy 95.489144 -250.428308)
			(xy 95.443165 -250.450125) (xy 95.394281 -250.464285) (xy 95.34376 -250.470419) (xy 95.292908 -250.46837)
			(xy 95.243044 -250.45819) (xy 95.195458 -250.440143) (xy 95.151384 -250.414697) (xy 95.111962 -250.38251)
			(xy 95.078214 -250.344416) (xy 95.051013 -250.301402) (xy 95.031065 -250.254582) (xy 95.018886 -250.205168)
			(xy 95.014791 -250.15444) (xy 94.69628 -250.15444) (xy 94.695785 -250.179047) (xy 94.68789 -250.227624)
			(xy 94.672306 -250.274305) (xy 94.649435 -250.317882) (xy 94.61987 -250.357226) (xy 94.584377 -250.391318)
			(xy 94.543874 -250.419274) (xy 94.499412 -250.440372) (xy 94.452141 -250.454064) (xy 94.403286 -250.459996)
			(xy 94.354111 -250.458015) (xy 94.305892 -250.448171) (xy 94.259876 -250.430719) (xy 94.217255 -250.406112)
			(xy 94.179134 -250.374987) (xy 94.146499 -250.33815) (xy 94.120196 -250.296554) (xy 94.100905 -250.251278)
			(xy 94.089128 -250.203494) (xy 94.085168 -250.15444) (xy 93.756226 -250.15444) (xy 93.755731 -250.179047)
			(xy 93.747836 -250.227624) (xy 93.732252 -250.274305) (xy 93.709381 -250.317882) (xy 93.679816 -250.357226)
			(xy 93.644323 -250.391318) (xy 93.60382 -250.419274) (xy 93.559358 -250.440372) (xy 93.512087 -250.454064)
			(xy 93.463232 -250.459996) (xy 93.414057 -250.458015) (xy 93.365838 -250.448171) (xy 93.319822 -250.430719)
			(xy 93.277201 -250.406112) (xy 93.23908 -250.374987) (xy 93.206445 -250.33815) (xy 93.180142 -250.296554)
			(xy 93.160851 -250.251278) (xy 93.149074 -250.203494) (xy 93.145114 -250.15444) (xy 92.82684 -250.15444)
			(xy 92.826328 -250.179886) (xy 92.818164 -250.23012) (xy 92.802048 -250.278394) (xy 92.778397 -250.323457)
			(xy 92.747824 -250.364143) (xy 92.71112 -250.399398) (xy 92.669236 -250.428308) (xy 92.623257 -250.450125)
			(xy 92.574373 -250.464285) (xy 92.523852 -250.470419) (xy 92.473 -250.46837) (xy 92.423136 -250.45819)
			(xy 92.37555 -250.440143) (xy 92.331476 -250.414697) (xy 92.292054 -250.38251) (xy 92.258306 -250.344416)
			(xy 92.231105 -250.301402) (xy 92.211157 -250.254582) (xy 92.198978 -250.205168) (xy 92.194883 -250.15444)
			(xy 91.876372 -250.15444) (xy 91.875877 -250.179047) (xy 91.867982 -250.227624) (xy 91.852398 -250.274305)
			(xy 91.829527 -250.317882) (xy 91.799962 -250.357226) (xy 91.764469 -250.391318) (xy 91.723966 -250.419274)
			(xy 91.679504 -250.440372) (xy 91.632233 -250.454064) (xy 91.583378 -250.459996) (xy 91.534203 -250.458015)
			(xy 91.485984 -250.448171) (xy 91.439968 -250.430719) (xy 91.397347 -250.406112) (xy 91.359226 -250.374987)
			(xy 91.326591 -250.33815) (xy 91.300288 -250.296554) (xy 91.280997 -250.251278) (xy 91.26922 -250.203494)
			(xy 91.26526 -250.15444) (xy 90.936318 -250.15444) (xy 90.935823 -250.179047) (xy 90.927928 -250.227624)
			(xy 90.912344 -250.274305) (xy 90.889473 -250.317882) (xy 90.859908 -250.357226) (xy 90.824415 -250.391318)
			(xy 90.783912 -250.419274) (xy 90.73945 -250.440372) (xy 90.692179 -250.454064) (xy 90.643324 -250.459996)
			(xy 90.594149 -250.458015) (xy 90.54593 -250.448171) (xy 90.499914 -250.430719) (xy 90.457293 -250.406112)
			(xy 90.419172 -250.374987) (xy 90.386537 -250.33815) (xy 90.360234 -250.296554) (xy 90.340943 -250.251278)
			(xy 90.329166 -250.203494) (xy 90.325206 -250.15444) (xy 89.996264 -250.15444) (xy 89.995769 -250.179047)
			(xy 89.987874 -250.227624) (xy 89.97229 -250.274305) (xy 89.949419 -250.317882) (xy 89.919854 -250.357226)
			(xy 89.884361 -250.391318) (xy 89.843858 -250.419274) (xy 89.799396 -250.440372) (xy 89.752125 -250.454064)
			(xy 89.70327 -250.459996) (xy 89.654095 -250.458015) (xy 89.605876 -250.448171) (xy 89.55986 -250.430719)
			(xy 89.517239 -250.406112) (xy 89.479118 -250.374987) (xy 89.446483 -250.33815) (xy 89.42018 -250.296554)
			(xy 89.400889 -250.251278) (xy 89.389112 -250.203494) (xy 89.385152 -250.15444) (xy 89.056464 -250.15444)
			(xy 89.055969 -250.179047) (xy 89.048074 -250.227624) (xy 89.03249 -250.274305) (xy 89.009619 -250.317882)
			(xy 88.980054 -250.357226) (xy 88.944561 -250.391318) (xy 88.904058 -250.419274) (xy 88.859596 -250.440372)
			(xy 88.812325 -250.454064) (xy 88.76347 -250.459996) (xy 88.714295 -250.458015) (xy 88.666076 -250.448171)
			(xy 88.62006 -250.430719) (xy 88.577439 -250.406112) (xy 88.539318 -250.374987) (xy 88.506683 -250.33815)
			(xy 88.48038 -250.296554) (xy 88.461089 -250.251278) (xy 88.449312 -250.203494) (xy 88.445352 -250.15444)
			(xy 88.11641 -250.15444) (xy 88.115915 -250.179047) (xy 88.10802 -250.227624) (xy 88.092436 -250.274305)
			(xy 88.069565 -250.317882) (xy 88.04 -250.357226) (xy 88.004507 -250.391318) (xy 87.964004 -250.419274)
			(xy 87.919542 -250.440372) (xy 87.872271 -250.454064) (xy 87.823416 -250.459996) (xy 87.774241 -250.458015)
			(xy 87.726022 -250.448171) (xy 87.680006 -250.430719) (xy 87.637385 -250.406112) (xy 87.599264 -250.374987)
			(xy 87.566629 -250.33815) (xy 87.540326 -250.296554) (xy 87.521035 -250.251278) (xy 87.509258 -250.203494)
			(xy 87.505298 -250.15444) (xy 87.176356 -250.15444) (xy 87.175861 -250.179047) (xy 87.167966 -250.227624)
			(xy 87.152382 -250.274305) (xy 87.129511 -250.317882) (xy 87.099946 -250.357226) (xy 87.064453 -250.391318)
			(xy 87.02395 -250.419274) (xy 86.979488 -250.440372) (xy 86.932217 -250.454064) (xy 86.883362 -250.459996)
			(xy 86.834187 -250.458015) (xy 86.785968 -250.448171) (xy 86.739952 -250.430719) (xy 86.697331 -250.406112)
			(xy 86.65921 -250.374987) (xy 86.626575 -250.33815) (xy 86.600272 -250.296554) (xy 86.580981 -250.251278)
			(xy 86.569204 -250.203494) (xy 86.565244 -250.15444) (xy 86.236302 -250.15444) (xy 86.235807 -250.179047)
			(xy 86.227912 -250.227624) (xy 86.212328 -250.274305) (xy 86.189457 -250.317882) (xy 86.159892 -250.357226)
			(xy 86.124399 -250.391318) (xy 86.083896 -250.419274) (xy 86.039434 -250.440372) (xy 85.992163 -250.454064)
			(xy 85.943308 -250.459996) (xy 85.894133 -250.458015) (xy 85.845914 -250.448171) (xy 85.799898 -250.430719)
			(xy 85.757277 -250.406112) (xy 85.719156 -250.374987) (xy 85.686521 -250.33815) (xy 85.660218 -250.296554)
			(xy 85.640927 -250.251278) (xy 85.62915 -250.203494) (xy 85.62519 -250.15444) (xy 85.296248 -250.15444)
			(xy 85.295753 -250.179047) (xy 85.287858 -250.227624) (xy 85.272274 -250.274305) (xy 85.249403 -250.317882)
			(xy 85.219838 -250.357226) (xy 85.184345 -250.391318) (xy 85.143842 -250.419274) (xy 85.09938 -250.440372)
			(xy 85.052109 -250.454064) (xy 85.003254 -250.459996) (xy 84.954079 -250.458015) (xy 84.90586 -250.448171)
			(xy 84.859844 -250.430719) (xy 84.817223 -250.406112) (xy 84.779102 -250.374987) (xy 84.746467 -250.33815)
			(xy 84.720164 -250.296554) (xy 84.700873 -250.251278) (xy 84.689096 -250.203494) (xy 84.685136 -250.15444)
			(xy 84.356448 -250.15444) (xy 84.355953 -250.179047) (xy 84.348058 -250.227624) (xy 84.332474 -250.274305)
			(xy 84.309603 -250.317882) (xy 84.280038 -250.357226) (xy 84.244545 -250.391318) (xy 84.204042 -250.419274)
			(xy 84.15958 -250.440372) (xy 84.112309 -250.454064) (xy 84.063454 -250.459996) (xy 84.014279 -250.458015)
			(xy 83.96606 -250.448171) (xy 83.920044 -250.430719) (xy 83.877423 -250.406112) (xy 83.839302 -250.374987)
			(xy 83.806667 -250.33815) (xy 83.780364 -250.296554) (xy 83.761073 -250.251278) (xy 83.749296 -250.203494)
			(xy 83.745336 -250.15444) (xy 83.49488 -250.15444) (xy 83.49488 -250.511564) (xy 83.494967 -250.516116)
			(xy 83.496622 -250.525067) (xy 83.498182 -250.529344) (xy 83.501738 -250.538742) (xy 83.537298 -250.578112)
			(xy 83.552792 -250.595384) (xy 83.559904 -250.601734) (xy 83.561936 -250.603004) (xy 83.567778 -250.60656)
			(xy 83.576414 -250.610624) (xy 83.585558 -250.61164) (xy 83.585812 -250.61164) (xy 83.609411 -250.614376)
			(xy 83.655419 -250.626215) (xy 83.699039 -250.645033) (xy 83.739221 -250.670378) (xy 83.774994 -250.701637)
			(xy 83.805497 -250.738057) (xy 83.829994 -250.77876) (xy 83.839304 -250.800616) (xy 83.84286 -250.80722)
			(xy 83.843114 -250.807728) (xy 83.856647 -250.831608) (xy 83.875906 -250.883001) (xy 83.885689 -250.937005)
			(xy 83.886294 -250.964446) (xy 84.215236 -250.964446) (xy 84.219196 -250.915392) (xy 84.230973 -250.867608)
			(xy 84.250264 -250.822332) (xy 84.276567 -250.780736) (xy 84.309202 -250.743899) (xy 84.347323 -250.712774)
			(xy 84.389944 -250.688167) (xy 84.43596 -250.670715) (xy 84.484179 -250.660871) (xy 84.533354 -250.65889)
			(xy 84.582209 -250.664822) (xy 84.62948 -250.678514) (xy 84.673942 -250.699612) (xy 84.714445 -250.727568)
			(xy 84.749938 -250.76166) (xy 84.779503 -250.801004) (xy 84.802374 -250.844581) (xy 84.817958 -250.891262)
			(xy 84.825853 -250.939839) (xy 84.826348 -250.964446) (xy 85.15529 -250.964446) (xy 85.15925 -250.915392)
			(xy 85.171027 -250.867608) (xy 85.190318 -250.822332) (xy 85.216621 -250.780736) (xy 85.249256 -250.743899)
			(xy 85.287377 -250.712774) (xy 85.329998 -250.688167) (xy 85.376014 -250.670715) (xy 85.424233 -250.660871)
			(xy 85.473408 -250.65889) (xy 85.522263 -250.664822) (xy 85.569534 -250.678514) (xy 85.613996 -250.699612)
			(xy 85.654499 -250.727568) (xy 85.689992 -250.76166) (xy 85.719557 -250.801004) (xy 85.742428 -250.844581)
			(xy 85.758012 -250.891262) (xy 85.765907 -250.939839) (xy 85.766402 -250.964446) (xy 86.095344 -250.964446)
			(xy 86.099304 -250.915392) (xy 86.111081 -250.867608) (xy 86.130372 -250.822332) (xy 86.156675 -250.780736)
			(xy 86.18931 -250.743899) (xy 86.227431 -250.712774) (xy 86.270052 -250.688167) (xy 86.316068 -250.670715)
			(xy 86.364287 -250.660871) (xy 86.413462 -250.65889) (xy 86.462317 -250.664822) (xy 86.509588 -250.678514)
			(xy 86.55405 -250.699612) (xy 86.594553 -250.727568) (xy 86.630046 -250.76166) (xy 86.659611 -250.801004)
			(xy 86.682482 -250.844581) (xy 86.698066 -250.891262) (xy 86.705961 -250.939839) (xy 86.706456 -250.964446)
			(xy 87.035144 -250.964446) (xy 87.039104 -250.915392) (xy 87.050881 -250.867608) (xy 87.070172 -250.822332)
			(xy 87.096475 -250.780736) (xy 87.12911 -250.743899) (xy 87.167231 -250.712774) (xy 87.209852 -250.688167)
			(xy 87.255868 -250.670715) (xy 87.304087 -250.660871) (xy 87.353262 -250.65889) (xy 87.402117 -250.664822)
			(xy 87.449388 -250.678514) (xy 87.49385 -250.699612) (xy 87.534353 -250.727568) (xy 87.569846 -250.76166)
			(xy 87.599411 -250.801004) (xy 87.622282 -250.844581) (xy 87.637866 -250.891262) (xy 87.645761 -250.939839)
			(xy 87.646256 -250.964446) (xy 87.975198 -250.964446) (xy 87.979158 -250.915392) (xy 87.990935 -250.867608)
			(xy 88.010226 -250.822332) (xy 88.036529 -250.780736) (xy 88.069164 -250.743899) (xy 88.107285 -250.712774)
			(xy 88.149906 -250.688167) (xy 88.195922 -250.670715) (xy 88.244141 -250.660871) (xy 88.293316 -250.65889)
			(xy 88.342171 -250.664822) (xy 88.389442 -250.678514) (xy 88.433904 -250.699612) (xy 88.474407 -250.727568)
			(xy 88.5099 -250.76166) (xy 88.539465 -250.801004) (xy 88.562336 -250.844581) (xy 88.57792 -250.891262)
			(xy 88.585815 -250.939839) (xy 88.58631 -250.964446) (xy 88.915252 -250.964446) (xy 88.919212 -250.915392)
			(xy 88.930989 -250.867608) (xy 88.95028 -250.822332) (xy 88.976583 -250.780736) (xy 89.009218 -250.743899)
			(xy 89.047339 -250.712774) (xy 89.08996 -250.688167) (xy 89.135976 -250.670715) (xy 89.184195 -250.660871)
			(xy 89.23337 -250.65889) (xy 89.282225 -250.664822) (xy 89.329496 -250.678514) (xy 89.373958 -250.699612)
			(xy 89.414461 -250.727568) (xy 89.449954 -250.76166) (xy 89.479519 -250.801004) (xy 89.50239 -250.844581)
			(xy 89.517974 -250.891262) (xy 89.525869 -250.939839) (xy 89.526364 -250.964446) (xy 89.855306 -250.964446)
			(xy 89.859266 -250.915392) (xy 89.871043 -250.867608) (xy 89.890334 -250.822332) (xy 89.916637 -250.780736)
			(xy 89.949272 -250.743899) (xy 89.987393 -250.712774) (xy 90.030014 -250.688167) (xy 90.07603 -250.670715)
			(xy 90.124249 -250.660871) (xy 90.173424 -250.65889) (xy 90.222279 -250.664822) (xy 90.26955 -250.678514)
			(xy 90.314012 -250.699612) (xy 90.354515 -250.727568) (xy 90.390008 -250.76166) (xy 90.419573 -250.801004)
			(xy 90.442444 -250.844581) (xy 90.458028 -250.891262) (xy 90.465923 -250.939839) (xy 90.466418 -250.964446)
			(xy 90.79536 -250.964446) (xy 90.79932 -250.915392) (xy 90.811097 -250.867608) (xy 90.830388 -250.822332)
			(xy 90.856691 -250.780736) (xy 90.889326 -250.743899) (xy 90.927447 -250.712774) (xy 90.970068 -250.688167)
			(xy 91.016084 -250.670715) (xy 91.064303 -250.660871) (xy 91.113478 -250.65889) (xy 91.162333 -250.664822)
			(xy 91.209604 -250.678514) (xy 91.254066 -250.699612) (xy 91.294569 -250.727568) (xy 91.330062 -250.76166)
			(xy 91.359627 -250.801004) (xy 91.382498 -250.844581) (xy 91.398082 -250.891262) (xy 91.405977 -250.939839)
			(xy 91.406472 -250.964446) (xy 91.724729 -250.964446) (xy 91.728824 -250.913718) (xy 91.741003 -250.864304)
			(xy 91.760951 -250.817484) (xy 91.788152 -250.77447) (xy 91.8219 -250.736376) (xy 91.861322 -250.704189)
			(xy 91.905396 -250.678743) (xy 91.952982 -250.660696) (xy 92.002846 -250.650516) (xy 92.053698 -250.648467)
			(xy 92.104219 -250.654601) (xy 92.153103 -250.668761) (xy 92.199082 -250.690578) (xy 92.240966 -250.719488)
			(xy 92.27767 -250.754743) (xy 92.308243 -250.795429) (xy 92.331894 -250.840492) (xy 92.34801 -250.888766)
			(xy 92.356174 -250.939) (xy 92.356686 -250.964446) (xy 92.675214 -250.964446) (xy 92.679174 -250.915392)
			(xy 92.690951 -250.867608) (xy 92.710242 -250.822332) (xy 92.736545 -250.780736) (xy 92.76918 -250.743899)
			(xy 92.807301 -250.712774) (xy 92.849922 -250.688167) (xy 92.895938 -250.670715) (xy 92.944157 -250.660871)
			(xy 92.993332 -250.65889) (xy 93.042187 -250.664822) (xy 93.089458 -250.678514) (xy 93.13392 -250.699612)
			(xy 93.174423 -250.727568) (xy 93.209916 -250.76166) (xy 93.239481 -250.801004) (xy 93.262352 -250.844581)
			(xy 93.277936 -250.891262) (xy 93.285831 -250.939839) (xy 93.286326 -250.964446) (xy 93.615268 -250.964446)
			(xy 93.619228 -250.915392) (xy 93.631005 -250.867608) (xy 93.650296 -250.822332) (xy 93.676599 -250.780736)
			(xy 93.709234 -250.743899) (xy 93.747355 -250.712774) (xy 93.789976 -250.688167) (xy 93.835992 -250.670715)
			(xy 93.884211 -250.660871) (xy 93.933386 -250.65889) (xy 93.982241 -250.664822) (xy 94.029512 -250.678514)
			(xy 94.073974 -250.699612) (xy 94.114477 -250.727568) (xy 94.14997 -250.76166) (xy 94.179535 -250.801004)
			(xy 94.202406 -250.844581) (xy 94.21799 -250.891262) (xy 94.225885 -250.939839) (xy 94.22638 -250.964446)
			(xy 94.555322 -250.964446) (xy 94.559282 -250.915392) (xy 94.571059 -250.867608) (xy 94.59035 -250.822332)
			(xy 94.616653 -250.780736) (xy 94.649288 -250.743899) (xy 94.687409 -250.712774) (xy 94.73003 -250.688167)
			(xy 94.776046 -250.670715) (xy 94.824265 -250.660871) (xy 94.87344 -250.65889) (xy 94.922295 -250.664822)
			(xy 94.969566 -250.678514) (xy 95.014028 -250.699612) (xy 95.054531 -250.727568) (xy 95.090024 -250.76166)
			(xy 95.119589 -250.801004) (xy 95.14246 -250.844581) (xy 95.158044 -250.891262) (xy 95.165939 -250.939839)
			(xy 95.166434 -250.964446) (xy 95.165939 -250.989053) (xy 95.158044 -251.03763) (xy 95.14246 -251.084311)
			(xy 95.119589 -251.127888) (xy 95.090024 -251.167232) (xy 95.054531 -251.201324) (xy 95.014028 -251.22928)
			(xy 94.969566 -251.250378) (xy 94.922295 -251.26407) (xy 94.87344 -251.270002) (xy 94.824265 -251.268021)
			(xy 94.776046 -251.258177) (xy 94.73003 -251.240725) (xy 94.687409 -251.216118) (xy 94.649288 -251.184993)
			(xy 94.616653 -251.148156) (xy 94.59035 -251.10656) (xy 94.571059 -251.061284) (xy 94.559282 -251.0135)
			(xy 94.555322 -250.964446) (xy 94.22638 -250.964446) (xy 94.225885 -250.989053) (xy 94.21799 -251.03763)
			(xy 94.202406 -251.084311) (xy 94.179535 -251.127888) (xy 94.14997 -251.167232) (xy 94.114477 -251.201324)
			(xy 94.073974 -251.22928) (xy 94.029512 -251.250378) (xy 93.982241 -251.26407) (xy 93.933386 -251.270002)
			(xy 93.884211 -251.268021) (xy 93.835992 -251.258177) (xy 93.789976 -251.240725) (xy 93.747355 -251.216118)
			(xy 93.709234 -251.184993) (xy 93.676599 -251.148156) (xy 93.650296 -251.10656) (xy 93.631005 -251.061284)
			(xy 93.619228 -251.0135) (xy 93.615268 -250.964446) (xy 93.286326 -250.964446) (xy 93.285831 -250.989053)
			(xy 93.277936 -251.03763) (xy 93.262352 -251.084311) (xy 93.239481 -251.127888) (xy 93.209916 -251.167232)
			(xy 93.174423 -251.201324) (xy 93.13392 -251.22928) (xy 93.089458 -251.250378) (xy 93.042187 -251.26407)
			(xy 92.993332 -251.270002) (xy 92.944157 -251.268021) (xy 92.895938 -251.258177) (xy 92.849922 -251.240725)
			(xy 92.807301 -251.216118) (xy 92.76918 -251.184993) (xy 92.736545 -251.148156) (xy 92.710242 -251.10656)
			(xy 92.690951 -251.061284) (xy 92.679174 -251.0135) (xy 92.675214 -250.964446) (xy 92.356686 -250.964446)
			(xy 92.356174 -250.989892) (xy 92.34801 -251.040126) (xy 92.331894 -251.0884) (xy 92.308243 -251.133463)
			(xy 92.27767 -251.174149) (xy 92.240966 -251.209404) (xy 92.199082 -251.238314) (xy 92.153103 -251.260131)
			(xy 92.104219 -251.274291) (xy 92.053698 -251.280425) (xy 92.002846 -251.278376) (xy 91.952982 -251.268196)
			(xy 91.905396 -251.250149) (xy 91.861322 -251.224703) (xy 91.8219 -251.192516) (xy 91.788152 -251.154422)
			(xy 91.760951 -251.111408) (xy 91.741003 -251.064588) (xy 91.728824 -251.015174) (xy 91.724729 -250.964446)
			(xy 91.406472 -250.964446) (xy 91.405977 -250.989053) (xy 91.398082 -251.03763) (xy 91.382498 -251.084311)
			(xy 91.359627 -251.127888) (xy 91.330062 -251.167232) (xy 91.294569 -251.201324) (xy 91.254066 -251.22928)
			(xy 91.209604 -251.250378) (xy 91.162333 -251.26407) (xy 91.113478 -251.270002) (xy 91.064303 -251.268021)
			(xy 91.016084 -251.258177) (xy 90.970068 -251.240725) (xy 90.927447 -251.216118) (xy 90.889326 -251.184993)
			(xy 90.856691 -251.148156) (xy 90.830388 -251.10656) (xy 90.811097 -251.061284) (xy 90.79932 -251.0135)
			(xy 90.79536 -250.964446) (xy 90.466418 -250.964446) (xy 90.465923 -250.989053) (xy 90.458028 -251.03763)
			(xy 90.442444 -251.084311) (xy 90.419573 -251.127888) (xy 90.390008 -251.167232) (xy 90.354515 -251.201324)
			(xy 90.314012 -251.22928) (xy 90.26955 -251.250378) (xy 90.222279 -251.26407) (xy 90.173424 -251.270002)
			(xy 90.124249 -251.268021) (xy 90.07603 -251.258177) (xy 90.030014 -251.240725) (xy 89.987393 -251.216118)
			(xy 89.949272 -251.184993) (xy 89.916637 -251.148156) (xy 89.890334 -251.10656) (xy 89.871043 -251.061284)
			(xy 89.859266 -251.0135) (xy 89.855306 -250.964446) (xy 89.526364 -250.964446) (xy 89.525869 -250.989053)
			(xy 89.517974 -251.03763) (xy 89.50239 -251.084311) (xy 89.479519 -251.127888) (xy 89.449954 -251.167232)
			(xy 89.414461 -251.201324) (xy 89.373958 -251.22928) (xy 89.329496 -251.250378) (xy 89.282225 -251.26407)
			(xy 89.23337 -251.270002) (xy 89.184195 -251.268021) (xy 89.135976 -251.258177) (xy 89.08996 -251.240725)
			(xy 89.047339 -251.216118) (xy 89.009218 -251.184993) (xy 88.976583 -251.148156) (xy 88.95028 -251.10656)
			(xy 88.930989 -251.061284) (xy 88.919212 -251.0135) (xy 88.915252 -250.964446) (xy 88.58631 -250.964446)
			(xy 88.585815 -250.989053) (xy 88.57792 -251.03763) (xy 88.562336 -251.084311) (xy 88.539465 -251.127888)
			(xy 88.5099 -251.167232) (xy 88.474407 -251.201324) (xy 88.433904 -251.22928) (xy 88.389442 -251.250378)
			(xy 88.342171 -251.26407) (xy 88.293316 -251.270002) (xy 88.244141 -251.268021) (xy 88.195922 -251.258177)
			(xy 88.149906 -251.240725) (xy 88.107285 -251.216118) (xy 88.069164 -251.184993) (xy 88.036529 -251.148156)
			(xy 88.010226 -251.10656) (xy 87.990935 -251.061284) (xy 87.979158 -251.0135) (xy 87.975198 -250.964446)
			(xy 87.646256 -250.964446) (xy 87.645761 -250.989053) (xy 87.637866 -251.03763) (xy 87.622282 -251.084311)
			(xy 87.599411 -251.127888) (xy 87.569846 -251.167232) (xy 87.534353 -251.201324) (xy 87.49385 -251.22928)
			(xy 87.449388 -251.250378) (xy 87.402117 -251.26407) (xy 87.353262 -251.270002) (xy 87.304087 -251.268021)
			(xy 87.255868 -251.258177) (xy 87.209852 -251.240725) (xy 87.167231 -251.216118) (xy 87.12911 -251.184993)
			(xy 87.096475 -251.148156) (xy 87.070172 -251.10656) (xy 87.050881 -251.061284) (xy 87.039104 -251.0135)
			(xy 87.035144 -250.964446) (xy 86.706456 -250.964446) (xy 86.705961 -250.989053) (xy 86.698066 -251.03763)
			(xy 86.682482 -251.084311) (xy 86.659611 -251.127888) (xy 86.630046 -251.167232) (xy 86.594553 -251.201324)
			(xy 86.55405 -251.22928) (xy 86.509588 -251.250378) (xy 86.462317 -251.26407) (xy 86.413462 -251.270002)
			(xy 86.364287 -251.268021) (xy 86.316068 -251.258177) (xy 86.270052 -251.240725) (xy 86.227431 -251.216118)
			(xy 86.18931 -251.184993) (xy 86.156675 -251.148156) (xy 86.130372 -251.10656) (xy 86.111081 -251.061284)
			(xy 86.099304 -251.0135) (xy 86.095344 -250.964446) (xy 85.766402 -250.964446) (xy 85.765907 -250.989053)
			(xy 85.758012 -251.03763) (xy 85.742428 -251.084311) (xy 85.719557 -251.127888) (xy 85.689992 -251.167232)
			(xy 85.654499 -251.201324) (xy 85.613996 -251.22928) (xy 85.569534 -251.250378) (xy 85.522263 -251.26407)
			(xy 85.473408 -251.270002) (xy 85.424233 -251.268021) (xy 85.376014 -251.258177) (xy 85.329998 -251.240725)
			(xy 85.287377 -251.216118) (xy 85.249256 -251.184993) (xy 85.216621 -251.148156) (xy 85.190318 -251.10656)
			(xy 85.171027 -251.061284) (xy 85.15925 -251.0135) (xy 85.15529 -250.964446) (xy 84.826348 -250.964446)
			(xy 84.825853 -250.989053) (xy 84.817958 -251.03763) (xy 84.802374 -251.084311) (xy 84.779503 -251.127888)
			(xy 84.749938 -251.167232) (xy 84.714445 -251.201324) (xy 84.673942 -251.22928) (xy 84.62948 -251.250378)
			(xy 84.582209 -251.26407) (xy 84.533354 -251.270002) (xy 84.484179 -251.268021) (xy 84.43596 -251.258177)
			(xy 84.389944 -251.240725) (xy 84.347323 -251.216118) (xy 84.309202 -251.184993) (xy 84.276567 -251.148156)
			(xy 84.250264 -251.10656) (xy 84.230973 -251.061284) (xy 84.219196 -251.0135) (xy 84.215236 -250.964446)
			(xy 83.886294 -250.964446) (xy 83.88582 -250.988434) (xy 83.878308 -251.03582) (xy 83.863476 -251.081447)
			(xy 83.84169 -251.124192) (xy 83.813486 -251.163003) (xy 83.779558 -251.196925) (xy 83.740741 -251.225122)
			(xy 83.697991 -251.246899) (xy 83.652361 -251.261722) (xy 83.604975 -251.269225) (xy 83.580986 -251.269754)
			(xy 83.551268 -251.26823) (xy 83.551014 -251.26823) (xy 83.539076 -251.267214) (xy 83.528408 -251.271278)
			(xy 83.522869 -251.273588) (xy 83.512985 -251.28039) (xy 83.50885 -251.28474) (xy 83.508088 -251.285502)
			(xy 83.502217 -251.292487) (xy 83.495445 -251.309415) (xy 83.49488 -251.318522) (xy 83.49488 -251.774452)
			(xy 83.745336 -251.774452) (xy 83.749296 -251.725398) (xy 83.761073 -251.677614) (xy 83.780364 -251.632338)
			(xy 83.806667 -251.590742) (xy 83.839302 -251.553905) (xy 83.877423 -251.52278) (xy 83.920044 -251.498173)
			(xy 83.96606 -251.480721) (xy 84.014279 -251.470877) (xy 84.063454 -251.468896) (xy 84.112309 -251.474828)
			(xy 84.15958 -251.48852) (xy 84.204042 -251.509618) (xy 84.244545 -251.537574) (xy 84.280038 -251.571666)
			(xy 84.309603 -251.61101) (xy 84.332474 -251.654587) (xy 84.348058 -251.701268) (xy 84.355953 -251.749845)
			(xy 84.356448 -251.774452) (xy 84.685136 -251.774452) (xy 84.689096 -251.725398) (xy 84.700873 -251.677614)
			(xy 84.720164 -251.632338) (xy 84.746467 -251.590742) (xy 84.779102 -251.553905) (xy 84.817223 -251.52278)
			(xy 84.859844 -251.498173) (xy 84.90586 -251.480721) (xy 84.954079 -251.470877) (xy 85.003254 -251.468896)
			(xy 85.052109 -251.474828) (xy 85.09938 -251.48852) (xy 85.143842 -251.509618) (xy 85.184345 -251.537574)
			(xy 85.219838 -251.571666) (xy 85.249403 -251.61101) (xy 85.272274 -251.654587) (xy 85.287858 -251.701268)
			(xy 85.295753 -251.749845) (xy 85.296248 -251.774452) (xy 85.62519 -251.774452) (xy 85.62915 -251.725398)
			(xy 85.640927 -251.677614) (xy 85.660218 -251.632338) (xy 85.686521 -251.590742) (xy 85.719156 -251.553905)
			(xy 85.757277 -251.52278) (xy 85.799898 -251.498173) (xy 85.845914 -251.480721) (xy 85.894133 -251.470877)
			(xy 85.943308 -251.468896) (xy 85.992163 -251.474828) (xy 86.039434 -251.48852) (xy 86.083896 -251.509618)
			(xy 86.124399 -251.537574) (xy 86.159892 -251.571666) (xy 86.189457 -251.61101) (xy 86.212328 -251.654587)
			(xy 86.227912 -251.701268) (xy 86.235807 -251.749845) (xy 86.236302 -251.774452) (xy 87.505298 -251.774452)
			(xy 87.509258 -251.725398) (xy 87.521035 -251.677614) (xy 87.540326 -251.632338) (xy 87.566629 -251.590742)
			(xy 87.599264 -251.553905) (xy 87.637385 -251.52278) (xy 87.680006 -251.498173) (xy 87.726022 -251.480721)
			(xy 87.774241 -251.470877) (xy 87.823416 -251.468896) (xy 87.872271 -251.474828) (xy 87.919542 -251.48852)
			(xy 87.964004 -251.509618) (xy 88.004507 -251.537574) (xy 88.04 -251.571666) (xy 88.069565 -251.61101)
			(xy 88.092436 -251.654587) (xy 88.10802 -251.701268) (xy 88.115915 -251.749845) (xy 88.11641 -251.774452)
			(xy 88.445352 -251.774452) (xy 88.449312 -251.725398) (xy 88.461089 -251.677614) (xy 88.48038 -251.632338)
			(xy 88.506683 -251.590742) (xy 88.539318 -251.553905) (xy 88.577439 -251.52278) (xy 88.62006 -251.498173)
			(xy 88.666076 -251.480721) (xy 88.714295 -251.470877) (xy 88.76347 -251.468896) (xy 88.812325 -251.474828)
			(xy 88.859596 -251.48852) (xy 88.904058 -251.509618) (xy 88.944561 -251.537574) (xy 88.980054 -251.571666)
			(xy 89.009619 -251.61101) (xy 89.03249 -251.654587) (xy 89.048074 -251.701268) (xy 89.055969 -251.749845)
			(xy 89.056464 -251.774452) (xy 89.385152 -251.774452) (xy 89.389112 -251.725398) (xy 89.400889 -251.677614)
			(xy 89.42018 -251.632338) (xy 89.446483 -251.590742) (xy 89.479118 -251.553905) (xy 89.517239 -251.52278)
			(xy 89.55986 -251.498173) (xy 89.605876 -251.480721) (xy 89.654095 -251.470877) (xy 89.70327 -251.468896)
			(xy 89.752125 -251.474828) (xy 89.799396 -251.48852) (xy 89.843858 -251.509618) (xy 89.884361 -251.537574)
			(xy 89.919854 -251.571666) (xy 89.949419 -251.61101) (xy 89.97229 -251.654587) (xy 89.987874 -251.701268)
			(xy 89.995769 -251.749845) (xy 89.996264 -251.774452) (xy 90.314775 -251.774452) (xy 90.31887 -251.723724)
			(xy 90.331049 -251.67431) (xy 90.350997 -251.62749) (xy 90.378198 -251.584476) (xy 90.411946 -251.546382)
			(xy 90.451368 -251.514195) (xy 90.495442 -251.488749) (xy 90.543028 -251.470702) (xy 90.592892 -251.460522)
			(xy 90.643744 -251.458473) (xy 90.694265 -251.464607) (xy 90.743149 -251.478767) (xy 90.789128 -251.500584)
			(xy 90.831012 -251.529494) (xy 90.867716 -251.564749) (xy 90.898289 -251.605435) (xy 90.92194 -251.650498)
			(xy 90.938056 -251.698772) (xy 90.94622 -251.749006) (xy 90.946732 -251.774452) (xy 91.26526 -251.774452)
			(xy 91.26922 -251.725398) (xy 91.280997 -251.677614) (xy 91.300288 -251.632338) (xy 91.326591 -251.590742)
			(xy 91.359226 -251.553905) (xy 91.397347 -251.52278) (xy 91.439968 -251.498173) (xy 91.485984 -251.480721)
			(xy 91.534203 -251.470877) (xy 91.583378 -251.468896) (xy 91.632233 -251.474828) (xy 91.679504 -251.48852)
			(xy 91.723966 -251.509618) (xy 91.764469 -251.537574) (xy 91.799962 -251.571666) (xy 91.829527 -251.61101)
			(xy 91.852398 -251.654587) (xy 91.867982 -251.701268) (xy 91.875877 -251.749845) (xy 91.876372 -251.774452)
			(xy 92.205314 -251.774452) (xy 92.209274 -251.725398) (xy 92.221051 -251.677614) (xy 92.240342 -251.632338)
			(xy 92.266645 -251.590742) (xy 92.29928 -251.553905) (xy 92.337401 -251.52278) (xy 92.380022 -251.498173)
			(xy 92.426038 -251.480721) (xy 92.474257 -251.470877) (xy 92.523432 -251.468896) (xy 92.572287 -251.474828)
			(xy 92.619558 -251.48852) (xy 92.66402 -251.509618) (xy 92.704523 -251.537574) (xy 92.740016 -251.571666)
			(xy 92.769581 -251.61101) (xy 92.792452 -251.654587) (xy 92.808036 -251.701268) (xy 92.815931 -251.749845)
			(xy 92.816426 -251.774452) (xy 94.074737 -251.774452) (xy 94.078832 -251.723724) (xy 94.091011 -251.67431)
			(xy 94.110959 -251.62749) (xy 94.13816 -251.584476) (xy 94.171908 -251.546382) (xy 94.21133 -251.514195)
			(xy 94.255404 -251.488749) (xy 94.30299 -251.470702) (xy 94.352854 -251.460522) (xy 94.403706 -251.458473)
			(xy 94.454227 -251.464607) (xy 94.503111 -251.478767) (xy 94.54909 -251.500584) (xy 94.590974 -251.529494)
			(xy 94.627678 -251.564749) (xy 94.658251 -251.605435) (xy 94.681902 -251.650498) (xy 94.698018 -251.698772)
			(xy 94.706182 -251.749006) (xy 94.706694 -251.774452) (xy 95.025222 -251.774452) (xy 95.029182 -251.725398)
			(xy 95.040959 -251.677614) (xy 95.06025 -251.632338) (xy 95.086553 -251.590742) (xy 95.119188 -251.553905)
			(xy 95.157309 -251.52278) (xy 95.19993 -251.498173) (xy 95.245946 -251.480721) (xy 95.294165 -251.470877)
			(xy 95.34334 -251.468896) (xy 95.392195 -251.474828) (xy 95.439466 -251.48852) (xy 95.483928 -251.509618)
			(xy 95.524431 -251.537574) (xy 95.559924 -251.571666) (xy 95.589489 -251.61101) (xy 95.61236 -251.654587)
			(xy 95.627944 -251.701268) (xy 95.635839 -251.749845) (xy 95.636334 -251.774452) (xy 95.635839 -251.799059)
			(xy 95.627944 -251.847636) (xy 95.61236 -251.894317) (xy 95.589489 -251.937894) (xy 95.559924 -251.977238)
			(xy 95.524431 -252.01133) (xy 95.483928 -252.039286) (xy 95.439466 -252.060384) (xy 95.392195 -252.074076)
			(xy 95.34334 -252.080008) (xy 95.294165 -252.078027) (xy 95.245946 -252.068183) (xy 95.19993 -252.050731)
			(xy 95.157309 -252.026124) (xy 95.119188 -251.994999) (xy 95.086553 -251.958162) (xy 95.06025 -251.916566)
			(xy 95.040959 -251.87129) (xy 95.029182 -251.823506) (xy 95.025222 -251.774452) (xy 94.706694 -251.774452)
			(xy 94.706182 -251.799898) (xy 94.698018 -251.850132) (xy 94.681902 -251.898406) (xy 94.658251 -251.943469)
			(xy 94.627678 -251.984155) (xy 94.590974 -252.01941) (xy 94.54909 -252.04832) (xy 94.503111 -252.070137)
			(xy 94.454227 -252.084297) (xy 94.403706 -252.090431) (xy 94.352854 -252.088382) (xy 94.30299 -252.078202)
			(xy 94.255404 -252.060155) (xy 94.21133 -252.034709) (xy 94.171908 -252.002522) (xy 94.13816 -251.964428)
			(xy 94.110959 -251.921414) (xy 94.091011 -251.874594) (xy 94.078832 -251.82518) (xy 94.074737 -251.774452)
			(xy 92.816426 -251.774452) (xy 92.815931 -251.799059) (xy 92.808036 -251.847636) (xy 92.792452 -251.894317)
			(xy 92.769581 -251.937894) (xy 92.740016 -251.977238) (xy 92.704523 -252.01133) (xy 92.66402 -252.039286)
			(xy 92.619558 -252.060384) (xy 92.572287 -252.074076) (xy 92.523432 -252.080008) (xy 92.474257 -252.078027)
			(xy 92.426038 -252.068183) (xy 92.380022 -252.050731) (xy 92.337401 -252.026124) (xy 92.29928 -251.994999)
			(xy 92.266645 -251.958162) (xy 92.240342 -251.916566) (xy 92.221051 -251.87129) (xy 92.209274 -251.823506)
			(xy 92.205314 -251.774452) (xy 91.876372 -251.774452) (xy 91.875877 -251.799059) (xy 91.867982 -251.847636)
			(xy 91.852398 -251.894317) (xy 91.829527 -251.937894) (xy 91.799962 -251.977238) (xy 91.764469 -252.01133)
			(xy 91.723966 -252.039286) (xy 91.679504 -252.060384) (xy 91.632233 -252.074076) (xy 91.583378 -252.080008)
			(xy 91.534203 -252.078027) (xy 91.485984 -252.068183) (xy 91.439968 -252.050731) (xy 91.397347 -252.026124)
			(xy 91.359226 -251.994999) (xy 91.326591 -251.958162) (xy 91.300288 -251.916566) (xy 91.280997 -251.87129)
			(xy 91.26922 -251.823506) (xy 91.26526 -251.774452) (xy 90.946732 -251.774452) (xy 90.94622 -251.799898)
			(xy 90.938056 -251.850132) (xy 90.92194 -251.898406) (xy 90.898289 -251.943469) (xy 90.867716 -251.984155)
			(xy 90.831012 -252.01941) (xy 90.789128 -252.04832) (xy 90.743149 -252.070137) (xy 90.694265 -252.084297)
			(xy 90.643744 -252.090431) (xy 90.592892 -252.088382) (xy 90.543028 -252.078202) (xy 90.495442 -252.060155)
			(xy 90.451368 -252.034709) (xy 90.411946 -252.002522) (xy 90.378198 -251.964428) (xy 90.350997 -251.921414)
			(xy 90.331049 -251.874594) (xy 90.31887 -251.82518) (xy 90.314775 -251.774452) (xy 89.996264 -251.774452)
			(xy 89.995769 -251.799059) (xy 89.987874 -251.847636) (xy 89.97229 -251.894317) (xy 89.949419 -251.937894)
			(xy 89.919854 -251.977238) (xy 89.884361 -252.01133) (xy 89.843858 -252.039286) (xy 89.799396 -252.060384)
			(xy 89.752125 -252.074076) (xy 89.70327 -252.080008) (xy 89.654095 -252.078027) (xy 89.605876 -252.068183)
			(xy 89.55986 -252.050731) (xy 89.517239 -252.026124) (xy 89.479118 -251.994999) (xy 89.446483 -251.958162)
			(xy 89.42018 -251.916566) (xy 89.400889 -251.87129) (xy 89.389112 -251.823506) (xy 89.385152 -251.774452)
			(xy 89.056464 -251.774452) (xy 89.055969 -251.799059) (xy 89.048074 -251.847636) (xy 89.03249 -251.894317)
			(xy 89.009619 -251.937894) (xy 88.980054 -251.977238) (xy 88.944561 -252.01133) (xy 88.904058 -252.039286)
			(xy 88.859596 -252.060384) (xy 88.812325 -252.074076) (xy 88.76347 -252.080008) (xy 88.714295 -252.078027)
			(xy 88.666076 -252.068183) (xy 88.62006 -252.050731) (xy 88.577439 -252.026124) (xy 88.539318 -251.994999)
			(xy 88.506683 -251.958162) (xy 88.48038 -251.916566) (xy 88.461089 -251.87129) (xy 88.449312 -251.823506)
			(xy 88.445352 -251.774452) (xy 88.11641 -251.774452) (xy 88.115915 -251.799059) (xy 88.10802 -251.847636)
			(xy 88.092436 -251.894317) (xy 88.069565 -251.937894) (xy 88.04 -251.977238) (xy 88.004507 -252.01133)
			(xy 87.964004 -252.039286) (xy 87.919542 -252.060384) (xy 87.872271 -252.074076) (xy 87.823416 -252.080008)
			(xy 87.774241 -252.078027) (xy 87.726022 -252.068183) (xy 87.680006 -252.050731) (xy 87.637385 -252.026124)
			(xy 87.599264 -251.994999) (xy 87.566629 -251.958162) (xy 87.540326 -251.916566) (xy 87.521035 -251.87129)
			(xy 87.509258 -251.823506) (xy 87.505298 -251.774452) (xy 86.236302 -251.774452) (xy 86.235807 -251.799059)
			(xy 86.227912 -251.847636) (xy 86.212328 -251.894317) (xy 86.189457 -251.937894) (xy 86.159892 -251.977238)
			(xy 86.124399 -252.01133) (xy 86.083896 -252.039286) (xy 86.039434 -252.060384) (xy 85.992163 -252.074076)
			(xy 85.943308 -252.080008) (xy 85.894133 -252.078027) (xy 85.845914 -252.068183) (xy 85.799898 -252.050731)
			(xy 85.757277 -252.026124) (xy 85.719156 -251.994999) (xy 85.686521 -251.958162) (xy 85.660218 -251.916566)
			(xy 85.640927 -251.87129) (xy 85.62915 -251.823506) (xy 85.62519 -251.774452) (xy 85.296248 -251.774452)
			(xy 85.295753 -251.799059) (xy 85.287858 -251.847636) (xy 85.272274 -251.894317) (xy 85.249403 -251.937894)
			(xy 85.219838 -251.977238) (xy 85.184345 -252.01133) (xy 85.143842 -252.039286) (xy 85.09938 -252.060384)
			(xy 85.052109 -252.074076) (xy 85.003254 -252.080008) (xy 84.954079 -252.078027) (xy 84.90586 -252.068183)
			(xy 84.859844 -252.050731) (xy 84.817223 -252.026124) (xy 84.779102 -251.994999) (xy 84.746467 -251.958162)
			(xy 84.720164 -251.916566) (xy 84.700873 -251.87129) (xy 84.689096 -251.823506) (xy 84.685136 -251.774452)
			(xy 84.356448 -251.774452) (xy 84.355953 -251.799059) (xy 84.348058 -251.847636) (xy 84.332474 -251.894317)
			(xy 84.309603 -251.937894) (xy 84.280038 -251.977238) (xy 84.244545 -252.01133) (xy 84.204042 -252.039286)
			(xy 84.15958 -252.060384) (xy 84.112309 -252.074076) (xy 84.063454 -252.080008) (xy 84.014279 -252.078027)
			(xy 83.96606 -252.068183) (xy 83.920044 -252.050731) (xy 83.877423 -252.026124) (xy 83.839302 -251.994999)
			(xy 83.806667 -251.958162) (xy 83.780364 -251.916566) (xy 83.761073 -251.87129) (xy 83.749296 -251.823506)
			(xy 83.745336 -251.774452) (xy 83.49488 -251.774452) (xy 83.49488 -252.131576) (xy 83.494968 -252.136128)
			(xy 83.496625 -252.145078) (xy 83.498182 -252.149356) (xy 83.501738 -252.158754) (xy 83.537298 -252.198124)
			(xy 83.552792 -252.215396) (xy 83.559904 -252.221746) (xy 83.561936 -252.223016) (xy 83.567778 -252.226572)
			(xy 83.576414 -252.230636) (xy 83.585558 -252.231652) (xy 83.585812 -252.231652) (xy 83.609411 -252.234388)
			(xy 83.655418 -252.246227) (xy 83.699038 -252.265046) (xy 83.739218 -252.290391) (xy 83.774991 -252.32165)
			(xy 83.805492 -252.358071) (xy 83.829988 -252.398774) (xy 83.839304 -252.420628) (xy 83.84286 -252.427232)
			(xy 83.843114 -252.42774) (xy 83.856646 -252.451621) (xy 83.875903 -252.503013) (xy 83.885684 -252.557017)
			(xy 83.886294 -252.584458) (xy 84.215236 -252.584458) (xy 84.219196 -252.535404) (xy 84.230973 -252.48762)
			(xy 84.250264 -252.442344) (xy 84.276567 -252.400748) (xy 84.309202 -252.363911) (xy 84.347323 -252.332786)
			(xy 84.389944 -252.308179) (xy 84.43596 -252.290727) (xy 84.484179 -252.280883) (xy 84.533354 -252.278902)
			(xy 84.582209 -252.284834) (xy 84.62948 -252.298526) (xy 84.673942 -252.319624) (xy 84.714445 -252.34758)
			(xy 84.749938 -252.381672) (xy 84.779503 -252.421016) (xy 84.802374 -252.464593) (xy 84.817958 -252.511274)
			(xy 84.825853 -252.559851) (xy 84.826348 -252.584458) (xy 85.15529 -252.584458) (xy 85.15925 -252.535404)
			(xy 85.171027 -252.48762) (xy 85.190318 -252.442344) (xy 85.216621 -252.400748) (xy 85.249256 -252.363911)
			(xy 85.287377 -252.332786) (xy 85.329998 -252.308179) (xy 85.376014 -252.290727) (xy 85.424233 -252.280883)
			(xy 85.473408 -252.278902) (xy 85.522263 -252.284834) (xy 85.569534 -252.298526) (xy 85.613996 -252.319624)
			(xy 85.654499 -252.34758) (xy 85.689992 -252.381672) (xy 85.719557 -252.421016) (xy 85.742428 -252.464593)
			(xy 85.758012 -252.511274) (xy 85.765907 -252.559851) (xy 85.766402 -252.584458) (xy 86.095344 -252.584458)
			(xy 86.099304 -252.535404) (xy 86.111081 -252.48762) (xy 86.130372 -252.442344) (xy 86.156675 -252.400748)
			(xy 86.18931 -252.363911) (xy 86.227431 -252.332786) (xy 86.270052 -252.308179) (xy 86.316068 -252.290727)
			(xy 86.364287 -252.280883) (xy 86.413462 -252.278902) (xy 86.462317 -252.284834) (xy 86.509588 -252.298526)
			(xy 86.55405 -252.319624) (xy 86.594553 -252.34758) (xy 86.630046 -252.381672) (xy 86.659611 -252.421016)
			(xy 86.682482 -252.464593) (xy 86.698066 -252.511274) (xy 86.705961 -252.559851) (xy 86.706456 -252.584458)
			(xy 87.035144 -252.584458) (xy 87.039104 -252.535404) (xy 87.050881 -252.48762) (xy 87.070172 -252.442344)
			(xy 87.096475 -252.400748) (xy 87.12911 -252.363911) (xy 87.167231 -252.332786) (xy 87.209852 -252.308179)
			(xy 87.255868 -252.290727) (xy 87.304087 -252.280883) (xy 87.353262 -252.278902) (xy 87.402117 -252.284834)
			(xy 87.449388 -252.298526) (xy 87.49385 -252.319624) (xy 87.534353 -252.34758) (xy 87.569846 -252.381672)
			(xy 87.599411 -252.421016) (xy 87.622282 -252.464593) (xy 87.637866 -252.511274) (xy 87.645761 -252.559851)
			(xy 87.646256 -252.584458) (xy 87.975198 -252.584458) (xy 87.979158 -252.535404) (xy 87.990935 -252.48762)
			(xy 88.010226 -252.442344) (xy 88.036529 -252.400748) (xy 88.069164 -252.363911) (xy 88.107285 -252.332786)
			(xy 88.149906 -252.308179) (xy 88.195922 -252.290727) (xy 88.244141 -252.280883) (xy 88.293316 -252.278902)
			(xy 88.342171 -252.284834) (xy 88.389442 -252.298526) (xy 88.433904 -252.319624) (xy 88.474407 -252.34758)
			(xy 88.5099 -252.381672) (xy 88.539465 -252.421016) (xy 88.562336 -252.464593) (xy 88.57792 -252.511274)
			(xy 88.585815 -252.559851) (xy 88.58631 -252.584458) (xy 88.915252 -252.584458) (xy 88.919212 -252.535404)
			(xy 88.930989 -252.48762) (xy 88.95028 -252.442344) (xy 88.976583 -252.400748) (xy 89.009218 -252.363911)
			(xy 89.047339 -252.332786) (xy 89.08996 -252.308179) (xy 89.135976 -252.290727) (xy 89.184195 -252.280883)
			(xy 89.23337 -252.278902) (xy 89.282225 -252.284834) (xy 89.329496 -252.298526) (xy 89.373958 -252.319624)
			(xy 89.414461 -252.34758) (xy 89.449954 -252.381672) (xy 89.479519 -252.421016) (xy 89.50239 -252.464593)
			(xy 89.517974 -252.511274) (xy 89.525869 -252.559851) (xy 89.526364 -252.584458) (xy 89.855306 -252.584458)
			(xy 89.859266 -252.535404) (xy 89.871043 -252.48762) (xy 89.890334 -252.442344) (xy 89.916637 -252.400748)
			(xy 89.949272 -252.363911) (xy 89.987393 -252.332786) (xy 90.030014 -252.308179) (xy 90.07603 -252.290727)
			(xy 90.124249 -252.280883) (xy 90.173424 -252.278902) (xy 90.222279 -252.284834) (xy 90.26955 -252.298526)
			(xy 90.314012 -252.319624) (xy 90.354515 -252.34758) (xy 90.390008 -252.381672) (xy 90.419573 -252.421016)
			(xy 90.442444 -252.464593) (xy 90.458028 -252.511274) (xy 90.465923 -252.559851) (xy 90.466418 -252.584458)
			(xy 90.784675 -252.584458) (xy 90.78877 -252.53373) (xy 90.800949 -252.484316) (xy 90.820897 -252.437496)
			(xy 90.848098 -252.394482) (xy 90.881846 -252.356388) (xy 90.921268 -252.324201) (xy 90.965342 -252.298755)
			(xy 91.012928 -252.280708) (xy 91.062792 -252.270528) (xy 91.113644 -252.268479) (xy 91.164165 -252.274613)
			(xy 91.213049 -252.288773) (xy 91.259028 -252.31059) (xy 91.300912 -252.3395) (xy 91.337616 -252.374755)
			(xy 91.368189 -252.415441) (xy 91.39184 -252.460504) (xy 91.407956 -252.508778) (xy 91.41612 -252.559012)
			(xy 91.416632 -252.584458) (xy 91.724729 -252.584458) (xy 91.728824 -252.53373) (xy 91.741003 -252.484316)
			(xy 91.760951 -252.437496) (xy 91.788152 -252.394482) (xy 91.8219 -252.356388) (xy 91.861322 -252.324201)
			(xy 91.905396 -252.298755) (xy 91.952982 -252.280708) (xy 92.002846 -252.270528) (xy 92.053698 -252.268479)
			(xy 92.104219 -252.274613) (xy 92.153103 -252.288773) (xy 92.199082 -252.31059) (xy 92.240966 -252.3395)
			(xy 92.27767 -252.374755) (xy 92.308243 -252.415441) (xy 92.331894 -252.460504) (xy 92.34801 -252.508778)
			(xy 92.356174 -252.559012) (xy 92.356686 -252.584458) (xy 92.675214 -252.584458) (xy 92.679174 -252.535404)
			(xy 92.690951 -252.48762) (xy 92.710242 -252.442344) (xy 92.736545 -252.400748) (xy 92.76918 -252.363911)
			(xy 92.807301 -252.332786) (xy 92.849922 -252.308179) (xy 92.895938 -252.290727) (xy 92.944157 -252.280883)
			(xy 92.993332 -252.278902) (xy 93.042187 -252.284834) (xy 93.089458 -252.298526) (xy 93.13392 -252.319624)
			(xy 93.174423 -252.34758) (xy 93.209916 -252.381672) (xy 93.239481 -252.421016) (xy 93.262352 -252.464593)
			(xy 93.277936 -252.511274) (xy 93.285831 -252.559851) (xy 93.286326 -252.584458) (xy 93.604837 -252.584458)
			(xy 93.608932 -252.53373) (xy 93.621111 -252.484316) (xy 93.641059 -252.437496) (xy 93.66826 -252.394482)
			(xy 93.702008 -252.356388) (xy 93.74143 -252.324201) (xy 93.785504 -252.298755) (xy 93.83309 -252.280708)
			(xy 93.882954 -252.270528) (xy 93.933806 -252.268479) (xy 93.984327 -252.274613) (xy 94.033211 -252.288773)
			(xy 94.07919 -252.31059) (xy 94.121074 -252.3395) (xy 94.157778 -252.374755) (xy 94.188351 -252.415441)
			(xy 94.212002 -252.460504) (xy 94.228118 -252.508778) (xy 94.236282 -252.559012) (xy 94.236794 -252.584458)
			(xy 94.555322 -252.584458) (xy 94.559282 -252.535404) (xy 94.571059 -252.48762) (xy 94.59035 -252.442344)
			(xy 94.616653 -252.400748) (xy 94.649288 -252.363911) (xy 94.687409 -252.332786) (xy 94.73003 -252.308179)
			(xy 94.776046 -252.290727) (xy 94.824265 -252.280883) (xy 94.87344 -252.278902) (xy 94.922295 -252.284834)
			(xy 94.969566 -252.298526) (xy 95.014028 -252.319624) (xy 95.054531 -252.34758) (xy 95.090024 -252.381672)
			(xy 95.119589 -252.421016) (xy 95.14246 -252.464593) (xy 95.158044 -252.511274) (xy 95.165939 -252.559851)
			(xy 95.166434 -252.584458) (xy 95.165939 -252.609065) (xy 95.158044 -252.657642) (xy 95.14246 -252.704323)
			(xy 95.119589 -252.7479) (xy 95.090024 -252.787244) (xy 95.054531 -252.821336) (xy 95.014028 -252.849292)
			(xy 94.969566 -252.87039) (xy 94.922295 -252.884082) (xy 94.87344 -252.890014) (xy 94.824265 -252.888033)
			(xy 94.776046 -252.878189) (xy 94.73003 -252.860737) (xy 94.687409 -252.83613) (xy 94.649288 -252.805005)
			(xy 94.616653 -252.768168) (xy 94.59035 -252.726572) (xy 94.571059 -252.681296) (xy 94.559282 -252.633512)
			(xy 94.555322 -252.584458) (xy 94.236794 -252.584458) (xy 94.236282 -252.609904) (xy 94.228118 -252.660138)
			(xy 94.212002 -252.708412) (xy 94.188351 -252.753475) (xy 94.157778 -252.794161) (xy 94.121074 -252.829416)
			(xy 94.07919 -252.858326) (xy 94.033211 -252.880143) (xy 93.984327 -252.894303) (xy 93.933806 -252.900437)
			(xy 93.882954 -252.898388) (xy 93.83309 -252.888208) (xy 93.785504 -252.870161) (xy 93.74143 -252.844715)
			(xy 93.702008 -252.812528) (xy 93.66826 -252.774434) (xy 93.641059 -252.73142) (xy 93.621111 -252.6846)
			(xy 93.608932 -252.635186) (xy 93.604837 -252.584458) (xy 93.286326 -252.584458) (xy 93.285831 -252.609065)
			(xy 93.277936 -252.657642) (xy 93.262352 -252.704323) (xy 93.239481 -252.7479) (xy 93.209916 -252.787244)
			(xy 93.174423 -252.821336) (xy 93.13392 -252.849292) (xy 93.089458 -252.87039) (xy 93.042187 -252.884082)
			(xy 92.993332 -252.890014) (xy 92.944157 -252.888033) (xy 92.895938 -252.878189) (xy 92.849922 -252.860737)
			(xy 92.807301 -252.83613) (xy 92.76918 -252.805005) (xy 92.736545 -252.768168) (xy 92.710242 -252.726572)
			(xy 92.690951 -252.681296) (xy 92.679174 -252.633512) (xy 92.675214 -252.584458) (xy 92.356686 -252.584458)
			(xy 92.356174 -252.609904) (xy 92.34801 -252.660138) (xy 92.331894 -252.708412) (xy 92.308243 -252.753475)
			(xy 92.27767 -252.794161) (xy 92.240966 -252.829416) (xy 92.199082 -252.858326) (xy 92.153103 -252.880143)
			(xy 92.104219 -252.894303) (xy 92.053698 -252.900437) (xy 92.002846 -252.898388) (xy 91.952982 -252.888208)
			(xy 91.905396 -252.870161) (xy 91.861322 -252.844715) (xy 91.8219 -252.812528) (xy 91.788152 -252.774434)
			(xy 91.760951 -252.73142) (xy 91.741003 -252.6846) (xy 91.728824 -252.635186) (xy 91.724729 -252.584458)
			(xy 91.416632 -252.584458) (xy 91.41612 -252.609904) (xy 91.407956 -252.660138) (xy 91.39184 -252.708412)
			(xy 91.368189 -252.753475) (xy 91.337616 -252.794161) (xy 91.300912 -252.829416) (xy 91.259028 -252.858326)
			(xy 91.213049 -252.880143) (xy 91.164165 -252.894303) (xy 91.113644 -252.900437) (xy 91.062792 -252.898388)
			(xy 91.012928 -252.888208) (xy 90.965342 -252.870161) (xy 90.921268 -252.844715) (xy 90.881846 -252.812528)
			(xy 90.848098 -252.774434) (xy 90.820897 -252.73142) (xy 90.800949 -252.6846) (xy 90.78877 -252.635186)
			(xy 90.784675 -252.584458) (xy 90.466418 -252.584458) (xy 90.465923 -252.609065) (xy 90.458028 -252.657642)
			(xy 90.442444 -252.704323) (xy 90.419573 -252.7479) (xy 90.390008 -252.787244) (xy 90.354515 -252.821336)
			(xy 90.314012 -252.849292) (xy 90.26955 -252.87039) (xy 90.222279 -252.884082) (xy 90.173424 -252.890014)
			(xy 90.124249 -252.888033) (xy 90.07603 -252.878189) (xy 90.030014 -252.860737) (xy 89.987393 -252.83613)
			(xy 89.949272 -252.805005) (xy 89.916637 -252.768168) (xy 89.890334 -252.726572) (xy 89.871043 -252.681296)
			(xy 89.859266 -252.633512) (xy 89.855306 -252.584458) (xy 89.526364 -252.584458) (xy 89.525869 -252.609065)
			(xy 89.517974 -252.657642) (xy 89.50239 -252.704323) (xy 89.479519 -252.7479) (xy 89.449954 -252.787244)
			(xy 89.414461 -252.821336) (xy 89.373958 -252.849292) (xy 89.329496 -252.87039) (xy 89.282225 -252.884082)
			(xy 89.23337 -252.890014) (xy 89.184195 -252.888033) (xy 89.135976 -252.878189) (xy 89.08996 -252.860737)
			(xy 89.047339 -252.83613) (xy 89.009218 -252.805005) (xy 88.976583 -252.768168) (xy 88.95028 -252.726572)
			(xy 88.930989 -252.681296) (xy 88.919212 -252.633512) (xy 88.915252 -252.584458) (xy 88.58631 -252.584458)
			(xy 88.585815 -252.609065) (xy 88.57792 -252.657642) (xy 88.562336 -252.704323) (xy 88.539465 -252.7479)
			(xy 88.5099 -252.787244) (xy 88.474407 -252.821336) (xy 88.433904 -252.849292) (xy 88.389442 -252.87039)
			(xy 88.342171 -252.884082) (xy 88.293316 -252.890014) (xy 88.244141 -252.888033) (xy 88.195922 -252.878189)
			(xy 88.149906 -252.860737) (xy 88.107285 -252.83613) (xy 88.069164 -252.805005) (xy 88.036529 -252.768168)
			(xy 88.010226 -252.726572) (xy 87.990935 -252.681296) (xy 87.979158 -252.633512) (xy 87.975198 -252.584458)
			(xy 87.646256 -252.584458) (xy 87.645761 -252.609065) (xy 87.637866 -252.657642) (xy 87.622282 -252.704323)
			(xy 87.599411 -252.7479) (xy 87.569846 -252.787244) (xy 87.534353 -252.821336) (xy 87.49385 -252.849292)
			(xy 87.449388 -252.87039) (xy 87.402117 -252.884082) (xy 87.353262 -252.890014) (xy 87.304087 -252.888033)
			(xy 87.255868 -252.878189) (xy 87.209852 -252.860737) (xy 87.167231 -252.83613) (xy 87.12911 -252.805005)
			(xy 87.096475 -252.768168) (xy 87.070172 -252.726572) (xy 87.050881 -252.681296) (xy 87.039104 -252.633512)
			(xy 87.035144 -252.584458) (xy 86.706456 -252.584458) (xy 86.705961 -252.609065) (xy 86.698066 -252.657642)
			(xy 86.682482 -252.704323) (xy 86.659611 -252.7479) (xy 86.630046 -252.787244) (xy 86.594553 -252.821336)
			(xy 86.55405 -252.849292) (xy 86.509588 -252.87039) (xy 86.462317 -252.884082) (xy 86.413462 -252.890014)
			(xy 86.364287 -252.888033) (xy 86.316068 -252.878189) (xy 86.270052 -252.860737) (xy 86.227431 -252.83613)
			(xy 86.18931 -252.805005) (xy 86.156675 -252.768168) (xy 86.130372 -252.726572) (xy 86.111081 -252.681296)
			(xy 86.099304 -252.633512) (xy 86.095344 -252.584458) (xy 85.766402 -252.584458) (xy 85.765907 -252.609065)
			(xy 85.758012 -252.657642) (xy 85.742428 -252.704323) (xy 85.719557 -252.7479) (xy 85.689992 -252.787244)
			(xy 85.654499 -252.821336) (xy 85.613996 -252.849292) (xy 85.569534 -252.87039) (xy 85.522263 -252.884082)
			(xy 85.473408 -252.890014) (xy 85.424233 -252.888033) (xy 85.376014 -252.878189) (xy 85.329998 -252.860737)
			(xy 85.287377 -252.83613) (xy 85.249256 -252.805005) (xy 85.216621 -252.768168) (xy 85.190318 -252.726572)
			(xy 85.171027 -252.681296) (xy 85.15925 -252.633512) (xy 85.15529 -252.584458) (xy 84.826348 -252.584458)
			(xy 84.825853 -252.609065) (xy 84.817958 -252.657642) (xy 84.802374 -252.704323) (xy 84.779503 -252.7479)
			(xy 84.749938 -252.787244) (xy 84.714445 -252.821336) (xy 84.673942 -252.849292) (xy 84.62948 -252.87039)
			(xy 84.582209 -252.884082) (xy 84.533354 -252.890014) (xy 84.484179 -252.888033) (xy 84.43596 -252.878189)
			(xy 84.389944 -252.860737) (xy 84.347323 -252.83613) (xy 84.309202 -252.805005) (xy 84.276567 -252.768168)
			(xy 84.250264 -252.726572) (xy 84.230973 -252.681296) (xy 84.219196 -252.633512) (xy 84.215236 -252.584458)
			(xy 83.886294 -252.584458) (xy 83.885851 -252.608453) (xy 83.878349 -252.655853) (xy 83.863524 -252.701495)
			(xy 83.841741 -252.744256) (xy 83.813536 -252.783082) (xy 83.779604 -252.817018) (xy 83.74078 -252.845226)
			(xy 83.698021 -252.867014) (xy 83.65238 -252.881843) (xy 83.604981 -252.889349) (xy 83.580986 -252.889766)
			(xy 83.551268 -252.888242) (xy 83.551014 -252.888242) (xy 83.539076 -252.887226) (xy 83.528408 -252.89129)
			(xy 83.522869 -252.893601) (xy 83.512986 -252.900404) (xy 83.50885 -252.904752) (xy 83.508088 -252.905514)
			(xy 83.502219 -252.912499) (xy 83.495451 -252.929428) (xy 83.49488 -252.938534) (xy 83.49488 -253.394464)
			(xy 83.745336 -253.394464) (xy 83.749296 -253.34541) (xy 83.761073 -253.297626) (xy 83.780364 -253.25235)
			(xy 83.806667 -253.210754) (xy 83.839302 -253.173917) (xy 83.877423 -253.142792) (xy 83.920044 -253.118185)
			(xy 83.96606 -253.100733) (xy 84.014279 -253.090889) (xy 84.063454 -253.088908) (xy 84.112309 -253.09484)
			(xy 84.15958 -253.108532) (xy 84.204042 -253.12963) (xy 84.244545 -253.157586) (xy 84.280038 -253.191678)
			(xy 84.309603 -253.231022) (xy 84.332474 -253.274599) (xy 84.348058 -253.32128) (xy 84.355953 -253.369857)
			(xy 84.356448 -253.394464) (xy 84.685136 -253.394464) (xy 84.689096 -253.34541) (xy 84.700873 -253.297626)
			(xy 84.720164 -253.25235) (xy 84.746467 -253.210754) (xy 84.779102 -253.173917) (xy 84.817223 -253.142792)
			(xy 84.859844 -253.118185) (xy 84.90586 -253.100733) (xy 84.954079 -253.090889) (xy 85.003254 -253.088908)
			(xy 85.052109 -253.09484) (xy 85.09938 -253.108532) (xy 85.143842 -253.12963) (xy 85.184345 -253.157586)
			(xy 85.219838 -253.191678) (xy 85.249403 -253.231022) (xy 85.272274 -253.274599) (xy 85.287858 -253.32128)
			(xy 85.295753 -253.369857) (xy 85.296248 -253.394464) (xy 85.62519 -253.394464) (xy 85.62915 -253.34541)
			(xy 85.640927 -253.297626) (xy 85.660218 -253.25235) (xy 85.686521 -253.210754) (xy 85.719156 -253.173917)
			(xy 85.757277 -253.142792) (xy 85.799898 -253.118185) (xy 85.845914 -253.100733) (xy 85.894133 -253.090889)
			(xy 85.943308 -253.088908) (xy 85.992163 -253.09484) (xy 86.039434 -253.108532) (xy 86.083896 -253.12963)
			(xy 86.124399 -253.157586) (xy 86.159892 -253.191678) (xy 86.189457 -253.231022) (xy 86.212328 -253.274599)
			(xy 86.227912 -253.32128) (xy 86.235807 -253.369857) (xy 86.236302 -253.394464) (xy 86.565244 -253.394464)
			(xy 86.569204 -253.34541) (xy 86.580981 -253.297626) (xy 86.600272 -253.25235) (xy 86.626575 -253.210754)
			(xy 86.65921 -253.173917) (xy 86.697331 -253.142792) (xy 86.739952 -253.118185) (xy 86.785968 -253.100733)
			(xy 86.834187 -253.090889) (xy 86.883362 -253.088908) (xy 86.932217 -253.09484) (xy 86.979488 -253.108532)
			(xy 87.02395 -253.12963) (xy 87.064453 -253.157586) (xy 87.099946 -253.191678) (xy 87.129511 -253.231022)
			(xy 87.152382 -253.274599) (xy 87.167966 -253.32128) (xy 87.175861 -253.369857) (xy 87.176356 -253.394464)
			(xy 87.505298 -253.394464) (xy 87.509258 -253.34541) (xy 87.521035 -253.297626) (xy 87.540326 -253.25235)
			(xy 87.566629 -253.210754) (xy 87.599264 -253.173917) (xy 87.637385 -253.142792) (xy 87.680006 -253.118185)
			(xy 87.726022 -253.100733) (xy 87.774241 -253.090889) (xy 87.823416 -253.088908) (xy 87.872271 -253.09484)
			(xy 87.919542 -253.108532) (xy 87.964004 -253.12963) (xy 88.004507 -253.157586) (xy 88.04 -253.191678)
			(xy 88.069565 -253.231022) (xy 88.092436 -253.274599) (xy 88.10802 -253.32128) (xy 88.115915 -253.369857)
			(xy 88.11641 -253.394464) (xy 88.445352 -253.394464) (xy 88.449312 -253.34541) (xy 88.461089 -253.297626)
			(xy 88.48038 -253.25235) (xy 88.506683 -253.210754) (xy 88.539318 -253.173917) (xy 88.577439 -253.142792)
			(xy 88.62006 -253.118185) (xy 88.666076 -253.100733) (xy 88.714295 -253.090889) (xy 88.76347 -253.088908)
			(xy 88.812325 -253.09484) (xy 88.859596 -253.108532) (xy 88.904058 -253.12963) (xy 88.944561 -253.157586)
			(xy 88.980054 -253.191678) (xy 89.009619 -253.231022) (xy 89.03249 -253.274599) (xy 89.048074 -253.32128)
			(xy 89.055969 -253.369857) (xy 89.056464 -253.394464) (xy 89.385152 -253.394464) (xy 89.389112 -253.34541)
			(xy 89.400889 -253.297626) (xy 89.42018 -253.25235) (xy 89.446483 -253.210754) (xy 89.479118 -253.173917)
			(xy 89.517239 -253.142792) (xy 89.55986 -253.118185) (xy 89.605876 -253.100733) (xy 89.654095 -253.090889)
			(xy 89.70327 -253.088908) (xy 89.752125 -253.09484) (xy 89.799396 -253.108532) (xy 89.843858 -253.12963)
			(xy 89.884361 -253.157586) (xy 89.919854 -253.191678) (xy 89.949419 -253.231022) (xy 89.97229 -253.274599)
			(xy 89.987874 -253.32128) (xy 89.995769 -253.369857) (xy 89.996264 -253.394464) (xy 90.314775 -253.394464)
			(xy 90.31887 -253.343736) (xy 90.331049 -253.294322) (xy 90.350997 -253.247502) (xy 90.378198 -253.204488)
			(xy 90.411946 -253.166394) (xy 90.451368 -253.134207) (xy 90.495442 -253.108761) (xy 90.543028 -253.090714)
			(xy 90.592892 -253.080534) (xy 90.643744 -253.078485) (xy 90.694265 -253.084619) (xy 90.743149 -253.098779)
			(xy 90.789128 -253.120596) (xy 90.831012 -253.149506) (xy 90.867716 -253.184761) (xy 90.898289 -253.225447)
			(xy 90.92194 -253.27051) (xy 90.938056 -253.318784) (xy 90.94622 -253.369018) (xy 90.946732 -253.394464)
			(xy 91.26526 -253.394464) (xy 91.26922 -253.34541) (xy 91.280997 -253.297626) (xy 91.300288 -253.25235)
			(xy 91.326591 -253.210754) (xy 91.359226 -253.173917) (xy 91.397347 -253.142792) (xy 91.439968 -253.118185)
			(xy 91.485984 -253.100733) (xy 91.534203 -253.090889) (xy 91.583378 -253.088908) (xy 91.632233 -253.09484)
			(xy 91.679504 -253.108532) (xy 91.723966 -253.12963) (xy 91.764469 -253.157586) (xy 91.799962 -253.191678)
			(xy 91.829527 -253.231022) (xy 91.852398 -253.274599) (xy 91.867982 -253.32128) (xy 91.875877 -253.369857)
			(xy 91.876372 -253.394464) (xy 92.194883 -253.394464) (xy 92.198978 -253.343736) (xy 92.211157 -253.294322)
			(xy 92.231105 -253.247502) (xy 92.258306 -253.204488) (xy 92.292054 -253.166394) (xy 92.331476 -253.134207)
			(xy 92.37555 -253.108761) (xy 92.423136 -253.090714) (xy 92.473 -253.080534) (xy 92.523852 -253.078485)
			(xy 92.574373 -253.084619) (xy 92.623257 -253.098779) (xy 92.669236 -253.120596) (xy 92.71112 -253.149506)
			(xy 92.747824 -253.184761) (xy 92.778397 -253.225447) (xy 92.802048 -253.27051) (xy 92.818164 -253.318784)
			(xy 92.826328 -253.369018) (xy 92.82684 -253.394464) (xy 93.145114 -253.394464) (xy 93.149074 -253.34541)
			(xy 93.160851 -253.297626) (xy 93.180142 -253.25235) (xy 93.206445 -253.210754) (xy 93.23908 -253.173917)
			(xy 93.277201 -253.142792) (xy 93.319822 -253.118185) (xy 93.365838 -253.100733) (xy 93.414057 -253.090889)
			(xy 93.463232 -253.088908) (xy 93.512087 -253.09484) (xy 93.559358 -253.108532) (xy 93.60382 -253.12963)
			(xy 93.644323 -253.157586) (xy 93.679816 -253.191678) (xy 93.709381 -253.231022) (xy 93.732252 -253.274599)
			(xy 93.747836 -253.32128) (xy 93.755731 -253.369857) (xy 93.756226 -253.394464) (xy 94.074737 -253.394464)
			(xy 94.078832 -253.343736) (xy 94.091011 -253.294322) (xy 94.110959 -253.247502) (xy 94.13816 -253.204488)
			(xy 94.171908 -253.166394) (xy 94.21133 -253.134207) (xy 94.255404 -253.108761) (xy 94.30299 -253.090714)
			(xy 94.352854 -253.080534) (xy 94.403706 -253.078485) (xy 94.454227 -253.084619) (xy 94.503111 -253.098779)
			(xy 94.54909 -253.120596) (xy 94.590974 -253.149506) (xy 94.627678 -253.184761) (xy 94.658251 -253.225447)
			(xy 94.681902 -253.27051) (xy 94.698018 -253.318784) (xy 94.706182 -253.369018) (xy 94.706694 -253.394464)
			(xy 95.014791 -253.394464) (xy 95.018886 -253.343736) (xy 95.031065 -253.294322) (xy 95.051013 -253.247502)
			(xy 95.078214 -253.204488) (xy 95.111962 -253.166394) (xy 95.151384 -253.134207) (xy 95.195458 -253.108761)
			(xy 95.243044 -253.090714) (xy 95.292908 -253.080534) (xy 95.34376 -253.078485) (xy 95.394281 -253.084619)
			(xy 95.443165 -253.098779) (xy 95.489144 -253.120596) (xy 95.531028 -253.149506) (xy 95.567732 -253.184761)
			(xy 95.598305 -253.225447) (xy 95.621956 -253.27051) (xy 95.638072 -253.318784) (xy 95.646236 -253.369018)
			(xy 95.646748 -253.394464) (xy 95.646236 -253.41991) (xy 95.638072 -253.470144) (xy 95.621956 -253.518418)
			(xy 95.598305 -253.563481) (xy 95.567732 -253.604167) (xy 95.531028 -253.639422) (xy 95.489144 -253.668332)
			(xy 95.443165 -253.690149) (xy 95.394281 -253.704309) (xy 95.34376 -253.710443) (xy 95.292908 -253.708394)
			(xy 95.243044 -253.698214) (xy 95.195458 -253.680167) (xy 95.151384 -253.654721) (xy 95.111962 -253.622534)
			(xy 95.078214 -253.58444) (xy 95.051013 -253.541426) (xy 95.031065 -253.494606) (xy 95.018886 -253.445192)
			(xy 95.014791 -253.394464) (xy 94.706694 -253.394464) (xy 94.706182 -253.41991) (xy 94.698018 -253.470144)
			(xy 94.681902 -253.518418) (xy 94.658251 -253.563481) (xy 94.627678 -253.604167) (xy 94.590974 -253.639422)
			(xy 94.54909 -253.668332) (xy 94.503111 -253.690149) (xy 94.454227 -253.704309) (xy 94.403706 -253.710443)
			(xy 94.352854 -253.708394) (xy 94.30299 -253.698214) (xy 94.255404 -253.680167) (xy 94.21133 -253.654721)
			(xy 94.171908 -253.622534) (xy 94.13816 -253.58444) (xy 94.110959 -253.541426) (xy 94.091011 -253.494606)
			(xy 94.078832 -253.445192) (xy 94.074737 -253.394464) (xy 93.756226 -253.394464) (xy 93.755731 -253.419071)
			(xy 93.747836 -253.467648) (xy 93.732252 -253.514329) (xy 93.709381 -253.557906) (xy 93.679816 -253.59725)
			(xy 93.644323 -253.631342) (xy 93.60382 -253.659298) (xy 93.559358 -253.680396) (xy 93.512087 -253.694088)
			(xy 93.463232 -253.70002) (xy 93.414057 -253.698039) (xy 93.365838 -253.688195) (xy 93.319822 -253.670743)
			(xy 93.277201 -253.646136) (xy 93.23908 -253.615011) (xy 93.206445 -253.578174) (xy 93.180142 -253.536578)
			(xy 93.160851 -253.491302) (xy 93.149074 -253.443518) (xy 93.145114 -253.394464) (xy 92.82684 -253.394464)
			(xy 92.826328 -253.41991) (xy 92.818164 -253.470144) (xy 92.802048 -253.518418) (xy 92.778397 -253.563481)
			(xy 92.747824 -253.604167) (xy 92.71112 -253.639422) (xy 92.669236 -253.668332) (xy 92.623257 -253.690149)
			(xy 92.574373 -253.704309) (xy 92.523852 -253.710443) (xy 92.473 -253.708394) (xy 92.423136 -253.698214)
			(xy 92.37555 -253.680167) (xy 92.331476 -253.654721) (xy 92.292054 -253.622534) (xy 92.258306 -253.58444)
			(xy 92.231105 -253.541426) (xy 92.211157 -253.494606) (xy 92.198978 -253.445192) (xy 92.194883 -253.394464)
			(xy 91.876372 -253.394464) (xy 91.875877 -253.419071) (xy 91.867982 -253.467648) (xy 91.852398 -253.514329)
			(xy 91.829527 -253.557906) (xy 91.799962 -253.59725) (xy 91.764469 -253.631342) (xy 91.723966 -253.659298)
			(xy 91.679504 -253.680396) (xy 91.632233 -253.694088) (xy 91.583378 -253.70002) (xy 91.534203 -253.698039)
			(xy 91.485984 -253.688195) (xy 91.439968 -253.670743) (xy 91.397347 -253.646136) (xy 91.359226 -253.615011)
			(xy 91.326591 -253.578174) (xy 91.300288 -253.536578) (xy 91.280997 -253.491302) (xy 91.26922 -253.443518)
			(xy 91.26526 -253.394464) (xy 90.946732 -253.394464) (xy 90.94622 -253.41991) (xy 90.938056 -253.470144)
			(xy 90.92194 -253.518418) (xy 90.898289 -253.563481) (xy 90.867716 -253.604167) (xy 90.831012 -253.639422)
			(xy 90.789128 -253.668332) (xy 90.743149 -253.690149) (xy 90.694265 -253.704309) (xy 90.643744 -253.710443)
			(xy 90.592892 -253.708394) (xy 90.543028 -253.698214) (xy 90.495442 -253.680167) (xy 90.451368 -253.654721)
			(xy 90.411946 -253.622534) (xy 90.378198 -253.58444) (xy 90.350997 -253.541426) (xy 90.331049 -253.494606)
			(xy 90.31887 -253.445192) (xy 90.314775 -253.394464) (xy 89.996264 -253.394464) (xy 89.995769 -253.419071)
			(xy 89.987874 -253.467648) (xy 89.97229 -253.514329) (xy 89.949419 -253.557906) (xy 89.919854 -253.59725)
			(xy 89.884361 -253.631342) (xy 89.843858 -253.659298) (xy 89.799396 -253.680396) (xy 89.752125 -253.694088)
			(xy 89.70327 -253.70002) (xy 89.654095 -253.698039) (xy 89.605876 -253.688195) (xy 89.55986 -253.670743)
			(xy 89.517239 -253.646136) (xy 89.479118 -253.615011) (xy 89.446483 -253.578174) (xy 89.42018 -253.536578)
			(xy 89.400889 -253.491302) (xy 89.389112 -253.443518) (xy 89.385152 -253.394464) (xy 89.056464 -253.394464)
			(xy 89.055969 -253.419071) (xy 89.048074 -253.467648) (xy 89.03249 -253.514329) (xy 89.009619 -253.557906)
			(xy 88.980054 -253.59725) (xy 88.944561 -253.631342) (xy 88.904058 -253.659298) (xy 88.859596 -253.680396)
			(xy 88.812325 -253.694088) (xy 88.76347 -253.70002) (xy 88.714295 -253.698039) (xy 88.666076 -253.688195)
			(xy 88.62006 -253.670743) (xy 88.577439 -253.646136) (xy 88.539318 -253.615011) (xy 88.506683 -253.578174)
			(xy 88.48038 -253.536578) (xy 88.461089 -253.491302) (xy 88.449312 -253.443518) (xy 88.445352 -253.394464)
			(xy 88.11641 -253.394464) (xy 88.115915 -253.419071) (xy 88.10802 -253.467648) (xy 88.092436 -253.514329)
			(xy 88.069565 -253.557906) (xy 88.04 -253.59725) (xy 88.004507 -253.631342) (xy 87.964004 -253.659298)
			(xy 87.919542 -253.680396) (xy 87.872271 -253.694088) (xy 87.823416 -253.70002) (xy 87.774241 -253.698039)
			(xy 87.726022 -253.688195) (xy 87.680006 -253.670743) (xy 87.637385 -253.646136) (xy 87.599264 -253.615011)
			(xy 87.566629 -253.578174) (xy 87.540326 -253.536578) (xy 87.521035 -253.491302) (xy 87.509258 -253.443518)
			(xy 87.505298 -253.394464) (xy 87.176356 -253.394464) (xy 87.175861 -253.419071) (xy 87.167966 -253.467648)
			(xy 87.152382 -253.514329) (xy 87.129511 -253.557906) (xy 87.099946 -253.59725) (xy 87.064453 -253.631342)
			(xy 87.02395 -253.659298) (xy 86.979488 -253.680396) (xy 86.932217 -253.694088) (xy 86.883362 -253.70002)
			(xy 86.834187 -253.698039) (xy 86.785968 -253.688195) (xy 86.739952 -253.670743) (xy 86.697331 -253.646136)
			(xy 86.65921 -253.615011) (xy 86.626575 -253.578174) (xy 86.600272 -253.536578) (xy 86.580981 -253.491302)
			(xy 86.569204 -253.443518) (xy 86.565244 -253.394464) (xy 86.236302 -253.394464) (xy 86.235807 -253.419071)
			(xy 86.227912 -253.467648) (xy 86.212328 -253.514329) (xy 86.189457 -253.557906) (xy 86.159892 -253.59725)
			(xy 86.124399 -253.631342) (xy 86.083896 -253.659298) (xy 86.039434 -253.680396) (xy 85.992163 -253.694088)
			(xy 85.943308 -253.70002) (xy 85.894133 -253.698039) (xy 85.845914 -253.688195) (xy 85.799898 -253.670743)
			(xy 85.757277 -253.646136) (xy 85.719156 -253.615011) (xy 85.686521 -253.578174) (xy 85.660218 -253.536578)
			(xy 85.640927 -253.491302) (xy 85.62915 -253.443518) (xy 85.62519 -253.394464) (xy 85.296248 -253.394464)
			(xy 85.295753 -253.419071) (xy 85.287858 -253.467648) (xy 85.272274 -253.514329) (xy 85.249403 -253.557906)
			(xy 85.219838 -253.59725) (xy 85.184345 -253.631342) (xy 85.143842 -253.659298) (xy 85.09938 -253.680396)
			(xy 85.052109 -253.694088) (xy 85.003254 -253.70002) (xy 84.954079 -253.698039) (xy 84.90586 -253.688195)
			(xy 84.859844 -253.670743) (xy 84.817223 -253.646136) (xy 84.779102 -253.615011) (xy 84.746467 -253.578174)
			(xy 84.720164 -253.536578) (xy 84.700873 -253.491302) (xy 84.689096 -253.443518) (xy 84.685136 -253.394464)
			(xy 84.356448 -253.394464) (xy 84.355953 -253.419071) (xy 84.348058 -253.467648) (xy 84.332474 -253.514329)
			(xy 84.309603 -253.557906) (xy 84.280038 -253.59725) (xy 84.244545 -253.631342) (xy 84.204042 -253.659298)
			(xy 84.15958 -253.680396) (xy 84.112309 -253.694088) (xy 84.063454 -253.70002) (xy 84.014279 -253.698039)
			(xy 83.96606 -253.688195) (xy 83.920044 -253.670743) (xy 83.877423 -253.646136) (xy 83.839302 -253.615011)
			(xy 83.806667 -253.578174) (xy 83.780364 -253.536578) (xy 83.761073 -253.491302) (xy 83.749296 -253.443518)
			(xy 83.745336 -253.394464) (xy 83.49488 -253.394464) (xy 83.49488 -253.751588) (xy 83.494969 -253.756139)
			(xy 83.496628 -253.765089) (xy 83.498182 -253.769368) (xy 83.501738 -253.778766) (xy 83.537298 -253.818136)
			(xy 83.552792 -253.835408) (xy 83.559904 -253.841758) (xy 83.561936 -253.843028) (xy 83.567778 -253.846584)
			(xy 83.576414 -253.850648) (xy 83.585558 -253.851664) (xy 83.585812 -253.851664) (xy 83.609411 -253.8544)
			(xy 83.655418 -253.86624) (xy 83.699037 -253.885059) (xy 83.739216 -253.910404) (xy 83.774987 -253.941664)
			(xy 83.805488 -253.978085) (xy 83.829982 -254.018789) (xy 83.839304 -254.04064) (xy 83.84286 -254.047244)
			(xy 83.843114 -254.047752) (xy 83.856645 -254.071633) (xy 83.8759 -254.123026) (xy 83.885678 -254.177029)
			(xy 83.886294 -254.20447) (xy 84.215236 -254.20447) (xy 84.219196 -254.155416) (xy 84.230973 -254.107632)
			(xy 84.250264 -254.062356) (xy 84.276567 -254.02076) (xy 84.309202 -253.983923) (xy 84.347323 -253.952798)
			(xy 84.389944 -253.928191) (xy 84.43596 -253.910739) (xy 84.484179 -253.900895) (xy 84.533354 -253.898914)
			(xy 84.582209 -253.904846) (xy 84.62948 -253.918538) (xy 84.673942 -253.939636) (xy 84.714445 -253.967592)
			(xy 84.749938 -254.001684) (xy 84.779503 -254.041028) (xy 84.802374 -254.084605) (xy 84.817958 -254.131286)
			(xy 84.825853 -254.179863) (xy 84.826348 -254.20447) (xy 85.15529 -254.20447) (xy 85.15925 -254.155416)
			(xy 85.171027 -254.107632) (xy 85.190318 -254.062356) (xy 85.216621 -254.02076) (xy 85.249256 -253.983923)
			(xy 85.287377 -253.952798) (xy 85.329998 -253.928191) (xy 85.376014 -253.910739) (xy 85.424233 -253.900895)
			(xy 85.473408 -253.898914) (xy 85.522263 -253.904846) (xy 85.569534 -253.918538) (xy 85.613996 -253.939636)
			(xy 85.654499 -253.967592) (xy 85.689992 -254.001684) (xy 85.719557 -254.041028) (xy 85.742428 -254.084605)
			(xy 85.758012 -254.131286) (xy 85.765907 -254.179863) (xy 85.766402 -254.20447) (xy 87.035144 -254.20447)
			(xy 87.039104 -254.155416) (xy 87.050881 -254.107632) (xy 87.070172 -254.062356) (xy 87.096475 -254.02076)
			(xy 87.12911 -253.983923) (xy 87.167231 -253.952798) (xy 87.209852 -253.928191) (xy 87.255868 -253.910739)
			(xy 87.304087 -253.900895) (xy 87.353262 -253.898914) (xy 87.402117 -253.904846) (xy 87.449388 -253.918538)
			(xy 87.49385 -253.939636) (xy 87.534353 -253.967592) (xy 87.569846 -254.001684) (xy 87.599411 -254.041028)
			(xy 87.622282 -254.084605) (xy 87.637866 -254.131286) (xy 87.645761 -254.179863) (xy 87.646256 -254.20447)
			(xy 87.975198 -254.20447) (xy 87.979158 -254.155416) (xy 87.990935 -254.107632) (xy 88.010226 -254.062356)
			(xy 88.036529 -254.02076) (xy 88.069164 -253.983923) (xy 88.107285 -253.952798) (xy 88.149906 -253.928191)
			(xy 88.195922 -253.910739) (xy 88.244141 -253.900895) (xy 88.293316 -253.898914) (xy 88.342171 -253.904846)
			(xy 88.389442 -253.918538) (xy 88.433904 -253.939636) (xy 88.474407 -253.967592) (xy 88.5099 -254.001684)
			(xy 88.539465 -254.041028) (xy 88.562336 -254.084605) (xy 88.57792 -254.131286) (xy 88.585815 -254.179863)
			(xy 88.58631 -254.20447) (xy 88.915252 -254.20447) (xy 88.919212 -254.155416) (xy 88.930989 -254.107632)
			(xy 88.95028 -254.062356) (xy 88.976583 -254.02076) (xy 89.009218 -253.983923) (xy 89.047339 -253.952798)
			(xy 89.08996 -253.928191) (xy 89.135976 -253.910739) (xy 89.184195 -253.900895) (xy 89.23337 -253.898914)
			(xy 89.282225 -253.904846) (xy 89.329496 -253.918538) (xy 89.373958 -253.939636) (xy 89.414461 -253.967592)
			(xy 89.449954 -254.001684) (xy 89.479519 -254.041028) (xy 89.50239 -254.084605) (xy 89.517974 -254.131286)
			(xy 89.525869 -254.179863) (xy 89.526364 -254.20447) (xy 89.855306 -254.20447) (xy 89.859266 -254.155416)
			(xy 89.871043 -254.107632) (xy 89.890334 -254.062356) (xy 89.916637 -254.02076) (xy 89.949272 -253.983923)
			(xy 89.987393 -253.952798) (xy 90.030014 -253.928191) (xy 90.07603 -253.910739) (xy 90.124249 -253.900895)
			(xy 90.173424 -253.898914) (xy 90.222279 -253.904846) (xy 90.26955 -253.918538) (xy 90.314012 -253.939636)
			(xy 90.354515 -253.967592) (xy 90.390008 -254.001684) (xy 90.419573 -254.041028) (xy 90.442444 -254.084605)
			(xy 90.458028 -254.131286) (xy 90.465923 -254.179863) (xy 90.466418 -254.20447) (xy 90.784675 -254.20447)
			(xy 90.78877 -254.153742) (xy 90.800949 -254.104328) (xy 90.820897 -254.057508) (xy 90.848098 -254.014494)
			(xy 90.881846 -253.9764) (xy 90.921268 -253.944213) (xy 90.965342 -253.918767) (xy 91.012928 -253.90072)
			(xy 91.062792 -253.89054) (xy 91.113644 -253.888491) (xy 91.164165 -253.894625) (xy 91.213049 -253.908785)
			(xy 91.259028 -253.930602) (xy 91.300912 -253.959512) (xy 91.337616 -253.994767) (xy 91.368189 -254.035453)
			(xy 91.39184 -254.080516) (xy 91.407956 -254.12879) (xy 91.41612 -254.179024) (xy 91.416632 -254.20447)
			(xy 91.724729 -254.20447) (xy 91.728824 -254.153742) (xy 91.741003 -254.104328) (xy 91.760951 -254.057508)
			(xy 91.788152 -254.014494) (xy 91.8219 -253.9764) (xy 91.861322 -253.944213) (xy 91.905396 -253.918767)
			(xy 91.952982 -253.90072) (xy 92.002846 -253.89054) (xy 92.053698 -253.888491) (xy 92.104219 -253.894625)
			(xy 92.153103 -253.908785) (xy 92.199082 -253.930602) (xy 92.240966 -253.959512) (xy 92.27767 -253.994767)
			(xy 92.308243 -254.035453) (xy 92.331894 -254.080516) (xy 92.34801 -254.12879) (xy 92.356174 -254.179024)
			(xy 92.356686 -254.20447) (xy 93.604837 -254.20447) (xy 93.608932 -254.153742) (xy 93.621111 -254.104328)
			(xy 93.641059 -254.057508) (xy 93.66826 -254.014494) (xy 93.702008 -253.9764) (xy 93.74143 -253.944213)
			(xy 93.785504 -253.918767) (xy 93.83309 -253.90072) (xy 93.882954 -253.89054) (xy 93.933806 -253.888491)
			(xy 93.984327 -253.894625) (xy 94.033211 -253.908785) (xy 94.07919 -253.930602) (xy 94.121074 -253.959512)
			(xy 94.157778 -253.994767) (xy 94.188351 -254.035453) (xy 94.212002 -254.080516) (xy 94.228118 -254.12879)
			(xy 94.236282 -254.179024) (xy 94.236794 -254.20447) (xy 94.555322 -254.20447) (xy 94.559282 -254.155416)
			(xy 94.571059 -254.107632) (xy 94.59035 -254.062356) (xy 94.616653 -254.02076) (xy 94.649288 -253.983923)
			(xy 94.687409 -253.952798) (xy 94.73003 -253.928191) (xy 94.776046 -253.910739) (xy 94.824265 -253.900895)
			(xy 94.87344 -253.898914) (xy 94.922295 -253.904846) (xy 94.969566 -253.918538) (xy 95.014028 -253.939636)
			(xy 95.054531 -253.967592) (xy 95.090024 -254.001684) (xy 95.119589 -254.041028) (xy 95.14246 -254.084605)
			(xy 95.158044 -254.131286) (xy 95.165939 -254.179863) (xy 95.166434 -254.20447) (xy 95.165939 -254.229077)
			(xy 95.158044 -254.277654) (xy 95.14246 -254.324335) (xy 95.119589 -254.367912) (xy 95.090024 -254.407256)
			(xy 95.054531 -254.441348) (xy 95.014028 -254.469304) (xy 94.969566 -254.490402) (xy 94.922295 -254.504094)
			(xy 94.87344 -254.510026) (xy 94.824265 -254.508045) (xy 94.776046 -254.498201) (xy 94.73003 -254.480749)
			(xy 94.687409 -254.456142) (xy 94.649288 -254.425017) (xy 94.616653 -254.38818) (xy 94.59035 -254.346584)
			(xy 94.571059 -254.301308) (xy 94.559282 -254.253524) (xy 94.555322 -254.20447) (xy 94.236794 -254.20447)
			(xy 94.236282 -254.229916) (xy 94.228118 -254.28015) (xy 94.212002 -254.328424) (xy 94.188351 -254.373487)
			(xy 94.157778 -254.414173) (xy 94.121074 -254.449428) (xy 94.07919 -254.478338) (xy 94.033211 -254.500155)
			(xy 93.984327 -254.514315) (xy 93.933806 -254.520449) (xy 93.882954 -254.5184) (xy 93.83309 -254.50822)
			(xy 93.785504 -254.490173) (xy 93.74143 -254.464727) (xy 93.702008 -254.43254) (xy 93.66826 -254.394446)
			(xy 93.641059 -254.351432) (xy 93.621111 -254.304612) (xy 93.608932 -254.255198) (xy 93.604837 -254.20447)
			(xy 92.356686 -254.20447) (xy 92.356174 -254.229916) (xy 92.34801 -254.28015) (xy 92.331894 -254.328424)
			(xy 92.308243 -254.373487) (xy 92.27767 -254.414173) (xy 92.240966 -254.449428) (xy 92.199082 -254.478338)
			(xy 92.153103 -254.500155) (xy 92.104219 -254.514315) (xy 92.053698 -254.520449) (xy 92.002846 -254.5184)
			(xy 91.952982 -254.50822) (xy 91.905396 -254.490173) (xy 91.861322 -254.464727) (xy 91.8219 -254.43254)
			(xy 91.788152 -254.394446) (xy 91.760951 -254.351432) (xy 91.741003 -254.304612) (xy 91.728824 -254.255198)
			(xy 91.724729 -254.20447) (xy 91.416632 -254.20447) (xy 91.41612 -254.229916) (xy 91.407956 -254.28015)
			(xy 91.39184 -254.328424) (xy 91.368189 -254.373487) (xy 91.337616 -254.414173) (xy 91.300912 -254.449428)
			(xy 91.259028 -254.478338) (xy 91.213049 -254.500155) (xy 91.164165 -254.514315) (xy 91.113644 -254.520449)
			(xy 91.062792 -254.5184) (xy 91.012928 -254.50822) (xy 90.965342 -254.490173) (xy 90.921268 -254.464727)
			(xy 90.881846 -254.43254) (xy 90.848098 -254.394446) (xy 90.820897 -254.351432) (xy 90.800949 -254.304612)
			(xy 90.78877 -254.255198) (xy 90.784675 -254.20447) (xy 90.466418 -254.20447) (xy 90.465923 -254.229077)
			(xy 90.458028 -254.277654) (xy 90.442444 -254.324335) (xy 90.419573 -254.367912) (xy 90.390008 -254.407256)
			(xy 90.354515 -254.441348) (xy 90.314012 -254.469304) (xy 90.26955 -254.490402) (xy 90.222279 -254.504094)
			(xy 90.173424 -254.510026) (xy 90.124249 -254.508045) (xy 90.07603 -254.498201) (xy 90.030014 -254.480749)
			(xy 89.987393 -254.456142) (xy 89.949272 -254.425017) (xy 89.916637 -254.38818) (xy 89.890334 -254.346584)
			(xy 89.871043 -254.301308) (xy 89.859266 -254.253524) (xy 89.855306 -254.20447) (xy 89.526364 -254.20447)
			(xy 89.525869 -254.229077) (xy 89.517974 -254.277654) (xy 89.50239 -254.324335) (xy 89.479519 -254.367912)
			(xy 89.449954 -254.407256) (xy 89.414461 -254.441348) (xy 89.373958 -254.469304) (xy 89.329496 -254.490402)
			(xy 89.282225 -254.504094) (xy 89.23337 -254.510026) (xy 89.184195 -254.508045) (xy 89.135976 -254.498201)
			(xy 89.08996 -254.480749) (xy 89.047339 -254.456142) (xy 89.009218 -254.425017) (xy 88.976583 -254.38818)
			(xy 88.95028 -254.346584) (xy 88.930989 -254.301308) (xy 88.919212 -254.253524) (xy 88.915252 -254.20447)
			(xy 88.58631 -254.20447) (xy 88.585815 -254.229077) (xy 88.57792 -254.277654) (xy 88.562336 -254.324335)
			(xy 88.539465 -254.367912) (xy 88.5099 -254.407256) (xy 88.474407 -254.441348) (xy 88.433904 -254.469304)
			(xy 88.389442 -254.490402) (xy 88.342171 -254.504094) (xy 88.293316 -254.510026) (xy 88.244141 -254.508045)
			(xy 88.195922 -254.498201) (xy 88.149906 -254.480749) (xy 88.107285 -254.456142) (xy 88.069164 -254.425017)
			(xy 88.036529 -254.38818) (xy 88.010226 -254.346584) (xy 87.990935 -254.301308) (xy 87.979158 -254.253524)
			(xy 87.975198 -254.20447) (xy 87.646256 -254.20447) (xy 87.645761 -254.229077) (xy 87.637866 -254.277654)
			(xy 87.622282 -254.324335) (xy 87.599411 -254.367912) (xy 87.569846 -254.407256) (xy 87.534353 -254.441348)
			(xy 87.49385 -254.469304) (xy 87.449388 -254.490402) (xy 87.402117 -254.504094) (xy 87.353262 -254.510026)
			(xy 87.304087 -254.508045) (xy 87.255868 -254.498201) (xy 87.209852 -254.480749) (xy 87.167231 -254.456142)
			(xy 87.12911 -254.425017) (xy 87.096475 -254.38818) (xy 87.070172 -254.346584) (xy 87.050881 -254.301308)
			(xy 87.039104 -254.253524) (xy 87.035144 -254.20447) (xy 85.766402 -254.20447) (xy 85.765907 -254.229077)
			(xy 85.758012 -254.277654) (xy 85.742428 -254.324335) (xy 85.719557 -254.367912) (xy 85.689992 -254.407256)
			(xy 85.654499 -254.441348) (xy 85.613996 -254.469304) (xy 85.569534 -254.490402) (xy 85.522263 -254.504094)
			(xy 85.473408 -254.510026) (xy 85.424233 -254.508045) (xy 85.376014 -254.498201) (xy 85.329998 -254.480749)
			(xy 85.287377 -254.456142) (xy 85.249256 -254.425017) (xy 85.216621 -254.38818) (xy 85.190318 -254.346584)
			(xy 85.171027 -254.301308) (xy 85.15925 -254.253524) (xy 85.15529 -254.20447) (xy 84.826348 -254.20447)
			(xy 84.825853 -254.229077) (xy 84.817958 -254.277654) (xy 84.802374 -254.324335) (xy 84.779503 -254.367912)
			(xy 84.749938 -254.407256) (xy 84.714445 -254.441348) (xy 84.673942 -254.469304) (xy 84.62948 -254.490402)
			(xy 84.582209 -254.504094) (xy 84.533354 -254.510026) (xy 84.484179 -254.508045) (xy 84.43596 -254.498201)
			(xy 84.389944 -254.480749) (xy 84.347323 -254.456142) (xy 84.309202 -254.425017) (xy 84.276567 -254.38818)
			(xy 84.250264 -254.346584) (xy 84.230973 -254.301308) (xy 84.219196 -254.253524) (xy 84.215236 -254.20447)
			(xy 83.886294 -254.20447) (xy 83.88585 -254.228464) (xy 83.878347 -254.275863) (xy 83.863521 -254.321503)
			(xy 83.841737 -254.364263) (xy 83.813532 -254.403087) (xy 83.779599 -254.437021) (xy 83.740776 -254.465229)
			(xy 83.698018 -254.487015) (xy 83.652378 -254.501843) (xy 83.60498 -254.509349) (xy 83.580986 -254.509778)
			(xy 83.551268 -254.508254) (xy 83.551014 -254.508254) (xy 83.539076 -254.507238) (xy 83.528408 -254.511302)
			(xy 83.522866 -254.513609) (xy 83.512975 -254.520404) (xy 83.50885 -254.524764) (xy 83.508088 -254.525526)
			(xy 83.50222 -254.532512) (xy 83.495457 -254.54944) (xy 83.49488 -254.558546) (xy 83.49488 -255.014476)
			(xy 83.745336 -255.014476) (xy 83.749296 -254.965422) (xy 83.761073 -254.917638) (xy 83.780364 -254.872362)
			(xy 83.806667 -254.830766) (xy 83.839302 -254.793929) (xy 83.877423 -254.762804) (xy 83.920044 -254.738197)
			(xy 83.96606 -254.720745) (xy 84.014279 -254.710901) (xy 84.063454 -254.70892) (xy 84.112309 -254.714852)
			(xy 84.15958 -254.728544) (xy 84.204042 -254.749642) (xy 84.244545 -254.777598) (xy 84.280038 -254.81169)
			(xy 84.309603 -254.851034) (xy 84.332474 -254.894611) (xy 84.348058 -254.941292) (xy 84.355953 -254.989869)
			(xy 84.356448 -255.014476) (xy 84.685136 -255.014476) (xy 84.689096 -254.965422) (xy 84.700873 -254.917638)
			(xy 84.720164 -254.872362) (xy 84.746467 -254.830766) (xy 84.779102 -254.793929) (xy 84.817223 -254.762804)
			(xy 84.859844 -254.738197) (xy 84.90586 -254.720745) (xy 84.954079 -254.710901) (xy 85.003254 -254.70892)
			(xy 85.052109 -254.714852) (xy 85.09938 -254.728544) (xy 85.143842 -254.749642) (xy 85.184345 -254.777598)
			(xy 85.219838 -254.81169) (xy 85.249403 -254.851034) (xy 85.272274 -254.894611) (xy 85.287858 -254.941292)
			(xy 85.295753 -254.989869) (xy 85.296248 -255.014476) (xy 85.62519 -255.014476) (xy 85.62915 -254.965422)
			(xy 85.640927 -254.917638) (xy 85.660218 -254.872362) (xy 85.686521 -254.830766) (xy 85.719156 -254.793929)
			(xy 85.757277 -254.762804) (xy 85.799898 -254.738197) (xy 85.845914 -254.720745) (xy 85.894133 -254.710901)
			(xy 85.943308 -254.70892) (xy 85.992163 -254.714852) (xy 86.039434 -254.728544) (xy 86.083896 -254.749642)
			(xy 86.124399 -254.777598) (xy 86.159892 -254.81169) (xy 86.189457 -254.851034) (xy 86.212328 -254.894611)
			(xy 86.227912 -254.941292) (xy 86.235807 -254.989869) (xy 86.236302 -255.014476) (xy 86.565244 -255.014476)
			(xy 86.569204 -254.965422) (xy 86.580981 -254.917638) (xy 86.600272 -254.872362) (xy 86.626575 -254.830766)
			(xy 86.65921 -254.793929) (xy 86.697331 -254.762804) (xy 86.739952 -254.738197) (xy 86.785968 -254.720745)
			(xy 86.834187 -254.710901) (xy 86.883362 -254.70892) (xy 86.932217 -254.714852) (xy 86.979488 -254.728544)
			(xy 87.02395 -254.749642) (xy 87.064453 -254.777598) (xy 87.099946 -254.81169) (xy 87.129511 -254.851034)
			(xy 87.152382 -254.894611) (xy 87.167966 -254.941292) (xy 87.175861 -254.989869) (xy 87.176356 -255.014476)
			(xy 87.505298 -255.014476) (xy 87.509258 -254.965422) (xy 87.521035 -254.917638) (xy 87.540326 -254.872362)
			(xy 87.566629 -254.830766) (xy 87.599264 -254.793929) (xy 87.637385 -254.762804) (xy 87.680006 -254.738197)
			(xy 87.726022 -254.720745) (xy 87.774241 -254.710901) (xy 87.823416 -254.70892) (xy 87.872271 -254.714852)
			(xy 87.919542 -254.728544) (xy 87.964004 -254.749642) (xy 88.004507 -254.777598) (xy 88.04 -254.81169)
			(xy 88.069565 -254.851034) (xy 88.092436 -254.894611) (xy 88.10802 -254.941292) (xy 88.115915 -254.989869)
			(xy 88.11641 -255.014476) (xy 88.445352 -255.014476) (xy 88.449312 -254.965422) (xy 88.461089 -254.917638)
			(xy 88.48038 -254.872362) (xy 88.506683 -254.830766) (xy 88.539318 -254.793929) (xy 88.577439 -254.762804)
			(xy 88.62006 -254.738197) (xy 88.666076 -254.720745) (xy 88.714295 -254.710901) (xy 88.76347 -254.70892)
			(xy 88.812325 -254.714852) (xy 88.859596 -254.728544) (xy 88.904058 -254.749642) (xy 88.944561 -254.777598)
			(xy 88.980054 -254.81169) (xy 89.009619 -254.851034) (xy 89.03249 -254.894611) (xy 89.048074 -254.941292)
			(xy 89.055969 -254.989869) (xy 89.056464 -255.014476) (xy 89.385152 -255.014476) (xy 89.389112 -254.965422)
			(xy 89.400889 -254.917638) (xy 89.42018 -254.872362) (xy 89.446483 -254.830766) (xy 89.479118 -254.793929)
			(xy 89.517239 -254.762804) (xy 89.55986 -254.738197) (xy 89.605876 -254.720745) (xy 89.654095 -254.710901)
			(xy 89.70327 -254.70892) (xy 89.752125 -254.714852) (xy 89.799396 -254.728544) (xy 89.843858 -254.749642)
			(xy 89.884361 -254.777598) (xy 89.919854 -254.81169) (xy 89.949419 -254.851034) (xy 89.97229 -254.894611)
			(xy 89.987874 -254.941292) (xy 89.995769 -254.989869) (xy 89.996264 -255.014476) (xy 90.314775 -255.014476)
			(xy 90.31887 -254.963748) (xy 90.331049 -254.914334) (xy 90.350997 -254.867514) (xy 90.378198 -254.8245)
			(xy 90.411946 -254.786406) (xy 90.451368 -254.754219) (xy 90.495442 -254.728773) (xy 90.543028 -254.710726)
			(xy 90.592892 -254.700546) (xy 90.643744 -254.698497) (xy 90.694265 -254.704631) (xy 90.743149 -254.718791)
			(xy 90.789128 -254.740608) (xy 90.831012 -254.769518) (xy 90.867716 -254.804773) (xy 90.898289 -254.845459)
			(xy 90.92194 -254.890522) (xy 90.938056 -254.938796) (xy 90.94622 -254.98903) (xy 90.946732 -255.014476)
			(xy 91.26526 -255.014476) (xy 91.26922 -254.965422) (xy 91.280997 -254.917638) (xy 91.300288 -254.872362)
			(xy 91.326591 -254.830766) (xy 91.359226 -254.793929) (xy 91.397347 -254.762804) (xy 91.439968 -254.738197)
			(xy 91.485984 -254.720745) (xy 91.534203 -254.710901) (xy 91.583378 -254.70892) (xy 91.632233 -254.714852)
			(xy 91.679504 -254.728544) (xy 91.723966 -254.749642) (xy 91.764469 -254.777598) (xy 91.799962 -254.81169)
			(xy 91.829527 -254.851034) (xy 91.852398 -254.894611) (xy 91.867982 -254.941292) (xy 91.875877 -254.989869)
			(xy 91.876372 -255.014476) (xy 92.194883 -255.014476) (xy 92.198978 -254.963748) (xy 92.211157 -254.914334)
			(xy 92.231105 -254.867514) (xy 92.258306 -254.8245) (xy 92.292054 -254.786406) (xy 92.331476 -254.754219)
			(xy 92.37555 -254.728773) (xy 92.423136 -254.710726) (xy 92.473 -254.700546) (xy 92.523852 -254.698497)
			(xy 92.574373 -254.704631) (xy 92.623257 -254.718791) (xy 92.669236 -254.740608) (xy 92.71112 -254.769518)
			(xy 92.747824 -254.804773) (xy 92.778397 -254.845459) (xy 92.802048 -254.890522) (xy 92.818164 -254.938796)
			(xy 92.826328 -254.98903) (xy 92.82684 -255.014476) (xy 93.145114 -255.014476) (xy 93.149074 -254.965422)
			(xy 93.160851 -254.917638) (xy 93.180142 -254.872362) (xy 93.206445 -254.830766) (xy 93.23908 -254.793929)
			(xy 93.277201 -254.762804) (xy 93.319822 -254.738197) (xy 93.365838 -254.720745) (xy 93.414057 -254.710901)
			(xy 93.463232 -254.70892) (xy 93.512087 -254.714852) (xy 93.559358 -254.728544) (xy 93.60382 -254.749642)
			(xy 93.644323 -254.777598) (xy 93.679816 -254.81169) (xy 93.709381 -254.851034) (xy 93.732252 -254.894611)
			(xy 93.747836 -254.941292) (xy 93.755731 -254.989869) (xy 93.756226 -255.014476) (xy 94.074737 -255.014476)
			(xy 94.078832 -254.963748) (xy 94.091011 -254.914334) (xy 94.110959 -254.867514) (xy 94.13816 -254.8245)
			(xy 94.171908 -254.786406) (xy 94.21133 -254.754219) (xy 94.255404 -254.728773) (xy 94.30299 -254.710726)
			(xy 94.352854 -254.700546) (xy 94.403706 -254.698497) (xy 94.454227 -254.704631) (xy 94.503111 -254.718791)
			(xy 94.54909 -254.740608) (xy 94.590974 -254.769518) (xy 94.627678 -254.804773) (xy 94.658251 -254.845459)
			(xy 94.681902 -254.890522) (xy 94.698018 -254.938796) (xy 94.706182 -254.98903) (xy 94.706694 -255.014476)
			(xy 95.014791 -255.014476) (xy 95.018886 -254.963748) (xy 95.031065 -254.914334) (xy 95.051013 -254.867514)
			(xy 95.078214 -254.8245) (xy 95.111962 -254.786406) (xy 95.151384 -254.754219) (xy 95.195458 -254.728773)
			(xy 95.243044 -254.710726) (xy 95.292908 -254.700546) (xy 95.34376 -254.698497) (xy 95.394281 -254.704631)
			(xy 95.443165 -254.718791) (xy 95.489144 -254.740608) (xy 95.531028 -254.769518) (xy 95.567732 -254.804773)
			(xy 95.598305 -254.845459) (xy 95.621956 -254.890522) (xy 95.638072 -254.938796) (xy 95.646236 -254.98903)
			(xy 95.646748 -255.014476) (xy 95.646236 -255.039922) (xy 95.638072 -255.090156) (xy 95.621956 -255.13843)
			(xy 95.598305 -255.183493) (xy 95.567732 -255.224179) (xy 95.531028 -255.259434) (xy 95.489144 -255.288344)
			(xy 95.443165 -255.310161) (xy 95.394281 -255.324321) (xy 95.34376 -255.330455) (xy 95.292908 -255.328406)
			(xy 95.243044 -255.318226) (xy 95.195458 -255.300179) (xy 95.151384 -255.274733) (xy 95.111962 -255.242546)
			(xy 95.078214 -255.204452) (xy 95.051013 -255.161438) (xy 95.031065 -255.114618) (xy 95.018886 -255.065204)
			(xy 95.014791 -255.014476) (xy 94.706694 -255.014476) (xy 94.706182 -255.039922) (xy 94.698018 -255.090156)
			(xy 94.681902 -255.13843) (xy 94.658251 -255.183493) (xy 94.627678 -255.224179) (xy 94.590974 -255.259434)
			(xy 94.54909 -255.288344) (xy 94.503111 -255.310161) (xy 94.454227 -255.324321) (xy 94.403706 -255.330455)
			(xy 94.352854 -255.328406) (xy 94.30299 -255.318226) (xy 94.255404 -255.300179) (xy 94.21133 -255.274733)
			(xy 94.171908 -255.242546) (xy 94.13816 -255.204452) (xy 94.110959 -255.161438) (xy 94.091011 -255.114618)
			(xy 94.078832 -255.065204) (xy 94.074737 -255.014476) (xy 93.756226 -255.014476) (xy 93.755731 -255.039083)
			(xy 93.747836 -255.08766) (xy 93.732252 -255.134341) (xy 93.709381 -255.177918) (xy 93.679816 -255.217262)
			(xy 93.644323 -255.251354) (xy 93.60382 -255.27931) (xy 93.559358 -255.300408) (xy 93.512087 -255.3141)
			(xy 93.463232 -255.320032) (xy 93.414057 -255.318051) (xy 93.365838 -255.308207) (xy 93.319822 -255.290755)
			(xy 93.277201 -255.266148) (xy 93.23908 -255.235023) (xy 93.206445 -255.198186) (xy 93.180142 -255.15659)
			(xy 93.160851 -255.111314) (xy 93.149074 -255.06353) (xy 93.145114 -255.014476) (xy 92.82684 -255.014476)
			(xy 92.826328 -255.039922) (xy 92.818164 -255.090156) (xy 92.802048 -255.13843) (xy 92.778397 -255.183493)
			(xy 92.747824 -255.224179) (xy 92.71112 -255.259434) (xy 92.669236 -255.288344) (xy 92.623257 -255.310161)
			(xy 92.574373 -255.324321) (xy 92.523852 -255.330455) (xy 92.473 -255.328406) (xy 92.423136 -255.318226)
			(xy 92.37555 -255.300179) (xy 92.331476 -255.274733) (xy 92.292054 -255.242546) (xy 92.258306 -255.204452)
			(xy 92.231105 -255.161438) (xy 92.211157 -255.114618) (xy 92.198978 -255.065204) (xy 92.194883 -255.014476)
			(xy 91.876372 -255.014476) (xy 91.875877 -255.039083) (xy 91.867982 -255.08766) (xy 91.852398 -255.134341)
			(xy 91.829527 -255.177918) (xy 91.799962 -255.217262) (xy 91.764469 -255.251354) (xy 91.723966 -255.27931)
			(xy 91.679504 -255.300408) (xy 91.632233 -255.3141) (xy 91.583378 -255.320032) (xy 91.534203 -255.318051)
			(xy 91.485984 -255.308207) (xy 91.439968 -255.290755) (xy 91.397347 -255.266148) (xy 91.359226 -255.235023)
			(xy 91.326591 -255.198186) (xy 91.300288 -255.15659) (xy 91.280997 -255.111314) (xy 91.26922 -255.06353)
			(xy 91.26526 -255.014476) (xy 90.946732 -255.014476) (xy 90.94622 -255.039922) (xy 90.938056 -255.090156)
			(xy 90.92194 -255.13843) (xy 90.898289 -255.183493) (xy 90.867716 -255.224179) (xy 90.831012 -255.259434)
			(xy 90.789128 -255.288344) (xy 90.743149 -255.310161) (xy 90.694265 -255.324321) (xy 90.643744 -255.330455)
			(xy 90.592892 -255.328406) (xy 90.543028 -255.318226) (xy 90.495442 -255.300179) (xy 90.451368 -255.274733)
			(xy 90.411946 -255.242546) (xy 90.378198 -255.204452) (xy 90.350997 -255.161438) (xy 90.331049 -255.114618)
			(xy 90.31887 -255.065204) (xy 90.314775 -255.014476) (xy 89.996264 -255.014476) (xy 89.995769 -255.039083)
			(xy 89.987874 -255.08766) (xy 89.97229 -255.134341) (xy 89.949419 -255.177918) (xy 89.919854 -255.217262)
			(xy 89.884361 -255.251354) (xy 89.843858 -255.27931) (xy 89.799396 -255.300408) (xy 89.752125 -255.3141)
			(xy 89.70327 -255.320032) (xy 89.654095 -255.318051) (xy 89.605876 -255.308207) (xy 89.55986 -255.290755)
			(xy 89.517239 -255.266148) (xy 89.479118 -255.235023) (xy 89.446483 -255.198186) (xy 89.42018 -255.15659)
			(xy 89.400889 -255.111314) (xy 89.389112 -255.06353) (xy 89.385152 -255.014476) (xy 89.056464 -255.014476)
			(xy 89.055969 -255.039083) (xy 89.048074 -255.08766) (xy 89.03249 -255.134341) (xy 89.009619 -255.177918)
			(xy 88.980054 -255.217262) (xy 88.944561 -255.251354) (xy 88.904058 -255.27931) (xy 88.859596 -255.300408)
			(xy 88.812325 -255.3141) (xy 88.76347 -255.320032) (xy 88.714295 -255.318051) (xy 88.666076 -255.308207)
			(xy 88.62006 -255.290755) (xy 88.577439 -255.266148) (xy 88.539318 -255.235023) (xy 88.506683 -255.198186)
			(xy 88.48038 -255.15659) (xy 88.461089 -255.111314) (xy 88.449312 -255.06353) (xy 88.445352 -255.014476)
			(xy 88.11641 -255.014476) (xy 88.115915 -255.039083) (xy 88.10802 -255.08766) (xy 88.092436 -255.134341)
			(xy 88.069565 -255.177918) (xy 88.04 -255.217262) (xy 88.004507 -255.251354) (xy 87.964004 -255.27931)
			(xy 87.919542 -255.300408) (xy 87.872271 -255.3141) (xy 87.823416 -255.320032) (xy 87.774241 -255.318051)
			(xy 87.726022 -255.308207) (xy 87.680006 -255.290755) (xy 87.637385 -255.266148) (xy 87.599264 -255.235023)
			(xy 87.566629 -255.198186) (xy 87.540326 -255.15659) (xy 87.521035 -255.111314) (xy 87.509258 -255.06353)
			(xy 87.505298 -255.014476) (xy 87.176356 -255.014476) (xy 87.175861 -255.039083) (xy 87.167966 -255.08766)
			(xy 87.152382 -255.134341) (xy 87.129511 -255.177918) (xy 87.099946 -255.217262) (xy 87.064453 -255.251354)
			(xy 87.02395 -255.27931) (xy 86.979488 -255.300408) (xy 86.932217 -255.3141) (xy 86.883362 -255.320032)
			(xy 86.834187 -255.318051) (xy 86.785968 -255.308207) (xy 86.739952 -255.290755) (xy 86.697331 -255.266148)
			(xy 86.65921 -255.235023) (xy 86.626575 -255.198186) (xy 86.600272 -255.15659) (xy 86.580981 -255.111314)
			(xy 86.569204 -255.06353) (xy 86.565244 -255.014476) (xy 86.236302 -255.014476) (xy 86.235807 -255.039083)
			(xy 86.227912 -255.08766) (xy 86.212328 -255.134341) (xy 86.189457 -255.177918) (xy 86.159892 -255.217262)
			(xy 86.124399 -255.251354) (xy 86.083896 -255.27931) (xy 86.039434 -255.300408) (xy 85.992163 -255.3141)
			(xy 85.943308 -255.320032) (xy 85.894133 -255.318051) (xy 85.845914 -255.308207) (xy 85.799898 -255.290755)
			(xy 85.757277 -255.266148) (xy 85.719156 -255.235023) (xy 85.686521 -255.198186) (xy 85.660218 -255.15659)
			(xy 85.640927 -255.111314) (xy 85.62915 -255.06353) (xy 85.62519 -255.014476) (xy 85.296248 -255.014476)
			(xy 85.295753 -255.039083) (xy 85.287858 -255.08766) (xy 85.272274 -255.134341) (xy 85.249403 -255.177918)
			(xy 85.219838 -255.217262) (xy 85.184345 -255.251354) (xy 85.143842 -255.27931) (xy 85.09938 -255.300408)
			(xy 85.052109 -255.3141) (xy 85.003254 -255.320032) (xy 84.954079 -255.318051) (xy 84.90586 -255.308207)
			(xy 84.859844 -255.290755) (xy 84.817223 -255.266148) (xy 84.779102 -255.235023) (xy 84.746467 -255.198186)
			(xy 84.720164 -255.15659) (xy 84.700873 -255.111314) (xy 84.689096 -255.06353) (xy 84.685136 -255.014476)
			(xy 84.356448 -255.014476) (xy 84.355953 -255.039083) (xy 84.348058 -255.08766) (xy 84.332474 -255.134341)
			(xy 84.309603 -255.177918) (xy 84.280038 -255.217262) (xy 84.244545 -255.251354) (xy 84.204042 -255.27931)
			(xy 84.15958 -255.300408) (xy 84.112309 -255.3141) (xy 84.063454 -255.320032) (xy 84.014279 -255.318051)
			(xy 83.96606 -255.308207) (xy 83.920044 -255.290755) (xy 83.877423 -255.266148) (xy 83.839302 -255.235023)
			(xy 83.806667 -255.198186) (xy 83.780364 -255.15659) (xy 83.761073 -255.111314) (xy 83.749296 -255.06353)
			(xy 83.745336 -255.014476) (xy 83.49488 -255.014476) (xy 83.49488 -255.3716) (xy 83.49497 -255.376151)
			(xy 83.496631 -255.3851) (xy 83.498182 -255.38938) (xy 83.501738 -255.398778) (xy 83.537298 -255.438148)
			(xy 83.552792 -255.45542) (xy 83.559904 -255.46177) (xy 83.561936 -255.46304) (xy 83.567778 -255.466596)
			(xy 83.576414 -255.47066) (xy 83.585558 -255.471676) (xy 83.585812 -255.471676) (xy 83.609411 -255.474413)
			(xy 83.655417 -255.486252) (xy 83.699035 -255.505072) (xy 83.739214 -255.530418) (xy 83.774984 -255.561678)
			(xy 83.805483 -255.5981) (xy 83.829976 -255.638804) (xy 83.839304 -255.660652) (xy 83.84286 -255.667256)
			(xy 83.843114 -255.667764) (xy 83.856644 -255.691645) (xy 83.875897 -255.743038) (xy 83.885673 -255.797041)
			(xy 83.886294 -255.824482) (xy 84.215236 -255.824482) (xy 84.219196 -255.775428) (xy 84.230973 -255.727644)
			(xy 84.250264 -255.682368) (xy 84.276567 -255.640772) (xy 84.309202 -255.603935) (xy 84.347323 -255.57281)
			(xy 84.389944 -255.548203) (xy 84.43596 -255.530751) (xy 84.484179 -255.520907) (xy 84.533354 -255.518926)
			(xy 84.582209 -255.524858) (xy 84.62948 -255.53855) (xy 84.673942 -255.559648) (xy 84.714445 -255.587604)
			(xy 84.749938 -255.621696) (xy 84.779503 -255.66104) (xy 84.802374 -255.704617) (xy 84.817958 -255.751298)
			(xy 84.825853 -255.799875) (xy 84.826348 -255.824482) (xy 85.15529 -255.824482) (xy 85.15925 -255.775428)
			(xy 85.171027 -255.727644) (xy 85.190318 -255.682368) (xy 85.216621 -255.640772) (xy 85.249256 -255.603935)
			(xy 85.287377 -255.57281) (xy 85.329998 -255.548203) (xy 85.376014 -255.530751) (xy 85.424233 -255.520907)
			(xy 85.473408 -255.518926) (xy 85.522263 -255.524858) (xy 85.569534 -255.53855) (xy 85.613996 -255.559648)
			(xy 85.654499 -255.587604) (xy 85.689992 -255.621696) (xy 85.719557 -255.66104) (xy 85.742428 -255.704617)
			(xy 85.758012 -255.751298) (xy 85.765907 -255.799875) (xy 85.766402 -255.824482) (xy 86.095344 -255.824482)
			(xy 86.099304 -255.775428) (xy 86.111081 -255.727644) (xy 86.130372 -255.682368) (xy 86.156675 -255.640772)
			(xy 86.18931 -255.603935) (xy 86.227431 -255.57281) (xy 86.270052 -255.548203) (xy 86.316068 -255.530751)
			(xy 86.364287 -255.520907) (xy 86.413462 -255.518926) (xy 86.462317 -255.524858) (xy 86.509588 -255.53855)
			(xy 86.55405 -255.559648) (xy 86.594553 -255.587604) (xy 86.630046 -255.621696) (xy 86.659611 -255.66104)
			(xy 86.682482 -255.704617) (xy 86.698066 -255.751298) (xy 86.705961 -255.799875) (xy 86.706456 -255.824482)
			(xy 87.035144 -255.824482) (xy 87.039104 -255.775428) (xy 87.050881 -255.727644) (xy 87.070172 -255.682368)
			(xy 87.096475 -255.640772) (xy 87.12911 -255.603935) (xy 87.167231 -255.57281) (xy 87.209852 -255.548203)
			(xy 87.255868 -255.530751) (xy 87.304087 -255.520907) (xy 87.353262 -255.518926) (xy 87.402117 -255.524858)
			(xy 87.449388 -255.53855) (xy 87.49385 -255.559648) (xy 87.534353 -255.587604) (xy 87.569846 -255.621696)
			(xy 87.599411 -255.66104) (xy 87.622282 -255.704617) (xy 87.637866 -255.751298) (xy 87.645761 -255.799875)
			(xy 87.646256 -255.824482) (xy 87.975198 -255.824482) (xy 87.979158 -255.775428) (xy 87.990935 -255.727644)
			(xy 88.010226 -255.682368) (xy 88.036529 -255.640772) (xy 88.069164 -255.603935) (xy 88.107285 -255.57281)
			(xy 88.149906 -255.548203) (xy 88.195922 -255.530751) (xy 88.244141 -255.520907) (xy 88.293316 -255.518926)
			(xy 88.342171 -255.524858) (xy 88.389442 -255.53855) (xy 88.433904 -255.559648) (xy 88.474407 -255.587604)
			(xy 88.5099 -255.621696) (xy 88.539465 -255.66104) (xy 88.562336 -255.704617) (xy 88.57792 -255.751298)
			(xy 88.585815 -255.799875) (xy 88.58631 -255.824482) (xy 88.915252 -255.824482) (xy 88.919212 -255.775428)
			(xy 88.930989 -255.727644) (xy 88.95028 -255.682368) (xy 88.976583 -255.640772) (xy 89.009218 -255.603935)
			(xy 89.047339 -255.57281) (xy 89.08996 -255.548203) (xy 89.135976 -255.530751) (xy 89.184195 -255.520907)
			(xy 89.23337 -255.518926) (xy 89.282225 -255.524858) (xy 89.329496 -255.53855) (xy 89.373958 -255.559648)
			(xy 89.414461 -255.587604) (xy 89.449954 -255.621696) (xy 89.479519 -255.66104) (xy 89.50239 -255.704617)
			(xy 89.517974 -255.751298) (xy 89.525869 -255.799875) (xy 89.526364 -255.824482) (xy 89.855306 -255.824482)
			(xy 89.859266 -255.775428) (xy 89.871043 -255.727644) (xy 89.890334 -255.682368) (xy 89.916637 -255.640772)
			(xy 89.949272 -255.603935) (xy 89.987393 -255.57281) (xy 90.030014 -255.548203) (xy 90.07603 -255.530751)
			(xy 90.124249 -255.520907) (xy 90.173424 -255.518926) (xy 90.222279 -255.524858) (xy 90.26955 -255.53855)
			(xy 90.314012 -255.559648) (xy 90.354515 -255.587604) (xy 90.390008 -255.621696) (xy 90.419573 -255.66104)
			(xy 90.442444 -255.704617) (xy 90.458028 -255.751298) (xy 90.465923 -255.799875) (xy 90.466418 -255.824482)
			(xy 90.784675 -255.824482) (xy 90.78877 -255.773754) (xy 90.800949 -255.72434) (xy 90.820897 -255.67752)
			(xy 90.848098 -255.634506) (xy 90.881846 -255.596412) (xy 90.921268 -255.564225) (xy 90.965342 -255.538779)
			(xy 91.012928 -255.520732) (xy 91.062792 -255.510552) (xy 91.113644 -255.508503) (xy 91.164165 -255.514637)
			(xy 91.213049 -255.528797) (xy 91.259028 -255.550614) (xy 91.300912 -255.579524) (xy 91.337616 -255.614779)
			(xy 91.368189 -255.655465) (xy 91.39184 -255.700528) (xy 91.407956 -255.748802) (xy 91.41612 -255.799036)
			(xy 91.416632 -255.824482) (xy 91.724729 -255.824482) (xy 91.728824 -255.773754) (xy 91.741003 -255.72434)
			(xy 91.760951 -255.67752) (xy 91.788152 -255.634506) (xy 91.8219 -255.596412) (xy 91.861322 -255.564225)
			(xy 91.905396 -255.538779) (xy 91.952982 -255.520732) (xy 92.002846 -255.510552) (xy 92.053698 -255.508503)
			(xy 92.104219 -255.514637) (xy 92.153103 -255.528797) (xy 92.199082 -255.550614) (xy 92.240966 -255.579524)
			(xy 92.27767 -255.614779) (xy 92.308243 -255.655465) (xy 92.331894 -255.700528) (xy 92.34801 -255.748802)
			(xy 92.356174 -255.799036) (xy 92.356686 -255.824482) (xy 92.675214 -255.824482) (xy 92.679174 -255.775428)
			(xy 92.690951 -255.727644) (xy 92.710242 -255.682368) (xy 92.736545 -255.640772) (xy 92.76918 -255.603935)
			(xy 92.807301 -255.57281) (xy 92.849922 -255.548203) (xy 92.895938 -255.530751) (xy 92.944157 -255.520907)
			(xy 92.993332 -255.518926) (xy 93.042187 -255.524858) (xy 93.089458 -255.53855) (xy 93.13392 -255.559648)
			(xy 93.174423 -255.587604) (xy 93.209916 -255.621696) (xy 93.239481 -255.66104) (xy 93.262352 -255.704617)
			(xy 93.277936 -255.751298) (xy 93.285831 -255.799875) (xy 93.286326 -255.824482) (xy 93.604837 -255.824482)
			(xy 93.608932 -255.773754) (xy 93.621111 -255.72434) (xy 93.641059 -255.67752) (xy 93.66826 -255.634506)
			(xy 93.702008 -255.596412) (xy 93.74143 -255.564225) (xy 93.785504 -255.538779) (xy 93.83309 -255.520732)
			(xy 93.882954 -255.510552) (xy 93.933806 -255.508503) (xy 93.984327 -255.514637) (xy 94.033211 -255.528797)
			(xy 94.07919 -255.550614) (xy 94.121074 -255.579524) (xy 94.157778 -255.614779) (xy 94.188351 -255.655465)
			(xy 94.212002 -255.700528) (xy 94.228118 -255.748802) (xy 94.236282 -255.799036) (xy 94.236794 -255.824482)
			(xy 94.555322 -255.824482) (xy 94.559282 -255.775428) (xy 94.571059 -255.727644) (xy 94.59035 -255.682368)
			(xy 94.616653 -255.640772) (xy 94.649288 -255.603935) (xy 94.687409 -255.57281) (xy 94.73003 -255.548203)
			(xy 94.776046 -255.530751) (xy 94.824265 -255.520907) (xy 94.87344 -255.518926) (xy 94.922295 -255.524858)
			(xy 94.969566 -255.53855) (xy 95.014028 -255.559648) (xy 95.054531 -255.587604) (xy 95.090024 -255.621696)
			(xy 95.119589 -255.66104) (xy 95.14246 -255.704617) (xy 95.158044 -255.751298) (xy 95.165939 -255.799875)
			(xy 95.166434 -255.824482) (xy 95.165939 -255.849089) (xy 95.158044 -255.897666) (xy 95.14246 -255.944347)
			(xy 95.119589 -255.987924) (xy 95.090024 -256.027268) (xy 95.054531 -256.06136) (xy 95.014028 -256.089316)
			(xy 94.969566 -256.110414) (xy 94.922295 -256.124106) (xy 94.87344 -256.130038) (xy 94.824265 -256.128057)
			(xy 94.776046 -256.118213) (xy 94.73003 -256.100761) (xy 94.687409 -256.076154) (xy 94.649288 -256.045029)
			(xy 94.616653 -256.008192) (xy 94.59035 -255.966596) (xy 94.571059 -255.92132) (xy 94.559282 -255.873536)
			(xy 94.555322 -255.824482) (xy 94.236794 -255.824482) (xy 94.236282 -255.849928) (xy 94.228118 -255.900162)
			(xy 94.212002 -255.948436) (xy 94.188351 -255.993499) (xy 94.157778 -256.034185) (xy 94.121074 -256.06944)
			(xy 94.07919 -256.09835) (xy 94.033211 -256.120167) (xy 93.984327 -256.134327) (xy 93.933806 -256.140461)
			(xy 93.882954 -256.138412) (xy 93.83309 -256.128232) (xy 93.785504 -256.110185) (xy 93.74143 -256.084739)
			(xy 93.702008 -256.052552) (xy 93.66826 -256.014458) (xy 93.641059 -255.971444) (xy 93.621111 -255.924624)
			(xy 93.608932 -255.87521) (xy 93.604837 -255.824482) (xy 93.286326 -255.824482) (xy 93.285831 -255.849089)
			(xy 93.277936 -255.897666) (xy 93.262352 -255.944347) (xy 93.239481 -255.987924) (xy 93.209916 -256.027268)
			(xy 93.174423 -256.06136) (xy 93.13392 -256.089316) (xy 93.089458 -256.110414) (xy 93.042187 -256.124106)
			(xy 92.993332 -256.130038) (xy 92.944157 -256.128057) (xy 92.895938 -256.118213) (xy 92.849922 -256.100761)
			(xy 92.807301 -256.076154) (xy 92.76918 -256.045029) (xy 92.736545 -256.008192) (xy 92.710242 -255.966596)
			(xy 92.690951 -255.92132) (xy 92.679174 -255.873536) (xy 92.675214 -255.824482) (xy 92.356686 -255.824482)
			(xy 92.356174 -255.849928) (xy 92.34801 -255.900162) (xy 92.331894 -255.948436) (xy 92.308243 -255.993499)
			(xy 92.27767 -256.034185) (xy 92.240966 -256.06944) (xy 92.199082 -256.09835) (xy 92.153103 -256.120167)
			(xy 92.104219 -256.134327) (xy 92.053698 -256.140461) (xy 92.002846 -256.138412) (xy 91.952982 -256.128232)
			(xy 91.905396 -256.110185) (xy 91.861322 -256.084739) (xy 91.8219 -256.052552) (xy 91.788152 -256.014458)
			(xy 91.760951 -255.971444) (xy 91.741003 -255.924624) (xy 91.728824 -255.87521) (xy 91.724729 -255.824482)
			(xy 91.416632 -255.824482) (xy 91.41612 -255.849928) (xy 91.407956 -255.900162) (xy 91.39184 -255.948436)
			(xy 91.368189 -255.993499) (xy 91.337616 -256.034185) (xy 91.300912 -256.06944) (xy 91.259028 -256.09835)
			(xy 91.213049 -256.120167) (xy 91.164165 -256.134327) (xy 91.113644 -256.140461) (xy 91.062792 -256.138412)
			(xy 91.012928 -256.128232) (xy 90.965342 -256.110185) (xy 90.921268 -256.084739) (xy 90.881846 -256.052552)
			(xy 90.848098 -256.014458) (xy 90.820897 -255.971444) (xy 90.800949 -255.924624) (xy 90.78877 -255.87521)
			(xy 90.784675 -255.824482) (xy 90.466418 -255.824482) (xy 90.465923 -255.849089) (xy 90.458028 -255.897666)
			(xy 90.442444 -255.944347) (xy 90.419573 -255.987924) (xy 90.390008 -256.027268) (xy 90.354515 -256.06136)
			(xy 90.314012 -256.089316) (xy 90.26955 -256.110414) (xy 90.222279 -256.124106) (xy 90.173424 -256.130038)
			(xy 90.124249 -256.128057) (xy 90.07603 -256.118213) (xy 90.030014 -256.100761) (xy 89.987393 -256.076154)
			(xy 89.949272 -256.045029) (xy 89.916637 -256.008192) (xy 89.890334 -255.966596) (xy 89.871043 -255.92132)
			(xy 89.859266 -255.873536) (xy 89.855306 -255.824482) (xy 89.526364 -255.824482) (xy 89.525869 -255.849089)
			(xy 89.517974 -255.897666) (xy 89.50239 -255.944347) (xy 89.479519 -255.987924) (xy 89.449954 -256.027268)
			(xy 89.414461 -256.06136) (xy 89.373958 -256.089316) (xy 89.329496 -256.110414) (xy 89.282225 -256.124106)
			(xy 89.23337 -256.130038) (xy 89.184195 -256.128057) (xy 89.135976 -256.118213) (xy 89.08996 -256.100761)
			(xy 89.047339 -256.076154) (xy 89.009218 -256.045029) (xy 88.976583 -256.008192) (xy 88.95028 -255.966596)
			(xy 88.930989 -255.92132) (xy 88.919212 -255.873536) (xy 88.915252 -255.824482) (xy 88.58631 -255.824482)
			(xy 88.585815 -255.849089) (xy 88.57792 -255.897666) (xy 88.562336 -255.944347) (xy 88.539465 -255.987924)
			(xy 88.5099 -256.027268) (xy 88.474407 -256.06136) (xy 88.433904 -256.089316) (xy 88.389442 -256.110414)
			(xy 88.342171 -256.124106) (xy 88.293316 -256.130038) (xy 88.244141 -256.128057) (xy 88.195922 -256.118213)
			(xy 88.149906 -256.100761) (xy 88.107285 -256.076154) (xy 88.069164 -256.045029) (xy 88.036529 -256.008192)
			(xy 88.010226 -255.966596) (xy 87.990935 -255.92132) (xy 87.979158 -255.873536) (xy 87.975198 -255.824482)
			(xy 87.646256 -255.824482) (xy 87.645761 -255.849089) (xy 87.637866 -255.897666) (xy 87.622282 -255.944347)
			(xy 87.599411 -255.987924) (xy 87.569846 -256.027268) (xy 87.534353 -256.06136) (xy 87.49385 -256.089316)
			(xy 87.449388 -256.110414) (xy 87.402117 -256.124106) (xy 87.353262 -256.130038) (xy 87.304087 -256.128057)
			(xy 87.255868 -256.118213) (xy 87.209852 -256.100761) (xy 87.167231 -256.076154) (xy 87.12911 -256.045029)
			(xy 87.096475 -256.008192) (xy 87.070172 -255.966596) (xy 87.050881 -255.92132) (xy 87.039104 -255.873536)
			(xy 87.035144 -255.824482) (xy 86.706456 -255.824482) (xy 86.705961 -255.849089) (xy 86.698066 -255.897666)
			(xy 86.682482 -255.944347) (xy 86.659611 -255.987924) (xy 86.630046 -256.027268) (xy 86.594553 -256.06136)
			(xy 86.55405 -256.089316) (xy 86.509588 -256.110414) (xy 86.462317 -256.124106) (xy 86.413462 -256.130038)
			(xy 86.364287 -256.128057) (xy 86.316068 -256.118213) (xy 86.270052 -256.100761) (xy 86.227431 -256.076154)
			(xy 86.18931 -256.045029) (xy 86.156675 -256.008192) (xy 86.130372 -255.966596) (xy 86.111081 -255.92132)
			(xy 86.099304 -255.873536) (xy 86.095344 -255.824482) (xy 85.766402 -255.824482) (xy 85.765907 -255.849089)
			(xy 85.758012 -255.897666) (xy 85.742428 -255.944347) (xy 85.719557 -255.987924) (xy 85.689992 -256.027268)
			(xy 85.654499 -256.06136) (xy 85.613996 -256.089316) (xy 85.569534 -256.110414) (xy 85.522263 -256.124106)
			(xy 85.473408 -256.130038) (xy 85.424233 -256.128057) (xy 85.376014 -256.118213) (xy 85.329998 -256.100761)
			(xy 85.287377 -256.076154) (xy 85.249256 -256.045029) (xy 85.216621 -256.008192) (xy 85.190318 -255.966596)
			(xy 85.171027 -255.92132) (xy 85.15925 -255.873536) (xy 85.15529 -255.824482) (xy 84.826348 -255.824482)
			(xy 84.825853 -255.849089) (xy 84.817958 -255.897666) (xy 84.802374 -255.944347) (xy 84.779503 -255.987924)
			(xy 84.749938 -256.027268) (xy 84.714445 -256.06136) (xy 84.673942 -256.089316) (xy 84.62948 -256.110414)
			(xy 84.582209 -256.124106) (xy 84.533354 -256.130038) (xy 84.484179 -256.128057) (xy 84.43596 -256.118213)
			(xy 84.389944 -256.100761) (xy 84.347323 -256.076154) (xy 84.309202 -256.045029) (xy 84.276567 -256.008192)
			(xy 84.250264 -255.966596) (xy 84.230973 -255.92132) (xy 84.219196 -255.873536) (xy 84.215236 -255.824482)
			(xy 83.886294 -255.824482) (xy 83.885849 -255.848476) (xy 83.878345 -255.895873) (xy 83.863517 -255.941512)
			(xy 83.841733 -255.984269) (xy 83.813527 -256.023092) (xy 83.779595 -256.057025) (xy 83.740773 -256.085231)
			(xy 83.698015 -256.107016) (xy 83.652376 -256.121844) (xy 83.60498 -256.129349) (xy 83.580986 -256.12979)
			(xy 83.551268 -256.128266) (xy 83.551014 -256.128266) (xy 83.539076 -256.12725) (xy 83.528408 -256.131314)
			(xy 83.522867 -256.133622) (xy 83.512977 -256.140418) (xy 83.50885 -256.144776) (xy 83.508088 -256.145538)
			(xy 83.502223 -256.152525) (xy 83.495463 -256.169453) (xy 83.49488 -256.178558) (xy 83.49488 -256.634488)
			(xy 83.745336 -256.634488) (xy 83.749296 -256.585434) (xy 83.761073 -256.53765) (xy 83.780364 -256.492374)
			(xy 83.806667 -256.450778) (xy 83.839302 -256.413941) (xy 83.877423 -256.382816) (xy 83.920044 -256.358209)
			(xy 83.96606 -256.340757) (xy 84.014279 -256.330913) (xy 84.063454 -256.328932) (xy 84.112309 -256.334864)
			(xy 84.15958 -256.348556) (xy 84.204042 -256.369654) (xy 84.244545 -256.39761) (xy 84.280038 -256.431702)
			(xy 84.309603 -256.471046) (xy 84.332474 -256.514623) (xy 84.348058 -256.561304) (xy 84.355953 -256.609881)
			(xy 84.356448 -256.634488) (xy 84.685136 -256.634488) (xy 84.689096 -256.585434) (xy 84.700873 -256.53765)
			(xy 84.720164 -256.492374) (xy 84.746467 -256.450778) (xy 84.779102 -256.413941) (xy 84.817223 -256.382816)
			(xy 84.859844 -256.358209) (xy 84.90586 -256.340757) (xy 84.954079 -256.330913) (xy 85.003254 -256.328932)
			(xy 85.052109 -256.334864) (xy 85.09938 -256.348556) (xy 85.143842 -256.369654) (xy 85.184345 -256.39761)
			(xy 85.219838 -256.431702) (xy 85.249403 -256.471046) (xy 85.272274 -256.514623) (xy 85.287858 -256.561304)
			(xy 85.295753 -256.609881) (xy 85.296248 -256.634488) (xy 85.62519 -256.634488) (xy 85.62915 -256.585434)
			(xy 85.640927 -256.53765) (xy 85.660218 -256.492374) (xy 85.686521 -256.450778) (xy 85.719156 -256.413941)
			(xy 85.757277 -256.382816) (xy 85.799898 -256.358209) (xy 85.845914 -256.340757) (xy 85.894133 -256.330913)
			(xy 85.943308 -256.328932) (xy 85.992163 -256.334864) (xy 86.039434 -256.348556) (xy 86.083896 -256.369654)
			(xy 86.124399 -256.39761) (xy 86.159892 -256.431702) (xy 86.189457 -256.471046) (xy 86.212328 -256.514623)
			(xy 86.227912 -256.561304) (xy 86.235807 -256.609881) (xy 86.236302 -256.634488) (xy 86.565244 -256.634488)
			(xy 86.569204 -256.585434) (xy 86.580981 -256.53765) (xy 86.600272 -256.492374) (xy 86.626575 -256.450778)
			(xy 86.65921 -256.413941) (xy 86.697331 -256.382816) (xy 86.739952 -256.358209) (xy 86.785968 -256.340757)
			(xy 86.834187 -256.330913) (xy 86.883362 -256.328932) (xy 86.932217 -256.334864) (xy 86.979488 -256.348556)
			(xy 87.02395 -256.369654) (xy 87.064453 -256.39761) (xy 87.099946 -256.431702) (xy 87.129511 -256.471046)
			(xy 87.152382 -256.514623) (xy 87.167966 -256.561304) (xy 87.175861 -256.609881) (xy 87.176356 -256.634488)
			(xy 87.505298 -256.634488) (xy 87.509258 -256.585434) (xy 87.521035 -256.53765) (xy 87.540326 -256.492374)
			(xy 87.566629 -256.450778) (xy 87.599264 -256.413941) (xy 87.637385 -256.382816) (xy 87.680006 -256.358209)
			(xy 87.726022 -256.340757) (xy 87.774241 -256.330913) (xy 87.823416 -256.328932) (xy 87.872271 -256.334864)
			(xy 87.919542 -256.348556) (xy 87.964004 -256.369654) (xy 88.004507 -256.39761) (xy 88.04 -256.431702)
			(xy 88.069565 -256.471046) (xy 88.092436 -256.514623) (xy 88.10802 -256.561304) (xy 88.115915 -256.609881)
			(xy 88.11641 -256.634488) (xy 88.445352 -256.634488) (xy 88.449312 -256.585434) (xy 88.461089 -256.53765)
			(xy 88.48038 -256.492374) (xy 88.506683 -256.450778) (xy 88.539318 -256.413941) (xy 88.577439 -256.382816)
			(xy 88.62006 -256.358209) (xy 88.666076 -256.340757) (xy 88.714295 -256.330913) (xy 88.76347 -256.328932)
			(xy 88.812325 -256.334864) (xy 88.859596 -256.348556) (xy 88.904058 -256.369654) (xy 88.944561 -256.39761)
			(xy 88.980054 -256.431702) (xy 89.009619 -256.471046) (xy 89.03249 -256.514623) (xy 89.048074 -256.561304)
			(xy 89.055969 -256.609881) (xy 89.056464 -256.634488) (xy 89.385152 -256.634488) (xy 89.389112 -256.585434)
			(xy 89.400889 -256.53765) (xy 89.42018 -256.492374) (xy 89.446483 -256.450778) (xy 89.479118 -256.413941)
			(xy 89.517239 -256.382816) (xy 89.55986 -256.358209) (xy 89.605876 -256.340757) (xy 89.654095 -256.330913)
			(xy 89.70327 -256.328932) (xy 89.752125 -256.334864) (xy 89.799396 -256.348556) (xy 89.843858 -256.369654)
			(xy 89.884361 -256.39761) (xy 89.919854 -256.431702) (xy 89.949419 -256.471046) (xy 89.97229 -256.514623)
			(xy 89.987874 -256.561304) (xy 89.995769 -256.609881) (xy 89.996264 -256.634488) (xy 90.314775 -256.634488)
			(xy 90.31887 -256.58376) (xy 90.331049 -256.534346) (xy 90.350997 -256.487526) (xy 90.378198 -256.444512)
			(xy 90.411946 -256.406418) (xy 90.451368 -256.374231) (xy 90.495442 -256.348785) (xy 90.543028 -256.330738)
			(xy 90.592892 -256.320558) (xy 90.643744 -256.318509) (xy 90.694265 -256.324643) (xy 90.743149 -256.338803)
			(xy 90.789128 -256.36062) (xy 90.831012 -256.38953) (xy 90.867716 -256.424785) (xy 90.898289 -256.465471)
			(xy 90.92194 -256.510534) (xy 90.938056 -256.558808) (xy 90.94622 -256.609042) (xy 90.946732 -256.634488)
			(xy 91.26526 -256.634488) (xy 91.26922 -256.585434) (xy 91.280997 -256.53765) (xy 91.300288 -256.492374)
			(xy 91.326591 -256.450778) (xy 91.359226 -256.413941) (xy 91.397347 -256.382816) (xy 91.439968 -256.358209)
			(xy 91.485984 -256.340757) (xy 91.534203 -256.330913) (xy 91.583378 -256.328932) (xy 91.632233 -256.334864)
			(xy 91.679504 -256.348556) (xy 91.723966 -256.369654) (xy 91.764469 -256.39761) (xy 91.799962 -256.431702)
			(xy 91.829527 -256.471046) (xy 91.852398 -256.514623) (xy 91.867982 -256.561304) (xy 91.875877 -256.609881)
			(xy 91.876372 -256.634488) (xy 92.205314 -256.634488) (xy 92.209274 -256.585434) (xy 92.221051 -256.53765)
			(xy 92.240342 -256.492374) (xy 92.266645 -256.450778) (xy 92.29928 -256.413941) (xy 92.337401 -256.382816)
			(xy 92.380022 -256.358209) (xy 92.426038 -256.340757) (xy 92.474257 -256.330913) (xy 92.523432 -256.328932)
			(xy 92.572287 -256.334864) (xy 92.619558 -256.348556) (xy 92.66402 -256.369654) (xy 92.704523 -256.39761)
			(xy 92.740016 -256.431702) (xy 92.769581 -256.471046) (xy 92.792452 -256.514623) (xy 92.808036 -256.561304)
			(xy 92.815931 -256.609881) (xy 92.816426 -256.634488) (xy 93.145114 -256.634488) (xy 93.149074 -256.585434)
			(xy 93.160851 -256.53765) (xy 93.180142 -256.492374) (xy 93.206445 -256.450778) (xy 93.23908 -256.413941)
			(xy 93.277201 -256.382816) (xy 93.319822 -256.358209) (xy 93.365838 -256.340757) (xy 93.414057 -256.330913)
			(xy 93.463232 -256.328932) (xy 93.512087 -256.334864) (xy 93.559358 -256.348556) (xy 93.60382 -256.369654)
			(xy 93.644323 -256.39761) (xy 93.679816 -256.431702) (xy 93.709381 -256.471046) (xy 93.732252 -256.514623)
			(xy 93.747836 -256.561304) (xy 93.755731 -256.609881) (xy 93.756226 -256.634488) (xy 94.074737 -256.634488)
			(xy 94.078832 -256.58376) (xy 94.091011 -256.534346) (xy 94.110959 -256.487526) (xy 94.13816 -256.444512)
			(xy 94.171908 -256.406418) (xy 94.21133 -256.374231) (xy 94.255404 -256.348785) (xy 94.30299 -256.330738)
			(xy 94.352854 -256.320558) (xy 94.403706 -256.318509) (xy 94.454227 -256.324643) (xy 94.503111 -256.338803)
			(xy 94.54909 -256.36062) (xy 94.590974 -256.38953) (xy 94.627678 -256.424785) (xy 94.658251 -256.465471)
			(xy 94.681902 -256.510534) (xy 94.698018 -256.558808) (xy 94.706182 -256.609042) (xy 94.706694 -256.634488)
			(xy 95.025222 -256.634488) (xy 95.029182 -256.585434) (xy 95.040959 -256.53765) (xy 95.06025 -256.492374)
			(xy 95.086553 -256.450778) (xy 95.119188 -256.413941) (xy 95.157309 -256.382816) (xy 95.19993 -256.358209)
			(xy 95.245946 -256.340757) (xy 95.294165 -256.330913) (xy 95.34334 -256.328932) (xy 95.392195 -256.334864)
			(xy 95.439466 -256.348556) (xy 95.483928 -256.369654) (xy 95.524431 -256.39761) (xy 95.559924 -256.431702)
			(xy 95.589489 -256.471046) (xy 95.61236 -256.514623) (xy 95.627944 -256.561304) (xy 95.635839 -256.609881)
			(xy 95.636334 -256.634488) (xy 95.635839 -256.659095) (xy 95.627944 -256.707672) (xy 95.61236 -256.754353)
			(xy 95.589489 -256.79793) (xy 95.559924 -256.837274) (xy 95.524431 -256.871366) (xy 95.483928 -256.899322)
			(xy 95.439466 -256.92042) (xy 95.392195 -256.934112) (xy 95.34334 -256.940044) (xy 95.294165 -256.938063)
			(xy 95.245946 -256.928219) (xy 95.19993 -256.910767) (xy 95.157309 -256.88616) (xy 95.119188 -256.855035)
			(xy 95.086553 -256.818198) (xy 95.06025 -256.776602) (xy 95.040959 -256.731326) (xy 95.029182 -256.683542)
			(xy 95.025222 -256.634488) (xy 94.706694 -256.634488) (xy 94.706182 -256.659934) (xy 94.698018 -256.710168)
			(xy 94.681902 -256.758442) (xy 94.658251 -256.803505) (xy 94.627678 -256.844191) (xy 94.590974 -256.879446)
			(xy 94.54909 -256.908356) (xy 94.503111 -256.930173) (xy 94.454227 -256.944333) (xy 94.403706 -256.950467)
			(xy 94.352854 -256.948418) (xy 94.30299 -256.938238) (xy 94.255404 -256.920191) (xy 94.21133 -256.894745)
			(xy 94.171908 -256.862558) (xy 94.13816 -256.824464) (xy 94.110959 -256.78145) (xy 94.091011 -256.73463)
			(xy 94.078832 -256.685216) (xy 94.074737 -256.634488) (xy 93.756226 -256.634488) (xy 93.755731 -256.659095)
			(xy 93.747836 -256.707672) (xy 93.732252 -256.754353) (xy 93.709381 -256.79793) (xy 93.679816 -256.837274)
			(xy 93.644323 -256.871366) (xy 93.60382 -256.899322) (xy 93.559358 -256.92042) (xy 93.512087 -256.934112)
			(xy 93.463232 -256.940044) (xy 93.414057 -256.938063) (xy 93.365838 -256.928219) (xy 93.319822 -256.910767)
			(xy 93.277201 -256.88616) (xy 93.23908 -256.855035) (xy 93.206445 -256.818198) (xy 93.180142 -256.776602)
			(xy 93.160851 -256.731326) (xy 93.149074 -256.683542) (xy 93.145114 -256.634488) (xy 92.816426 -256.634488)
			(xy 92.815931 -256.659095) (xy 92.808036 -256.707672) (xy 92.792452 -256.754353) (xy 92.769581 -256.79793)
			(xy 92.740016 -256.837274) (xy 92.704523 -256.871366) (xy 92.66402 -256.899322) (xy 92.619558 -256.92042)
			(xy 92.572287 -256.934112) (xy 92.523432 -256.940044) (xy 92.474257 -256.938063) (xy 92.426038 -256.928219)
			(xy 92.380022 -256.910767) (xy 92.337401 -256.88616) (xy 92.29928 -256.855035) (xy 92.266645 -256.818198)
			(xy 92.240342 -256.776602) (xy 92.221051 -256.731326) (xy 92.209274 -256.683542) (xy 92.205314 -256.634488)
			(xy 91.876372 -256.634488) (xy 91.875877 -256.659095) (xy 91.867982 -256.707672) (xy 91.852398 -256.754353)
			(xy 91.829527 -256.79793) (xy 91.799962 -256.837274) (xy 91.764469 -256.871366) (xy 91.723966 -256.899322)
			(xy 91.679504 -256.92042) (xy 91.632233 -256.934112) (xy 91.583378 -256.940044) (xy 91.534203 -256.938063)
			(xy 91.485984 -256.928219) (xy 91.439968 -256.910767) (xy 91.397347 -256.88616) (xy 91.359226 -256.855035)
			(xy 91.326591 -256.818198) (xy 91.300288 -256.776602) (xy 91.280997 -256.731326) (xy 91.26922 -256.683542)
			(xy 91.26526 -256.634488) (xy 90.946732 -256.634488) (xy 90.94622 -256.659934) (xy 90.938056 -256.710168)
			(xy 90.92194 -256.758442) (xy 90.898289 -256.803505) (xy 90.867716 -256.844191) (xy 90.831012 -256.879446)
			(xy 90.789128 -256.908356) (xy 90.743149 -256.930173) (xy 90.694265 -256.944333) (xy 90.643744 -256.950467)
			(xy 90.592892 -256.948418) (xy 90.543028 -256.938238) (xy 90.495442 -256.920191) (xy 90.451368 -256.894745)
			(xy 90.411946 -256.862558) (xy 90.378198 -256.824464) (xy 90.350997 -256.78145) (xy 90.331049 -256.73463)
			(xy 90.31887 -256.685216) (xy 90.314775 -256.634488) (xy 89.996264 -256.634488) (xy 89.995769 -256.659095)
			(xy 89.987874 -256.707672) (xy 89.97229 -256.754353) (xy 89.949419 -256.79793) (xy 89.919854 -256.837274)
			(xy 89.884361 -256.871366) (xy 89.843858 -256.899322) (xy 89.799396 -256.92042) (xy 89.752125 -256.934112)
			(xy 89.70327 -256.940044) (xy 89.654095 -256.938063) (xy 89.605876 -256.928219) (xy 89.55986 -256.910767)
			(xy 89.517239 -256.88616) (xy 89.479118 -256.855035) (xy 89.446483 -256.818198) (xy 89.42018 -256.776602)
			(xy 89.400889 -256.731326) (xy 89.389112 -256.683542) (xy 89.385152 -256.634488) (xy 89.056464 -256.634488)
			(xy 89.055969 -256.659095) (xy 89.048074 -256.707672) (xy 89.03249 -256.754353) (xy 89.009619 -256.79793)
			(xy 88.980054 -256.837274) (xy 88.944561 -256.871366) (xy 88.904058 -256.899322) (xy 88.859596 -256.92042)
			(xy 88.812325 -256.934112) (xy 88.76347 -256.940044) (xy 88.714295 -256.938063) (xy 88.666076 -256.928219)
			(xy 88.62006 -256.910767) (xy 88.577439 -256.88616) (xy 88.539318 -256.855035) (xy 88.506683 -256.818198)
			(xy 88.48038 -256.776602) (xy 88.461089 -256.731326) (xy 88.449312 -256.683542) (xy 88.445352 -256.634488)
			(xy 88.11641 -256.634488) (xy 88.115915 -256.659095) (xy 88.10802 -256.707672) (xy 88.092436 -256.754353)
			(xy 88.069565 -256.79793) (xy 88.04 -256.837274) (xy 88.004507 -256.871366) (xy 87.964004 -256.899322)
			(xy 87.919542 -256.92042) (xy 87.872271 -256.934112) (xy 87.823416 -256.940044) (xy 87.774241 -256.938063)
			(xy 87.726022 -256.928219) (xy 87.680006 -256.910767) (xy 87.637385 -256.88616) (xy 87.599264 -256.855035)
			(xy 87.566629 -256.818198) (xy 87.540326 -256.776602) (xy 87.521035 -256.731326) (xy 87.509258 -256.683542)
			(xy 87.505298 -256.634488) (xy 87.176356 -256.634488) (xy 87.175861 -256.659095) (xy 87.167966 -256.707672)
			(xy 87.152382 -256.754353) (xy 87.129511 -256.79793) (xy 87.099946 -256.837274) (xy 87.064453 -256.871366)
			(xy 87.02395 -256.899322) (xy 86.979488 -256.92042) (xy 86.932217 -256.934112) (xy 86.883362 -256.940044)
			(xy 86.834187 -256.938063) (xy 86.785968 -256.928219) (xy 86.739952 -256.910767) (xy 86.697331 -256.88616)
			(xy 86.65921 -256.855035) (xy 86.626575 -256.818198) (xy 86.600272 -256.776602) (xy 86.580981 -256.731326)
			(xy 86.569204 -256.683542) (xy 86.565244 -256.634488) (xy 86.236302 -256.634488) (xy 86.235807 -256.659095)
			(xy 86.227912 -256.707672) (xy 86.212328 -256.754353) (xy 86.189457 -256.79793) (xy 86.159892 -256.837274)
			(xy 86.124399 -256.871366) (xy 86.083896 -256.899322) (xy 86.039434 -256.92042) (xy 85.992163 -256.934112)
			(xy 85.943308 -256.940044) (xy 85.894133 -256.938063) (xy 85.845914 -256.928219) (xy 85.799898 -256.910767)
			(xy 85.757277 -256.88616) (xy 85.719156 -256.855035) (xy 85.686521 -256.818198) (xy 85.660218 -256.776602)
			(xy 85.640927 -256.731326) (xy 85.62915 -256.683542) (xy 85.62519 -256.634488) (xy 85.296248 -256.634488)
			(xy 85.295753 -256.659095) (xy 85.287858 -256.707672) (xy 85.272274 -256.754353) (xy 85.249403 -256.79793)
			(xy 85.219838 -256.837274) (xy 85.184345 -256.871366) (xy 85.143842 -256.899322) (xy 85.09938 -256.92042)
			(xy 85.052109 -256.934112) (xy 85.003254 -256.940044) (xy 84.954079 -256.938063) (xy 84.90586 -256.928219)
			(xy 84.859844 -256.910767) (xy 84.817223 -256.88616) (xy 84.779102 -256.855035) (xy 84.746467 -256.818198)
			(xy 84.720164 -256.776602) (xy 84.700873 -256.731326) (xy 84.689096 -256.683542) (xy 84.685136 -256.634488)
			(xy 84.356448 -256.634488) (xy 84.355953 -256.659095) (xy 84.348058 -256.707672) (xy 84.332474 -256.754353)
			(xy 84.309603 -256.79793) (xy 84.280038 -256.837274) (xy 84.244545 -256.871366) (xy 84.204042 -256.899322)
			(xy 84.15958 -256.92042) (xy 84.112309 -256.934112) (xy 84.063454 -256.940044) (xy 84.014279 -256.938063)
			(xy 83.96606 -256.928219) (xy 83.920044 -256.910767) (xy 83.877423 -256.88616) (xy 83.839302 -256.855035)
			(xy 83.806667 -256.818198) (xy 83.780364 -256.776602) (xy 83.761073 -256.731326) (xy 83.749296 -256.683542)
			(xy 83.745336 -256.634488) (xy 83.49488 -256.634488) (xy 83.49488 -257.930396) (xy 98.711261 -257.930396)
			(xy 98.715291 -257.877898) (xy 98.727288 -257.82663) (xy 98.746971 -257.777795) (xy 98.773877 -257.732536)
			(xy 98.807377 -257.691915) (xy 98.846685 -257.656884) (xy 98.89088 -257.628264) (xy 98.938925 -257.606725)
			(xy 98.989696 -257.592773) (xy 99.042001 -257.586735) (xy 99.094615 -257.588752) (xy 99.146305 -257.598776)
			(xy 99.195858 -257.616574) (xy 99.242114 -257.641727) (xy 99.283988 -257.673646) (xy 99.3205 -257.711584)
			(xy 99.350792 -257.75465) (xy 99.374155 -257.801835) (xy 99.390041 -257.852034) (xy 99.398078 -257.90407)
			(xy 99.398582 -257.930396) (xy 100.611181 -257.930396) (xy 100.615211 -257.877898) (xy 100.627208 -257.82663)
			(xy 100.646891 -257.777795) (xy 100.673797 -257.732536) (xy 100.707297 -257.691915) (xy 100.746605 -257.656884)
			(xy 100.7908 -257.628264) (xy 100.838845 -257.606725) (xy 100.889616 -257.592773) (xy 100.941921 -257.586735)
			(xy 100.994535 -257.588752) (xy 101.046225 -257.598776) (xy 101.095778 -257.616574) (xy 101.142034 -257.641727)
			(xy 101.183908 -257.673646) (xy 101.22042 -257.711584) (xy 101.250712 -257.75465) (xy 101.274075 -257.801835)
			(xy 101.289961 -257.852034) (xy 101.297998 -257.90407) (xy 101.298502 -257.930396) (xy 102.511101 -257.930396)
			(xy 102.515131 -257.877898) (xy 102.527128 -257.82663) (xy 102.546811 -257.777795) (xy 102.573717 -257.732536)
			(xy 102.607217 -257.691915) (xy 102.646525 -257.656884) (xy 102.69072 -257.628264) (xy 102.738765 -257.606725)
			(xy 102.789536 -257.592773) (xy 102.841841 -257.586735) (xy 102.894455 -257.588752) (xy 102.946145 -257.598776)
			(xy 102.995698 -257.616574) (xy 103.041954 -257.641727) (xy 103.083828 -257.673646) (xy 103.12034 -257.711584)
			(xy 103.150632 -257.75465) (xy 103.173995 -257.801835) (xy 103.189881 -257.852034) (xy 103.197918 -257.90407)
			(xy 103.198422 -257.930396) (xy 103.197918 -257.956722) (xy 103.189881 -258.008758) (xy 103.173995 -258.058957)
			(xy 103.150632 -258.106142) (xy 103.12034 -258.149208) (xy 103.083828 -258.187146) (xy 103.041954 -258.219065)
			(xy 102.995698 -258.244218) (xy 102.946145 -258.262016) (xy 102.894455 -258.27204) (xy 102.841841 -258.274057)
			(xy 102.789536 -258.268019) (xy 102.738765 -258.254067) (xy 102.69072 -258.232528) (xy 102.646525 -258.203908)
			(xy 102.607217 -258.168877) (xy 102.573717 -258.128256) (xy 102.546811 -258.082997) (xy 102.527128 -258.034162)
			(xy 102.515131 -257.982894) (xy 102.511101 -257.930396) (xy 101.298502 -257.930396) (xy 101.297998 -257.956722)
			(xy 101.289961 -258.008758) (xy 101.274075 -258.058957) (xy 101.250712 -258.106142) (xy 101.22042 -258.149208)
			(xy 101.183908 -258.187146) (xy 101.142034 -258.219065) (xy 101.095778 -258.244218) (xy 101.046225 -258.262016)
			(xy 100.994535 -258.27204) (xy 100.941921 -258.274057) (xy 100.889616 -258.268019) (xy 100.838845 -258.254067)
			(xy 100.7908 -258.232528) (xy 100.746605 -258.203908) (xy 100.707297 -258.168877) (xy 100.673797 -258.128256)
			(xy 100.646891 -258.082997) (xy 100.627208 -258.034162) (xy 100.615211 -257.982894) (xy 100.611181 -257.930396)
			(xy 99.398582 -257.930396) (xy 99.398078 -257.956722) (xy 99.390041 -258.008758) (xy 99.374155 -258.058957)
			(xy 99.350792 -258.106142) (xy 99.3205 -258.149208) (xy 99.283988 -258.187146) (xy 99.242114 -258.219065)
			(xy 99.195858 -258.244218) (xy 99.146305 -258.262016) (xy 99.094615 -258.27204) (xy 99.042001 -258.274057)
			(xy 98.989696 -258.268019) (xy 98.938925 -258.254067) (xy 98.89088 -258.232528) (xy 98.846685 -258.203908)
			(xy 98.807377 -258.168877) (xy 98.773877 -258.128256) (xy 98.746971 -258.082997) (xy 98.727288 -258.034162)
			(xy 98.715291 -257.982894) (xy 98.711261 -257.930396) (xy 83.49488 -257.930396) (xy 83.49488 -258.38023)
			(xy 106.061259 -258.38023) (xy 106.065289 -258.327732) (xy 106.077286 -258.276464) (xy 106.096969 -258.227629)
			(xy 106.123875 -258.18237) (xy 106.157375 -258.141749) (xy 106.196683 -258.106718) (xy 106.240878 -258.078098)
			(xy 106.288923 -258.056559) (xy 106.339694 -258.042607) (xy 106.391999 -258.036569) (xy 106.444613 -258.038586)
			(xy 106.496303 -258.04861) (xy 106.545856 -258.066408) (xy 106.592112 -258.091561) (xy 106.633986 -258.12348)
			(xy 106.670498 -258.161418) (xy 106.70079 -258.204484) (xy 106.724153 -258.251669) (xy 106.740039 -258.301868)
			(xy 106.748076 -258.353904) (xy 106.74858 -258.38023) (xy 106.748076 -258.406556) (xy 106.740039 -258.458592)
			(xy 106.724153 -258.508791) (xy 106.70079 -258.555976) (xy 106.670498 -258.599042) (xy 106.633986 -258.63698)
			(xy 106.592112 -258.668899) (xy 106.545856 -258.694052) (xy 106.496303 -258.71185) (xy 106.444613 -258.721874)
			(xy 106.391999 -258.723891) (xy 106.339694 -258.717853) (xy 106.288923 -258.703901) (xy 106.240878 -258.682362)
			(xy 106.196683 -258.653742) (xy 106.157375 -258.618711) (xy 106.123875 -258.57809) (xy 106.096969 -258.532831)
			(xy 106.077286 -258.483996) (xy 106.065289 -258.432728) (xy 106.061259 -258.38023) (xy 83.49488 -258.38023)
			(xy 83.49488 -258.830318) (xy 98.711261 -258.830318) (xy 98.715291 -258.77782) (xy 98.727288 -258.726552)
			(xy 98.746971 -258.677717) (xy 98.773877 -258.632458) (xy 98.807377 -258.591837) (xy 98.846685 -258.556806)
			(xy 98.89088 -258.528186) (xy 98.938925 -258.506647) (xy 98.989696 -258.492695) (xy 99.042001 -258.486657)
			(xy 99.094615 -258.488674) (xy 99.146305 -258.498698) (xy 99.195858 -258.516496) (xy 99.242114 -258.541649)
			(xy 99.283988 -258.573568) (xy 99.3205 -258.611506) (xy 99.350792 -258.654572) (xy 99.374155 -258.701757)
			(xy 99.390041 -258.751956) (xy 99.398078 -258.803992) (xy 99.398582 -258.830318) (xy 100.611181 -258.830318)
			(xy 100.615211 -258.77782) (xy 100.627208 -258.726552) (xy 100.646891 -258.677717) (xy 100.673797 -258.632458)
			(xy 100.707297 -258.591837) (xy 100.746605 -258.556806) (xy 100.7908 -258.528186) (xy 100.838845 -258.506647)
			(xy 100.889616 -258.492695) (xy 100.941921 -258.486657) (xy 100.994535 -258.488674) (xy 101.046225 -258.498698)
			(xy 101.095778 -258.516496) (xy 101.142034 -258.541649) (xy 101.183908 -258.573568) (xy 101.22042 -258.611506)
			(xy 101.250712 -258.654572) (xy 101.274075 -258.701757) (xy 101.289961 -258.751956) (xy 101.297998 -258.803992)
			(xy 101.298502 -258.830318) (xy 102.511101 -258.830318) (xy 102.515131 -258.77782) (xy 102.527128 -258.726552)
			(xy 102.546811 -258.677717) (xy 102.573717 -258.632458) (xy 102.607217 -258.591837) (xy 102.646525 -258.556806)
			(xy 102.69072 -258.528186) (xy 102.738765 -258.506647) (xy 102.789536 -258.492695) (xy 102.841841 -258.486657)
			(xy 102.894455 -258.488674) (xy 102.946145 -258.498698) (xy 102.995698 -258.516496) (xy 103.041954 -258.541649)
			(xy 103.083828 -258.573568) (xy 103.12034 -258.611506) (xy 103.150632 -258.654572) (xy 103.173995 -258.701757)
			(xy 103.189881 -258.751956) (xy 103.197918 -258.803992) (xy 103.198422 -258.830318) (xy 103.197918 -258.856644)
			(xy 103.189881 -258.90868) (xy 103.173995 -258.958879) (xy 103.150632 -259.006064) (xy 103.12034 -259.04913)
			(xy 103.083828 -259.087068) (xy 103.041954 -259.118987) (xy 102.995698 -259.14414) (xy 102.946145 -259.161938)
			(xy 102.894455 -259.171962) (xy 102.841841 -259.173979) (xy 102.789536 -259.167941) (xy 102.738765 -259.153989)
			(xy 102.69072 -259.13245) (xy 102.646525 -259.10383) (xy 102.607217 -259.068799) (xy 102.573717 -259.028178)
			(xy 102.546811 -258.982919) (xy 102.527128 -258.934084) (xy 102.515131 -258.882816) (xy 102.511101 -258.830318)
			(xy 101.298502 -258.830318) (xy 101.297998 -258.856644) (xy 101.289961 -258.90868) (xy 101.274075 -258.958879)
			(xy 101.250712 -259.006064) (xy 101.22042 -259.04913) (xy 101.183908 -259.087068) (xy 101.142034 -259.118987)
			(xy 101.095778 -259.14414) (xy 101.046225 -259.161938) (xy 100.994535 -259.171962) (xy 100.941921 -259.173979)
			(xy 100.889616 -259.167941) (xy 100.838845 -259.153989) (xy 100.7908 -259.13245) (xy 100.746605 -259.10383)
			(xy 100.707297 -259.068799) (xy 100.673797 -259.028178) (xy 100.646891 -258.982919) (xy 100.627208 -258.934084)
			(xy 100.615211 -258.882816) (xy 100.611181 -258.830318) (xy 99.398582 -258.830318) (xy 99.398078 -258.856644)
			(xy 99.390041 -258.90868) (xy 99.374155 -258.958879) (xy 99.350792 -259.006064) (xy 99.3205 -259.04913)
			(xy 99.283988 -259.087068) (xy 99.242114 -259.118987) (xy 99.195858 -259.14414) (xy 99.146305 -259.161938)
			(xy 99.094615 -259.171962) (xy 99.042001 -259.173979) (xy 98.989696 -259.167941) (xy 98.938925 -259.153989)
			(xy 98.89088 -259.13245) (xy 98.846685 -259.10383) (xy 98.807377 -259.068799) (xy 98.773877 -259.028178)
			(xy 98.746971 -258.982919) (xy 98.727288 -258.934084) (xy 98.715291 -258.882816) (xy 98.711261 -258.830318)
			(xy 83.49488 -258.830318) (xy 83.49488 -259.330444) (xy 106.061259 -259.330444) (xy 106.065289 -259.277946)
			(xy 106.077286 -259.226678) (xy 106.096969 -259.177843) (xy 106.123875 -259.132584) (xy 106.157375 -259.091963)
			(xy 106.196683 -259.056932) (xy 106.240878 -259.028312) (xy 106.288923 -259.006773) (xy 106.339694 -258.992821)
			(xy 106.391999 -258.986783) (xy 106.444613 -258.9888) (xy 106.496303 -258.998824) (xy 106.545856 -259.016622)
			(xy 106.592112 -259.041775) (xy 106.633986 -259.073694) (xy 106.670498 -259.111632) (xy 106.70079 -259.154698)
			(xy 106.724153 -259.201883) (xy 106.740039 -259.252082) (xy 106.748076 -259.304118) (xy 106.74858 -259.330444)
			(xy 106.748076 -259.35677) (xy 106.740039 -259.408806) (xy 106.724153 -259.459005) (xy 106.70079 -259.50619)
			(xy 106.670498 -259.549256) (xy 106.633986 -259.587194) (xy 106.592112 -259.619113) (xy 106.545856 -259.644266)
			(xy 106.496303 -259.662064) (xy 106.444613 -259.672088) (xy 106.391999 -259.674105) (xy 106.339694 -259.668067)
			(xy 106.288923 -259.654115) (xy 106.240878 -259.632576) (xy 106.196683 -259.603956) (xy 106.157375 -259.568925)
			(xy 106.123875 -259.528304) (xy 106.096969 -259.483045) (xy 106.077286 -259.43421) (xy 106.065289 -259.382942)
			(xy 106.061259 -259.330444) (xy 83.49488 -259.330444) (xy 83.49488 -259.73024) (xy 98.711261 -259.73024)
			(xy 98.715291 -259.677742) (xy 98.727288 -259.626474) (xy 98.746971 -259.577639) (xy 98.773877 -259.53238)
			(xy 98.807377 -259.491759) (xy 98.846685 -259.456728) (xy 98.89088 -259.428108) (xy 98.938925 -259.406569)
			(xy 98.989696 -259.392617) (xy 99.042001 -259.386579) (xy 99.094615 -259.388596) (xy 99.146305 -259.39862)
			(xy 99.195858 -259.416418) (xy 99.242114 -259.441571) (xy 99.283988 -259.47349) (xy 99.3205 -259.511428)
			(xy 99.350792 -259.554494) (xy 99.374155 -259.601679) (xy 99.390041 -259.651878) (xy 99.398078 -259.703914)
			(xy 99.398582 -259.73024) (xy 100.611181 -259.73024) (xy 100.615211 -259.677742) (xy 100.627208 -259.626474)
			(xy 100.646891 -259.577639) (xy 100.673797 -259.53238) (xy 100.707297 -259.491759) (xy 100.746605 -259.456728)
			(xy 100.7908 -259.428108) (xy 100.838845 -259.406569) (xy 100.889616 -259.392617) (xy 100.941921 -259.386579)
			(xy 100.994535 -259.388596) (xy 101.046225 -259.39862) (xy 101.095778 -259.416418) (xy 101.142034 -259.441571)
			(xy 101.183908 -259.47349) (xy 101.22042 -259.511428) (xy 101.250712 -259.554494) (xy 101.274075 -259.601679)
			(xy 101.289961 -259.651878) (xy 101.297998 -259.703914) (xy 101.298502 -259.73024) (xy 102.511101 -259.73024)
			(xy 102.515131 -259.677742) (xy 102.527128 -259.626474) (xy 102.546811 -259.577639) (xy 102.573717 -259.53238)
			(xy 102.607217 -259.491759) (xy 102.646525 -259.456728) (xy 102.69072 -259.428108) (xy 102.738765 -259.406569)
			(xy 102.789536 -259.392617) (xy 102.841841 -259.386579) (xy 102.894455 -259.388596) (xy 102.946145 -259.39862)
			(xy 102.995698 -259.416418) (xy 103.041954 -259.441571) (xy 103.083828 -259.47349) (xy 103.12034 -259.511428)
			(xy 103.150632 -259.554494) (xy 103.173995 -259.601679) (xy 103.189881 -259.651878) (xy 103.197918 -259.703914)
			(xy 103.198422 -259.73024) (xy 103.197918 -259.756566) (xy 103.189881 -259.808602) (xy 103.173995 -259.858801)
			(xy 103.150632 -259.905986) (xy 103.12034 -259.949052) (xy 103.083828 -259.98699) (xy 103.041954 -260.018909)
			(xy 102.995698 -260.044062) (xy 102.946145 -260.06186) (xy 102.894455 -260.071884) (xy 102.841841 -260.073901)
			(xy 102.789536 -260.067863) (xy 102.738765 -260.053911) (xy 102.69072 -260.032372) (xy 102.646525 -260.003752)
			(xy 102.607217 -259.968721) (xy 102.573717 -259.9281) (xy 102.546811 -259.882841) (xy 102.527128 -259.834006)
			(xy 102.515131 -259.782738) (xy 102.511101 -259.73024) (xy 101.298502 -259.73024) (xy 101.297998 -259.756566)
			(xy 101.289961 -259.808602) (xy 101.274075 -259.858801) (xy 101.250712 -259.905986) (xy 101.22042 -259.949052)
			(xy 101.183908 -259.98699) (xy 101.142034 -260.018909) (xy 101.095778 -260.044062) (xy 101.046225 -260.06186)
			(xy 100.994535 -260.071884) (xy 100.941921 -260.073901) (xy 100.889616 -260.067863) (xy 100.838845 -260.053911)
			(xy 100.7908 -260.032372) (xy 100.746605 -260.003752) (xy 100.707297 -259.968721) (xy 100.673797 -259.9281)
			(xy 100.646891 -259.882841) (xy 100.627208 -259.834006) (xy 100.615211 -259.782738) (xy 100.611181 -259.73024)
			(xy 99.398582 -259.73024) (xy 99.398078 -259.756566) (xy 99.390041 -259.808602) (xy 99.374155 -259.858801)
			(xy 99.350792 -259.905986) (xy 99.3205 -259.949052) (xy 99.283988 -259.98699) (xy 99.242114 -260.018909)
			(xy 99.195858 -260.044062) (xy 99.146305 -260.06186) (xy 99.094615 -260.071884) (xy 99.042001 -260.073901)
			(xy 98.989696 -260.067863) (xy 98.938925 -260.053911) (xy 98.89088 -260.032372) (xy 98.846685 -260.003752)
			(xy 98.807377 -259.968721) (xy 98.773877 -259.9281) (xy 98.746971 -259.882841) (xy 98.727288 -259.834006)
			(xy 98.715291 -259.782738) (xy 98.711261 -259.73024) (xy 83.49488 -259.73024) (xy 83.49488 -260.280404)
			(xy 106.061259 -260.280404) (xy 106.065289 -260.227906) (xy 106.077286 -260.176638) (xy 106.096969 -260.127803)
			(xy 106.123875 -260.082544) (xy 106.157375 -260.041923) (xy 106.196683 -260.006892) (xy 106.240878 -259.978272)
			(xy 106.288923 -259.956733) (xy 106.339694 -259.942781) (xy 106.391999 -259.936743) (xy 106.444613 -259.93876)
			(xy 106.496303 -259.948784) (xy 106.545856 -259.966582) (xy 106.592112 -259.991735) (xy 106.633986 -260.023654)
			(xy 106.670498 -260.061592) (xy 106.70079 -260.104658) (xy 106.724153 -260.151843) (xy 106.740039 -260.202042)
			(xy 106.748076 -260.254078) (xy 106.74858 -260.280404) (xy 106.748076 -260.30673) (xy 106.740039 -260.358766)
			(xy 106.724153 -260.408965) (xy 106.70079 -260.45615) (xy 106.670498 -260.499216) (xy 106.633986 -260.537154)
			(xy 106.592112 -260.569073) (xy 106.545856 -260.594226) (xy 106.496303 -260.612024) (xy 106.444613 -260.622048)
			(xy 106.391999 -260.624065) (xy 106.339694 -260.618027) (xy 106.288923 -260.604075) (xy 106.240878 -260.582536)
			(xy 106.196683 -260.553916) (xy 106.157375 -260.518885) (xy 106.123875 -260.478264) (xy 106.096969 -260.433005)
			(xy 106.077286 -260.38417) (xy 106.065289 -260.332902) (xy 106.061259 -260.280404) (xy 83.49488 -260.280404)
			(xy 83.49488 -260.745224) (xy 83.494915 -260.74936) (xy 83.496196 -260.757529) (xy 83.49742 -260.76148)
			(xy 83.502246 -260.77164) (xy 83.515708 -260.792722) (xy 83.519209 -260.797984) (xy 83.528334 -260.806723)
			(xy 83.533742 -260.809994) (xy 83.533996 -260.809994) (xy 83.555756 -260.822574) (xy 83.595202 -260.853718)
			(xy 83.612482 -260.87197) (xy 83.630125 -260.892168) (xy 83.65874 -260.937521) (xy 83.669378 -260.96214)
			(xy 83.672934 -260.968744) (xy 83.673188 -260.969252) (xy 83.686701 -260.993094) (xy 83.705943 -261.044402)
			(xy 83.715737 -261.098318) (xy 83.716368 -261.125716) (xy 83.716368 -261.126224) (xy 84.04531 -261.126224)
			(xy 84.04927 -261.07717) (xy 84.061047 -261.029386) (xy 84.080338 -260.98411) (xy 84.106641 -260.942514)
			(xy 84.139276 -260.905677) (xy 84.177397 -260.874552) (xy 84.220018 -260.849945) (xy 84.266034 -260.832493)
			(xy 84.314253 -260.822649) (xy 84.363428 -260.820668) (xy 84.412283 -260.8266) (xy 84.459554 -260.840292)
			(xy 84.504016 -260.86139) (xy 84.544519 -260.889346) (xy 84.580012 -260.923438) (xy 84.609577 -260.962782)
			(xy 84.632448 -261.006359) (xy 84.648032 -261.05304) (xy 84.655927 -261.101617) (xy 84.656422 -261.126224)
			(xy 84.98511 -261.126224) (xy 84.98907 -261.07717) (xy 85.000847 -261.029386) (xy 85.020138 -260.98411)
			(xy 85.046441 -260.942514) (xy 85.079076 -260.905677) (xy 85.117197 -260.874552) (xy 85.159818 -260.849945)
			(xy 85.205834 -260.832493) (xy 85.254053 -260.822649) (xy 85.303228 -260.820668) (xy 85.352083 -260.8266)
			(xy 85.399354 -260.840292) (xy 85.443816 -260.86139) (xy 85.484319 -260.889346) (xy 85.519812 -260.923438)
			(xy 85.549377 -260.962782) (xy 85.572248 -261.006359) (xy 85.587832 -261.05304) (xy 85.595727 -261.101617)
			(xy 85.596222 -261.126224) (xy 85.925164 -261.126224) (xy 85.929124 -261.07717) (xy 85.940901 -261.029386)
			(xy 85.960192 -260.98411) (xy 85.986495 -260.942514) (xy 86.01913 -260.905677) (xy 86.057251 -260.874552)
			(xy 86.099872 -260.849945) (xy 86.145888 -260.832493) (xy 86.194107 -260.822649) (xy 86.243282 -260.820668)
			(xy 86.292137 -260.8266) (xy 86.339408 -260.840292) (xy 86.38387 -260.86139) (xy 86.424373 -260.889346)
			(xy 86.459866 -260.923438) (xy 86.489431 -260.962782) (xy 86.512302 -261.006359) (xy 86.527886 -261.05304)
			(xy 86.535781 -261.101617) (xy 86.536276 -261.126224) (xy 87.805272 -261.126224) (xy 87.809232 -261.07717)
			(xy 87.821009 -261.029386) (xy 87.8403 -260.98411) (xy 87.866603 -260.942514) (xy 87.899238 -260.905677)
			(xy 87.937359 -260.874552) (xy 87.97998 -260.849945) (xy 88.025996 -260.832493) (xy 88.074215 -260.822649)
			(xy 88.12339 -260.820668) (xy 88.172245 -260.8266) (xy 88.219516 -260.840292) (xy 88.263978 -260.86139)
			(xy 88.304481 -260.889346) (xy 88.339974 -260.923438) (xy 88.369539 -260.962782) (xy 88.39241 -261.006359)
			(xy 88.407994 -261.05304) (xy 88.415889 -261.101617) (xy 88.416384 -261.126224) (xy 88.745326 -261.126224)
			(xy 88.749286 -261.07717) (xy 88.761063 -261.029386) (xy 88.780354 -260.98411) (xy 88.806657 -260.942514)
			(xy 88.839292 -260.905677) (xy 88.877413 -260.874552) (xy 88.920034 -260.849945) (xy 88.96605 -260.832493)
			(xy 89.014269 -260.822649) (xy 89.063444 -260.820668) (xy 89.112299 -260.8266) (xy 89.15957 -260.840292)
			(xy 89.204032 -260.86139) (xy 89.244535 -260.889346) (xy 89.280028 -260.923438) (xy 89.309593 -260.962782)
			(xy 89.332464 -261.006359) (xy 89.348048 -261.05304) (xy 89.355943 -261.101617) (xy 89.356438 -261.126224)
			(xy 89.685126 -261.126224) (xy 89.689086 -261.07717) (xy 89.700863 -261.029386) (xy 89.720154 -260.98411)
			(xy 89.746457 -260.942514) (xy 89.779092 -260.905677) (xy 89.817213 -260.874552) (xy 89.859834 -260.849945)
			(xy 89.90585 -260.832493) (xy 89.954069 -260.822649) (xy 90.003244 -260.820668) (xy 90.052099 -260.8266)
			(xy 90.09937 -260.840292) (xy 90.143832 -260.86139) (xy 90.184335 -260.889346) (xy 90.219828 -260.923438)
			(xy 90.249393 -260.962782) (xy 90.272264 -261.006359) (xy 90.287848 -261.05304) (xy 90.295743 -261.101617)
			(xy 90.296238 -261.126224) (xy 90.62518 -261.126224) (xy 90.62914 -261.07717) (xy 90.640917 -261.029386)
			(xy 90.660208 -260.98411) (xy 90.686511 -260.942514) (xy 90.719146 -260.905677) (xy 90.757267 -260.874552)
			(xy 90.799888 -260.849945) (xy 90.845904 -260.832493) (xy 90.894123 -260.822649) (xy 90.943298 -260.820668)
			(xy 90.992153 -260.8266) (xy 91.039424 -260.840292) (xy 91.083886 -260.86139) (xy 91.124389 -260.889346)
			(xy 91.159882 -260.923438) (xy 91.189447 -260.962782) (xy 91.212318 -261.006359) (xy 91.227902 -261.05304)
			(xy 91.235797 -261.101617) (xy 91.236292 -261.126224) (xy 91.565234 -261.126224) (xy 91.569194 -261.07717)
			(xy 91.580971 -261.029386) (xy 91.600262 -260.98411) (xy 91.626565 -260.942514) (xy 91.6592 -260.905677)
			(xy 91.697321 -260.874552) (xy 91.739942 -260.849945) (xy 91.785958 -260.832493) (xy 91.834177 -260.822649)
			(xy 91.883352 -260.820668) (xy 91.932207 -260.8266) (xy 91.979478 -260.840292) (xy 92.02394 -260.86139)
			(xy 92.064443 -260.889346) (xy 92.099936 -260.923438) (xy 92.129501 -260.962782) (xy 92.152372 -261.006359)
			(xy 92.167956 -261.05304) (xy 92.175851 -261.101617) (xy 92.176346 -261.126224) (xy 92.505288 -261.126224)
			(xy 92.509248 -261.07717) (xy 92.521025 -261.029386) (xy 92.540316 -260.98411) (xy 92.566619 -260.942514)
			(xy 92.599254 -260.905677) (xy 92.637375 -260.874552) (xy 92.679996 -260.849945) (xy 92.726012 -260.832493)
			(xy 92.774231 -260.822649) (xy 92.823406 -260.820668) (xy 92.872261 -260.8266) (xy 92.919532 -260.840292)
			(xy 92.963994 -260.86139) (xy 93.004497 -260.889346) (xy 93.03999 -260.923438) (xy 93.069555 -260.962782)
			(xy 93.092426 -261.006359) (xy 93.10801 -261.05304) (xy 93.115905 -261.101617) (xy 93.1164 -261.126224)
			(xy 94.385142 -261.126224) (xy 94.389102 -261.07717) (xy 94.400879 -261.029386) (xy 94.42017 -260.98411)
			(xy 94.446473 -260.942514) (xy 94.479108 -260.905677) (xy 94.517229 -260.874552) (xy 94.55985 -260.849945)
			(xy 94.605866 -260.832493) (xy 94.654085 -260.822649) (xy 94.70326 -260.820668) (xy 94.752115 -260.8266)
			(xy 94.799386 -260.840292) (xy 94.843848 -260.86139) (xy 94.884351 -260.889346) (xy 94.919844 -260.923438)
			(xy 94.949409 -260.962782) (xy 94.97228 -261.006359) (xy 94.987864 -261.05304) (xy 94.995759 -261.101617)
			(xy 94.996254 -261.126224) (xy 95.325196 -261.126224) (xy 95.329156 -261.07717) (xy 95.340933 -261.029386)
			(xy 95.360224 -260.98411) (xy 95.386527 -260.942514) (xy 95.419162 -260.905677) (xy 95.457283 -260.874552)
			(xy 95.499904 -260.849945) (xy 95.54592 -260.832493) (xy 95.594139 -260.822649) (xy 95.643314 -260.820668)
			(xy 95.692169 -260.8266) (xy 95.73944 -260.840292) (xy 95.783902 -260.86139) (xy 95.824405 -260.889346)
			(xy 95.859898 -260.923438) (xy 95.889463 -260.962782) (xy 95.912334 -261.006359) (xy 95.927918 -261.05304)
			(xy 95.935813 -261.101617) (xy 95.936308 -261.126224) (xy 96.26525 -261.126224) (xy 96.26921 -261.07717)
			(xy 96.280987 -261.029386) (xy 96.300278 -260.98411) (xy 96.326581 -260.942514) (xy 96.359216 -260.905677)
			(xy 96.397337 -260.874552) (xy 96.439958 -260.849945) (xy 96.485974 -260.832493) (xy 96.534193 -260.822649)
			(xy 96.583368 -260.820668) (xy 96.632223 -260.8266) (xy 96.679494 -260.840292) (xy 96.723956 -260.86139)
			(xy 96.764459 -260.889346) (xy 96.799952 -260.923438) (xy 96.829517 -260.962782) (xy 96.852388 -261.006359)
			(xy 96.867972 -261.05304) (xy 96.875867 -261.101617) (xy 96.876362 -261.126224) (xy 98.145358 -261.126224)
			(xy 98.149318 -261.07717) (xy 98.161095 -261.029386) (xy 98.180386 -260.98411) (xy 98.206689 -260.942514)
			(xy 98.239324 -260.905677) (xy 98.277445 -260.874552) (xy 98.320066 -260.849945) (xy 98.366082 -260.832493)
			(xy 98.414301 -260.822649) (xy 98.463476 -260.820668) (xy 98.512331 -260.8266) (xy 98.559602 -260.840292)
			(xy 98.604064 -260.86139) (xy 98.644567 -260.889346) (xy 98.68006 -260.923438) (xy 98.709625 -260.962782)
			(xy 98.732496 -261.006359) (xy 98.74808 -261.05304) (xy 98.755975 -261.101617) (xy 98.75647 -261.126224)
			(xy 100.025212 -261.126224) (xy 100.029172 -261.07717) (xy 100.040949 -261.029386) (xy 100.06024 -260.98411)
			(xy 100.086543 -260.942514) (xy 100.119178 -260.905677) (xy 100.157299 -260.874552) (xy 100.19992 -260.849945)
			(xy 100.245936 -260.832493) (xy 100.294155 -260.822649) (xy 100.34333 -260.820668) (xy 100.392185 -260.8266)
			(xy 100.439456 -260.840292) (xy 100.483918 -260.86139) (xy 100.524421 -260.889346) (xy 100.559914 -260.923438)
			(xy 100.589479 -260.962782) (xy 100.61235 -261.006359) (xy 100.627934 -261.05304) (xy 100.635829 -261.101617)
			(xy 100.636324 -261.126224) (xy 100.965266 -261.126224) (xy 100.969226 -261.07717) (xy 100.981003 -261.029386)
			(xy 101.000294 -260.98411) (xy 101.026597 -260.942514) (xy 101.059232 -260.905677) (xy 101.097353 -260.874552)
			(xy 101.139974 -260.849945) (xy 101.18599 -260.832493) (xy 101.234209 -260.822649) (xy 101.283384 -260.820668)
			(xy 101.332239 -260.8266) (xy 101.37951 -260.840292) (xy 101.423972 -260.86139) (xy 101.464475 -260.889346)
			(xy 101.499968 -260.923438) (xy 101.529533 -260.962782) (xy 101.552404 -261.006359) (xy 101.567988 -261.05304)
			(xy 101.575883 -261.101617) (xy 101.576378 -261.126224) (xy 101.90532 -261.126224) (xy 101.90928 -261.07717)
			(xy 101.921057 -261.029386) (xy 101.940348 -260.98411) (xy 101.966651 -260.942514) (xy 101.999286 -260.905677)
			(xy 102.037407 -260.874552) (xy 102.080028 -260.849945) (xy 102.126044 -260.832493) (xy 102.174263 -260.822649)
			(xy 102.223438 -260.820668) (xy 102.272293 -260.8266) (xy 102.319564 -260.840292) (xy 102.364026 -260.86139)
			(xy 102.404529 -260.889346) (xy 102.440022 -260.923438) (xy 102.469587 -260.962782) (xy 102.492458 -261.006359)
			(xy 102.508042 -261.05304) (xy 102.515937 -261.101617) (xy 102.516432 -261.126224) (xy 102.516391 -261.128256)
			(xy 102.842072 -261.128256) (xy 102.846032 -261.079202) (xy 102.857809 -261.031418) (xy 102.8771 -260.986142)
			(xy 102.903403 -260.944546) (xy 102.936038 -260.907709) (xy 102.974159 -260.876584) (xy 103.01678 -260.851977)
			(xy 103.062796 -260.834525) (xy 103.111015 -260.824681) (xy 103.16019 -260.8227) (xy 103.209045 -260.828632)
			(xy 103.256316 -260.842324) (xy 103.300778 -260.863422) (xy 103.341281 -260.891378) (xy 103.376774 -260.92547)
			(xy 103.406339 -260.964814) (xy 103.42921 -261.008391) (xy 103.444794 -261.055072) (xy 103.452689 -261.103649)
			(xy 103.453184 -261.128256) (xy 103.782126 -261.128256) (xy 103.786086 -261.079202) (xy 103.797863 -261.031418)
			(xy 103.817154 -260.986142) (xy 103.843457 -260.944546) (xy 103.876092 -260.907709) (xy 103.914213 -260.876584)
			(xy 103.956834 -260.851977) (xy 104.00285 -260.834525) (xy 104.051069 -260.824681) (xy 104.100244 -260.8227)
			(xy 104.149099 -260.828632) (xy 104.19637 -260.842324) (xy 104.240832 -260.863422) (xy 104.281335 -260.891378)
			(xy 104.316828 -260.92547) (xy 104.346393 -260.964814) (xy 104.369264 -261.008391) (xy 104.384848 -261.055072)
			(xy 104.392743 -261.103649) (xy 104.393238 -261.128256) (xy 104.392743 -261.152863) (xy 104.384848 -261.20144)
			(xy 104.375192 -261.230364) (xy 106.061259 -261.230364) (xy 106.065289 -261.177866) (xy 106.077286 -261.126598)
			(xy 106.096969 -261.077763) (xy 106.123875 -261.032504) (xy 106.157375 -260.991883) (xy 106.196683 -260.956852)
			(xy 106.240878 -260.928232) (xy 106.288923 -260.906693) (xy 106.339694 -260.892741) (xy 106.391999 -260.886703)
			(xy 106.444613 -260.88872) (xy 106.496303 -260.898744) (xy 106.545856 -260.916542) (xy 106.592112 -260.941695)
			(xy 106.633986 -260.973614) (xy 106.670498 -261.011552) (xy 106.70079 -261.054618) (xy 106.724153 -261.101803)
			(xy 106.740039 -261.152002) (xy 106.748076 -261.204038) (xy 106.74858 -261.230364) (xy 106.748076 -261.25669)
			(xy 106.740039 -261.308726) (xy 106.735498 -261.323074) (xy 107.304081 -261.323074) (xy 107.308111 -261.270576)
			(xy 107.320108 -261.219308) (xy 107.339791 -261.170473) (xy 107.366697 -261.125214) (xy 107.400197 -261.084593)
			(xy 107.439505 -261.049562) (xy 107.4837 -261.020942) (xy 107.531745 -260.999403) (xy 107.582516 -260.985451)
			(xy 107.634821 -260.979413) (xy 107.687435 -260.98143) (xy 107.739125 -260.991454) (xy 107.788678 -261.009252)
			(xy 107.834934 -261.034405) (xy 107.876808 -261.066324) (xy 107.91332 -261.104262) (xy 107.943612 -261.147328)
			(xy 107.966975 -261.194513) (xy 107.982861 -261.244712) (xy 107.990898 -261.296748) (xy 107.991402 -261.323074)
			(xy 107.990898 -261.3494) (xy 107.982861 -261.401436) (xy 107.966975 -261.451635) (xy 107.943612 -261.49882)
			(xy 107.91332 -261.541886) (xy 107.876808 -261.579824) (xy 107.834934 -261.611743) (xy 107.788678 -261.636896)
			(xy 107.739125 -261.654694) (xy 107.687435 -261.664718) (xy 107.634821 -261.666735) (xy 107.582516 -261.660697)
			(xy 107.531745 -261.646745) (xy 107.4837 -261.625206) (xy 107.439505 -261.596586) (xy 107.400197 -261.561555)
			(xy 107.366697 -261.520934) (xy 107.339791 -261.475675) (xy 107.320108 -261.42684) (xy 107.308111 -261.375572)
			(xy 107.304081 -261.323074) (xy 106.735498 -261.323074) (xy 106.724153 -261.358925) (xy 106.70079 -261.40611)
			(xy 106.670498 -261.449176) (xy 106.633986 -261.487114) (xy 106.592112 -261.519033) (xy 106.545856 -261.544186)
			(xy 106.496303 -261.561984) (xy 106.444613 -261.572008) (xy 106.391999 -261.574025) (xy 106.339694 -261.567987)
			(xy 106.288923 -261.554035) (xy 106.240878 -261.532496) (xy 106.196683 -261.503876) (xy 106.157375 -261.468845)
			(xy 106.123875 -261.428224) (xy 106.096969 -261.382965) (xy 106.077286 -261.33413) (xy 106.065289 -261.282862)
			(xy 106.061259 -261.230364) (xy 104.375192 -261.230364) (xy 104.369264 -261.248121) (xy 104.346393 -261.291698)
			(xy 104.316828 -261.331042) (xy 104.281335 -261.365134) (xy 104.240832 -261.39309) (xy 104.19637 -261.414188)
			(xy 104.149099 -261.42788) (xy 104.100244 -261.433812) (xy 104.051069 -261.431831) (xy 104.00285 -261.421987)
			(xy 103.956834 -261.404535) (xy 103.914213 -261.379928) (xy 103.876092 -261.348803) (xy 103.843457 -261.311966)
			(xy 103.817154 -261.27037) (xy 103.797863 -261.225094) (xy 103.786086 -261.17731) (xy 103.782126 -261.128256)
			(xy 103.453184 -261.128256) (xy 103.452689 -261.152863) (xy 103.444794 -261.20144) (xy 103.42921 -261.248121)
			(xy 103.406339 -261.291698) (xy 103.376774 -261.331042) (xy 103.341281 -261.365134) (xy 103.300778 -261.39309)
			(xy 103.256316 -261.414188) (xy 103.209045 -261.42788) (xy 103.16019 -261.433812) (xy 103.111015 -261.431831)
			(xy 103.062796 -261.421987) (xy 103.01678 -261.404535) (xy 102.974159 -261.379928) (xy 102.936038 -261.348803)
			(xy 102.903403 -261.311966) (xy 102.8771 -261.27037) (xy 102.857809 -261.225094) (xy 102.846032 -261.17731)
			(xy 102.842072 -261.128256) (xy 102.516391 -261.128256) (xy 102.515937 -261.150831) (xy 102.508042 -261.199408)
			(xy 102.492458 -261.246089) (xy 102.469587 -261.289666) (xy 102.440022 -261.32901) (xy 102.404529 -261.363102)
			(xy 102.364026 -261.391058) (xy 102.319564 -261.412156) (xy 102.272293 -261.425848) (xy 102.223438 -261.43178)
			(xy 102.174263 -261.429799) (xy 102.126044 -261.419955) (xy 102.080028 -261.402503) (xy 102.037407 -261.377896)
			(xy 101.999286 -261.346771) (xy 101.966651 -261.309934) (xy 101.940348 -261.268338) (xy 101.921057 -261.223062)
			(xy 101.90928 -261.175278) (xy 101.90532 -261.126224) (xy 101.576378 -261.126224) (xy 101.575883 -261.150831)
			(xy 101.567988 -261.199408) (xy 101.552404 -261.246089) (xy 101.529533 -261.289666) (xy 101.499968 -261.32901)
			(xy 101.464475 -261.363102) (xy 101.423972 -261.391058) (xy 101.37951 -261.412156) (xy 101.332239 -261.425848)
			(xy 101.283384 -261.43178) (xy 101.234209 -261.429799) (xy 101.18599 -261.419955) (xy 101.139974 -261.402503)
			(xy 101.097353 -261.377896) (xy 101.059232 -261.346771) (xy 101.026597 -261.309934) (xy 101.000294 -261.268338)
			(xy 100.981003 -261.223062) (xy 100.969226 -261.175278) (xy 100.965266 -261.126224) (xy 100.636324 -261.126224)
			(xy 100.635829 -261.150831) (xy 100.627934 -261.199408) (xy 100.61235 -261.246089) (xy 100.589479 -261.289666)
			(xy 100.559914 -261.32901) (xy 100.524421 -261.363102) (xy 100.483918 -261.391058) (xy 100.439456 -261.412156)
			(xy 100.392185 -261.425848) (xy 100.34333 -261.43178) (xy 100.294155 -261.429799) (xy 100.245936 -261.419955)
			(xy 100.19992 -261.402503) (xy 100.157299 -261.377896) (xy 100.119178 -261.346771) (xy 100.086543 -261.309934)
			(xy 100.06024 -261.268338) (xy 100.040949 -261.223062) (xy 100.029172 -261.175278) (xy 100.025212 -261.126224)
			(xy 98.75647 -261.126224) (xy 98.755975 -261.150831) (xy 98.74808 -261.199408) (xy 98.732496 -261.246089)
			(xy 98.709625 -261.289666) (xy 98.68006 -261.32901) (xy 98.644567 -261.363102) (xy 98.604064 -261.391058)
			(xy 98.559602 -261.412156) (xy 98.512331 -261.425848) (xy 98.463476 -261.43178) (xy 98.414301 -261.429799)
			(xy 98.366082 -261.419955) (xy 98.320066 -261.402503) (xy 98.277445 -261.377896) (xy 98.239324 -261.346771)
			(xy 98.206689 -261.309934) (xy 98.180386 -261.268338) (xy 98.161095 -261.223062) (xy 98.149318 -261.175278)
			(xy 98.145358 -261.126224) (xy 96.876362 -261.126224) (xy 96.875867 -261.150831) (xy 96.867972 -261.199408)
			(xy 96.852388 -261.246089) (xy 96.829517 -261.289666) (xy 96.799952 -261.32901) (xy 96.764459 -261.363102)
			(xy 96.723956 -261.391058) (xy 96.679494 -261.412156) (xy 96.632223 -261.425848) (xy 96.583368 -261.43178)
			(xy 96.534193 -261.429799) (xy 96.485974 -261.419955) (xy 96.439958 -261.402503) (xy 96.397337 -261.377896)
			(xy 96.359216 -261.346771) (xy 96.326581 -261.309934) (xy 96.300278 -261.268338) (xy 96.280987 -261.223062)
			(xy 96.26921 -261.175278) (xy 96.26525 -261.126224) (xy 95.936308 -261.126224) (xy 95.935813 -261.150831)
			(xy 95.927918 -261.199408) (xy 95.912334 -261.246089) (xy 95.889463 -261.289666) (xy 95.859898 -261.32901)
			(xy 95.824405 -261.363102) (xy 95.783902 -261.391058) (xy 95.73944 -261.412156) (xy 95.692169 -261.425848)
			(xy 95.643314 -261.43178) (xy 95.594139 -261.429799) (xy 95.54592 -261.419955) (xy 95.499904 -261.402503)
			(xy 95.457283 -261.377896) (xy 95.419162 -261.346771) (xy 95.386527 -261.309934) (xy 95.360224 -261.268338)
			(xy 95.340933 -261.223062) (xy 95.329156 -261.175278) (xy 95.325196 -261.126224) (xy 94.996254 -261.126224)
			(xy 94.995759 -261.150831) (xy 94.987864 -261.199408) (xy 94.97228 -261.246089) (xy 94.949409 -261.289666)
			(xy 94.919844 -261.32901) (xy 94.884351 -261.363102) (xy 94.843848 -261.391058) (xy 94.799386 -261.412156)
			(xy 94.752115 -261.425848) (xy 94.70326 -261.43178) (xy 94.654085 -261.429799) (xy 94.605866 -261.419955)
			(xy 94.55985 -261.402503) (xy 94.517229 -261.377896) (xy 94.479108 -261.346771) (xy 94.446473 -261.309934)
			(xy 94.42017 -261.268338) (xy 94.400879 -261.223062) (xy 94.389102 -261.175278) (xy 94.385142 -261.126224)
			(xy 93.1164 -261.126224) (xy 93.115905 -261.150831) (xy 93.10801 -261.199408) (xy 93.092426 -261.246089)
			(xy 93.069555 -261.289666) (xy 93.03999 -261.32901) (xy 93.004497 -261.363102) (xy 92.963994 -261.391058)
			(xy 92.919532 -261.412156) (xy 92.872261 -261.425848) (xy 92.823406 -261.43178) (xy 92.774231 -261.429799)
			(xy 92.726012 -261.419955) (xy 92.679996 -261.402503) (xy 92.637375 -261.377896) (xy 92.599254 -261.346771)
			(xy 92.566619 -261.309934) (xy 92.540316 -261.268338) (xy 92.521025 -261.223062) (xy 92.509248 -261.175278)
			(xy 92.505288 -261.126224) (xy 92.176346 -261.126224) (xy 92.175851 -261.150831) (xy 92.167956 -261.199408)
			(xy 92.152372 -261.246089) (xy 92.129501 -261.289666) (xy 92.099936 -261.32901) (xy 92.064443 -261.363102)
			(xy 92.02394 -261.391058) (xy 91.979478 -261.412156) (xy 91.932207 -261.425848) (xy 91.883352 -261.43178)
			(xy 91.834177 -261.429799) (xy 91.785958 -261.419955) (xy 91.739942 -261.402503) (xy 91.697321 -261.377896)
			(xy 91.6592 -261.346771) (xy 91.626565 -261.309934) (xy 91.600262 -261.268338) (xy 91.580971 -261.223062)
			(xy 91.569194 -261.175278) (xy 91.565234 -261.126224) (xy 91.236292 -261.126224) (xy 91.235797 -261.150831)
			(xy 91.227902 -261.199408) (xy 91.212318 -261.246089) (xy 91.189447 -261.289666) (xy 91.159882 -261.32901)
			(xy 91.124389 -261.363102) (xy 91.083886 -261.391058) (xy 91.039424 -261.412156) (xy 90.992153 -261.425848)
			(xy 90.943298 -261.43178) (xy 90.894123 -261.429799) (xy 90.845904 -261.419955) (xy 90.799888 -261.402503)
			(xy 90.757267 -261.377896) (xy 90.719146 -261.346771) (xy 90.686511 -261.309934) (xy 90.660208 -261.268338)
			(xy 90.640917 -261.223062) (xy 90.62914 -261.175278) (xy 90.62518 -261.126224) (xy 90.296238 -261.126224)
			(xy 90.295743 -261.150831) (xy 90.287848 -261.199408) (xy 90.272264 -261.246089) (xy 90.249393 -261.289666)
			(xy 90.219828 -261.32901) (xy 90.184335 -261.363102) (xy 90.143832 -261.391058) (xy 90.09937 -261.412156)
			(xy 90.052099 -261.425848) (xy 90.003244 -261.43178) (xy 89.954069 -261.429799) (xy 89.90585 -261.419955)
			(xy 89.859834 -261.402503) (xy 89.817213 -261.377896) (xy 89.779092 -261.346771) (xy 89.746457 -261.309934)
			(xy 89.720154 -261.268338) (xy 89.700863 -261.223062) (xy 89.689086 -261.175278) (xy 89.685126 -261.126224)
			(xy 89.356438 -261.126224) (xy 89.355943 -261.150831) (xy 89.348048 -261.199408) (xy 89.332464 -261.246089)
			(xy 89.309593 -261.289666) (xy 89.280028 -261.32901) (xy 89.244535 -261.363102) (xy 89.204032 -261.391058)
			(xy 89.15957 -261.412156) (xy 89.112299 -261.425848) (xy 89.063444 -261.43178) (xy 89.014269 -261.429799)
			(xy 88.96605 -261.419955) (xy 88.920034 -261.402503) (xy 88.877413 -261.377896) (xy 88.839292 -261.346771)
			(xy 88.806657 -261.309934) (xy 88.780354 -261.268338) (xy 88.761063 -261.223062) (xy 88.749286 -261.175278)
			(xy 88.745326 -261.126224) (xy 88.416384 -261.126224) (xy 88.415889 -261.150831) (xy 88.407994 -261.199408)
			(xy 88.39241 -261.246089) (xy 88.369539 -261.289666) (xy 88.339974 -261.32901) (xy 88.304481 -261.363102)
			(xy 88.263978 -261.391058) (xy 88.219516 -261.412156) (xy 88.172245 -261.425848) (xy 88.12339 -261.43178)
			(xy 88.074215 -261.429799) (xy 88.025996 -261.419955) (xy 87.97998 -261.402503) (xy 87.937359 -261.377896)
			(xy 87.899238 -261.346771) (xy 87.866603 -261.309934) (xy 87.8403 -261.268338) (xy 87.821009 -261.223062)
			(xy 87.809232 -261.175278) (xy 87.805272 -261.126224) (xy 86.536276 -261.126224) (xy 86.535781 -261.150831)
			(xy 86.527886 -261.199408) (xy 86.512302 -261.246089) (xy 86.489431 -261.289666) (xy 86.459866 -261.32901)
			(xy 86.424373 -261.363102) (xy 86.38387 -261.391058) (xy 86.339408 -261.412156) (xy 86.292137 -261.425848)
			(xy 86.243282 -261.43178) (xy 86.194107 -261.429799) (xy 86.145888 -261.419955) (xy 86.099872 -261.402503)
			(xy 86.057251 -261.377896) (xy 86.01913 -261.346771) (xy 85.986495 -261.309934) (xy 85.960192 -261.268338)
			(xy 85.940901 -261.223062) (xy 85.929124 -261.175278) (xy 85.925164 -261.126224) (xy 85.596222 -261.126224)
			(xy 85.595727 -261.150831) (xy 85.587832 -261.199408) (xy 85.572248 -261.246089) (xy 85.549377 -261.289666)
			(xy 85.519812 -261.32901) (xy 85.484319 -261.363102) (xy 85.443816 -261.391058) (xy 85.399354 -261.412156)
			(xy 85.352083 -261.425848) (xy 85.303228 -261.43178) (xy 85.254053 -261.429799) (xy 85.205834 -261.419955)
			(xy 85.159818 -261.402503) (xy 85.117197 -261.377896) (xy 85.079076 -261.346771) (xy 85.046441 -261.309934)
			(xy 85.020138 -261.268338) (xy 85.000847 -261.223062) (xy 84.98907 -261.175278) (xy 84.98511 -261.126224)
			(xy 84.656422 -261.126224) (xy 84.655927 -261.150831) (xy 84.648032 -261.199408) (xy 84.632448 -261.246089)
			(xy 84.609577 -261.289666) (xy 84.580012 -261.32901) (xy 84.544519 -261.363102) (xy 84.504016 -261.391058)
			(xy 84.459554 -261.412156) (xy 84.412283 -261.425848) (xy 84.363428 -261.43178) (xy 84.314253 -261.429799)
			(xy 84.266034 -261.419955) (xy 84.220018 -261.402503) (xy 84.177397 -261.377896) (xy 84.139276 -261.346771)
			(xy 84.106641 -261.309934) (xy 84.080338 -261.268338) (xy 84.061047 -261.223062) (xy 84.04927 -261.175278)
			(xy 84.04531 -261.126224) (xy 83.716368 -261.126224) (xy 83.716368 -261.132066) (xy 83.715352 -261.157758)
			(xy 83.705782 -261.208273) (xy 83.687884 -261.25647) (xy 83.662163 -261.300987) (xy 83.629348 -261.340565)
			(xy 83.590365 -261.374086) (xy 83.546317 -261.400602) (xy 83.522566 -261.41045) (xy 83.512152 -261.414768)
			(xy 83.503516 -261.427468) (xy 83.499484 -261.433874) (xy 83.495088 -261.44835) (xy 83.49488 -261.455916)
			(xy 83.49488 -261.578344) (xy 83.495141 -261.583952) (xy 83.497837 -261.594848) (xy 83.500214 -261.599934)
			(xy 83.504786 -261.607808) (xy 83.508734 -261.612666) (xy 83.51849 -261.620505) (xy 83.52409 -261.623302)
			(xy 83.524344 -261.623556) (xy 83.605116 -261.660894) (xy 83.618832 -261.664196) (xy 83.631278 -261.664704)
			(xy 83.648042 -261.658354) (xy 83.6549 -261.655052) (xy 83.665314 -261.64921) (xy 83.6676 -261.647432)
			(xy 83.668616 -261.64667) (xy 83.66887 -261.646416) (xy 83.689158 -261.631344) (xy 83.73364 -261.607355)
			(xy 83.781455 -261.590991) (xy 83.831307 -261.582695) (xy 83.856576 -261.582154) (xy 83.882413 -261.582702)
			(xy 83.933348 -261.591416) (xy 83.982089 -261.608581) (xy 84.027243 -261.633709) (xy 84.067521 -261.66608)
			(xy 84.101774 -261.704772) (xy 84.129023 -261.748678) (xy 84.139278 -261.7724) (xy 84.142834 -261.779004)
			(xy 84.143088 -261.779512) (xy 84.156623 -261.803392) (xy 84.175887 -261.854784) (xy 84.185673 -261.908788)
			(xy 84.186268 -261.93623) (xy 84.51521 -261.93623) (xy 84.51917 -261.887176) (xy 84.530947 -261.839392)
			(xy 84.550238 -261.794116) (xy 84.576541 -261.75252) (xy 84.609176 -261.715683) (xy 84.647297 -261.684558)
			(xy 84.689918 -261.659951) (xy 84.735934 -261.642499) (xy 84.784153 -261.632655) (xy 84.833328 -261.630674)
			(xy 84.882183 -261.636606) (xy 84.929454 -261.650298) (xy 84.973916 -261.671396) (xy 85.014419 -261.699352)
			(xy 85.049912 -261.733444) (xy 85.079477 -261.772788) (xy 85.102348 -261.816365) (xy 85.117932 -261.863046)
			(xy 85.125827 -261.911623) (xy 85.126322 -261.93623) (xy 85.455264 -261.93623) (xy 85.459224 -261.887176)
			(xy 85.471001 -261.839392) (xy 85.490292 -261.794116) (xy 85.516595 -261.75252) (xy 85.54923 -261.715683)
			(xy 85.587351 -261.684558) (xy 85.629972 -261.659951) (xy 85.675988 -261.642499) (xy 85.724207 -261.632655)
			(xy 85.773382 -261.630674) (xy 85.822237 -261.636606) (xy 85.869508 -261.650298) (xy 85.91397 -261.671396)
			(xy 85.954473 -261.699352) (xy 85.989966 -261.733444) (xy 86.019531 -261.772788) (xy 86.042402 -261.816365)
			(xy 86.057986 -261.863046) (xy 86.065881 -261.911623) (xy 86.066376 -261.93623) (xy 86.395318 -261.93623)
			(xy 86.399278 -261.887176) (xy 86.411055 -261.839392) (xy 86.430346 -261.794116) (xy 86.456649 -261.75252)
			(xy 86.489284 -261.715683) (xy 86.527405 -261.684558) (xy 86.570026 -261.659951) (xy 86.616042 -261.642499)
			(xy 86.664261 -261.632655) (xy 86.713436 -261.630674) (xy 86.762291 -261.636606) (xy 86.809562 -261.650298)
			(xy 86.854024 -261.671396) (xy 86.894527 -261.699352) (xy 86.93002 -261.733444) (xy 86.959585 -261.772788)
			(xy 86.982456 -261.816365) (xy 86.99804 -261.863046) (xy 87.005935 -261.911623) (xy 87.00643 -261.93623)
			(xy 87.335118 -261.93623) (xy 87.339078 -261.887176) (xy 87.350855 -261.839392) (xy 87.370146 -261.794116)
			(xy 87.396449 -261.75252) (xy 87.429084 -261.715683) (xy 87.467205 -261.684558) (xy 87.509826 -261.659951)
			(xy 87.555842 -261.642499) (xy 87.604061 -261.632655) (xy 87.653236 -261.630674) (xy 87.702091 -261.636606)
			(xy 87.749362 -261.650298) (xy 87.793824 -261.671396) (xy 87.834327 -261.699352) (xy 87.86982 -261.733444)
			(xy 87.899385 -261.772788) (xy 87.922256 -261.816365) (xy 87.93784 -261.863046) (xy 87.945735 -261.911623)
			(xy 87.94623 -261.93623) (xy 88.275172 -261.93623) (xy 88.279132 -261.887176) (xy 88.290909 -261.839392)
			(xy 88.3102 -261.794116) (xy 88.336503 -261.75252) (xy 88.369138 -261.715683) (xy 88.407259 -261.684558)
			(xy 88.44988 -261.659951) (xy 88.495896 -261.642499) (xy 88.544115 -261.632655) (xy 88.59329 -261.630674)
			(xy 88.642145 -261.636606) (xy 88.689416 -261.650298) (xy 88.733878 -261.671396) (xy 88.774381 -261.699352)
			(xy 88.809874 -261.733444) (xy 88.839439 -261.772788) (xy 88.86231 -261.816365) (xy 88.877894 -261.863046)
			(xy 88.885789 -261.911623) (xy 88.886284 -261.93623) (xy 89.215226 -261.93623) (xy 89.219186 -261.887176)
			(xy 89.230963 -261.839392) (xy 89.250254 -261.794116) (xy 89.276557 -261.75252) (xy 89.309192 -261.715683)
			(xy 89.347313 -261.684558) (xy 89.389934 -261.659951) (xy 89.43595 -261.642499) (xy 89.484169 -261.632655)
			(xy 89.533344 -261.630674) (xy 89.582199 -261.636606) (xy 89.62947 -261.650298) (xy 89.673932 -261.671396)
			(xy 89.714435 -261.699352) (xy 89.749928 -261.733444) (xy 89.779493 -261.772788) (xy 89.802364 -261.816365)
			(xy 89.817948 -261.863046) (xy 89.825843 -261.911623) (xy 89.826338 -261.93623) (xy 90.15528 -261.93623)
			(xy 90.15924 -261.887176) (xy 90.171017 -261.839392) (xy 90.190308 -261.794116) (xy 90.216611 -261.75252)
			(xy 90.249246 -261.715683) (xy 90.287367 -261.684558) (xy 90.329988 -261.659951) (xy 90.376004 -261.642499)
			(xy 90.424223 -261.632655) (xy 90.473398 -261.630674) (xy 90.522253 -261.636606) (xy 90.569524 -261.650298)
			(xy 90.613986 -261.671396) (xy 90.654489 -261.699352) (xy 90.689982 -261.733444) (xy 90.719547 -261.772788)
			(xy 90.742418 -261.816365) (xy 90.758002 -261.863046) (xy 90.765897 -261.911623) (xy 90.766392 -261.93623)
			(xy 91.095334 -261.93623) (xy 91.099294 -261.887176) (xy 91.111071 -261.839392) (xy 91.130362 -261.794116)
			(xy 91.156665 -261.75252) (xy 91.1893 -261.715683) (xy 91.227421 -261.684558) (xy 91.270042 -261.659951)
			(xy 91.316058 -261.642499) (xy 91.364277 -261.632655) (xy 91.413452 -261.630674) (xy 91.462307 -261.636606)
			(xy 91.509578 -261.650298) (xy 91.55404 -261.671396) (xy 91.594543 -261.699352) (xy 91.630036 -261.733444)
			(xy 91.659601 -261.772788) (xy 91.682472 -261.816365) (xy 91.698056 -261.863046) (xy 91.705951 -261.911623)
			(xy 91.706446 -261.93623) (xy 92.024703 -261.93623) (xy 92.028798 -261.885502) (xy 92.040977 -261.836088)
			(xy 92.060925 -261.789268) (xy 92.088126 -261.746254) (xy 92.121874 -261.70816) (xy 92.161296 -261.675973)
			(xy 92.20537 -261.650527) (xy 92.252956 -261.63248) (xy 92.30282 -261.6223) (xy 92.353672 -261.620251)
			(xy 92.404193 -261.626385) (xy 92.453077 -261.640545) (xy 92.499056 -261.662362) (xy 92.54094 -261.691272)
			(xy 92.577644 -261.726527) (xy 92.608217 -261.767213) (xy 92.631868 -261.812276) (xy 92.647984 -261.86055)
			(xy 92.656148 -261.910784) (xy 92.65666 -261.93623) (xy 92.975188 -261.93623) (xy 92.979148 -261.887176)
			(xy 92.990925 -261.839392) (xy 93.010216 -261.794116) (xy 93.036519 -261.75252) (xy 93.069154 -261.715683)
			(xy 93.107275 -261.684558) (xy 93.149896 -261.659951) (xy 93.195912 -261.642499) (xy 93.244131 -261.632655)
			(xy 93.293306 -261.630674) (xy 93.342161 -261.636606) (xy 93.389432 -261.650298) (xy 93.433894 -261.671396)
			(xy 93.474397 -261.699352) (xy 93.50989 -261.733444) (xy 93.539455 -261.772788) (xy 93.562326 -261.816365)
			(xy 93.57791 -261.863046) (xy 93.585805 -261.911623) (xy 93.5863 -261.93623) (xy 93.915242 -261.93623)
			(xy 93.919202 -261.887176) (xy 93.930979 -261.839392) (xy 93.95027 -261.794116) (xy 93.976573 -261.75252)
			(xy 94.009208 -261.715683) (xy 94.047329 -261.684558) (xy 94.08995 -261.659951) (xy 94.135966 -261.642499)
			(xy 94.184185 -261.632655) (xy 94.23336 -261.630674) (xy 94.282215 -261.636606) (xy 94.329486 -261.650298)
			(xy 94.373948 -261.671396) (xy 94.414451 -261.699352) (xy 94.449944 -261.733444) (xy 94.479509 -261.772788)
			(xy 94.50238 -261.816365) (xy 94.517964 -261.863046) (xy 94.525859 -261.911623) (xy 94.526354 -261.93623)
			(xy 94.855296 -261.93623) (xy 94.859256 -261.887176) (xy 94.871033 -261.839392) (xy 94.890324 -261.794116)
			(xy 94.916627 -261.75252) (xy 94.949262 -261.715683) (xy 94.987383 -261.684558) (xy 95.030004 -261.659951)
			(xy 95.07602 -261.642499) (xy 95.124239 -261.632655) (xy 95.173414 -261.630674) (xy 95.222269 -261.636606)
			(xy 95.26954 -261.650298) (xy 95.314002 -261.671396) (xy 95.354505 -261.699352) (xy 95.389998 -261.733444)
			(xy 95.419563 -261.772788) (xy 95.442434 -261.816365) (xy 95.458018 -261.863046) (xy 95.465913 -261.911623)
			(xy 95.466408 -261.93623) (xy 95.784919 -261.93623) (xy 95.789014 -261.885502) (xy 95.801193 -261.836088)
			(xy 95.821141 -261.789268) (xy 95.848342 -261.746254) (xy 95.88209 -261.70816) (xy 95.921512 -261.675973)
			(xy 95.965586 -261.650527) (xy 96.013172 -261.63248) (xy 96.063036 -261.6223) (xy 96.113888 -261.620251)
			(xy 96.164409 -261.626385) (xy 96.213293 -261.640545) (xy 96.259272 -261.662362) (xy 96.301156 -261.691272)
			(xy 96.33786 -261.726527) (xy 96.368433 -261.767213) (xy 96.392084 -261.812276) (xy 96.4082 -261.86055)
			(xy 96.416364 -261.910784) (xy 96.416876 -261.93623) (xy 97.675204 -261.93623) (xy 97.679164 -261.887176)
			(xy 97.690941 -261.839392) (xy 97.710232 -261.794116) (xy 97.736535 -261.75252) (xy 97.76917 -261.715683)
			(xy 97.807291 -261.684558) (xy 97.849912 -261.659951) (xy 97.895928 -261.642499) (xy 97.944147 -261.632655)
			(xy 97.993322 -261.630674) (xy 98.042177 -261.636606) (xy 98.089448 -261.650298) (xy 98.13391 -261.671396)
			(xy 98.174413 -261.699352) (xy 98.209906 -261.733444) (xy 98.239471 -261.772788) (xy 98.262342 -261.816365)
			(xy 98.277926 -261.863046) (xy 98.285821 -261.911623) (xy 98.286316 -261.93623) (xy 99.555312 -261.93623)
			(xy 99.559272 -261.887176) (xy 99.571049 -261.839392) (xy 99.59034 -261.794116) (xy 99.616643 -261.75252)
			(xy 99.649278 -261.715683) (xy 99.687399 -261.684558) (xy 99.73002 -261.659951) (xy 99.776036 -261.642499)
			(xy 99.824255 -261.632655) (xy 99.87343 -261.630674) (xy 99.922285 -261.636606) (xy 99.969556 -261.650298)
			(xy 100.014018 -261.671396) (xy 100.054521 -261.699352) (xy 100.090014 -261.733444) (xy 100.119579 -261.772788)
			(xy 100.14245 -261.816365) (xy 100.158034 -261.863046) (xy 100.165929 -261.911623) (xy 100.166424 -261.93623)
			(xy 101.435166 -261.93623) (xy 101.439126 -261.887176) (xy 101.450903 -261.839392) (xy 101.470194 -261.794116)
			(xy 101.496497 -261.75252) (xy 101.529132 -261.715683) (xy 101.567253 -261.684558) (xy 101.609874 -261.659951)
			(xy 101.65589 -261.642499) (xy 101.704109 -261.632655) (xy 101.753284 -261.630674) (xy 101.802139 -261.636606)
			(xy 101.84941 -261.650298) (xy 101.893872 -261.671396) (xy 101.934375 -261.699352) (xy 101.969868 -261.733444)
			(xy 101.999433 -261.772788) (xy 102.022304 -261.816365) (xy 102.037888 -261.863046) (xy 102.045783 -261.911623)
			(xy 102.046278 -261.93623) (xy 102.045783 -261.960837) (xy 102.037888 -262.009414) (xy 102.022304 -262.056095)
			(xy 101.999433 -262.099672) (xy 101.969868 -262.139016) (xy 101.934375 -262.173108) (xy 101.893872 -262.201064)
			(xy 101.84941 -262.222162) (xy 101.802139 -262.235854) (xy 101.753284 -262.241786) (xy 101.704109 -262.239805)
			(xy 101.65589 -262.229961) (xy 101.609874 -262.212509) (xy 101.567253 -262.187902) (xy 101.529132 -262.156777)
			(xy 101.496497 -262.11994) (xy 101.470194 -262.078344) (xy 101.450903 -262.033068) (xy 101.439126 -261.985284)
			(xy 101.435166 -261.93623) (xy 100.166424 -261.93623) (xy 100.165929 -261.960837) (xy 100.158034 -262.009414)
			(xy 100.14245 -262.056095) (xy 100.119579 -262.099672) (xy 100.090014 -262.139016) (xy 100.054521 -262.173108)
			(xy 100.014018 -262.201064) (xy 99.969556 -262.222162) (xy 99.922285 -262.235854) (xy 99.87343 -262.241786)
			(xy 99.824255 -262.239805) (xy 99.776036 -262.229961) (xy 99.73002 -262.212509) (xy 99.687399 -262.187902)
			(xy 99.649278 -262.156777) (xy 99.616643 -262.11994) (xy 99.59034 -262.078344) (xy 99.571049 -262.033068)
			(xy 99.559272 -261.985284) (xy 99.555312 -261.93623) (xy 98.286316 -261.93623) (xy 98.285821 -261.960837)
			(xy 98.277926 -262.009414) (xy 98.262342 -262.056095) (xy 98.239471 -262.099672) (xy 98.209906 -262.139016)
			(xy 98.174413 -262.173108) (xy 98.13391 -262.201064) (xy 98.089448 -262.222162) (xy 98.042177 -262.235854)
			(xy 97.993322 -262.241786) (xy 97.944147 -262.239805) (xy 97.895928 -262.229961) (xy 97.849912 -262.212509)
			(xy 97.807291 -262.187902) (xy 97.76917 -262.156777) (xy 97.736535 -262.11994) (xy 97.710232 -262.078344)
			(xy 97.690941 -262.033068) (xy 97.679164 -261.985284) (xy 97.675204 -261.93623) (xy 96.416876 -261.93623)
			(xy 96.416364 -261.961676) (xy 96.4082 -262.01191) (xy 96.392084 -262.060184) (xy 96.368433 -262.105247)
			(xy 96.33786 -262.145933) (xy 96.301156 -262.181188) (xy 96.259272 -262.210098) (xy 96.213293 -262.231915)
			(xy 96.164409 -262.246075) (xy 96.113888 -262.252209) (xy 96.063036 -262.25016) (xy 96.013172 -262.23998)
			(xy 95.965586 -262.221933) (xy 95.921512 -262.196487) (xy 95.88209 -262.1643) (xy 95.848342 -262.126206)
			(xy 95.821141 -262.083192) (xy 95.801193 -262.036372) (xy 95.789014 -261.986958) (xy 95.784919 -261.93623)
			(xy 95.466408 -261.93623) (xy 95.465913 -261.960837) (xy 95.458018 -262.009414) (xy 95.442434 -262.056095)
			(xy 95.419563 -262.099672) (xy 95.389998 -262.139016) (xy 95.354505 -262.173108) (xy 95.314002 -262.201064)
			(xy 95.26954 -262.222162) (xy 95.222269 -262.235854) (xy 95.173414 -262.241786) (xy 95.124239 -262.239805)
			(xy 95.07602 -262.229961) (xy 95.030004 -262.212509) (xy 94.987383 -262.187902) (xy 94.949262 -262.156777)
			(xy 94.916627 -262.11994) (xy 94.890324 -262.078344) (xy 94.871033 -262.033068) (xy 94.859256 -261.985284)
			(xy 94.855296 -261.93623) (xy 94.526354 -261.93623) (xy 94.525859 -261.960837) (xy 94.517964 -262.009414)
			(xy 94.50238 -262.056095) (xy 94.479509 -262.099672) (xy 94.449944 -262.139016) (xy 94.414451 -262.173108)
			(xy 94.373948 -262.201064) (xy 94.329486 -262.222162) (xy 94.282215 -262.235854) (xy 94.23336 -262.241786)
			(xy 94.184185 -262.239805) (xy 94.135966 -262.229961) (xy 94.08995 -262.212509) (xy 94.047329 -262.187902)
			(xy 94.009208 -262.156777) (xy 93.976573 -262.11994) (xy 93.95027 -262.078344) (xy 93.930979 -262.033068)
			(xy 93.919202 -261.985284) (xy 93.915242 -261.93623) (xy 93.5863 -261.93623) (xy 93.585805 -261.960837)
			(xy 93.57791 -262.009414) (xy 93.562326 -262.056095) (xy 93.539455 -262.099672) (xy 93.50989 -262.139016)
			(xy 93.474397 -262.173108) (xy 93.433894 -262.201064) (xy 93.389432 -262.222162) (xy 93.342161 -262.235854)
			(xy 93.293306 -262.241786) (xy 93.244131 -262.239805) (xy 93.195912 -262.229961) (xy 93.149896 -262.212509)
			(xy 93.107275 -262.187902) (xy 93.069154 -262.156777) (xy 93.036519 -262.11994) (xy 93.010216 -262.078344)
			(xy 92.990925 -262.033068) (xy 92.979148 -261.985284) (xy 92.975188 -261.93623) (xy 92.65666 -261.93623)
			(xy 92.656148 -261.961676) (xy 92.647984 -262.01191) (xy 92.631868 -262.060184) (xy 92.608217 -262.105247)
			(xy 92.577644 -262.145933) (xy 92.54094 -262.181188) (xy 92.499056 -262.210098) (xy 92.453077 -262.231915)
			(xy 92.404193 -262.246075) (xy 92.353672 -262.252209) (xy 92.30282 -262.25016) (xy 92.252956 -262.23998)
			(xy 92.20537 -262.221933) (xy 92.161296 -262.196487) (xy 92.121874 -262.1643) (xy 92.088126 -262.126206)
			(xy 92.060925 -262.083192) (xy 92.040977 -262.036372) (xy 92.028798 -261.986958) (xy 92.024703 -261.93623)
			(xy 91.706446 -261.93623) (xy 91.705951 -261.960837) (xy 91.698056 -262.009414) (xy 91.682472 -262.056095)
			(xy 91.659601 -262.099672) (xy 91.630036 -262.139016) (xy 91.594543 -262.173108) (xy 91.55404 -262.201064)
			(xy 91.509578 -262.222162) (xy 91.462307 -262.235854) (xy 91.413452 -262.241786) (xy 91.364277 -262.239805)
			(xy 91.316058 -262.229961) (xy 91.270042 -262.212509) (xy 91.227421 -262.187902) (xy 91.1893 -262.156777)
			(xy 91.156665 -262.11994) (xy 91.130362 -262.078344) (xy 91.111071 -262.033068) (xy 91.099294 -261.985284)
			(xy 91.095334 -261.93623) (xy 90.766392 -261.93623) (xy 90.765897 -261.960837) (xy 90.758002 -262.009414)
			(xy 90.742418 -262.056095) (xy 90.719547 -262.099672) (xy 90.689982 -262.139016) (xy 90.654489 -262.173108)
			(xy 90.613986 -262.201064) (xy 90.569524 -262.222162) (xy 90.522253 -262.235854) (xy 90.473398 -262.241786)
			(xy 90.424223 -262.239805) (xy 90.376004 -262.229961) (xy 90.329988 -262.212509) (xy 90.287367 -262.187902)
			(xy 90.249246 -262.156777) (xy 90.216611 -262.11994) (xy 90.190308 -262.078344) (xy 90.171017 -262.033068)
			(xy 90.15924 -261.985284) (xy 90.15528 -261.93623) (xy 89.826338 -261.93623) (xy 89.825843 -261.960837)
			(xy 89.817948 -262.009414) (xy 89.802364 -262.056095) (xy 89.779493 -262.099672) (xy 89.749928 -262.139016)
			(xy 89.714435 -262.173108) (xy 89.673932 -262.201064) (xy 89.62947 -262.222162) (xy 89.582199 -262.235854)
			(xy 89.533344 -262.241786) (xy 89.484169 -262.239805) (xy 89.43595 -262.229961) (xy 89.389934 -262.212509)
			(xy 89.347313 -262.187902) (xy 89.309192 -262.156777) (xy 89.276557 -262.11994) (xy 89.250254 -262.078344)
			(xy 89.230963 -262.033068) (xy 89.219186 -261.985284) (xy 89.215226 -261.93623) (xy 88.886284 -261.93623)
			(xy 88.885789 -261.960837) (xy 88.877894 -262.009414) (xy 88.86231 -262.056095) (xy 88.839439 -262.099672)
			(xy 88.809874 -262.139016) (xy 88.774381 -262.173108) (xy 88.733878 -262.201064) (xy 88.689416 -262.222162)
			(xy 88.642145 -262.235854) (xy 88.59329 -262.241786) (xy 88.544115 -262.239805) (xy 88.495896 -262.229961)
			(xy 88.44988 -262.212509) (xy 88.407259 -262.187902) (xy 88.369138 -262.156777) (xy 88.336503 -262.11994)
			(xy 88.3102 -262.078344) (xy 88.290909 -262.033068) (xy 88.279132 -261.985284) (xy 88.275172 -261.93623)
			(xy 87.94623 -261.93623) (xy 87.945735 -261.960837) (xy 87.93784 -262.009414) (xy 87.922256 -262.056095)
			(xy 87.899385 -262.099672) (xy 87.86982 -262.139016) (xy 87.834327 -262.173108) (xy 87.793824 -262.201064)
			(xy 87.749362 -262.222162) (xy 87.702091 -262.235854) (xy 87.653236 -262.241786) (xy 87.604061 -262.239805)
			(xy 87.555842 -262.229961) (xy 87.509826 -262.212509) (xy 87.467205 -262.187902) (xy 87.429084 -262.156777)
			(xy 87.396449 -262.11994) (xy 87.370146 -262.078344) (xy 87.350855 -262.033068) (xy 87.339078 -261.985284)
			(xy 87.335118 -261.93623) (xy 87.00643 -261.93623) (xy 87.005935 -261.960837) (xy 86.99804 -262.009414)
			(xy 86.982456 -262.056095) (xy 86.959585 -262.099672) (xy 86.93002 -262.139016) (xy 86.894527 -262.173108)
			(xy 86.854024 -262.201064) (xy 86.809562 -262.222162) (xy 86.762291 -262.235854) (xy 86.713436 -262.241786)
			(xy 86.664261 -262.239805) (xy 86.616042 -262.229961) (xy 86.570026 -262.212509) (xy 86.527405 -262.187902)
			(xy 86.489284 -262.156777) (xy 86.456649 -262.11994) (xy 86.430346 -262.078344) (xy 86.411055 -262.033068)
			(xy 86.399278 -261.985284) (xy 86.395318 -261.93623) (xy 86.066376 -261.93623) (xy 86.065881 -261.960837)
			(xy 86.057986 -262.009414) (xy 86.042402 -262.056095) (xy 86.019531 -262.099672) (xy 85.989966 -262.139016)
			(xy 85.954473 -262.173108) (xy 85.91397 -262.201064) (xy 85.869508 -262.222162) (xy 85.822237 -262.235854)
			(xy 85.773382 -262.241786) (xy 85.724207 -262.239805) (xy 85.675988 -262.229961) (xy 85.629972 -262.212509)
			(xy 85.587351 -262.187902) (xy 85.54923 -262.156777) (xy 85.516595 -262.11994) (xy 85.490292 -262.078344)
			(xy 85.471001 -262.033068) (xy 85.459224 -261.985284) (xy 85.455264 -261.93623) (xy 85.126322 -261.93623)
			(xy 85.125827 -261.960837) (xy 85.117932 -262.009414) (xy 85.102348 -262.056095) (xy 85.079477 -262.099672)
			(xy 85.049912 -262.139016) (xy 85.014419 -262.173108) (xy 84.973916 -262.201064) (xy 84.929454 -262.222162)
			(xy 84.882183 -262.235854) (xy 84.833328 -262.241786) (xy 84.784153 -262.239805) (xy 84.735934 -262.229961)
			(xy 84.689918 -262.212509) (xy 84.647297 -262.187902) (xy 84.609176 -262.156777) (xy 84.576541 -262.11994)
			(xy 84.550238 -262.078344) (xy 84.530947 -262.033068) (xy 84.51917 -261.985284) (xy 84.51521 -261.93623)
			(xy 84.186268 -261.93623) (xy 84.18582 -261.96022) (xy 84.178309 -262.00761) (xy 84.163477 -262.053241)
			(xy 84.14169 -262.09599) (xy 84.113483 -262.134804) (xy 84.079551 -262.168728) (xy 84.04073 -262.196926)
			(xy 83.997976 -262.218704) (xy 83.952342 -262.233525) (xy 83.904951 -262.241025) (xy 83.88096 -262.241538)
			(xy 83.854569 -262.240987) (xy 83.802571 -262.231927) (xy 83.752904 -262.214068) (xy 83.707043 -262.187939)
			(xy 83.666355 -262.154319) (xy 83.648804 -262.134604) (xy 83.627468 -262.109458) (xy 83.62569 -262.109458)
			(xy 83.621481 -262.10954) (xy 83.613182 -262.110947) (xy 83.60918 -262.112252) (xy 83.521804 -262.152638)
			(xy 83.514018 -262.157168) (xy 83.502017 -262.170586) (xy 83.495416 -262.187334) (xy 83.49488 -262.196326)
			(xy 83.49488 -262.365236) (xy 83.494916 -262.369371) (xy 83.496199 -262.37754) (xy 83.49742 -262.381492)
			(xy 83.502246 -262.391652) (xy 83.515708 -262.412734) (xy 83.51921 -262.417995) (xy 83.528335 -262.426733)
			(xy 83.533742 -262.430006) (xy 83.533996 -262.430006) (xy 83.555755 -262.442587) (xy 83.5952 -262.473731)
			(xy 83.612482 -262.491982) (xy 83.630124 -262.512181) (xy 83.658738 -262.557534) (xy 83.669378 -262.582152)
			(xy 83.672934 -262.588756) (xy 83.673188 -262.589264) (xy 83.6867 -262.613106) (xy 83.70594 -262.664415)
			(xy 83.715732 -262.71833) (xy 83.716368 -262.745728) (xy 83.716368 -262.746236) (xy 84.04531 -262.746236)
			(xy 84.04927 -262.697182) (xy 84.061047 -262.649398) (xy 84.080338 -262.604122) (xy 84.106641 -262.562526)
			(xy 84.139276 -262.525689) (xy 84.177397 -262.494564) (xy 84.220018 -262.469957) (xy 84.266034 -262.452505)
			(xy 84.314253 -262.442661) (xy 84.363428 -262.44068) (xy 84.412283 -262.446612) (xy 84.459554 -262.460304)
			(xy 84.504016 -262.481402) (xy 84.544519 -262.509358) (xy 84.580012 -262.54345) (xy 84.609577 -262.582794)
			(xy 84.632448 -262.626371) (xy 84.648032 -262.673052) (xy 84.655927 -262.721629) (xy 84.656422 -262.746236)
			(xy 84.98511 -262.746236) (xy 84.98907 -262.697182) (xy 85.000847 -262.649398) (xy 85.020138 -262.604122)
			(xy 85.046441 -262.562526) (xy 85.079076 -262.525689) (xy 85.117197 -262.494564) (xy 85.159818 -262.469957)
			(xy 85.205834 -262.452505) (xy 85.254053 -262.442661) (xy 85.303228 -262.44068) (xy 85.352083 -262.446612)
			(xy 85.399354 -262.460304) (xy 85.443816 -262.481402) (xy 85.484319 -262.509358) (xy 85.519812 -262.54345)
			(xy 85.549377 -262.582794) (xy 85.572248 -262.626371) (xy 85.587832 -262.673052) (xy 85.595727 -262.721629)
			(xy 85.596222 -262.746236) (xy 85.925164 -262.746236) (xy 85.929124 -262.697182) (xy 85.940901 -262.649398)
			(xy 85.960192 -262.604122) (xy 85.986495 -262.562526) (xy 86.01913 -262.525689) (xy 86.057251 -262.494564)
			(xy 86.099872 -262.469957) (xy 86.145888 -262.452505) (xy 86.194107 -262.442661) (xy 86.243282 -262.44068)
			(xy 86.292137 -262.446612) (xy 86.339408 -262.460304) (xy 86.38387 -262.481402) (xy 86.424373 -262.509358)
			(xy 86.459866 -262.54345) (xy 86.489431 -262.582794) (xy 86.512302 -262.626371) (xy 86.527886 -262.673052)
			(xy 86.535781 -262.721629) (xy 86.536276 -262.746236) (xy 86.865218 -262.746236) (xy 86.869178 -262.697182)
			(xy 86.880955 -262.649398) (xy 86.900246 -262.604122) (xy 86.926549 -262.562526) (xy 86.959184 -262.525689)
			(xy 86.997305 -262.494564) (xy 87.039926 -262.469957) (xy 87.085942 -262.452505) (xy 87.134161 -262.442661)
			(xy 87.183336 -262.44068) (xy 87.232191 -262.446612) (xy 87.279462 -262.460304) (xy 87.323924 -262.481402)
			(xy 87.364427 -262.509358) (xy 87.39992 -262.54345) (xy 87.429485 -262.582794) (xy 87.452356 -262.626371)
			(xy 87.46794 -262.673052) (xy 87.475835 -262.721629) (xy 87.47633 -262.746236) (xy 87.805272 -262.746236)
			(xy 87.809232 -262.697182) (xy 87.821009 -262.649398) (xy 87.8403 -262.604122) (xy 87.866603 -262.562526)
			(xy 87.899238 -262.525689) (xy 87.937359 -262.494564) (xy 87.97998 -262.469957) (xy 88.025996 -262.452505)
			(xy 88.074215 -262.442661) (xy 88.12339 -262.44068) (xy 88.172245 -262.446612) (xy 88.219516 -262.460304)
			(xy 88.263978 -262.481402) (xy 88.304481 -262.509358) (xy 88.339974 -262.54345) (xy 88.369539 -262.582794)
			(xy 88.39241 -262.626371) (xy 88.407994 -262.673052) (xy 88.415889 -262.721629) (xy 88.416384 -262.746236)
			(xy 88.745326 -262.746236) (xy 88.749286 -262.697182) (xy 88.761063 -262.649398) (xy 88.780354 -262.604122)
			(xy 88.806657 -262.562526) (xy 88.839292 -262.525689) (xy 88.877413 -262.494564) (xy 88.920034 -262.469957)
			(xy 88.96605 -262.452505) (xy 89.014269 -262.442661) (xy 89.063444 -262.44068) (xy 89.112299 -262.446612)
			(xy 89.15957 -262.460304) (xy 89.204032 -262.481402) (xy 89.244535 -262.509358) (xy 89.280028 -262.54345)
			(xy 89.309593 -262.582794) (xy 89.332464 -262.626371) (xy 89.348048 -262.673052) (xy 89.355943 -262.721629)
			(xy 89.356438 -262.746236) (xy 89.685126 -262.746236) (xy 89.689086 -262.697182) (xy 89.700863 -262.649398)
			(xy 89.720154 -262.604122) (xy 89.746457 -262.562526) (xy 89.779092 -262.525689) (xy 89.817213 -262.494564)
			(xy 89.859834 -262.469957) (xy 89.90585 -262.452505) (xy 89.954069 -262.442661) (xy 90.003244 -262.44068)
			(xy 90.052099 -262.446612) (xy 90.09937 -262.460304) (xy 90.143832 -262.481402) (xy 90.184335 -262.509358)
			(xy 90.219828 -262.54345) (xy 90.249393 -262.582794) (xy 90.272264 -262.626371) (xy 90.287848 -262.673052)
			(xy 90.295743 -262.721629) (xy 90.296238 -262.746236) (xy 90.614749 -262.746236) (xy 90.618844 -262.695508)
			(xy 90.631023 -262.646094) (xy 90.650971 -262.599274) (xy 90.678172 -262.55626) (xy 90.71192 -262.518166)
			(xy 90.751342 -262.485979) (xy 90.795416 -262.460533) (xy 90.843002 -262.442486) (xy 90.892866 -262.432306)
			(xy 90.943718 -262.430257) (xy 90.994239 -262.436391) (xy 91.043123 -262.450551) (xy 91.089102 -262.472368)
			(xy 91.130986 -262.501278) (xy 91.16769 -262.536533) (xy 91.198263 -262.577219) (xy 91.221914 -262.622282)
			(xy 91.23803 -262.670556) (xy 91.246194 -262.72079) (xy 91.246706 -262.746236) (xy 91.565234 -262.746236)
			(xy 91.569194 -262.697182) (xy 91.580971 -262.649398) (xy 91.600262 -262.604122) (xy 91.626565 -262.562526)
			(xy 91.6592 -262.525689) (xy 91.697321 -262.494564) (xy 91.739942 -262.469957) (xy 91.785958 -262.452505)
			(xy 91.834177 -262.442661) (xy 91.883352 -262.44068) (xy 91.932207 -262.446612) (xy 91.979478 -262.460304)
			(xy 92.02394 -262.481402) (xy 92.064443 -262.509358) (xy 92.099936 -262.54345) (xy 92.129501 -262.582794)
			(xy 92.152372 -262.626371) (xy 92.167956 -262.673052) (xy 92.175851 -262.721629) (xy 92.176346 -262.746236)
			(xy 92.494857 -262.746236) (xy 92.498952 -262.695508) (xy 92.511131 -262.646094) (xy 92.531079 -262.599274)
			(xy 92.55828 -262.55626) (xy 92.592028 -262.518166) (xy 92.63145 -262.485979) (xy 92.675524 -262.460533)
			(xy 92.72311 -262.442486) (xy 92.772974 -262.432306) (xy 92.823826 -262.430257) (xy 92.874347 -262.436391)
			(xy 92.923231 -262.450551) (xy 92.96921 -262.472368) (xy 93.011094 -262.501278) (xy 93.047798 -262.536533)
			(xy 93.078371 -262.577219) (xy 93.102022 -262.622282) (xy 93.118138 -262.670556) (xy 93.126302 -262.72079)
			(xy 93.126814 -262.746236) (xy 93.445342 -262.746236) (xy 93.449302 -262.697182) (xy 93.461079 -262.649398)
			(xy 93.48037 -262.604122) (xy 93.506673 -262.562526) (xy 93.539308 -262.525689) (xy 93.577429 -262.494564)
			(xy 93.62005 -262.469957) (xy 93.666066 -262.452505) (xy 93.714285 -262.442661) (xy 93.76346 -262.44068)
			(xy 93.812315 -262.446612) (xy 93.859586 -262.460304) (xy 93.904048 -262.481402) (xy 93.944551 -262.509358)
			(xy 93.980044 -262.54345) (xy 94.009609 -262.582794) (xy 94.03248 -262.626371) (xy 94.048064 -262.673052)
			(xy 94.055959 -262.721629) (xy 94.056454 -262.746236) (xy 94.374711 -262.746236) (xy 94.378806 -262.695508)
			(xy 94.390985 -262.646094) (xy 94.410933 -262.599274) (xy 94.438134 -262.55626) (xy 94.471882 -262.518166)
			(xy 94.511304 -262.485979) (xy 94.555378 -262.460533) (xy 94.602964 -262.442486) (xy 94.652828 -262.432306)
			(xy 94.70368 -262.430257) (xy 94.754201 -262.436391) (xy 94.803085 -262.450551) (xy 94.849064 -262.472368)
			(xy 94.890948 -262.501278) (xy 94.927652 -262.536533) (xy 94.958225 -262.577219) (xy 94.981876 -262.622282)
			(xy 94.997992 -262.670556) (xy 95.006156 -262.72079) (xy 95.006668 -262.746236) (xy 95.314765 -262.746236)
			(xy 95.31886 -262.695508) (xy 95.331039 -262.646094) (xy 95.350987 -262.599274) (xy 95.378188 -262.55626)
			(xy 95.411936 -262.518166) (xy 95.451358 -262.485979) (xy 95.495432 -262.460533) (xy 95.543018 -262.442486)
			(xy 95.592882 -262.432306) (xy 95.643734 -262.430257) (xy 95.694255 -262.436391) (xy 95.743139 -262.450551)
			(xy 95.789118 -262.472368) (xy 95.831002 -262.501278) (xy 95.867706 -262.536533) (xy 95.898279 -262.577219)
			(xy 95.92193 -262.622282) (xy 95.938046 -262.670556) (xy 95.94621 -262.72079) (xy 95.946722 -262.746236)
			(xy 96.26525 -262.746236) (xy 96.26921 -262.697182) (xy 96.280987 -262.649398) (xy 96.300278 -262.604122)
			(xy 96.326581 -262.562526) (xy 96.359216 -262.525689) (xy 96.397337 -262.494564) (xy 96.439958 -262.469957)
			(xy 96.485974 -262.452505) (xy 96.534193 -262.442661) (xy 96.583368 -262.44068) (xy 96.632223 -262.446612)
			(xy 96.679494 -262.460304) (xy 96.723956 -262.481402) (xy 96.764459 -262.509358) (xy 96.799952 -262.54345)
			(xy 96.829517 -262.582794) (xy 96.852388 -262.626371) (xy 96.867972 -262.673052) (xy 96.875867 -262.721629)
			(xy 96.876362 -262.746236) (xy 98.145358 -262.746236) (xy 98.149318 -262.697182) (xy 98.161095 -262.649398)
			(xy 98.180386 -262.604122) (xy 98.206689 -262.562526) (xy 98.239324 -262.525689) (xy 98.277445 -262.494564)
			(xy 98.320066 -262.469957) (xy 98.366082 -262.452505) (xy 98.414301 -262.442661) (xy 98.463476 -262.44068)
			(xy 98.512331 -262.446612) (xy 98.559602 -262.460304) (xy 98.604064 -262.481402) (xy 98.644567 -262.509358)
			(xy 98.68006 -262.54345) (xy 98.709625 -262.582794) (xy 98.732496 -262.626371) (xy 98.74808 -262.673052)
			(xy 98.755975 -262.721629) (xy 98.75647 -262.746236) (xy 100.025212 -262.746236) (xy 100.029172 -262.697182)
			(xy 100.040949 -262.649398) (xy 100.06024 -262.604122) (xy 100.086543 -262.562526) (xy 100.119178 -262.525689)
			(xy 100.157299 -262.494564) (xy 100.19992 -262.469957) (xy 100.245936 -262.452505) (xy 100.294155 -262.442661)
			(xy 100.34333 -262.44068) (xy 100.392185 -262.446612) (xy 100.439456 -262.460304) (xy 100.483918 -262.481402)
			(xy 100.524421 -262.509358) (xy 100.559914 -262.54345) (xy 100.589479 -262.582794) (xy 100.61235 -262.626371)
			(xy 100.627934 -262.673052) (xy 100.635829 -262.721629) (xy 100.636324 -262.746236) (xy 100.965266 -262.746236)
			(xy 100.969226 -262.697182) (xy 100.981003 -262.649398) (xy 101.000294 -262.604122) (xy 101.026597 -262.562526)
			(xy 101.059232 -262.525689) (xy 101.097353 -262.494564) (xy 101.139974 -262.469957) (xy 101.18599 -262.452505)
			(xy 101.234209 -262.442661) (xy 101.283384 -262.44068) (xy 101.332239 -262.446612) (xy 101.37951 -262.460304)
			(xy 101.423972 -262.481402) (xy 101.464475 -262.509358) (xy 101.499968 -262.54345) (xy 101.529533 -262.582794)
			(xy 101.552404 -262.626371) (xy 101.567988 -262.673052) (xy 101.575883 -262.721629) (xy 101.576378 -262.746236)
			(xy 101.575883 -262.770843) (xy 101.567988 -262.81942) (xy 101.552404 -262.866101) (xy 101.529533 -262.909678)
			(xy 101.499968 -262.949022) (xy 101.464475 -262.983114) (xy 101.423972 -263.01107) (xy 101.37951 -263.032168)
			(xy 101.332239 -263.04586) (xy 101.283384 -263.051792) (xy 101.234209 -263.049811) (xy 101.18599 -263.039967)
			(xy 101.139974 -263.022515) (xy 101.097353 -262.997908) (xy 101.059232 -262.966783) (xy 101.026597 -262.929946)
			(xy 101.000294 -262.88835) (xy 100.981003 -262.843074) (xy 100.969226 -262.79529) (xy 100.965266 -262.746236)
			(xy 100.636324 -262.746236) (xy 100.635829 -262.770843) (xy 100.627934 -262.81942) (xy 100.61235 -262.866101)
			(xy 100.589479 -262.909678) (xy 100.559914 -262.949022) (xy 100.524421 -262.983114) (xy 100.483918 -263.01107)
			(xy 100.439456 -263.032168) (xy 100.392185 -263.04586) (xy 100.34333 -263.051792) (xy 100.294155 -263.049811)
			(xy 100.245936 -263.039967) (xy 100.19992 -263.022515) (xy 100.157299 -262.997908) (xy 100.119178 -262.966783)
			(xy 100.086543 -262.929946) (xy 100.06024 -262.88835) (xy 100.040949 -262.843074) (xy 100.029172 -262.79529)
			(xy 100.025212 -262.746236) (xy 98.75647 -262.746236) (xy 98.755975 -262.770843) (xy 98.74808 -262.81942)
			(xy 98.732496 -262.866101) (xy 98.709625 -262.909678) (xy 98.68006 -262.949022) (xy 98.644567 -262.983114)
			(xy 98.604064 -263.01107) (xy 98.559602 -263.032168) (xy 98.512331 -263.04586) (xy 98.463476 -263.051792)
			(xy 98.414301 -263.049811) (xy 98.366082 -263.039967) (xy 98.320066 -263.022515) (xy 98.277445 -262.997908)
			(xy 98.239324 -262.966783) (xy 98.206689 -262.929946) (xy 98.180386 -262.88835) (xy 98.161095 -262.843074)
			(xy 98.149318 -262.79529) (xy 98.145358 -262.746236) (xy 96.876362 -262.746236) (xy 96.875867 -262.770843)
			(xy 96.867972 -262.81942) (xy 96.852388 -262.866101) (xy 96.829517 -262.909678) (xy 96.799952 -262.949022)
			(xy 96.764459 -262.983114) (xy 96.723956 -263.01107) (xy 96.679494 -263.032168) (xy 96.632223 -263.04586)
			(xy 96.583368 -263.051792) (xy 96.534193 -263.049811) (xy 96.485974 -263.039967) (xy 96.439958 -263.022515)
			(xy 96.397337 -262.997908) (xy 96.359216 -262.966783) (xy 96.326581 -262.929946) (xy 96.300278 -262.88835)
			(xy 96.280987 -262.843074) (xy 96.26921 -262.79529) (xy 96.26525 -262.746236) (xy 95.946722 -262.746236)
			(xy 95.94621 -262.771682) (xy 95.938046 -262.821916) (xy 95.92193 -262.87019) (xy 95.898279 -262.915253)
			(xy 95.867706 -262.955939) (xy 95.831002 -262.991194) (xy 95.789118 -263.020104) (xy 95.743139 -263.041921)
			(xy 95.694255 -263.056081) (xy 95.643734 -263.062215) (xy 95.592882 -263.060166) (xy 95.543018 -263.049986)
			(xy 95.495432 -263.031939) (xy 95.451358 -263.006493) (xy 95.411936 -262.974306) (xy 95.378188 -262.936212)
			(xy 95.350987 -262.893198) (xy 95.331039 -262.846378) (xy 95.31886 -262.796964) (xy 95.314765 -262.746236)
			(xy 95.006668 -262.746236) (xy 95.006156 -262.771682) (xy 94.997992 -262.821916) (xy 94.981876 -262.87019)
			(xy 94.958225 -262.915253) (xy 94.927652 -262.955939) (xy 94.890948 -262.991194) (xy 94.849064 -263.020104)
			(xy 94.803085 -263.041921) (xy 94.754201 -263.056081) (xy 94.70368 -263.062215) (xy 94.652828 -263.060166)
			(xy 94.602964 -263.049986) (xy 94.555378 -263.031939) (xy 94.511304 -263.006493) (xy 94.471882 -262.974306)
			(xy 94.438134 -262.936212) (xy 94.410933 -262.893198) (xy 94.390985 -262.846378) (xy 94.378806 -262.796964)
			(xy 94.374711 -262.746236) (xy 94.056454 -262.746236) (xy 94.055959 -262.770843) (xy 94.048064 -262.81942)
			(xy 94.03248 -262.866101) (xy 94.009609 -262.909678) (xy 93.980044 -262.949022) (xy 93.944551 -262.983114)
			(xy 93.904048 -263.01107) (xy 93.859586 -263.032168) (xy 93.812315 -263.04586) (xy 93.76346 -263.051792)
			(xy 93.714285 -263.049811) (xy 93.666066 -263.039967) (xy 93.62005 -263.022515) (xy 93.577429 -262.997908)
			(xy 93.539308 -262.966783) (xy 93.506673 -262.929946) (xy 93.48037 -262.88835) (xy 93.461079 -262.843074)
			(xy 93.449302 -262.79529) (xy 93.445342 -262.746236) (xy 93.126814 -262.746236) (xy 93.126302 -262.771682)
			(xy 93.118138 -262.821916) (xy 93.102022 -262.87019) (xy 93.078371 -262.915253) (xy 93.047798 -262.955939)
			(xy 93.011094 -262.991194) (xy 92.96921 -263.020104) (xy 92.923231 -263.041921) (xy 92.874347 -263.056081)
			(xy 92.823826 -263.062215) (xy 92.772974 -263.060166) (xy 92.72311 -263.049986) (xy 92.675524 -263.031939)
			(xy 92.63145 -263.006493) (xy 92.592028 -262.974306) (xy 92.55828 -262.936212) (xy 92.531079 -262.893198)
			(xy 92.511131 -262.846378) (xy 92.498952 -262.796964) (xy 92.494857 -262.746236) (xy 92.176346 -262.746236)
			(xy 92.175851 -262.770843) (xy 92.167956 -262.81942) (xy 92.152372 -262.866101) (xy 92.129501 -262.909678)
			(xy 92.099936 -262.949022) (xy 92.064443 -262.983114) (xy 92.02394 -263.01107) (xy 91.979478 -263.032168)
			(xy 91.932207 -263.04586) (xy 91.883352 -263.051792) (xy 91.834177 -263.049811) (xy 91.785958 -263.039967)
			(xy 91.739942 -263.022515) (xy 91.697321 -262.997908) (xy 91.6592 -262.966783) (xy 91.626565 -262.929946)
			(xy 91.600262 -262.88835) (xy 91.580971 -262.843074) (xy 91.569194 -262.79529) (xy 91.565234 -262.746236)
			(xy 91.246706 -262.746236) (xy 91.246194 -262.771682) (xy 91.23803 -262.821916) (xy 91.221914 -262.87019)
			(xy 91.198263 -262.915253) (xy 91.16769 -262.955939) (xy 91.130986 -262.991194) (xy 91.089102 -263.020104)
			(xy 91.043123 -263.041921) (xy 90.994239 -263.056081) (xy 90.943718 -263.062215) (xy 90.892866 -263.060166)
			(xy 90.843002 -263.049986) (xy 90.795416 -263.031939) (xy 90.751342 -263.006493) (xy 90.71192 -262.974306)
			(xy 90.678172 -262.936212) (xy 90.650971 -262.893198) (xy 90.631023 -262.846378) (xy 90.618844 -262.796964)
			(xy 90.614749 -262.746236) (xy 90.296238 -262.746236) (xy 90.295743 -262.770843) (xy 90.287848 -262.81942)
			(xy 90.272264 -262.866101) (xy 90.249393 -262.909678) (xy 90.219828 -262.949022) (xy 90.184335 -262.983114)
			(xy 90.143832 -263.01107) (xy 90.09937 -263.032168) (xy 90.052099 -263.04586) (xy 90.003244 -263.051792)
			(xy 89.954069 -263.049811) (xy 89.90585 -263.039967) (xy 89.859834 -263.022515) (xy 89.817213 -262.997908)
			(xy 89.779092 -262.966783) (xy 89.746457 -262.929946) (xy 89.720154 -262.88835) (xy 89.700863 -262.843074)
			(xy 89.689086 -262.79529) (xy 89.685126 -262.746236) (xy 89.356438 -262.746236) (xy 89.355943 -262.770843)
			(xy 89.348048 -262.81942) (xy 89.332464 -262.866101) (xy 89.309593 -262.909678) (xy 89.280028 -262.949022)
			(xy 89.244535 -262.983114) (xy 89.204032 -263.01107) (xy 89.15957 -263.032168) (xy 89.112299 -263.04586)
			(xy 89.063444 -263.051792) (xy 89.014269 -263.049811) (xy 88.96605 -263.039967) (xy 88.920034 -263.022515)
			(xy 88.877413 -262.997908) (xy 88.839292 -262.966783) (xy 88.806657 -262.929946) (xy 88.780354 -262.88835)
			(xy 88.761063 -262.843074) (xy 88.749286 -262.79529) (xy 88.745326 -262.746236) (xy 88.416384 -262.746236)
			(xy 88.415889 -262.770843) (xy 88.407994 -262.81942) (xy 88.39241 -262.866101) (xy 88.369539 -262.909678)
			(xy 88.339974 -262.949022) (xy 88.304481 -262.983114) (xy 88.263978 -263.01107) (xy 88.219516 -263.032168)
			(xy 88.172245 -263.04586) (xy 88.12339 -263.051792) (xy 88.074215 -263.049811) (xy 88.025996 -263.039967)
			(xy 87.97998 -263.022515) (xy 87.937359 -262.997908) (xy 87.899238 -262.966783) (xy 87.866603 -262.929946)
			(xy 87.8403 -262.88835) (xy 87.821009 -262.843074) (xy 87.809232 -262.79529) (xy 87.805272 -262.746236)
			(xy 87.47633 -262.746236) (xy 87.475835 -262.770843) (xy 87.46794 -262.81942) (xy 87.452356 -262.866101)
			(xy 87.429485 -262.909678) (xy 87.39992 -262.949022) (xy 87.364427 -262.983114) (xy 87.323924 -263.01107)
			(xy 87.279462 -263.032168) (xy 87.232191 -263.04586) (xy 87.183336 -263.051792) (xy 87.134161 -263.049811)
			(xy 87.085942 -263.039967) (xy 87.039926 -263.022515) (xy 86.997305 -262.997908) (xy 86.959184 -262.966783)
			(xy 86.926549 -262.929946) (xy 86.900246 -262.88835) (xy 86.880955 -262.843074) (xy 86.869178 -262.79529)
			(xy 86.865218 -262.746236) (xy 86.536276 -262.746236) (xy 86.535781 -262.770843) (xy 86.527886 -262.81942)
			(xy 86.512302 -262.866101) (xy 86.489431 -262.909678) (xy 86.459866 -262.949022) (xy 86.424373 -262.983114)
			(xy 86.38387 -263.01107) (xy 86.339408 -263.032168) (xy 86.292137 -263.04586) (xy 86.243282 -263.051792)
			(xy 86.194107 -263.049811) (xy 86.145888 -263.039967) (xy 86.099872 -263.022515) (xy 86.057251 -262.997908)
			(xy 86.01913 -262.966783) (xy 85.986495 -262.929946) (xy 85.960192 -262.88835) (xy 85.940901 -262.843074)
			(xy 85.929124 -262.79529) (xy 85.925164 -262.746236) (xy 85.596222 -262.746236) (xy 85.595727 -262.770843)
			(xy 85.587832 -262.81942) (xy 85.572248 -262.866101) (xy 85.549377 -262.909678) (xy 85.519812 -262.949022)
			(xy 85.484319 -262.983114) (xy 85.443816 -263.01107) (xy 85.399354 -263.032168) (xy 85.352083 -263.04586)
			(xy 85.303228 -263.051792) (xy 85.254053 -263.049811) (xy 85.205834 -263.039967) (xy 85.159818 -263.022515)
			(xy 85.117197 -262.997908) (xy 85.079076 -262.966783) (xy 85.046441 -262.929946) (xy 85.020138 -262.88835)
			(xy 85.000847 -262.843074) (xy 84.98907 -262.79529) (xy 84.98511 -262.746236) (xy 84.656422 -262.746236)
			(xy 84.655927 -262.770843) (xy 84.648032 -262.81942) (xy 84.632448 -262.866101) (xy 84.609577 -262.909678)
			(xy 84.580012 -262.949022) (xy 84.544519 -262.983114) (xy 84.504016 -263.01107) (xy 84.459554 -263.032168)
			(xy 84.412283 -263.04586) (xy 84.363428 -263.051792) (xy 84.314253 -263.049811) (xy 84.266034 -263.039967)
			(xy 84.220018 -263.022515) (xy 84.177397 -262.997908) (xy 84.139276 -262.966783) (xy 84.106641 -262.929946)
			(xy 84.080338 -262.88835) (xy 84.061047 -262.843074) (xy 84.04927 -262.79529) (xy 84.04531 -262.746236)
			(xy 83.716368 -262.746236) (xy 83.716368 -262.752078) (xy 83.715351 -262.777769) (xy 83.705779 -262.828283)
			(xy 83.68788 -262.876478) (xy 83.662159 -262.920994) (xy 83.629343 -262.960571) (xy 83.59036 -262.99409)
			(xy 83.546312 -263.020604) (xy 83.522566 -263.030462) (xy 83.512152 -263.03478) (xy 83.503516 -263.04748)
			(xy 83.499485 -263.053886) (xy 83.495093 -263.068362) (xy 83.49488 -263.075928) (xy 83.49488 -263.198356)
			(xy 83.495143 -263.203964) (xy 83.49784 -263.214858) (xy 83.500214 -263.219946) (xy 83.504786 -263.22782)
			(xy 83.508735 -263.232677) (xy 83.518491 -263.240514) (xy 83.52409 -263.243314) (xy 83.524344 -263.243568)
			(xy 83.605116 -263.280906) (xy 83.618832 -263.284208) (xy 83.631278 -263.284716) (xy 83.648042 -263.278366)
			(xy 83.6549 -263.275064) (xy 83.665314 -263.269222) (xy 83.6676 -263.267444) (xy 83.668616 -263.266682)
			(xy 83.66887 -263.266428) (xy 83.689158 -263.251355) (xy 83.73364 -263.227366) (xy 83.781455 -263.211001)
			(xy 83.831307 -263.202704) (xy 83.856576 -263.202166) (xy 83.882413 -263.202714) (xy 83.933347 -263.211428)
			(xy 83.982087 -263.228594) (xy 84.027241 -263.253722) (xy 84.067518 -263.286094) (xy 84.10177 -263.324786)
			(xy 84.129017 -263.368693) (xy 84.139278 -263.392412) (xy 84.142834 -263.399016) (xy 84.143088 -263.399524)
			(xy 84.156622 -263.423404) (xy 84.175884 -263.474796) (xy 84.185668 -263.5288) (xy 84.186268 -263.556242)
			(xy 84.51521 -263.556242) (xy 84.51917 -263.507188) (xy 84.530947 -263.459404) (xy 84.550238 -263.414128)
			(xy 84.576541 -263.372532) (xy 84.609176 -263.335695) (xy 84.647297 -263.30457) (xy 84.689918 -263.279963)
			(xy 84.735934 -263.262511) (xy 84.784153 -263.252667) (xy 84.833328 -263.250686) (xy 84.882183 -263.256618)
			(xy 84.929454 -263.27031) (xy 84.973916 -263.291408) (xy 85.014419 -263.319364) (xy 85.049912 -263.353456)
			(xy 85.079477 -263.3928) (xy 85.102348 -263.436377) (xy 85.117932 -263.483058) (xy 85.125827 -263.531635)
			(xy 85.126322 -263.556242) (xy 85.455264 -263.556242) (xy 85.459224 -263.507188) (xy 85.471001 -263.459404)
			(xy 85.490292 -263.414128) (xy 85.516595 -263.372532) (xy 85.54923 -263.335695) (xy 85.587351 -263.30457)
			(xy 85.629972 -263.279963) (xy 85.675988 -263.262511) (xy 85.724207 -263.252667) (xy 85.773382 -263.250686)
			(xy 85.822237 -263.256618) (xy 85.869508 -263.27031) (xy 85.91397 -263.291408) (xy 85.954473 -263.319364)
			(xy 85.989966 -263.353456) (xy 86.019531 -263.3928) (xy 86.042402 -263.436377) (xy 86.057986 -263.483058)
			(xy 86.065881 -263.531635) (xy 86.066376 -263.556242) (xy 87.335118 -263.556242) (xy 87.339078 -263.507188)
			(xy 87.350855 -263.459404) (xy 87.370146 -263.414128) (xy 87.396449 -263.372532) (xy 87.429084 -263.335695)
			(xy 87.467205 -263.30457) (xy 87.509826 -263.279963) (xy 87.555842 -263.262511) (xy 87.604061 -263.252667)
			(xy 87.653236 -263.250686) (xy 87.702091 -263.256618) (xy 87.749362 -263.27031) (xy 87.793824 -263.291408)
			(xy 87.834327 -263.319364) (xy 87.86982 -263.353456) (xy 87.899385 -263.3928) (xy 87.922256 -263.436377)
			(xy 87.93784 -263.483058) (xy 87.945735 -263.531635) (xy 87.94623 -263.556242) (xy 88.275172 -263.556242)
			(xy 88.279132 -263.507188) (xy 88.290909 -263.459404) (xy 88.3102 -263.414128) (xy 88.336503 -263.372532)
			(xy 88.369138 -263.335695) (xy 88.407259 -263.30457) (xy 88.44988 -263.279963) (xy 88.495896 -263.262511)
			(xy 88.544115 -263.252667) (xy 88.59329 -263.250686) (xy 88.642145 -263.256618) (xy 88.689416 -263.27031)
			(xy 88.733878 -263.291408) (xy 88.774381 -263.319364) (xy 88.809874 -263.353456) (xy 88.839439 -263.3928)
			(xy 88.86231 -263.436377) (xy 88.877894 -263.483058) (xy 88.885789 -263.531635) (xy 88.886284 -263.556242)
			(xy 89.215226 -263.556242) (xy 89.219186 -263.507188) (xy 89.230963 -263.459404) (xy 89.250254 -263.414128)
			(xy 89.276557 -263.372532) (xy 89.309192 -263.335695) (xy 89.347313 -263.30457) (xy 89.389934 -263.279963)
			(xy 89.43595 -263.262511) (xy 89.484169 -263.252667) (xy 89.533344 -263.250686) (xy 89.582199 -263.256618)
			(xy 89.62947 -263.27031) (xy 89.673932 -263.291408) (xy 89.714435 -263.319364) (xy 89.749928 -263.353456)
			(xy 89.779493 -263.3928) (xy 89.802364 -263.436377) (xy 89.817948 -263.483058) (xy 89.825843 -263.531635)
			(xy 89.826338 -263.556242) (xy 90.15528 -263.556242) (xy 90.15924 -263.507188) (xy 90.171017 -263.459404)
			(xy 90.190308 -263.414128) (xy 90.216611 -263.372532) (xy 90.249246 -263.335695) (xy 90.287367 -263.30457)
			(xy 90.329988 -263.279963) (xy 90.376004 -263.262511) (xy 90.424223 -263.252667) (xy 90.473398 -263.250686)
			(xy 90.522253 -263.256618) (xy 90.569524 -263.27031) (xy 90.613986 -263.291408) (xy 90.654489 -263.319364)
			(xy 90.689982 -263.353456) (xy 90.719547 -263.3928) (xy 90.742418 -263.436377) (xy 90.758002 -263.483058)
			(xy 90.765897 -263.531635) (xy 90.766392 -263.556242) (xy 91.084903 -263.556242) (xy 91.088998 -263.505514)
			(xy 91.101177 -263.4561) (xy 91.121125 -263.40928) (xy 91.148326 -263.366266) (xy 91.182074 -263.328172)
			(xy 91.221496 -263.295985) (xy 91.26557 -263.270539) (xy 91.313156 -263.252492) (xy 91.36302 -263.242312)
			(xy 91.413872 -263.240263) (xy 91.464393 -263.246397) (xy 91.513277 -263.260557) (xy 91.559256 -263.282374)
			(xy 91.60114 -263.311284) (xy 91.637844 -263.346539) (xy 91.668417 -263.387225) (xy 91.692068 -263.432288)
			(xy 91.708184 -263.480562) (xy 91.716348 -263.530796) (xy 91.71686 -263.556242) (xy 92.024703 -263.556242)
			(xy 92.028798 -263.505514) (xy 92.040977 -263.4561) (xy 92.060925 -263.40928) (xy 92.088126 -263.366266)
			(xy 92.121874 -263.328172) (xy 92.161296 -263.295985) (xy 92.20537 -263.270539) (xy 92.252956 -263.252492)
			(xy 92.30282 -263.242312) (xy 92.353672 -263.240263) (xy 92.404193 -263.246397) (xy 92.453077 -263.260557)
			(xy 92.499056 -263.282374) (xy 92.54094 -263.311284) (xy 92.577644 -263.346539) (xy 92.608217 -263.387225)
			(xy 92.631868 -263.432288) (xy 92.647984 -263.480562) (xy 92.656148 -263.530796) (xy 92.65666 -263.556242)
			(xy 93.904811 -263.556242) (xy 93.908906 -263.505514) (xy 93.921085 -263.4561) (xy 93.941033 -263.40928)
			(xy 93.968234 -263.366266) (xy 94.001982 -263.328172) (xy 94.041404 -263.295985) (xy 94.085478 -263.270539)
			(xy 94.133064 -263.252492) (xy 94.182928 -263.242312) (xy 94.23378 -263.240263) (xy 94.284301 -263.246397)
			(xy 94.333185 -263.260557) (xy 94.379164 -263.282374) (xy 94.421048 -263.311284) (xy 94.457752 -263.346539)
			(xy 94.488325 -263.387225) (xy 94.511976 -263.432288) (xy 94.528092 -263.480562) (xy 94.536256 -263.530796)
			(xy 94.536768 -263.556242) (xy 94.855296 -263.556242) (xy 94.859256 -263.507188) (xy 94.871033 -263.459404)
			(xy 94.890324 -263.414128) (xy 94.916627 -263.372532) (xy 94.949262 -263.335695) (xy 94.987383 -263.30457)
			(xy 95.030004 -263.279963) (xy 95.07602 -263.262511) (xy 95.124239 -263.252667) (xy 95.173414 -263.250686)
			(xy 95.222269 -263.256618) (xy 95.26954 -263.27031) (xy 95.314002 -263.291408) (xy 95.354505 -263.319364)
			(xy 95.389998 -263.353456) (xy 95.419563 -263.3928) (xy 95.442434 -263.436377) (xy 95.458018 -263.483058)
			(xy 95.465913 -263.531635) (xy 95.466408 -263.556242) (xy 95.784919 -263.556242) (xy 95.789014 -263.505514)
			(xy 95.801193 -263.4561) (xy 95.821141 -263.40928) (xy 95.848342 -263.366266) (xy 95.88209 -263.328172)
			(xy 95.921512 -263.295985) (xy 95.965586 -263.270539) (xy 96.013172 -263.252492) (xy 96.063036 -263.242312)
			(xy 96.113888 -263.240263) (xy 96.164409 -263.246397) (xy 96.213293 -263.260557) (xy 96.259272 -263.282374)
			(xy 96.301156 -263.311284) (xy 96.33786 -263.346539) (xy 96.368433 -263.387225) (xy 96.392084 -263.432288)
			(xy 96.4082 -263.480562) (xy 96.416364 -263.530796) (xy 96.416876 -263.556242) (xy 97.675204 -263.556242)
			(xy 97.679164 -263.507188) (xy 97.690941 -263.459404) (xy 97.710232 -263.414128) (xy 97.736535 -263.372532)
			(xy 97.76917 -263.335695) (xy 97.807291 -263.30457) (xy 97.849912 -263.279963) (xy 97.895928 -263.262511)
			(xy 97.944147 -263.252667) (xy 97.993322 -263.250686) (xy 98.042177 -263.256618) (xy 98.089448 -263.27031)
			(xy 98.13391 -263.291408) (xy 98.174413 -263.319364) (xy 98.209906 -263.353456) (xy 98.239471 -263.3928)
			(xy 98.262342 -263.436377) (xy 98.277926 -263.483058) (xy 98.285821 -263.531635) (xy 98.286316 -263.556242)
			(xy 99.555312 -263.556242) (xy 99.559272 -263.507188) (xy 99.571049 -263.459404) (xy 99.59034 -263.414128)
			(xy 99.616643 -263.372532) (xy 99.649278 -263.335695) (xy 99.687399 -263.30457) (xy 99.73002 -263.279963)
			(xy 99.776036 -263.262511) (xy 99.824255 -263.252667) (xy 99.87343 -263.250686) (xy 99.922285 -263.256618)
			(xy 99.969556 -263.27031) (xy 100.014018 -263.291408) (xy 100.054521 -263.319364) (xy 100.090014 -263.353456)
			(xy 100.119579 -263.3928) (xy 100.14245 -263.436377) (xy 100.158034 -263.483058) (xy 100.165929 -263.531635)
			(xy 100.166424 -263.556242) (xy 100.165929 -263.580849) (xy 100.158034 -263.629426) (xy 100.14245 -263.676107)
			(xy 100.119579 -263.719684) (xy 100.090014 -263.759028) (xy 100.054521 -263.79312) (xy 100.014018 -263.821076)
			(xy 99.969556 -263.842174) (xy 99.922285 -263.855866) (xy 99.87343 -263.861798) (xy 99.824255 -263.859817)
			(xy 99.776036 -263.849973) (xy 99.73002 -263.832521) (xy 99.687399 -263.807914) (xy 99.649278 -263.776789)
			(xy 99.616643 -263.739952) (xy 99.59034 -263.698356) (xy 99.571049 -263.65308) (xy 99.559272 -263.605296)
			(xy 99.555312 -263.556242) (xy 98.286316 -263.556242) (xy 98.285821 -263.580849) (xy 98.277926 -263.629426)
			(xy 98.262342 -263.676107) (xy 98.239471 -263.719684) (xy 98.209906 -263.759028) (xy 98.174413 -263.79312)
			(xy 98.13391 -263.821076) (xy 98.089448 -263.842174) (xy 98.042177 -263.855866) (xy 97.993322 -263.861798)
			(xy 97.944147 -263.859817) (xy 97.895928 -263.849973) (xy 97.849912 -263.832521) (xy 97.807291 -263.807914)
			(xy 97.76917 -263.776789) (xy 97.736535 -263.739952) (xy 97.710232 -263.698356) (xy 97.690941 -263.65308)
			(xy 97.679164 -263.605296) (xy 97.675204 -263.556242) (xy 96.416876 -263.556242) (xy 96.416364 -263.581688)
			(xy 96.4082 -263.631922) (xy 96.392084 -263.680196) (xy 96.368433 -263.725259) (xy 96.33786 -263.765945)
			(xy 96.301156 -263.8012) (xy 96.259272 -263.83011) (xy 96.213293 -263.851927) (xy 96.164409 -263.866087)
			(xy 96.113888 -263.872221) (xy 96.063036 -263.870172) (xy 96.013172 -263.859992) (xy 95.965586 -263.841945)
			(xy 95.921512 -263.816499) (xy 95.88209 -263.784312) (xy 95.848342 -263.746218) (xy 95.821141 -263.703204)
			(xy 95.801193 -263.656384) (xy 95.789014 -263.60697) (xy 95.784919 -263.556242) (xy 95.466408 -263.556242)
			(xy 95.465913 -263.580849) (xy 95.458018 -263.629426) (xy 95.442434 -263.676107) (xy 95.419563 -263.719684)
			(xy 95.389998 -263.759028) (xy 95.354505 -263.79312) (xy 95.314002 -263.821076) (xy 95.26954 -263.842174)
			(xy 95.222269 -263.855866) (xy 95.173414 -263.861798) (xy 95.124239 -263.859817) (xy 95.07602 -263.849973)
			(xy 95.030004 -263.832521) (xy 94.987383 -263.807914) (xy 94.949262 -263.776789) (xy 94.916627 -263.739952)
			(xy 94.890324 -263.698356) (xy 94.871033 -263.65308) (xy 94.859256 -263.605296) (xy 94.855296 -263.556242)
			(xy 94.536768 -263.556242) (xy 94.536256 -263.581688) (xy 94.528092 -263.631922) (xy 94.511976 -263.680196)
			(xy 94.488325 -263.725259) (xy 94.457752 -263.765945) (xy 94.421048 -263.8012) (xy 94.379164 -263.83011)
			(xy 94.333185 -263.851927) (xy 94.284301 -263.866087) (xy 94.23378 -263.872221) (xy 94.182928 -263.870172)
			(xy 94.133064 -263.859992) (xy 94.085478 -263.841945) (xy 94.041404 -263.816499) (xy 94.001982 -263.784312)
			(xy 93.968234 -263.746218) (xy 93.941033 -263.703204) (xy 93.921085 -263.656384) (xy 93.908906 -263.60697)
			(xy 93.904811 -263.556242) (xy 92.65666 -263.556242) (xy 92.656148 -263.581688) (xy 92.647984 -263.631922)
			(xy 92.631868 -263.680196) (xy 92.608217 -263.725259) (xy 92.577644 -263.765945) (xy 92.54094 -263.8012)
			(xy 92.499056 -263.83011) (xy 92.453077 -263.851927) (xy 92.404193 -263.866087) (xy 92.353672 -263.872221)
			(xy 92.30282 -263.870172) (xy 92.252956 -263.859992) (xy 92.20537 -263.841945) (xy 92.161296 -263.816499)
			(xy 92.121874 -263.784312) (xy 92.088126 -263.746218) (xy 92.060925 -263.703204) (xy 92.040977 -263.656384)
			(xy 92.028798 -263.60697) (xy 92.024703 -263.556242) (xy 91.71686 -263.556242) (xy 91.716348 -263.581688)
			(xy 91.708184 -263.631922) (xy 91.692068 -263.680196) (xy 91.668417 -263.725259) (xy 91.637844 -263.765945)
			(xy 91.60114 -263.8012) (xy 91.559256 -263.83011) (xy 91.513277 -263.851927) (xy 91.464393 -263.866087)
			(xy 91.413872 -263.872221) (xy 91.36302 -263.870172) (xy 91.313156 -263.859992) (xy 91.26557 -263.841945)
			(xy 91.221496 -263.816499) (xy 91.182074 -263.784312) (xy 91.148326 -263.746218) (xy 91.121125 -263.703204)
			(xy 91.101177 -263.656384) (xy 91.088998 -263.60697) (xy 91.084903 -263.556242) (xy 90.766392 -263.556242)
			(xy 90.765897 -263.580849) (xy 90.758002 -263.629426) (xy 90.742418 -263.676107) (xy 90.719547 -263.719684)
			(xy 90.689982 -263.759028) (xy 90.654489 -263.79312) (xy 90.613986 -263.821076) (xy 90.569524 -263.842174)
			(xy 90.522253 -263.855866) (xy 90.473398 -263.861798) (xy 90.424223 -263.859817) (xy 90.376004 -263.849973)
			(xy 90.329988 -263.832521) (xy 90.287367 -263.807914) (xy 90.249246 -263.776789) (xy 90.216611 -263.739952)
			(xy 90.190308 -263.698356) (xy 90.171017 -263.65308) (xy 90.15924 -263.605296) (xy 90.15528 -263.556242)
			(xy 89.826338 -263.556242) (xy 89.825843 -263.580849) (xy 89.817948 -263.629426) (xy 89.802364 -263.676107)
			(xy 89.779493 -263.719684) (xy 89.749928 -263.759028) (xy 89.714435 -263.79312) (xy 89.673932 -263.821076)
			(xy 89.62947 -263.842174) (xy 89.582199 -263.855866) (xy 89.533344 -263.861798) (xy 89.484169 -263.859817)
			(xy 89.43595 -263.849973) (xy 89.389934 -263.832521) (xy 89.347313 -263.807914) (xy 89.309192 -263.776789)
			(xy 89.276557 -263.739952) (xy 89.250254 -263.698356) (xy 89.230963 -263.65308) (xy 89.219186 -263.605296)
			(xy 89.215226 -263.556242) (xy 88.886284 -263.556242) (xy 88.885789 -263.580849) (xy 88.877894 -263.629426)
			(xy 88.86231 -263.676107) (xy 88.839439 -263.719684) (xy 88.809874 -263.759028) (xy 88.774381 -263.79312)
			(xy 88.733878 -263.821076) (xy 88.689416 -263.842174) (xy 88.642145 -263.855866) (xy 88.59329 -263.861798)
			(xy 88.544115 -263.859817) (xy 88.495896 -263.849973) (xy 88.44988 -263.832521) (xy 88.407259 -263.807914)
			(xy 88.369138 -263.776789) (xy 88.336503 -263.739952) (xy 88.3102 -263.698356) (xy 88.290909 -263.65308)
			(xy 88.279132 -263.605296) (xy 88.275172 -263.556242) (xy 87.94623 -263.556242) (xy 87.945735 -263.580849)
			(xy 87.93784 -263.629426) (xy 87.922256 -263.676107) (xy 87.899385 -263.719684) (xy 87.86982 -263.759028)
			(xy 87.834327 -263.79312) (xy 87.793824 -263.821076) (xy 87.749362 -263.842174) (xy 87.702091 -263.855866)
			(xy 87.653236 -263.861798) (xy 87.604061 -263.859817) (xy 87.555842 -263.849973) (xy 87.509826 -263.832521)
			(xy 87.467205 -263.807914) (xy 87.429084 -263.776789) (xy 87.396449 -263.739952) (xy 87.370146 -263.698356)
			(xy 87.350855 -263.65308) (xy 87.339078 -263.605296) (xy 87.335118 -263.556242) (xy 86.066376 -263.556242)
			(xy 86.065881 -263.580849) (xy 86.057986 -263.629426) (xy 86.042402 -263.676107) (xy 86.019531 -263.719684)
			(xy 85.989966 -263.759028) (xy 85.954473 -263.79312) (xy 85.91397 -263.821076) (xy 85.869508 -263.842174)
			(xy 85.822237 -263.855866) (xy 85.773382 -263.861798) (xy 85.724207 -263.859817) (xy 85.675988 -263.849973)
			(xy 85.629972 -263.832521) (xy 85.587351 -263.807914) (xy 85.54923 -263.776789) (xy 85.516595 -263.739952)
			(xy 85.490292 -263.698356) (xy 85.471001 -263.65308) (xy 85.459224 -263.605296) (xy 85.455264 -263.556242)
			(xy 85.126322 -263.556242) (xy 85.125827 -263.580849) (xy 85.117932 -263.629426) (xy 85.102348 -263.676107)
			(xy 85.079477 -263.719684) (xy 85.049912 -263.759028) (xy 85.014419 -263.79312) (xy 84.973916 -263.821076)
			(xy 84.929454 -263.842174) (xy 84.882183 -263.855866) (xy 84.833328 -263.861798) (xy 84.784153 -263.859817)
			(xy 84.735934 -263.849973) (xy 84.689918 -263.832521) (xy 84.647297 -263.807914) (xy 84.609176 -263.776789)
			(xy 84.576541 -263.739952) (xy 84.550238 -263.698356) (xy 84.530947 -263.65308) (xy 84.51917 -263.605296)
			(xy 84.51521 -263.556242) (xy 84.186268 -263.556242) (xy 84.185794 -263.58023) (xy 84.178283 -263.627614)
			(xy 84.163451 -263.67324) (xy 84.141665 -263.715984) (xy 84.11346 -263.754794) (xy 84.079531 -263.788713)
			(xy 84.040714 -263.816907) (xy 83.997964 -263.838682) (xy 83.952334 -263.853502) (xy 83.904948 -263.861001)
			(xy 83.88096 -263.86155) (xy 83.854569 -263.860999) (xy 83.802571 -263.85194) (xy 83.752903 -263.834081)
			(xy 83.707042 -263.807953) (xy 83.666353 -263.774334) (xy 83.648804 -263.754616) (xy 83.627468 -263.72947)
			(xy 83.62569 -263.72947) (xy 83.621481 -263.729547) (xy 83.613181 -263.730954) (xy 83.60918 -263.732264)
			(xy 83.521804 -263.77265) (xy 83.514019 -263.777181) (xy 83.502021 -263.7906) (xy 83.495424 -263.807347)
			(xy 83.49488 -263.816338) (xy 83.49488 -263.985248) (xy 83.494909 -263.989385) (xy 83.496178 -263.997558)
			(xy 83.49742 -264.001504) (xy 83.502246 -264.011664) (xy 83.515708 -264.032746) (xy 83.519211 -264.038006)
			(xy 83.528337 -264.046742) (xy 83.533742 -264.050018) (xy 83.533996 -264.050018) (xy 83.555755 -264.062599)
			(xy 83.595199 -264.093745) (xy 83.612482 -264.111994) (xy 83.630124 -264.132193) (xy 83.658735 -264.177547)
			(xy 83.669378 -264.202164) (xy 83.672934 -264.208768) (xy 83.673188 -264.209276) (xy 83.6867 -264.233119)
			(xy 83.705937 -264.284427) (xy 83.715727 -264.338342) (xy 83.716368 -264.36574) (xy 83.716368 -264.366248)
			(xy 84.04531 -264.366248) (xy 84.04927 -264.317194) (xy 84.061047 -264.26941) (xy 84.080338 -264.224134)
			(xy 84.106641 -264.182538) (xy 84.139276 -264.145701) (xy 84.177397 -264.114576) (xy 84.220018 -264.089969)
			(xy 84.266034 -264.072517) (xy 84.314253 -264.062673) (xy 84.363428 -264.060692) (xy 84.412283 -264.066624)
			(xy 84.459554 -264.080316) (xy 84.504016 -264.101414) (xy 84.544519 -264.12937) (xy 84.580012 -264.163462)
			(xy 84.609577 -264.202806) (xy 84.632448 -264.246383) (xy 84.648032 -264.293064) (xy 84.655927 -264.341641)
			(xy 84.656422 -264.366248) (xy 84.98511 -264.366248) (xy 84.98907 -264.317194) (xy 85.000847 -264.26941)
			(xy 85.020138 -264.224134) (xy 85.046441 -264.182538) (xy 85.079076 -264.145701) (xy 85.117197 -264.114576)
			(xy 85.159818 -264.089969) (xy 85.205834 -264.072517) (xy 85.254053 -264.062673) (xy 85.303228 -264.060692)
			(xy 85.352083 -264.066624) (xy 85.399354 -264.080316) (xy 85.443816 -264.101414) (xy 85.484319 -264.12937)
			(xy 85.519812 -264.163462) (xy 85.549377 -264.202806) (xy 85.572248 -264.246383) (xy 85.587832 -264.293064)
			(xy 85.595727 -264.341641) (xy 85.596222 -264.366248) (xy 85.925164 -264.366248) (xy 85.929124 -264.317194)
			(xy 85.940901 -264.26941) (xy 85.960192 -264.224134) (xy 85.986495 -264.182538) (xy 86.01913 -264.145701)
			(xy 86.057251 -264.114576) (xy 86.099872 -264.089969) (xy 86.145888 -264.072517) (xy 86.194107 -264.062673)
			(xy 86.243282 -264.060692) (xy 86.292137 -264.066624) (xy 86.339408 -264.080316) (xy 86.38387 -264.101414)
			(xy 86.424373 -264.12937) (xy 86.459866 -264.163462) (xy 86.489431 -264.202806) (xy 86.512302 -264.246383)
			(xy 86.527886 -264.293064) (xy 86.535781 -264.341641) (xy 86.536276 -264.366248) (xy 86.865218 -264.366248)
			(xy 86.869178 -264.317194) (xy 86.880955 -264.26941) (xy 86.900246 -264.224134) (xy 86.926549 -264.182538)
			(xy 86.959184 -264.145701) (xy 86.997305 -264.114576) (xy 87.039926 -264.089969) (xy 87.085942 -264.072517)
			(xy 87.134161 -264.062673) (xy 87.183336 -264.060692) (xy 87.232191 -264.066624) (xy 87.279462 -264.080316)
			(xy 87.323924 -264.101414) (xy 87.364427 -264.12937) (xy 87.39992 -264.163462) (xy 87.429485 -264.202806)
			(xy 87.452356 -264.246383) (xy 87.46794 -264.293064) (xy 87.475835 -264.341641) (xy 87.47633 -264.366248)
			(xy 87.805272 -264.366248) (xy 87.809232 -264.317194) (xy 87.821009 -264.26941) (xy 87.8403 -264.224134)
			(xy 87.866603 -264.182538) (xy 87.899238 -264.145701) (xy 87.937359 -264.114576) (xy 87.97998 -264.089969)
			(xy 88.025996 -264.072517) (xy 88.074215 -264.062673) (xy 88.12339 -264.060692) (xy 88.172245 -264.066624)
			(xy 88.219516 -264.080316) (xy 88.263978 -264.101414) (xy 88.304481 -264.12937) (xy 88.339974 -264.163462)
			(xy 88.369539 -264.202806) (xy 88.39241 -264.246383) (xy 88.407994 -264.293064) (xy 88.415889 -264.341641)
			(xy 88.416384 -264.366248) (xy 88.745326 -264.366248) (xy 88.749286 -264.317194) (xy 88.761063 -264.26941)
			(xy 88.780354 -264.224134) (xy 88.806657 -264.182538) (xy 88.839292 -264.145701) (xy 88.877413 -264.114576)
			(xy 88.920034 -264.089969) (xy 88.96605 -264.072517) (xy 89.014269 -264.062673) (xy 89.063444 -264.060692)
			(xy 89.112299 -264.066624) (xy 89.15957 -264.080316) (xy 89.204032 -264.101414) (xy 89.244535 -264.12937)
			(xy 89.280028 -264.163462) (xy 89.309593 -264.202806) (xy 89.332464 -264.246383) (xy 89.348048 -264.293064)
			(xy 89.355943 -264.341641) (xy 89.356438 -264.366248) (xy 89.685126 -264.366248) (xy 89.689086 -264.317194)
			(xy 89.700863 -264.26941) (xy 89.720154 -264.224134) (xy 89.746457 -264.182538) (xy 89.779092 -264.145701)
			(xy 89.817213 -264.114576) (xy 89.859834 -264.089969) (xy 89.90585 -264.072517) (xy 89.954069 -264.062673)
			(xy 90.003244 -264.060692) (xy 90.052099 -264.066624) (xy 90.09937 -264.080316) (xy 90.143832 -264.101414)
			(xy 90.184335 -264.12937) (xy 90.219828 -264.163462) (xy 90.249393 -264.202806) (xy 90.272264 -264.246383)
			(xy 90.287848 -264.293064) (xy 90.295743 -264.341641) (xy 90.296238 -264.366248) (xy 90.614749 -264.366248)
			(xy 90.618844 -264.31552) (xy 90.631023 -264.266106) (xy 90.650971 -264.219286) (xy 90.678172 -264.176272)
			(xy 90.71192 -264.138178) (xy 90.751342 -264.105991) (xy 90.795416 -264.080545) (xy 90.843002 -264.062498)
			(xy 90.892866 -264.052318) (xy 90.943718 -264.050269) (xy 90.994239 -264.056403) (xy 91.043123 -264.070563)
			(xy 91.089102 -264.09238) (xy 91.130986 -264.12129) (xy 91.16769 -264.156545) (xy 91.198263 -264.197231)
			(xy 91.221914 -264.242294) (xy 91.23803 -264.290568) (xy 91.246194 -264.340802) (xy 91.246706 -264.366248)
			(xy 91.565234 -264.366248) (xy 91.569194 -264.317194) (xy 91.580971 -264.26941) (xy 91.600262 -264.224134)
			(xy 91.626565 -264.182538) (xy 91.6592 -264.145701) (xy 91.697321 -264.114576) (xy 91.739942 -264.089969)
			(xy 91.785958 -264.072517) (xy 91.834177 -264.062673) (xy 91.883352 -264.060692) (xy 91.932207 -264.066624)
			(xy 91.979478 -264.080316) (xy 92.02394 -264.101414) (xy 92.064443 -264.12937) (xy 92.099936 -264.163462)
			(xy 92.129501 -264.202806) (xy 92.152372 -264.246383) (xy 92.167956 -264.293064) (xy 92.175851 -264.341641)
			(xy 92.176346 -264.366248) (xy 92.494857 -264.366248) (xy 92.498952 -264.31552) (xy 92.511131 -264.266106)
			(xy 92.531079 -264.219286) (xy 92.55828 -264.176272) (xy 92.592028 -264.138178) (xy 92.63145 -264.105991)
			(xy 92.675524 -264.080545) (xy 92.72311 -264.062498) (xy 92.772974 -264.052318) (xy 92.823826 -264.050269)
			(xy 92.874347 -264.056403) (xy 92.923231 -264.070563) (xy 92.96921 -264.09238) (xy 93.011094 -264.12129)
			(xy 93.047798 -264.156545) (xy 93.078371 -264.197231) (xy 93.102022 -264.242294) (xy 93.118138 -264.290568)
			(xy 93.126302 -264.340802) (xy 93.126814 -264.366248) (xy 93.445342 -264.366248) (xy 93.449302 -264.317194)
			(xy 93.461079 -264.26941) (xy 93.48037 -264.224134) (xy 93.506673 -264.182538) (xy 93.539308 -264.145701)
			(xy 93.577429 -264.114576) (xy 93.62005 -264.089969) (xy 93.666066 -264.072517) (xy 93.714285 -264.062673)
			(xy 93.76346 -264.060692) (xy 93.812315 -264.066624) (xy 93.859586 -264.080316) (xy 93.904048 -264.101414)
			(xy 93.944551 -264.12937) (xy 93.980044 -264.163462) (xy 94.009609 -264.202806) (xy 94.03248 -264.246383)
			(xy 94.048064 -264.293064) (xy 94.055959 -264.341641) (xy 94.056454 -264.366248) (xy 94.374711 -264.366248)
			(xy 94.378806 -264.31552) (xy 94.390985 -264.266106) (xy 94.410933 -264.219286) (xy 94.438134 -264.176272)
			(xy 94.471882 -264.138178) (xy 94.511304 -264.105991) (xy 94.555378 -264.080545) (xy 94.602964 -264.062498)
			(xy 94.652828 -264.052318) (xy 94.70368 -264.050269) (xy 94.754201 -264.056403) (xy 94.803085 -264.070563)
			(xy 94.849064 -264.09238) (xy 94.890948 -264.12129) (xy 94.927652 -264.156545) (xy 94.958225 -264.197231)
			(xy 94.981876 -264.242294) (xy 94.997992 -264.290568) (xy 95.006156 -264.340802) (xy 95.006668 -264.366248)
			(xy 95.314765 -264.366248) (xy 95.31886 -264.31552) (xy 95.331039 -264.266106) (xy 95.350987 -264.219286)
			(xy 95.378188 -264.176272) (xy 95.411936 -264.138178) (xy 95.451358 -264.105991) (xy 95.495432 -264.080545)
			(xy 95.543018 -264.062498) (xy 95.592882 -264.052318) (xy 95.643734 -264.050269) (xy 95.694255 -264.056403)
			(xy 95.743139 -264.070563) (xy 95.789118 -264.09238) (xy 95.831002 -264.12129) (xy 95.867706 -264.156545)
			(xy 95.898279 -264.197231) (xy 95.92193 -264.242294) (xy 95.938046 -264.290568) (xy 95.94621 -264.340802)
			(xy 95.946722 -264.366248) (xy 96.26525 -264.366248) (xy 96.26921 -264.317194) (xy 96.280987 -264.26941)
			(xy 96.300278 -264.224134) (xy 96.326581 -264.182538) (xy 96.359216 -264.145701) (xy 96.397337 -264.114576)
			(xy 96.439958 -264.089969) (xy 96.485974 -264.072517) (xy 96.534193 -264.062673) (xy 96.583368 -264.060692)
			(xy 96.632223 -264.066624) (xy 96.679494 -264.080316) (xy 96.723956 -264.101414) (xy 96.764459 -264.12937)
			(xy 96.799952 -264.163462) (xy 96.829517 -264.202806) (xy 96.852388 -264.246383) (xy 96.867972 -264.293064)
			(xy 96.875867 -264.341641) (xy 96.876362 -264.366248) (xy 98.145358 -264.366248) (xy 98.149318 -264.317194)
			(xy 98.161095 -264.26941) (xy 98.180386 -264.224134) (xy 98.206689 -264.182538) (xy 98.239324 -264.145701)
			(xy 98.277445 -264.114576) (xy 98.320066 -264.089969) (xy 98.366082 -264.072517) (xy 98.414301 -264.062673)
			(xy 98.463476 -264.060692) (xy 98.512331 -264.066624) (xy 98.559602 -264.080316) (xy 98.604064 -264.101414)
			(xy 98.644567 -264.12937) (xy 98.68006 -264.163462) (xy 98.709625 -264.202806) (xy 98.732496 -264.246383)
			(xy 98.74808 -264.293064) (xy 98.755975 -264.341641) (xy 98.75647 -264.366248) (xy 100.025212 -264.366248)
			(xy 100.029172 -264.317194) (xy 100.040949 -264.26941) (xy 100.06024 -264.224134) (xy 100.086543 -264.182538)
			(xy 100.119178 -264.145701) (xy 100.157299 -264.114576) (xy 100.19992 -264.089969) (xy 100.245936 -264.072517)
			(xy 100.294155 -264.062673) (xy 100.34333 -264.060692) (xy 100.392185 -264.066624) (xy 100.439456 -264.080316)
			(xy 100.483918 -264.101414) (xy 100.524421 -264.12937) (xy 100.559914 -264.163462) (xy 100.589479 -264.202806)
			(xy 100.61235 -264.246383) (xy 100.627934 -264.293064) (xy 100.635829 -264.341641) (xy 100.636324 -264.366248)
			(xy 100.635829 -264.390855) (xy 100.627934 -264.439432) (xy 100.61235 -264.486113) (xy 100.589479 -264.52969)
			(xy 100.559914 -264.569034) (xy 100.524421 -264.603126) (xy 100.483918 -264.631082) (xy 100.439456 -264.65218)
			(xy 100.392185 -264.665872) (xy 100.34333 -264.671804) (xy 100.294155 -264.669823) (xy 100.245936 -264.659979)
			(xy 100.19992 -264.642527) (xy 100.157299 -264.61792) (xy 100.119178 -264.586795) (xy 100.086543 -264.549958)
			(xy 100.06024 -264.508362) (xy 100.040949 -264.463086) (xy 100.029172 -264.415302) (xy 100.025212 -264.366248)
			(xy 98.75647 -264.366248) (xy 98.755975 -264.390855) (xy 98.74808 -264.439432) (xy 98.732496 -264.486113)
			(xy 98.709625 -264.52969) (xy 98.68006 -264.569034) (xy 98.644567 -264.603126) (xy 98.604064 -264.631082)
			(xy 98.559602 -264.65218) (xy 98.512331 -264.665872) (xy 98.463476 -264.671804) (xy 98.414301 -264.669823)
			(xy 98.366082 -264.659979) (xy 98.320066 -264.642527) (xy 98.277445 -264.61792) (xy 98.239324 -264.586795)
			(xy 98.206689 -264.549958) (xy 98.180386 -264.508362) (xy 98.161095 -264.463086) (xy 98.149318 -264.415302)
			(xy 98.145358 -264.366248) (xy 96.876362 -264.366248) (xy 96.875867 -264.390855) (xy 96.867972 -264.439432)
			(xy 96.852388 -264.486113) (xy 96.829517 -264.52969) (xy 96.799952 -264.569034) (xy 96.764459 -264.603126)
			(xy 96.723956 -264.631082) (xy 96.679494 -264.65218) (xy 96.632223 -264.665872) (xy 96.583368 -264.671804)
			(xy 96.534193 -264.669823) (xy 96.485974 -264.659979) (xy 96.439958 -264.642527) (xy 96.397337 -264.61792)
			(xy 96.359216 -264.586795) (xy 96.326581 -264.549958) (xy 96.300278 -264.508362) (xy 96.280987 -264.463086)
			(xy 96.26921 -264.415302) (xy 96.26525 -264.366248) (xy 95.946722 -264.366248) (xy 95.94621 -264.391694)
			(xy 95.938046 -264.441928) (xy 95.92193 -264.490202) (xy 95.898279 -264.535265) (xy 95.867706 -264.575951)
			(xy 95.831002 -264.611206) (xy 95.789118 -264.640116) (xy 95.743139 -264.661933) (xy 95.694255 -264.676093)
			(xy 95.643734 -264.682227) (xy 95.592882 -264.680178) (xy 95.543018 -264.669998) (xy 95.495432 -264.651951)
			(xy 95.451358 -264.626505) (xy 95.411936 -264.594318) (xy 95.378188 -264.556224) (xy 95.350987 -264.51321)
			(xy 95.331039 -264.46639) (xy 95.31886 -264.416976) (xy 95.314765 -264.366248) (xy 95.006668 -264.366248)
			(xy 95.006156 -264.391694) (xy 94.997992 -264.441928) (xy 94.981876 -264.490202) (xy 94.958225 -264.535265)
			(xy 94.927652 -264.575951) (xy 94.890948 -264.611206) (xy 94.849064 -264.640116) (xy 94.803085 -264.661933)
			(xy 94.754201 -264.676093) (xy 94.70368 -264.682227) (xy 94.652828 -264.680178) (xy 94.602964 -264.669998)
			(xy 94.555378 -264.651951) (xy 94.511304 -264.626505) (xy 94.471882 -264.594318) (xy 94.438134 -264.556224)
			(xy 94.410933 -264.51321) (xy 94.390985 -264.46639) (xy 94.378806 -264.416976) (xy 94.374711 -264.366248)
			(xy 94.056454 -264.366248) (xy 94.055959 -264.390855) (xy 94.048064 -264.439432) (xy 94.03248 -264.486113)
			(xy 94.009609 -264.52969) (xy 93.980044 -264.569034) (xy 93.944551 -264.603126) (xy 93.904048 -264.631082)
			(xy 93.859586 -264.65218) (xy 93.812315 -264.665872) (xy 93.76346 -264.671804) (xy 93.714285 -264.669823)
			(xy 93.666066 -264.659979) (xy 93.62005 -264.642527) (xy 93.577429 -264.61792) (xy 93.539308 -264.586795)
			(xy 93.506673 -264.549958) (xy 93.48037 -264.508362) (xy 93.461079 -264.463086) (xy 93.449302 -264.415302)
			(xy 93.445342 -264.366248) (xy 93.126814 -264.366248) (xy 93.126302 -264.391694) (xy 93.118138 -264.441928)
			(xy 93.102022 -264.490202) (xy 93.078371 -264.535265) (xy 93.047798 -264.575951) (xy 93.011094 -264.611206)
			(xy 92.96921 -264.640116) (xy 92.923231 -264.661933) (xy 92.874347 -264.676093) (xy 92.823826 -264.682227)
			(xy 92.772974 -264.680178) (xy 92.72311 -264.669998) (xy 92.675524 -264.651951) (xy 92.63145 -264.626505)
			(xy 92.592028 -264.594318) (xy 92.55828 -264.556224) (xy 92.531079 -264.51321) (xy 92.511131 -264.46639)
			(xy 92.498952 -264.416976) (xy 92.494857 -264.366248) (xy 92.176346 -264.366248) (xy 92.175851 -264.390855)
			(xy 92.167956 -264.439432) (xy 92.152372 -264.486113) (xy 92.129501 -264.52969) (xy 92.099936 -264.569034)
			(xy 92.064443 -264.603126) (xy 92.02394 -264.631082) (xy 91.979478 -264.65218) (xy 91.932207 -264.665872)
			(xy 91.883352 -264.671804) (xy 91.834177 -264.669823) (xy 91.785958 -264.659979) (xy 91.739942 -264.642527)
			(xy 91.697321 -264.61792) (xy 91.6592 -264.586795) (xy 91.626565 -264.549958) (xy 91.600262 -264.508362)
			(xy 91.580971 -264.463086) (xy 91.569194 -264.415302) (xy 91.565234 -264.366248) (xy 91.246706 -264.366248)
			(xy 91.246194 -264.391694) (xy 91.23803 -264.441928) (xy 91.221914 -264.490202) (xy 91.198263 -264.535265)
			(xy 91.16769 -264.575951) (xy 91.130986 -264.611206) (xy 91.089102 -264.640116) (xy 91.043123 -264.661933)
			(xy 90.994239 -264.676093) (xy 90.943718 -264.682227) (xy 90.892866 -264.680178) (xy 90.843002 -264.669998)
			(xy 90.795416 -264.651951) (xy 90.751342 -264.626505) (xy 90.71192 -264.594318) (xy 90.678172 -264.556224)
			(xy 90.650971 -264.51321) (xy 90.631023 -264.46639) (xy 90.618844 -264.416976) (xy 90.614749 -264.366248)
			(xy 90.296238 -264.366248) (xy 90.295743 -264.390855) (xy 90.287848 -264.439432) (xy 90.272264 -264.486113)
			(xy 90.249393 -264.52969) (xy 90.219828 -264.569034) (xy 90.184335 -264.603126) (xy 90.143832 -264.631082)
			(xy 90.09937 -264.65218) (xy 90.052099 -264.665872) (xy 90.003244 -264.671804) (xy 89.954069 -264.669823)
			(xy 89.90585 -264.659979) (xy 89.859834 -264.642527) (xy 89.817213 -264.61792) (xy 89.779092 -264.586795)
			(xy 89.746457 -264.549958) (xy 89.720154 -264.508362) (xy 89.700863 -264.463086) (xy 89.689086 -264.415302)
			(xy 89.685126 -264.366248) (xy 89.356438 -264.366248) (xy 89.355943 -264.390855) (xy 89.348048 -264.439432)
			(xy 89.332464 -264.486113) (xy 89.309593 -264.52969) (xy 89.280028 -264.569034) (xy 89.244535 -264.603126)
			(xy 89.204032 -264.631082) (xy 89.15957 -264.65218) (xy 89.112299 -264.665872) (xy 89.063444 -264.671804)
			(xy 89.014269 -264.669823) (xy 88.96605 -264.659979) (xy 88.920034 -264.642527) (xy 88.877413 -264.61792)
			(xy 88.839292 -264.586795) (xy 88.806657 -264.549958) (xy 88.780354 -264.508362) (xy 88.761063 -264.463086)
			(xy 88.749286 -264.415302) (xy 88.745326 -264.366248) (xy 88.416384 -264.366248) (xy 88.415889 -264.390855)
			(xy 88.407994 -264.439432) (xy 88.39241 -264.486113) (xy 88.369539 -264.52969) (xy 88.339974 -264.569034)
			(xy 88.304481 -264.603126) (xy 88.263978 -264.631082) (xy 88.219516 -264.65218) (xy 88.172245 -264.665872)
			(xy 88.12339 -264.671804) (xy 88.074215 -264.669823) (xy 88.025996 -264.659979) (xy 87.97998 -264.642527)
			(xy 87.937359 -264.61792) (xy 87.899238 -264.586795) (xy 87.866603 -264.549958) (xy 87.8403 -264.508362)
			(xy 87.821009 -264.463086) (xy 87.809232 -264.415302) (xy 87.805272 -264.366248) (xy 87.47633 -264.366248)
			(xy 87.475835 -264.390855) (xy 87.46794 -264.439432) (xy 87.452356 -264.486113) (xy 87.429485 -264.52969)
			(xy 87.39992 -264.569034) (xy 87.364427 -264.603126) (xy 87.323924 -264.631082) (xy 87.279462 -264.65218)
			(xy 87.232191 -264.665872) (xy 87.183336 -264.671804) (xy 87.134161 -264.669823) (xy 87.085942 -264.659979)
			(xy 87.039926 -264.642527) (xy 86.997305 -264.61792) (xy 86.959184 -264.586795) (xy 86.926549 -264.549958)
			(xy 86.900246 -264.508362) (xy 86.880955 -264.463086) (xy 86.869178 -264.415302) (xy 86.865218 -264.366248)
			(xy 86.536276 -264.366248) (xy 86.535781 -264.390855) (xy 86.527886 -264.439432) (xy 86.512302 -264.486113)
			(xy 86.489431 -264.52969) (xy 86.459866 -264.569034) (xy 86.424373 -264.603126) (xy 86.38387 -264.631082)
			(xy 86.339408 -264.65218) (xy 86.292137 -264.665872) (xy 86.243282 -264.671804) (xy 86.194107 -264.669823)
			(xy 86.145888 -264.659979) (xy 86.099872 -264.642527) (xy 86.057251 -264.61792) (xy 86.01913 -264.586795)
			(xy 85.986495 -264.549958) (xy 85.960192 -264.508362) (xy 85.940901 -264.463086) (xy 85.929124 -264.415302)
			(xy 85.925164 -264.366248) (xy 85.596222 -264.366248) (xy 85.595727 -264.390855) (xy 85.587832 -264.439432)
			(xy 85.572248 -264.486113) (xy 85.549377 -264.52969) (xy 85.519812 -264.569034) (xy 85.484319 -264.603126)
			(xy 85.443816 -264.631082) (xy 85.399354 -264.65218) (xy 85.352083 -264.665872) (xy 85.303228 -264.671804)
			(xy 85.254053 -264.669823) (xy 85.205834 -264.659979) (xy 85.159818 -264.642527) (xy 85.117197 -264.61792)
			(xy 85.079076 -264.586795) (xy 85.046441 -264.549958) (xy 85.020138 -264.508362) (xy 85.000847 -264.463086)
			(xy 84.98907 -264.415302) (xy 84.98511 -264.366248) (xy 84.656422 -264.366248) (xy 84.655927 -264.390855)
			(xy 84.648032 -264.439432) (xy 84.632448 -264.486113) (xy 84.609577 -264.52969) (xy 84.580012 -264.569034)
			(xy 84.544519 -264.603126) (xy 84.504016 -264.631082) (xy 84.459554 -264.65218) (xy 84.412283 -264.665872)
			(xy 84.363428 -264.671804) (xy 84.314253 -264.669823) (xy 84.266034 -264.659979) (xy 84.220018 -264.642527)
			(xy 84.177397 -264.61792) (xy 84.139276 -264.586795) (xy 84.106641 -264.549958) (xy 84.080338 -264.508362)
			(xy 84.061047 -264.463086) (xy 84.04927 -264.415302) (xy 84.04531 -264.366248) (xy 83.716368 -264.366248)
			(xy 83.716368 -264.37209) (xy 83.71535 -264.397781) (xy 83.705777 -264.448293) (xy 83.687876 -264.496487)
			(xy 83.662154 -264.541001) (xy 83.629338 -264.580576) (xy 83.590355 -264.614094) (xy 83.546308 -264.640607)
			(xy 83.522566 -264.650474) (xy 83.512152 -264.654792) (xy 83.503516 -264.667492) (xy 83.499487 -264.673898)
			(xy 83.495098 -264.688375) (xy 83.49488 -264.69594) (xy 83.49488 -264.818368) (xy 83.495144 -264.823975)
			(xy 83.497844 -264.834869) (xy 83.500214 -264.839958) (xy 83.504786 -264.847832) (xy 83.508736 -264.852688)
			(xy 83.518493 -264.860524) (xy 83.52409 -264.863326) (xy 83.524344 -264.86358) (xy 83.605116 -264.900918)
			(xy 83.618832 -264.90422) (xy 83.631278 -264.904728) (xy 83.648042 -264.898378) (xy 83.6549 -264.895076)
			(xy 83.665314 -264.889234) (xy 83.6676 -264.887456) (xy 83.668616 -264.886694) (xy 83.66887 -264.88644)
			(xy 83.689158 -264.871367) (xy 83.733639 -264.847377) (xy 83.781454 -264.831011) (xy 83.831307 -264.822714)
			(xy 83.856576 -264.822178) (xy 83.882413 -264.822726) (xy 83.933347 -264.83144) (xy 83.982086 -264.848606)
			(xy 84.027239 -264.873735) (xy 84.067515 -264.906107) (xy 84.101765 -264.9448) (xy 84.129011 -264.988708)
			(xy 84.139278 -265.012424) (xy 84.142834 -265.019028) (xy 84.143088 -265.019536) (xy 84.156621 -265.043416)
			(xy 84.175881 -265.094809) (xy 84.185663 -265.148813) (xy 84.186268 -265.176254) (xy 84.51521 -265.176254)
			(xy 84.51917 -265.1272) (xy 84.530947 -265.079416) (xy 84.550238 -265.03414) (xy 84.576541 -264.992544)
			(xy 84.609176 -264.955707) (xy 84.647297 -264.924582) (xy 84.689918 -264.899975) (xy 84.735934 -264.882523)
			(xy 84.784153 -264.872679) (xy 84.833328 -264.870698) (xy 84.882183 -264.87663) (xy 84.929454 -264.890322)
			(xy 84.973916 -264.91142) (xy 85.014419 -264.939376) (xy 85.049912 -264.973468) (xy 85.079477 -265.012812)
			(xy 85.102348 -265.056389) (xy 85.117932 -265.10307) (xy 85.125827 -265.151647) (xy 85.126322 -265.176254)
			(xy 85.455264 -265.176254) (xy 85.459224 -265.1272) (xy 85.471001 -265.079416) (xy 85.490292 -265.03414)
			(xy 85.516595 -264.992544) (xy 85.54923 -264.955707) (xy 85.587351 -264.924582) (xy 85.629972 -264.899975)
			(xy 85.675988 -264.882523) (xy 85.724207 -264.872679) (xy 85.773382 -264.870698) (xy 85.822237 -264.87663)
			(xy 85.869508 -264.890322) (xy 85.91397 -264.91142) (xy 85.954473 -264.939376) (xy 85.989966 -264.973468)
			(xy 86.019531 -265.012812) (xy 86.042402 -265.056389) (xy 86.057986 -265.10307) (xy 86.065881 -265.151647)
			(xy 86.066376 -265.176254) (xy 86.395318 -265.176254) (xy 86.399278 -265.1272) (xy 86.411055 -265.079416)
			(xy 86.430346 -265.03414) (xy 86.456649 -264.992544) (xy 86.489284 -264.955707) (xy 86.527405 -264.924582)
			(xy 86.570026 -264.899975) (xy 86.616042 -264.882523) (xy 86.664261 -264.872679) (xy 86.713436 -264.870698)
			(xy 86.762291 -264.87663) (xy 86.809562 -264.890322) (xy 86.854024 -264.91142) (xy 86.894527 -264.939376)
			(xy 86.93002 -264.973468) (xy 86.959585 -265.012812) (xy 86.982456 -265.056389) (xy 86.99804 -265.10307)
			(xy 87.005935 -265.151647) (xy 87.00643 -265.176254) (xy 87.335118 -265.176254) (xy 87.339078 -265.1272)
			(xy 87.350855 -265.079416) (xy 87.370146 -265.03414) (xy 87.396449 -264.992544) (xy 87.429084 -264.955707)
			(xy 87.467205 -264.924582) (xy 87.509826 -264.899975) (xy 87.555842 -264.882523) (xy 87.604061 -264.872679)
			(xy 87.653236 -264.870698) (xy 87.702091 -264.87663) (xy 87.749362 -264.890322) (xy 87.793824 -264.91142)
			(xy 87.834327 -264.939376) (xy 87.86982 -264.973468) (xy 87.899385 -265.012812) (xy 87.922256 -265.056389)
			(xy 87.93784 -265.10307) (xy 87.945735 -265.151647) (xy 87.94623 -265.176254) (xy 88.275172 -265.176254)
			(xy 88.279132 -265.1272) (xy 88.290909 -265.079416) (xy 88.3102 -265.03414) (xy 88.336503 -264.992544)
			(xy 88.369138 -264.955707) (xy 88.407259 -264.924582) (xy 88.44988 -264.899975) (xy 88.495896 -264.882523)
			(xy 88.544115 -264.872679) (xy 88.59329 -264.870698) (xy 88.642145 -264.87663) (xy 88.689416 -264.890322)
			(xy 88.733878 -264.91142) (xy 88.774381 -264.939376) (xy 88.809874 -264.973468) (xy 88.839439 -265.012812)
			(xy 88.86231 -265.056389) (xy 88.877894 -265.10307) (xy 88.885789 -265.151647) (xy 88.886284 -265.176254)
			(xy 89.215226 -265.176254) (xy 89.219186 -265.1272) (xy 89.230963 -265.079416) (xy 89.250254 -265.03414)
			(xy 89.276557 -264.992544) (xy 89.309192 -264.955707) (xy 89.347313 -264.924582) (xy 89.389934 -264.899975)
			(xy 89.43595 -264.882523) (xy 89.484169 -264.872679) (xy 89.533344 -264.870698) (xy 89.582199 -264.87663)
			(xy 89.62947 -264.890322) (xy 89.673932 -264.91142) (xy 89.714435 -264.939376) (xy 89.749928 -264.973468)
			(xy 89.779493 -265.012812) (xy 89.802364 -265.056389) (xy 89.817948 -265.10307) (xy 89.825843 -265.151647)
			(xy 89.826338 -265.176254) (xy 90.15528 -265.176254) (xy 90.15924 -265.1272) (xy 90.171017 -265.079416)
			(xy 90.190308 -265.03414) (xy 90.216611 -264.992544) (xy 90.249246 -264.955707) (xy 90.287367 -264.924582)
			(xy 90.329988 -264.899975) (xy 90.376004 -264.882523) (xy 90.424223 -264.872679) (xy 90.473398 -264.870698)
			(xy 90.522253 -264.87663) (xy 90.569524 -264.890322) (xy 90.613986 -264.91142) (xy 90.654489 -264.939376)
			(xy 90.689982 -264.973468) (xy 90.719547 -265.012812) (xy 90.742418 -265.056389) (xy 90.758002 -265.10307)
			(xy 90.765897 -265.151647) (xy 90.766392 -265.176254) (xy 91.084903 -265.176254) (xy 91.088998 -265.125526)
			(xy 91.101177 -265.076112) (xy 91.121125 -265.029292) (xy 91.148326 -264.986278) (xy 91.182074 -264.948184)
			(xy 91.221496 -264.915997) (xy 91.26557 -264.890551) (xy 91.313156 -264.872504) (xy 91.36302 -264.862324)
			(xy 91.413872 -264.860275) (xy 91.464393 -264.866409) (xy 91.513277 -264.880569) (xy 91.559256 -264.902386)
			(xy 91.60114 -264.931296) (xy 91.637844 -264.966551) (xy 91.668417 -265.007237) (xy 91.692068 -265.0523)
			(xy 91.708184 -265.100574) (xy 91.716348 -265.150808) (xy 91.71686 -265.176254) (xy 92.035134 -265.176254)
			(xy 92.039094 -265.1272) (xy 92.050871 -265.079416) (xy 92.070162 -265.03414) (xy 92.096465 -264.992544)
			(xy 92.1291 -264.955707) (xy 92.167221 -264.924582) (xy 92.209842 -264.899975) (xy 92.255858 -264.882523)
			(xy 92.304077 -264.872679) (xy 92.353252 -264.870698) (xy 92.402107 -264.87663) (xy 92.449378 -264.890322)
			(xy 92.49384 -264.91142) (xy 92.534343 -264.939376) (xy 92.569836 -264.973468) (xy 92.599401 -265.012812)
			(xy 92.622272 -265.056389) (xy 92.637856 -265.10307) (xy 92.645751 -265.151647) (xy 92.646246 -265.176254)
			(xy 92.975188 -265.176254) (xy 92.979148 -265.1272) (xy 92.990925 -265.079416) (xy 93.010216 -265.03414)
			(xy 93.036519 -264.992544) (xy 93.069154 -264.955707) (xy 93.107275 -264.924582) (xy 93.149896 -264.899975)
			(xy 93.195912 -264.882523) (xy 93.244131 -264.872679) (xy 93.293306 -264.870698) (xy 93.342161 -264.87663)
			(xy 93.389432 -264.890322) (xy 93.433894 -264.91142) (xy 93.474397 -264.939376) (xy 93.50989 -264.973468)
			(xy 93.539455 -265.012812) (xy 93.562326 -265.056389) (xy 93.57791 -265.10307) (xy 93.585805 -265.151647)
			(xy 93.5863 -265.176254) (xy 93.904811 -265.176254) (xy 93.908906 -265.125526) (xy 93.921085 -265.076112)
			(xy 93.941033 -265.029292) (xy 93.968234 -264.986278) (xy 94.001982 -264.948184) (xy 94.041404 -264.915997)
			(xy 94.085478 -264.890551) (xy 94.133064 -264.872504) (xy 94.182928 -264.862324) (xy 94.23378 -264.860275)
			(xy 94.284301 -264.866409) (xy 94.333185 -264.880569) (xy 94.379164 -264.902386) (xy 94.421048 -264.931296)
			(xy 94.457752 -264.966551) (xy 94.488325 -265.007237) (xy 94.511976 -265.0523) (xy 94.528092 -265.100574)
			(xy 94.536256 -265.150808) (xy 94.536768 -265.176254) (xy 94.855296 -265.176254) (xy 94.859256 -265.1272)
			(xy 94.871033 -265.079416) (xy 94.890324 -265.03414) (xy 94.916627 -264.992544) (xy 94.949262 -264.955707)
			(xy 94.987383 -264.924582) (xy 95.030004 -264.899975) (xy 95.07602 -264.882523) (xy 95.124239 -264.872679)
			(xy 95.173414 -264.870698) (xy 95.222269 -264.87663) (xy 95.26954 -264.890322) (xy 95.314002 -264.91142)
			(xy 95.354505 -264.939376) (xy 95.389998 -264.973468) (xy 95.419563 -265.012812) (xy 95.442434 -265.056389)
			(xy 95.458018 -265.10307) (xy 95.465913 -265.151647) (xy 95.466408 -265.176254) (xy 95.79535 -265.176254)
			(xy 95.79931 -265.1272) (xy 95.811087 -265.079416) (xy 95.830378 -265.03414) (xy 95.856681 -264.992544)
			(xy 95.889316 -264.955707) (xy 95.927437 -264.924582) (xy 95.970058 -264.899975) (xy 96.016074 -264.882523)
			(xy 96.064293 -264.872679) (xy 96.113468 -264.870698) (xy 96.162323 -264.87663) (xy 96.209594 -264.890322)
			(xy 96.254056 -264.91142) (xy 96.294559 -264.939376) (xy 96.330052 -264.973468) (xy 96.359617 -265.012812)
			(xy 96.382488 -265.056389) (xy 96.398072 -265.10307) (xy 96.405967 -265.151647) (xy 96.406462 -265.176254)
			(xy 97.675204 -265.176254) (xy 97.679164 -265.1272) (xy 97.690941 -265.079416) (xy 97.710232 -265.03414)
			(xy 97.736535 -264.992544) (xy 97.76917 -264.955707) (xy 97.807291 -264.924582) (xy 97.849912 -264.899975)
			(xy 97.895928 -264.882523) (xy 97.944147 -264.872679) (xy 97.993322 -264.870698) (xy 98.042177 -264.87663)
			(xy 98.089448 -264.890322) (xy 98.13391 -264.91142) (xy 98.174413 -264.939376) (xy 98.209906 -264.973468)
			(xy 98.239471 -265.012812) (xy 98.262342 -265.056389) (xy 98.277926 -265.10307) (xy 98.285821 -265.151647)
			(xy 98.286316 -265.176254) (xy 99.555312 -265.176254) (xy 99.559272 -265.1272) (xy 99.571049 -265.079416)
			(xy 99.59034 -265.03414) (xy 99.616643 -264.992544) (xy 99.649278 -264.955707) (xy 99.687399 -264.924582)
			(xy 99.73002 -264.899975) (xy 99.776036 -264.882523) (xy 99.824255 -264.872679) (xy 99.87343 -264.870698)
			(xy 99.922285 -264.87663) (xy 99.969556 -264.890322) (xy 100.014018 -264.91142) (xy 100.054521 -264.939376)
			(xy 100.090014 -264.973468) (xy 100.119579 -265.012812) (xy 100.14245 -265.056389) (xy 100.158034 -265.10307)
			(xy 100.165929 -265.151647) (xy 100.166424 -265.176254) (xy 100.165929 -265.200861) (xy 100.158034 -265.249438)
			(xy 100.14245 -265.296119) (xy 100.119579 -265.339696) (xy 100.090014 -265.37904) (xy 100.054521 -265.413132)
			(xy 100.014018 -265.441088) (xy 99.969556 -265.462186) (xy 99.922285 -265.475878) (xy 99.87343 -265.48181)
			(xy 99.824255 -265.479829) (xy 99.776036 -265.469985) (xy 99.73002 -265.452533) (xy 99.687399 -265.427926)
			(xy 99.649278 -265.396801) (xy 99.616643 -265.359964) (xy 99.59034 -265.318368) (xy 99.571049 -265.273092)
			(xy 99.559272 -265.225308) (xy 99.555312 -265.176254) (xy 98.286316 -265.176254) (xy 98.285821 -265.200861)
			(xy 98.277926 -265.249438) (xy 98.262342 -265.296119) (xy 98.239471 -265.339696) (xy 98.209906 -265.37904)
			(xy 98.174413 -265.413132) (xy 98.13391 -265.441088) (xy 98.089448 -265.462186) (xy 98.042177 -265.475878)
			(xy 97.993322 -265.48181) (xy 97.944147 -265.479829) (xy 97.895928 -265.469985) (xy 97.849912 -265.452533)
			(xy 97.807291 -265.427926) (xy 97.76917 -265.396801) (xy 97.736535 -265.359964) (xy 97.710232 -265.318368)
			(xy 97.690941 -265.273092) (xy 97.679164 -265.225308) (xy 97.675204 -265.176254) (xy 96.406462 -265.176254)
			(xy 96.405967 -265.200861) (xy 96.398072 -265.249438) (xy 96.382488 -265.296119) (xy 96.359617 -265.339696)
			(xy 96.330052 -265.37904) (xy 96.294559 -265.413132) (xy 96.254056 -265.441088) (xy 96.209594 -265.462186)
			(xy 96.162323 -265.475878) (xy 96.113468 -265.48181) (xy 96.064293 -265.479829) (xy 96.016074 -265.469985)
			(xy 95.970058 -265.452533) (xy 95.927437 -265.427926) (xy 95.889316 -265.396801) (xy 95.856681 -265.359964)
			(xy 95.830378 -265.318368) (xy 95.811087 -265.273092) (xy 95.79931 -265.225308) (xy 95.79535 -265.176254)
			(xy 95.466408 -265.176254) (xy 95.465913 -265.200861) (xy 95.458018 -265.249438) (xy 95.442434 -265.296119)
			(xy 95.419563 -265.339696) (xy 95.389998 -265.37904) (xy 95.354505 -265.413132) (xy 95.314002 -265.441088)
			(xy 95.26954 -265.462186) (xy 95.222269 -265.475878) (xy 95.173414 -265.48181) (xy 95.124239 -265.479829)
			(xy 95.07602 -265.469985) (xy 95.030004 -265.452533) (xy 94.987383 -265.427926) (xy 94.949262 -265.396801)
			(xy 94.916627 -265.359964) (xy 94.890324 -265.318368) (xy 94.871033 -265.273092) (xy 94.859256 -265.225308)
			(xy 94.855296 -265.176254) (xy 94.536768 -265.176254) (xy 94.536256 -265.2017) (xy 94.528092 -265.251934)
			(xy 94.511976 -265.300208) (xy 94.488325 -265.345271) (xy 94.457752 -265.385957) (xy 94.421048 -265.421212)
			(xy 94.379164 -265.450122) (xy 94.333185 -265.471939) (xy 94.284301 -265.486099) (xy 94.23378 -265.492233)
			(xy 94.182928 -265.490184) (xy 94.133064 -265.480004) (xy 94.085478 -265.461957) (xy 94.041404 -265.436511)
			(xy 94.001982 -265.404324) (xy 93.968234 -265.36623) (xy 93.941033 -265.323216) (xy 93.921085 -265.276396)
			(xy 93.908906 -265.226982) (xy 93.904811 -265.176254) (xy 93.5863 -265.176254) (xy 93.585805 -265.200861)
			(xy 93.57791 -265.249438) (xy 93.562326 -265.296119) (xy 93.539455 -265.339696) (xy 93.50989 -265.37904)
			(xy 93.474397 -265.413132) (xy 93.433894 -265.441088) (xy 93.389432 -265.462186) (xy 93.342161 -265.475878)
			(xy 93.293306 -265.48181) (xy 93.244131 -265.479829) (xy 93.195912 -265.469985) (xy 93.149896 -265.452533)
			(xy 93.107275 -265.427926) (xy 93.069154 -265.396801) (xy 93.036519 -265.359964) (xy 93.010216 -265.318368)
			(xy 92.990925 -265.273092) (xy 92.979148 -265.225308) (xy 92.975188 -265.176254) (xy 92.646246 -265.176254)
			(xy 92.645751 -265.200861) (xy 92.637856 -265.249438) (xy 92.622272 -265.296119) (xy 92.599401 -265.339696)
			(xy 92.569836 -265.37904) (xy 92.534343 -265.413132) (xy 92.49384 -265.441088) (xy 92.449378 -265.462186)
			(xy 92.402107 -265.475878) (xy 92.353252 -265.48181) (xy 92.304077 -265.479829) (xy 92.255858 -265.469985)
			(xy 92.209842 -265.452533) (xy 92.167221 -265.427926) (xy 92.1291 -265.396801) (xy 92.096465 -265.359964)
			(xy 92.070162 -265.318368) (xy 92.050871 -265.273092) (xy 92.039094 -265.225308) (xy 92.035134 -265.176254)
			(xy 91.71686 -265.176254) (xy 91.716348 -265.2017) (xy 91.708184 -265.251934) (xy 91.692068 -265.300208)
			(xy 91.668417 -265.345271) (xy 91.637844 -265.385957) (xy 91.60114 -265.421212) (xy 91.559256 -265.450122)
			(xy 91.513277 -265.471939) (xy 91.464393 -265.486099) (xy 91.413872 -265.492233) (xy 91.36302 -265.490184)
			(xy 91.313156 -265.480004) (xy 91.26557 -265.461957) (xy 91.221496 -265.436511) (xy 91.182074 -265.404324)
			(xy 91.148326 -265.36623) (xy 91.121125 -265.323216) (xy 91.101177 -265.276396) (xy 91.088998 -265.226982)
			(xy 91.084903 -265.176254) (xy 90.766392 -265.176254) (xy 90.765897 -265.200861) (xy 90.758002 -265.249438)
			(xy 90.742418 -265.296119) (xy 90.719547 -265.339696) (xy 90.689982 -265.37904) (xy 90.654489 -265.413132)
			(xy 90.613986 -265.441088) (xy 90.569524 -265.462186) (xy 90.522253 -265.475878) (xy 90.473398 -265.48181)
			(xy 90.424223 -265.479829) (xy 90.376004 -265.469985) (xy 90.329988 -265.452533) (xy 90.287367 -265.427926)
			(xy 90.249246 -265.396801) (xy 90.216611 -265.359964) (xy 90.190308 -265.318368) (xy 90.171017 -265.273092)
			(xy 90.15924 -265.225308) (xy 90.15528 -265.176254) (xy 89.826338 -265.176254) (xy 89.825843 -265.200861)
			(xy 89.817948 -265.249438) (xy 89.802364 -265.296119) (xy 89.779493 -265.339696) (xy 89.749928 -265.37904)
			(xy 89.714435 -265.413132) (xy 89.673932 -265.441088) (xy 89.62947 -265.462186) (xy 89.582199 -265.475878)
			(xy 89.533344 -265.48181) (xy 89.484169 -265.479829) (xy 89.43595 -265.469985) (xy 89.389934 -265.452533)
			(xy 89.347313 -265.427926) (xy 89.309192 -265.396801) (xy 89.276557 -265.359964) (xy 89.250254 -265.318368)
			(xy 89.230963 -265.273092) (xy 89.219186 -265.225308) (xy 89.215226 -265.176254) (xy 88.886284 -265.176254)
			(xy 88.885789 -265.200861) (xy 88.877894 -265.249438) (xy 88.86231 -265.296119) (xy 88.839439 -265.339696)
			(xy 88.809874 -265.37904) (xy 88.774381 -265.413132) (xy 88.733878 -265.441088) (xy 88.689416 -265.462186)
			(xy 88.642145 -265.475878) (xy 88.59329 -265.48181) (xy 88.544115 -265.479829) (xy 88.495896 -265.469985)
			(xy 88.44988 -265.452533) (xy 88.407259 -265.427926) (xy 88.369138 -265.396801) (xy 88.336503 -265.359964)
			(xy 88.3102 -265.318368) (xy 88.290909 -265.273092) (xy 88.279132 -265.225308) (xy 88.275172 -265.176254)
			(xy 87.94623 -265.176254) (xy 87.945735 -265.200861) (xy 87.93784 -265.249438) (xy 87.922256 -265.296119)
			(xy 87.899385 -265.339696) (xy 87.86982 -265.37904) (xy 87.834327 -265.413132) (xy 87.793824 -265.441088)
			(xy 87.749362 -265.462186) (xy 87.702091 -265.475878) (xy 87.653236 -265.48181) (xy 87.604061 -265.479829)
			(xy 87.555842 -265.469985) (xy 87.509826 -265.452533) (xy 87.467205 -265.427926) (xy 87.429084 -265.396801)
			(xy 87.396449 -265.359964) (xy 87.370146 -265.318368) (xy 87.350855 -265.273092) (xy 87.339078 -265.225308)
			(xy 87.335118 -265.176254) (xy 87.00643 -265.176254) (xy 87.005935 -265.200861) (xy 86.99804 -265.249438)
			(xy 86.982456 -265.296119) (xy 86.959585 -265.339696) (xy 86.93002 -265.37904) (xy 86.894527 -265.413132)
			(xy 86.854024 -265.441088) (xy 86.809562 -265.462186) (xy 86.762291 -265.475878) (xy 86.713436 -265.48181)
			(xy 86.664261 -265.479829) (xy 86.616042 -265.469985) (xy 86.570026 -265.452533) (xy 86.527405 -265.427926)
			(xy 86.489284 -265.396801) (xy 86.456649 -265.359964) (xy 86.430346 -265.318368) (xy 86.411055 -265.273092)
			(xy 86.399278 -265.225308) (xy 86.395318 -265.176254) (xy 86.066376 -265.176254) (xy 86.065881 -265.200861)
			(xy 86.057986 -265.249438) (xy 86.042402 -265.296119) (xy 86.019531 -265.339696) (xy 85.989966 -265.37904)
			(xy 85.954473 -265.413132) (xy 85.91397 -265.441088) (xy 85.869508 -265.462186) (xy 85.822237 -265.475878)
			(xy 85.773382 -265.48181) (xy 85.724207 -265.479829) (xy 85.675988 -265.469985) (xy 85.629972 -265.452533)
			(xy 85.587351 -265.427926) (xy 85.54923 -265.396801) (xy 85.516595 -265.359964) (xy 85.490292 -265.318368)
			(xy 85.471001 -265.273092) (xy 85.459224 -265.225308) (xy 85.455264 -265.176254) (xy 85.126322 -265.176254)
			(xy 85.125827 -265.200861) (xy 85.117932 -265.249438) (xy 85.102348 -265.296119) (xy 85.079477 -265.339696)
			(xy 85.049912 -265.37904) (xy 85.014419 -265.413132) (xy 84.973916 -265.441088) (xy 84.929454 -265.462186)
			(xy 84.882183 -265.475878) (xy 84.833328 -265.48181) (xy 84.784153 -265.479829) (xy 84.735934 -265.469985)
			(xy 84.689918 -265.452533) (xy 84.647297 -265.427926) (xy 84.609176 -265.396801) (xy 84.576541 -265.359964)
			(xy 84.550238 -265.318368) (xy 84.530947 -265.273092) (xy 84.51917 -265.225308) (xy 84.51521 -265.176254)
			(xy 84.186268 -265.176254) (xy 84.185825 -265.200248) (xy 84.178324 -265.247647) (xy 84.163499 -265.293288)
			(xy 84.141715 -265.336048) (xy 84.11351 -265.374873) (xy 84.079577 -265.408806) (xy 84.040753 -265.437012)
			(xy 83.997994 -265.458797) (xy 83.952353 -265.473623) (xy 83.904954 -265.481125) (xy 83.88096 -265.481562)
			(xy 83.85457 -265.48101) (xy 83.802574 -265.471949) (xy 83.752909 -265.454086) (xy 83.707054 -265.427953)
			(xy 83.666372 -265.394328) (xy 83.648804 -265.374628) (xy 83.627468 -265.349482) (xy 83.62569 -265.349482)
			(xy 83.621481 -265.349563) (xy 83.613182 -265.350969) (xy 83.60918 -265.352276) (xy 83.521804 -265.392662)
			(xy 83.51402 -265.397193) (xy 83.502026 -265.410613) (xy 83.495432 -265.42736) (xy 83.49488 -265.43635)
			(xy 83.49488 -265.60526) (xy 83.49491 -265.609396) (xy 83.496181 -265.61757) (xy 83.49742 -265.621516)
			(xy 83.502246 -265.631676) (xy 83.515708 -265.652758) (xy 83.519212 -265.658017) (xy 83.528339 -265.666751)
			(xy 83.533742 -265.67003) (xy 83.533996 -265.67003) (xy 83.555755 -265.682611) (xy 83.595198 -265.713758)
			(xy 83.612482 -265.732006) (xy 83.630123 -265.752205) (xy 83.658733 -265.797561) (xy 83.669378 -265.822176)
			(xy 83.672934 -265.82878) (xy 83.673188 -265.829288) (xy 83.686699 -265.853131) (xy 83.705934 -265.90444)
			(xy 83.715722 -265.958354) (xy 83.716368 -265.985752) (xy 83.716368 -265.98626) (xy 84.04531 -265.98626)
			(xy 84.04927 -265.937206) (xy 84.061047 -265.889422) (xy 84.080338 -265.844146) (xy 84.106641 -265.80255)
			(xy 84.139276 -265.765713) (xy 84.177397 -265.734588) (xy 84.220018 -265.709981) (xy 84.266034 -265.692529)
			(xy 84.314253 -265.682685) (xy 84.363428 -265.680704) (xy 84.412283 -265.686636) (xy 84.459554 -265.700328)
			(xy 84.504016 -265.721426) (xy 84.544519 -265.749382) (xy 84.580012 -265.783474) (xy 84.609577 -265.822818)
			(xy 84.632448 -265.866395) (xy 84.648032 -265.913076) (xy 84.655927 -265.961653) (xy 84.656422 -265.98626)
			(xy 84.98511 -265.98626) (xy 84.98907 -265.937206) (xy 85.000847 -265.889422) (xy 85.020138 -265.844146)
			(xy 85.046441 -265.80255) (xy 85.079076 -265.765713) (xy 85.117197 -265.734588) (xy 85.159818 -265.709981)
			(xy 85.205834 -265.692529) (xy 85.254053 -265.682685) (xy 85.303228 -265.680704) (xy 85.352083 -265.686636)
			(xy 85.399354 -265.700328) (xy 85.443816 -265.721426) (xy 85.484319 -265.749382) (xy 85.519812 -265.783474)
			(xy 85.549377 -265.822818) (xy 85.572248 -265.866395) (xy 85.587832 -265.913076) (xy 85.595727 -265.961653)
			(xy 85.596222 -265.98626) (xy 85.925164 -265.98626) (xy 85.929124 -265.937206) (xy 85.940901 -265.889422)
			(xy 85.960192 -265.844146) (xy 85.986495 -265.80255) (xy 86.01913 -265.765713) (xy 86.057251 -265.734588)
			(xy 86.099872 -265.709981) (xy 86.145888 -265.692529) (xy 86.194107 -265.682685) (xy 86.243282 -265.680704)
			(xy 86.292137 -265.686636) (xy 86.339408 -265.700328) (xy 86.38387 -265.721426) (xy 86.424373 -265.749382)
			(xy 86.459866 -265.783474) (xy 86.489431 -265.822818) (xy 86.512302 -265.866395) (xy 86.527886 -265.913076)
			(xy 86.535781 -265.961653) (xy 86.536276 -265.98626) (xy 87.805272 -265.98626) (xy 87.809232 -265.937206)
			(xy 87.821009 -265.889422) (xy 87.8403 -265.844146) (xy 87.866603 -265.80255) (xy 87.899238 -265.765713)
			(xy 87.937359 -265.734588) (xy 87.97998 -265.709981) (xy 88.025996 -265.692529) (xy 88.074215 -265.682685)
			(xy 88.12339 -265.680704) (xy 88.172245 -265.686636) (xy 88.219516 -265.700328) (xy 88.263978 -265.721426)
			(xy 88.304481 -265.749382) (xy 88.339974 -265.783474) (xy 88.369539 -265.822818) (xy 88.39241 -265.866395)
			(xy 88.407994 -265.913076) (xy 88.415889 -265.961653) (xy 88.416384 -265.98626) (xy 88.745326 -265.98626)
			(xy 88.749286 -265.937206) (xy 88.761063 -265.889422) (xy 88.780354 -265.844146) (xy 88.806657 -265.80255)
			(xy 88.839292 -265.765713) (xy 88.877413 -265.734588) (xy 88.920034 -265.709981) (xy 88.96605 -265.692529)
			(xy 89.014269 -265.682685) (xy 89.063444 -265.680704) (xy 89.112299 -265.686636) (xy 89.15957 -265.700328)
			(xy 89.204032 -265.721426) (xy 89.244535 -265.749382) (xy 89.280028 -265.783474) (xy 89.309593 -265.822818)
			(xy 89.332464 -265.866395) (xy 89.348048 -265.913076) (xy 89.355943 -265.961653) (xy 89.356438 -265.98626)
			(xy 89.685126 -265.98626) (xy 89.689086 -265.937206) (xy 89.700863 -265.889422) (xy 89.720154 -265.844146)
			(xy 89.746457 -265.80255) (xy 89.779092 -265.765713) (xy 89.817213 -265.734588) (xy 89.859834 -265.709981)
			(xy 89.90585 -265.692529) (xy 89.954069 -265.682685) (xy 90.003244 -265.680704) (xy 90.052099 -265.686636)
			(xy 90.09937 -265.700328) (xy 90.143832 -265.721426) (xy 90.184335 -265.749382) (xy 90.219828 -265.783474)
			(xy 90.249393 -265.822818) (xy 90.272264 -265.866395) (xy 90.287848 -265.913076) (xy 90.295743 -265.961653)
			(xy 90.296238 -265.98626) (xy 90.62518 -265.98626) (xy 90.62914 -265.937206) (xy 90.640917 -265.889422)
			(xy 90.660208 -265.844146) (xy 90.686511 -265.80255) (xy 90.719146 -265.765713) (xy 90.757267 -265.734588)
			(xy 90.799888 -265.709981) (xy 90.845904 -265.692529) (xy 90.894123 -265.682685) (xy 90.943298 -265.680704)
			(xy 90.992153 -265.686636) (xy 91.039424 -265.700328) (xy 91.083886 -265.721426) (xy 91.124389 -265.749382)
			(xy 91.159882 -265.783474) (xy 91.189447 -265.822818) (xy 91.212318 -265.866395) (xy 91.227902 -265.913076)
			(xy 91.235797 -265.961653) (xy 91.236292 -265.98626) (xy 91.565234 -265.98626) (xy 91.569194 -265.937206)
			(xy 91.580971 -265.889422) (xy 91.600262 -265.844146) (xy 91.626565 -265.80255) (xy 91.6592 -265.765713)
			(xy 91.697321 -265.734588) (xy 91.739942 -265.709981) (xy 91.785958 -265.692529) (xy 91.834177 -265.682685)
			(xy 91.883352 -265.680704) (xy 91.932207 -265.686636) (xy 91.979478 -265.700328) (xy 92.02394 -265.721426)
			(xy 92.064443 -265.749382) (xy 92.099936 -265.783474) (xy 92.129501 -265.822818) (xy 92.152372 -265.866395)
			(xy 92.167956 -265.913076) (xy 92.175851 -265.961653) (xy 92.176346 -265.98626) (xy 92.494857 -265.98626)
			(xy 92.498952 -265.935532) (xy 92.511131 -265.886118) (xy 92.531079 -265.839298) (xy 92.55828 -265.796284)
			(xy 92.592028 -265.75819) (xy 92.63145 -265.726003) (xy 92.675524 -265.700557) (xy 92.72311 -265.68251)
			(xy 92.772974 -265.67233) (xy 92.823826 -265.670281) (xy 92.874347 -265.676415) (xy 92.923231 -265.690575)
			(xy 92.96921 -265.712392) (xy 93.011094 -265.741302) (xy 93.047798 -265.776557) (xy 93.078371 -265.817243)
			(xy 93.102022 -265.862306) (xy 93.118138 -265.91058) (xy 93.126302 -265.960814) (xy 93.126814 -265.98626)
			(xy 94.385142 -265.98626) (xy 94.389102 -265.937206) (xy 94.400879 -265.889422) (xy 94.42017 -265.844146)
			(xy 94.446473 -265.80255) (xy 94.479108 -265.765713) (xy 94.517229 -265.734588) (xy 94.55985 -265.709981)
			(xy 94.605866 -265.692529) (xy 94.654085 -265.682685) (xy 94.70326 -265.680704) (xy 94.752115 -265.686636)
			(xy 94.799386 -265.700328) (xy 94.843848 -265.721426) (xy 94.884351 -265.749382) (xy 94.919844 -265.783474)
			(xy 94.949409 -265.822818) (xy 94.97228 -265.866395) (xy 94.987864 -265.913076) (xy 94.995759 -265.961653)
			(xy 94.996254 -265.98626) (xy 95.314765 -265.98626) (xy 95.31886 -265.935532) (xy 95.331039 -265.886118)
			(xy 95.350987 -265.839298) (xy 95.378188 -265.796284) (xy 95.411936 -265.75819) (xy 95.451358 -265.726003)
			(xy 95.495432 -265.700557) (xy 95.543018 -265.68251) (xy 95.592882 -265.67233) (xy 95.643734 -265.670281)
			(xy 95.694255 -265.676415) (xy 95.743139 -265.690575) (xy 95.789118 -265.712392) (xy 95.831002 -265.741302)
			(xy 95.867706 -265.776557) (xy 95.898279 -265.817243) (xy 95.92193 -265.862306) (xy 95.938046 -265.91058)
			(xy 95.94621 -265.960814) (xy 95.946722 -265.98626) (xy 96.26525 -265.98626) (xy 96.26921 -265.937206)
			(xy 96.280987 -265.889422) (xy 96.300278 -265.844146) (xy 96.326581 -265.80255) (xy 96.359216 -265.765713)
			(xy 96.397337 -265.734588) (xy 96.439958 -265.709981) (xy 96.485974 -265.692529) (xy 96.534193 -265.682685)
			(xy 96.583368 -265.680704) (xy 96.632223 -265.686636) (xy 96.679494 -265.700328) (xy 96.723956 -265.721426)
			(xy 96.764459 -265.749382) (xy 96.799952 -265.783474) (xy 96.829517 -265.822818) (xy 96.852388 -265.866395)
			(xy 96.867972 -265.913076) (xy 96.875867 -265.961653) (xy 96.876362 -265.98626) (xy 96.875867 -266.010867)
			(xy 96.867972 -266.059444) (xy 96.852388 -266.106125) (xy 96.829517 -266.149702) (xy 96.799952 -266.189046)
			(xy 96.764459 -266.223138) (xy 96.723956 -266.251094) (xy 96.679494 -266.272192) (xy 96.632223 -266.285884)
			(xy 96.583368 -266.291816) (xy 96.534193 -266.289835) (xy 96.485974 -266.279991) (xy 96.439958 -266.262539)
			(xy 96.397337 -266.237932) (xy 96.359216 -266.206807) (xy 96.326581 -266.16997) (xy 96.300278 -266.128374)
			(xy 96.280987 -266.083098) (xy 96.26921 -266.035314) (xy 96.26525 -265.98626) (xy 95.946722 -265.98626)
			(xy 95.94621 -266.011706) (xy 95.938046 -266.06194) (xy 95.92193 -266.110214) (xy 95.898279 -266.155277)
			(xy 95.867706 -266.195963) (xy 95.831002 -266.231218) (xy 95.789118 -266.260128) (xy 95.743139 -266.281945)
			(xy 95.694255 -266.296105) (xy 95.643734 -266.302239) (xy 95.592882 -266.30019) (xy 95.543018 -266.29001)
			(xy 95.495432 -266.271963) (xy 95.451358 -266.246517) (xy 95.411936 -266.21433) (xy 95.378188 -266.176236)
			(xy 95.350987 -266.133222) (xy 95.331039 -266.086402) (xy 95.31886 -266.036988) (xy 95.314765 -265.98626)
			(xy 94.996254 -265.98626) (xy 94.995759 -266.010867) (xy 94.987864 -266.059444) (xy 94.97228 -266.106125)
			(xy 94.949409 -266.149702) (xy 94.919844 -266.189046) (xy 94.884351 -266.223138) (xy 94.843848 -266.251094)
			(xy 94.799386 -266.272192) (xy 94.752115 -266.285884) (xy 94.70326 -266.291816) (xy 94.654085 -266.289835)
			(xy 94.605866 -266.279991) (xy 94.55985 -266.262539) (xy 94.517229 -266.237932) (xy 94.479108 -266.206807)
			(xy 94.446473 -266.16997) (xy 94.42017 -266.128374) (xy 94.400879 -266.083098) (xy 94.389102 -266.035314)
			(xy 94.385142 -265.98626) (xy 93.126814 -265.98626) (xy 93.126302 -266.011706) (xy 93.118138 -266.06194)
			(xy 93.102022 -266.110214) (xy 93.078371 -266.155277) (xy 93.047798 -266.195963) (xy 93.011094 -266.231218)
			(xy 92.96921 -266.260128) (xy 92.923231 -266.281945) (xy 92.874347 -266.296105) (xy 92.823826 -266.302239)
			(xy 92.772974 -266.30019) (xy 92.72311 -266.29001) (xy 92.675524 -266.271963) (xy 92.63145 -266.246517)
			(xy 92.592028 -266.21433) (xy 92.55828 -266.176236) (xy 92.531079 -266.133222) (xy 92.511131 -266.086402)
			(xy 92.498952 -266.036988) (xy 92.494857 -265.98626) (xy 92.176346 -265.98626) (xy 92.175851 -266.010867)
			(xy 92.167956 -266.059444) (xy 92.152372 -266.106125) (xy 92.129501 -266.149702) (xy 92.099936 -266.189046)
			(xy 92.064443 -266.223138) (xy 92.02394 -266.251094) (xy 91.979478 -266.272192) (xy 91.932207 -266.285884)
			(xy 91.883352 -266.291816) (xy 91.834177 -266.289835) (xy 91.785958 -266.279991) (xy 91.739942 -266.262539)
			(xy 91.697321 -266.237932) (xy 91.6592 -266.206807) (xy 91.626565 -266.16997) (xy 91.600262 -266.128374)
			(xy 91.580971 -266.083098) (xy 91.569194 -266.035314) (xy 91.565234 -265.98626) (xy 91.236292 -265.98626)
			(xy 91.235797 -266.010867) (xy 91.227902 -266.059444) (xy 91.212318 -266.106125) (xy 91.189447 -266.149702)
			(xy 91.159882 -266.189046) (xy 91.124389 -266.223138) (xy 91.083886 -266.251094) (xy 91.039424 -266.272192)
			(xy 90.992153 -266.285884) (xy 90.943298 -266.291816) (xy 90.894123 -266.289835) (xy 90.845904 -266.279991)
			(xy 90.799888 -266.262539) (xy 90.757267 -266.237932) (xy 90.719146 -266.206807) (xy 90.686511 -266.16997)
			(xy 90.660208 -266.128374) (xy 90.640917 -266.083098) (xy 90.62914 -266.035314) (xy 90.62518 -265.98626)
			(xy 90.296238 -265.98626) (xy 90.295743 -266.010867) (xy 90.287848 -266.059444) (xy 90.272264 -266.106125)
			(xy 90.249393 -266.149702) (xy 90.219828 -266.189046) (xy 90.184335 -266.223138) (xy 90.143832 -266.251094)
			(xy 90.09937 -266.272192) (xy 90.052099 -266.285884) (xy 90.003244 -266.291816) (xy 89.954069 -266.289835)
			(xy 89.90585 -266.279991) (xy 89.859834 -266.262539) (xy 89.817213 -266.237932) (xy 89.779092 -266.206807)
			(xy 89.746457 -266.16997) (xy 89.720154 -266.128374) (xy 89.700863 -266.083098) (xy 89.689086 -266.035314)
			(xy 89.685126 -265.98626) (xy 89.356438 -265.98626) (xy 89.355943 -266.010867) (xy 89.348048 -266.059444)
			(xy 89.332464 -266.106125) (xy 89.309593 -266.149702) (xy 89.280028 -266.189046) (xy 89.244535 -266.223138)
			(xy 89.204032 -266.251094) (xy 89.15957 -266.272192) (xy 89.112299 -266.285884) (xy 89.063444 -266.291816)
			(xy 89.014269 -266.289835) (xy 88.96605 -266.279991) (xy 88.920034 -266.262539) (xy 88.877413 -266.237932)
			(xy 88.839292 -266.206807) (xy 88.806657 -266.16997) (xy 88.780354 -266.128374) (xy 88.761063 -266.083098)
			(xy 88.749286 -266.035314) (xy 88.745326 -265.98626) (xy 88.416384 -265.98626) (xy 88.415889 -266.010867)
			(xy 88.407994 -266.059444) (xy 88.39241 -266.106125) (xy 88.369539 -266.149702) (xy 88.339974 -266.189046)
			(xy 88.304481 -266.223138) (xy 88.263978 -266.251094) (xy 88.219516 -266.272192) (xy 88.172245 -266.285884)
			(xy 88.12339 -266.291816) (xy 88.074215 -266.289835) (xy 88.025996 -266.279991) (xy 87.97998 -266.262539)
			(xy 87.937359 -266.237932) (xy 87.899238 -266.206807) (xy 87.866603 -266.16997) (xy 87.8403 -266.128374)
			(xy 87.821009 -266.083098) (xy 87.809232 -266.035314) (xy 87.805272 -265.98626) (xy 86.536276 -265.98626)
			(xy 86.535781 -266.010867) (xy 86.527886 -266.059444) (xy 86.512302 -266.106125) (xy 86.489431 -266.149702)
			(xy 86.459866 -266.189046) (xy 86.424373 -266.223138) (xy 86.38387 -266.251094) (xy 86.339408 -266.272192)
			(xy 86.292137 -266.285884) (xy 86.243282 -266.291816) (xy 86.194107 -266.289835) (xy 86.145888 -266.279991)
			(xy 86.099872 -266.262539) (xy 86.057251 -266.237932) (xy 86.01913 -266.206807) (xy 85.986495 -266.16997)
			(xy 85.960192 -266.128374) (xy 85.940901 -266.083098) (xy 85.929124 -266.035314) (xy 85.925164 -265.98626)
			(xy 85.596222 -265.98626) (xy 85.595727 -266.010867) (xy 85.587832 -266.059444) (xy 85.572248 -266.106125)
			(xy 85.549377 -266.149702) (xy 85.519812 -266.189046) (xy 85.484319 -266.223138) (xy 85.443816 -266.251094)
			(xy 85.399354 -266.272192) (xy 85.352083 -266.285884) (xy 85.303228 -266.291816) (xy 85.254053 -266.289835)
			(xy 85.205834 -266.279991) (xy 85.159818 -266.262539) (xy 85.117197 -266.237932) (xy 85.079076 -266.206807)
			(xy 85.046441 -266.16997) (xy 85.020138 -266.128374) (xy 85.000847 -266.083098) (xy 84.98907 -266.035314)
			(xy 84.98511 -265.98626) (xy 84.656422 -265.98626) (xy 84.655927 -266.010867) (xy 84.648032 -266.059444)
			(xy 84.632448 -266.106125) (xy 84.609577 -266.149702) (xy 84.580012 -266.189046) (xy 84.544519 -266.223138)
			(xy 84.504016 -266.251094) (xy 84.459554 -266.272192) (xy 84.412283 -266.285884) (xy 84.363428 -266.291816)
			(xy 84.314253 -266.289835) (xy 84.266034 -266.279991) (xy 84.220018 -266.262539) (xy 84.177397 -266.237932)
			(xy 84.139276 -266.206807) (xy 84.106641 -266.16997) (xy 84.080338 -266.128374) (xy 84.061047 -266.083098)
			(xy 84.04927 -266.035314) (xy 84.04531 -265.98626) (xy 83.716368 -265.98626) (xy 83.716368 -265.992102)
			(xy 83.715349 -266.017792) (xy 83.705774 -266.068303) (xy 83.687872 -266.116495) (xy 83.66215 -266.161007)
			(xy 83.629333 -266.200581) (xy 83.590351 -266.234097) (xy 83.546304 -266.260609) (xy 83.522566 -266.270486)
			(xy 83.512152 -266.274804) (xy 83.503516 -266.287504) (xy 83.499489 -266.293911) (xy 83.495103 -266.308387)
			(xy 83.49488 -266.315952) (xy 83.49488 -266.43838) (xy 83.495134 -266.44399) (xy 83.497817 -266.454892)
			(xy 83.500214 -266.45997) (xy 83.504786 -266.467844) (xy 83.508736 -266.472699) (xy 83.518494 -266.480533)
			(xy 83.52409 -266.483338) (xy 83.524344 -266.483592) (xy 83.605116 -266.52093) (xy 83.618832 -266.524232)
			(xy 83.631278 -266.52474) (xy 83.648042 -266.51839) (xy 83.6549 -266.515088) (xy 83.665314 -266.509246)
			(xy 83.6676 -266.507468) (xy 83.668616 -266.506706) (xy 83.66887 -266.506452) (xy 83.689157 -266.491378)
			(xy 83.733639 -266.467387) (xy 83.781454 -266.451021) (xy 83.831307 -266.442723) (xy 83.856576 -266.44219)
			(xy 83.882414 -266.442738) (xy 83.933352 -266.45145) (xy 83.982095 -266.468614) (xy 84.027254 -266.493739)
			(xy 84.067538 -266.526108) (xy 84.101797 -266.564796) (xy 84.129055 -266.6087) (xy 84.139278 -266.632436)
			(xy 84.142834 -266.63904) (xy 84.143088 -266.639548) (xy 84.15662 -266.663428) (xy 84.175878 -266.714821)
			(xy 84.185658 -266.768825) (xy 84.186268 -266.796266) (xy 84.51521 -266.796266) (xy 84.51917 -266.747212)
			(xy 84.530947 -266.699428) (xy 84.550238 -266.654152) (xy 84.576541 -266.612556) (xy 84.609176 -266.575719)
			(xy 84.647297 -266.544594) (xy 84.689918 -266.519987) (xy 84.735934 -266.502535) (xy 84.784153 -266.492691)
			(xy 84.833328 -266.49071) (xy 84.882183 -266.496642) (xy 84.929454 -266.510334) (xy 84.973916 -266.531432)
			(xy 85.014419 -266.559388) (xy 85.049912 -266.59348) (xy 85.079477 -266.632824) (xy 85.102348 -266.676401)
			(xy 85.117932 -266.723082) (xy 85.125827 -266.771659) (xy 85.126322 -266.796266) (xy 85.455264 -266.796266)
			(xy 85.459224 -266.747212) (xy 85.471001 -266.699428) (xy 85.490292 -266.654152) (xy 85.516595 -266.612556)
			(xy 85.54923 -266.575719) (xy 85.587351 -266.544594) (xy 85.629972 -266.519987) (xy 85.675988 -266.502535)
			(xy 85.724207 -266.492691) (xy 85.773382 -266.49071) (xy 85.822237 -266.496642) (xy 85.869508 -266.510334)
			(xy 85.91397 -266.531432) (xy 85.954473 -266.559388) (xy 85.989966 -266.59348) (xy 86.019531 -266.632824)
			(xy 86.042402 -266.676401) (xy 86.057986 -266.723082) (xy 86.065881 -266.771659) (xy 86.066376 -266.796266)
			(xy 86.395318 -266.796266) (xy 86.399278 -266.747212) (xy 86.411055 -266.699428) (xy 86.430346 -266.654152)
			(xy 86.456649 -266.612556) (xy 86.489284 -266.575719) (xy 86.527405 -266.544594) (xy 86.570026 -266.519987)
			(xy 86.616042 -266.502535) (xy 86.664261 -266.492691) (xy 86.713436 -266.49071) (xy 86.762291 -266.496642)
			(xy 86.809562 -266.510334) (xy 86.854024 -266.531432) (xy 86.894527 -266.559388) (xy 86.93002 -266.59348)
			(xy 86.959585 -266.632824) (xy 86.982456 -266.676401) (xy 86.99804 -266.723082) (xy 87.005935 -266.771659)
			(xy 87.00643 -266.796266) (xy 87.335118 -266.796266) (xy 87.339078 -266.747212) (xy 87.350855 -266.699428)
			(xy 87.370146 -266.654152) (xy 87.396449 -266.612556) (xy 87.429084 -266.575719) (xy 87.467205 -266.544594)
			(xy 87.509826 -266.519987) (xy 87.555842 -266.502535) (xy 87.604061 -266.492691) (xy 87.653236 -266.49071)
			(xy 87.702091 -266.496642) (xy 87.749362 -266.510334) (xy 87.793824 -266.531432) (xy 87.834327 -266.559388)
			(xy 87.86982 -266.59348) (xy 87.899385 -266.632824) (xy 87.922256 -266.676401) (xy 87.93784 -266.723082)
			(xy 87.945735 -266.771659) (xy 87.94623 -266.796266) (xy 88.275172 -266.796266) (xy 88.279132 -266.747212)
			(xy 88.290909 -266.699428) (xy 88.3102 -266.654152) (xy 88.336503 -266.612556) (xy 88.369138 -266.575719)
			(xy 88.407259 -266.544594) (xy 88.44988 -266.519987) (xy 88.495896 -266.502535) (xy 88.544115 -266.492691)
			(xy 88.59329 -266.49071) (xy 88.642145 -266.496642) (xy 88.689416 -266.510334) (xy 88.733878 -266.531432)
			(xy 88.774381 -266.559388) (xy 88.809874 -266.59348) (xy 88.839439 -266.632824) (xy 88.86231 -266.676401)
			(xy 88.877894 -266.723082) (xy 88.885789 -266.771659) (xy 88.886284 -266.796266) (xy 89.215226 -266.796266)
			(xy 89.219186 -266.747212) (xy 89.230963 -266.699428) (xy 89.250254 -266.654152) (xy 89.276557 -266.612556)
			(xy 89.309192 -266.575719) (xy 89.347313 -266.544594) (xy 89.389934 -266.519987) (xy 89.43595 -266.502535)
			(xy 89.484169 -266.492691) (xy 89.533344 -266.49071) (xy 89.582199 -266.496642) (xy 89.62947 -266.510334)
			(xy 89.673932 -266.531432) (xy 89.714435 -266.559388) (xy 89.749928 -266.59348) (xy 89.779493 -266.632824)
			(xy 89.802364 -266.676401) (xy 89.817948 -266.723082) (xy 89.825843 -266.771659) (xy 89.826338 -266.796266)
			(xy 90.15528 -266.796266) (xy 90.15924 -266.747212) (xy 90.171017 -266.699428) (xy 90.190308 -266.654152)
			(xy 90.216611 -266.612556) (xy 90.249246 -266.575719) (xy 90.287367 -266.544594) (xy 90.329988 -266.519987)
			(xy 90.376004 -266.502535) (xy 90.424223 -266.492691) (xy 90.473398 -266.49071) (xy 90.522253 -266.496642)
			(xy 90.569524 -266.510334) (xy 90.613986 -266.531432) (xy 90.654489 -266.559388) (xy 90.689982 -266.59348)
			(xy 90.719547 -266.632824) (xy 90.742418 -266.676401) (xy 90.758002 -266.723082) (xy 90.765897 -266.771659)
			(xy 90.766392 -266.796266) (xy 91.084903 -266.796266) (xy 91.088998 -266.745538) (xy 91.101177 -266.696124)
			(xy 91.121125 -266.649304) (xy 91.148326 -266.60629) (xy 91.182074 -266.568196) (xy 91.221496 -266.536009)
			(xy 91.26557 -266.510563) (xy 91.313156 -266.492516) (xy 91.36302 -266.482336) (xy 91.413872 -266.480287)
			(xy 91.464393 -266.486421) (xy 91.513277 -266.500581) (xy 91.559256 -266.522398) (xy 91.60114 -266.551308)
			(xy 91.637844 -266.586563) (xy 91.668417 -266.627249) (xy 91.692068 -266.672312) (xy 91.708184 -266.720586)
			(xy 91.716348 -266.77082) (xy 91.71686 -266.796266) (xy 92.024703 -266.796266) (xy 92.028798 -266.745538)
			(xy 92.040977 -266.696124) (xy 92.060925 -266.649304) (xy 92.088126 -266.60629) (xy 92.121874 -266.568196)
			(xy 92.161296 -266.536009) (xy 92.20537 -266.510563) (xy 92.252956 -266.492516) (xy 92.30282 -266.482336)
			(xy 92.353672 -266.480287) (xy 92.404193 -266.486421) (xy 92.453077 -266.500581) (xy 92.499056 -266.522398)
			(xy 92.54094 -266.551308) (xy 92.577644 -266.586563) (xy 92.608217 -266.627249) (xy 92.631868 -266.672312)
			(xy 92.647984 -266.720586) (xy 92.656148 -266.77082) (xy 92.65666 -266.796266) (xy 92.975188 -266.796266)
			(xy 92.979148 -266.747212) (xy 92.990925 -266.699428) (xy 93.010216 -266.654152) (xy 93.036519 -266.612556)
			(xy 93.069154 -266.575719) (xy 93.107275 -266.544594) (xy 93.149896 -266.519987) (xy 93.195912 -266.502535)
			(xy 93.244131 -266.492691) (xy 93.293306 -266.49071) (xy 93.342161 -266.496642) (xy 93.389432 -266.510334)
			(xy 93.433894 -266.531432) (xy 93.474397 -266.559388) (xy 93.50989 -266.59348) (xy 93.539455 -266.632824)
			(xy 93.562326 -266.676401) (xy 93.57791 -266.723082) (xy 93.585805 -266.771659) (xy 93.5863 -266.796266)
			(xy 93.904811 -266.796266) (xy 93.908906 -266.745538) (xy 93.921085 -266.696124) (xy 93.941033 -266.649304)
			(xy 93.968234 -266.60629) (xy 94.001982 -266.568196) (xy 94.041404 -266.536009) (xy 94.085478 -266.510563)
			(xy 94.133064 -266.492516) (xy 94.182928 -266.482336) (xy 94.23378 -266.480287) (xy 94.284301 -266.486421)
			(xy 94.333185 -266.500581) (xy 94.379164 -266.522398) (xy 94.421048 -266.551308) (xy 94.457752 -266.586563)
			(xy 94.488325 -266.627249) (xy 94.511976 -266.672312) (xy 94.528092 -266.720586) (xy 94.536256 -266.77082)
			(xy 94.536768 -266.796266) (xy 94.855296 -266.796266) (xy 94.859256 -266.747212) (xy 94.871033 -266.699428)
			(xy 94.890324 -266.654152) (xy 94.916627 -266.612556) (xy 94.949262 -266.575719) (xy 94.987383 -266.544594)
			(xy 95.030004 -266.519987) (xy 95.07602 -266.502535) (xy 95.124239 -266.492691) (xy 95.173414 -266.49071)
			(xy 95.222269 -266.496642) (xy 95.26954 -266.510334) (xy 95.314002 -266.531432) (xy 95.354505 -266.559388)
			(xy 95.389998 -266.59348) (xy 95.419563 -266.632824) (xy 95.442434 -266.676401) (xy 95.458018 -266.723082)
			(xy 95.465913 -266.771659) (xy 95.466408 -266.796266) (xy 95.784919 -266.796266) (xy 95.789014 -266.745538)
			(xy 95.801193 -266.696124) (xy 95.821141 -266.649304) (xy 95.848342 -266.60629) (xy 95.88209 -266.568196)
			(xy 95.921512 -266.536009) (xy 95.965586 -266.510563) (xy 96.013172 -266.492516) (xy 96.063036 -266.482336)
			(xy 96.113888 -266.480287) (xy 96.164409 -266.486421) (xy 96.213293 -266.500581) (xy 96.259272 -266.522398)
			(xy 96.301156 -266.551308) (xy 96.33786 -266.586563) (xy 96.368433 -266.627249) (xy 96.392084 -266.672312)
			(xy 96.4082 -266.720586) (xy 96.416364 -266.77082) (xy 96.416876 -266.796266) (xy 96.416364 -266.821712)
			(xy 96.4082 -266.871946) (xy 96.392084 -266.92022) (xy 96.368433 -266.965283) (xy 96.33786 -267.005969)
			(xy 96.301156 -267.041224) (xy 96.259272 -267.070134) (xy 96.213293 -267.091951) (xy 96.164409 -267.106111)
			(xy 96.113888 -267.112245) (xy 96.063036 -267.110196) (xy 96.013172 -267.100016) (xy 95.965586 -267.081969)
			(xy 95.921512 -267.056523) (xy 95.88209 -267.024336) (xy 95.848342 -266.986242) (xy 95.821141 -266.943228)
			(xy 95.801193 -266.896408) (xy 95.789014 -266.846994) (xy 95.784919 -266.796266) (xy 95.466408 -266.796266)
			(xy 95.465913 -266.820873) (xy 95.458018 -266.86945) (xy 95.442434 -266.916131) (xy 95.419563 -266.959708)
			(xy 95.389998 -266.999052) (xy 95.354505 -267.033144) (xy 95.314002 -267.0611) (xy 95.26954 -267.082198)
			(xy 95.222269 -267.09589) (xy 95.173414 -267.101822) (xy 95.124239 -267.099841) (xy 95.07602 -267.089997)
			(xy 95.030004 -267.072545) (xy 94.987383 -267.047938) (xy 94.949262 -267.016813) (xy 94.916627 -266.979976)
			(xy 94.890324 -266.93838) (xy 94.871033 -266.893104) (xy 94.859256 -266.84532) (xy 94.855296 -266.796266)
			(xy 94.536768 -266.796266) (xy 94.536256 -266.821712) (xy 94.528092 -266.871946) (xy 94.511976 -266.92022)
			(xy 94.488325 -266.965283) (xy 94.457752 -267.005969) (xy 94.421048 -267.041224) (xy 94.379164 -267.070134)
			(xy 94.333185 -267.091951) (xy 94.284301 -267.106111) (xy 94.23378 -267.112245) (xy 94.182928 -267.110196)
			(xy 94.133064 -267.100016) (xy 94.085478 -267.081969) (xy 94.041404 -267.056523) (xy 94.001982 -267.024336)
			(xy 93.968234 -266.986242) (xy 93.941033 -266.943228) (xy 93.921085 -266.896408) (xy 93.908906 -266.846994)
			(xy 93.904811 -266.796266) (xy 93.5863 -266.796266) (xy 93.585805 -266.820873) (xy 93.57791 -266.86945)
			(xy 93.562326 -266.916131) (xy 93.539455 -266.959708) (xy 93.50989 -266.999052) (xy 93.474397 -267.033144)
			(xy 93.433894 -267.0611) (xy 93.389432 -267.082198) (xy 93.342161 -267.09589) (xy 93.293306 -267.101822)
			(xy 93.244131 -267.099841) (xy 93.195912 -267.089997) (xy 93.149896 -267.072545) (xy 93.107275 -267.047938)
			(xy 93.069154 -267.016813) (xy 93.036519 -266.979976) (xy 93.010216 -266.93838) (xy 92.990925 -266.893104)
			(xy 92.979148 -266.84532) (xy 92.975188 -266.796266) (xy 92.65666 -266.796266) (xy 92.656148 -266.821712)
			(xy 92.647984 -266.871946) (xy 92.631868 -266.92022) (xy 92.608217 -266.965283) (xy 92.577644 -267.005969)
			(xy 92.54094 -267.041224) (xy 92.499056 -267.070134) (xy 92.453077 -267.091951) (xy 92.404193 -267.106111)
			(xy 92.353672 -267.112245) (xy 92.30282 -267.110196) (xy 92.252956 -267.100016) (xy 92.20537 -267.081969)
			(xy 92.161296 -267.056523) (xy 92.121874 -267.024336) (xy 92.088126 -266.986242) (xy 92.060925 -266.943228)
			(xy 92.040977 -266.896408) (xy 92.028798 -266.846994) (xy 92.024703 -266.796266) (xy 91.71686 -266.796266)
			(xy 91.716348 -266.821712) (xy 91.708184 -266.871946) (xy 91.692068 -266.92022) (xy 91.668417 -266.965283)
			(xy 91.637844 -267.005969) (xy 91.60114 -267.041224) (xy 91.559256 -267.070134) (xy 91.513277 -267.091951)
			(xy 91.464393 -267.106111) (xy 91.413872 -267.112245) (xy 91.36302 -267.110196) (xy 91.313156 -267.100016)
			(xy 91.26557 -267.081969) (xy 91.221496 -267.056523) (xy 91.182074 -267.024336) (xy 91.148326 -266.986242)
			(xy 91.121125 -266.943228) (xy 91.101177 -266.896408) (xy 91.088998 -266.846994) (xy 91.084903 -266.796266)
			(xy 90.766392 -266.796266) (xy 90.765897 -266.820873) (xy 90.758002 -266.86945) (xy 90.742418 -266.916131)
			(xy 90.719547 -266.959708) (xy 90.689982 -266.999052) (xy 90.654489 -267.033144) (xy 90.613986 -267.0611)
			(xy 90.569524 -267.082198) (xy 90.522253 -267.09589) (xy 90.473398 -267.101822) (xy 90.424223 -267.099841)
			(xy 90.376004 -267.089997) (xy 90.329988 -267.072545) (xy 90.287367 -267.047938) (xy 90.249246 -267.016813)
			(xy 90.216611 -266.979976) (xy 90.190308 -266.93838) (xy 90.171017 -266.893104) (xy 90.15924 -266.84532)
			(xy 90.15528 -266.796266) (xy 89.826338 -266.796266) (xy 89.825843 -266.820873) (xy 89.817948 -266.86945)
			(xy 89.802364 -266.916131) (xy 89.779493 -266.959708) (xy 89.749928 -266.999052) (xy 89.714435 -267.033144)
			(xy 89.673932 -267.0611) (xy 89.62947 -267.082198) (xy 89.582199 -267.09589) (xy 89.533344 -267.101822)
			(xy 89.484169 -267.099841) (xy 89.43595 -267.089997) (xy 89.389934 -267.072545) (xy 89.347313 -267.047938)
			(xy 89.309192 -267.016813) (xy 89.276557 -266.979976) (xy 89.250254 -266.93838) (xy 89.230963 -266.893104)
			(xy 89.219186 -266.84532) (xy 89.215226 -266.796266) (xy 88.886284 -266.796266) (xy 88.885789 -266.820873)
			(xy 88.877894 -266.86945) (xy 88.86231 -266.916131) (xy 88.839439 -266.959708) (xy 88.809874 -266.999052)
			(xy 88.774381 -267.033144) (xy 88.733878 -267.0611) (xy 88.689416 -267.082198) (xy 88.642145 -267.09589)
			(xy 88.59329 -267.101822) (xy 88.544115 -267.099841) (xy 88.495896 -267.089997) (xy 88.44988 -267.072545)
			(xy 88.407259 -267.047938) (xy 88.369138 -267.016813) (xy 88.336503 -266.979976) (xy 88.3102 -266.93838)
			(xy 88.290909 -266.893104) (xy 88.279132 -266.84532) (xy 88.275172 -266.796266) (xy 87.94623 -266.796266)
			(xy 87.945735 -266.820873) (xy 87.93784 -266.86945) (xy 87.922256 -266.916131) (xy 87.899385 -266.959708)
			(xy 87.86982 -266.999052) (xy 87.834327 -267.033144) (xy 87.793824 -267.0611) (xy 87.749362 -267.082198)
			(xy 87.702091 -267.09589) (xy 87.653236 -267.101822) (xy 87.604061 -267.099841) (xy 87.555842 -267.089997)
			(xy 87.509826 -267.072545) (xy 87.467205 -267.047938) (xy 87.429084 -267.016813) (xy 87.396449 -266.979976)
			(xy 87.370146 -266.93838) (xy 87.350855 -266.893104) (xy 87.339078 -266.84532) (xy 87.335118 -266.796266)
			(xy 87.00643 -266.796266) (xy 87.005935 -266.820873) (xy 86.99804 -266.86945) (xy 86.982456 -266.916131)
			(xy 86.959585 -266.959708) (xy 86.93002 -266.999052) (xy 86.894527 -267.033144) (xy 86.854024 -267.0611)
			(xy 86.809562 -267.082198) (xy 86.762291 -267.09589) (xy 86.713436 -267.101822) (xy 86.664261 -267.099841)
			(xy 86.616042 -267.089997) (xy 86.570026 -267.072545) (xy 86.527405 -267.047938) (xy 86.489284 -267.016813)
			(xy 86.456649 -266.979976) (xy 86.430346 -266.93838) (xy 86.411055 -266.893104) (xy 86.399278 -266.84532)
			(xy 86.395318 -266.796266) (xy 86.066376 -266.796266) (xy 86.065881 -266.820873) (xy 86.057986 -266.86945)
			(xy 86.042402 -266.916131) (xy 86.019531 -266.959708) (xy 85.989966 -266.999052) (xy 85.954473 -267.033144)
			(xy 85.91397 -267.0611) (xy 85.869508 -267.082198) (xy 85.822237 -267.09589) (xy 85.773382 -267.101822)
			(xy 85.724207 -267.099841) (xy 85.675988 -267.089997) (xy 85.629972 -267.072545) (xy 85.587351 -267.047938)
			(xy 85.54923 -267.016813) (xy 85.516595 -266.979976) (xy 85.490292 -266.93838) (xy 85.471001 -266.893104)
			(xy 85.459224 -266.84532) (xy 85.455264 -266.796266) (xy 85.126322 -266.796266) (xy 85.125827 -266.820873)
			(xy 85.117932 -266.86945) (xy 85.102348 -266.916131) (xy 85.079477 -266.959708) (xy 85.049912 -266.999052)
			(xy 85.014419 -267.033144) (xy 84.973916 -267.0611) (xy 84.929454 -267.082198) (xy 84.882183 -267.09589)
			(xy 84.833328 -267.101822) (xy 84.784153 -267.099841) (xy 84.735934 -267.089997) (xy 84.689918 -267.072545)
			(xy 84.647297 -267.047938) (xy 84.609176 -267.016813) (xy 84.576541 -266.979976) (xy 84.550238 -266.93838)
			(xy 84.530947 -266.893104) (xy 84.51917 -266.84532) (xy 84.51521 -266.796266) (xy 84.186268 -266.796266)
			(xy 84.185824 -266.82026) (xy 84.178322 -266.867657) (xy 84.163496 -266.913297) (xy 84.141711 -266.956055)
			(xy 84.113506 -266.994878) (xy 84.079573 -267.02881) (xy 84.040749 -267.057014) (xy 83.997991 -267.078798)
			(xy 83.952351 -267.093623) (xy 83.904954 -267.101125) (xy 83.88096 -267.101574) (xy 83.85457 -267.101022)
			(xy 83.802574 -267.091961) (xy 83.752909 -267.074099) (xy 83.707052 -267.047967) (xy 83.666369 -267.014343)
			(xy 83.648804 -266.99464) (xy 83.627468 -266.969494) (xy 83.62569 -266.969494) (xy 83.621481 -266.969575)
			(xy 83.613182 -266.970981) (xy 83.60918 -266.972288) (xy 83.521804 -267.012674) (xy 83.514021 -267.017206)
			(xy 83.50203 -267.030626) (xy 83.49544 -267.047373) (xy 83.49488 -267.056362) (xy 83.49488 -267.225272)
			(xy 83.494911 -267.229408) (xy 83.496184 -267.237581) (xy 83.49742 -267.241528) (xy 83.502246 -267.251688)
			(xy 83.515708 -267.27277) (xy 83.519212 -267.278029) (xy 83.528341 -267.286761) (xy 83.533742 -267.290042)
			(xy 83.533996 -267.290042) (xy 83.555754 -267.302624) (xy 83.595197 -267.333771) (xy 83.612482 -267.352018)
			(xy 83.630122 -267.372218) (xy 83.658731 -267.417574) (xy 83.669378 -267.442188) (xy 83.672934 -267.448792)
			(xy 83.673188 -267.4493) (xy 83.686705 -267.473141) (xy 83.705956 -267.524449) (xy 83.715759 -267.578365)
			(xy 83.716368 -267.605764) (xy 83.716368 -267.606272) (xy 84.04531 -267.606272) (xy 84.04927 -267.557218)
			(xy 84.061047 -267.509434) (xy 84.080338 -267.464158) (xy 84.106641 -267.422562) (xy 84.139276 -267.385725)
			(xy 84.177397 -267.3546) (xy 84.220018 -267.329993) (xy 84.266034 -267.312541) (xy 84.314253 -267.302697)
			(xy 84.363428 -267.300716) (xy 84.412283 -267.306648) (xy 84.459554 -267.32034) (xy 84.504016 -267.341438)
			(xy 84.544519 -267.369394) (xy 84.580012 -267.403486) (xy 84.609577 -267.44283) (xy 84.632448 -267.486407)
			(xy 84.648032 -267.533088) (xy 84.655927 -267.581665) (xy 84.656422 -267.606272) (xy 84.98511 -267.606272)
			(xy 84.98907 -267.557218) (xy 85.000847 -267.509434) (xy 85.020138 -267.464158) (xy 85.046441 -267.422562)
			(xy 85.079076 -267.385725) (xy 85.117197 -267.3546) (xy 85.159818 -267.329993) (xy 85.205834 -267.312541)
			(xy 85.254053 -267.302697) (xy 85.303228 -267.300716) (xy 85.352083 -267.306648) (xy 85.399354 -267.32034)
			(xy 85.443816 -267.341438) (xy 85.484319 -267.369394) (xy 85.519812 -267.403486) (xy 85.549377 -267.44283)
			(xy 85.572248 -267.486407) (xy 85.587832 -267.533088) (xy 85.595727 -267.581665) (xy 85.596222 -267.606272)
			(xy 85.925164 -267.606272) (xy 85.929124 -267.557218) (xy 85.940901 -267.509434) (xy 85.960192 -267.464158)
			(xy 85.986495 -267.422562) (xy 86.01913 -267.385725) (xy 86.057251 -267.3546) (xy 86.099872 -267.329993)
			(xy 86.145888 -267.312541) (xy 86.194107 -267.302697) (xy 86.243282 -267.300716) (xy 86.292137 -267.306648)
			(xy 86.339408 -267.32034) (xy 86.38387 -267.341438) (xy 86.424373 -267.369394) (xy 86.459866 -267.403486)
			(xy 86.489431 -267.44283) (xy 86.512302 -267.486407) (xy 86.527886 -267.533088) (xy 86.535781 -267.581665)
			(xy 86.536276 -267.606272) (xy 86.865218 -267.606272) (xy 86.869178 -267.557218) (xy 86.880955 -267.509434)
			(xy 86.900246 -267.464158) (xy 86.926549 -267.422562) (xy 86.959184 -267.385725) (xy 86.997305 -267.3546)
			(xy 87.039926 -267.329993) (xy 87.085942 -267.312541) (xy 87.134161 -267.302697) (xy 87.183336 -267.300716)
			(xy 87.232191 -267.306648) (xy 87.279462 -267.32034) (xy 87.323924 -267.341438) (xy 87.364427 -267.369394)
			(xy 87.39992 -267.403486) (xy 87.429485 -267.44283) (xy 87.452356 -267.486407) (xy 87.46794 -267.533088)
			(xy 87.475835 -267.581665) (xy 87.47633 -267.606272) (xy 87.805272 -267.606272) (xy 87.809232 -267.557218)
			(xy 87.821009 -267.509434) (xy 87.8403 -267.464158) (xy 87.866603 -267.422562) (xy 87.899238 -267.385725)
			(xy 87.937359 -267.3546) (xy 87.97998 -267.329993) (xy 88.025996 -267.312541) (xy 88.074215 -267.302697)
			(xy 88.12339 -267.300716) (xy 88.172245 -267.306648) (xy 88.219516 -267.32034) (xy 88.263978 -267.341438)
			(xy 88.304481 -267.369394) (xy 88.339974 -267.403486) (xy 88.369539 -267.44283) (xy 88.39241 -267.486407)
			(xy 88.407994 -267.533088) (xy 88.415889 -267.581665) (xy 88.416384 -267.606272) (xy 88.745326 -267.606272)
			(xy 88.749286 -267.557218) (xy 88.761063 -267.509434) (xy 88.780354 -267.464158) (xy 88.806657 -267.422562)
			(xy 88.839292 -267.385725) (xy 88.877413 -267.3546) (xy 88.920034 -267.329993) (xy 88.96605 -267.312541)
			(xy 89.014269 -267.302697) (xy 89.063444 -267.300716) (xy 89.112299 -267.306648) (xy 89.15957 -267.32034)
			(xy 89.204032 -267.341438) (xy 89.244535 -267.369394) (xy 89.280028 -267.403486) (xy 89.309593 -267.44283)
			(xy 89.332464 -267.486407) (xy 89.348048 -267.533088) (xy 89.355943 -267.581665) (xy 89.356438 -267.606272)
			(xy 89.685126 -267.606272) (xy 89.689086 -267.557218) (xy 89.700863 -267.509434) (xy 89.720154 -267.464158)
			(xy 89.746457 -267.422562) (xy 89.779092 -267.385725) (xy 89.817213 -267.3546) (xy 89.859834 -267.329993)
			(xy 89.90585 -267.312541) (xy 89.954069 -267.302697) (xy 90.003244 -267.300716) (xy 90.052099 -267.306648)
			(xy 90.09937 -267.32034) (xy 90.143832 -267.341438) (xy 90.184335 -267.369394) (xy 90.219828 -267.403486)
			(xy 90.249393 -267.44283) (xy 90.272264 -267.486407) (xy 90.287848 -267.533088) (xy 90.295743 -267.581665)
			(xy 90.296238 -267.606272) (xy 90.614749 -267.606272) (xy 90.618844 -267.555544) (xy 90.631023 -267.50613)
			(xy 90.650971 -267.45931) (xy 90.678172 -267.416296) (xy 90.71192 -267.378202) (xy 90.751342 -267.346015)
			(xy 90.795416 -267.320569) (xy 90.843002 -267.302522) (xy 90.892866 -267.292342) (xy 90.943718 -267.290293)
			(xy 90.994239 -267.296427) (xy 91.043123 -267.310587) (xy 91.089102 -267.332404) (xy 91.130986 -267.361314)
			(xy 91.16769 -267.396569) (xy 91.198263 -267.437255) (xy 91.221914 -267.482318) (xy 91.23803 -267.530592)
			(xy 91.246194 -267.580826) (xy 91.246706 -267.606272) (xy 91.565234 -267.606272) (xy 91.569194 -267.557218)
			(xy 91.580971 -267.509434) (xy 91.600262 -267.464158) (xy 91.626565 -267.422562) (xy 91.6592 -267.385725)
			(xy 91.697321 -267.3546) (xy 91.739942 -267.329993) (xy 91.785958 -267.312541) (xy 91.834177 -267.302697)
			(xy 91.883352 -267.300716) (xy 91.932207 -267.306648) (xy 91.979478 -267.32034) (xy 92.02394 -267.341438)
			(xy 92.064443 -267.369394) (xy 92.099936 -267.403486) (xy 92.129501 -267.44283) (xy 92.152372 -267.486407)
			(xy 92.167956 -267.533088) (xy 92.175851 -267.581665) (xy 92.176346 -267.606272) (xy 92.505288 -267.606272)
			(xy 92.509248 -267.557218) (xy 92.521025 -267.509434) (xy 92.540316 -267.464158) (xy 92.566619 -267.422562)
			(xy 92.599254 -267.385725) (xy 92.637375 -267.3546) (xy 92.679996 -267.329993) (xy 92.726012 -267.312541)
			(xy 92.774231 -267.302697) (xy 92.823406 -267.300716) (xy 92.872261 -267.306648) (xy 92.919532 -267.32034)
			(xy 92.963994 -267.341438) (xy 93.004497 -267.369394) (xy 93.03999 -267.403486) (xy 93.069555 -267.44283)
			(xy 93.092426 -267.486407) (xy 93.10801 -267.533088) (xy 93.115905 -267.581665) (xy 93.1164 -267.606272)
			(xy 93.445342 -267.606272) (xy 93.449302 -267.557218) (xy 93.461079 -267.509434) (xy 93.48037 -267.464158)
			(xy 93.506673 -267.422562) (xy 93.539308 -267.385725) (xy 93.577429 -267.3546) (xy 93.62005 -267.329993)
			(xy 93.666066 -267.312541) (xy 93.714285 -267.302697) (xy 93.76346 -267.300716) (xy 93.812315 -267.306648)
			(xy 93.859586 -267.32034) (xy 93.904048 -267.341438) (xy 93.944551 -267.369394) (xy 93.980044 -267.403486)
			(xy 94.009609 -267.44283) (xy 94.03248 -267.486407) (xy 94.048064 -267.533088) (xy 94.055959 -267.581665)
			(xy 94.056454 -267.606272) (xy 94.374711 -267.606272) (xy 94.378806 -267.555544) (xy 94.390985 -267.50613)
			(xy 94.410933 -267.45931) (xy 94.438134 -267.416296) (xy 94.471882 -267.378202) (xy 94.511304 -267.346015)
			(xy 94.555378 -267.320569) (xy 94.602964 -267.302522) (xy 94.652828 -267.292342) (xy 94.70368 -267.290293)
			(xy 94.754201 -267.296427) (xy 94.803085 -267.310587) (xy 94.849064 -267.332404) (xy 94.890948 -267.361314)
			(xy 94.927652 -267.396569) (xy 94.958225 -267.437255) (xy 94.981876 -267.482318) (xy 94.997992 -267.530592)
			(xy 95.006156 -267.580826) (xy 95.006668 -267.606272) (xy 95.325196 -267.606272) (xy 95.329156 -267.557218)
			(xy 95.340933 -267.509434) (xy 95.360224 -267.464158) (xy 95.386527 -267.422562) (xy 95.419162 -267.385725)
			(xy 95.457283 -267.3546) (xy 95.499904 -267.329993) (xy 95.54592 -267.312541) (xy 95.594139 -267.302697)
			(xy 95.643314 -267.300716) (xy 95.692169 -267.306648) (xy 95.73944 -267.32034) (xy 95.783902 -267.341438)
			(xy 95.824405 -267.369394) (xy 95.859898 -267.403486) (xy 95.889463 -267.44283) (xy 95.912334 -267.486407)
			(xy 95.927918 -267.533088) (xy 95.935813 -267.581665) (xy 95.936308 -267.606272) (xy 95.935813 -267.630879)
			(xy 95.927918 -267.679456) (xy 95.912334 -267.726137) (xy 95.889463 -267.769714) (xy 95.859898 -267.809058)
			(xy 95.824405 -267.84315) (xy 95.783902 -267.871106) (xy 95.73944 -267.892204) (xy 95.692169 -267.905896)
			(xy 95.643314 -267.911828) (xy 95.594139 -267.909847) (xy 95.54592 -267.900003) (xy 95.499904 -267.882551)
			(xy 95.457283 -267.857944) (xy 95.419162 -267.826819) (xy 95.386527 -267.789982) (xy 95.360224 -267.748386)
			(xy 95.340933 -267.70311) (xy 95.329156 -267.655326) (xy 95.325196 -267.606272) (xy 95.006668 -267.606272)
			(xy 95.006156 -267.631718) (xy 94.997992 -267.681952) (xy 94.981876 -267.730226) (xy 94.958225 -267.775289)
			(xy 94.927652 -267.815975) (xy 94.890948 -267.85123) (xy 94.849064 -267.88014) (xy 94.803085 -267.901957)
			(xy 94.754201 -267.916117) (xy 94.70368 -267.922251) (xy 94.652828 -267.920202) (xy 94.602964 -267.910022)
			(xy 94.555378 -267.891975) (xy 94.511304 -267.866529) (xy 94.471882 -267.834342) (xy 94.438134 -267.796248)
			(xy 94.410933 -267.753234) (xy 94.390985 -267.706414) (xy 94.378806 -267.657) (xy 94.374711 -267.606272)
			(xy 94.056454 -267.606272) (xy 94.055959 -267.630879) (xy 94.048064 -267.679456) (xy 94.03248 -267.726137)
			(xy 94.009609 -267.769714) (xy 93.980044 -267.809058) (xy 93.944551 -267.84315) (xy 93.904048 -267.871106)
			(xy 93.859586 -267.892204) (xy 93.812315 -267.905896) (xy 93.76346 -267.911828) (xy 93.714285 -267.909847)
			(xy 93.666066 -267.900003) (xy 93.62005 -267.882551) (xy 93.577429 -267.857944) (xy 93.539308 -267.826819)
			(xy 93.506673 -267.789982) (xy 93.48037 -267.748386) (xy 93.461079 -267.70311) (xy 93.449302 -267.655326)
			(xy 93.445342 -267.606272) (xy 93.1164 -267.606272) (xy 93.115905 -267.630879) (xy 93.10801 -267.679456)
			(xy 93.092426 -267.726137) (xy 93.069555 -267.769714) (xy 93.03999 -267.809058) (xy 93.004497 -267.84315)
			(xy 92.963994 -267.871106) (xy 92.919532 -267.892204) (xy 92.872261 -267.905896) (xy 92.823406 -267.911828)
			(xy 92.774231 -267.909847) (xy 92.726012 -267.900003) (xy 92.679996 -267.882551) (xy 92.637375 -267.857944)
			(xy 92.599254 -267.826819) (xy 92.566619 -267.789982) (xy 92.540316 -267.748386) (xy 92.521025 -267.70311)
			(xy 92.509248 -267.655326) (xy 92.505288 -267.606272) (xy 92.176346 -267.606272) (xy 92.175851 -267.630879)
			(xy 92.167956 -267.679456) (xy 92.152372 -267.726137) (xy 92.129501 -267.769714) (xy 92.099936 -267.809058)
			(xy 92.064443 -267.84315) (xy 92.02394 -267.871106) (xy 91.979478 -267.892204) (xy 91.932207 -267.905896)
			(xy 91.883352 -267.911828) (xy 91.834177 -267.909847) (xy 91.785958 -267.900003) (xy 91.739942 -267.882551)
			(xy 91.697321 -267.857944) (xy 91.6592 -267.826819) (xy 91.626565 -267.789982) (xy 91.600262 -267.748386)
			(xy 91.580971 -267.70311) (xy 91.569194 -267.655326) (xy 91.565234 -267.606272) (xy 91.246706 -267.606272)
			(xy 91.246194 -267.631718) (xy 91.23803 -267.681952) (xy 91.221914 -267.730226) (xy 91.198263 -267.775289)
			(xy 91.16769 -267.815975) (xy 91.130986 -267.85123) (xy 91.089102 -267.88014) (xy 91.043123 -267.901957)
			(xy 90.994239 -267.916117) (xy 90.943718 -267.922251) (xy 90.892866 -267.920202) (xy 90.843002 -267.910022)
			(xy 90.795416 -267.891975) (xy 90.751342 -267.866529) (xy 90.71192 -267.834342) (xy 90.678172 -267.796248)
			(xy 90.650971 -267.753234) (xy 90.631023 -267.706414) (xy 90.618844 -267.657) (xy 90.614749 -267.606272)
			(xy 90.296238 -267.606272) (xy 90.295743 -267.630879) (xy 90.287848 -267.679456) (xy 90.272264 -267.726137)
			(xy 90.249393 -267.769714) (xy 90.219828 -267.809058) (xy 90.184335 -267.84315) (xy 90.143832 -267.871106)
			(xy 90.09937 -267.892204) (xy 90.052099 -267.905896) (xy 90.003244 -267.911828) (xy 89.954069 -267.909847)
			(xy 89.90585 -267.900003) (xy 89.859834 -267.882551) (xy 89.817213 -267.857944) (xy 89.779092 -267.826819)
			(xy 89.746457 -267.789982) (xy 89.720154 -267.748386) (xy 89.700863 -267.70311) (xy 89.689086 -267.655326)
			(xy 89.685126 -267.606272) (xy 89.356438 -267.606272) (xy 89.355943 -267.630879) (xy 89.348048 -267.679456)
			(xy 89.332464 -267.726137) (xy 89.309593 -267.769714) (xy 89.280028 -267.809058) (xy 89.244535 -267.84315)
			(xy 89.204032 -267.871106) (xy 89.15957 -267.892204) (xy 89.112299 -267.905896) (xy 89.063444 -267.911828)
			(xy 89.014269 -267.909847) (xy 88.96605 -267.900003) (xy 88.920034 -267.882551) (xy 88.877413 -267.857944)
			(xy 88.839292 -267.826819) (xy 88.806657 -267.789982) (xy 88.780354 -267.748386) (xy 88.761063 -267.70311)
			(xy 88.749286 -267.655326) (xy 88.745326 -267.606272) (xy 88.416384 -267.606272) (xy 88.415889 -267.630879)
			(xy 88.407994 -267.679456) (xy 88.39241 -267.726137) (xy 88.369539 -267.769714) (xy 88.339974 -267.809058)
			(xy 88.304481 -267.84315) (xy 88.263978 -267.871106) (xy 88.219516 -267.892204) (xy 88.172245 -267.905896)
			(xy 88.12339 -267.911828) (xy 88.074215 -267.909847) (xy 88.025996 -267.900003) (xy 87.97998 -267.882551)
			(xy 87.937359 -267.857944) (xy 87.899238 -267.826819) (xy 87.866603 -267.789982) (xy 87.8403 -267.748386)
			(xy 87.821009 -267.70311) (xy 87.809232 -267.655326) (xy 87.805272 -267.606272) (xy 87.47633 -267.606272)
			(xy 87.475835 -267.630879) (xy 87.46794 -267.679456) (xy 87.452356 -267.726137) (xy 87.429485 -267.769714)
			(xy 87.39992 -267.809058) (xy 87.364427 -267.84315) (xy 87.323924 -267.871106) (xy 87.279462 -267.892204)
			(xy 87.232191 -267.905896) (xy 87.183336 -267.911828) (xy 87.134161 -267.909847) (xy 87.085942 -267.900003)
			(xy 87.039926 -267.882551) (xy 86.997305 -267.857944) (xy 86.959184 -267.826819) (xy 86.926549 -267.789982)
			(xy 86.900246 -267.748386) (xy 86.880955 -267.70311) (xy 86.869178 -267.655326) (xy 86.865218 -267.606272)
			(xy 86.536276 -267.606272) (xy 86.535781 -267.630879) (xy 86.527886 -267.679456) (xy 86.512302 -267.726137)
			(xy 86.489431 -267.769714) (xy 86.459866 -267.809058) (xy 86.424373 -267.84315) (xy 86.38387 -267.871106)
			(xy 86.339408 -267.892204) (xy 86.292137 -267.905896) (xy 86.243282 -267.911828) (xy 86.194107 -267.909847)
			(xy 86.145888 -267.900003) (xy 86.099872 -267.882551) (xy 86.057251 -267.857944) (xy 86.01913 -267.826819)
			(xy 85.986495 -267.789982) (xy 85.960192 -267.748386) (xy 85.940901 -267.70311) (xy 85.929124 -267.655326)
			(xy 85.925164 -267.606272) (xy 85.596222 -267.606272) (xy 85.595727 -267.630879) (xy 85.587832 -267.679456)
			(xy 85.572248 -267.726137) (xy 85.549377 -267.769714) (xy 85.519812 -267.809058) (xy 85.484319 -267.84315)
			(xy 85.443816 -267.871106) (xy 85.399354 -267.892204) (xy 85.352083 -267.905896) (xy 85.303228 -267.911828)
			(xy 85.254053 -267.909847) (xy 85.205834 -267.900003) (xy 85.159818 -267.882551) (xy 85.117197 -267.857944)
			(xy 85.079076 -267.826819) (xy 85.046441 -267.789982) (xy 85.020138 -267.748386) (xy 85.000847 -267.70311)
			(xy 84.98907 -267.655326) (xy 84.98511 -267.606272) (xy 84.656422 -267.606272) (xy 84.655927 -267.630879)
			(xy 84.648032 -267.679456) (xy 84.632448 -267.726137) (xy 84.609577 -267.769714) (xy 84.580012 -267.809058)
			(xy 84.544519 -267.84315) (xy 84.504016 -267.871106) (xy 84.459554 -267.892204) (xy 84.412283 -267.905896)
			(xy 84.363428 -267.911828) (xy 84.314253 -267.909847) (xy 84.266034 -267.900003) (xy 84.220018 -267.882551)
			(xy 84.177397 -267.857944) (xy 84.139276 -267.826819) (xy 84.106641 -267.789982) (xy 84.080338 -267.748386)
			(xy 84.061047 -267.70311) (xy 84.04927 -267.655326) (xy 84.04531 -267.606272) (xy 83.716368 -267.606272)
			(xy 83.716368 -267.612114) (xy 83.715348 -267.637804) (xy 83.705772 -267.688313) (xy 83.687869 -267.736504)
			(xy 83.662145 -267.781014) (xy 83.629328 -267.820586) (xy 83.590346 -267.854101) (xy 83.546299 -267.880611)
			(xy 83.522566 -267.890498) (xy 83.512152 -267.894816) (xy 83.503516 -267.907516) (xy 83.499477 -267.91392)
			(xy 83.495066 -267.928396) (xy 83.49488 -267.935964) (xy 83.49488 -268.058392) (xy 83.495136 -268.064002)
			(xy 83.497821 -268.074902) (xy 83.500214 -268.079982) (xy 83.504786 -268.087856) (xy 83.508737 -268.092711)
			(xy 83.518496 -268.100542) (xy 83.52409 -268.10335) (xy 83.524344 -268.103604) (xy 83.605116 -268.140942)
			(xy 83.618832 -268.144244) (xy 83.631278 -268.144752) (xy 83.648042 -268.138402) (xy 83.6549 -268.1351)
			(xy 83.665314 -268.129258) (xy 83.6676 -268.12748) (xy 83.668616 -268.126718) (xy 83.66887 -268.126464)
			(xy 83.689157 -268.111389) (xy 83.733638 -268.087398) (xy 83.781454 -268.071031) (xy 83.831307 -268.062733)
			(xy 83.856576 -268.062202) (xy 83.882414 -268.06275) (xy 83.933351 -268.071463) (xy 83.982094 -268.088627)
			(xy 84.027252 -268.113752) (xy 84.067535 -268.146121) (xy 84.101793 -268.18481) (xy 84.129049 -268.228715)
			(xy 84.139278 -268.252448) (xy 84.142834 -268.259052) (xy 84.143088 -268.25956) (xy 84.156619 -268.283441)
			(xy 84.175875 -268.334833) (xy 84.185653 -268.388837) (xy 84.186268 -268.416278) (xy 84.51521 -268.416278)
			(xy 84.51917 -268.367224) (xy 84.530947 -268.31944) (xy 84.550238 -268.274164) (xy 84.576541 -268.232568)
			(xy 84.609176 -268.195731) (xy 84.647297 -268.164606) (xy 84.689918 -268.139999) (xy 84.735934 -268.122547)
			(xy 84.784153 -268.112703) (xy 84.833328 -268.110722) (xy 84.882183 -268.116654) (xy 84.929454 -268.130346)
			(xy 84.973916 -268.151444) (xy 85.014419 -268.1794) (xy 85.049912 -268.213492) (xy 85.079477 -268.252836)
			(xy 85.102348 -268.296413) (xy 85.117932 -268.343094) (xy 85.125827 -268.391671) (xy 85.126322 -268.416278)
			(xy 85.455264 -268.416278) (xy 85.459224 -268.367224) (xy 85.471001 -268.31944) (xy 85.490292 -268.274164)
			(xy 85.516595 -268.232568) (xy 85.54923 -268.195731) (xy 85.587351 -268.164606) (xy 85.629972 -268.139999)
			(xy 85.675988 -268.122547) (xy 85.724207 -268.112703) (xy 85.773382 -268.110722) (xy 85.822237 -268.116654)
			(xy 85.869508 -268.130346) (xy 85.91397 -268.151444) (xy 85.954473 -268.1794) (xy 85.989966 -268.213492)
			(xy 86.019531 -268.252836) (xy 86.042402 -268.296413) (xy 86.057986 -268.343094) (xy 86.065881 -268.391671)
			(xy 86.066376 -268.416278) (xy 87.335118 -268.416278) (xy 87.339078 -268.367224) (xy 87.350855 -268.31944)
			(xy 87.370146 -268.274164) (xy 87.396449 -268.232568) (xy 87.429084 -268.195731) (xy 87.467205 -268.164606)
			(xy 87.509826 -268.139999) (xy 87.555842 -268.122547) (xy 87.604061 -268.112703) (xy 87.653236 -268.110722)
			(xy 87.702091 -268.116654) (xy 87.749362 -268.130346) (xy 87.793824 -268.151444) (xy 87.834327 -268.1794)
			(xy 87.86982 -268.213492) (xy 87.899385 -268.252836) (xy 87.922256 -268.296413) (xy 87.93784 -268.343094)
			(xy 87.945735 -268.391671) (xy 87.94623 -268.416278) (xy 88.275172 -268.416278) (xy 88.279132 -268.367224)
			(xy 88.290909 -268.31944) (xy 88.3102 -268.274164) (xy 88.336503 -268.232568) (xy 88.369138 -268.195731)
			(xy 88.407259 -268.164606) (xy 88.44988 -268.139999) (xy 88.495896 -268.122547) (xy 88.544115 -268.112703)
			(xy 88.59329 -268.110722) (xy 88.642145 -268.116654) (xy 88.689416 -268.130346) (xy 88.733878 -268.151444)
			(xy 88.774381 -268.1794) (xy 88.809874 -268.213492) (xy 88.839439 -268.252836) (xy 88.86231 -268.296413)
			(xy 88.877894 -268.343094) (xy 88.885789 -268.391671) (xy 88.886284 -268.416278) (xy 89.215226 -268.416278)
			(xy 89.219186 -268.367224) (xy 89.230963 -268.31944) (xy 89.250254 -268.274164) (xy 89.276557 -268.232568)
			(xy 89.309192 -268.195731) (xy 89.347313 -268.164606) (xy 89.389934 -268.139999) (xy 89.43595 -268.122547)
			(xy 89.484169 -268.112703) (xy 89.533344 -268.110722) (xy 89.582199 -268.116654) (xy 89.62947 -268.130346)
			(xy 89.673932 -268.151444) (xy 89.714435 -268.1794) (xy 89.749928 -268.213492) (xy 89.779493 -268.252836)
			(xy 89.802364 -268.296413) (xy 89.817948 -268.343094) (xy 89.825843 -268.391671) (xy 89.826338 -268.416278)
			(xy 90.15528 -268.416278) (xy 90.15924 -268.367224) (xy 90.171017 -268.31944) (xy 90.190308 -268.274164)
			(xy 90.216611 -268.232568) (xy 90.249246 -268.195731) (xy 90.287367 -268.164606) (xy 90.329988 -268.139999)
			(xy 90.376004 -268.122547) (xy 90.424223 -268.112703) (xy 90.473398 -268.110722) (xy 90.522253 -268.116654)
			(xy 90.569524 -268.130346) (xy 90.613986 -268.151444) (xy 90.654489 -268.1794) (xy 90.689982 -268.213492)
			(xy 90.719547 -268.252836) (xy 90.742418 -268.296413) (xy 90.758002 -268.343094) (xy 90.765897 -268.391671)
			(xy 90.766392 -268.416278) (xy 91.095334 -268.416278) (xy 91.099294 -268.367224) (xy 91.111071 -268.31944)
			(xy 91.130362 -268.274164) (xy 91.156665 -268.232568) (xy 91.1893 -268.195731) (xy 91.227421 -268.164606)
			(xy 91.270042 -268.139999) (xy 91.316058 -268.122547) (xy 91.364277 -268.112703) (xy 91.413452 -268.110722)
			(xy 91.462307 -268.116654) (xy 91.509578 -268.130346) (xy 91.55404 -268.151444) (xy 91.594543 -268.1794)
			(xy 91.630036 -268.213492) (xy 91.659601 -268.252836) (xy 91.682472 -268.296413) (xy 91.698056 -268.343094)
			(xy 91.705951 -268.391671) (xy 91.706446 -268.416278) (xy 92.035134 -268.416278) (xy 92.039094 -268.367224)
			(xy 92.050871 -268.31944) (xy 92.070162 -268.274164) (xy 92.096465 -268.232568) (xy 92.1291 -268.195731)
			(xy 92.167221 -268.164606) (xy 92.209842 -268.139999) (xy 92.255858 -268.122547) (xy 92.304077 -268.112703)
			(xy 92.353252 -268.110722) (xy 92.402107 -268.116654) (xy 92.449378 -268.130346) (xy 92.49384 -268.151444)
			(xy 92.534343 -268.1794) (xy 92.569836 -268.213492) (xy 92.599401 -268.252836) (xy 92.622272 -268.296413)
			(xy 92.637856 -268.343094) (xy 92.645751 -268.391671) (xy 92.646246 -268.416278) (xy 93.915242 -268.416278)
			(xy 93.919202 -268.367224) (xy 93.930979 -268.31944) (xy 93.95027 -268.274164) (xy 93.976573 -268.232568)
			(xy 94.009208 -268.195731) (xy 94.047329 -268.164606) (xy 94.08995 -268.139999) (xy 94.135966 -268.122547)
			(xy 94.184185 -268.112703) (xy 94.23336 -268.110722) (xy 94.282215 -268.116654) (xy 94.329486 -268.130346)
			(xy 94.373948 -268.151444) (xy 94.414451 -268.1794) (xy 94.449944 -268.213492) (xy 94.479509 -268.252836)
			(xy 94.50238 -268.296413) (xy 94.517964 -268.343094) (xy 94.525859 -268.391671) (xy 94.526354 -268.416278)
			(xy 94.855296 -268.416278) (xy 94.859256 -268.367224) (xy 94.871033 -268.31944) (xy 94.890324 -268.274164)
			(xy 94.916627 -268.232568) (xy 94.949262 -268.195731) (xy 94.987383 -268.164606) (xy 95.030004 -268.139999)
			(xy 95.07602 -268.122547) (xy 95.124239 -268.112703) (xy 95.173414 -268.110722) (xy 95.222269 -268.116654)
			(xy 95.26954 -268.130346) (xy 95.314002 -268.151444) (xy 95.354505 -268.1794) (xy 95.389998 -268.213492)
			(xy 95.419563 -268.252836) (xy 95.442434 -268.296413) (xy 95.458018 -268.343094) (xy 95.465913 -268.391671)
			(xy 95.466408 -268.416278) (xy 95.79535 -268.416278) (xy 95.79931 -268.367224) (xy 95.811087 -268.31944)
			(xy 95.830378 -268.274164) (xy 95.856681 -268.232568) (xy 95.889316 -268.195731) (xy 95.927437 -268.164606)
			(xy 95.970058 -268.139999) (xy 96.016074 -268.122547) (xy 96.064293 -268.112703) (xy 96.113468 -268.110722)
			(xy 96.162323 -268.116654) (xy 96.209594 -268.130346) (xy 96.254056 -268.151444) (xy 96.294559 -268.1794)
			(xy 96.330052 -268.213492) (xy 96.359617 -268.252836) (xy 96.382488 -268.296413) (xy 96.398072 -268.343094)
			(xy 96.405967 -268.391671) (xy 96.406462 -268.416278) (xy 96.405967 -268.440885) (xy 96.398072 -268.489462)
			(xy 96.382488 -268.536143) (xy 96.359617 -268.57972) (xy 96.330052 -268.619064) (xy 96.294559 -268.653156)
			(xy 96.254056 -268.681112) (xy 96.209594 -268.70221) (xy 96.162323 -268.715902) (xy 96.113468 -268.721834)
			(xy 96.064293 -268.719853) (xy 96.016074 -268.710009) (xy 95.970058 -268.692557) (xy 95.927437 -268.66795)
			(xy 95.889316 -268.636825) (xy 95.856681 -268.599988) (xy 95.830378 -268.558392) (xy 95.811087 -268.513116)
			(xy 95.79931 -268.465332) (xy 95.79535 -268.416278) (xy 95.466408 -268.416278) (xy 95.465913 -268.440885)
			(xy 95.458018 -268.489462) (xy 95.442434 -268.536143) (xy 95.419563 -268.57972) (xy 95.389998 -268.619064)
			(xy 95.354505 -268.653156) (xy 95.314002 -268.681112) (xy 95.26954 -268.70221) (xy 95.222269 -268.715902)
			(xy 95.173414 -268.721834) (xy 95.124239 -268.719853) (xy 95.07602 -268.710009) (xy 95.030004 -268.692557)
			(xy 94.987383 -268.66795) (xy 94.949262 -268.636825) (xy 94.916627 -268.599988) (xy 94.890324 -268.558392)
			(xy 94.871033 -268.513116) (xy 94.859256 -268.465332) (xy 94.855296 -268.416278) (xy 94.526354 -268.416278)
			(xy 94.525859 -268.440885) (xy 94.517964 -268.489462) (xy 94.50238 -268.536143) (xy 94.479509 -268.57972)
			(xy 94.449944 -268.619064) (xy 94.414451 -268.653156) (xy 94.373948 -268.681112) (xy 94.329486 -268.70221)
			(xy 94.282215 -268.715902) (xy 94.23336 -268.721834) (xy 94.184185 -268.719853) (xy 94.135966 -268.710009)
			(xy 94.08995 -268.692557) (xy 94.047329 -268.66795) (xy 94.009208 -268.636825) (xy 93.976573 -268.599988)
			(xy 93.95027 -268.558392) (xy 93.930979 -268.513116) (xy 93.919202 -268.465332) (xy 93.915242 -268.416278)
			(xy 92.646246 -268.416278) (xy 92.645751 -268.440885) (xy 92.637856 -268.489462) (xy 92.622272 -268.536143)
			(xy 92.599401 -268.57972) (xy 92.569836 -268.619064) (xy 92.534343 -268.653156) (xy 92.49384 -268.681112)
			(xy 92.449378 -268.70221) (xy 92.402107 -268.715902) (xy 92.353252 -268.721834) (xy 92.304077 -268.719853)
			(xy 92.255858 -268.710009) (xy 92.209842 -268.692557) (xy 92.167221 -268.66795) (xy 92.1291 -268.636825)
			(xy 92.096465 -268.599988) (xy 92.070162 -268.558392) (xy 92.050871 -268.513116) (xy 92.039094 -268.465332)
			(xy 92.035134 -268.416278) (xy 91.706446 -268.416278) (xy 91.705951 -268.440885) (xy 91.698056 -268.489462)
			(xy 91.682472 -268.536143) (xy 91.659601 -268.57972) (xy 91.630036 -268.619064) (xy 91.594543 -268.653156)
			(xy 91.55404 -268.681112) (xy 91.509578 -268.70221) (xy 91.462307 -268.715902) (xy 91.413452 -268.721834)
			(xy 91.364277 -268.719853) (xy 91.316058 -268.710009) (xy 91.270042 -268.692557) (xy 91.227421 -268.66795)
			(xy 91.1893 -268.636825) (xy 91.156665 -268.599988) (xy 91.130362 -268.558392) (xy 91.111071 -268.513116)
			(xy 91.099294 -268.465332) (xy 91.095334 -268.416278) (xy 90.766392 -268.416278) (xy 90.765897 -268.440885)
			(xy 90.758002 -268.489462) (xy 90.742418 -268.536143) (xy 90.719547 -268.57972) (xy 90.689982 -268.619064)
			(xy 90.654489 -268.653156) (xy 90.613986 -268.681112) (xy 90.569524 -268.70221) (xy 90.522253 -268.715902)
			(xy 90.473398 -268.721834) (xy 90.424223 -268.719853) (xy 90.376004 -268.710009) (xy 90.329988 -268.692557)
			(xy 90.287367 -268.66795) (xy 90.249246 -268.636825) (xy 90.216611 -268.599988) (xy 90.190308 -268.558392)
			(xy 90.171017 -268.513116) (xy 90.15924 -268.465332) (xy 90.15528 -268.416278) (xy 89.826338 -268.416278)
			(xy 89.825843 -268.440885) (xy 89.817948 -268.489462) (xy 89.802364 -268.536143) (xy 89.779493 -268.57972)
			(xy 89.749928 -268.619064) (xy 89.714435 -268.653156) (xy 89.673932 -268.681112) (xy 89.62947 -268.70221)
			(xy 89.582199 -268.715902) (xy 89.533344 -268.721834) (xy 89.484169 -268.719853) (xy 89.43595 -268.710009)
			(xy 89.389934 -268.692557) (xy 89.347313 -268.66795) (xy 89.309192 -268.636825) (xy 89.276557 -268.599988)
			(xy 89.250254 -268.558392) (xy 89.230963 -268.513116) (xy 89.219186 -268.465332) (xy 89.215226 -268.416278)
			(xy 88.886284 -268.416278) (xy 88.885789 -268.440885) (xy 88.877894 -268.489462) (xy 88.86231 -268.536143)
			(xy 88.839439 -268.57972) (xy 88.809874 -268.619064) (xy 88.774381 -268.653156) (xy 88.733878 -268.681112)
			(xy 88.689416 -268.70221) (xy 88.642145 -268.715902) (xy 88.59329 -268.721834) (xy 88.544115 -268.719853)
			(xy 88.495896 -268.710009) (xy 88.44988 -268.692557) (xy 88.407259 -268.66795) (xy 88.369138 -268.636825)
			(xy 88.336503 -268.599988) (xy 88.3102 -268.558392) (xy 88.290909 -268.513116) (xy 88.279132 -268.465332)
			(xy 88.275172 -268.416278) (xy 87.94623 -268.416278) (xy 87.945735 -268.440885) (xy 87.93784 -268.489462)
			(xy 87.922256 -268.536143) (xy 87.899385 -268.57972) (xy 87.86982 -268.619064) (xy 87.834327 -268.653156)
			(xy 87.793824 -268.681112) (xy 87.749362 -268.70221) (xy 87.702091 -268.715902) (xy 87.653236 -268.721834)
			(xy 87.604061 -268.719853) (xy 87.555842 -268.710009) (xy 87.509826 -268.692557) (xy 87.467205 -268.66795)
			(xy 87.429084 -268.636825) (xy 87.396449 -268.599988) (xy 87.370146 -268.558392) (xy 87.350855 -268.513116)
			(xy 87.339078 -268.465332) (xy 87.335118 -268.416278) (xy 86.066376 -268.416278) (xy 86.065881 -268.440885)
			(xy 86.057986 -268.489462) (xy 86.042402 -268.536143) (xy 86.019531 -268.57972) (xy 85.989966 -268.619064)
			(xy 85.954473 -268.653156) (xy 85.91397 -268.681112) (xy 85.869508 -268.70221) (xy 85.822237 -268.715902)
			(xy 85.773382 -268.721834) (xy 85.724207 -268.719853) (xy 85.675988 -268.710009) (xy 85.629972 -268.692557)
			(xy 85.587351 -268.66795) (xy 85.54923 -268.636825) (xy 85.516595 -268.599988) (xy 85.490292 -268.558392)
			(xy 85.471001 -268.513116) (xy 85.459224 -268.465332) (xy 85.455264 -268.416278) (xy 85.126322 -268.416278)
			(xy 85.125827 -268.440885) (xy 85.117932 -268.489462) (xy 85.102348 -268.536143) (xy 85.079477 -268.57972)
			(xy 85.049912 -268.619064) (xy 85.014419 -268.653156) (xy 84.973916 -268.681112) (xy 84.929454 -268.70221)
			(xy 84.882183 -268.715902) (xy 84.833328 -268.721834) (xy 84.784153 -268.719853) (xy 84.735934 -268.710009)
			(xy 84.689918 -268.692557) (xy 84.647297 -268.66795) (xy 84.609176 -268.636825) (xy 84.576541 -268.599988)
			(xy 84.550238 -268.558392) (xy 84.530947 -268.513116) (xy 84.51917 -268.465332) (xy 84.51521 -268.416278)
			(xy 84.186268 -268.416278) (xy 84.185823 -268.440271) (xy 84.178319 -268.487667) (xy 84.163492 -268.533305)
			(xy 84.141707 -268.576061) (xy 84.113501 -268.614883) (xy 84.079569 -268.648813) (xy 84.040746 -268.677017)
			(xy 83.997988 -268.698799) (xy 83.952349 -268.713623) (xy 83.904953 -268.721125) (xy 83.88096 -268.721586)
			(xy 83.85457 -268.721034) (xy 83.802573 -268.711974) (xy 83.752907 -268.694112) (xy 83.70705 -268.667981)
			(xy 83.666366 -268.634357) (xy 83.648804 -268.614652) (xy 83.627468 -268.589506) (xy 83.62569 -268.589506)
			(xy 83.621481 -268.589587) (xy 83.613182 -268.590993) (xy 83.60918 -268.5923) (xy 83.521804 -268.632686)
			(xy 83.514023 -268.637218) (xy 83.502034 -268.650639) (xy 83.495449 -268.667386) (xy 83.49488 -268.676374)
			(xy 83.49488 -268.845284) (xy 83.494912 -268.84942) (xy 83.496187 -268.857592) (xy 83.49742 -268.86154)
			(xy 83.502246 -268.8717) (xy 83.515708 -268.892782) (xy 83.519213 -268.89804) (xy 83.528343 -268.90677)
			(xy 83.533742 -268.910054) (xy 83.533996 -268.910054) (xy 83.555754 -268.922636) (xy 83.595195 -268.953784)
			(xy 83.612482 -268.97203) (xy 83.630128 -268.992227) (xy 83.658748 -269.037578) (xy 83.669378 -269.0622)
			(xy 83.672934 -269.068804) (xy 83.673188 -269.069312) (xy 83.686705 -269.093153) (xy 83.705953 -269.144461)
			(xy 83.715754 -269.198377) (xy 83.716368 -269.225776) (xy 83.716368 -269.226284) (xy 84.04531 -269.226284)
			(xy 84.04927 -269.17723) (xy 84.061047 -269.129446) (xy 84.080338 -269.08417) (xy 84.106641 -269.042574)
			(xy 84.139276 -269.005737) (xy 84.177397 -268.974612) (xy 84.220018 -268.950005) (xy 84.266034 -268.932553)
			(xy 84.314253 -268.922709) (xy 84.363428 -268.920728) (xy 84.412283 -268.92666) (xy 84.459554 -268.940352)
			(xy 84.504016 -268.96145) (xy 84.544519 -268.989406) (xy 84.580012 -269.023498) (xy 84.609577 -269.062842)
			(xy 84.632448 -269.106419) (xy 84.648032 -269.1531) (xy 84.655927 -269.201677) (xy 84.656422 -269.226284)
			(xy 84.98511 -269.226284) (xy 84.98907 -269.17723) (xy 85.000847 -269.129446) (xy 85.020138 -269.08417)
			(xy 85.046441 -269.042574) (xy 85.079076 -269.005737) (xy 85.117197 -268.974612) (xy 85.159818 -268.950005)
			(xy 85.205834 -268.932553) (xy 85.254053 -268.922709) (xy 85.303228 -268.920728) (xy 85.352083 -268.92666)
			(xy 85.399354 -268.940352) (xy 85.443816 -268.96145) (xy 85.484319 -268.989406) (xy 85.519812 -269.023498)
			(xy 85.549377 -269.062842) (xy 85.572248 -269.106419) (xy 85.587832 -269.1531) (xy 85.595727 -269.201677)
			(xy 85.596222 -269.226284) (xy 85.925164 -269.226284) (xy 85.929124 -269.17723) (xy 85.940901 -269.129446)
			(xy 85.960192 -269.08417) (xy 85.986495 -269.042574) (xy 86.01913 -269.005737) (xy 86.057251 -268.974612)
			(xy 86.099872 -268.950005) (xy 86.145888 -268.932553) (xy 86.194107 -268.922709) (xy 86.243282 -268.920728)
			(xy 86.292137 -268.92666) (xy 86.339408 -268.940352) (xy 86.38387 -268.96145) (xy 86.424373 -268.989406)
			(xy 86.459866 -269.023498) (xy 86.489431 -269.062842) (xy 86.512302 -269.106419) (xy 86.527886 -269.1531)
			(xy 86.535781 -269.201677) (xy 86.536276 -269.226284) (xy 86.865218 -269.226284) (xy 86.869178 -269.17723)
			(xy 86.880955 -269.129446) (xy 86.900246 -269.08417) (xy 86.926549 -269.042574) (xy 86.959184 -269.005737)
			(xy 86.997305 -268.974612) (xy 87.039926 -268.950005) (xy 87.085942 -268.932553) (xy 87.134161 -268.922709)
			(xy 87.183336 -268.920728) (xy 87.232191 -268.92666) (xy 87.279462 -268.940352) (xy 87.323924 -268.96145)
			(xy 87.364427 -268.989406) (xy 87.39992 -269.023498) (xy 87.429485 -269.062842) (xy 87.452356 -269.106419)
			(xy 87.46794 -269.1531) (xy 87.475835 -269.201677) (xy 87.47633 -269.226284) (xy 87.805272 -269.226284)
			(xy 87.809232 -269.17723) (xy 87.821009 -269.129446) (xy 87.8403 -269.08417) (xy 87.866603 -269.042574)
			(xy 87.899238 -269.005737) (xy 87.937359 -268.974612) (xy 87.97998 -268.950005) (xy 88.025996 -268.932553)
			(xy 88.074215 -268.922709) (xy 88.12339 -268.920728) (xy 88.172245 -268.92666) (xy 88.219516 -268.940352)
			(xy 88.263978 -268.96145) (xy 88.304481 -268.989406) (xy 88.339974 -269.023498) (xy 88.369539 -269.062842)
			(xy 88.39241 -269.106419) (xy 88.407994 -269.1531) (xy 88.415889 -269.201677) (xy 88.416384 -269.226284)
			(xy 88.745326 -269.226284) (xy 88.749286 -269.17723) (xy 88.761063 -269.129446) (xy 88.780354 -269.08417)
			(xy 88.806657 -269.042574) (xy 88.839292 -269.005737) (xy 88.877413 -268.974612) (xy 88.920034 -268.950005)
			(xy 88.96605 -268.932553) (xy 89.014269 -268.922709) (xy 89.063444 -268.920728) (xy 89.112299 -268.92666)
			(xy 89.15957 -268.940352) (xy 89.204032 -268.96145) (xy 89.244535 -268.989406) (xy 89.280028 -269.023498)
			(xy 89.309593 -269.062842) (xy 89.332464 -269.106419) (xy 89.348048 -269.1531) (xy 89.355943 -269.201677)
			(xy 89.356438 -269.226284) (xy 89.685126 -269.226284) (xy 89.689086 -269.17723) (xy 89.700863 -269.129446)
			(xy 89.720154 -269.08417) (xy 89.746457 -269.042574) (xy 89.779092 -269.005737) (xy 89.817213 -268.974612)
			(xy 89.859834 -268.950005) (xy 89.90585 -268.932553) (xy 89.954069 -268.922709) (xy 90.003244 -268.920728)
			(xy 90.052099 -268.92666) (xy 90.09937 -268.940352) (xy 90.143832 -268.96145) (xy 90.184335 -268.989406)
			(xy 90.219828 -269.023498) (xy 90.249393 -269.062842) (xy 90.272264 -269.106419) (xy 90.287848 -269.1531)
			(xy 90.295743 -269.201677) (xy 90.296238 -269.226284) (xy 90.614749 -269.226284) (xy 90.618844 -269.175556)
			(xy 90.631023 -269.126142) (xy 90.650971 -269.079322) (xy 90.678172 -269.036308) (xy 90.71192 -268.998214)
			(xy 90.751342 -268.966027) (xy 90.795416 -268.940581) (xy 90.843002 -268.922534) (xy 90.892866 -268.912354)
			(xy 90.943718 -268.910305) (xy 90.994239 -268.916439) (xy 91.043123 -268.930599) (xy 91.089102 -268.952416)
			(xy 91.130986 -268.981326) (xy 91.16769 -269.016581) (xy 91.198263 -269.057267) (xy 91.221914 -269.10233)
			(xy 91.23803 -269.150604) (xy 91.246194 -269.200838) (xy 91.246706 -269.226284) (xy 91.565234 -269.226284)
			(xy 91.569194 -269.17723) (xy 91.580971 -269.129446) (xy 91.600262 -269.08417) (xy 91.626565 -269.042574)
			(xy 91.6592 -269.005737) (xy 91.697321 -268.974612) (xy 91.739942 -268.950005) (xy 91.785958 -268.932553)
			(xy 91.834177 -268.922709) (xy 91.883352 -268.920728) (xy 91.932207 -268.92666) (xy 91.979478 -268.940352)
			(xy 92.02394 -268.96145) (xy 92.064443 -268.989406) (xy 92.099936 -269.023498) (xy 92.129501 -269.062842)
			(xy 92.152372 -269.106419) (xy 92.167956 -269.1531) (xy 92.175851 -269.201677) (xy 92.176346 -269.226284)
			(xy 92.505288 -269.226284) (xy 92.509248 -269.17723) (xy 92.521025 -269.129446) (xy 92.540316 -269.08417)
			(xy 92.566619 -269.042574) (xy 92.599254 -269.005737) (xy 92.637375 -268.974612) (xy 92.679996 -268.950005)
			(xy 92.726012 -268.932553) (xy 92.774231 -268.922709) (xy 92.823406 -268.920728) (xy 92.872261 -268.92666)
			(xy 92.919532 -268.940352) (xy 92.963994 -268.96145) (xy 93.004497 -268.989406) (xy 93.03999 -269.023498)
			(xy 93.069555 -269.062842) (xy 93.092426 -269.106419) (xy 93.10801 -269.1531) (xy 93.115905 -269.201677)
			(xy 93.1164 -269.226284) (xy 93.445342 -269.226284) (xy 93.449302 -269.17723) (xy 93.461079 -269.129446)
			(xy 93.48037 -269.08417) (xy 93.506673 -269.042574) (xy 93.539308 -269.005737) (xy 93.577429 -268.974612)
			(xy 93.62005 -268.950005) (xy 93.666066 -268.932553) (xy 93.714285 -268.922709) (xy 93.76346 -268.920728)
			(xy 93.812315 -268.92666) (xy 93.859586 -268.940352) (xy 93.904048 -268.96145) (xy 93.944551 -268.989406)
			(xy 93.980044 -269.023498) (xy 94.009609 -269.062842) (xy 94.03248 -269.106419) (xy 94.048064 -269.1531)
			(xy 94.055959 -269.201677) (xy 94.056454 -269.226284) (xy 94.374711 -269.226284) (xy 94.378806 -269.175556)
			(xy 94.390985 -269.126142) (xy 94.410933 -269.079322) (xy 94.438134 -269.036308) (xy 94.471882 -268.998214)
			(xy 94.511304 -268.966027) (xy 94.555378 -268.940581) (xy 94.602964 -268.922534) (xy 94.652828 -268.912354)
			(xy 94.70368 -268.910305) (xy 94.754201 -268.916439) (xy 94.803085 -268.930599) (xy 94.849064 -268.952416)
			(xy 94.890948 -268.981326) (xy 94.927652 -269.016581) (xy 94.958225 -269.057267) (xy 94.981876 -269.10233)
			(xy 94.997992 -269.150604) (xy 95.006156 -269.200838) (xy 95.006668 -269.226284) (xy 95.325196 -269.226284)
			(xy 95.329156 -269.17723) (xy 95.340933 -269.129446) (xy 95.360224 -269.08417) (xy 95.386527 -269.042574)
			(xy 95.419162 -269.005737) (xy 95.457283 -268.974612) (xy 95.499904 -268.950005) (xy 95.54592 -268.932553)
			(xy 95.594139 -268.922709) (xy 95.643314 -268.920728) (xy 95.692169 -268.92666) (xy 95.73944 -268.940352)
			(xy 95.783902 -268.96145) (xy 95.824405 -268.989406) (xy 95.859898 -269.023498) (xy 95.889463 -269.062842)
			(xy 95.912334 -269.106419) (xy 95.927918 -269.1531) (xy 95.935813 -269.201677) (xy 95.936308 -269.226284)
			(xy 95.935813 -269.250891) (xy 95.927918 -269.299468) (xy 95.912334 -269.346149) (xy 95.889463 -269.389726)
			(xy 95.859898 -269.42907) (xy 95.824405 -269.463162) (xy 95.783902 -269.491118) (xy 95.73944 -269.512216)
			(xy 95.692169 -269.525908) (xy 95.643314 -269.53184) (xy 95.594139 -269.529859) (xy 95.54592 -269.520015)
			(xy 95.499904 -269.502563) (xy 95.457283 -269.477956) (xy 95.419162 -269.446831) (xy 95.386527 -269.409994)
			(xy 95.360224 -269.368398) (xy 95.340933 -269.323122) (xy 95.329156 -269.275338) (xy 95.325196 -269.226284)
			(xy 95.006668 -269.226284) (xy 95.006156 -269.25173) (xy 94.997992 -269.301964) (xy 94.981876 -269.350238)
			(xy 94.958225 -269.395301) (xy 94.927652 -269.435987) (xy 94.890948 -269.471242) (xy 94.849064 -269.500152)
			(xy 94.803085 -269.521969) (xy 94.754201 -269.536129) (xy 94.70368 -269.542263) (xy 94.652828 -269.540214)
			(xy 94.602964 -269.530034) (xy 94.555378 -269.511987) (xy 94.511304 -269.486541) (xy 94.471882 -269.454354)
			(xy 94.438134 -269.41626) (xy 94.410933 -269.373246) (xy 94.390985 -269.326426) (xy 94.378806 -269.277012)
			(xy 94.374711 -269.226284) (xy 94.056454 -269.226284) (xy 94.055959 -269.250891) (xy 94.048064 -269.299468)
			(xy 94.03248 -269.346149) (xy 94.009609 -269.389726) (xy 93.980044 -269.42907) (xy 93.944551 -269.463162)
			(xy 93.904048 -269.491118) (xy 93.859586 -269.512216) (xy 93.812315 -269.525908) (xy 93.76346 -269.53184)
			(xy 93.714285 -269.529859) (xy 93.666066 -269.520015) (xy 93.62005 -269.502563) (xy 93.577429 -269.477956)
			(xy 93.539308 -269.446831) (xy 93.506673 -269.409994) (xy 93.48037 -269.368398) (xy 93.461079 -269.323122)
			(xy 93.449302 -269.275338) (xy 93.445342 -269.226284) (xy 93.1164 -269.226284) (xy 93.115905 -269.250891)
			(xy 93.10801 -269.299468) (xy 93.092426 -269.346149) (xy 93.069555 -269.389726) (xy 93.03999 -269.42907)
			(xy 93.004497 -269.463162) (xy 92.963994 -269.491118) (xy 92.919532 -269.512216) (xy 92.872261 -269.525908)
			(xy 92.823406 -269.53184) (xy 92.774231 -269.529859) (xy 92.726012 -269.520015) (xy 92.679996 -269.502563)
			(xy 92.637375 -269.477956) (xy 92.599254 -269.446831) (xy 92.566619 -269.409994) (xy 92.540316 -269.368398)
			(xy 92.521025 -269.323122) (xy 92.509248 -269.275338) (xy 92.505288 -269.226284) (xy 92.176346 -269.226284)
			(xy 92.175851 -269.250891) (xy 92.167956 -269.299468) (xy 92.152372 -269.346149) (xy 92.129501 -269.389726)
			(xy 92.099936 -269.42907) (xy 92.064443 -269.463162) (xy 92.02394 -269.491118) (xy 91.979478 -269.512216)
			(xy 91.932207 -269.525908) (xy 91.883352 -269.53184) (xy 91.834177 -269.529859) (xy 91.785958 -269.520015)
			(xy 91.739942 -269.502563) (xy 91.697321 -269.477956) (xy 91.6592 -269.446831) (xy 91.626565 -269.409994)
			(xy 91.600262 -269.368398) (xy 91.580971 -269.323122) (xy 91.569194 -269.275338) (xy 91.565234 -269.226284)
			(xy 91.246706 -269.226284) (xy 91.246194 -269.25173) (xy 91.23803 -269.301964) (xy 91.221914 -269.350238)
			(xy 91.198263 -269.395301) (xy 91.16769 -269.435987) (xy 91.130986 -269.471242) (xy 91.089102 -269.500152)
			(xy 91.043123 -269.521969) (xy 90.994239 -269.536129) (xy 90.943718 -269.542263) (xy 90.892866 -269.540214)
			(xy 90.843002 -269.530034) (xy 90.795416 -269.511987) (xy 90.751342 -269.486541) (xy 90.71192 -269.454354)
			(xy 90.678172 -269.41626) (xy 90.650971 -269.373246) (xy 90.631023 -269.326426) (xy 90.618844 -269.277012)
			(xy 90.614749 -269.226284) (xy 90.296238 -269.226284) (xy 90.295743 -269.250891) (xy 90.287848 -269.299468)
			(xy 90.272264 -269.346149) (xy 90.249393 -269.389726) (xy 90.219828 -269.42907) (xy 90.184335 -269.463162)
			(xy 90.143832 -269.491118) (xy 90.09937 -269.512216) (xy 90.052099 -269.525908) (xy 90.003244 -269.53184)
			(xy 89.954069 -269.529859) (xy 89.90585 -269.520015) (xy 89.859834 -269.502563) (xy 89.817213 -269.477956)
			(xy 89.779092 -269.446831) (xy 89.746457 -269.409994) (xy 89.720154 -269.368398) (xy 89.700863 -269.323122)
			(xy 89.689086 -269.275338) (xy 89.685126 -269.226284) (xy 89.356438 -269.226284) (xy 89.355943 -269.250891)
			(xy 89.348048 -269.299468) (xy 89.332464 -269.346149) (xy 89.309593 -269.389726) (xy 89.280028 -269.42907)
			(xy 89.244535 -269.463162) (xy 89.204032 -269.491118) (xy 89.15957 -269.512216) (xy 89.112299 -269.525908)
			(xy 89.063444 -269.53184) (xy 89.014269 -269.529859) (xy 88.96605 -269.520015) (xy 88.920034 -269.502563)
			(xy 88.877413 -269.477956) (xy 88.839292 -269.446831) (xy 88.806657 -269.409994) (xy 88.780354 -269.368398)
			(xy 88.761063 -269.323122) (xy 88.749286 -269.275338) (xy 88.745326 -269.226284) (xy 88.416384 -269.226284)
			(xy 88.415889 -269.250891) (xy 88.407994 -269.299468) (xy 88.39241 -269.346149) (xy 88.369539 -269.389726)
			(xy 88.339974 -269.42907) (xy 88.304481 -269.463162) (xy 88.263978 -269.491118) (xy 88.219516 -269.512216)
			(xy 88.172245 -269.525908) (xy 88.12339 -269.53184) (xy 88.074215 -269.529859) (xy 88.025996 -269.520015)
			(xy 87.97998 -269.502563) (xy 87.937359 -269.477956) (xy 87.899238 -269.446831) (xy 87.866603 -269.409994)
			(xy 87.8403 -269.368398) (xy 87.821009 -269.323122) (xy 87.809232 -269.275338) (xy 87.805272 -269.226284)
			(xy 87.47633 -269.226284) (xy 87.475835 -269.250891) (xy 87.46794 -269.299468) (xy 87.452356 -269.346149)
			(xy 87.429485 -269.389726) (xy 87.39992 -269.42907) (xy 87.364427 -269.463162) (xy 87.323924 -269.491118)
			(xy 87.279462 -269.512216) (xy 87.232191 -269.525908) (xy 87.183336 -269.53184) (xy 87.134161 -269.529859)
			(xy 87.085942 -269.520015) (xy 87.039926 -269.502563) (xy 86.997305 -269.477956) (xy 86.959184 -269.446831)
			(xy 86.926549 -269.409994) (xy 86.900246 -269.368398) (xy 86.880955 -269.323122) (xy 86.869178 -269.275338)
			(xy 86.865218 -269.226284) (xy 86.536276 -269.226284) (xy 86.535781 -269.250891) (xy 86.527886 -269.299468)
			(xy 86.512302 -269.346149) (xy 86.489431 -269.389726) (xy 86.459866 -269.42907) (xy 86.424373 -269.463162)
			(xy 86.38387 -269.491118) (xy 86.339408 -269.512216) (xy 86.292137 -269.525908) (xy 86.243282 -269.53184)
			(xy 86.194107 -269.529859) (xy 86.145888 -269.520015) (xy 86.099872 -269.502563) (xy 86.057251 -269.477956)
			(xy 86.01913 -269.446831) (xy 85.986495 -269.409994) (xy 85.960192 -269.368398) (xy 85.940901 -269.323122)
			(xy 85.929124 -269.275338) (xy 85.925164 -269.226284) (xy 85.596222 -269.226284) (xy 85.595727 -269.250891)
			(xy 85.587832 -269.299468) (xy 85.572248 -269.346149) (xy 85.549377 -269.389726) (xy 85.519812 -269.42907)
			(xy 85.484319 -269.463162) (xy 85.443816 -269.491118) (xy 85.399354 -269.512216) (xy 85.352083 -269.525908)
			(xy 85.303228 -269.53184) (xy 85.254053 -269.529859) (xy 85.205834 -269.520015) (xy 85.159818 -269.502563)
			(xy 85.117197 -269.477956) (xy 85.079076 -269.446831) (xy 85.046441 -269.409994) (xy 85.020138 -269.368398)
			(xy 85.000847 -269.323122) (xy 84.98907 -269.275338) (xy 84.98511 -269.226284) (xy 84.656422 -269.226284)
			(xy 84.655927 -269.250891) (xy 84.648032 -269.299468) (xy 84.632448 -269.346149) (xy 84.609577 -269.389726)
			(xy 84.580012 -269.42907) (xy 84.544519 -269.463162) (xy 84.504016 -269.491118) (xy 84.459554 -269.512216)
			(xy 84.412283 -269.525908) (xy 84.363428 -269.53184) (xy 84.314253 -269.529859) (xy 84.266034 -269.520015)
			(xy 84.220018 -269.502563) (xy 84.177397 -269.477956) (xy 84.139276 -269.446831) (xy 84.106641 -269.409994)
			(xy 84.080338 -269.368398) (xy 84.061047 -269.323122) (xy 84.04927 -269.275338) (xy 84.04531 -269.226284)
			(xy 83.716368 -269.226284) (xy 83.716368 -269.232126) (xy 83.715347 -269.257815) (xy 83.705769 -269.308323)
			(xy 83.687865 -269.356512) (xy 83.662141 -269.401021) (xy 83.629324 -269.440591) (xy 83.590341 -269.474105)
			(xy 83.546295 -269.500614) (xy 83.522566 -269.51051) (xy 83.512152 -269.514828) (xy 83.503516 -269.527528)
			(xy 83.499479 -269.533932) (xy 83.495071 -269.548409) (xy 83.49488 -269.555976) (xy 83.49488 -269.678404)
			(xy 83.495137 -269.684013) (xy 83.497824 -269.694913) (xy 83.500214 -269.699994) (xy 83.504786 -269.707868)
			(xy 83.508738 -269.712722) (xy 83.518497 -269.720552) (xy 83.52409 -269.723362) (xy 83.524344 -269.723616)
			(xy 83.605116 -269.760954) (xy 83.618832 -269.764256) (xy 83.631278 -269.764764) (xy 83.648042 -269.758414)
			(xy 83.6549 -269.755112) (xy 83.665314 -269.74927) (xy 83.6676 -269.747492) (xy 83.668616 -269.74673)
			(xy 83.66887 -269.746476) (xy 83.689157 -269.731401) (xy 83.733638 -269.707408) (xy 83.781453 -269.691041)
			(xy 83.831306 -269.682743) (xy 83.856576 -269.682214) (xy 83.882414 -269.682762) (xy 83.93335 -269.691475)
			(xy 83.982093 -269.708639) (xy 84.02725 -269.733765) (xy 84.067532 -269.766135) (xy 84.101789 -269.804824)
			(xy 84.129043 -269.848729) (xy 84.139278 -269.87246) (xy 84.142834 -269.879064) (xy 84.143088 -269.879572)
			(xy 84.156618 -269.903453) (xy 84.175872 -269.954846) (xy 84.185648 -270.008849) (xy 84.186268 -270.03629)
			(xy 84.51521 -270.03629) (xy 84.51917 -269.987236) (xy 84.530947 -269.939452) (xy 84.550238 -269.894176)
			(xy 84.576541 -269.85258) (xy 84.609176 -269.815743) (xy 84.647297 -269.784618) (xy 84.689918 -269.760011)
			(xy 84.735934 -269.742559) (xy 84.784153 -269.732715) (xy 84.833328 -269.730734) (xy 84.882183 -269.736666)
			(xy 84.929454 -269.750358) (xy 84.973916 -269.771456) (xy 85.014419 -269.799412) (xy 85.049912 -269.833504)
			(xy 85.079477 -269.872848) (xy 85.102348 -269.916425) (xy 85.117932 -269.963106) (xy 85.125827 -270.011683)
			(xy 85.126322 -270.03629) (xy 85.455264 -270.03629) (xy 85.459224 -269.987236) (xy 85.471001 -269.939452)
			(xy 85.490292 -269.894176) (xy 85.516595 -269.85258) (xy 85.54923 -269.815743) (xy 85.587351 -269.784618)
			(xy 85.629972 -269.760011) (xy 85.675988 -269.742559) (xy 85.724207 -269.732715) (xy 85.773382 -269.730734)
			(xy 85.822237 -269.736666) (xy 85.869508 -269.750358) (xy 85.91397 -269.771456) (xy 85.954473 -269.799412)
			(xy 85.989966 -269.833504) (xy 86.019531 -269.872848) (xy 86.042402 -269.916425) (xy 86.057986 -269.963106)
			(xy 86.065881 -270.011683) (xy 86.066376 -270.03629) (xy 86.395318 -270.03629) (xy 86.399278 -269.987236)
			(xy 86.411055 -269.939452) (xy 86.430346 -269.894176) (xy 86.456649 -269.85258) (xy 86.489284 -269.815743)
			(xy 86.527405 -269.784618) (xy 86.570026 -269.760011) (xy 86.616042 -269.742559) (xy 86.664261 -269.732715)
			(xy 86.713436 -269.730734) (xy 86.762291 -269.736666) (xy 86.809562 -269.750358) (xy 86.854024 -269.771456)
			(xy 86.894527 -269.799412) (xy 86.93002 -269.833504) (xy 86.959585 -269.872848) (xy 86.982456 -269.916425)
			(xy 86.99804 -269.963106) (xy 87.005935 -270.011683) (xy 87.00643 -270.03629) (xy 87.335118 -270.03629)
			(xy 87.339078 -269.987236) (xy 87.350855 -269.939452) (xy 87.370146 -269.894176) (xy 87.396449 -269.85258)
			(xy 87.429084 -269.815743) (xy 87.467205 -269.784618) (xy 87.509826 -269.760011) (xy 87.555842 -269.742559)
			(xy 87.604061 -269.732715) (xy 87.653236 -269.730734) (xy 87.702091 -269.736666) (xy 87.749362 -269.750358)
			(xy 87.793824 -269.771456) (xy 87.834327 -269.799412) (xy 87.86982 -269.833504) (xy 87.899385 -269.872848)
			(xy 87.922256 -269.916425) (xy 87.93784 -269.963106) (xy 87.945735 -270.011683) (xy 87.94623 -270.03629)
			(xy 88.275172 -270.03629) (xy 88.279132 -269.987236) (xy 88.290909 -269.939452) (xy 88.3102 -269.894176)
			(xy 88.336503 -269.85258) (xy 88.369138 -269.815743) (xy 88.407259 -269.784618) (xy 88.44988 -269.760011)
			(xy 88.495896 -269.742559) (xy 88.544115 -269.732715) (xy 88.59329 -269.730734) (xy 88.642145 -269.736666)
			(xy 88.689416 -269.750358) (xy 88.733878 -269.771456) (xy 88.774381 -269.799412) (xy 88.809874 -269.833504)
			(xy 88.839439 -269.872848) (xy 88.86231 -269.916425) (xy 88.877894 -269.963106) (xy 88.885789 -270.011683)
			(xy 88.886284 -270.03629) (xy 89.215226 -270.03629) (xy 89.219186 -269.987236) (xy 89.230963 -269.939452)
			(xy 89.250254 -269.894176) (xy 89.276557 -269.85258) (xy 89.309192 -269.815743) (xy 89.347313 -269.784618)
			(xy 89.389934 -269.760011) (xy 89.43595 -269.742559) (xy 89.484169 -269.732715) (xy 89.533344 -269.730734)
			(xy 89.582199 -269.736666) (xy 89.62947 -269.750358) (xy 89.673932 -269.771456) (xy 89.714435 -269.799412)
			(xy 89.749928 -269.833504) (xy 89.779493 -269.872848) (xy 89.802364 -269.916425) (xy 89.817948 -269.963106)
			(xy 89.825843 -270.011683) (xy 89.826338 -270.03629) (xy 90.15528 -270.03629) (xy 90.15924 -269.987236)
			(xy 90.171017 -269.939452) (xy 90.190308 -269.894176) (xy 90.216611 -269.85258) (xy 90.249246 -269.815743)
			(xy 90.287367 -269.784618) (xy 90.329988 -269.760011) (xy 90.376004 -269.742559) (xy 90.424223 -269.732715)
			(xy 90.473398 -269.730734) (xy 90.522253 -269.736666) (xy 90.569524 -269.750358) (xy 90.613986 -269.771456)
			(xy 90.654489 -269.799412) (xy 90.689982 -269.833504) (xy 90.719547 -269.872848) (xy 90.742418 -269.916425)
			(xy 90.758002 -269.963106) (xy 90.765897 -270.011683) (xy 90.766392 -270.03629) (xy 91.084903 -270.03629)
			(xy 91.088998 -269.985562) (xy 91.101177 -269.936148) (xy 91.121125 -269.889328) (xy 91.148326 -269.846314)
			(xy 91.182074 -269.80822) (xy 91.221496 -269.776033) (xy 91.26557 -269.750587) (xy 91.313156 -269.73254)
			(xy 91.36302 -269.72236) (xy 91.413872 -269.720311) (xy 91.464393 -269.726445) (xy 91.513277 -269.740605)
			(xy 91.559256 -269.762422) (xy 91.60114 -269.791332) (xy 91.637844 -269.826587) (xy 91.668417 -269.867273)
			(xy 91.692068 -269.912336) (xy 91.708184 -269.96061) (xy 91.716348 -270.010844) (xy 91.71686 -270.03629)
			(xy 92.024703 -270.03629) (xy 92.028798 -269.985562) (xy 92.040977 -269.936148) (xy 92.060925 -269.889328)
			(xy 92.088126 -269.846314) (xy 92.121874 -269.80822) (xy 92.161296 -269.776033) (xy 92.20537 -269.750587)
			(xy 92.252956 -269.73254) (xy 92.30282 -269.72236) (xy 92.353672 -269.720311) (xy 92.404193 -269.726445)
			(xy 92.453077 -269.740605) (xy 92.499056 -269.762422) (xy 92.54094 -269.791332) (xy 92.577644 -269.826587)
			(xy 92.608217 -269.867273) (xy 92.631868 -269.912336) (xy 92.647984 -269.96061) (xy 92.656148 -270.010844)
			(xy 92.65666 -270.03629) (xy 92.975188 -270.03629) (xy 92.979148 -269.987236) (xy 92.990925 -269.939452)
			(xy 93.010216 -269.894176) (xy 93.036519 -269.85258) (xy 93.069154 -269.815743) (xy 93.107275 -269.784618)
			(xy 93.149896 -269.760011) (xy 93.195912 -269.742559) (xy 93.244131 -269.732715) (xy 93.293306 -269.730734)
			(xy 93.342161 -269.736666) (xy 93.389432 -269.750358) (xy 93.433894 -269.771456) (xy 93.474397 -269.799412)
			(xy 93.50989 -269.833504) (xy 93.539455 -269.872848) (xy 93.562326 -269.916425) (xy 93.57791 -269.963106)
			(xy 93.585805 -270.011683) (xy 93.5863 -270.03629) (xy 93.904811 -270.03629) (xy 93.908906 -269.985562)
			(xy 93.921085 -269.936148) (xy 93.941033 -269.889328) (xy 93.968234 -269.846314) (xy 94.001982 -269.80822)
			(xy 94.041404 -269.776033) (xy 94.085478 -269.750587) (xy 94.133064 -269.73254) (xy 94.182928 -269.72236)
			(xy 94.23378 -269.720311) (xy 94.284301 -269.726445) (xy 94.333185 -269.740605) (xy 94.379164 -269.762422)
			(xy 94.421048 -269.791332) (xy 94.457752 -269.826587) (xy 94.488325 -269.867273) (xy 94.511976 -269.912336)
			(xy 94.528092 -269.96061) (xy 94.536256 -270.010844) (xy 94.536768 -270.03629) (xy 94.855296 -270.03629)
			(xy 94.859256 -269.987236) (xy 94.871033 -269.939452) (xy 94.890324 -269.894176) (xy 94.916627 -269.85258)
			(xy 94.949262 -269.815743) (xy 94.987383 -269.784618) (xy 95.030004 -269.760011) (xy 95.07602 -269.742559)
			(xy 95.124239 -269.732715) (xy 95.173414 -269.730734) (xy 95.222269 -269.736666) (xy 95.26954 -269.750358)
			(xy 95.314002 -269.771456) (xy 95.354505 -269.799412) (xy 95.389998 -269.833504) (xy 95.419563 -269.872848)
			(xy 95.442434 -269.916425) (xy 95.458018 -269.963106) (xy 95.465913 -270.011683) (xy 95.466408 -270.03629)
			(xy 95.784919 -270.03629) (xy 95.789014 -269.985562) (xy 95.801193 -269.936148) (xy 95.821141 -269.889328)
			(xy 95.848342 -269.846314) (xy 95.88209 -269.80822) (xy 95.921512 -269.776033) (xy 95.965586 -269.750587)
			(xy 96.013172 -269.73254) (xy 96.063036 -269.72236) (xy 96.113888 -269.720311) (xy 96.164409 -269.726445)
			(xy 96.213293 -269.740605) (xy 96.259272 -269.762422) (xy 96.301156 -269.791332) (xy 96.33786 -269.826587)
			(xy 96.368433 -269.867273) (xy 96.392084 -269.912336) (xy 96.4082 -269.96061) (xy 96.416364 -270.010844)
			(xy 96.416876 -270.03629) (xy 96.416364 -270.061736) (xy 96.4082 -270.11197) (xy 96.392084 -270.160244)
			(xy 96.368433 -270.205307) (xy 96.33786 -270.245993) (xy 96.301156 -270.281248) (xy 96.259272 -270.310158)
			(xy 96.213293 -270.331975) (xy 96.164409 -270.346135) (xy 96.113888 -270.352269) (xy 96.063036 -270.35022)
			(xy 96.013172 -270.34004) (xy 95.965586 -270.321993) (xy 95.921512 -270.296547) (xy 95.88209 -270.26436)
			(xy 95.848342 -270.226266) (xy 95.821141 -270.183252) (xy 95.801193 -270.136432) (xy 95.789014 -270.087018)
			(xy 95.784919 -270.03629) (xy 95.466408 -270.03629) (xy 95.465913 -270.060897) (xy 95.458018 -270.109474)
			(xy 95.442434 -270.156155) (xy 95.419563 -270.199732) (xy 95.389998 -270.239076) (xy 95.354505 -270.273168)
			(xy 95.314002 -270.301124) (xy 95.26954 -270.322222) (xy 95.222269 -270.335914) (xy 95.173414 -270.341846)
			(xy 95.124239 -270.339865) (xy 95.07602 -270.330021) (xy 95.030004 -270.312569) (xy 94.987383 -270.287962)
			(xy 94.949262 -270.256837) (xy 94.916627 -270.22) (xy 94.890324 -270.178404) (xy 94.871033 -270.133128)
			(xy 94.859256 -270.085344) (xy 94.855296 -270.03629) (xy 94.536768 -270.03629) (xy 94.536256 -270.061736)
			(xy 94.528092 -270.11197) (xy 94.511976 -270.160244) (xy 94.488325 -270.205307) (xy 94.457752 -270.245993)
			(xy 94.421048 -270.281248) (xy 94.379164 -270.310158) (xy 94.333185 -270.331975) (xy 94.284301 -270.346135)
			(xy 94.23378 -270.352269) (xy 94.182928 -270.35022) (xy 94.133064 -270.34004) (xy 94.085478 -270.321993)
			(xy 94.041404 -270.296547) (xy 94.001982 -270.26436) (xy 93.968234 -270.226266) (xy 93.941033 -270.183252)
			(xy 93.921085 -270.136432) (xy 93.908906 -270.087018) (xy 93.904811 -270.03629) (xy 93.5863 -270.03629)
			(xy 93.585805 -270.060897) (xy 93.57791 -270.109474) (xy 93.562326 -270.156155) (xy 93.539455 -270.199732)
			(xy 93.50989 -270.239076) (xy 93.474397 -270.273168) (xy 93.433894 -270.301124) (xy 93.389432 -270.322222)
			(xy 93.342161 -270.335914) (xy 93.293306 -270.341846) (xy 93.244131 -270.339865) (xy 93.195912 -270.330021)
			(xy 93.149896 -270.312569) (xy 93.107275 -270.287962) (xy 93.069154 -270.256837) (xy 93.036519 -270.22)
			(xy 93.010216 -270.178404) (xy 92.990925 -270.133128) (xy 92.979148 -270.085344) (xy 92.975188 -270.03629)
			(xy 92.65666 -270.03629) (xy 92.656148 -270.061736) (xy 92.647984 -270.11197) (xy 92.631868 -270.160244)
			(xy 92.608217 -270.205307) (xy 92.577644 -270.245993) (xy 92.54094 -270.281248) (xy 92.499056 -270.310158)
			(xy 92.453077 -270.331975) (xy 92.404193 -270.346135) (xy 92.353672 -270.352269) (xy 92.30282 -270.35022)
			(xy 92.252956 -270.34004) (xy 92.20537 -270.321993) (xy 92.161296 -270.296547) (xy 92.121874 -270.26436)
			(xy 92.088126 -270.226266) (xy 92.060925 -270.183252) (xy 92.040977 -270.136432) (xy 92.028798 -270.087018)
			(xy 92.024703 -270.03629) (xy 91.71686 -270.03629) (xy 91.716348 -270.061736) (xy 91.708184 -270.11197)
			(xy 91.692068 -270.160244) (xy 91.668417 -270.205307) (xy 91.637844 -270.245993) (xy 91.60114 -270.281248)
			(xy 91.559256 -270.310158) (xy 91.513277 -270.331975) (xy 91.464393 -270.346135) (xy 91.413872 -270.352269)
			(xy 91.36302 -270.35022) (xy 91.313156 -270.34004) (xy 91.26557 -270.321993) (xy 91.221496 -270.296547)
			(xy 91.182074 -270.26436) (xy 91.148326 -270.226266) (xy 91.121125 -270.183252) (xy 91.101177 -270.136432)
			(xy 91.088998 -270.087018) (xy 91.084903 -270.03629) (xy 90.766392 -270.03629) (xy 90.765897 -270.060897)
			(xy 90.758002 -270.109474) (xy 90.742418 -270.156155) (xy 90.719547 -270.199732) (xy 90.689982 -270.239076)
			(xy 90.654489 -270.273168) (xy 90.613986 -270.301124) (xy 90.569524 -270.322222) (xy 90.522253 -270.335914)
			(xy 90.473398 -270.341846) (xy 90.424223 -270.339865) (xy 90.376004 -270.330021) (xy 90.329988 -270.312569)
			(xy 90.287367 -270.287962) (xy 90.249246 -270.256837) (xy 90.216611 -270.22) (xy 90.190308 -270.178404)
			(xy 90.171017 -270.133128) (xy 90.15924 -270.085344) (xy 90.15528 -270.03629) (xy 89.826338 -270.03629)
			(xy 89.825843 -270.060897) (xy 89.817948 -270.109474) (xy 89.802364 -270.156155) (xy 89.779493 -270.199732)
			(xy 89.749928 -270.239076) (xy 89.714435 -270.273168) (xy 89.673932 -270.301124) (xy 89.62947 -270.322222)
			(xy 89.582199 -270.335914) (xy 89.533344 -270.341846) (xy 89.484169 -270.339865) (xy 89.43595 -270.330021)
			(xy 89.389934 -270.312569) (xy 89.347313 -270.287962) (xy 89.309192 -270.256837) (xy 89.276557 -270.22)
			(xy 89.250254 -270.178404) (xy 89.230963 -270.133128) (xy 89.219186 -270.085344) (xy 89.215226 -270.03629)
			(xy 88.886284 -270.03629) (xy 88.885789 -270.060897) (xy 88.877894 -270.109474) (xy 88.86231 -270.156155)
			(xy 88.839439 -270.199732) (xy 88.809874 -270.239076) (xy 88.774381 -270.273168) (xy 88.733878 -270.301124)
			(xy 88.689416 -270.322222) (xy 88.642145 -270.335914) (xy 88.59329 -270.341846) (xy 88.544115 -270.339865)
			(xy 88.495896 -270.330021) (xy 88.44988 -270.312569) (xy 88.407259 -270.287962) (xy 88.369138 -270.256837)
			(xy 88.336503 -270.22) (xy 88.3102 -270.178404) (xy 88.290909 -270.133128) (xy 88.279132 -270.085344)
			(xy 88.275172 -270.03629) (xy 87.94623 -270.03629) (xy 87.945735 -270.060897) (xy 87.93784 -270.109474)
			(xy 87.922256 -270.156155) (xy 87.899385 -270.199732) (xy 87.86982 -270.239076) (xy 87.834327 -270.273168)
			(xy 87.793824 -270.301124) (xy 87.749362 -270.322222) (xy 87.702091 -270.335914) (xy 87.653236 -270.341846)
			(xy 87.604061 -270.339865) (xy 87.555842 -270.330021) (xy 87.509826 -270.312569) (xy 87.467205 -270.287962)
			(xy 87.429084 -270.256837) (xy 87.396449 -270.22) (xy 87.370146 -270.178404) (xy 87.350855 -270.133128)
			(xy 87.339078 -270.085344) (xy 87.335118 -270.03629) (xy 87.00643 -270.03629) (xy 87.005935 -270.060897)
			(xy 86.99804 -270.109474) (xy 86.982456 -270.156155) (xy 86.959585 -270.199732) (xy 86.93002 -270.239076)
			(xy 86.894527 -270.273168) (xy 86.854024 -270.301124) (xy 86.809562 -270.322222) (xy 86.762291 -270.335914)
			(xy 86.713436 -270.341846) (xy 86.664261 -270.339865) (xy 86.616042 -270.330021) (xy 86.570026 -270.312569)
			(xy 86.527405 -270.287962) (xy 86.489284 -270.256837) (xy 86.456649 -270.22) (xy 86.430346 -270.178404)
			(xy 86.411055 -270.133128) (xy 86.399278 -270.085344) (xy 86.395318 -270.03629) (xy 86.066376 -270.03629)
			(xy 86.065881 -270.060897) (xy 86.057986 -270.109474) (xy 86.042402 -270.156155) (xy 86.019531 -270.199732)
			(xy 85.989966 -270.239076) (xy 85.954473 -270.273168) (xy 85.91397 -270.301124) (xy 85.869508 -270.322222)
			(xy 85.822237 -270.335914) (xy 85.773382 -270.341846) (xy 85.724207 -270.339865) (xy 85.675988 -270.330021)
			(xy 85.629972 -270.312569) (xy 85.587351 -270.287962) (xy 85.54923 -270.256837) (xy 85.516595 -270.22)
			(xy 85.490292 -270.178404) (xy 85.471001 -270.133128) (xy 85.459224 -270.085344) (xy 85.455264 -270.03629)
			(xy 85.126322 -270.03629) (xy 85.125827 -270.060897) (xy 85.117932 -270.109474) (xy 85.102348 -270.156155)
			(xy 85.079477 -270.199732) (xy 85.049912 -270.239076) (xy 85.014419 -270.273168) (xy 84.973916 -270.301124)
			(xy 84.929454 -270.322222) (xy 84.882183 -270.335914) (xy 84.833328 -270.341846) (xy 84.784153 -270.339865)
			(xy 84.735934 -270.330021) (xy 84.689918 -270.312569) (xy 84.647297 -270.287962) (xy 84.609176 -270.256837)
			(xy 84.576541 -270.22) (xy 84.550238 -270.178404) (xy 84.530947 -270.133128) (xy 84.51917 -270.085344)
			(xy 84.51521 -270.03629) (xy 84.186268 -270.03629) (xy 84.185823 -270.060283) (xy 84.178317 -270.107677)
			(xy 84.163489 -270.153313) (xy 84.141703 -270.196068) (xy 84.113497 -270.234888) (xy 84.079565 -270.268817)
			(xy 84.040742 -270.297019) (xy 83.997986 -270.3188) (xy 83.952348 -270.333624) (xy 83.904953 -270.341125)
			(xy 83.88096 -270.341598) (xy 83.85457 -270.341047) (xy 83.802573 -270.331986) (xy 83.752907 -270.314125)
			(xy 83.707049 -270.287994) (xy 83.666364 -270.254372) (xy 83.648804 -270.234664) (xy 83.627468 -270.209518)
			(xy 83.62569 -270.209518) (xy 83.621481 -270.209599) (xy 83.613182 -270.211006) (xy 83.60918 -270.212312)
			(xy 83.521804 -270.252698) (xy 83.514024 -270.257231) (xy 83.502039 -270.270652) (xy 83.495457 -270.287399)
			(xy 83.49488 -270.296386) (xy 83.49488 -270.465296) (xy 83.494913 -270.469432) (xy 83.49619 -270.477603)
			(xy 83.49742 -270.481552) (xy 83.502246 -270.491712) (xy 83.515708 -270.512794) (xy 83.519207 -270.518058)
			(xy 83.528329 -270.526802) (xy 83.533742 -270.530066) (xy 83.533996 -270.530066) (xy 83.555756 -270.542645)
			(xy 83.595204 -270.573787) (xy 83.612482 -270.592042) (xy 83.630127 -270.612239) (xy 83.658745 -270.657591)
			(xy 83.669378 -270.682212) (xy 83.672934 -270.688816) (xy 83.673188 -270.689324) (xy 83.686704 -270.713166)
			(xy 83.70595 -270.764473) (xy 83.715749 -270.818389) (xy 83.716368 -270.845788) (xy 83.716368 -270.846296)
			(xy 84.04531 -270.846296) (xy 84.04927 -270.797242) (xy 84.061047 -270.749458) (xy 84.080338 -270.704182)
			(xy 84.106641 -270.662586) (xy 84.139276 -270.625749) (xy 84.177397 -270.594624) (xy 84.220018 -270.570017)
			(xy 84.266034 -270.552565) (xy 84.314253 -270.542721) (xy 84.363428 -270.54074) (xy 84.412283 -270.546672)
			(xy 84.459554 -270.560364) (xy 84.504016 -270.581462) (xy 84.544519 -270.609418) (xy 84.580012 -270.64351)
			(xy 84.609577 -270.682854) (xy 84.632448 -270.726431) (xy 84.648032 -270.773112) (xy 84.655927 -270.821689)
			(xy 84.656422 -270.846296) (xy 84.98511 -270.846296) (xy 84.98907 -270.797242) (xy 85.000847 -270.749458)
			(xy 85.020138 -270.704182) (xy 85.046441 -270.662586) (xy 85.079076 -270.625749) (xy 85.117197 -270.594624)
			(xy 85.159818 -270.570017) (xy 85.205834 -270.552565) (xy 85.254053 -270.542721) (xy 85.303228 -270.54074)
			(xy 85.352083 -270.546672) (xy 85.399354 -270.560364) (xy 85.443816 -270.581462) (xy 85.484319 -270.609418)
			(xy 85.519812 -270.64351) (xy 85.549377 -270.682854) (xy 85.572248 -270.726431) (xy 85.587832 -270.773112)
			(xy 85.595727 -270.821689) (xy 85.596222 -270.846296) (xy 85.925164 -270.846296) (xy 85.929124 -270.797242)
			(xy 85.940901 -270.749458) (xy 85.960192 -270.704182) (xy 85.986495 -270.662586) (xy 86.01913 -270.625749)
			(xy 86.057251 -270.594624) (xy 86.099872 -270.570017) (xy 86.145888 -270.552565) (xy 86.194107 -270.542721)
			(xy 86.243282 -270.54074) (xy 86.292137 -270.546672) (xy 86.339408 -270.560364) (xy 86.38387 -270.581462)
			(xy 86.424373 -270.609418) (xy 86.459866 -270.64351) (xy 86.489431 -270.682854) (xy 86.512302 -270.726431)
			(xy 86.527886 -270.773112) (xy 86.535781 -270.821689) (xy 86.536276 -270.846296) (xy 87.805272 -270.846296)
			(xy 87.809232 -270.797242) (xy 87.821009 -270.749458) (xy 87.8403 -270.704182) (xy 87.866603 -270.662586)
			(xy 87.899238 -270.625749) (xy 87.937359 -270.594624) (xy 87.97998 -270.570017) (xy 88.025996 -270.552565)
			(xy 88.074215 -270.542721) (xy 88.12339 -270.54074) (xy 88.172245 -270.546672) (xy 88.219516 -270.560364)
			(xy 88.263978 -270.581462) (xy 88.304481 -270.609418) (xy 88.339974 -270.64351) (xy 88.369539 -270.682854)
			(xy 88.39241 -270.726431) (xy 88.407994 -270.773112) (xy 88.415889 -270.821689) (xy 88.416384 -270.846296)
			(xy 88.745326 -270.846296) (xy 88.749286 -270.797242) (xy 88.761063 -270.749458) (xy 88.780354 -270.704182)
			(xy 88.806657 -270.662586) (xy 88.839292 -270.625749) (xy 88.877413 -270.594624) (xy 88.920034 -270.570017)
			(xy 88.96605 -270.552565) (xy 89.014269 -270.542721) (xy 89.063444 -270.54074) (xy 89.112299 -270.546672)
			(xy 89.15957 -270.560364) (xy 89.204032 -270.581462) (xy 89.244535 -270.609418) (xy 89.280028 -270.64351)
			(xy 89.309593 -270.682854) (xy 89.332464 -270.726431) (xy 89.348048 -270.773112) (xy 89.355943 -270.821689)
			(xy 89.356438 -270.846296) (xy 89.685126 -270.846296) (xy 89.689086 -270.797242) (xy 89.700863 -270.749458)
			(xy 89.720154 -270.704182) (xy 89.746457 -270.662586) (xy 89.779092 -270.625749) (xy 89.817213 -270.594624)
			(xy 89.859834 -270.570017) (xy 89.90585 -270.552565) (xy 89.954069 -270.542721) (xy 90.003244 -270.54074)
			(xy 90.052099 -270.546672) (xy 90.09937 -270.560364) (xy 90.143832 -270.581462) (xy 90.184335 -270.609418)
			(xy 90.219828 -270.64351) (xy 90.249393 -270.682854) (xy 90.272264 -270.726431) (xy 90.287848 -270.773112)
			(xy 90.295743 -270.821689) (xy 90.296238 -270.846296) (xy 90.614749 -270.846296) (xy 90.618844 -270.795568)
			(xy 90.631023 -270.746154) (xy 90.650971 -270.699334) (xy 90.678172 -270.65632) (xy 90.71192 -270.618226)
			(xy 90.751342 -270.586039) (xy 90.795416 -270.560593) (xy 90.843002 -270.542546) (xy 90.892866 -270.532366)
			(xy 90.943718 -270.530317) (xy 90.994239 -270.536451) (xy 91.043123 -270.550611) (xy 91.089102 -270.572428)
			(xy 91.130986 -270.601338) (xy 91.16769 -270.636593) (xy 91.198263 -270.677279) (xy 91.221914 -270.722342)
			(xy 91.23803 -270.770616) (xy 91.246194 -270.82085) (xy 91.246706 -270.846296) (xy 91.565234 -270.846296)
			(xy 91.569194 -270.797242) (xy 91.580971 -270.749458) (xy 91.600262 -270.704182) (xy 91.626565 -270.662586)
			(xy 91.6592 -270.625749) (xy 91.697321 -270.594624) (xy 91.739942 -270.570017) (xy 91.785958 -270.552565)
			(xy 91.834177 -270.542721) (xy 91.883352 -270.54074) (xy 91.932207 -270.546672) (xy 91.979478 -270.560364)
			(xy 92.02394 -270.581462) (xy 92.064443 -270.609418) (xy 92.099936 -270.64351) (xy 92.129501 -270.682854)
			(xy 92.152372 -270.726431) (xy 92.167956 -270.773112) (xy 92.175851 -270.821689) (xy 92.176346 -270.846296)
			(xy 92.494857 -270.846296) (xy 92.498952 -270.795568) (xy 92.511131 -270.746154) (xy 92.531079 -270.699334)
			(xy 92.55828 -270.65632) (xy 92.592028 -270.618226) (xy 92.63145 -270.586039) (xy 92.675524 -270.560593)
			(xy 92.72311 -270.542546) (xy 92.772974 -270.532366) (xy 92.823826 -270.530317) (xy 92.874347 -270.536451)
			(xy 92.923231 -270.550611) (xy 92.96921 -270.572428) (xy 93.011094 -270.601338) (xy 93.047798 -270.636593)
			(xy 93.078371 -270.677279) (xy 93.102022 -270.722342) (xy 93.118138 -270.770616) (xy 93.126302 -270.82085)
			(xy 93.126814 -270.846296) (xy 94.374711 -270.846296) (xy 94.378806 -270.795568) (xy 94.390985 -270.746154)
			(xy 94.410933 -270.699334) (xy 94.438134 -270.65632) (xy 94.471882 -270.618226) (xy 94.511304 -270.586039)
			(xy 94.555378 -270.560593) (xy 94.602964 -270.542546) (xy 94.652828 -270.532366) (xy 94.70368 -270.530317)
			(xy 94.754201 -270.536451) (xy 94.803085 -270.550611) (xy 94.849064 -270.572428) (xy 94.890948 -270.601338)
			(xy 94.927652 -270.636593) (xy 94.958225 -270.677279) (xy 94.981876 -270.722342) (xy 94.997992 -270.770616)
			(xy 95.006156 -270.82085) (xy 95.006668 -270.846296) (xy 95.314765 -270.846296) (xy 95.31886 -270.795568)
			(xy 95.331039 -270.746154) (xy 95.350987 -270.699334) (xy 95.378188 -270.65632) (xy 95.411936 -270.618226)
			(xy 95.451358 -270.586039) (xy 95.495432 -270.560593) (xy 95.543018 -270.542546) (xy 95.592882 -270.532366)
			(xy 95.643734 -270.530317) (xy 95.694255 -270.536451) (xy 95.743139 -270.550611) (xy 95.789118 -270.572428)
			(xy 95.831002 -270.601338) (xy 95.867706 -270.636593) (xy 95.898279 -270.677279) (xy 95.92193 -270.722342)
			(xy 95.938046 -270.770616) (xy 95.94621 -270.82085) (xy 95.946722 -270.846296) (xy 95.94621 -270.871742)
			(xy 95.938046 -270.921976) (xy 95.92193 -270.97025) (xy 95.898279 -271.015313) (xy 95.867706 -271.055999)
			(xy 95.831002 -271.091254) (xy 95.789118 -271.120164) (xy 95.743139 -271.141981) (xy 95.694255 -271.156141)
			(xy 95.643734 -271.162275) (xy 95.592882 -271.160226) (xy 95.543018 -271.150046) (xy 95.495432 -271.131999)
			(xy 95.451358 -271.106553) (xy 95.411936 -271.074366) (xy 95.378188 -271.036272) (xy 95.350987 -270.993258)
			(xy 95.331039 -270.946438) (xy 95.31886 -270.897024) (xy 95.314765 -270.846296) (xy 95.006668 -270.846296)
			(xy 95.006156 -270.871742) (xy 94.997992 -270.921976) (xy 94.981876 -270.97025) (xy 94.958225 -271.015313)
			(xy 94.927652 -271.055999) (xy 94.890948 -271.091254) (xy 94.849064 -271.120164) (xy 94.803085 -271.141981)
			(xy 94.754201 -271.156141) (xy 94.70368 -271.162275) (xy 94.652828 -271.160226) (xy 94.602964 -271.150046)
			(xy 94.555378 -271.131999) (xy 94.511304 -271.106553) (xy 94.471882 -271.074366) (xy 94.438134 -271.036272)
			(xy 94.410933 -270.993258) (xy 94.390985 -270.946438) (xy 94.378806 -270.897024) (xy 94.374711 -270.846296)
			(xy 93.126814 -270.846296) (xy 93.126302 -270.871742) (xy 93.118138 -270.921976) (xy 93.102022 -270.97025)
			(xy 93.078371 -271.015313) (xy 93.047798 -271.055999) (xy 93.011094 -271.091254) (xy 92.96921 -271.120164)
			(xy 92.923231 -271.141981) (xy 92.874347 -271.156141) (xy 92.823826 -271.162275) (xy 92.772974 -271.160226)
			(xy 92.72311 -271.150046) (xy 92.675524 -271.131999) (xy 92.63145 -271.106553) (xy 92.592028 -271.074366)
			(xy 92.55828 -271.036272) (xy 92.531079 -270.993258) (xy 92.511131 -270.946438) (xy 92.498952 -270.897024)
			(xy 92.494857 -270.846296) (xy 92.176346 -270.846296) (xy 92.175851 -270.870903) (xy 92.167956 -270.91948)
			(xy 92.152372 -270.966161) (xy 92.129501 -271.009738) (xy 92.099936 -271.049082) (xy 92.064443 -271.083174)
			(xy 92.02394 -271.11113) (xy 91.979478 -271.132228) (xy 91.932207 -271.14592) (xy 91.883352 -271.151852)
			(xy 91.834177 -271.149871) (xy 91.785958 -271.140027) (xy 91.739942 -271.122575) (xy 91.697321 -271.097968)
			(xy 91.6592 -271.066843) (xy 91.626565 -271.030006) (xy 91.600262 -270.98841) (xy 91.580971 -270.943134)
			(xy 91.569194 -270.89535) (xy 91.565234 -270.846296) (xy 91.246706 -270.846296) (xy 91.246194 -270.871742)
			(xy 91.23803 -270.921976) (xy 91.221914 -270.97025) (xy 91.198263 -271.015313) (xy 91.16769 -271.055999)
			(xy 91.130986 -271.091254) (xy 91.089102 -271.120164) (xy 91.043123 -271.141981) (xy 90.994239 -271.156141)
			(xy 90.943718 -271.162275) (xy 90.892866 -271.160226) (xy 90.843002 -271.150046) (xy 90.795416 -271.131999)
			(xy 90.751342 -271.106553) (xy 90.71192 -271.074366) (xy 90.678172 -271.036272) (xy 90.650971 -270.993258)
			(xy 90.631023 -270.946438) (xy 90.618844 -270.897024) (xy 90.614749 -270.846296) (xy 90.296238 -270.846296)
			(xy 90.295743 -270.870903) (xy 90.287848 -270.91948) (xy 90.272264 -270.966161) (xy 90.249393 -271.009738)
			(xy 90.219828 -271.049082) (xy 90.184335 -271.083174) (xy 90.143832 -271.11113) (xy 90.09937 -271.132228)
			(xy 90.052099 -271.14592) (xy 90.003244 -271.151852) (xy 89.954069 -271.149871) (xy 89.90585 -271.140027)
			(xy 89.859834 -271.122575) (xy 89.817213 -271.097968) (xy 89.779092 -271.066843) (xy 89.746457 -271.030006)
			(xy 89.720154 -270.98841) (xy 89.700863 -270.943134) (xy 89.689086 -270.89535) (xy 89.685126 -270.846296)
			(xy 89.356438 -270.846296) (xy 89.355943 -270.870903) (xy 89.348048 -270.91948) (xy 89.332464 -270.966161)
			(xy 89.309593 -271.009738) (xy 89.280028 -271.049082) (xy 89.244535 -271.083174) (xy 89.204032 -271.11113)
			(xy 89.15957 -271.132228) (xy 89.112299 -271.14592) (xy 89.063444 -271.151852) (xy 89.014269 -271.149871)
			(xy 88.96605 -271.140027) (xy 88.920034 -271.122575) (xy 88.877413 -271.097968) (xy 88.839292 -271.066843)
			(xy 88.806657 -271.030006) (xy 88.780354 -270.98841) (xy 88.761063 -270.943134) (xy 88.749286 -270.89535)
			(xy 88.745326 -270.846296) (xy 88.416384 -270.846296) (xy 88.415889 -270.870903) (xy 88.407994 -270.91948)
			(xy 88.39241 -270.966161) (xy 88.369539 -271.009738) (xy 88.339974 -271.049082) (xy 88.304481 -271.083174)
			(xy 88.263978 -271.11113) (xy 88.219516 -271.132228) (xy 88.172245 -271.14592) (xy 88.12339 -271.151852)
			(xy 88.074215 -271.149871) (xy 88.025996 -271.140027) (xy 87.97998 -271.122575) (xy 87.937359 -271.097968)
			(xy 87.899238 -271.066843) (xy 87.866603 -271.030006) (xy 87.8403 -270.98841) (xy 87.821009 -270.943134)
			(xy 87.809232 -270.89535) (xy 87.805272 -270.846296) (xy 86.536276 -270.846296) (xy 86.535781 -270.870903)
			(xy 86.527886 -270.91948) (xy 86.512302 -270.966161) (xy 86.489431 -271.009738) (xy 86.459866 -271.049082)
			(xy 86.424373 -271.083174) (xy 86.38387 -271.11113) (xy 86.339408 -271.132228) (xy 86.292137 -271.14592)
			(xy 86.243282 -271.151852) (xy 86.194107 -271.149871) (xy 86.145888 -271.140027) (xy 86.099872 -271.122575)
			(xy 86.057251 -271.097968) (xy 86.01913 -271.066843) (xy 85.986495 -271.030006) (xy 85.960192 -270.98841)
			(xy 85.940901 -270.943134) (xy 85.929124 -270.89535) (xy 85.925164 -270.846296) (xy 85.596222 -270.846296)
			(xy 85.595727 -270.870903) (xy 85.587832 -270.91948) (xy 85.572248 -270.966161) (xy 85.549377 -271.009738)
			(xy 85.519812 -271.049082) (xy 85.484319 -271.083174) (xy 85.443816 -271.11113) (xy 85.399354 -271.132228)
			(xy 85.352083 -271.14592) (xy 85.303228 -271.151852) (xy 85.254053 -271.149871) (xy 85.205834 -271.140027)
			(xy 85.159818 -271.122575) (xy 85.117197 -271.097968) (xy 85.079076 -271.066843) (xy 85.046441 -271.030006)
			(xy 85.020138 -270.98841) (xy 85.000847 -270.943134) (xy 84.98907 -270.89535) (xy 84.98511 -270.846296)
			(xy 84.656422 -270.846296) (xy 84.655927 -270.870903) (xy 84.648032 -270.91948) (xy 84.632448 -270.966161)
			(xy 84.609577 -271.009738) (xy 84.580012 -271.049082) (xy 84.544519 -271.083174) (xy 84.504016 -271.11113)
			(xy 84.459554 -271.132228) (xy 84.412283 -271.14592) (xy 84.363428 -271.151852) (xy 84.314253 -271.149871)
			(xy 84.266034 -271.140027) (xy 84.220018 -271.122575) (xy 84.177397 -271.097968) (xy 84.139276 -271.066843)
			(xy 84.106641 -271.030006) (xy 84.080338 -270.98841) (xy 84.061047 -270.943134) (xy 84.04927 -270.89535)
			(xy 84.04531 -270.846296) (xy 83.716368 -270.846296) (xy 83.716368 -270.852138) (xy 83.715346 -270.877827)
			(xy 83.705767 -270.928333) (xy 83.687861 -270.976521) (xy 83.662136 -271.021028) (xy 83.629319 -271.060597)
			(xy 83.590336 -271.094108) (xy 83.546291 -271.120616) (xy 83.522566 -271.130522) (xy 83.512152 -271.13484)
			(xy 83.503516 -271.14754) (xy 83.49948 -271.153945) (xy 83.495076 -271.168421) (xy 83.49488 -271.175988)
			(xy 83.49488 -271.298416) (xy 83.495138 -271.304025) (xy 83.497828 -271.314923) (xy 83.500214 -271.320006)
			(xy 83.504786 -271.32788) (xy 83.508738 -271.332733) (xy 83.518499 -271.340561) (xy 83.52409 -271.343374)
			(xy 83.524344 -271.343628) (xy 83.605116 -271.380966) (xy 83.618832 -271.384268) (xy 83.631278 -271.384776)
			(xy 83.648042 -271.378426) (xy 83.6549 -271.375124) (xy 83.665314 -271.369282) (xy 83.6676 -271.367504)
			(xy 83.668616 -271.366742) (xy 83.66887 -271.366488) (xy 83.689157 -271.351412) (xy 83.733637 -271.327419)
			(xy 83.781453 -271.311051) (xy 83.831306 -271.302752) (xy 83.856576 -271.302226) (xy 83.882414 -271.302774)
			(xy 83.93335 -271.311487) (xy 83.982092 -271.328652) (xy 84.027248 -271.353778) (xy 84.067528 -271.386148)
			(xy 84.101784 -271.424839) (xy 84.129037 -271.468744) (xy 84.139278 -271.492472) (xy 84.142834 -271.499076)
			(xy 84.143088 -271.499584) (xy 84.156617 -271.523465) (xy 84.175869 -271.574858) (xy 84.185642 -271.628861)
			(xy 84.186268 -271.656302) (xy 84.51521 -271.656302) (xy 84.51917 -271.607248) (xy 84.530947 -271.559464)
			(xy 84.550238 -271.514188) (xy 84.576541 -271.472592) (xy 84.609176 -271.435755) (xy 84.647297 -271.40463)
			(xy 84.689918 -271.380023) (xy 84.735934 -271.362571) (xy 84.784153 -271.352727) (xy 84.833328 -271.350746)
			(xy 84.882183 -271.356678) (xy 84.929454 -271.37037) (xy 84.973916 -271.391468) (xy 85.014419 -271.419424)
			(xy 85.049912 -271.453516) (xy 85.079477 -271.49286) (xy 85.102348 -271.536437) (xy 85.117932 -271.583118)
			(xy 85.125827 -271.631695) (xy 85.126322 -271.656302) (xy 85.455264 -271.656302) (xy 85.459224 -271.607248)
			(xy 85.471001 -271.559464) (xy 85.490292 -271.514188) (xy 85.516595 -271.472592) (xy 85.54923 -271.435755)
			(xy 85.587351 -271.40463) (xy 85.629972 -271.380023) (xy 85.675988 -271.362571) (xy 85.724207 -271.352727)
			(xy 85.773382 -271.350746) (xy 85.822237 -271.356678) (xy 85.869508 -271.37037) (xy 85.91397 -271.391468)
			(xy 85.954473 -271.419424) (xy 85.989966 -271.453516) (xy 86.019531 -271.49286) (xy 86.042402 -271.536437)
			(xy 86.057986 -271.583118) (xy 86.065881 -271.631695) (xy 86.066376 -271.656302) (xy 86.395318 -271.656302)
			(xy 86.399278 -271.607248) (xy 86.411055 -271.559464) (xy 86.430346 -271.514188) (xy 86.456649 -271.472592)
			(xy 86.489284 -271.435755) (xy 86.527405 -271.40463) (xy 86.570026 -271.380023) (xy 86.616042 -271.362571)
			(xy 86.664261 -271.352727) (xy 86.713436 -271.350746) (xy 86.762291 -271.356678) (xy 86.809562 -271.37037)
			(xy 86.854024 -271.391468) (xy 86.894527 -271.419424) (xy 86.93002 -271.453516) (xy 86.959585 -271.49286)
			(xy 86.982456 -271.536437) (xy 86.99804 -271.583118) (xy 87.005935 -271.631695) (xy 87.00643 -271.656302)
			(xy 87.335118 -271.656302) (xy 87.339078 -271.607248) (xy 87.350855 -271.559464) (xy 87.370146 -271.514188)
			(xy 87.396449 -271.472592) (xy 87.429084 -271.435755) (xy 87.467205 -271.40463) (xy 87.509826 -271.380023)
			(xy 87.555842 -271.362571) (xy 87.604061 -271.352727) (xy 87.653236 -271.350746) (xy 87.702091 -271.356678)
			(xy 87.749362 -271.37037) (xy 87.793824 -271.391468) (xy 87.834327 -271.419424) (xy 87.86982 -271.453516)
			(xy 87.899385 -271.49286) (xy 87.922256 -271.536437) (xy 87.93784 -271.583118) (xy 87.945735 -271.631695)
			(xy 87.94623 -271.656302) (xy 88.275172 -271.656302) (xy 88.279132 -271.607248) (xy 88.290909 -271.559464)
			(xy 88.3102 -271.514188) (xy 88.336503 -271.472592) (xy 88.369138 -271.435755) (xy 88.407259 -271.40463)
			(xy 88.44988 -271.380023) (xy 88.495896 -271.362571) (xy 88.544115 -271.352727) (xy 88.59329 -271.350746)
			(xy 88.642145 -271.356678) (xy 88.689416 -271.37037) (xy 88.733878 -271.391468) (xy 88.774381 -271.419424)
			(xy 88.809874 -271.453516) (xy 88.839439 -271.49286) (xy 88.86231 -271.536437) (xy 88.877894 -271.583118)
			(xy 88.885789 -271.631695) (xy 88.886284 -271.656302) (xy 89.215226 -271.656302) (xy 89.219186 -271.607248)
			(xy 89.230963 -271.559464) (xy 89.250254 -271.514188) (xy 89.276557 -271.472592) (xy 89.309192 -271.435755)
			(xy 89.347313 -271.40463) (xy 89.389934 -271.380023) (xy 89.43595 -271.362571) (xy 89.484169 -271.352727)
			(xy 89.533344 -271.350746) (xy 89.582199 -271.356678) (xy 89.62947 -271.37037) (xy 89.673932 -271.391468)
			(xy 89.714435 -271.419424) (xy 89.749928 -271.453516) (xy 89.779493 -271.49286) (xy 89.802364 -271.536437)
			(xy 89.817948 -271.583118) (xy 89.825843 -271.631695) (xy 89.826338 -271.656302) (xy 90.15528 -271.656302)
			(xy 90.15924 -271.607248) (xy 90.171017 -271.559464) (xy 90.190308 -271.514188) (xy 90.216611 -271.472592)
			(xy 90.249246 -271.435755) (xy 90.287367 -271.40463) (xy 90.329988 -271.380023) (xy 90.376004 -271.362571)
			(xy 90.424223 -271.352727) (xy 90.473398 -271.350746) (xy 90.522253 -271.356678) (xy 90.569524 -271.37037)
			(xy 90.613986 -271.391468) (xy 90.654489 -271.419424) (xy 90.689982 -271.453516) (xy 90.719547 -271.49286)
			(xy 90.742418 -271.536437) (xy 90.758002 -271.583118) (xy 90.765897 -271.631695) (xy 90.766392 -271.656302)
			(xy 91.084903 -271.656302) (xy 91.088998 -271.605574) (xy 91.101177 -271.55616) (xy 91.121125 -271.50934)
			(xy 91.148326 -271.466326) (xy 91.182074 -271.428232) (xy 91.221496 -271.396045) (xy 91.26557 -271.370599)
			(xy 91.313156 -271.352552) (xy 91.36302 -271.342372) (xy 91.413872 -271.340323) (xy 91.464393 -271.346457)
			(xy 91.513277 -271.360617) (xy 91.559256 -271.382434) (xy 91.60114 -271.411344) (xy 91.637844 -271.446599)
			(xy 91.668417 -271.487285) (xy 91.692068 -271.532348) (xy 91.708184 -271.580622) (xy 91.716348 -271.630856)
			(xy 91.71686 -271.656302) (xy 92.024703 -271.656302) (xy 92.028798 -271.605574) (xy 92.040977 -271.55616)
			(xy 92.060925 -271.50934) (xy 92.088126 -271.466326) (xy 92.121874 -271.428232) (xy 92.161296 -271.396045)
			(xy 92.20537 -271.370599) (xy 92.252956 -271.352552) (xy 92.30282 -271.342372) (xy 92.353672 -271.340323)
			(xy 92.404193 -271.346457) (xy 92.453077 -271.360617) (xy 92.499056 -271.382434) (xy 92.54094 -271.411344)
			(xy 92.577644 -271.446599) (xy 92.608217 -271.487285) (xy 92.631868 -271.532348) (xy 92.647984 -271.580622)
			(xy 92.656148 -271.630856) (xy 92.65666 -271.656302) (xy 92.975188 -271.656302) (xy 92.979148 -271.607248)
			(xy 92.990925 -271.559464) (xy 93.010216 -271.514188) (xy 93.036519 -271.472592) (xy 93.069154 -271.435755)
			(xy 93.107275 -271.40463) (xy 93.149896 -271.380023) (xy 93.195912 -271.362571) (xy 93.244131 -271.352727)
			(xy 93.293306 -271.350746) (xy 93.342161 -271.356678) (xy 93.389432 -271.37037) (xy 93.433894 -271.391468)
			(xy 93.474397 -271.419424) (xy 93.50989 -271.453516) (xy 93.539455 -271.49286) (xy 93.562326 -271.536437)
			(xy 93.57791 -271.583118) (xy 93.585805 -271.631695) (xy 93.5863 -271.656302) (xy 93.904811 -271.656302)
			(xy 93.908906 -271.605574) (xy 93.921085 -271.55616) (xy 93.941033 -271.50934) (xy 93.968234 -271.466326)
			(xy 94.001982 -271.428232) (xy 94.041404 -271.396045) (xy 94.085478 -271.370599) (xy 94.133064 -271.352552)
			(xy 94.182928 -271.342372) (xy 94.23378 -271.340323) (xy 94.284301 -271.346457) (xy 94.333185 -271.360617)
			(xy 94.379164 -271.382434) (xy 94.421048 -271.411344) (xy 94.457752 -271.446599) (xy 94.488325 -271.487285)
			(xy 94.511976 -271.532348) (xy 94.528092 -271.580622) (xy 94.536256 -271.630856) (xy 94.536768 -271.656302)
			(xy 94.855296 -271.656302) (xy 94.859256 -271.607248) (xy 94.871033 -271.559464) (xy 94.890324 -271.514188)
			(xy 94.916627 -271.472592) (xy 94.949262 -271.435755) (xy 94.987383 -271.40463) (xy 95.030004 -271.380023)
			(xy 95.07602 -271.362571) (xy 95.124239 -271.352727) (xy 95.173414 -271.350746) (xy 95.222269 -271.356678)
			(xy 95.26954 -271.37037) (xy 95.314002 -271.391468) (xy 95.354505 -271.419424) (xy 95.389998 -271.453516)
			(xy 95.419563 -271.49286) (xy 95.442434 -271.536437) (xy 95.458018 -271.583118) (xy 95.465913 -271.631695)
			(xy 95.466408 -271.656302) (xy 95.784919 -271.656302) (xy 95.789014 -271.605574) (xy 95.801193 -271.55616)
			(xy 95.821141 -271.50934) (xy 95.848342 -271.466326) (xy 95.88209 -271.428232) (xy 95.921512 -271.396045)
			(xy 95.965586 -271.370599) (xy 96.013172 -271.352552) (xy 96.063036 -271.342372) (xy 96.113888 -271.340323)
			(xy 96.164409 -271.346457) (xy 96.213293 -271.360617) (xy 96.259272 -271.382434) (xy 96.301156 -271.411344)
			(xy 96.33786 -271.446599) (xy 96.368433 -271.487285) (xy 96.392084 -271.532348) (xy 96.4082 -271.580622)
			(xy 96.416364 -271.630856) (xy 96.416876 -271.656302) (xy 96.416364 -271.681748) (xy 96.4082 -271.731982)
			(xy 96.392084 -271.780256) (xy 96.368433 -271.825319) (xy 96.33786 -271.866005) (xy 96.301156 -271.90126)
			(xy 96.259272 -271.93017) (xy 96.213293 -271.951987) (xy 96.164409 -271.966147) (xy 96.113888 -271.972281)
			(xy 96.063036 -271.970232) (xy 96.013172 -271.960052) (xy 95.965586 -271.942005) (xy 95.921512 -271.916559)
			(xy 95.88209 -271.884372) (xy 95.848342 -271.846278) (xy 95.821141 -271.803264) (xy 95.801193 -271.756444)
			(xy 95.789014 -271.70703) (xy 95.784919 -271.656302) (xy 95.466408 -271.656302) (xy 95.465913 -271.680909)
			(xy 95.458018 -271.729486) (xy 95.442434 -271.776167) (xy 95.419563 -271.819744) (xy 95.389998 -271.859088)
			(xy 95.354505 -271.89318) (xy 95.314002 -271.921136) (xy 95.26954 -271.942234) (xy 95.222269 -271.955926)
			(xy 95.173414 -271.961858) (xy 95.124239 -271.959877) (xy 95.07602 -271.950033) (xy 95.030004 -271.932581)
			(xy 94.987383 -271.907974) (xy 94.949262 -271.876849) (xy 94.916627 -271.840012) (xy 94.890324 -271.798416)
			(xy 94.871033 -271.75314) (xy 94.859256 -271.705356) (xy 94.855296 -271.656302) (xy 94.536768 -271.656302)
			(xy 94.536256 -271.681748) (xy 94.528092 -271.731982) (xy 94.511976 -271.780256) (xy 94.488325 -271.825319)
			(xy 94.457752 -271.866005) (xy 94.421048 -271.90126) (xy 94.379164 -271.93017) (xy 94.333185 -271.951987)
			(xy 94.284301 -271.966147) (xy 94.23378 -271.972281) (xy 94.182928 -271.970232) (xy 94.133064 -271.960052)
			(xy 94.085478 -271.942005) (xy 94.041404 -271.916559) (xy 94.001982 -271.884372) (xy 93.968234 -271.846278)
			(xy 93.941033 -271.803264) (xy 93.921085 -271.756444) (xy 93.908906 -271.70703) (xy 93.904811 -271.656302)
			(xy 93.5863 -271.656302) (xy 93.585805 -271.680909) (xy 93.57791 -271.729486) (xy 93.562326 -271.776167)
			(xy 93.539455 -271.819744) (xy 93.50989 -271.859088) (xy 93.474397 -271.89318) (xy 93.433894 -271.921136)
			(xy 93.389432 -271.942234) (xy 93.342161 -271.955926) (xy 93.293306 -271.961858) (xy 93.244131 -271.959877)
			(xy 93.195912 -271.950033) (xy 93.149896 -271.932581) (xy 93.107275 -271.907974) (xy 93.069154 -271.876849)
			(xy 93.036519 -271.840012) (xy 93.010216 -271.798416) (xy 92.990925 -271.75314) (xy 92.979148 -271.705356)
			(xy 92.975188 -271.656302) (xy 92.65666 -271.656302) (xy 92.656148 -271.681748) (xy 92.647984 -271.731982)
			(xy 92.631868 -271.780256) (xy 92.608217 -271.825319) (xy 92.577644 -271.866005) (xy 92.54094 -271.90126)
			(xy 92.499056 -271.93017) (xy 92.453077 -271.951987) (xy 92.404193 -271.966147) (xy 92.353672 -271.972281)
			(xy 92.30282 -271.970232) (xy 92.252956 -271.960052) (xy 92.20537 -271.942005) (xy 92.161296 -271.916559)
			(xy 92.121874 -271.884372) (xy 92.088126 -271.846278) (xy 92.060925 -271.803264) (xy 92.040977 -271.756444)
			(xy 92.028798 -271.70703) (xy 92.024703 -271.656302) (xy 91.71686 -271.656302) (xy 91.716348 -271.681748)
			(xy 91.708184 -271.731982) (xy 91.692068 -271.780256) (xy 91.668417 -271.825319) (xy 91.637844 -271.866005)
			(xy 91.60114 -271.90126) (xy 91.559256 -271.93017) (xy 91.513277 -271.951987) (xy 91.464393 -271.966147)
			(xy 91.413872 -271.972281) (xy 91.36302 -271.970232) (xy 91.313156 -271.960052) (xy 91.26557 -271.942005)
			(xy 91.221496 -271.916559) (xy 91.182074 -271.884372) (xy 91.148326 -271.846278) (xy 91.121125 -271.803264)
			(xy 91.101177 -271.756444) (xy 91.088998 -271.70703) (xy 91.084903 -271.656302) (xy 90.766392 -271.656302)
			(xy 90.765897 -271.680909) (xy 90.758002 -271.729486) (xy 90.742418 -271.776167) (xy 90.719547 -271.819744)
			(xy 90.689982 -271.859088) (xy 90.654489 -271.89318) (xy 90.613986 -271.921136) (xy 90.569524 -271.942234)
			(xy 90.522253 -271.955926) (xy 90.473398 -271.961858) (xy 90.424223 -271.959877) (xy 90.376004 -271.950033)
			(xy 90.329988 -271.932581) (xy 90.287367 -271.907974) (xy 90.249246 -271.876849) (xy 90.216611 -271.840012)
			(xy 90.190308 -271.798416) (xy 90.171017 -271.75314) (xy 90.15924 -271.705356) (xy 90.15528 -271.656302)
			(xy 89.826338 -271.656302) (xy 89.825843 -271.680909) (xy 89.817948 -271.729486) (xy 89.802364 -271.776167)
			(xy 89.779493 -271.819744) (xy 89.749928 -271.859088) (xy 89.714435 -271.89318) (xy 89.673932 -271.921136)
			(xy 89.62947 -271.942234) (xy 89.582199 -271.955926) (xy 89.533344 -271.961858) (xy 89.484169 -271.959877)
			(xy 89.43595 -271.950033) (xy 89.389934 -271.932581) (xy 89.347313 -271.907974) (xy 89.309192 -271.876849)
			(xy 89.276557 -271.840012) (xy 89.250254 -271.798416) (xy 89.230963 -271.75314) (xy 89.219186 -271.705356)
			(xy 89.215226 -271.656302) (xy 88.886284 -271.656302) (xy 88.885789 -271.680909) (xy 88.877894 -271.729486)
			(xy 88.86231 -271.776167) (xy 88.839439 -271.819744) (xy 88.809874 -271.859088) (xy 88.774381 -271.89318)
			(xy 88.733878 -271.921136) (xy 88.689416 -271.942234) (xy 88.642145 -271.955926) (xy 88.59329 -271.961858)
			(xy 88.544115 -271.959877) (xy 88.495896 -271.950033) (xy 88.44988 -271.932581) (xy 88.407259 -271.907974)
			(xy 88.369138 -271.876849) (xy 88.336503 -271.840012) (xy 88.3102 -271.798416) (xy 88.290909 -271.75314)
			(xy 88.279132 -271.705356) (xy 88.275172 -271.656302) (xy 87.94623 -271.656302) (xy 87.945735 -271.680909)
			(xy 87.93784 -271.729486) (xy 87.922256 -271.776167) (xy 87.899385 -271.819744) (xy 87.86982 -271.859088)
			(xy 87.834327 -271.89318) (xy 87.793824 -271.921136) (xy 87.749362 -271.942234) (xy 87.702091 -271.955926)
			(xy 87.653236 -271.961858) (xy 87.604061 -271.959877) (xy 87.555842 -271.950033) (xy 87.509826 -271.932581)
			(xy 87.467205 -271.907974) (xy 87.429084 -271.876849) (xy 87.396449 -271.840012) (xy 87.370146 -271.798416)
			(xy 87.350855 -271.75314) (xy 87.339078 -271.705356) (xy 87.335118 -271.656302) (xy 87.00643 -271.656302)
			(xy 87.005935 -271.680909) (xy 86.99804 -271.729486) (xy 86.982456 -271.776167) (xy 86.959585 -271.819744)
			(xy 86.93002 -271.859088) (xy 86.894527 -271.89318) (xy 86.854024 -271.921136) (xy 86.809562 -271.942234)
			(xy 86.762291 -271.955926) (xy 86.713436 -271.961858) (xy 86.664261 -271.959877) (xy 86.616042 -271.950033)
			(xy 86.570026 -271.932581) (xy 86.527405 -271.907974) (xy 86.489284 -271.876849) (xy 86.456649 -271.840012)
			(xy 86.430346 -271.798416) (xy 86.411055 -271.75314) (xy 86.399278 -271.705356) (xy 86.395318 -271.656302)
			(xy 86.066376 -271.656302) (xy 86.065881 -271.680909) (xy 86.057986 -271.729486) (xy 86.042402 -271.776167)
			(xy 86.019531 -271.819744) (xy 85.989966 -271.859088) (xy 85.954473 -271.89318) (xy 85.91397 -271.921136)
			(xy 85.869508 -271.942234) (xy 85.822237 -271.955926) (xy 85.773382 -271.961858) (xy 85.724207 -271.959877)
			(xy 85.675988 -271.950033) (xy 85.629972 -271.932581) (xy 85.587351 -271.907974) (xy 85.54923 -271.876849)
			(xy 85.516595 -271.840012) (xy 85.490292 -271.798416) (xy 85.471001 -271.75314) (xy 85.459224 -271.705356)
			(xy 85.455264 -271.656302) (xy 85.126322 -271.656302) (xy 85.125827 -271.680909) (xy 85.117932 -271.729486)
			(xy 85.102348 -271.776167) (xy 85.079477 -271.819744) (xy 85.049912 -271.859088) (xy 85.014419 -271.89318)
			(xy 84.973916 -271.921136) (xy 84.929454 -271.942234) (xy 84.882183 -271.955926) (xy 84.833328 -271.961858)
			(xy 84.784153 -271.959877) (xy 84.735934 -271.950033) (xy 84.689918 -271.932581) (xy 84.647297 -271.907974)
			(xy 84.609176 -271.876849) (xy 84.576541 -271.840012) (xy 84.550238 -271.798416) (xy 84.530947 -271.75314)
			(xy 84.51917 -271.705356) (xy 84.51521 -271.656302) (xy 84.186268 -271.656302) (xy 84.185822 -271.680294)
			(xy 84.178314 -271.727687) (xy 84.163485 -271.773322) (xy 84.141699 -271.816075) (xy 84.113493 -271.854893)
			(xy 84.079561 -271.88882) (xy 84.040739 -271.917021) (xy 83.997983 -271.938801) (xy 83.952346 -271.953624)
			(xy 83.904952 -271.961125) (xy 83.88096 -271.96161) (xy 83.85457 -271.961059) (xy 83.802572 -271.951999)
			(xy 83.752906 -271.934138) (xy 83.707047 -271.908008) (xy 83.666361 -271.874386) (xy 83.648804 -271.854676)
			(xy 83.627468 -271.82953) (xy 83.62569 -271.82953) (xy 83.621481 -271.829612) (xy 83.613182 -271.831018)
			(xy 83.60918 -271.832324) (xy 83.521804 -271.87271) (xy 83.514025 -271.877243) (xy 83.502044 -271.890665)
			(xy 83.495466 -271.907412) (xy 83.49488 -271.916398) (xy 83.49488 -272.085308) (xy 83.494914 -272.089444)
			(xy 83.496193 -272.097614) (xy 83.49742 -272.101564) (xy 83.502246 -272.111724) (xy 83.515708 -272.132806)
			(xy 83.519208 -272.138069) (xy 83.528331 -272.146811) (xy 83.533742 -272.150078) (xy 83.533996 -272.150078)
			(xy 83.555756 -272.162658) (xy 83.595203 -272.193801) (xy 83.612482 -272.212054) (xy 83.630126 -272.232252)
			(xy 83.658743 -272.277604) (xy 83.669378 -272.302224) (xy 83.672934 -272.308828) (xy 83.673188 -272.309336)
			(xy 83.686703 -272.333178) (xy 83.705947 -272.384486) (xy 83.715744 -272.438401) (xy 83.716368 -272.4658)
			(xy 83.716368 -272.466308) (xy 84.04531 -272.466308) (xy 84.04927 -272.417254) (xy 84.061047 -272.36947)
			(xy 84.080338 -272.324194) (xy 84.106641 -272.282598) (xy 84.139276 -272.245761) (xy 84.177397 -272.214636)
			(xy 84.220018 -272.190029) (xy 84.266034 -272.172577) (xy 84.314253 -272.162733) (xy 84.363428 -272.160752)
			(xy 84.412283 -272.166684) (xy 84.459554 -272.180376) (xy 84.504016 -272.201474) (xy 84.544519 -272.22943)
			(xy 84.580012 -272.263522) (xy 84.609577 -272.302866) (xy 84.632448 -272.346443) (xy 84.648032 -272.393124)
			(xy 84.655927 -272.441701) (xy 84.656422 -272.466308) (xy 84.98511 -272.466308) (xy 84.98907 -272.417254)
			(xy 85.000847 -272.36947) (xy 85.020138 -272.324194) (xy 85.046441 -272.282598) (xy 85.079076 -272.245761)
			(xy 85.117197 -272.214636) (xy 85.159818 -272.190029) (xy 85.205834 -272.172577) (xy 85.254053 -272.162733)
			(xy 85.303228 -272.160752) (xy 85.352083 -272.166684) (xy 85.399354 -272.180376) (xy 85.443816 -272.201474)
			(xy 85.484319 -272.22943) (xy 85.519812 -272.263522) (xy 85.549377 -272.302866) (xy 85.572248 -272.346443)
			(xy 85.587832 -272.393124) (xy 85.595727 -272.441701) (xy 85.596222 -272.466308) (xy 85.925164 -272.466308)
			(xy 85.929124 -272.417254) (xy 85.940901 -272.36947) (xy 85.960192 -272.324194) (xy 85.986495 -272.282598)
			(xy 86.01913 -272.245761) (xy 86.057251 -272.214636) (xy 86.099872 -272.190029) (xy 86.145888 -272.172577)
			(xy 86.194107 -272.162733) (xy 86.243282 -272.160752) (xy 86.292137 -272.166684) (xy 86.339408 -272.180376)
			(xy 86.38387 -272.201474) (xy 86.424373 -272.22943) (xy 86.459866 -272.263522) (xy 86.489431 -272.302866)
			(xy 86.512302 -272.346443) (xy 86.527886 -272.393124) (xy 86.535781 -272.441701) (xy 86.536276 -272.466308)
			(xy 86.865218 -272.466308) (xy 86.869178 -272.417254) (xy 86.880955 -272.36947) (xy 86.900246 -272.324194)
			(xy 86.926549 -272.282598) (xy 86.959184 -272.245761) (xy 86.997305 -272.214636) (xy 87.039926 -272.190029)
			(xy 87.085942 -272.172577) (xy 87.134161 -272.162733) (xy 87.183336 -272.160752) (xy 87.232191 -272.166684)
			(xy 87.279462 -272.180376) (xy 87.323924 -272.201474) (xy 87.364427 -272.22943) (xy 87.39992 -272.263522)
			(xy 87.429485 -272.302866) (xy 87.452356 -272.346443) (xy 87.46794 -272.393124) (xy 87.475835 -272.441701)
			(xy 87.47633 -272.466308) (xy 87.805272 -272.466308) (xy 87.809232 -272.417254) (xy 87.821009 -272.36947)
			(xy 87.8403 -272.324194) (xy 87.866603 -272.282598) (xy 87.899238 -272.245761) (xy 87.937359 -272.214636)
			(xy 87.97998 -272.190029) (xy 88.025996 -272.172577) (xy 88.074215 -272.162733) (xy 88.12339 -272.160752)
			(xy 88.172245 -272.166684) (xy 88.219516 -272.180376) (xy 88.263978 -272.201474) (xy 88.304481 -272.22943)
			(xy 88.339974 -272.263522) (xy 88.369539 -272.302866) (xy 88.39241 -272.346443) (xy 88.407994 -272.393124)
			(xy 88.415889 -272.441701) (xy 88.416384 -272.466308) (xy 88.745326 -272.466308) (xy 88.749286 -272.417254)
			(xy 88.761063 -272.36947) (xy 88.780354 -272.324194) (xy 88.806657 -272.282598) (xy 88.839292 -272.245761)
			(xy 88.877413 -272.214636) (xy 88.920034 -272.190029) (xy 88.96605 -272.172577) (xy 89.014269 -272.162733)
			(xy 89.063444 -272.160752) (xy 89.112299 -272.166684) (xy 89.15957 -272.180376) (xy 89.204032 -272.201474)
			(xy 89.244535 -272.22943) (xy 89.280028 -272.263522) (xy 89.309593 -272.302866) (xy 89.332464 -272.346443)
			(xy 89.348048 -272.393124) (xy 89.355943 -272.441701) (xy 89.356438 -272.466308) (xy 89.685126 -272.466308)
			(xy 89.689086 -272.417254) (xy 89.700863 -272.36947) (xy 89.720154 -272.324194) (xy 89.746457 -272.282598)
			(xy 89.779092 -272.245761) (xy 89.817213 -272.214636) (xy 89.859834 -272.190029) (xy 89.90585 -272.172577)
			(xy 89.954069 -272.162733) (xy 90.003244 -272.160752) (xy 90.052099 -272.166684) (xy 90.09937 -272.180376)
			(xy 90.143832 -272.201474) (xy 90.184335 -272.22943) (xy 90.219828 -272.263522) (xy 90.249393 -272.302866)
			(xy 90.272264 -272.346443) (xy 90.287848 -272.393124) (xy 90.295743 -272.441701) (xy 90.296238 -272.466308)
			(xy 90.614749 -272.466308) (xy 90.618844 -272.41558) (xy 90.631023 -272.366166) (xy 90.650971 -272.319346)
			(xy 90.678172 -272.276332) (xy 90.71192 -272.238238) (xy 90.751342 -272.206051) (xy 90.795416 -272.180605)
			(xy 90.843002 -272.162558) (xy 90.892866 -272.152378) (xy 90.943718 -272.150329) (xy 90.994239 -272.156463)
			(xy 91.043123 -272.170623) (xy 91.089102 -272.19244) (xy 91.130986 -272.22135) (xy 91.16769 -272.256605)
			(xy 91.198263 -272.297291) (xy 91.221914 -272.342354) (xy 91.23803 -272.390628) (xy 91.246194 -272.440862)
			(xy 91.246706 -272.466308) (xy 91.565234 -272.466308) (xy 91.569194 -272.417254) (xy 91.580971 -272.36947)
			(xy 91.600262 -272.324194) (xy 91.626565 -272.282598) (xy 91.6592 -272.245761) (xy 91.697321 -272.214636)
			(xy 91.739942 -272.190029) (xy 91.785958 -272.172577) (xy 91.834177 -272.162733) (xy 91.883352 -272.160752)
			(xy 91.932207 -272.166684) (xy 91.979478 -272.180376) (xy 92.02394 -272.201474) (xy 92.064443 -272.22943)
			(xy 92.099936 -272.263522) (xy 92.129501 -272.302866) (xy 92.152372 -272.346443) (xy 92.167956 -272.393124)
			(xy 92.175851 -272.441701) (xy 92.176346 -272.466308) (xy 92.494857 -272.466308) (xy 92.498952 -272.41558)
			(xy 92.511131 -272.366166) (xy 92.531079 -272.319346) (xy 92.55828 -272.276332) (xy 92.592028 -272.238238)
			(xy 92.63145 -272.206051) (xy 92.675524 -272.180605) (xy 92.72311 -272.162558) (xy 92.772974 -272.152378)
			(xy 92.823826 -272.150329) (xy 92.874347 -272.156463) (xy 92.923231 -272.170623) (xy 92.96921 -272.19244)
			(xy 93.011094 -272.22135) (xy 93.047798 -272.256605) (xy 93.078371 -272.297291) (xy 93.102022 -272.342354)
			(xy 93.118138 -272.390628) (xy 93.126302 -272.440862) (xy 93.126814 -272.466308) (xy 93.445342 -272.466308)
			(xy 93.449302 -272.417254) (xy 93.461079 -272.36947) (xy 93.48037 -272.324194) (xy 93.506673 -272.282598)
			(xy 93.539308 -272.245761) (xy 93.577429 -272.214636) (xy 93.62005 -272.190029) (xy 93.666066 -272.172577)
			(xy 93.714285 -272.162733) (xy 93.76346 -272.160752) (xy 93.812315 -272.166684) (xy 93.859586 -272.180376)
			(xy 93.904048 -272.201474) (xy 93.944551 -272.22943) (xy 93.980044 -272.263522) (xy 94.009609 -272.302866)
			(xy 94.03248 -272.346443) (xy 94.048064 -272.393124) (xy 94.055959 -272.441701) (xy 94.056454 -272.466308)
			(xy 94.374711 -272.466308) (xy 94.378806 -272.41558) (xy 94.390985 -272.366166) (xy 94.410933 -272.319346)
			(xy 94.438134 -272.276332) (xy 94.471882 -272.238238) (xy 94.511304 -272.206051) (xy 94.555378 -272.180605)
			(xy 94.602964 -272.162558) (xy 94.652828 -272.152378) (xy 94.70368 -272.150329) (xy 94.754201 -272.156463)
			(xy 94.803085 -272.170623) (xy 94.849064 -272.19244) (xy 94.890948 -272.22135) (xy 94.927652 -272.256605)
			(xy 94.958225 -272.297291) (xy 94.981876 -272.342354) (xy 94.997992 -272.390628) (xy 95.006156 -272.440862)
			(xy 95.006668 -272.466308) (xy 95.314765 -272.466308) (xy 95.31886 -272.41558) (xy 95.331039 -272.366166)
			(xy 95.350987 -272.319346) (xy 95.378188 -272.276332) (xy 95.411936 -272.238238) (xy 95.451358 -272.206051)
			(xy 95.495432 -272.180605) (xy 95.543018 -272.162558) (xy 95.592882 -272.152378) (xy 95.643734 -272.150329)
			(xy 95.694255 -272.156463) (xy 95.743139 -272.170623) (xy 95.789118 -272.19244) (xy 95.831002 -272.22135)
			(xy 95.867706 -272.256605) (xy 95.898279 -272.297291) (xy 95.92193 -272.342354) (xy 95.938046 -272.390628)
			(xy 95.94621 -272.440862) (xy 95.946722 -272.466308) (xy 95.94621 -272.491754) (xy 95.938046 -272.541988)
			(xy 95.92193 -272.590262) (xy 95.898279 -272.635325) (xy 95.867706 -272.676011) (xy 95.831002 -272.711266)
			(xy 95.789118 -272.740176) (xy 95.743139 -272.761993) (xy 95.694255 -272.776153) (xy 95.643734 -272.782287)
			(xy 95.592882 -272.780238) (xy 95.543018 -272.770058) (xy 95.495432 -272.752011) (xy 95.451358 -272.726565)
			(xy 95.411936 -272.694378) (xy 95.378188 -272.656284) (xy 95.350987 -272.61327) (xy 95.331039 -272.56645)
			(xy 95.31886 -272.517036) (xy 95.314765 -272.466308) (xy 95.006668 -272.466308) (xy 95.006156 -272.491754)
			(xy 94.997992 -272.541988) (xy 94.981876 -272.590262) (xy 94.958225 -272.635325) (xy 94.927652 -272.676011)
			(xy 94.890948 -272.711266) (xy 94.849064 -272.740176) (xy 94.803085 -272.761993) (xy 94.754201 -272.776153)
			(xy 94.70368 -272.782287) (xy 94.652828 -272.780238) (xy 94.602964 -272.770058) (xy 94.555378 -272.752011)
			(xy 94.511304 -272.726565) (xy 94.471882 -272.694378) (xy 94.438134 -272.656284) (xy 94.410933 -272.61327)
			(xy 94.390985 -272.56645) (xy 94.378806 -272.517036) (xy 94.374711 -272.466308) (xy 94.056454 -272.466308)
			(xy 94.055959 -272.490915) (xy 94.048064 -272.539492) (xy 94.03248 -272.586173) (xy 94.009609 -272.62975)
			(xy 93.980044 -272.669094) (xy 93.944551 -272.703186) (xy 93.904048 -272.731142) (xy 93.859586 -272.75224)
			(xy 93.812315 -272.765932) (xy 93.76346 -272.771864) (xy 93.714285 -272.769883) (xy 93.666066 -272.760039)
			(xy 93.62005 -272.742587) (xy 93.577429 -272.71798) (xy 93.539308 -272.686855) (xy 93.506673 -272.650018)
			(xy 93.48037 -272.608422) (xy 93.461079 -272.563146) (xy 93.449302 -272.515362) (xy 93.445342 -272.466308)
			(xy 93.126814 -272.466308) (xy 93.126302 -272.491754) (xy 93.118138 -272.541988) (xy 93.102022 -272.590262)
			(xy 93.078371 -272.635325) (xy 93.047798 -272.676011) (xy 93.011094 -272.711266) (xy 92.96921 -272.740176)
			(xy 92.923231 -272.761993) (xy 92.874347 -272.776153) (xy 92.823826 -272.782287) (xy 92.772974 -272.780238)
			(xy 92.72311 -272.770058) (xy 92.675524 -272.752011) (xy 92.63145 -272.726565) (xy 92.592028 -272.694378)
			(xy 92.55828 -272.656284) (xy 92.531079 -272.61327) (xy 92.511131 -272.56645) (xy 92.498952 -272.517036)
			(xy 92.494857 -272.466308) (xy 92.176346 -272.466308) (xy 92.175851 -272.490915) (xy 92.167956 -272.539492)
			(xy 92.152372 -272.586173) (xy 92.129501 -272.62975) (xy 92.099936 -272.669094) (xy 92.064443 -272.703186)
			(xy 92.02394 -272.731142) (xy 91.979478 -272.75224) (xy 91.932207 -272.765932) (xy 91.883352 -272.771864)
			(xy 91.834177 -272.769883) (xy 91.785958 -272.760039) (xy 91.739942 -272.742587) (xy 91.697321 -272.71798)
			(xy 91.6592 -272.686855) (xy 91.626565 -272.650018) (xy 91.600262 -272.608422) (xy 91.580971 -272.563146)
			(xy 91.569194 -272.515362) (xy 91.565234 -272.466308) (xy 91.246706 -272.466308) (xy 91.246194 -272.491754)
			(xy 91.23803 -272.541988) (xy 91.221914 -272.590262) (xy 91.198263 -272.635325) (xy 91.16769 -272.676011)
			(xy 91.130986 -272.711266) (xy 91.089102 -272.740176) (xy 91.043123 -272.761993) (xy 90.994239 -272.776153)
			(xy 90.943718 -272.782287) (xy 90.892866 -272.780238) (xy 90.843002 -272.770058) (xy 90.795416 -272.752011)
			(xy 90.751342 -272.726565) (xy 90.71192 -272.694378) (xy 90.678172 -272.656284) (xy 90.650971 -272.61327)
			(xy 90.631023 -272.56645) (xy 90.618844 -272.517036) (xy 90.614749 -272.466308) (xy 90.296238 -272.466308)
			(xy 90.295743 -272.490915) (xy 90.287848 -272.539492) (xy 90.272264 -272.586173) (xy 90.249393 -272.62975)
			(xy 90.219828 -272.669094) (xy 90.184335 -272.703186) (xy 90.143832 -272.731142) (xy 90.09937 -272.75224)
			(xy 90.052099 -272.765932) (xy 90.003244 -272.771864) (xy 89.954069 -272.769883) (xy 89.90585 -272.760039)
			(xy 89.859834 -272.742587) (xy 89.817213 -272.71798) (xy 89.779092 -272.686855) (xy 89.746457 -272.650018)
			(xy 89.720154 -272.608422) (xy 89.700863 -272.563146) (xy 89.689086 -272.515362) (xy 89.685126 -272.466308)
			(xy 89.356438 -272.466308) (xy 89.355943 -272.490915) (xy 89.348048 -272.539492) (xy 89.332464 -272.586173)
			(xy 89.309593 -272.62975) (xy 89.280028 -272.669094) (xy 89.244535 -272.703186) (xy 89.204032 -272.731142)
			(xy 89.15957 -272.75224) (xy 89.112299 -272.765932) (xy 89.063444 -272.771864) (xy 89.014269 -272.769883)
			(xy 88.96605 -272.760039) (xy 88.920034 -272.742587) (xy 88.877413 -272.71798) (xy 88.839292 -272.686855)
			(xy 88.806657 -272.650018) (xy 88.780354 -272.608422) (xy 88.761063 -272.563146) (xy 88.749286 -272.515362)
			(xy 88.745326 -272.466308) (xy 88.416384 -272.466308) (xy 88.415889 -272.490915) (xy 88.407994 -272.539492)
			(xy 88.39241 -272.586173) (xy 88.369539 -272.62975) (xy 88.339974 -272.669094) (xy 88.304481 -272.703186)
			(xy 88.263978 -272.731142) (xy 88.219516 -272.75224) (xy 88.172245 -272.765932) (xy 88.12339 -272.771864)
			(xy 88.074215 -272.769883) (xy 88.025996 -272.760039) (xy 87.97998 -272.742587) (xy 87.937359 -272.71798)
			(xy 87.899238 -272.686855) (xy 87.866603 -272.650018) (xy 87.8403 -272.608422) (xy 87.821009 -272.563146)
			(xy 87.809232 -272.515362) (xy 87.805272 -272.466308) (xy 87.47633 -272.466308) (xy 87.475835 -272.490915)
			(xy 87.46794 -272.539492) (xy 87.452356 -272.586173) (xy 87.429485 -272.62975) (xy 87.39992 -272.669094)
			(xy 87.364427 -272.703186) (xy 87.323924 -272.731142) (xy 87.279462 -272.75224) (xy 87.232191 -272.765932)
			(xy 87.183336 -272.771864) (xy 87.134161 -272.769883) (xy 87.085942 -272.760039) (xy 87.039926 -272.742587)
			(xy 86.997305 -272.71798) (xy 86.959184 -272.686855) (xy 86.926549 -272.650018) (xy 86.900246 -272.608422)
			(xy 86.880955 -272.563146) (xy 86.869178 -272.515362) (xy 86.865218 -272.466308) (xy 86.536276 -272.466308)
			(xy 86.535781 -272.490915) (xy 86.527886 -272.539492) (xy 86.512302 -272.586173) (xy 86.489431 -272.62975)
			(xy 86.459866 -272.669094) (xy 86.424373 -272.703186) (xy 86.38387 -272.731142) (xy 86.339408 -272.75224)
			(xy 86.292137 -272.765932) (xy 86.243282 -272.771864) (xy 86.194107 -272.769883) (xy 86.145888 -272.760039)
			(xy 86.099872 -272.742587) (xy 86.057251 -272.71798) (xy 86.01913 -272.686855) (xy 85.986495 -272.650018)
			(xy 85.960192 -272.608422) (xy 85.940901 -272.563146) (xy 85.929124 -272.515362) (xy 85.925164 -272.466308)
			(xy 85.596222 -272.466308) (xy 85.595727 -272.490915) (xy 85.587832 -272.539492) (xy 85.572248 -272.586173)
			(xy 85.549377 -272.62975) (xy 85.519812 -272.669094) (xy 85.484319 -272.703186) (xy 85.443816 -272.731142)
			(xy 85.399354 -272.75224) (xy 85.352083 -272.765932) (xy 85.303228 -272.771864) (xy 85.254053 -272.769883)
			(xy 85.205834 -272.760039) (xy 85.159818 -272.742587) (xy 85.117197 -272.71798) (xy 85.079076 -272.686855)
			(xy 85.046441 -272.650018) (xy 85.020138 -272.608422) (xy 85.000847 -272.563146) (xy 84.98907 -272.515362)
			(xy 84.98511 -272.466308) (xy 84.656422 -272.466308) (xy 84.655927 -272.490915) (xy 84.648032 -272.539492)
			(xy 84.632448 -272.586173) (xy 84.609577 -272.62975) (xy 84.580012 -272.669094) (xy 84.544519 -272.703186)
			(xy 84.504016 -272.731142) (xy 84.459554 -272.75224) (xy 84.412283 -272.765932) (xy 84.363428 -272.771864)
			(xy 84.314253 -272.769883) (xy 84.266034 -272.760039) (xy 84.220018 -272.742587) (xy 84.177397 -272.71798)
			(xy 84.139276 -272.686855) (xy 84.106641 -272.650018) (xy 84.080338 -272.608422) (xy 84.061047 -272.563146)
			(xy 84.04927 -272.515362) (xy 84.04531 -272.466308) (xy 83.716368 -272.466308) (xy 83.716368 -272.47215)
			(xy 83.715353 -272.497843) (xy 83.705785 -272.548359) (xy 83.687889 -272.596558) (xy 83.662169 -272.641078)
			(xy 83.629354 -272.680658) (xy 83.590371 -272.714181) (xy 83.546322 -272.740699) (xy 83.522566 -272.750534)
			(xy 83.512152 -272.754852) (xy 83.503516 -272.767552) (xy 83.499482 -272.773957) (xy 83.495081 -272.788433)
			(xy 83.49488 -272.796) (xy 83.49488 -272.918428) (xy 83.49514 -272.924037) (xy 83.497832 -272.934934)
			(xy 83.500214 -272.940018) (xy 83.504786 -272.947892) (xy 83.508733 -272.952751) (xy 83.518488 -272.960592)
			(xy 83.52409 -272.963386) (xy 83.524344 -272.96364) (xy 83.605116 -273.000978) (xy 83.618832 -273.00428)
			(xy 83.631278 -273.004788) (xy 83.648042 -272.998438) (xy 83.6549 -272.995136) (xy 83.665314 -272.989294)
			(xy 83.6676 -272.987516) (xy 83.668616 -272.986754) (xy 83.66887 -272.9865) (xy 83.689158 -272.971428)
			(xy 83.73364 -272.947441) (xy 83.781456 -272.931078) (xy 83.831307 -272.922782) (xy 83.856576 -272.922238)
			(xy 83.882414 -272.922786) (xy 83.933349 -272.931499) (xy 83.98209 -272.948664) (xy 84.027245 -272.973791)
			(xy 84.067525 -273.006162) (xy 84.10178 -273.044853) (xy 84.129031 -273.088759) (xy 84.139278 -273.112484)
			(xy 84.142834 -273.119088) (xy 84.143088 -273.119596) (xy 84.156624 -273.143475) (xy 84.175891 -273.194867)
			(xy 84.18568 -273.248872) (xy 84.186268 -273.276314) (xy 84.51521 -273.276314) (xy 84.51917 -273.22726)
			(xy 84.530947 -273.179476) (xy 84.550238 -273.1342) (xy 84.576541 -273.092604) (xy 84.609176 -273.055767)
			(xy 84.647297 -273.024642) (xy 84.689918 -273.000035) (xy 84.735934 -272.982583) (xy 84.784153 -272.972739)
			(xy 84.833328 -272.970758) (xy 84.882183 -272.97669) (xy 84.929454 -272.990382) (xy 84.973916 -273.01148)
			(xy 85.014419 -273.039436) (xy 85.049912 -273.073528) (xy 85.079477 -273.112872) (xy 85.102348 -273.156449)
			(xy 85.117932 -273.20313) (xy 85.125827 -273.251707) (xy 85.126322 -273.276314) (xy 85.455264 -273.276314)
			(xy 85.459224 -273.22726) (xy 85.471001 -273.179476) (xy 85.490292 -273.1342) (xy 85.516595 -273.092604)
			(xy 85.54923 -273.055767) (xy 85.587351 -273.024642) (xy 85.629972 -273.000035) (xy 85.675988 -272.982583)
			(xy 85.724207 -272.972739) (xy 85.773382 -272.970758) (xy 85.822237 -272.97669) (xy 85.869508 -272.990382)
			(xy 85.91397 -273.01148) (xy 85.954473 -273.039436) (xy 85.989966 -273.073528) (xy 86.019531 -273.112872)
			(xy 86.042402 -273.156449) (xy 86.057986 -273.20313) (xy 86.065881 -273.251707) (xy 86.066376 -273.276314)
			(xy 87.335118 -273.276314) (xy 87.339078 -273.22726) (xy 87.350855 -273.179476) (xy 87.370146 -273.1342)
			(xy 87.396449 -273.092604) (xy 87.429084 -273.055767) (xy 87.467205 -273.024642) (xy 87.509826 -273.000035)
			(xy 87.555842 -272.982583) (xy 87.604061 -272.972739) (xy 87.653236 -272.970758) (xy 87.702091 -272.97669)
			(xy 87.749362 -272.990382) (xy 87.793824 -273.01148) (xy 87.834327 -273.039436) (xy 87.86982 -273.073528)
			(xy 87.899385 -273.112872) (xy 87.922256 -273.156449) (xy 87.93784 -273.20313) (xy 87.945735 -273.251707)
			(xy 87.94623 -273.276314) (xy 88.275172 -273.276314) (xy 88.279132 -273.22726) (xy 88.290909 -273.179476)
			(xy 88.3102 -273.1342) (xy 88.336503 -273.092604) (xy 88.369138 -273.055767) (xy 88.407259 -273.024642)
			(xy 88.44988 -273.000035) (xy 88.495896 -272.982583) (xy 88.544115 -272.972739) (xy 88.59329 -272.970758)
			(xy 88.642145 -272.97669) (xy 88.689416 -272.990382) (xy 88.733878 -273.01148) (xy 88.774381 -273.039436)
			(xy 88.809874 -273.073528) (xy 88.839439 -273.112872) (xy 88.86231 -273.156449) (xy 88.877894 -273.20313)
			(xy 88.885789 -273.251707) (xy 88.886284 -273.276314) (xy 89.215226 -273.276314) (xy 89.219186 -273.22726)
			(xy 89.230963 -273.179476) (xy 89.250254 -273.1342) (xy 89.276557 -273.092604) (xy 89.309192 -273.055767)
			(xy 89.347313 -273.024642) (xy 89.389934 -273.000035) (xy 89.43595 -272.982583) (xy 89.484169 -272.972739)
			(xy 89.533344 -272.970758) (xy 89.582199 -272.97669) (xy 89.62947 -272.990382) (xy 89.673932 -273.01148)
			(xy 89.714435 -273.039436) (xy 89.749928 -273.073528) (xy 89.779493 -273.112872) (xy 89.802364 -273.156449)
			(xy 89.817948 -273.20313) (xy 89.825843 -273.251707) (xy 89.826338 -273.276314) (xy 90.15528 -273.276314)
			(xy 90.15924 -273.22726) (xy 90.171017 -273.179476) (xy 90.190308 -273.1342) (xy 90.216611 -273.092604)
			(xy 90.249246 -273.055767) (xy 90.287367 -273.024642) (xy 90.329988 -273.000035) (xy 90.376004 -272.982583)
			(xy 90.424223 -272.972739) (xy 90.473398 -272.970758) (xy 90.522253 -272.97669) (xy 90.569524 -272.990382)
			(xy 90.613986 -273.01148) (xy 90.654489 -273.039436) (xy 90.689982 -273.073528) (xy 90.719547 -273.112872)
			(xy 90.742418 -273.156449) (xy 90.758002 -273.20313) (xy 90.765897 -273.251707) (xy 90.766392 -273.276314)
			(xy 91.084903 -273.276314) (xy 91.088998 -273.225586) (xy 91.101177 -273.176172) (xy 91.121125 -273.129352)
			(xy 91.148326 -273.086338) (xy 91.182074 -273.048244) (xy 91.221496 -273.016057) (xy 91.26557 -272.990611)
			(xy 91.313156 -272.972564) (xy 91.36302 -272.962384) (xy 91.413872 -272.960335) (xy 91.464393 -272.966469)
			(xy 91.513277 -272.980629) (xy 91.559256 -273.002446) (xy 91.60114 -273.031356) (xy 91.637844 -273.066611)
			(xy 91.668417 -273.107297) (xy 91.692068 -273.15236) (xy 91.708184 -273.200634) (xy 91.716348 -273.250868)
			(xy 91.71686 -273.276314) (xy 92.024703 -273.276314) (xy 92.028798 -273.225586) (xy 92.040977 -273.176172)
			(xy 92.060925 -273.129352) (xy 92.088126 -273.086338) (xy 92.121874 -273.048244) (xy 92.161296 -273.016057)
			(xy 92.20537 -272.990611) (xy 92.252956 -272.972564) (xy 92.30282 -272.962384) (xy 92.353672 -272.960335)
			(xy 92.404193 -272.966469) (xy 92.453077 -272.980629) (xy 92.499056 -273.002446) (xy 92.54094 -273.031356)
			(xy 92.577644 -273.066611) (xy 92.608217 -273.107297) (xy 92.631868 -273.15236) (xy 92.647984 -273.200634)
			(xy 92.656148 -273.250868) (xy 92.65666 -273.276314) (xy 93.904811 -273.276314) (xy 93.908906 -273.225586)
			(xy 93.921085 -273.176172) (xy 93.941033 -273.129352) (xy 93.968234 -273.086338) (xy 94.001982 -273.048244)
			(xy 94.041404 -273.016057) (xy 94.085478 -272.990611) (xy 94.133064 -272.972564) (xy 94.182928 -272.962384)
			(xy 94.23378 -272.960335) (xy 94.284301 -272.966469) (xy 94.333185 -272.980629) (xy 94.379164 -273.002446)
			(xy 94.421048 -273.031356) (xy 94.457752 -273.066611) (xy 94.488325 -273.107297) (xy 94.511976 -273.15236)
			(xy 94.528092 -273.200634) (xy 94.536256 -273.250868) (xy 94.536768 -273.276314) (xy 94.855296 -273.276314)
			(xy 94.859256 -273.22726) (xy 94.871033 -273.179476) (xy 94.890324 -273.1342) (xy 94.916627 -273.092604)
			(xy 94.949262 -273.055767) (xy 94.987383 -273.024642) (xy 95.030004 -273.000035) (xy 95.07602 -272.982583)
			(xy 95.124239 -272.972739) (xy 95.173414 -272.970758) (xy 95.222269 -272.97669) (xy 95.26954 -272.990382)
			(xy 95.314002 -273.01148) (xy 95.354505 -273.039436) (xy 95.389998 -273.073528) (xy 95.419563 -273.112872)
			(xy 95.442434 -273.156449) (xy 95.458018 -273.20313) (xy 95.465913 -273.251707) (xy 95.466408 -273.276314)
			(xy 95.784919 -273.276314) (xy 95.789014 -273.225586) (xy 95.801193 -273.176172) (xy 95.821141 -273.129352)
			(xy 95.848342 -273.086338) (xy 95.88209 -273.048244) (xy 95.921512 -273.016057) (xy 95.965586 -272.990611)
			(xy 96.013172 -272.972564) (xy 96.063036 -272.962384) (xy 96.113888 -272.960335) (xy 96.164409 -272.966469)
			(xy 96.213293 -272.980629) (xy 96.259272 -273.002446) (xy 96.301156 -273.031356) (xy 96.33786 -273.066611)
			(xy 96.368433 -273.107297) (xy 96.392084 -273.15236) (xy 96.4082 -273.200634) (xy 96.416364 -273.250868)
			(xy 96.416876 -273.276314) (xy 96.416364 -273.30176) (xy 96.4082 -273.351994) (xy 96.392084 -273.400268)
			(xy 96.368433 -273.445331) (xy 96.33786 -273.486017) (xy 96.301156 -273.521272) (xy 96.259272 -273.550182)
			(xy 96.213293 -273.571999) (xy 96.164409 -273.586159) (xy 96.113888 -273.592293) (xy 96.063036 -273.590244)
			(xy 96.013172 -273.580064) (xy 95.965586 -273.562017) (xy 95.921512 -273.536571) (xy 95.88209 -273.504384)
			(xy 95.848342 -273.46629) (xy 95.821141 -273.423276) (xy 95.801193 -273.376456) (xy 95.789014 -273.327042)
			(xy 95.784919 -273.276314) (xy 95.466408 -273.276314) (xy 95.465913 -273.300921) (xy 95.458018 -273.349498)
			(xy 95.442434 -273.396179) (xy 95.419563 -273.439756) (xy 95.389998 -273.4791) (xy 95.354505 -273.513192)
			(xy 95.314002 -273.541148) (xy 95.26954 -273.562246) (xy 95.222269 -273.575938) (xy 95.173414 -273.58187)
			(xy 95.124239 -273.579889) (xy 95.07602 -273.570045) (xy 95.030004 -273.552593) (xy 94.987383 -273.527986)
			(xy 94.949262 -273.496861) (xy 94.916627 -273.460024) (xy 94.890324 -273.418428) (xy 94.871033 -273.373152)
			(xy 94.859256 -273.325368) (xy 94.855296 -273.276314) (xy 94.536768 -273.276314) (xy 94.536256 -273.30176)
			(xy 94.528092 -273.351994) (xy 94.511976 -273.400268) (xy 94.488325 -273.445331) (xy 94.457752 -273.486017)
			(xy 94.421048 -273.521272) (xy 94.379164 -273.550182) (xy 94.333185 -273.571999) (xy 94.284301 -273.586159)
			(xy 94.23378 -273.592293) (xy 94.182928 -273.590244) (xy 94.133064 -273.580064) (xy 94.085478 -273.562017)
			(xy 94.041404 -273.536571) (xy 94.001982 -273.504384) (xy 93.968234 -273.46629) (xy 93.941033 -273.423276)
			(xy 93.921085 -273.376456) (xy 93.908906 -273.327042) (xy 93.904811 -273.276314) (xy 92.65666 -273.276314)
			(xy 92.656148 -273.30176) (xy 92.647984 -273.351994) (xy 92.631868 -273.400268) (xy 92.608217 -273.445331)
			(xy 92.577644 -273.486017) (xy 92.54094 -273.521272) (xy 92.499056 -273.550182) (xy 92.453077 -273.571999)
			(xy 92.404193 -273.586159) (xy 92.353672 -273.592293) (xy 92.30282 -273.590244) (xy 92.252956 -273.580064)
			(xy 92.20537 -273.562017) (xy 92.161296 -273.536571) (xy 92.121874 -273.504384) (xy 92.088126 -273.46629)
			(xy 92.060925 -273.423276) (xy 92.040977 -273.376456) (xy 92.028798 -273.327042) (xy 92.024703 -273.276314)
			(xy 91.71686 -273.276314) (xy 91.716348 -273.30176) (xy 91.708184 -273.351994) (xy 91.692068 -273.400268)
			(xy 91.668417 -273.445331) (xy 91.637844 -273.486017) (xy 91.60114 -273.521272) (xy 91.559256 -273.550182)
			(xy 91.513277 -273.571999) (xy 91.464393 -273.586159) (xy 91.413872 -273.592293) (xy 91.36302 -273.590244)
			(xy 91.313156 -273.580064) (xy 91.26557 -273.562017) (xy 91.221496 -273.536571) (xy 91.182074 -273.504384)
			(xy 91.148326 -273.46629) (xy 91.121125 -273.423276) (xy 91.101177 -273.376456) (xy 91.088998 -273.327042)
			(xy 91.084903 -273.276314) (xy 90.766392 -273.276314) (xy 90.765897 -273.300921) (xy 90.758002 -273.349498)
			(xy 90.742418 -273.396179) (xy 90.719547 -273.439756) (xy 90.689982 -273.4791) (xy 90.654489 -273.513192)
			(xy 90.613986 -273.541148) (xy 90.569524 -273.562246) (xy 90.522253 -273.575938) (xy 90.473398 -273.58187)
			(xy 90.424223 -273.579889) (xy 90.376004 -273.570045) (xy 90.329988 -273.552593) (xy 90.287367 -273.527986)
			(xy 90.249246 -273.496861) (xy 90.216611 -273.460024) (xy 90.190308 -273.418428) (xy 90.171017 -273.373152)
			(xy 90.15924 -273.325368) (xy 90.15528 -273.276314) (xy 89.826338 -273.276314) (xy 89.825843 -273.300921)
			(xy 89.817948 -273.349498) (xy 89.802364 -273.396179) (xy 89.779493 -273.439756) (xy 89.749928 -273.4791)
			(xy 89.714435 -273.513192) (xy 89.673932 -273.541148) (xy 89.62947 -273.562246) (xy 89.582199 -273.575938)
			(xy 89.533344 -273.58187) (xy 89.484169 -273.579889) (xy 89.43595 -273.570045) (xy 89.389934 -273.552593)
			(xy 89.347313 -273.527986) (xy 89.309192 -273.496861) (xy 89.276557 -273.460024) (xy 89.250254 -273.418428)
			(xy 89.230963 -273.373152) (xy 89.219186 -273.325368) (xy 89.215226 -273.276314) (xy 88.886284 -273.276314)
			(xy 88.885789 -273.300921) (xy 88.877894 -273.349498) (xy 88.86231 -273.396179) (xy 88.839439 -273.439756)
			(xy 88.809874 -273.4791) (xy 88.774381 -273.513192) (xy 88.733878 -273.541148) (xy 88.689416 -273.562246)
			(xy 88.642145 -273.575938) (xy 88.59329 -273.58187) (xy 88.544115 -273.579889) (xy 88.495896 -273.570045)
			(xy 88.44988 -273.552593) (xy 88.407259 -273.527986) (xy 88.369138 -273.496861) (xy 88.336503 -273.460024)
			(xy 88.3102 -273.418428) (xy 88.290909 -273.373152) (xy 88.279132 -273.325368) (xy 88.275172 -273.276314)
			(xy 87.94623 -273.276314) (xy 87.945735 -273.300921) (xy 87.93784 -273.349498) (xy 87.922256 -273.396179)
			(xy 87.899385 -273.439756) (xy 87.86982 -273.4791) (xy 87.834327 -273.513192) (xy 87.793824 -273.541148)
			(xy 87.749362 -273.562246) (xy 87.702091 -273.575938) (xy 87.653236 -273.58187) (xy 87.604061 -273.579889)
			(xy 87.555842 -273.570045) (xy 87.509826 -273.552593) (xy 87.467205 -273.527986) (xy 87.429084 -273.496861)
			(xy 87.396449 -273.460024) (xy 87.370146 -273.418428) (xy 87.350855 -273.373152) (xy 87.339078 -273.325368)
			(xy 87.335118 -273.276314) (xy 86.066376 -273.276314) (xy 86.065881 -273.300921) (xy 86.057986 -273.349498)
			(xy 86.042402 -273.396179) (xy 86.019531 -273.439756) (xy 85.989966 -273.4791) (xy 85.954473 -273.513192)
			(xy 85.91397 -273.541148) (xy 85.869508 -273.562246) (xy 85.822237 -273.575938) (xy 85.773382 -273.58187)
			(xy 85.724207 -273.579889) (xy 85.675988 -273.570045) (xy 85.629972 -273.552593) (xy 85.587351 -273.527986)
			(xy 85.54923 -273.496861) (xy 85.516595 -273.460024) (xy 85.490292 -273.418428) (xy 85.471001 -273.373152)
			(xy 85.459224 -273.325368) (xy 85.455264 -273.276314) (xy 85.126322 -273.276314) (xy 85.125827 -273.300921)
			(xy 85.117932 -273.349498) (xy 85.102348 -273.396179) (xy 85.079477 -273.439756) (xy 85.049912 -273.4791)
			(xy 85.014419 -273.513192) (xy 84.973916 -273.541148) (xy 84.929454 -273.562246) (xy 84.882183 -273.575938)
			(xy 84.833328 -273.58187) (xy 84.784153 -273.579889) (xy 84.735934 -273.570045) (xy 84.689918 -273.552593)
			(xy 84.647297 -273.527986) (xy 84.609176 -273.496861) (xy 84.576541 -273.460024) (xy 84.550238 -273.418428)
			(xy 84.530947 -273.373152) (xy 84.51917 -273.325368) (xy 84.51521 -273.276314) (xy 84.186268 -273.276314)
			(xy 84.185821 -273.300305) (xy 84.178312 -273.347697) (xy 84.163482 -273.39333) (xy 84.141695 -273.436081)
			(xy 84.113488 -273.474898) (xy 84.079557 -273.508824) (xy 84.040735 -273.537023) (xy 83.99798 -273.558802)
			(xy 83.952344 -273.573625) (xy 83.904951 -273.581125) (xy 83.88096 -273.581622) (xy 83.854569 -273.581071)
			(xy 83.802572 -273.572011) (xy 83.752905 -273.554151) (xy 83.707046 -273.528021) (xy 83.666359 -273.4944)
			(xy 83.648804 -273.474688) (xy 83.627468 -273.449542) (xy 83.62569 -273.449542) (xy 83.621481 -273.449624)
			(xy 83.613182 -273.45103) (xy 83.60918 -273.452336) (xy 83.521804 -273.492722) (xy 83.514027 -273.497256)
			(xy 83.502048 -273.510679) (xy 83.495474 -273.527425) (xy 83.49488 -273.53641) (xy 83.49488 -273.70532)
			(xy 83.494915 -273.709456) (xy 83.496196 -273.717626) (xy 83.49742 -273.721576) (xy 83.502246 -273.731736)
			(xy 83.515708 -273.752818) (xy 83.519209 -273.75808) (xy 83.528333 -273.76682) (xy 83.533742 -273.77009)
			(xy 83.533996 -273.77009) (xy 83.555756 -273.78267) (xy 83.595202 -273.813814) (xy 83.612482 -273.832066)
			(xy 83.630125 -273.852264) (xy 83.658741 -273.897617) (xy 83.669378 -273.922236) (xy 83.672934 -273.92884)
			(xy 83.673188 -273.929348) (xy 83.686702 -273.95319) (xy 83.705944 -274.004498) (xy 83.715739 -274.058414)
			(xy 83.716368 -274.085812) (xy 83.716368 -274.08632) (xy 84.04531 -274.08632) (xy 84.04927 -274.037266)
			(xy 84.061047 -273.989482) (xy 84.080338 -273.944206) (xy 84.106641 -273.90261) (xy 84.139276 -273.865773)
			(xy 84.177397 -273.834648) (xy 84.220018 -273.810041) (xy 84.266034 -273.792589) (xy 84.314253 -273.782745)
			(xy 84.363428 -273.780764) (xy 84.412283 -273.786696) (xy 84.459554 -273.800388) (xy 84.504016 -273.821486)
			(xy 84.544519 -273.849442) (xy 84.580012 -273.883534) (xy 84.609577 -273.922878) (xy 84.632448 -273.966455)
			(xy 84.648032 -274.013136) (xy 84.655927 -274.061713) (xy 84.656422 -274.08632) (xy 84.98511 -274.08632)
			(xy 84.98907 -274.037266) (xy 85.000847 -273.989482) (xy 85.020138 -273.944206) (xy 85.046441 -273.90261)
			(xy 85.079076 -273.865773) (xy 85.117197 -273.834648) (xy 85.159818 -273.810041) (xy 85.205834 -273.792589)
			(xy 85.254053 -273.782745) (xy 85.303228 -273.780764) (xy 85.352083 -273.786696) (xy 85.399354 -273.800388)
			(xy 85.443816 -273.821486) (xy 85.484319 -273.849442) (xy 85.519812 -273.883534) (xy 85.549377 -273.922878)
			(xy 85.572248 -273.966455) (xy 85.587832 -274.013136) (xy 85.595727 -274.061713) (xy 85.596222 -274.08632)
			(xy 85.925164 -274.08632) (xy 85.929124 -274.037266) (xy 85.940901 -273.989482) (xy 85.960192 -273.944206)
			(xy 85.986495 -273.90261) (xy 86.01913 -273.865773) (xy 86.057251 -273.834648) (xy 86.099872 -273.810041)
			(xy 86.145888 -273.792589) (xy 86.194107 -273.782745) (xy 86.243282 -273.780764) (xy 86.292137 -273.786696)
			(xy 86.339408 -273.800388) (xy 86.38387 -273.821486) (xy 86.424373 -273.849442) (xy 86.459866 -273.883534)
			(xy 86.489431 -273.922878) (xy 86.512302 -273.966455) (xy 86.527886 -274.013136) (xy 86.535781 -274.061713)
			(xy 86.536276 -274.08632) (xy 86.865218 -274.08632) (xy 86.869178 -274.037266) (xy 86.880955 -273.989482)
			(xy 86.900246 -273.944206) (xy 86.926549 -273.90261) (xy 86.959184 -273.865773) (xy 86.997305 -273.834648)
			(xy 87.039926 -273.810041) (xy 87.085942 -273.792589) (xy 87.134161 -273.782745) (xy 87.183336 -273.780764)
			(xy 87.232191 -273.786696) (xy 87.279462 -273.800388) (xy 87.323924 -273.821486) (xy 87.364427 -273.849442)
			(xy 87.39992 -273.883534) (xy 87.429485 -273.922878) (xy 87.452356 -273.966455) (xy 87.46794 -274.013136)
			(xy 87.475835 -274.061713) (xy 87.47633 -274.08632) (xy 87.805272 -274.08632) (xy 87.809232 -274.037266)
			(xy 87.821009 -273.989482) (xy 87.8403 -273.944206) (xy 87.866603 -273.90261) (xy 87.899238 -273.865773)
			(xy 87.937359 -273.834648) (xy 87.97998 -273.810041) (xy 88.025996 -273.792589) (xy 88.074215 -273.782745)
			(xy 88.12339 -273.780764) (xy 88.172245 -273.786696) (xy 88.219516 -273.800388) (xy 88.263978 -273.821486)
			(xy 88.304481 -273.849442) (xy 88.339974 -273.883534) (xy 88.369539 -273.922878) (xy 88.39241 -273.966455)
			(xy 88.407994 -274.013136) (xy 88.415889 -274.061713) (xy 88.416384 -274.08632) (xy 88.745326 -274.08632)
			(xy 88.749286 -274.037266) (xy 88.761063 -273.989482) (xy 88.780354 -273.944206) (xy 88.806657 -273.90261)
			(xy 88.839292 -273.865773) (xy 88.877413 -273.834648) (xy 88.920034 -273.810041) (xy 88.96605 -273.792589)
			(xy 89.014269 -273.782745) (xy 89.063444 -273.780764) (xy 89.112299 -273.786696) (xy 89.15957 -273.800388)
			(xy 89.204032 -273.821486) (xy 89.244535 -273.849442) (xy 89.280028 -273.883534) (xy 89.309593 -273.922878)
			(xy 89.332464 -273.966455) (xy 89.348048 -274.013136) (xy 89.355943 -274.061713) (xy 89.356438 -274.08632)
			(xy 89.685126 -274.08632) (xy 89.689086 -274.037266) (xy 89.700863 -273.989482) (xy 89.720154 -273.944206)
			(xy 89.746457 -273.90261) (xy 89.779092 -273.865773) (xy 89.817213 -273.834648) (xy 89.859834 -273.810041)
			(xy 89.90585 -273.792589) (xy 89.954069 -273.782745) (xy 90.003244 -273.780764) (xy 90.052099 -273.786696)
			(xy 90.09937 -273.800388) (xy 90.143832 -273.821486) (xy 90.184335 -273.849442) (xy 90.219828 -273.883534)
			(xy 90.249393 -273.922878) (xy 90.272264 -273.966455) (xy 90.287848 -274.013136) (xy 90.295743 -274.061713)
			(xy 90.296238 -274.08632) (xy 90.614749 -274.08632) (xy 90.618844 -274.035592) (xy 90.631023 -273.986178)
			(xy 90.650971 -273.939358) (xy 90.678172 -273.896344) (xy 90.71192 -273.85825) (xy 90.751342 -273.826063)
			(xy 90.795416 -273.800617) (xy 90.843002 -273.78257) (xy 90.892866 -273.77239) (xy 90.943718 -273.770341)
			(xy 90.994239 -273.776475) (xy 91.043123 -273.790635) (xy 91.089102 -273.812452) (xy 91.130986 -273.841362)
			(xy 91.16769 -273.876617) (xy 91.198263 -273.917303) (xy 91.221914 -273.962366) (xy 91.23803 -274.01064)
			(xy 91.246194 -274.060874) (xy 91.246706 -274.08632) (xy 91.565234 -274.08632) (xy 91.569194 -274.037266)
			(xy 91.580971 -273.989482) (xy 91.600262 -273.944206) (xy 91.626565 -273.90261) (xy 91.6592 -273.865773)
			(xy 91.697321 -273.834648) (xy 91.739942 -273.810041) (xy 91.785958 -273.792589) (xy 91.834177 -273.782745)
			(xy 91.883352 -273.780764) (xy 91.932207 -273.786696) (xy 91.979478 -273.800388) (xy 92.02394 -273.821486)
			(xy 92.064443 -273.849442) (xy 92.099936 -273.883534) (xy 92.129501 -273.922878) (xy 92.152372 -273.966455)
			(xy 92.167956 -274.013136) (xy 92.175851 -274.061713) (xy 92.176346 -274.08632) (xy 92.494857 -274.08632)
			(xy 92.498952 -274.035592) (xy 92.511131 -273.986178) (xy 92.531079 -273.939358) (xy 92.55828 -273.896344)
			(xy 92.592028 -273.85825) (xy 92.63145 -273.826063) (xy 92.675524 -273.800617) (xy 92.72311 -273.78257)
			(xy 92.772974 -273.77239) (xy 92.823826 -273.770341) (xy 92.874347 -273.776475) (xy 92.923231 -273.790635)
			(xy 92.96921 -273.812452) (xy 93.011094 -273.841362) (xy 93.047798 -273.876617) (xy 93.078371 -273.917303)
			(xy 93.102022 -273.962366) (xy 93.118138 -274.01064) (xy 93.126302 -274.060874) (xy 93.126814 -274.08632)
			(xy 93.445342 -274.08632) (xy 93.449302 -274.037266) (xy 93.461079 -273.989482) (xy 93.48037 -273.944206)
			(xy 93.506673 -273.90261) (xy 93.539308 -273.865773) (xy 93.577429 -273.834648) (xy 93.62005 -273.810041)
			(xy 93.666066 -273.792589) (xy 93.714285 -273.782745) (xy 93.76346 -273.780764) (xy 93.812315 -273.786696)
			(xy 93.859586 -273.800388) (xy 93.904048 -273.821486) (xy 93.944551 -273.849442) (xy 93.980044 -273.883534)
			(xy 94.009609 -273.922878) (xy 94.03248 -273.966455) (xy 94.048064 -274.013136) (xy 94.055959 -274.061713)
			(xy 94.056454 -274.08632) (xy 94.374711 -274.08632) (xy 94.378806 -274.035592) (xy 94.390985 -273.986178)
			(xy 94.410933 -273.939358) (xy 94.438134 -273.896344) (xy 94.471882 -273.85825) (xy 94.511304 -273.826063)
			(xy 94.555378 -273.800617) (xy 94.602964 -273.78257) (xy 94.652828 -273.77239) (xy 94.70368 -273.770341)
			(xy 94.754201 -273.776475) (xy 94.803085 -273.790635) (xy 94.849064 -273.812452) (xy 94.890948 -273.841362)
			(xy 94.927652 -273.876617) (xy 94.958225 -273.917303) (xy 94.981876 -273.962366) (xy 94.997992 -274.01064)
			(xy 95.006156 -274.060874) (xy 95.006668 -274.08632) (xy 95.314765 -274.08632) (xy 95.31886 -274.035592)
			(xy 95.331039 -273.986178) (xy 95.350987 -273.939358) (xy 95.378188 -273.896344) (xy 95.411936 -273.85825)
			(xy 95.451358 -273.826063) (xy 95.495432 -273.800617) (xy 95.543018 -273.78257) (xy 95.592882 -273.77239)
			(xy 95.643734 -273.770341) (xy 95.694255 -273.776475) (xy 95.743139 -273.790635) (xy 95.789118 -273.812452)
			(xy 95.831002 -273.841362) (xy 95.867706 -273.876617) (xy 95.898279 -273.917303) (xy 95.92193 -273.962366)
			(xy 95.938046 -274.01064) (xy 95.94621 -274.060874) (xy 95.946722 -274.08632) (xy 95.94621 -274.111766)
			(xy 95.938046 -274.162) (xy 95.92193 -274.210274) (xy 95.898279 -274.255337) (xy 95.867706 -274.296023)
			(xy 95.831002 -274.331278) (xy 95.789118 -274.360188) (xy 95.743139 -274.382005) (xy 95.694255 -274.396165)
			(xy 95.643734 -274.402299) (xy 95.592882 -274.40025) (xy 95.543018 -274.39007) (xy 95.495432 -274.372023)
			(xy 95.451358 -274.346577) (xy 95.411936 -274.31439) (xy 95.378188 -274.276296) (xy 95.350987 -274.233282)
			(xy 95.331039 -274.186462) (xy 95.31886 -274.137048) (xy 95.314765 -274.08632) (xy 95.006668 -274.08632)
			(xy 95.006156 -274.111766) (xy 94.997992 -274.162) (xy 94.981876 -274.210274) (xy 94.958225 -274.255337)
			(xy 94.927652 -274.296023) (xy 94.890948 -274.331278) (xy 94.849064 -274.360188) (xy 94.803085 -274.382005)
			(xy 94.754201 -274.396165) (xy 94.70368 -274.402299) (xy 94.652828 -274.40025) (xy 94.602964 -274.39007)
			(xy 94.555378 -274.372023) (xy 94.511304 -274.346577) (xy 94.471882 -274.31439) (xy 94.438134 -274.276296)
			(xy 94.410933 -274.233282) (xy 94.390985 -274.186462) (xy 94.378806 -274.137048) (xy 94.374711 -274.08632)
			(xy 94.056454 -274.08632) (xy 94.055959 -274.110927) (xy 94.048064 -274.159504) (xy 94.03248 -274.206185)
			(xy 94.009609 -274.249762) (xy 93.980044 -274.289106) (xy 93.944551 -274.323198) (xy 93.904048 -274.351154)
			(xy 93.859586 -274.372252) (xy 93.812315 -274.385944) (xy 93.76346 -274.391876) (xy 93.714285 -274.389895)
			(xy 93.666066 -274.380051) (xy 93.62005 -274.362599) (xy 93.577429 -274.337992) (xy 93.539308 -274.306867)
			(xy 93.506673 -274.27003) (xy 93.48037 -274.228434) (xy 93.461079 -274.183158) (xy 93.449302 -274.135374)
			(xy 93.445342 -274.08632) (xy 93.126814 -274.08632) (xy 93.126302 -274.111766) (xy 93.118138 -274.162)
			(xy 93.102022 -274.210274) (xy 93.078371 -274.255337) (xy 93.047798 -274.296023) (xy 93.011094 -274.331278)
			(xy 92.96921 -274.360188) (xy 92.923231 -274.382005) (xy 92.874347 -274.396165) (xy 92.823826 -274.402299)
			(xy 92.772974 -274.40025) (xy 92.72311 -274.39007) (xy 92.675524 -274.372023) (xy 92.63145 -274.346577)
			(xy 92.592028 -274.31439) (xy 92.55828 -274.276296) (xy 92.531079 -274.233282) (xy 92.511131 -274.186462)
			(xy 92.498952 -274.137048) (xy 92.494857 -274.08632) (xy 92.176346 -274.08632) (xy 92.175851 -274.110927)
			(xy 92.167956 -274.159504) (xy 92.152372 -274.206185) (xy 92.129501 -274.249762) (xy 92.099936 -274.289106)
			(xy 92.064443 -274.323198) (xy 92.02394 -274.351154) (xy 91.979478 -274.372252) (xy 91.932207 -274.385944)
			(xy 91.883352 -274.391876) (xy 91.834177 -274.389895) (xy 91.785958 -274.380051) (xy 91.739942 -274.362599)
			(xy 91.697321 -274.337992) (xy 91.6592 -274.306867) (xy 91.626565 -274.27003) (xy 91.600262 -274.228434)
			(xy 91.580971 -274.183158) (xy 91.569194 -274.135374) (xy 91.565234 -274.08632) (xy 91.246706 -274.08632)
			(xy 91.246194 -274.111766) (xy 91.23803 -274.162) (xy 91.221914 -274.210274) (xy 91.198263 -274.255337)
			(xy 91.16769 -274.296023) (xy 91.130986 -274.331278) (xy 91.089102 -274.360188) (xy 91.043123 -274.382005)
			(xy 90.994239 -274.396165) (xy 90.943718 -274.402299) (xy 90.892866 -274.40025) (xy 90.843002 -274.39007)
			(xy 90.795416 -274.372023) (xy 90.751342 -274.346577) (xy 90.71192 -274.31439) (xy 90.678172 -274.276296)
			(xy 90.650971 -274.233282) (xy 90.631023 -274.186462) (xy 90.618844 -274.137048) (xy 90.614749 -274.08632)
			(xy 90.296238 -274.08632) (xy 90.295743 -274.110927) (xy 90.287848 -274.159504) (xy 90.272264 -274.206185)
			(xy 90.249393 -274.249762) (xy 90.219828 -274.289106) (xy 90.184335 -274.323198) (xy 90.143832 -274.351154)
			(xy 90.09937 -274.372252) (xy 90.052099 -274.385944) (xy 90.003244 -274.391876) (xy 89.954069 -274.389895)
			(xy 89.90585 -274.380051) (xy 89.859834 -274.362599) (xy 89.817213 -274.337992) (xy 89.779092 -274.306867)
			(xy 89.746457 -274.27003) (xy 89.720154 -274.228434) (xy 89.700863 -274.183158) (xy 89.689086 -274.135374)
			(xy 89.685126 -274.08632) (xy 89.356438 -274.08632) (xy 89.355943 -274.110927) (xy 89.348048 -274.159504)
			(xy 89.332464 -274.206185) (xy 89.309593 -274.249762) (xy 89.280028 -274.289106) (xy 89.244535 -274.323198)
			(xy 89.204032 -274.351154) (xy 89.15957 -274.372252) (xy 89.112299 -274.385944) (xy 89.063444 -274.391876)
			(xy 89.014269 -274.389895) (xy 88.96605 -274.380051) (xy 88.920034 -274.362599) (xy 88.877413 -274.337992)
			(xy 88.839292 -274.306867) (xy 88.806657 -274.27003) (xy 88.780354 -274.228434) (xy 88.761063 -274.183158)
			(xy 88.749286 -274.135374) (xy 88.745326 -274.08632) (xy 88.416384 -274.08632) (xy 88.415889 -274.110927)
			(xy 88.407994 -274.159504) (xy 88.39241 -274.206185) (xy 88.369539 -274.249762) (xy 88.339974 -274.289106)
			(xy 88.304481 -274.323198) (xy 88.263978 -274.351154) (xy 88.219516 -274.372252) (xy 88.172245 -274.385944)
			(xy 88.12339 -274.391876) (xy 88.074215 -274.389895) (xy 88.025996 -274.380051) (xy 87.97998 -274.362599)
			(xy 87.937359 -274.337992) (xy 87.899238 -274.306867) (xy 87.866603 -274.27003) (xy 87.8403 -274.228434)
			(xy 87.821009 -274.183158) (xy 87.809232 -274.135374) (xy 87.805272 -274.08632) (xy 87.47633 -274.08632)
			(xy 87.475835 -274.110927) (xy 87.46794 -274.159504) (xy 87.452356 -274.206185) (xy 87.429485 -274.249762)
			(xy 87.39992 -274.289106) (xy 87.364427 -274.323198) (xy 87.323924 -274.351154) (xy 87.279462 -274.372252)
			(xy 87.232191 -274.385944) (xy 87.183336 -274.391876) (xy 87.134161 -274.389895) (xy 87.085942 -274.380051)
			(xy 87.039926 -274.362599) (xy 86.997305 -274.337992) (xy 86.959184 -274.306867) (xy 86.926549 -274.27003)
			(xy 86.900246 -274.228434) (xy 86.880955 -274.183158) (xy 86.869178 -274.135374) (xy 86.865218 -274.08632)
			(xy 86.536276 -274.08632) (xy 86.535781 -274.110927) (xy 86.527886 -274.159504) (xy 86.512302 -274.206185)
			(xy 86.489431 -274.249762) (xy 86.459866 -274.289106) (xy 86.424373 -274.323198) (xy 86.38387 -274.351154)
			(xy 86.339408 -274.372252) (xy 86.292137 -274.385944) (xy 86.243282 -274.391876) (xy 86.194107 -274.389895)
			(xy 86.145888 -274.380051) (xy 86.099872 -274.362599) (xy 86.057251 -274.337992) (xy 86.01913 -274.306867)
			(xy 85.986495 -274.27003) (xy 85.960192 -274.228434) (xy 85.940901 -274.183158) (xy 85.929124 -274.135374)
			(xy 85.925164 -274.08632) (xy 85.596222 -274.08632) (xy 85.595727 -274.110927) (xy 85.587832 -274.159504)
			(xy 85.572248 -274.206185) (xy 85.549377 -274.249762) (xy 85.519812 -274.289106) (xy 85.484319 -274.323198)
			(xy 85.443816 -274.351154) (xy 85.399354 -274.372252) (xy 85.352083 -274.385944) (xy 85.303228 -274.391876)
			(xy 85.254053 -274.389895) (xy 85.205834 -274.380051) (xy 85.159818 -274.362599) (xy 85.117197 -274.337992)
			(xy 85.079076 -274.306867) (xy 85.046441 -274.27003) (xy 85.020138 -274.228434) (xy 85.000847 -274.183158)
			(xy 84.98907 -274.135374) (xy 84.98511 -274.08632) (xy 84.656422 -274.08632) (xy 84.655927 -274.110927)
			(xy 84.648032 -274.159504) (xy 84.632448 -274.206185) (xy 84.609577 -274.249762) (xy 84.580012 -274.289106)
			(xy 84.544519 -274.323198) (xy 84.504016 -274.351154) (xy 84.459554 -274.372252) (xy 84.412283 -274.385944)
			(xy 84.363428 -274.391876) (xy 84.314253 -274.389895) (xy 84.266034 -274.380051) (xy 84.220018 -274.362599)
			(xy 84.177397 -274.337992) (xy 84.139276 -274.306867) (xy 84.106641 -274.27003) (xy 84.080338 -274.228434)
			(xy 84.061047 -274.183158) (xy 84.04927 -274.135374) (xy 84.04531 -274.08632) (xy 83.716368 -274.08632)
			(xy 83.716368 -274.092162) (xy 83.715352 -274.117854) (xy 83.705783 -274.168369) (xy 83.687885 -274.216567)
			(xy 83.662165 -274.261085) (xy 83.629349 -274.300664) (xy 83.590366 -274.334185) (xy 83.546318 -274.360701)
			(xy 83.522566 -274.370546) (xy 83.512152 -274.374864) (xy 83.503516 -274.387564) (xy 83.499483 -274.393969)
			(xy 83.495086 -274.408446) (xy 83.49488 -274.416012) (xy 83.49488 -274.53844) (xy 83.495141 -274.544048)
			(xy 83.497835 -274.554944) (xy 83.500214 -274.56003) (xy 83.504786 -274.567904) (xy 83.508734 -274.572762)
			(xy 83.51849 -274.580601) (xy 83.52409 -274.583398) (xy 83.524344 -274.583652) (xy 83.605116 -274.62099)
			(xy 83.618832 -274.624292) (xy 83.631278 -274.6248) (xy 83.648042 -274.61845) (xy 83.6549 -274.615148)
			(xy 83.665314 -274.609306) (xy 83.6676 -274.607528) (xy 83.668616 -274.606766) (xy 83.66887 -274.606512)
			(xy 83.689158 -274.59144) (xy 83.73364 -274.567452) (xy 83.781455 -274.551088) (xy 83.831307 -274.542792)
			(xy 83.856576 -274.54225) (xy 83.882413 -274.542798) (xy 83.933348 -274.551511) (xy 83.982089 -274.568677)
			(xy 84.027243 -274.593804) (xy 84.067522 -274.626176) (xy 84.101775 -274.664867) (xy 84.129025 -274.708773)
			(xy 84.139278 -274.732496) (xy 84.142834 -274.7391) (xy 84.143088 -274.739608) (xy 84.156623 -274.763488)
			(xy 84.175888 -274.81488) (xy 84.185675 -274.868884) (xy 84.186268 -274.896326) (xy 84.51521 -274.896326)
			(xy 84.51917 -274.847272) (xy 84.530947 -274.799488) (xy 84.550238 -274.754212) (xy 84.576541 -274.712616)
			(xy 84.609176 -274.675779) (xy 84.647297 -274.644654) (xy 84.689918 -274.620047) (xy 84.735934 -274.602595)
			(xy 84.784153 -274.592751) (xy 84.833328 -274.59077) (xy 84.882183 -274.596702) (xy 84.929454 -274.610394)
			(xy 84.973916 -274.631492) (xy 85.014419 -274.659448) (xy 85.049912 -274.69354) (xy 85.079477 -274.732884)
			(xy 85.102348 -274.776461) (xy 85.117932 -274.823142) (xy 85.125827 -274.871719) (xy 85.126322 -274.896326)
			(xy 85.455264 -274.896326) (xy 85.459224 -274.847272) (xy 85.471001 -274.799488) (xy 85.490292 -274.754212)
			(xy 85.516595 -274.712616) (xy 85.54923 -274.675779) (xy 85.587351 -274.644654) (xy 85.629972 -274.620047)
			(xy 85.675988 -274.602595) (xy 85.724207 -274.592751) (xy 85.773382 -274.59077) (xy 85.822237 -274.596702)
			(xy 85.869508 -274.610394) (xy 85.91397 -274.631492) (xy 85.954473 -274.659448) (xy 85.989966 -274.69354)
			(xy 86.019531 -274.732884) (xy 86.042402 -274.776461) (xy 86.057986 -274.823142) (xy 86.065881 -274.871719)
			(xy 86.066376 -274.896326) (xy 86.395318 -274.896326) (xy 86.399278 -274.847272) (xy 86.411055 -274.799488)
			(xy 86.430346 -274.754212) (xy 86.456649 -274.712616) (xy 86.489284 -274.675779) (xy 86.527405 -274.644654)
			(xy 86.570026 -274.620047) (xy 86.616042 -274.602595) (xy 86.664261 -274.592751) (xy 86.713436 -274.59077)
			(xy 86.762291 -274.596702) (xy 86.809562 -274.610394) (xy 86.854024 -274.631492) (xy 86.894527 -274.659448)
			(xy 86.93002 -274.69354) (xy 86.959585 -274.732884) (xy 86.982456 -274.776461) (xy 86.99804 -274.823142)
			(xy 87.005935 -274.871719) (xy 87.00643 -274.896326) (xy 87.335118 -274.896326) (xy 87.339078 -274.847272)
			(xy 87.350855 -274.799488) (xy 87.370146 -274.754212) (xy 87.396449 -274.712616) (xy 87.429084 -274.675779)
			(xy 87.467205 -274.644654) (xy 87.509826 -274.620047) (xy 87.555842 -274.602595) (xy 87.604061 -274.592751)
			(xy 87.653236 -274.59077) (xy 87.702091 -274.596702) (xy 87.749362 -274.610394) (xy 87.793824 -274.631492)
			(xy 87.834327 -274.659448) (xy 87.86982 -274.69354) (xy 87.899385 -274.732884) (xy 87.922256 -274.776461)
			(xy 87.93784 -274.823142) (xy 87.945735 -274.871719) (xy 87.94623 -274.896326) (xy 88.275172 -274.896326)
			(xy 88.279132 -274.847272) (xy 88.290909 -274.799488) (xy 88.3102 -274.754212) (xy 88.336503 -274.712616)
			(xy 88.369138 -274.675779) (xy 88.407259 -274.644654) (xy 88.44988 -274.620047) (xy 88.495896 -274.602595)
			(xy 88.544115 -274.592751) (xy 88.59329 -274.59077) (xy 88.642145 -274.596702) (xy 88.689416 -274.610394)
			(xy 88.733878 -274.631492) (xy 88.774381 -274.659448) (xy 88.809874 -274.69354) (xy 88.839439 -274.732884)
			(xy 88.86231 -274.776461) (xy 88.877894 -274.823142) (xy 88.885789 -274.871719) (xy 88.886284 -274.896326)
			(xy 89.215226 -274.896326) (xy 89.219186 -274.847272) (xy 89.230963 -274.799488) (xy 89.250254 -274.754212)
			(xy 89.276557 -274.712616) (xy 89.309192 -274.675779) (xy 89.347313 -274.644654) (xy 89.389934 -274.620047)
			(xy 89.43595 -274.602595) (xy 89.484169 -274.592751) (xy 89.533344 -274.59077) (xy 89.582199 -274.596702)
			(xy 89.62947 -274.610394) (xy 89.673932 -274.631492) (xy 89.714435 -274.659448) (xy 89.749928 -274.69354)
			(xy 89.779493 -274.732884) (xy 89.802364 -274.776461) (xy 89.817948 -274.823142) (xy 89.825843 -274.871719)
			(xy 89.826338 -274.896326) (xy 90.15528 -274.896326) (xy 90.15924 -274.847272) (xy 90.171017 -274.799488)
			(xy 90.190308 -274.754212) (xy 90.216611 -274.712616) (xy 90.249246 -274.675779) (xy 90.287367 -274.644654)
			(xy 90.329988 -274.620047) (xy 90.376004 -274.602595) (xy 90.424223 -274.592751) (xy 90.473398 -274.59077)
			(xy 90.522253 -274.596702) (xy 90.569524 -274.610394) (xy 90.613986 -274.631492) (xy 90.654489 -274.659448)
			(xy 90.689982 -274.69354) (xy 90.719547 -274.732884) (xy 90.742418 -274.776461) (xy 90.758002 -274.823142)
			(xy 90.765897 -274.871719) (xy 90.766392 -274.896326) (xy 91.084903 -274.896326) (xy 91.088998 -274.845598)
			(xy 91.101177 -274.796184) (xy 91.121125 -274.749364) (xy 91.148326 -274.70635) (xy 91.182074 -274.668256)
			(xy 91.221496 -274.636069) (xy 91.26557 -274.610623) (xy 91.313156 -274.592576) (xy 91.36302 -274.582396)
			(xy 91.413872 -274.580347) (xy 91.464393 -274.586481) (xy 91.513277 -274.600641) (xy 91.559256 -274.622458)
			(xy 91.60114 -274.651368) (xy 91.637844 -274.686623) (xy 91.668417 -274.727309) (xy 91.692068 -274.772372)
			(xy 91.708184 -274.820646) (xy 91.716348 -274.87088) (xy 91.71686 -274.896326) (xy 92.024703 -274.896326)
			(xy 92.028798 -274.845598) (xy 92.040977 -274.796184) (xy 92.060925 -274.749364) (xy 92.088126 -274.70635)
			(xy 92.121874 -274.668256) (xy 92.161296 -274.636069) (xy 92.20537 -274.610623) (xy 92.252956 -274.592576)
			(xy 92.30282 -274.582396) (xy 92.353672 -274.580347) (xy 92.404193 -274.586481) (xy 92.453077 -274.600641)
			(xy 92.499056 -274.622458) (xy 92.54094 -274.651368) (xy 92.577644 -274.686623) (xy 92.608217 -274.727309)
			(xy 92.631868 -274.772372) (xy 92.647984 -274.820646) (xy 92.656148 -274.87088) (xy 92.65666 -274.896326)
			(xy 92.975188 -274.896326) (xy 92.979148 -274.847272) (xy 92.990925 -274.799488) (xy 93.010216 -274.754212)
			(xy 93.036519 -274.712616) (xy 93.069154 -274.675779) (xy 93.107275 -274.644654) (xy 93.149896 -274.620047)
			(xy 93.195912 -274.602595) (xy 93.244131 -274.592751) (xy 93.293306 -274.59077) (xy 93.342161 -274.596702)
			(xy 93.389432 -274.610394) (xy 93.433894 -274.631492) (xy 93.474397 -274.659448) (xy 93.50989 -274.69354)
			(xy 93.539455 -274.732884) (xy 93.562326 -274.776461) (xy 93.57791 -274.823142) (xy 93.585805 -274.871719)
			(xy 93.5863 -274.896326) (xy 93.904811 -274.896326) (xy 93.908906 -274.845598) (xy 93.921085 -274.796184)
			(xy 93.941033 -274.749364) (xy 93.968234 -274.70635) (xy 94.001982 -274.668256) (xy 94.041404 -274.636069)
			(xy 94.085478 -274.610623) (xy 94.133064 -274.592576) (xy 94.182928 -274.582396) (xy 94.23378 -274.580347)
			(xy 94.284301 -274.586481) (xy 94.333185 -274.600641) (xy 94.379164 -274.622458) (xy 94.421048 -274.651368)
			(xy 94.457752 -274.686623) (xy 94.488325 -274.727309) (xy 94.511976 -274.772372) (xy 94.528092 -274.820646)
			(xy 94.536256 -274.87088) (xy 94.536768 -274.896326) (xy 94.855296 -274.896326) (xy 94.859256 -274.847272)
			(xy 94.871033 -274.799488) (xy 94.890324 -274.754212) (xy 94.916627 -274.712616) (xy 94.949262 -274.675779)
			(xy 94.987383 -274.644654) (xy 95.030004 -274.620047) (xy 95.07602 -274.602595) (xy 95.124239 -274.592751)
			(xy 95.173414 -274.59077) (xy 95.222269 -274.596702) (xy 95.26954 -274.610394) (xy 95.314002 -274.631492)
			(xy 95.354505 -274.659448) (xy 95.389998 -274.69354) (xy 95.419563 -274.732884) (xy 95.442434 -274.776461)
			(xy 95.458018 -274.823142) (xy 95.465913 -274.871719) (xy 95.466408 -274.896326) (xy 95.784919 -274.896326)
			(xy 95.789014 -274.845598) (xy 95.801193 -274.796184) (xy 95.821141 -274.749364) (xy 95.848342 -274.70635)
			(xy 95.88209 -274.668256) (xy 95.921512 -274.636069) (xy 95.965586 -274.610623) (xy 96.013172 -274.592576)
			(xy 96.063036 -274.582396) (xy 96.113888 -274.580347) (xy 96.164409 -274.586481) (xy 96.213293 -274.600641)
			(xy 96.259272 -274.622458) (xy 96.301156 -274.651368) (xy 96.33786 -274.686623) (xy 96.368433 -274.727309)
			(xy 96.392084 -274.772372) (xy 96.4082 -274.820646) (xy 96.416364 -274.87088) (xy 96.416876 -274.896326)
			(xy 96.416364 -274.921772) (xy 96.4082 -274.972006) (xy 96.392084 -275.02028) (xy 96.368433 -275.065343)
			(xy 96.33786 -275.106029) (xy 96.301156 -275.141284) (xy 96.259272 -275.170194) (xy 96.213293 -275.192011)
			(xy 96.164409 -275.206171) (xy 96.113888 -275.212305) (xy 96.063036 -275.210256) (xy 96.013172 -275.200076)
			(xy 95.965586 -275.182029) (xy 95.921512 -275.156583) (xy 95.88209 -275.124396) (xy 95.848342 -275.086302)
			(xy 95.821141 -275.043288) (xy 95.801193 -274.996468) (xy 95.789014 -274.947054) (xy 95.784919 -274.896326)
			(xy 95.466408 -274.896326) (xy 95.465913 -274.920933) (xy 95.458018 -274.96951) (xy 95.442434 -275.016191)
			(xy 95.419563 -275.059768) (xy 95.389998 -275.099112) (xy 95.354505 -275.133204) (xy 95.314002 -275.16116)
			(xy 95.26954 -275.182258) (xy 95.222269 -275.19595) (xy 95.173414 -275.201882) (xy 95.124239 -275.199901)
			(xy 95.07602 -275.190057) (xy 95.030004 -275.172605) (xy 94.987383 -275.147998) (xy 94.949262 -275.116873)
			(xy 94.916627 -275.080036) (xy 94.890324 -275.03844) (xy 94.871033 -274.993164) (xy 94.859256 -274.94538)
			(xy 94.855296 -274.896326) (xy 94.536768 -274.896326) (xy 94.536256 -274.921772) (xy 94.528092 -274.972006)
			(xy 94.511976 -275.02028) (xy 94.488325 -275.065343) (xy 94.457752 -275.106029) (xy 94.421048 -275.141284)
			(xy 94.379164 -275.170194) (xy 94.333185 -275.192011) (xy 94.284301 -275.206171) (xy 94.23378 -275.212305)
			(xy 94.182928 -275.210256) (xy 94.133064 -275.200076) (xy 94.085478 -275.182029) (xy 94.041404 -275.156583)
			(xy 94.001982 -275.124396) (xy 93.968234 -275.086302) (xy 93.941033 -275.043288) (xy 93.921085 -274.996468)
			(xy 93.908906 -274.947054) (xy 93.904811 -274.896326) (xy 93.5863 -274.896326) (xy 93.585805 -274.920933)
			(xy 93.57791 -274.96951) (xy 93.562326 -275.016191) (xy 93.539455 -275.059768) (xy 93.50989 -275.099112)
			(xy 93.474397 -275.133204) (xy 93.433894 -275.16116) (xy 93.389432 -275.182258) (xy 93.342161 -275.19595)
			(xy 93.293306 -275.201882) (xy 93.244131 -275.199901) (xy 93.195912 -275.190057) (xy 93.149896 -275.172605)
			(xy 93.107275 -275.147998) (xy 93.069154 -275.116873) (xy 93.036519 -275.080036) (xy 93.010216 -275.03844)
			(xy 92.990925 -274.993164) (xy 92.979148 -274.94538) (xy 92.975188 -274.896326) (xy 92.65666 -274.896326)
			(xy 92.656148 -274.921772) (xy 92.647984 -274.972006) (xy 92.631868 -275.02028) (xy 92.608217 -275.065343)
			(xy 92.577644 -275.106029) (xy 92.54094 -275.141284) (xy 92.499056 -275.170194) (xy 92.453077 -275.192011)
			(xy 92.404193 -275.206171) (xy 92.353672 -275.212305) (xy 92.30282 -275.210256) (xy 92.252956 -275.200076)
			(xy 92.20537 -275.182029) (xy 92.161296 -275.156583) (xy 92.121874 -275.124396) (xy 92.088126 -275.086302)
			(xy 92.060925 -275.043288) (xy 92.040977 -274.996468) (xy 92.028798 -274.947054) (xy 92.024703 -274.896326)
			(xy 91.71686 -274.896326) (xy 91.716348 -274.921772) (xy 91.708184 -274.972006) (xy 91.692068 -275.02028)
			(xy 91.668417 -275.065343) (xy 91.637844 -275.106029) (xy 91.60114 -275.141284) (xy 91.559256 -275.170194)
			(xy 91.513277 -275.192011) (xy 91.464393 -275.206171) (xy 91.413872 -275.212305) (xy 91.36302 -275.210256)
			(xy 91.313156 -275.200076) (xy 91.26557 -275.182029) (xy 91.221496 -275.156583) (xy 91.182074 -275.124396)
			(xy 91.148326 -275.086302) (xy 91.121125 -275.043288) (xy 91.101177 -274.996468) (xy 91.088998 -274.947054)
			(xy 91.084903 -274.896326) (xy 90.766392 -274.896326) (xy 90.765897 -274.920933) (xy 90.758002 -274.96951)
			(xy 90.742418 -275.016191) (xy 90.719547 -275.059768) (xy 90.689982 -275.099112) (xy 90.654489 -275.133204)
			(xy 90.613986 -275.16116) (xy 90.569524 -275.182258) (xy 90.522253 -275.19595) (xy 90.473398 -275.201882)
			(xy 90.424223 -275.199901) (xy 90.376004 -275.190057) (xy 90.329988 -275.172605) (xy 90.287367 -275.147998)
			(xy 90.249246 -275.116873) (xy 90.216611 -275.080036) (xy 90.190308 -275.03844) (xy 90.171017 -274.993164)
			(xy 90.15924 -274.94538) (xy 90.15528 -274.896326) (xy 89.826338 -274.896326) (xy 89.825843 -274.920933)
			(xy 89.817948 -274.96951) (xy 89.802364 -275.016191) (xy 89.779493 -275.059768) (xy 89.749928 -275.099112)
			(xy 89.714435 -275.133204) (xy 89.673932 -275.16116) (xy 89.62947 -275.182258) (xy 89.582199 -275.19595)
			(xy 89.533344 -275.201882) (xy 89.484169 -275.199901) (xy 89.43595 -275.190057) (xy 89.389934 -275.172605)
			(xy 89.347313 -275.147998) (xy 89.309192 -275.116873) (xy 89.276557 -275.080036) (xy 89.250254 -275.03844)
			(xy 89.230963 -274.993164) (xy 89.219186 -274.94538) (xy 89.215226 -274.896326) (xy 88.886284 -274.896326)
			(xy 88.885789 -274.920933) (xy 88.877894 -274.96951) (xy 88.86231 -275.016191) (xy 88.839439 -275.059768)
			(xy 88.809874 -275.099112) (xy 88.774381 -275.133204) (xy 88.733878 -275.16116) (xy 88.689416 -275.182258)
			(xy 88.642145 -275.19595) (xy 88.59329 -275.201882) (xy 88.544115 -275.199901) (xy 88.495896 -275.190057)
			(xy 88.44988 -275.172605) (xy 88.407259 -275.147998) (xy 88.369138 -275.116873) (xy 88.336503 -275.080036)
			(xy 88.3102 -275.03844) (xy 88.290909 -274.993164) (xy 88.279132 -274.94538) (xy 88.275172 -274.896326)
			(xy 87.94623 -274.896326) (xy 87.945735 -274.920933) (xy 87.93784 -274.96951) (xy 87.922256 -275.016191)
			(xy 87.899385 -275.059768) (xy 87.86982 -275.099112) (xy 87.834327 -275.133204) (xy 87.793824 -275.16116)
			(xy 87.749362 -275.182258) (xy 87.702091 -275.19595) (xy 87.653236 -275.201882) (xy 87.604061 -275.199901)
			(xy 87.555842 -275.190057) (xy 87.509826 -275.172605) (xy 87.467205 -275.147998) (xy 87.429084 -275.116873)
			(xy 87.396449 -275.080036) (xy 87.370146 -275.03844) (xy 87.350855 -274.993164) (xy 87.339078 -274.94538)
			(xy 87.335118 -274.896326) (xy 87.00643 -274.896326) (xy 87.005935 -274.920933) (xy 86.99804 -274.96951)
			(xy 86.982456 -275.016191) (xy 86.959585 -275.059768) (xy 86.93002 -275.099112) (xy 86.894527 -275.133204)
			(xy 86.854024 -275.16116) (xy 86.809562 -275.182258) (xy 86.762291 -275.19595) (xy 86.713436 -275.201882)
			(xy 86.664261 -275.199901) (xy 86.616042 -275.190057) (xy 86.570026 -275.172605) (xy 86.527405 -275.147998)
			(xy 86.489284 -275.116873) (xy 86.456649 -275.080036) (xy 86.430346 -275.03844) (xy 86.411055 -274.993164)
			(xy 86.399278 -274.94538) (xy 86.395318 -274.896326) (xy 86.066376 -274.896326) (xy 86.065881 -274.920933)
			(xy 86.057986 -274.96951) (xy 86.042402 -275.016191) (xy 86.019531 -275.059768) (xy 85.989966 -275.099112)
			(xy 85.954473 -275.133204) (xy 85.91397 -275.16116) (xy 85.869508 -275.182258) (xy 85.822237 -275.19595)
			(xy 85.773382 -275.201882) (xy 85.724207 -275.199901) (xy 85.675988 -275.190057) (xy 85.629972 -275.172605)
			(xy 85.587351 -275.147998) (xy 85.54923 -275.116873) (xy 85.516595 -275.080036) (xy 85.490292 -275.03844)
			(xy 85.471001 -274.993164) (xy 85.459224 -274.94538) (xy 85.455264 -274.896326) (xy 85.126322 -274.896326)
			(xy 85.125827 -274.920933) (xy 85.117932 -274.96951) (xy 85.102348 -275.016191) (xy 85.079477 -275.059768)
			(xy 85.049912 -275.099112) (xy 85.014419 -275.133204) (xy 84.973916 -275.16116) (xy 84.929454 -275.182258)
			(xy 84.882183 -275.19595) (xy 84.833328 -275.201882) (xy 84.784153 -275.199901) (xy 84.735934 -275.190057)
			(xy 84.689918 -275.172605) (xy 84.647297 -275.147998) (xy 84.609176 -275.116873) (xy 84.576541 -275.080036)
			(xy 84.550238 -275.03844) (xy 84.530947 -274.993164) (xy 84.51917 -274.94538) (xy 84.51521 -274.896326)
			(xy 84.186268 -274.896326) (xy 84.18582 -274.920317) (xy 84.17831 -274.967707) (xy 84.163478 -275.013338)
			(xy 84.141691 -275.056088) (xy 84.113484 -275.094903) (xy 84.079552 -275.128827) (xy 84.040732 -275.157025)
			(xy 83.997977 -275.178804) (xy 83.952342 -275.193625) (xy 83.904951 -275.201125) (xy 83.88096 -275.201634)
			(xy 83.854569 -275.201083) (xy 83.802572 -275.192023) (xy 83.752904 -275.174164) (xy 83.707044 -275.148035)
			(xy 83.666356 -275.114415) (xy 83.648804 -275.0947) (xy 83.627468 -275.069554) (xy 83.62569 -275.069554)
			(xy 83.621481 -275.069636) (xy 83.613182 -275.071043) (xy 83.60918 -275.072348) (xy 83.521804 -275.112734)
			(xy 83.514028 -275.117268) (xy 83.502052 -275.130692) (xy 83.495482 -275.147438) (xy 83.49488 -275.156422)
			(xy 83.49488 -275.325332) (xy 83.494916 -275.329467) (xy 83.496198 -275.337637) (xy 83.49742 -275.341588)
			(xy 83.502246 -275.351748) (xy 83.515708 -275.37283) (xy 83.51921 -275.378091) (xy 83.528335 -275.386829)
			(xy 83.533742 -275.390102) (xy 83.533996 -275.390102) (xy 83.555755 -275.402682) (xy 83.595201 -275.433827)
			(xy 83.612482 -275.452078) (xy 83.630125 -275.472276) (xy 83.658738 -275.51763) (xy 83.669378 -275.542248)
			(xy 83.672934 -275.548852) (xy 83.673188 -275.54936) (xy 83.686701 -275.573202) (xy 83.705941 -275.624511)
			(xy 83.715734 -275.678426) (xy 83.716368 -275.705824) (xy 83.716368 -275.706332) (xy 84.04531 -275.706332)
			(xy 84.04927 -275.657278) (xy 84.061047 -275.609494) (xy 84.080338 -275.564218) (xy 84.106641 -275.522622)
			(xy 84.139276 -275.485785) (xy 84.177397 -275.45466) (xy 84.220018 -275.430053) (xy 84.266034 -275.412601)
			(xy 84.314253 -275.402757) (xy 84.363428 -275.400776) (xy 84.412283 -275.406708) (xy 84.459554 -275.4204)
			(xy 84.504016 -275.441498) (xy 84.544519 -275.469454) (xy 84.580012 -275.503546) (xy 84.609577 -275.54289)
			(xy 84.632448 -275.586467) (xy 84.648032 -275.633148) (xy 84.655927 -275.681725) (xy 84.656422 -275.706332)
			(xy 84.98511 -275.706332) (xy 84.98907 -275.657278) (xy 85.000847 -275.609494) (xy 85.020138 -275.564218)
			(xy 85.046441 -275.522622) (xy 85.079076 -275.485785) (xy 85.117197 -275.45466) (xy 85.159818 -275.430053)
			(xy 85.205834 -275.412601) (xy 85.254053 -275.402757) (xy 85.303228 -275.400776) (xy 85.352083 -275.406708)
			(xy 85.399354 -275.4204) (xy 85.443816 -275.441498) (xy 85.484319 -275.469454) (xy 85.519812 -275.503546)
			(xy 85.549377 -275.54289) (xy 85.572248 -275.586467) (xy 85.587832 -275.633148) (xy 85.595727 -275.681725)
			(xy 85.596222 -275.706332) (xy 85.925164 -275.706332) (xy 85.929124 -275.657278) (xy 85.940901 -275.609494)
			(xy 85.960192 -275.564218) (xy 85.986495 -275.522622) (xy 86.01913 -275.485785) (xy 86.057251 -275.45466)
			(xy 86.099872 -275.430053) (xy 86.145888 -275.412601) (xy 86.194107 -275.402757) (xy 86.243282 -275.400776)
			(xy 86.292137 -275.406708) (xy 86.339408 -275.4204) (xy 86.38387 -275.441498) (xy 86.424373 -275.469454)
			(xy 86.459866 -275.503546) (xy 86.489431 -275.54289) (xy 86.512302 -275.586467) (xy 86.527886 -275.633148)
			(xy 86.535781 -275.681725) (xy 86.536276 -275.706332) (xy 87.805272 -275.706332) (xy 87.809232 -275.657278)
			(xy 87.821009 -275.609494) (xy 87.8403 -275.564218) (xy 87.866603 -275.522622) (xy 87.899238 -275.485785)
			(xy 87.937359 -275.45466) (xy 87.97998 -275.430053) (xy 88.025996 -275.412601) (xy 88.074215 -275.402757)
			(xy 88.12339 -275.400776) (xy 88.172245 -275.406708) (xy 88.219516 -275.4204) (xy 88.263978 -275.441498)
			(xy 88.304481 -275.469454) (xy 88.339974 -275.503546) (xy 88.369539 -275.54289) (xy 88.39241 -275.586467)
			(xy 88.407994 -275.633148) (xy 88.415889 -275.681725) (xy 88.416384 -275.706332) (xy 88.745326 -275.706332)
			(xy 88.749286 -275.657278) (xy 88.761063 -275.609494) (xy 88.780354 -275.564218) (xy 88.806657 -275.522622)
			(xy 88.839292 -275.485785) (xy 88.877413 -275.45466) (xy 88.920034 -275.430053) (xy 88.96605 -275.412601)
			(xy 89.014269 -275.402757) (xy 89.063444 -275.400776) (xy 89.112299 -275.406708) (xy 89.15957 -275.4204)
			(xy 89.204032 -275.441498) (xy 89.244535 -275.469454) (xy 89.280028 -275.503546) (xy 89.309593 -275.54289)
			(xy 89.332464 -275.586467) (xy 89.348048 -275.633148) (xy 89.355943 -275.681725) (xy 89.356438 -275.706332)
			(xy 89.685126 -275.706332) (xy 89.689086 -275.657278) (xy 89.700863 -275.609494) (xy 89.720154 -275.564218)
			(xy 89.746457 -275.522622) (xy 89.779092 -275.485785) (xy 89.817213 -275.45466) (xy 89.859834 -275.430053)
			(xy 89.90585 -275.412601) (xy 89.954069 -275.402757) (xy 90.003244 -275.400776) (xy 90.052099 -275.406708)
			(xy 90.09937 -275.4204) (xy 90.143832 -275.441498) (xy 90.184335 -275.469454) (xy 90.219828 -275.503546)
			(xy 90.249393 -275.54289) (xy 90.272264 -275.586467) (xy 90.287848 -275.633148) (xy 90.295743 -275.681725)
			(xy 90.296238 -275.706332) (xy 90.614749 -275.706332) (xy 90.618844 -275.655604) (xy 90.631023 -275.60619)
			(xy 90.650971 -275.55937) (xy 90.678172 -275.516356) (xy 90.71192 -275.478262) (xy 90.751342 -275.446075)
			(xy 90.795416 -275.420629) (xy 90.843002 -275.402582) (xy 90.892866 -275.392402) (xy 90.943718 -275.390353)
			(xy 90.994239 -275.396487) (xy 91.043123 -275.410647) (xy 91.089102 -275.432464) (xy 91.130986 -275.461374)
			(xy 91.16769 -275.496629) (xy 91.198263 -275.537315) (xy 91.221914 -275.582378) (xy 91.23803 -275.630652)
			(xy 91.246194 -275.680886) (xy 91.246706 -275.706332) (xy 91.565234 -275.706332) (xy 91.569194 -275.657278)
			(xy 91.580971 -275.609494) (xy 91.600262 -275.564218) (xy 91.626565 -275.522622) (xy 91.6592 -275.485785)
			(xy 91.697321 -275.45466) (xy 91.739942 -275.430053) (xy 91.785958 -275.412601) (xy 91.834177 -275.402757)
			(xy 91.883352 -275.400776) (xy 91.932207 -275.406708) (xy 91.979478 -275.4204) (xy 92.02394 -275.441498)
			(xy 92.064443 -275.469454) (xy 92.099936 -275.503546) (xy 92.129501 -275.54289) (xy 92.152372 -275.586467)
			(xy 92.167956 -275.633148) (xy 92.175851 -275.681725) (xy 92.176346 -275.706332) (xy 92.494857 -275.706332)
			(xy 92.498952 -275.655604) (xy 92.511131 -275.60619) (xy 92.531079 -275.55937) (xy 92.55828 -275.516356)
			(xy 92.592028 -275.478262) (xy 92.63145 -275.446075) (xy 92.675524 -275.420629) (xy 92.72311 -275.402582)
			(xy 92.772974 -275.392402) (xy 92.823826 -275.390353) (xy 92.874347 -275.396487) (xy 92.923231 -275.410647)
			(xy 92.96921 -275.432464) (xy 93.011094 -275.461374) (xy 93.047798 -275.496629) (xy 93.078371 -275.537315)
			(xy 93.102022 -275.582378) (xy 93.118138 -275.630652) (xy 93.126302 -275.680886) (xy 93.126814 -275.706332)
			(xy 94.374711 -275.706332) (xy 94.378806 -275.655604) (xy 94.390985 -275.60619) (xy 94.410933 -275.55937)
			(xy 94.438134 -275.516356) (xy 94.471882 -275.478262) (xy 94.511304 -275.446075) (xy 94.555378 -275.420629)
			(xy 94.602964 -275.402582) (xy 94.652828 -275.392402) (xy 94.70368 -275.390353) (xy 94.754201 -275.396487)
			(xy 94.803085 -275.410647) (xy 94.849064 -275.432464) (xy 94.890948 -275.461374) (xy 94.927652 -275.496629)
			(xy 94.958225 -275.537315) (xy 94.981876 -275.582378) (xy 94.997992 -275.630652) (xy 95.006156 -275.680886)
			(xy 95.006668 -275.706332) (xy 95.314765 -275.706332) (xy 95.31886 -275.655604) (xy 95.331039 -275.60619)
			(xy 95.350987 -275.55937) (xy 95.378188 -275.516356) (xy 95.411936 -275.478262) (xy 95.451358 -275.446075)
			(xy 95.495432 -275.420629) (xy 95.543018 -275.402582) (xy 95.592882 -275.392402) (xy 95.643734 -275.390353)
			(xy 95.694255 -275.396487) (xy 95.743139 -275.410647) (xy 95.789118 -275.432464) (xy 95.831002 -275.461374)
			(xy 95.867706 -275.496629) (xy 95.898279 -275.537315) (xy 95.92193 -275.582378) (xy 95.938046 -275.630652)
			(xy 95.94621 -275.680886) (xy 95.946722 -275.706332) (xy 95.94621 -275.731778) (xy 95.938046 -275.782012)
			(xy 95.92193 -275.830286) (xy 95.898279 -275.875349) (xy 95.867706 -275.916035) (xy 95.831002 -275.95129)
			(xy 95.789118 -275.9802) (xy 95.743139 -276.002017) (xy 95.694255 -276.016177) (xy 95.643734 -276.022311)
			(xy 95.592882 -276.020262) (xy 95.543018 -276.010082) (xy 95.495432 -275.992035) (xy 95.451358 -275.966589)
			(xy 95.411936 -275.934402) (xy 95.378188 -275.896308) (xy 95.350987 -275.853294) (xy 95.331039 -275.806474)
			(xy 95.31886 -275.75706) (xy 95.314765 -275.706332) (xy 95.006668 -275.706332) (xy 95.006156 -275.731778)
			(xy 94.997992 -275.782012) (xy 94.981876 -275.830286) (xy 94.958225 -275.875349) (xy 94.927652 -275.916035)
			(xy 94.890948 -275.95129) (xy 94.849064 -275.9802) (xy 94.803085 -276.002017) (xy 94.754201 -276.016177)
			(xy 94.70368 -276.022311) (xy 94.652828 -276.020262) (xy 94.602964 -276.010082) (xy 94.555378 -275.992035)
			(xy 94.511304 -275.966589) (xy 94.471882 -275.934402) (xy 94.438134 -275.896308) (xy 94.410933 -275.853294)
			(xy 94.390985 -275.806474) (xy 94.378806 -275.75706) (xy 94.374711 -275.706332) (xy 93.126814 -275.706332)
			(xy 93.126302 -275.731778) (xy 93.118138 -275.782012) (xy 93.102022 -275.830286) (xy 93.078371 -275.875349)
			(xy 93.047798 -275.916035) (xy 93.011094 -275.95129) (xy 92.96921 -275.9802) (xy 92.923231 -276.002017)
			(xy 92.874347 -276.016177) (xy 92.823826 -276.022311) (xy 92.772974 -276.020262) (xy 92.72311 -276.010082)
			(xy 92.675524 -275.992035) (xy 92.63145 -275.966589) (xy 92.592028 -275.934402) (xy 92.55828 -275.896308)
			(xy 92.531079 -275.853294) (xy 92.511131 -275.806474) (xy 92.498952 -275.75706) (xy 92.494857 -275.706332)
			(xy 92.176346 -275.706332) (xy 92.175851 -275.730939) (xy 92.167956 -275.779516) (xy 92.152372 -275.826197)
			(xy 92.129501 -275.869774) (xy 92.099936 -275.909118) (xy 92.064443 -275.94321) (xy 92.02394 -275.971166)
			(xy 91.979478 -275.992264) (xy 91.932207 -276.005956) (xy 91.883352 -276.011888) (xy 91.834177 -276.009907)
			(xy 91.785958 -276.000063) (xy 91.739942 -275.982611) (xy 91.697321 -275.958004) (xy 91.6592 -275.926879)
			(xy 91.626565 -275.890042) (xy 91.600262 -275.848446) (xy 91.580971 -275.80317) (xy 91.569194 -275.755386)
			(xy 91.565234 -275.706332) (xy 91.246706 -275.706332) (xy 91.246194 -275.731778) (xy 91.23803 -275.782012)
			(xy 91.221914 -275.830286) (xy 91.198263 -275.875349) (xy 91.16769 -275.916035) (xy 91.130986 -275.95129)
			(xy 91.089102 -275.9802) (xy 91.043123 -276.002017) (xy 90.994239 -276.016177) (xy 90.943718 -276.022311)
			(xy 90.892866 -276.020262) (xy 90.843002 -276.010082) (xy 90.795416 -275.992035) (xy 90.751342 -275.966589)
			(xy 90.71192 -275.934402) (xy 90.678172 -275.896308) (xy 90.650971 -275.853294) (xy 90.631023 -275.806474)
			(xy 90.618844 -275.75706) (xy 90.614749 -275.706332) (xy 90.296238 -275.706332) (xy 90.295743 -275.730939)
			(xy 90.287848 -275.779516) (xy 90.272264 -275.826197) (xy 90.249393 -275.869774) (xy 90.219828 -275.909118)
			(xy 90.184335 -275.94321) (xy 90.143832 -275.971166) (xy 90.09937 -275.992264) (xy 90.052099 -276.005956)
			(xy 90.003244 -276.011888) (xy 89.954069 -276.009907) (xy 89.90585 -276.000063) (xy 89.859834 -275.982611)
			(xy 89.817213 -275.958004) (xy 89.779092 -275.926879) (xy 89.746457 -275.890042) (xy 89.720154 -275.848446)
			(xy 89.700863 -275.80317) (xy 89.689086 -275.755386) (xy 89.685126 -275.706332) (xy 89.356438 -275.706332)
			(xy 89.355943 -275.730939) (xy 89.348048 -275.779516) (xy 89.332464 -275.826197) (xy 89.309593 -275.869774)
			(xy 89.280028 -275.909118) (xy 89.244535 -275.94321) (xy 89.204032 -275.971166) (xy 89.15957 -275.992264)
			(xy 89.112299 -276.005956) (xy 89.063444 -276.011888) (xy 89.014269 -276.009907) (xy 88.96605 -276.000063)
			(xy 88.920034 -275.982611) (xy 88.877413 -275.958004) (xy 88.839292 -275.926879) (xy 88.806657 -275.890042)
			(xy 88.780354 -275.848446) (xy 88.761063 -275.80317) (xy 88.749286 -275.755386) (xy 88.745326 -275.706332)
			(xy 88.416384 -275.706332) (xy 88.415889 -275.730939) (xy 88.407994 -275.779516) (xy 88.39241 -275.826197)
			(xy 88.369539 -275.869774) (xy 88.339974 -275.909118) (xy 88.304481 -275.94321) (xy 88.263978 -275.971166)
			(xy 88.219516 -275.992264) (xy 88.172245 -276.005956) (xy 88.12339 -276.011888) (xy 88.074215 -276.009907)
			(xy 88.025996 -276.000063) (xy 87.97998 -275.982611) (xy 87.937359 -275.958004) (xy 87.899238 -275.926879)
			(xy 87.866603 -275.890042) (xy 87.8403 -275.848446) (xy 87.821009 -275.80317) (xy 87.809232 -275.755386)
			(xy 87.805272 -275.706332) (xy 86.536276 -275.706332) (xy 86.535781 -275.730939) (xy 86.527886 -275.779516)
			(xy 86.512302 -275.826197) (xy 86.489431 -275.869774) (xy 86.459866 -275.909118) (xy 86.424373 -275.94321)
			(xy 86.38387 -275.971166) (xy 86.339408 -275.992264) (xy 86.292137 -276.005956) (xy 86.243282 -276.011888)
			(xy 86.194107 -276.009907) (xy 86.145888 -276.000063) (xy 86.099872 -275.982611) (xy 86.057251 -275.958004)
			(xy 86.01913 -275.926879) (xy 85.986495 -275.890042) (xy 85.960192 -275.848446) (xy 85.940901 -275.80317)
			(xy 85.929124 -275.755386) (xy 85.925164 -275.706332) (xy 85.596222 -275.706332) (xy 85.595727 -275.730939)
			(xy 85.587832 -275.779516) (xy 85.572248 -275.826197) (xy 85.549377 -275.869774) (xy 85.519812 -275.909118)
			(xy 85.484319 -275.94321) (xy 85.443816 -275.971166) (xy 85.399354 -275.992264) (xy 85.352083 -276.005956)
			(xy 85.303228 -276.011888) (xy 85.254053 -276.009907) (xy 85.205834 -276.000063) (xy 85.159818 -275.982611)
			(xy 85.117197 -275.958004) (xy 85.079076 -275.926879) (xy 85.046441 -275.890042) (xy 85.020138 -275.848446)
			(xy 85.000847 -275.80317) (xy 84.98907 -275.755386) (xy 84.98511 -275.706332) (xy 84.656422 -275.706332)
			(xy 84.655927 -275.730939) (xy 84.648032 -275.779516) (xy 84.632448 -275.826197) (xy 84.609577 -275.869774)
			(xy 84.580012 -275.909118) (xy 84.544519 -275.94321) (xy 84.504016 -275.971166) (xy 84.459554 -275.992264)
			(xy 84.412283 -276.005956) (xy 84.363428 -276.011888) (xy 84.314253 -276.009907) (xy 84.266034 -276.000063)
			(xy 84.220018 -275.982611) (xy 84.177397 -275.958004) (xy 84.139276 -275.926879) (xy 84.106641 -275.890042)
			(xy 84.080338 -275.848446) (xy 84.061047 -275.80317) (xy 84.04927 -275.755386) (xy 84.04531 -275.706332)
			(xy 83.716368 -275.706332) (xy 83.716368 -275.712174) (xy 83.715351 -275.737866) (xy 83.70578 -275.788379)
			(xy 83.687881 -275.836575) (xy 83.66216 -275.881091) (xy 83.629344 -275.920669) (xy 83.590362 -275.954189)
			(xy 83.546314 -275.980703) (xy 83.522566 -275.990558) (xy 83.512152 -275.994876) (xy 83.503516 -276.007576)
			(xy 83.499485 -276.013982) (xy 83.495091 -276.028458) (xy 83.49488 -276.036024) (xy 83.49488 -276.158452)
			(xy 83.495142 -276.16406) (xy 83.497839 -276.174955) (xy 83.500214 -276.180042) (xy 83.504786 -276.187916)
			(xy 83.508735 -276.192774) (xy 83.518491 -276.200611) (xy 83.52409 -276.20341) (xy 83.524344 -276.203664)
			(xy 83.605116 -276.241002) (xy 83.618832 -276.244304) (xy 83.631278 -276.244812) (xy 83.648042 -276.238462)
			(xy 83.6549 -276.23516) (xy 83.665314 -276.229318) (xy 83.6676 -276.22754) (xy 83.668616 -276.226778)
			(xy 83.66887 -276.226524) (xy 83.689158 -276.211451) (xy 83.73364 -276.187462) (xy 83.781455 -276.171098)
			(xy 83.831307 -276.162801) (xy 83.856576 -276.162262) (xy 83.882413 -276.16281) (xy 83.933348 -276.171524)
			(xy 83.982088 -276.18869) (xy 84.027241 -276.213817) (xy 84.067519 -276.246189) (xy 84.101771 -276.284881)
			(xy 84.129019 -276.328788) (xy 84.139278 -276.352508) (xy 84.142834 -276.359112) (xy 84.143088 -276.35962)
			(xy 84.156622 -276.3835) (xy 84.175885 -276.434892) (xy 84.18567 -276.488896) (xy 84.186268 -276.516338)
			(xy 84.51521 -276.516338) (xy 84.51917 -276.467284) (xy 84.530947 -276.4195) (xy 84.550238 -276.374224)
			(xy 84.576541 -276.332628) (xy 84.609176 -276.295791) (xy 84.647297 -276.264666) (xy 84.689918 -276.240059)
			(xy 84.735934 -276.222607) (xy 84.784153 -276.212763) (xy 84.833328 -276.210782) (xy 84.882183 -276.216714)
			(xy 84.929454 -276.230406) (xy 84.973916 -276.251504) (xy 85.014419 -276.27946) (xy 85.049912 -276.313552)
			(xy 85.079477 -276.352896) (xy 85.102348 -276.396473) (xy 85.117932 -276.443154) (xy 85.125827 -276.491731)
			(xy 85.126322 -276.516338) (xy 85.455264 -276.516338) (xy 85.459224 -276.467284) (xy 85.471001 -276.4195)
			(xy 85.490292 -276.374224) (xy 85.516595 -276.332628) (xy 85.54923 -276.295791) (xy 85.587351 -276.264666)
			(xy 85.629972 -276.240059) (xy 85.675988 -276.222607) (xy 85.724207 -276.212763) (xy 85.773382 -276.210782)
			(xy 85.822237 -276.216714) (xy 85.869508 -276.230406) (xy 85.91397 -276.251504) (xy 85.954473 -276.27946)
			(xy 85.989966 -276.313552) (xy 86.019531 -276.352896) (xy 86.042402 -276.396473) (xy 86.057986 -276.443154)
			(xy 86.065881 -276.491731) (xy 86.066376 -276.516338) (xy 86.395318 -276.516338) (xy 86.399278 -276.467284)
			(xy 86.411055 -276.4195) (xy 86.430346 -276.374224) (xy 86.456649 -276.332628) (xy 86.489284 -276.295791)
			(xy 86.527405 -276.264666) (xy 86.570026 -276.240059) (xy 86.616042 -276.222607) (xy 86.664261 -276.212763)
			(xy 86.713436 -276.210782) (xy 86.762291 -276.216714) (xy 86.809562 -276.230406) (xy 86.854024 -276.251504)
			(xy 86.894527 -276.27946) (xy 86.93002 -276.313552) (xy 86.959585 -276.352896) (xy 86.982456 -276.396473)
			(xy 86.99804 -276.443154) (xy 87.005935 -276.491731) (xy 87.00643 -276.516338) (xy 87.335118 -276.516338)
			(xy 87.339078 -276.467284) (xy 87.350855 -276.4195) (xy 87.370146 -276.374224) (xy 87.396449 -276.332628)
			(xy 87.429084 -276.295791) (xy 87.467205 -276.264666) (xy 87.509826 -276.240059) (xy 87.555842 -276.222607)
			(xy 87.604061 -276.212763) (xy 87.653236 -276.210782) (xy 87.702091 -276.216714) (xy 87.749362 -276.230406)
			(xy 87.793824 -276.251504) (xy 87.834327 -276.27946) (xy 87.86982 -276.313552) (xy 87.899385 -276.352896)
			(xy 87.922256 -276.396473) (xy 87.93784 -276.443154) (xy 87.945735 -276.491731) (xy 87.94623 -276.516338)
			(xy 88.275172 -276.516338) (xy 88.279132 -276.467284) (xy 88.290909 -276.4195) (xy 88.3102 -276.374224)
			(xy 88.336503 -276.332628) (xy 88.369138 -276.295791) (xy 88.407259 -276.264666) (xy 88.44988 -276.240059)
			(xy 88.495896 -276.222607) (xy 88.544115 -276.212763) (xy 88.59329 -276.210782) (xy 88.642145 -276.216714)
			(xy 88.689416 -276.230406) (xy 88.733878 -276.251504) (xy 88.774381 -276.27946) (xy 88.809874 -276.313552)
			(xy 88.839439 -276.352896) (xy 88.86231 -276.396473) (xy 88.877894 -276.443154) (xy 88.885789 -276.491731)
			(xy 88.886284 -276.516338) (xy 89.215226 -276.516338) (xy 89.219186 -276.467284) (xy 89.230963 -276.4195)
			(xy 89.250254 -276.374224) (xy 89.276557 -276.332628) (xy 89.309192 -276.295791) (xy 89.347313 -276.264666)
			(xy 89.389934 -276.240059) (xy 89.43595 -276.222607) (xy 89.484169 -276.212763) (xy 89.533344 -276.210782)
			(xy 89.582199 -276.216714) (xy 89.62947 -276.230406) (xy 89.673932 -276.251504) (xy 89.714435 -276.27946)
			(xy 89.749928 -276.313552) (xy 89.779493 -276.352896) (xy 89.802364 -276.396473) (xy 89.817948 -276.443154)
			(xy 89.825843 -276.491731) (xy 89.826338 -276.516338) (xy 90.15528 -276.516338) (xy 90.15924 -276.467284)
			(xy 90.171017 -276.4195) (xy 90.190308 -276.374224) (xy 90.216611 -276.332628) (xy 90.249246 -276.295791)
			(xy 90.287367 -276.264666) (xy 90.329988 -276.240059) (xy 90.376004 -276.222607) (xy 90.424223 -276.212763)
			(xy 90.473398 -276.210782) (xy 90.522253 -276.216714) (xy 90.569524 -276.230406) (xy 90.613986 -276.251504)
			(xy 90.654489 -276.27946) (xy 90.689982 -276.313552) (xy 90.719547 -276.352896) (xy 90.742418 -276.396473)
			(xy 90.758002 -276.443154) (xy 90.765897 -276.491731) (xy 90.766392 -276.516338) (xy 91.084903 -276.516338)
			(xy 91.088998 -276.46561) (xy 91.101177 -276.416196) (xy 91.121125 -276.369376) (xy 91.148326 -276.326362)
			(xy 91.182074 -276.288268) (xy 91.221496 -276.256081) (xy 91.26557 -276.230635) (xy 91.313156 -276.212588)
			(xy 91.36302 -276.202408) (xy 91.413872 -276.200359) (xy 91.464393 -276.206493) (xy 91.513277 -276.220653)
			(xy 91.559256 -276.24247) (xy 91.60114 -276.27138) (xy 91.637844 -276.306635) (xy 91.668417 -276.347321)
			(xy 91.692068 -276.392384) (xy 91.708184 -276.440658) (xy 91.716348 -276.490892) (xy 91.71686 -276.516338)
			(xy 92.024703 -276.516338) (xy 92.028798 -276.46561) (xy 92.040977 -276.416196) (xy 92.060925 -276.369376)
			(xy 92.088126 -276.326362) (xy 92.121874 -276.288268) (xy 92.161296 -276.256081) (xy 92.20537 -276.230635)
			(xy 92.252956 -276.212588) (xy 92.30282 -276.202408) (xy 92.353672 -276.200359) (xy 92.404193 -276.206493)
			(xy 92.453077 -276.220653) (xy 92.499056 -276.24247) (xy 92.54094 -276.27138) (xy 92.577644 -276.306635)
			(xy 92.608217 -276.347321) (xy 92.631868 -276.392384) (xy 92.647984 -276.440658) (xy 92.656148 -276.490892)
			(xy 92.65666 -276.516338) (xy 92.975188 -276.516338) (xy 92.979148 -276.467284) (xy 92.990925 -276.4195)
			(xy 93.010216 -276.374224) (xy 93.036519 -276.332628) (xy 93.069154 -276.295791) (xy 93.107275 -276.264666)
			(xy 93.149896 -276.240059) (xy 93.195912 -276.222607) (xy 93.244131 -276.212763) (xy 93.293306 -276.210782)
			(xy 93.342161 -276.216714) (xy 93.389432 -276.230406) (xy 93.433894 -276.251504) (xy 93.474397 -276.27946)
			(xy 93.50989 -276.313552) (xy 93.539455 -276.352896) (xy 93.562326 -276.396473) (xy 93.57791 -276.443154)
			(xy 93.585805 -276.491731) (xy 93.5863 -276.516338) (xy 93.904811 -276.516338) (xy 93.908906 -276.46561)
			(xy 93.921085 -276.416196) (xy 93.941033 -276.369376) (xy 93.968234 -276.326362) (xy 94.001982 -276.288268)
			(xy 94.041404 -276.256081) (xy 94.085478 -276.230635) (xy 94.133064 -276.212588) (xy 94.182928 -276.202408)
			(xy 94.23378 -276.200359) (xy 94.284301 -276.206493) (xy 94.333185 -276.220653) (xy 94.379164 -276.24247)
			(xy 94.421048 -276.27138) (xy 94.457752 -276.306635) (xy 94.488325 -276.347321) (xy 94.511976 -276.392384)
			(xy 94.528092 -276.440658) (xy 94.536256 -276.490892) (xy 94.536768 -276.516338) (xy 94.855296 -276.516338)
			(xy 94.859256 -276.467284) (xy 94.871033 -276.4195) (xy 94.890324 -276.374224) (xy 94.916627 -276.332628)
			(xy 94.949262 -276.295791) (xy 94.987383 -276.264666) (xy 95.030004 -276.240059) (xy 95.07602 -276.222607)
			(xy 95.124239 -276.212763) (xy 95.173414 -276.210782) (xy 95.222269 -276.216714) (xy 95.26954 -276.230406)
			(xy 95.314002 -276.251504) (xy 95.354505 -276.27946) (xy 95.389998 -276.313552) (xy 95.419563 -276.352896)
			(xy 95.442434 -276.396473) (xy 95.458018 -276.443154) (xy 95.465913 -276.491731) (xy 95.466408 -276.516338)
			(xy 95.784919 -276.516338) (xy 95.789014 -276.46561) (xy 95.801193 -276.416196) (xy 95.821141 -276.369376)
			(xy 95.848342 -276.326362) (xy 95.88209 -276.288268) (xy 95.921512 -276.256081) (xy 95.965586 -276.230635)
			(xy 96.013172 -276.212588) (xy 96.063036 -276.202408) (xy 96.113888 -276.200359) (xy 96.164409 -276.206493)
			(xy 96.213293 -276.220653) (xy 96.259272 -276.24247) (xy 96.301156 -276.27138) (xy 96.33786 -276.306635)
			(xy 96.368433 -276.347321) (xy 96.392084 -276.392384) (xy 96.4082 -276.440658) (xy 96.416364 -276.490892)
			(xy 96.416876 -276.516338) (xy 96.416364 -276.541784) (xy 96.4082 -276.592018) (xy 96.392084 -276.640292)
			(xy 96.368433 -276.685355) (xy 96.33786 -276.726041) (xy 96.301156 -276.761296) (xy 96.259272 -276.790206)
			(xy 96.213293 -276.812023) (xy 96.164409 -276.826183) (xy 96.113888 -276.832317) (xy 96.063036 -276.830268)
			(xy 96.013172 -276.820088) (xy 95.965586 -276.802041) (xy 95.921512 -276.776595) (xy 95.88209 -276.744408)
			(xy 95.848342 -276.706314) (xy 95.821141 -276.6633) (xy 95.801193 -276.61648) (xy 95.789014 -276.567066)
			(xy 95.784919 -276.516338) (xy 95.466408 -276.516338) (xy 95.465913 -276.540945) (xy 95.458018 -276.589522)
			(xy 95.442434 -276.636203) (xy 95.419563 -276.67978) (xy 95.389998 -276.719124) (xy 95.354505 -276.753216)
			(xy 95.314002 -276.781172) (xy 95.26954 -276.80227) (xy 95.222269 -276.815962) (xy 95.173414 -276.821894)
			(xy 95.124239 -276.819913) (xy 95.07602 -276.810069) (xy 95.030004 -276.792617) (xy 94.987383 -276.76801)
			(xy 94.949262 -276.736885) (xy 94.916627 -276.700048) (xy 94.890324 -276.658452) (xy 94.871033 -276.613176)
			(xy 94.859256 -276.565392) (xy 94.855296 -276.516338) (xy 94.536768 -276.516338) (xy 94.536256 -276.541784)
			(xy 94.528092 -276.592018) (xy 94.511976 -276.640292) (xy 94.488325 -276.685355) (xy 94.457752 -276.726041)
			(xy 94.421048 -276.761296) (xy 94.379164 -276.790206) (xy 94.333185 -276.812023) (xy 94.284301 -276.826183)
			(xy 94.23378 -276.832317) (xy 94.182928 -276.830268) (xy 94.133064 -276.820088) (xy 94.085478 -276.802041)
			(xy 94.041404 -276.776595) (xy 94.001982 -276.744408) (xy 93.968234 -276.706314) (xy 93.941033 -276.6633)
			(xy 93.921085 -276.61648) (xy 93.908906 -276.567066) (xy 93.904811 -276.516338) (xy 93.5863 -276.516338)
			(xy 93.585805 -276.540945) (xy 93.57791 -276.589522) (xy 93.562326 -276.636203) (xy 93.539455 -276.67978)
			(xy 93.50989 -276.719124) (xy 93.474397 -276.753216) (xy 93.433894 -276.781172) (xy 93.389432 -276.80227)
			(xy 93.342161 -276.815962) (xy 93.293306 -276.821894) (xy 93.244131 -276.819913) (xy 93.195912 -276.810069)
			(xy 93.149896 -276.792617) (xy 93.107275 -276.76801) (xy 93.069154 -276.736885) (xy 93.036519 -276.700048)
			(xy 93.010216 -276.658452) (xy 92.990925 -276.613176) (xy 92.979148 -276.565392) (xy 92.975188 -276.516338)
			(xy 92.65666 -276.516338) (xy 92.656148 -276.541784) (xy 92.647984 -276.592018) (xy 92.631868 -276.640292)
			(xy 92.608217 -276.685355) (xy 92.577644 -276.726041) (xy 92.54094 -276.761296) (xy 92.499056 -276.790206)
			(xy 92.453077 -276.812023) (xy 92.404193 -276.826183) (xy 92.353672 -276.832317) (xy 92.30282 -276.830268)
			(xy 92.252956 -276.820088) (xy 92.20537 -276.802041) (xy 92.161296 -276.776595) (xy 92.121874 -276.744408)
			(xy 92.088126 -276.706314) (xy 92.060925 -276.6633) (xy 92.040977 -276.61648) (xy 92.028798 -276.567066)
			(xy 92.024703 -276.516338) (xy 91.71686 -276.516338) (xy 91.716348 -276.541784) (xy 91.708184 -276.592018)
			(xy 91.692068 -276.640292) (xy 91.668417 -276.685355) (xy 91.637844 -276.726041) (xy 91.60114 -276.761296)
			(xy 91.559256 -276.790206) (xy 91.513277 -276.812023) (xy 91.464393 -276.826183) (xy 91.413872 -276.832317)
			(xy 91.36302 -276.830268) (xy 91.313156 -276.820088) (xy 91.26557 -276.802041) (xy 91.221496 -276.776595)
			(xy 91.182074 -276.744408) (xy 91.148326 -276.706314) (xy 91.121125 -276.6633) (xy 91.101177 -276.61648)
			(xy 91.088998 -276.567066) (xy 91.084903 -276.516338) (xy 90.766392 -276.516338) (xy 90.765897 -276.540945)
			(xy 90.758002 -276.589522) (xy 90.742418 -276.636203) (xy 90.719547 -276.67978) (xy 90.689982 -276.719124)
			(xy 90.654489 -276.753216) (xy 90.613986 -276.781172) (xy 90.569524 -276.80227) (xy 90.522253 -276.815962)
			(xy 90.473398 -276.821894) (xy 90.424223 -276.819913) (xy 90.376004 -276.810069) (xy 90.329988 -276.792617)
			(xy 90.287367 -276.76801) (xy 90.249246 -276.736885) (xy 90.216611 -276.700048) (xy 90.190308 -276.658452)
			(xy 90.171017 -276.613176) (xy 90.15924 -276.565392) (xy 90.15528 -276.516338) (xy 89.826338 -276.516338)
			(xy 89.825843 -276.540945) (xy 89.817948 -276.589522) (xy 89.802364 -276.636203) (xy 89.779493 -276.67978)
			(xy 89.749928 -276.719124) (xy 89.714435 -276.753216) (xy 89.673932 -276.781172) (xy 89.62947 -276.80227)
			(xy 89.582199 -276.815962) (xy 89.533344 -276.821894) (xy 89.484169 -276.819913) (xy 89.43595 -276.810069)
			(xy 89.389934 -276.792617) (xy 89.347313 -276.76801) (xy 89.309192 -276.736885) (xy 89.276557 -276.700048)
			(xy 89.250254 -276.658452) (xy 89.230963 -276.613176) (xy 89.219186 -276.565392) (xy 89.215226 -276.516338)
			(xy 88.886284 -276.516338) (xy 88.885789 -276.540945) (xy 88.877894 -276.589522) (xy 88.86231 -276.636203)
			(xy 88.839439 -276.67978) (xy 88.809874 -276.719124) (xy 88.774381 -276.753216) (xy 88.733878 -276.781172)
			(xy 88.689416 -276.80227) (xy 88.642145 -276.815962) (xy 88.59329 -276.821894) (xy 88.544115 -276.819913)
			(xy 88.495896 -276.810069) (xy 88.44988 -276.792617) (xy 88.407259 -276.76801) (xy 88.369138 -276.736885)
			(xy 88.336503 -276.700048) (xy 88.3102 -276.658452) (xy 88.290909 -276.613176) (xy 88.279132 -276.565392)
			(xy 88.275172 -276.516338) (xy 87.94623 -276.516338) (xy 87.945735 -276.540945) (xy 87.93784 -276.589522)
			(xy 87.922256 -276.636203) (xy 87.899385 -276.67978) (xy 87.86982 -276.719124) (xy 87.834327 -276.753216)
			(xy 87.793824 -276.781172) (xy 87.749362 -276.80227) (xy 87.702091 -276.815962) (xy 87.653236 -276.821894)
			(xy 87.604061 -276.819913) (xy 87.555842 -276.810069) (xy 87.509826 -276.792617) (xy 87.467205 -276.76801)
			(xy 87.429084 -276.736885) (xy 87.396449 -276.700048) (xy 87.370146 -276.658452) (xy 87.350855 -276.613176)
			(xy 87.339078 -276.565392) (xy 87.335118 -276.516338) (xy 87.00643 -276.516338) (xy 87.005935 -276.540945)
			(xy 86.99804 -276.589522) (xy 86.982456 -276.636203) (xy 86.959585 -276.67978) (xy 86.93002 -276.719124)
			(xy 86.894527 -276.753216) (xy 86.854024 -276.781172) (xy 86.809562 -276.80227) (xy 86.762291 -276.815962)
			(xy 86.713436 -276.821894) (xy 86.664261 -276.819913) (xy 86.616042 -276.810069) (xy 86.570026 -276.792617)
			(xy 86.527405 -276.76801) (xy 86.489284 -276.736885) (xy 86.456649 -276.700048) (xy 86.430346 -276.658452)
			(xy 86.411055 -276.613176) (xy 86.399278 -276.565392) (xy 86.395318 -276.516338) (xy 86.066376 -276.516338)
			(xy 86.065881 -276.540945) (xy 86.057986 -276.589522) (xy 86.042402 -276.636203) (xy 86.019531 -276.67978)
			(xy 85.989966 -276.719124) (xy 85.954473 -276.753216) (xy 85.91397 -276.781172) (xy 85.869508 -276.80227)
			(xy 85.822237 -276.815962) (xy 85.773382 -276.821894) (xy 85.724207 -276.819913) (xy 85.675988 -276.810069)
			(xy 85.629972 -276.792617) (xy 85.587351 -276.76801) (xy 85.54923 -276.736885) (xy 85.516595 -276.700048)
			(xy 85.490292 -276.658452) (xy 85.471001 -276.613176) (xy 85.459224 -276.565392) (xy 85.455264 -276.516338)
			(xy 85.126322 -276.516338) (xy 85.125827 -276.540945) (xy 85.117932 -276.589522) (xy 85.102348 -276.636203)
			(xy 85.079477 -276.67978) (xy 85.049912 -276.719124) (xy 85.014419 -276.753216) (xy 84.973916 -276.781172)
			(xy 84.929454 -276.80227) (xy 84.882183 -276.815962) (xy 84.833328 -276.821894) (xy 84.784153 -276.819913)
			(xy 84.735934 -276.810069) (xy 84.689918 -276.792617) (xy 84.647297 -276.76801) (xy 84.609176 -276.736885)
			(xy 84.576541 -276.700048) (xy 84.550238 -276.658452) (xy 84.530947 -276.613176) (xy 84.51917 -276.565392)
			(xy 84.51521 -276.516338) (xy 84.186268 -276.516338) (xy 84.185819 -276.540328) (xy 84.178307 -276.587717)
			(xy 84.163475 -276.633347) (xy 84.141687 -276.676095) (xy 84.11348 -276.714908) (xy 84.079548 -276.748831)
			(xy 84.040728 -276.777028) (xy 83.997974 -276.798805) (xy 83.952341 -276.813625) (xy 83.90495 -276.821125)
			(xy 83.88096 -276.821646) (xy 83.854569 -276.821095) (xy 83.802571 -276.812036) (xy 83.752903 -276.794176)
			(xy 83.707042 -276.768048) (xy 83.666353 -276.734429) (xy 83.648804 -276.714712) (xy 83.627468 -276.689566)
			(xy 83.62569 -276.689566) (xy 83.621481 -276.689643) (xy 83.613181 -276.69105) (xy 83.60918 -276.69236)
			(xy 83.521804 -276.732746) (xy 83.514019 -276.737276) (xy 83.50202 -276.750695) (xy 83.495421 -276.767443)
			(xy 83.49488 -276.776434) (xy 83.49488 -276.945344) (xy 83.494917 -276.949479) (xy 83.496201 -276.957648)
			(xy 83.49742 -276.9616) (xy 83.502246 -276.97176) (xy 83.515708 -276.992842) (xy 83.51921 -276.998103)
			(xy 83.528337 -277.006839) (xy 83.533742 -277.010114) (xy 83.533996 -277.010114) (xy 83.555755 -277.022695)
			(xy 83.5952 -277.05384) (xy 83.612482 -277.07209) (xy 83.630124 -277.092289) (xy 83.658736 -277.137643)
			(xy 83.669378 -277.16226) (xy 83.672934 -277.168864) (xy 83.673188 -277.169372) (xy 83.6867 -277.193215)
			(xy 83.705938 -277.244523) (xy 83.715729 -277.298438) (xy 83.716368 -277.325836) (xy 83.716368 -277.326344)
			(xy 84.04531 -277.326344) (xy 84.04927 -277.27729) (xy 84.061047 -277.229506) (xy 84.080338 -277.18423)
			(xy 84.106641 -277.142634) (xy 84.139276 -277.105797) (xy 84.177397 -277.074672) (xy 84.220018 -277.050065)
			(xy 84.266034 -277.032613) (xy 84.314253 -277.022769) (xy 84.363428 -277.020788) (xy 84.412283 -277.02672)
			(xy 84.459554 -277.040412) (xy 84.504016 -277.06151) (xy 84.544519 -277.089466) (xy 84.580012 -277.123558)
			(xy 84.609577 -277.162902) (xy 84.632448 -277.206479) (xy 84.648032 -277.25316) (xy 84.655927 -277.301737)
			(xy 84.656422 -277.326344) (xy 84.98511 -277.326344) (xy 84.98907 -277.27729) (xy 85.000847 -277.229506)
			(xy 85.020138 -277.18423) (xy 85.046441 -277.142634) (xy 85.079076 -277.105797) (xy 85.117197 -277.074672)
			(xy 85.159818 -277.050065) (xy 85.205834 -277.032613) (xy 85.254053 -277.022769) (xy 85.303228 -277.020788)
			(xy 85.352083 -277.02672) (xy 85.399354 -277.040412) (xy 85.443816 -277.06151) (xy 85.484319 -277.089466)
			(xy 85.519812 -277.123558) (xy 85.549377 -277.162902) (xy 85.572248 -277.206479) (xy 85.587832 -277.25316)
			(xy 85.595727 -277.301737) (xy 85.596222 -277.326344) (xy 85.925164 -277.326344) (xy 85.929124 -277.27729)
			(xy 85.940901 -277.229506) (xy 85.960192 -277.18423) (xy 85.986495 -277.142634) (xy 86.01913 -277.105797)
			(xy 86.057251 -277.074672) (xy 86.099872 -277.050065) (xy 86.145888 -277.032613) (xy 86.194107 -277.022769)
			(xy 86.243282 -277.020788) (xy 86.292137 -277.02672) (xy 86.339408 -277.040412) (xy 86.38387 -277.06151)
			(xy 86.424373 -277.089466) (xy 86.459866 -277.123558) (xy 86.489431 -277.162902) (xy 86.512302 -277.206479)
			(xy 86.527886 -277.25316) (xy 86.535781 -277.301737) (xy 86.536276 -277.326344) (xy 86.865218 -277.326344)
			(xy 86.869178 -277.27729) (xy 86.880955 -277.229506) (xy 86.900246 -277.18423) (xy 86.926549 -277.142634)
			(xy 86.959184 -277.105797) (xy 86.997305 -277.074672) (xy 87.039926 -277.050065) (xy 87.085942 -277.032613)
			(xy 87.134161 -277.022769) (xy 87.183336 -277.020788) (xy 87.232191 -277.02672) (xy 87.279462 -277.040412)
			(xy 87.323924 -277.06151) (xy 87.364427 -277.089466) (xy 87.39992 -277.123558) (xy 87.429485 -277.162902)
			(xy 87.452356 -277.206479) (xy 87.46794 -277.25316) (xy 87.475835 -277.301737) (xy 87.47633 -277.326344)
			(xy 87.805272 -277.326344) (xy 87.809232 -277.27729) (xy 87.821009 -277.229506) (xy 87.8403 -277.18423)
			(xy 87.866603 -277.142634) (xy 87.899238 -277.105797) (xy 87.937359 -277.074672) (xy 87.97998 -277.050065)
			(xy 88.025996 -277.032613) (xy 88.074215 -277.022769) (xy 88.12339 -277.020788) (xy 88.172245 -277.02672)
			(xy 88.219516 -277.040412) (xy 88.263978 -277.06151) (xy 88.304481 -277.089466) (xy 88.339974 -277.123558)
			(xy 88.369539 -277.162902) (xy 88.39241 -277.206479) (xy 88.407994 -277.25316) (xy 88.415889 -277.301737)
			(xy 88.416384 -277.326344) (xy 88.745326 -277.326344) (xy 88.749286 -277.27729) (xy 88.761063 -277.229506)
			(xy 88.780354 -277.18423) (xy 88.806657 -277.142634) (xy 88.839292 -277.105797) (xy 88.877413 -277.074672)
			(xy 88.920034 -277.050065) (xy 88.96605 -277.032613) (xy 89.014269 -277.022769) (xy 89.063444 -277.020788)
			(xy 89.112299 -277.02672) (xy 89.15957 -277.040412) (xy 89.204032 -277.06151) (xy 89.244535 -277.089466)
			(xy 89.280028 -277.123558) (xy 89.309593 -277.162902) (xy 89.332464 -277.206479) (xy 89.348048 -277.25316)
			(xy 89.355943 -277.301737) (xy 89.356438 -277.326344) (xy 89.685126 -277.326344) (xy 89.689086 -277.27729)
			(xy 89.700863 -277.229506) (xy 89.720154 -277.18423) (xy 89.746457 -277.142634) (xy 89.779092 -277.105797)
			(xy 89.817213 -277.074672) (xy 89.859834 -277.050065) (xy 89.90585 -277.032613) (xy 89.954069 -277.022769)
			(xy 90.003244 -277.020788) (xy 90.052099 -277.02672) (xy 90.09937 -277.040412) (xy 90.143832 -277.06151)
			(xy 90.184335 -277.089466) (xy 90.219828 -277.123558) (xy 90.249393 -277.162902) (xy 90.272264 -277.206479)
			(xy 90.287848 -277.25316) (xy 90.295743 -277.301737) (xy 90.296238 -277.326344) (xy 90.614749 -277.326344)
			(xy 90.618844 -277.275616) (xy 90.631023 -277.226202) (xy 90.650971 -277.179382) (xy 90.678172 -277.136368)
			(xy 90.71192 -277.098274) (xy 90.751342 -277.066087) (xy 90.795416 -277.040641) (xy 90.843002 -277.022594)
			(xy 90.892866 -277.012414) (xy 90.943718 -277.010365) (xy 90.994239 -277.016499) (xy 91.043123 -277.030659)
			(xy 91.089102 -277.052476) (xy 91.130986 -277.081386) (xy 91.16769 -277.116641) (xy 91.198263 -277.157327)
			(xy 91.221914 -277.20239) (xy 91.23803 -277.250664) (xy 91.246194 -277.300898) (xy 91.246706 -277.326344)
			(xy 91.565234 -277.326344) (xy 91.569194 -277.27729) (xy 91.580971 -277.229506) (xy 91.600262 -277.18423)
			(xy 91.626565 -277.142634) (xy 91.6592 -277.105797) (xy 91.697321 -277.074672) (xy 91.739942 -277.050065)
			(xy 91.785958 -277.032613) (xy 91.834177 -277.022769) (xy 91.883352 -277.020788) (xy 91.932207 -277.02672)
			(xy 91.979478 -277.040412) (xy 92.02394 -277.06151) (xy 92.064443 -277.089466) (xy 92.099936 -277.123558)
			(xy 92.129501 -277.162902) (xy 92.152372 -277.206479) (xy 92.167956 -277.25316) (xy 92.175851 -277.301737)
			(xy 92.176346 -277.326344) (xy 92.494857 -277.326344) (xy 92.498952 -277.275616) (xy 92.511131 -277.226202)
			(xy 92.531079 -277.179382) (xy 92.55828 -277.136368) (xy 92.592028 -277.098274) (xy 92.63145 -277.066087)
			(xy 92.675524 -277.040641) (xy 92.72311 -277.022594) (xy 92.772974 -277.012414) (xy 92.823826 -277.010365)
			(xy 92.874347 -277.016499) (xy 92.923231 -277.030659) (xy 92.96921 -277.052476) (xy 93.011094 -277.081386)
			(xy 93.047798 -277.116641) (xy 93.078371 -277.157327) (xy 93.102022 -277.20239) (xy 93.118138 -277.250664)
			(xy 93.126302 -277.300898) (xy 93.126814 -277.326344) (xy 93.445342 -277.326344) (xy 93.449302 -277.27729)
			(xy 93.461079 -277.229506) (xy 93.48037 -277.18423) (xy 93.506673 -277.142634) (xy 93.539308 -277.105797)
			(xy 93.577429 -277.074672) (xy 93.62005 -277.050065) (xy 93.666066 -277.032613) (xy 93.714285 -277.022769)
			(xy 93.76346 -277.020788) (xy 93.812315 -277.02672) (xy 93.859586 -277.040412) (xy 93.904048 -277.06151)
			(xy 93.944551 -277.089466) (xy 93.980044 -277.123558) (xy 94.009609 -277.162902) (xy 94.03248 -277.206479)
			(xy 94.048064 -277.25316) (xy 94.055959 -277.301737) (xy 94.056454 -277.326344) (xy 94.374711 -277.326344)
			(xy 94.378806 -277.275616) (xy 94.390985 -277.226202) (xy 94.410933 -277.179382) (xy 94.438134 -277.136368)
			(xy 94.471882 -277.098274) (xy 94.511304 -277.066087) (xy 94.555378 -277.040641) (xy 94.602964 -277.022594)
			(xy 94.652828 -277.012414) (xy 94.70368 -277.010365) (xy 94.754201 -277.016499) (xy 94.803085 -277.030659)
			(xy 94.849064 -277.052476) (xy 94.890948 -277.081386) (xy 94.927652 -277.116641) (xy 94.958225 -277.157327)
			(xy 94.981876 -277.20239) (xy 94.997992 -277.250664) (xy 95.006156 -277.300898) (xy 95.006668 -277.326344)
			(xy 95.314765 -277.326344) (xy 95.31886 -277.275616) (xy 95.331039 -277.226202) (xy 95.350987 -277.179382)
			(xy 95.378188 -277.136368) (xy 95.411936 -277.098274) (xy 95.451358 -277.066087) (xy 95.495432 -277.040641)
			(xy 95.543018 -277.022594) (xy 95.592882 -277.012414) (xy 95.643734 -277.010365) (xy 95.694255 -277.016499)
			(xy 95.743139 -277.030659) (xy 95.789118 -277.052476) (xy 95.831002 -277.081386) (xy 95.867706 -277.116641)
			(xy 95.898279 -277.157327) (xy 95.92193 -277.20239) (xy 95.938046 -277.250664) (xy 95.94621 -277.300898)
			(xy 95.946722 -277.326344) (xy 95.94621 -277.35179) (xy 95.938046 -277.402024) (xy 95.92193 -277.450298)
			(xy 95.898279 -277.495361) (xy 95.867706 -277.536047) (xy 95.831002 -277.571302) (xy 95.789118 -277.600212)
			(xy 95.743139 -277.622029) (xy 95.694255 -277.636189) (xy 95.643734 -277.642323) (xy 95.592882 -277.640274)
			(xy 95.543018 -277.630094) (xy 95.495432 -277.612047) (xy 95.451358 -277.586601) (xy 95.411936 -277.554414)
			(xy 95.378188 -277.51632) (xy 95.350987 -277.473306) (xy 95.331039 -277.426486) (xy 95.31886 -277.377072)
			(xy 95.314765 -277.326344) (xy 95.006668 -277.326344) (xy 95.006156 -277.35179) (xy 94.997992 -277.402024)
			(xy 94.981876 -277.450298) (xy 94.958225 -277.495361) (xy 94.927652 -277.536047) (xy 94.890948 -277.571302)
			(xy 94.849064 -277.600212) (xy 94.803085 -277.622029) (xy 94.754201 -277.636189) (xy 94.70368 -277.642323)
			(xy 94.652828 -277.640274) (xy 94.602964 -277.630094) (xy 94.555378 -277.612047) (xy 94.511304 -277.586601)
			(xy 94.471882 -277.554414) (xy 94.438134 -277.51632) (xy 94.410933 -277.473306) (xy 94.390985 -277.426486)
			(xy 94.378806 -277.377072) (xy 94.374711 -277.326344) (xy 94.056454 -277.326344) (xy 94.055959 -277.350951)
			(xy 94.048064 -277.399528) (xy 94.03248 -277.446209) (xy 94.009609 -277.489786) (xy 93.980044 -277.52913)
			(xy 93.944551 -277.563222) (xy 93.904048 -277.591178) (xy 93.859586 -277.612276) (xy 93.812315 -277.625968)
			(xy 93.76346 -277.6319) (xy 93.714285 -277.629919) (xy 93.666066 -277.620075) (xy 93.62005 -277.602623)
			(xy 93.577429 -277.578016) (xy 93.539308 -277.546891) (xy 93.506673 -277.510054) (xy 93.48037 -277.468458)
			(xy 93.461079 -277.423182) (xy 93.449302 -277.375398) (xy 93.445342 -277.326344) (xy 93.126814 -277.326344)
			(xy 93.126302 -277.35179) (xy 93.118138 -277.402024) (xy 93.102022 -277.450298) (xy 93.078371 -277.495361)
			(xy 93.047798 -277.536047) (xy 93.011094 -277.571302) (xy 92.96921 -277.600212) (xy 92.923231 -277.622029)
			(xy 92.874347 -277.636189) (xy 92.823826 -277.642323) (xy 92.772974 -277.640274) (xy 92.72311 -277.630094)
			(xy 92.675524 -277.612047) (xy 92.63145 -277.586601) (xy 92.592028 -277.554414) (xy 92.55828 -277.51632)
			(xy 92.531079 -277.473306) (xy 92.511131 -277.426486) (xy 92.498952 -277.377072) (xy 92.494857 -277.326344)
			(xy 92.176346 -277.326344) (xy 92.175851 -277.350951) (xy 92.167956 -277.399528) (xy 92.152372 -277.446209)
			(xy 92.129501 -277.489786) (xy 92.099936 -277.52913) (xy 92.064443 -277.563222) (xy 92.02394 -277.591178)
			(xy 91.979478 -277.612276) (xy 91.932207 -277.625968) (xy 91.883352 -277.6319) (xy 91.834177 -277.629919)
			(xy 91.785958 -277.620075) (xy 91.739942 -277.602623) (xy 91.697321 -277.578016) (xy 91.6592 -277.546891)
			(xy 91.626565 -277.510054) (xy 91.600262 -277.468458) (xy 91.580971 -277.423182) (xy 91.569194 -277.375398)
			(xy 91.565234 -277.326344) (xy 91.246706 -277.326344) (xy 91.246194 -277.35179) (xy 91.23803 -277.402024)
			(xy 91.221914 -277.450298) (xy 91.198263 -277.495361) (xy 91.16769 -277.536047) (xy 91.130986 -277.571302)
			(xy 91.089102 -277.600212) (xy 91.043123 -277.622029) (xy 90.994239 -277.636189) (xy 90.943718 -277.642323)
			(xy 90.892866 -277.640274) (xy 90.843002 -277.630094) (xy 90.795416 -277.612047) (xy 90.751342 -277.586601)
			(xy 90.71192 -277.554414) (xy 90.678172 -277.51632) (xy 90.650971 -277.473306) (xy 90.631023 -277.426486)
			(xy 90.618844 -277.377072) (xy 90.614749 -277.326344) (xy 90.296238 -277.326344) (xy 90.295743 -277.350951)
			(xy 90.287848 -277.399528) (xy 90.272264 -277.446209) (xy 90.249393 -277.489786) (xy 90.219828 -277.52913)
			(xy 90.184335 -277.563222) (xy 90.143832 -277.591178) (xy 90.09937 -277.612276) (xy 90.052099 -277.625968)
			(xy 90.003244 -277.6319) (xy 89.954069 -277.629919) (xy 89.90585 -277.620075) (xy 89.859834 -277.602623)
			(xy 89.817213 -277.578016) (xy 89.779092 -277.546891) (xy 89.746457 -277.510054) (xy 89.720154 -277.468458)
			(xy 89.700863 -277.423182) (xy 89.689086 -277.375398) (xy 89.685126 -277.326344) (xy 89.356438 -277.326344)
			(xy 89.355943 -277.350951) (xy 89.348048 -277.399528) (xy 89.332464 -277.446209) (xy 89.309593 -277.489786)
			(xy 89.280028 -277.52913) (xy 89.244535 -277.563222) (xy 89.204032 -277.591178) (xy 89.15957 -277.612276)
			(xy 89.112299 -277.625968) (xy 89.063444 -277.6319) (xy 89.014269 -277.629919) (xy 88.96605 -277.620075)
			(xy 88.920034 -277.602623) (xy 88.877413 -277.578016) (xy 88.839292 -277.546891) (xy 88.806657 -277.510054)
			(xy 88.780354 -277.468458) (xy 88.761063 -277.423182) (xy 88.749286 -277.375398) (xy 88.745326 -277.326344)
			(xy 88.416384 -277.326344) (xy 88.415889 -277.350951) (xy 88.407994 -277.399528) (xy 88.39241 -277.446209)
			(xy 88.369539 -277.489786) (xy 88.339974 -277.52913) (xy 88.304481 -277.563222) (xy 88.263978 -277.591178)
			(xy 88.219516 -277.612276) (xy 88.172245 -277.625968) (xy 88.12339 -277.6319) (xy 88.074215 -277.629919)
			(xy 88.025996 -277.620075) (xy 87.97998 -277.602623) (xy 87.937359 -277.578016) (xy 87.899238 -277.546891)
			(xy 87.866603 -277.510054) (xy 87.8403 -277.468458) (xy 87.821009 -277.423182) (xy 87.809232 -277.375398)
			(xy 87.805272 -277.326344) (xy 87.47633 -277.326344) (xy 87.475835 -277.350951) (xy 87.46794 -277.399528)
			(xy 87.452356 -277.446209) (xy 87.429485 -277.489786) (xy 87.39992 -277.52913) (xy 87.364427 -277.563222)
			(xy 87.323924 -277.591178) (xy 87.279462 -277.612276) (xy 87.232191 -277.625968) (xy 87.183336 -277.6319)
			(xy 87.134161 -277.629919) (xy 87.085942 -277.620075) (xy 87.039926 -277.602623) (xy 86.997305 -277.578016)
			(xy 86.959184 -277.546891) (xy 86.926549 -277.510054) (xy 86.900246 -277.468458) (xy 86.880955 -277.423182)
			(xy 86.869178 -277.375398) (xy 86.865218 -277.326344) (xy 86.536276 -277.326344) (xy 86.535781 -277.350951)
			(xy 86.527886 -277.399528) (xy 86.512302 -277.446209) (xy 86.489431 -277.489786) (xy 86.459866 -277.52913)
			(xy 86.424373 -277.563222) (xy 86.38387 -277.591178) (xy 86.339408 -277.612276) (xy 86.292137 -277.625968)
			(xy 86.243282 -277.6319) (xy 86.194107 -277.629919) (xy 86.145888 -277.620075) (xy 86.099872 -277.602623)
			(xy 86.057251 -277.578016) (xy 86.01913 -277.546891) (xy 85.986495 -277.510054) (xy 85.960192 -277.468458)
			(xy 85.940901 -277.423182) (xy 85.929124 -277.375398) (xy 85.925164 -277.326344) (xy 85.596222 -277.326344)
			(xy 85.595727 -277.350951) (xy 85.587832 -277.399528) (xy 85.572248 -277.446209) (xy 85.549377 -277.489786)
			(xy 85.519812 -277.52913) (xy 85.484319 -277.563222) (xy 85.443816 -277.591178) (xy 85.399354 -277.612276)
			(xy 85.352083 -277.625968) (xy 85.303228 -277.6319) (xy 85.254053 -277.629919) (xy 85.205834 -277.620075)
			(xy 85.159818 -277.602623) (xy 85.117197 -277.578016) (xy 85.079076 -277.546891) (xy 85.046441 -277.510054)
			(xy 85.020138 -277.468458) (xy 85.000847 -277.423182) (xy 84.98907 -277.375398) (xy 84.98511 -277.326344)
			(xy 84.656422 -277.326344) (xy 84.655927 -277.350951) (xy 84.648032 -277.399528) (xy 84.632448 -277.446209)
			(xy 84.609577 -277.489786) (xy 84.580012 -277.52913) (xy 84.544519 -277.563222) (xy 84.504016 -277.591178)
			(xy 84.459554 -277.612276) (xy 84.412283 -277.625968) (xy 84.363428 -277.6319) (xy 84.314253 -277.629919)
			(xy 84.266034 -277.620075) (xy 84.220018 -277.602623) (xy 84.177397 -277.578016) (xy 84.139276 -277.546891)
			(xy 84.106641 -277.510054) (xy 84.080338 -277.468458) (xy 84.061047 -277.423182) (xy 84.04927 -277.375398)
			(xy 84.04531 -277.326344) (xy 83.716368 -277.326344) (xy 83.716368 -277.332186) (xy 83.71535 -277.357877)
			(xy 83.705778 -277.408389) (xy 83.687877 -277.456584) (xy 83.662156 -277.501098) (xy 83.62934 -277.540674)
			(xy 83.590357 -277.574192) (xy 83.546309 -277.600706) (xy 83.522566 -277.61057) (xy 83.512152 -277.614888)
			(xy 83.503516 -277.627588) (xy 83.499486 -277.633994) (xy 83.495096 -277.648471) (xy 83.49488 -277.656036)
			(xy 83.49488 -277.778464) (xy 83.495143 -277.784072) (xy 83.497843 -277.794965) (xy 83.500214 -277.800054)
			(xy 83.504786 -277.807928) (xy 83.508735 -277.812785) (xy 83.518492 -277.82062) (xy 83.52409 -277.823422)
			(xy 83.524344 -277.823676) (xy 83.605116 -277.861014) (xy 83.618832 -277.864316) (xy 83.631278 -277.864824)
			(xy 83.648042 -277.858474) (xy 83.6549 -277.855172) (xy 83.665314 -277.84933) (xy 83.6676 -277.847552)
			(xy 83.668616 -277.84679) (xy 83.66887 -277.846536) (xy 83.689158 -277.831463) (xy 83.733639 -277.807473)
			(xy 83.781454 -277.791108) (xy 83.831307 -277.782811) (xy 83.856576 -277.782274) (xy 83.882413 -277.782822)
			(xy 83.933347 -277.791536) (xy 83.982086 -277.808702) (xy 84.027239 -277.83383) (xy 84.067516 -277.866203)
			(xy 84.101767 -277.904895) (xy 84.129013 -277.948803) (xy 84.139278 -277.97252) (xy 84.142834 -277.979124)
			(xy 84.143088 -277.979632) (xy 84.156621 -278.003512) (xy 84.175882 -278.054904) (xy 84.185664 -278.108908)
			(xy 84.186268 -278.13635) (xy 84.51521 -278.13635) (xy 84.51917 -278.087296) (xy 84.530947 -278.039512)
			(xy 84.550238 -277.994236) (xy 84.576541 -277.95264) (xy 84.609176 -277.915803) (xy 84.647297 -277.884678)
			(xy 84.689918 -277.860071) (xy 84.735934 -277.842619) (xy 84.784153 -277.832775) (xy 84.833328 -277.830794)
			(xy 84.882183 -277.836726) (xy 84.929454 -277.850418) (xy 84.973916 -277.871516) (xy 85.014419 -277.899472)
			(xy 85.049912 -277.933564) (xy 85.079477 -277.972908) (xy 85.102348 -278.016485) (xy 85.117932 -278.063166)
			(xy 85.125827 -278.111743) (xy 85.126322 -278.13635) (xy 85.455264 -278.13635) (xy 85.459224 -278.087296)
			(xy 85.471001 -278.039512) (xy 85.490292 -277.994236) (xy 85.516595 -277.95264) (xy 85.54923 -277.915803)
			(xy 85.587351 -277.884678) (xy 85.629972 -277.860071) (xy 85.675988 -277.842619) (xy 85.724207 -277.832775)
			(xy 85.773382 -277.830794) (xy 85.822237 -277.836726) (xy 85.869508 -277.850418) (xy 85.91397 -277.871516)
			(xy 85.954473 -277.899472) (xy 85.989966 -277.933564) (xy 86.019531 -277.972908) (xy 86.042402 -278.016485)
			(xy 86.057986 -278.063166) (xy 86.065881 -278.111743) (xy 86.066376 -278.13635) (xy 87.335118 -278.13635)
			(xy 87.339078 -278.087296) (xy 87.350855 -278.039512) (xy 87.370146 -277.994236) (xy 87.396449 -277.95264)
			(xy 87.429084 -277.915803) (xy 87.467205 -277.884678) (xy 87.509826 -277.860071) (xy 87.555842 -277.842619)
			(xy 87.604061 -277.832775) (xy 87.653236 -277.830794) (xy 87.702091 -277.836726) (xy 87.749362 -277.850418)
			(xy 87.793824 -277.871516) (xy 87.834327 -277.899472) (xy 87.86982 -277.933564) (xy 87.899385 -277.972908)
			(xy 87.922256 -278.016485) (xy 87.93784 -278.063166) (xy 87.945735 -278.111743) (xy 87.94623 -278.13635)
			(xy 88.275172 -278.13635) (xy 88.279132 -278.087296) (xy 88.290909 -278.039512) (xy 88.3102 -277.994236)
			(xy 88.336503 -277.95264) (xy 88.369138 -277.915803) (xy 88.407259 -277.884678) (xy 88.44988 -277.860071)
			(xy 88.495896 -277.842619) (xy 88.544115 -277.832775) (xy 88.59329 -277.830794) (xy 88.642145 -277.836726)
			(xy 88.689416 -277.850418) (xy 88.733878 -277.871516) (xy 88.774381 -277.899472) (xy 88.809874 -277.933564)
			(xy 88.839439 -277.972908) (xy 88.86231 -278.016485) (xy 88.877894 -278.063166) (xy 88.885789 -278.111743)
			(xy 88.886284 -278.13635) (xy 89.215226 -278.13635) (xy 89.219186 -278.087296) (xy 89.230963 -278.039512)
			(xy 89.250254 -277.994236) (xy 89.276557 -277.95264) (xy 89.309192 -277.915803) (xy 89.347313 -277.884678)
			(xy 89.389934 -277.860071) (xy 89.43595 -277.842619) (xy 89.484169 -277.832775) (xy 89.533344 -277.830794)
			(xy 89.582199 -277.836726) (xy 89.62947 -277.850418) (xy 89.673932 -277.871516) (xy 89.714435 -277.899472)
			(xy 89.749928 -277.933564) (xy 89.779493 -277.972908) (xy 89.802364 -278.016485) (xy 89.817948 -278.063166)
			(xy 89.825843 -278.111743) (xy 89.826338 -278.13635) (xy 90.15528 -278.13635) (xy 90.15924 -278.087296)
			(xy 90.171017 -278.039512) (xy 90.190308 -277.994236) (xy 90.216611 -277.95264) (xy 90.249246 -277.915803)
			(xy 90.287367 -277.884678) (xy 90.329988 -277.860071) (xy 90.376004 -277.842619) (xy 90.424223 -277.832775)
			(xy 90.473398 -277.830794) (xy 90.522253 -277.836726) (xy 90.569524 -277.850418) (xy 90.613986 -277.871516)
			(xy 90.654489 -277.899472) (xy 90.689982 -277.933564) (xy 90.719547 -277.972908) (xy 90.742418 -278.016485)
			(xy 90.758002 -278.063166) (xy 90.765897 -278.111743) (xy 90.766392 -278.13635) (xy 91.084903 -278.13635)
			(xy 91.088998 -278.085622) (xy 91.101177 -278.036208) (xy 91.121125 -277.989388) (xy 91.148326 -277.946374)
			(xy 91.182074 -277.90828) (xy 91.221496 -277.876093) (xy 91.26557 -277.850647) (xy 91.313156 -277.8326)
			(xy 91.36302 -277.82242) (xy 91.413872 -277.820371) (xy 91.464393 -277.826505) (xy 91.513277 -277.840665)
			(xy 91.559256 -277.862482) (xy 91.60114 -277.891392) (xy 91.637844 -277.926647) (xy 91.668417 -277.967333)
			(xy 91.692068 -278.012396) (xy 91.708184 -278.06067) (xy 91.716348 -278.110904) (xy 91.71686 -278.13635)
			(xy 92.024703 -278.13635) (xy 92.028798 -278.085622) (xy 92.040977 -278.036208) (xy 92.060925 -277.989388)
			(xy 92.088126 -277.946374) (xy 92.121874 -277.90828) (xy 92.161296 -277.876093) (xy 92.20537 -277.850647)
			(xy 92.252956 -277.8326) (xy 92.30282 -277.82242) (xy 92.353672 -277.820371) (xy 92.404193 -277.826505)
			(xy 92.453077 -277.840665) (xy 92.499056 -277.862482) (xy 92.54094 -277.891392) (xy 92.577644 -277.926647)
			(xy 92.608217 -277.967333) (xy 92.631868 -278.012396) (xy 92.647984 -278.06067) (xy 92.656148 -278.110904)
			(xy 92.65666 -278.13635) (xy 93.904811 -278.13635) (xy 93.908906 -278.085622) (xy 93.921085 -278.036208)
			(xy 93.941033 -277.989388) (xy 93.968234 -277.946374) (xy 94.001982 -277.90828) (xy 94.041404 -277.876093)
			(xy 94.085478 -277.850647) (xy 94.133064 -277.8326) (xy 94.182928 -277.82242) (xy 94.23378 -277.820371)
			(xy 94.284301 -277.826505) (xy 94.333185 -277.840665) (xy 94.379164 -277.862482) (xy 94.421048 -277.891392)
			(xy 94.457752 -277.926647) (xy 94.488325 -277.967333) (xy 94.511976 -278.012396) (xy 94.528092 -278.06067)
			(xy 94.536256 -278.110904) (xy 94.536768 -278.13635) (xy 94.855296 -278.13635) (xy 94.859256 -278.087296)
			(xy 94.871033 -278.039512) (xy 94.890324 -277.994236) (xy 94.916627 -277.95264) (xy 94.949262 -277.915803)
			(xy 94.987383 -277.884678) (xy 95.030004 -277.860071) (xy 95.07602 -277.842619) (xy 95.124239 -277.832775)
			(xy 95.173414 -277.830794) (xy 95.222269 -277.836726) (xy 95.26954 -277.850418) (xy 95.314002 -277.871516)
			(xy 95.354505 -277.899472) (xy 95.389998 -277.933564) (xy 95.419563 -277.972908) (xy 95.442434 -278.016485)
			(xy 95.458018 -278.063166) (xy 95.465913 -278.111743) (xy 95.466408 -278.13635) (xy 95.784919 -278.13635)
			(xy 95.789014 -278.085622) (xy 95.801193 -278.036208) (xy 95.821141 -277.989388) (xy 95.848342 -277.946374)
			(xy 95.88209 -277.90828) (xy 95.921512 -277.876093) (xy 95.965586 -277.850647) (xy 96.013172 -277.8326)
			(xy 96.063036 -277.82242) (xy 96.113888 -277.820371) (xy 96.164409 -277.826505) (xy 96.213293 -277.840665)
			(xy 96.259272 -277.862482) (xy 96.301156 -277.891392) (xy 96.33786 -277.926647) (xy 96.368433 -277.967333)
			(xy 96.392084 -278.012396) (xy 96.4082 -278.06067) (xy 96.416364 -278.110904) (xy 96.416876 -278.13635)
			(xy 96.416364 -278.161796) (xy 96.4082 -278.21203) (xy 96.392084 -278.260304) (xy 96.368433 -278.305367)
			(xy 96.33786 -278.346053) (xy 96.301156 -278.381308) (xy 96.259272 -278.410218) (xy 96.213293 -278.432035)
			(xy 96.164409 -278.446195) (xy 96.113888 -278.452329) (xy 96.063036 -278.45028) (xy 96.013172 -278.4401)
			(xy 95.965586 -278.422053) (xy 95.921512 -278.396607) (xy 95.88209 -278.36442) (xy 95.848342 -278.326326)
			(xy 95.821141 -278.283312) (xy 95.801193 -278.236492) (xy 95.789014 -278.187078) (xy 95.784919 -278.13635)
			(xy 95.466408 -278.13635) (xy 95.465913 -278.160957) (xy 95.458018 -278.209534) (xy 95.442434 -278.256215)
			(xy 95.419563 -278.299792) (xy 95.389998 -278.339136) (xy 95.354505 -278.373228) (xy 95.314002 -278.401184)
			(xy 95.26954 -278.422282) (xy 95.222269 -278.435974) (xy 95.173414 -278.441906) (xy 95.124239 -278.439925)
			(xy 95.07602 -278.430081) (xy 95.030004 -278.412629) (xy 94.987383 -278.388022) (xy 94.949262 -278.356897)
			(xy 94.916627 -278.32006) (xy 94.890324 -278.278464) (xy 94.871033 -278.233188) (xy 94.859256 -278.185404)
			(xy 94.855296 -278.13635) (xy 94.536768 -278.13635) (xy 94.536256 -278.161796) (xy 94.528092 -278.21203)
			(xy 94.511976 -278.260304) (xy 94.488325 -278.305367) (xy 94.457752 -278.346053) (xy 94.421048 -278.381308)
			(xy 94.379164 -278.410218) (xy 94.333185 -278.432035) (xy 94.284301 -278.446195) (xy 94.23378 -278.452329)
			(xy 94.182928 -278.45028) (xy 94.133064 -278.4401) (xy 94.085478 -278.422053) (xy 94.041404 -278.396607)
			(xy 94.001982 -278.36442) (xy 93.968234 -278.326326) (xy 93.941033 -278.283312) (xy 93.921085 -278.236492)
			(xy 93.908906 -278.187078) (xy 93.904811 -278.13635) (xy 92.65666 -278.13635) (xy 92.656148 -278.161796)
			(xy 92.647984 -278.21203) (xy 92.631868 -278.260304) (xy 92.608217 -278.305367) (xy 92.577644 -278.346053)
			(xy 92.54094 -278.381308) (xy 92.499056 -278.410218) (xy 92.453077 -278.432035) (xy 92.404193 -278.446195)
			(xy 92.353672 -278.452329) (xy 92.30282 -278.45028) (xy 92.252956 -278.4401) (xy 92.20537 -278.422053)
			(xy 92.161296 -278.396607) (xy 92.121874 -278.36442) (xy 92.088126 -278.326326) (xy 92.060925 -278.283312)
			(xy 92.040977 -278.236492) (xy 92.028798 -278.187078) (xy 92.024703 -278.13635) (xy 91.71686 -278.13635)
			(xy 91.716348 -278.161796) (xy 91.708184 -278.21203) (xy 91.692068 -278.260304) (xy 91.668417 -278.305367)
			(xy 91.637844 -278.346053) (xy 91.60114 -278.381308) (xy 91.559256 -278.410218) (xy 91.513277 -278.432035)
			(xy 91.464393 -278.446195) (xy 91.413872 -278.452329) (xy 91.36302 -278.45028) (xy 91.313156 -278.4401)
			(xy 91.26557 -278.422053) (xy 91.221496 -278.396607) (xy 91.182074 -278.36442) (xy 91.148326 -278.326326)
			(xy 91.121125 -278.283312) (xy 91.101177 -278.236492) (xy 91.088998 -278.187078) (xy 91.084903 -278.13635)
			(xy 90.766392 -278.13635) (xy 90.765897 -278.160957) (xy 90.758002 -278.209534) (xy 90.742418 -278.256215)
			(xy 90.719547 -278.299792) (xy 90.689982 -278.339136) (xy 90.654489 -278.373228) (xy 90.613986 -278.401184)
			(xy 90.569524 -278.422282) (xy 90.522253 -278.435974) (xy 90.473398 -278.441906) (xy 90.424223 -278.439925)
			(xy 90.376004 -278.430081) (xy 90.329988 -278.412629) (xy 90.287367 -278.388022) (xy 90.249246 -278.356897)
			(xy 90.216611 -278.32006) (xy 90.190308 -278.278464) (xy 90.171017 -278.233188) (xy 90.15924 -278.185404)
			(xy 90.15528 -278.13635) (xy 89.826338 -278.13635) (xy 89.825843 -278.160957) (xy 89.817948 -278.209534)
			(xy 89.802364 -278.256215) (xy 89.779493 -278.299792) (xy 89.749928 -278.339136) (xy 89.714435 -278.373228)
			(xy 89.673932 -278.401184) (xy 89.62947 -278.422282) (xy 89.582199 -278.435974) (xy 89.533344 -278.441906)
			(xy 89.484169 -278.439925) (xy 89.43595 -278.430081) (xy 89.389934 -278.412629) (xy 89.347313 -278.388022)
			(xy 89.309192 -278.356897) (xy 89.276557 -278.32006) (xy 89.250254 -278.278464) (xy 89.230963 -278.233188)
			(xy 89.219186 -278.185404) (xy 89.215226 -278.13635) (xy 88.886284 -278.13635) (xy 88.885789 -278.160957)
			(xy 88.877894 -278.209534) (xy 88.86231 -278.256215) (xy 88.839439 -278.299792) (xy 88.809874 -278.339136)
			(xy 88.774381 -278.373228) (xy 88.733878 -278.401184) (xy 88.689416 -278.422282) (xy 88.642145 -278.435974)
			(xy 88.59329 -278.441906) (xy 88.544115 -278.439925) (xy 88.495896 -278.430081) (xy 88.44988 -278.412629)
			(xy 88.407259 -278.388022) (xy 88.369138 -278.356897) (xy 88.336503 -278.32006) (xy 88.3102 -278.278464)
			(xy 88.290909 -278.233188) (xy 88.279132 -278.185404) (xy 88.275172 -278.13635) (xy 87.94623 -278.13635)
			(xy 87.945735 -278.160957) (xy 87.93784 -278.209534) (xy 87.922256 -278.256215) (xy 87.899385 -278.299792)
			(xy 87.86982 -278.339136) (xy 87.834327 -278.373228) (xy 87.793824 -278.401184) (xy 87.749362 -278.422282)
			(xy 87.702091 -278.435974) (xy 87.653236 -278.441906) (xy 87.604061 -278.439925) (xy 87.555842 -278.430081)
			(xy 87.509826 -278.412629) (xy 87.467205 -278.388022) (xy 87.429084 -278.356897) (xy 87.396449 -278.32006)
			(xy 87.370146 -278.278464) (xy 87.350855 -278.233188) (xy 87.339078 -278.185404) (xy 87.335118 -278.13635)
			(xy 86.066376 -278.13635) (xy 86.065881 -278.160957) (xy 86.057986 -278.209534) (xy 86.042402 -278.256215)
			(xy 86.019531 -278.299792) (xy 85.989966 -278.339136) (xy 85.954473 -278.373228) (xy 85.91397 -278.401184)
			(xy 85.869508 -278.422282) (xy 85.822237 -278.435974) (xy 85.773382 -278.441906) (xy 85.724207 -278.439925)
			(xy 85.675988 -278.430081) (xy 85.629972 -278.412629) (xy 85.587351 -278.388022) (xy 85.54923 -278.356897)
			(xy 85.516595 -278.32006) (xy 85.490292 -278.278464) (xy 85.471001 -278.233188) (xy 85.459224 -278.185404)
			(xy 85.455264 -278.13635) (xy 85.126322 -278.13635) (xy 85.125827 -278.160957) (xy 85.117932 -278.209534)
			(xy 85.102348 -278.256215) (xy 85.079477 -278.299792) (xy 85.049912 -278.339136) (xy 85.014419 -278.373228)
			(xy 84.973916 -278.401184) (xy 84.929454 -278.422282) (xy 84.882183 -278.435974) (xy 84.833328 -278.441906)
			(xy 84.784153 -278.439925) (xy 84.735934 -278.430081) (xy 84.689918 -278.412629) (xy 84.647297 -278.388022)
			(xy 84.609176 -278.356897) (xy 84.576541 -278.32006) (xy 84.550238 -278.278464) (xy 84.530947 -278.233188)
			(xy 84.51917 -278.185404) (xy 84.51521 -278.13635) (xy 84.186268 -278.13635) (xy 84.185794 -278.160338)
			(xy 84.178281 -278.207721) (xy 84.163449 -278.253346) (xy 84.141662 -278.296088) (xy 84.113457 -278.334897)
			(xy 84.079528 -278.368815) (xy 84.040712 -278.397009) (xy 83.997962 -278.418783) (xy 83.952333 -278.433602)
			(xy 83.904948 -278.441101) (xy 83.88096 -278.441658) (xy 83.85457 -278.441106) (xy 83.802574 -278.432045)
			(xy 83.75291 -278.414182) (xy 83.707054 -278.388049) (xy 83.666373 -278.354423) (xy 83.648804 -278.334724)
			(xy 83.627468 -278.309578) (xy 83.62569 -278.309578) (xy 83.621481 -278.309655) (xy 83.613181 -278.311063)
			(xy 83.60918 -278.312372) (xy 83.521804 -278.352758) (xy 83.51402 -278.357289) (xy 83.502024 -278.370708)
			(xy 83.495429 -278.387456) (xy 83.49488 -278.396446) (xy 83.49488 -278.565356) (xy 83.49491 -278.569492)
			(xy 83.49618 -278.577666) (xy 83.49742 -278.581612) (xy 83.502246 -278.591772) (xy 83.515708 -278.612854)
			(xy 83.519211 -278.618114) (xy 83.528338 -278.626848) (xy 83.533742 -278.630126) (xy 83.533996 -278.630126)
			(xy 83.555755 -278.642707) (xy 83.595198 -278.673854) (xy 83.612482 -278.692102) (xy 83.630123 -278.712301)
			(xy 83.658734 -278.757656) (xy 83.669378 -278.782272) (xy 83.672934 -278.788876) (xy 83.673188 -278.789384)
			(xy 83.686699 -278.813227) (xy 83.705935 -278.864535) (xy 83.715723 -278.91845) (xy 83.716368 -278.945848)
			(xy 83.716368 -278.946356) (xy 84.04531 -278.946356) (xy 84.04927 -278.897302) (xy 84.061047 -278.849518)
			(xy 84.080338 -278.804242) (xy 84.106641 -278.762646) (xy 84.139276 -278.725809) (xy 84.177397 -278.694684)
			(xy 84.220018 -278.670077) (xy 84.266034 -278.652625) (xy 84.314253 -278.642781) (xy 84.363428 -278.6408)
			(xy 84.412283 -278.646732) (xy 84.459554 -278.660424) (xy 84.504016 -278.681522) (xy 84.544519 -278.709478)
			(xy 84.580012 -278.74357) (xy 84.609577 -278.782914) (xy 84.632448 -278.826491) (xy 84.648032 -278.873172)
			(xy 84.655927 -278.921749) (xy 84.656422 -278.946356) (xy 84.98511 -278.946356) (xy 84.98907 -278.897302)
			(xy 85.000847 -278.849518) (xy 85.020138 -278.804242) (xy 85.046441 -278.762646) (xy 85.079076 -278.725809)
			(xy 85.117197 -278.694684) (xy 85.159818 -278.670077) (xy 85.205834 -278.652625) (xy 85.254053 -278.642781)
			(xy 85.303228 -278.6408) (xy 85.352083 -278.646732) (xy 85.399354 -278.660424) (xy 85.443816 -278.681522)
			(xy 85.484319 -278.709478) (xy 85.519812 -278.74357) (xy 85.549377 -278.782914) (xy 85.572248 -278.826491)
			(xy 85.587832 -278.873172) (xy 85.595727 -278.921749) (xy 85.596222 -278.946356) (xy 85.925164 -278.946356)
			(xy 85.929124 -278.897302) (xy 85.940901 -278.849518) (xy 85.960192 -278.804242) (xy 85.986495 -278.762646)
			(xy 86.01913 -278.725809) (xy 86.057251 -278.694684) (xy 86.099872 -278.670077) (xy 86.145888 -278.652625)
			(xy 86.194107 -278.642781) (xy 86.243282 -278.6408) (xy 86.292137 -278.646732) (xy 86.339408 -278.660424)
			(xy 86.38387 -278.681522) (xy 86.424373 -278.709478) (xy 86.459866 -278.74357) (xy 86.489431 -278.782914)
			(xy 86.512302 -278.826491) (xy 86.527886 -278.873172) (xy 86.535781 -278.921749) (xy 86.536276 -278.946356)
			(xy 86.865218 -278.946356) (xy 86.869178 -278.897302) (xy 86.880955 -278.849518) (xy 86.900246 -278.804242)
			(xy 86.926549 -278.762646) (xy 86.959184 -278.725809) (xy 86.997305 -278.694684) (xy 87.039926 -278.670077)
			(xy 87.085942 -278.652625) (xy 87.134161 -278.642781) (xy 87.183336 -278.6408) (xy 87.232191 -278.646732)
			(xy 87.279462 -278.660424) (xy 87.323924 -278.681522) (xy 87.364427 -278.709478) (xy 87.39992 -278.74357)
			(xy 87.429485 -278.782914) (xy 87.452356 -278.826491) (xy 87.46794 -278.873172) (xy 87.475835 -278.921749)
			(xy 87.47633 -278.946356) (xy 87.805272 -278.946356) (xy 87.809232 -278.897302) (xy 87.821009 -278.849518)
			(xy 87.8403 -278.804242) (xy 87.866603 -278.762646) (xy 87.899238 -278.725809) (xy 87.937359 -278.694684)
			(xy 87.97998 -278.670077) (xy 88.025996 -278.652625) (xy 88.074215 -278.642781) (xy 88.12339 -278.6408)
			(xy 88.172245 -278.646732) (xy 88.219516 -278.660424) (xy 88.263978 -278.681522) (xy 88.304481 -278.709478)
			(xy 88.339974 -278.74357) (xy 88.369539 -278.782914) (xy 88.39241 -278.826491) (xy 88.407994 -278.873172)
			(xy 88.415889 -278.921749) (xy 88.416384 -278.946356) (xy 88.745326 -278.946356) (xy 88.749286 -278.897302)
			(xy 88.761063 -278.849518) (xy 88.780354 -278.804242) (xy 88.806657 -278.762646) (xy 88.839292 -278.725809)
			(xy 88.877413 -278.694684) (xy 88.920034 -278.670077) (xy 88.96605 -278.652625) (xy 89.014269 -278.642781)
			(xy 89.063444 -278.6408) (xy 89.112299 -278.646732) (xy 89.15957 -278.660424) (xy 89.204032 -278.681522)
			(xy 89.244535 -278.709478) (xy 89.280028 -278.74357) (xy 89.309593 -278.782914) (xy 89.332464 -278.826491)
			(xy 89.348048 -278.873172) (xy 89.355943 -278.921749) (xy 89.356438 -278.946356) (xy 89.685126 -278.946356)
			(xy 89.689086 -278.897302) (xy 89.700863 -278.849518) (xy 89.720154 -278.804242) (xy 89.746457 -278.762646)
			(xy 89.779092 -278.725809) (xy 89.817213 -278.694684) (xy 89.859834 -278.670077) (xy 89.90585 -278.652625)
			(xy 89.954069 -278.642781) (xy 90.003244 -278.6408) (xy 90.052099 -278.646732) (xy 90.09937 -278.660424)
			(xy 90.143832 -278.681522) (xy 90.184335 -278.709478) (xy 90.219828 -278.74357) (xy 90.249393 -278.782914)
			(xy 90.272264 -278.826491) (xy 90.287848 -278.873172) (xy 90.295743 -278.921749) (xy 90.296238 -278.946356)
			(xy 90.614749 -278.946356) (xy 90.618844 -278.895628) (xy 90.631023 -278.846214) (xy 90.650971 -278.799394)
			(xy 90.678172 -278.75638) (xy 90.71192 -278.718286) (xy 90.751342 -278.686099) (xy 90.795416 -278.660653)
			(xy 90.843002 -278.642606) (xy 90.892866 -278.632426) (xy 90.943718 -278.630377) (xy 90.994239 -278.636511)
			(xy 91.043123 -278.650671) (xy 91.089102 -278.672488) (xy 91.130986 -278.701398) (xy 91.16769 -278.736653)
			(xy 91.198263 -278.777339) (xy 91.221914 -278.822402) (xy 91.23803 -278.870676) (xy 91.246194 -278.92091)
			(xy 91.246706 -278.946356) (xy 91.565234 -278.946356) (xy 91.569194 -278.897302) (xy 91.580971 -278.849518)
			(xy 91.600262 -278.804242) (xy 91.626565 -278.762646) (xy 91.6592 -278.725809) (xy 91.697321 -278.694684)
			(xy 91.739942 -278.670077) (xy 91.785958 -278.652625) (xy 91.834177 -278.642781) (xy 91.883352 -278.6408)
			(xy 91.932207 -278.646732) (xy 91.979478 -278.660424) (xy 92.02394 -278.681522) (xy 92.064443 -278.709478)
			(xy 92.099936 -278.74357) (xy 92.129501 -278.782914) (xy 92.152372 -278.826491) (xy 92.167956 -278.873172)
			(xy 92.175851 -278.921749) (xy 92.176346 -278.946356) (xy 92.494857 -278.946356) (xy 92.498952 -278.895628)
			(xy 92.511131 -278.846214) (xy 92.531079 -278.799394) (xy 92.55828 -278.75638) (xy 92.592028 -278.718286)
			(xy 92.63145 -278.686099) (xy 92.675524 -278.660653) (xy 92.72311 -278.642606) (xy 92.772974 -278.632426)
			(xy 92.823826 -278.630377) (xy 92.874347 -278.636511) (xy 92.923231 -278.650671) (xy 92.96921 -278.672488)
			(xy 93.011094 -278.701398) (xy 93.047798 -278.736653) (xy 93.078371 -278.777339) (xy 93.102022 -278.822402)
			(xy 93.118138 -278.870676) (xy 93.126302 -278.92091) (xy 93.126814 -278.946356) (xy 93.445342 -278.946356)
			(xy 93.449302 -278.897302) (xy 93.461079 -278.849518) (xy 93.48037 -278.804242) (xy 93.506673 -278.762646)
			(xy 93.539308 -278.725809) (xy 93.577429 -278.694684) (xy 93.62005 -278.670077) (xy 93.666066 -278.652625)
			(xy 93.714285 -278.642781) (xy 93.76346 -278.6408) (xy 93.812315 -278.646732) (xy 93.859586 -278.660424)
			(xy 93.904048 -278.681522) (xy 93.944551 -278.709478) (xy 93.980044 -278.74357) (xy 94.009609 -278.782914)
			(xy 94.03248 -278.826491) (xy 94.048064 -278.873172) (xy 94.055959 -278.921749) (xy 94.056454 -278.946356)
			(xy 94.374711 -278.946356) (xy 94.378806 -278.895628) (xy 94.390985 -278.846214) (xy 94.410933 -278.799394)
			(xy 94.438134 -278.75638) (xy 94.471882 -278.718286) (xy 94.511304 -278.686099) (xy 94.555378 -278.660653)
			(xy 94.602964 -278.642606) (xy 94.652828 -278.632426) (xy 94.70368 -278.630377) (xy 94.754201 -278.636511)
			(xy 94.803085 -278.650671) (xy 94.849064 -278.672488) (xy 94.890948 -278.701398) (xy 94.927652 -278.736653)
			(xy 94.958225 -278.777339) (xy 94.981876 -278.822402) (xy 94.997992 -278.870676) (xy 95.006156 -278.92091)
			(xy 95.006668 -278.946356) (xy 95.314765 -278.946356) (xy 95.31886 -278.895628) (xy 95.331039 -278.846214)
			(xy 95.350987 -278.799394) (xy 95.378188 -278.75638) (xy 95.411936 -278.718286) (xy 95.451358 -278.686099)
			(xy 95.495432 -278.660653) (xy 95.543018 -278.642606) (xy 95.592882 -278.632426) (xy 95.643734 -278.630377)
			(xy 95.694255 -278.636511) (xy 95.743139 -278.650671) (xy 95.789118 -278.672488) (xy 95.831002 -278.701398)
			(xy 95.867706 -278.736653) (xy 95.898279 -278.777339) (xy 95.92193 -278.822402) (xy 95.938046 -278.870676)
			(xy 95.94621 -278.92091) (xy 95.946722 -278.946356) (xy 95.94621 -278.971802) (xy 95.938046 -279.022036)
			(xy 95.92193 -279.07031) (xy 95.898279 -279.115373) (xy 95.867706 -279.156059) (xy 95.831002 -279.191314)
			(xy 95.789118 -279.220224) (xy 95.743139 -279.242041) (xy 95.694255 -279.256201) (xy 95.643734 -279.262335)
			(xy 95.592882 -279.260286) (xy 95.543018 -279.250106) (xy 95.495432 -279.232059) (xy 95.451358 -279.206613)
			(xy 95.411936 -279.174426) (xy 95.378188 -279.136332) (xy 95.350987 -279.093318) (xy 95.331039 -279.046498)
			(xy 95.31886 -278.997084) (xy 95.314765 -278.946356) (xy 95.006668 -278.946356) (xy 95.006156 -278.971802)
			(xy 94.997992 -279.022036) (xy 94.981876 -279.07031) (xy 94.958225 -279.115373) (xy 94.927652 -279.156059)
			(xy 94.890948 -279.191314) (xy 94.849064 -279.220224) (xy 94.803085 -279.242041) (xy 94.754201 -279.256201)
			(xy 94.70368 -279.262335) (xy 94.652828 -279.260286) (xy 94.602964 -279.250106) (xy 94.555378 -279.232059)
			(xy 94.511304 -279.206613) (xy 94.471882 -279.174426) (xy 94.438134 -279.136332) (xy 94.410933 -279.093318)
			(xy 94.390985 -279.046498) (xy 94.378806 -278.997084) (xy 94.374711 -278.946356) (xy 94.056454 -278.946356)
			(xy 94.055959 -278.970963) (xy 94.048064 -279.01954) (xy 94.03248 -279.066221) (xy 94.009609 -279.109798)
			(xy 93.980044 -279.149142) (xy 93.944551 -279.183234) (xy 93.904048 -279.21119) (xy 93.859586 -279.232288)
			(xy 93.812315 -279.24598) (xy 93.76346 -279.251912) (xy 93.714285 -279.249931) (xy 93.666066 -279.240087)
			(xy 93.62005 -279.222635) (xy 93.577429 -279.198028) (xy 93.539308 -279.166903) (xy 93.506673 -279.130066)
			(xy 93.48037 -279.08847) (xy 93.461079 -279.043194) (xy 93.449302 -278.99541) (xy 93.445342 -278.946356)
			(xy 93.126814 -278.946356) (xy 93.126302 -278.971802) (xy 93.118138 -279.022036) (xy 93.102022 -279.07031)
			(xy 93.078371 -279.115373) (xy 93.047798 -279.156059) (xy 93.011094 -279.191314) (xy 92.96921 -279.220224)
			(xy 92.923231 -279.242041) (xy 92.874347 -279.256201) (xy 92.823826 -279.262335) (xy 92.772974 -279.260286)
			(xy 92.72311 -279.250106) (xy 92.675524 -279.232059) (xy 92.63145 -279.206613) (xy 92.592028 -279.174426)
			(xy 92.55828 -279.136332) (xy 92.531079 -279.093318) (xy 92.511131 -279.046498) (xy 92.498952 -278.997084)
			(xy 92.494857 -278.946356) (xy 92.176346 -278.946356) (xy 92.175851 -278.970963) (xy 92.167956 -279.01954)
			(xy 92.152372 -279.066221) (xy 92.129501 -279.109798) (xy 92.099936 -279.149142) (xy 92.064443 -279.183234)
			(xy 92.02394 -279.21119) (xy 91.979478 -279.232288) (xy 91.932207 -279.24598) (xy 91.883352 -279.251912)
			(xy 91.834177 -279.249931) (xy 91.785958 -279.240087) (xy 91.739942 -279.222635) (xy 91.697321 -279.198028)
			(xy 91.6592 -279.166903) (xy 91.626565 -279.130066) (xy 91.600262 -279.08847) (xy 91.580971 -279.043194)
			(xy 91.569194 -278.99541) (xy 91.565234 -278.946356) (xy 91.246706 -278.946356) (xy 91.246194 -278.971802)
			(xy 91.23803 -279.022036) (xy 91.221914 -279.07031) (xy 91.198263 -279.115373) (xy 91.16769 -279.156059)
			(xy 91.130986 -279.191314) (xy 91.089102 -279.220224) (xy 91.043123 -279.242041) (xy 90.994239 -279.256201)
			(xy 90.943718 -279.262335) (xy 90.892866 -279.260286) (xy 90.843002 -279.250106) (xy 90.795416 -279.232059)
			(xy 90.751342 -279.206613) (xy 90.71192 -279.174426) (xy 90.678172 -279.136332) (xy 90.650971 -279.093318)
			(xy 90.631023 -279.046498) (xy 90.618844 -278.997084) (xy 90.614749 -278.946356) (xy 90.296238 -278.946356)
			(xy 90.295743 -278.970963) (xy 90.287848 -279.01954) (xy 90.272264 -279.066221) (xy 90.249393 -279.109798)
			(xy 90.219828 -279.149142) (xy 90.184335 -279.183234) (xy 90.143832 -279.21119) (xy 90.09937 -279.232288)
			(xy 90.052099 -279.24598) (xy 90.003244 -279.251912) (xy 89.954069 -279.249931) (xy 89.90585 -279.240087)
			(xy 89.859834 -279.222635) (xy 89.817213 -279.198028) (xy 89.779092 -279.166903) (xy 89.746457 -279.130066)
			(xy 89.720154 -279.08847) (xy 89.700863 -279.043194) (xy 89.689086 -278.99541) (xy 89.685126 -278.946356)
			(xy 89.356438 -278.946356) (xy 89.355943 -278.970963) (xy 89.348048 -279.01954) (xy 89.332464 -279.066221)
			(xy 89.309593 -279.109798) (xy 89.280028 -279.149142) (xy 89.244535 -279.183234) (xy 89.204032 -279.21119)
			(xy 89.15957 -279.232288) (xy 89.112299 -279.24598) (xy 89.063444 -279.251912) (xy 89.014269 -279.249931)
			(xy 88.96605 -279.240087) (xy 88.920034 -279.222635) (xy 88.877413 -279.198028) (xy 88.839292 -279.166903)
			(xy 88.806657 -279.130066) (xy 88.780354 -279.08847) (xy 88.761063 -279.043194) (xy 88.749286 -278.99541)
			(xy 88.745326 -278.946356) (xy 88.416384 -278.946356) (xy 88.415889 -278.970963) (xy 88.407994 -279.01954)
			(xy 88.39241 -279.066221) (xy 88.369539 -279.109798) (xy 88.339974 -279.149142) (xy 88.304481 -279.183234)
			(xy 88.263978 -279.21119) (xy 88.219516 -279.232288) (xy 88.172245 -279.24598) (xy 88.12339 -279.251912)
			(xy 88.074215 -279.249931) (xy 88.025996 -279.240087) (xy 87.97998 -279.222635) (xy 87.937359 -279.198028)
			(xy 87.899238 -279.166903) (xy 87.866603 -279.130066) (xy 87.8403 -279.08847) (xy 87.821009 -279.043194)
			(xy 87.809232 -278.99541) (xy 87.805272 -278.946356) (xy 87.47633 -278.946356) (xy 87.475835 -278.970963)
			(xy 87.46794 -279.01954) (xy 87.452356 -279.066221) (xy 87.429485 -279.109798) (xy 87.39992 -279.149142)
			(xy 87.364427 -279.183234) (xy 87.323924 -279.21119) (xy 87.279462 -279.232288) (xy 87.232191 -279.24598)
			(xy 87.183336 -279.251912) (xy 87.134161 -279.249931) (xy 87.085942 -279.240087) (xy 87.039926 -279.222635)
			(xy 86.997305 -279.198028) (xy 86.959184 -279.166903) (xy 86.926549 -279.130066) (xy 86.900246 -279.08847)
			(xy 86.880955 -279.043194) (xy 86.869178 -278.99541) (xy 86.865218 -278.946356) (xy 86.536276 -278.946356)
			(xy 86.535781 -278.970963) (xy 86.527886 -279.01954) (xy 86.512302 -279.066221) (xy 86.489431 -279.109798)
			(xy 86.459866 -279.149142) (xy 86.424373 -279.183234) (xy 86.38387 -279.21119) (xy 86.339408 -279.232288)
			(xy 86.292137 -279.24598) (xy 86.243282 -279.251912) (xy 86.194107 -279.249931) (xy 86.145888 -279.240087)
			(xy 86.099872 -279.222635) (xy 86.057251 -279.198028) (xy 86.01913 -279.166903) (xy 85.986495 -279.130066)
			(xy 85.960192 -279.08847) (xy 85.940901 -279.043194) (xy 85.929124 -278.99541) (xy 85.925164 -278.946356)
			(xy 85.596222 -278.946356) (xy 85.595727 -278.970963) (xy 85.587832 -279.01954) (xy 85.572248 -279.066221)
			(xy 85.549377 -279.109798) (xy 85.519812 -279.149142) (xy 85.484319 -279.183234) (xy 85.443816 -279.21119)
			(xy 85.399354 -279.232288) (xy 85.352083 -279.24598) (xy 85.303228 -279.251912) (xy 85.254053 -279.249931)
			(xy 85.205834 -279.240087) (xy 85.159818 -279.222635) (xy 85.117197 -279.198028) (xy 85.079076 -279.166903)
			(xy 85.046441 -279.130066) (xy 85.020138 -279.08847) (xy 85.000847 -279.043194) (xy 84.98907 -278.99541)
			(xy 84.98511 -278.946356) (xy 84.656422 -278.946356) (xy 84.655927 -278.970963) (xy 84.648032 -279.01954)
			(xy 84.632448 -279.066221) (xy 84.609577 -279.109798) (xy 84.580012 -279.149142) (xy 84.544519 -279.183234)
			(xy 84.504016 -279.21119) (xy 84.459554 -279.232288) (xy 84.412283 -279.24598) (xy 84.363428 -279.251912)
			(xy 84.314253 -279.249931) (xy 84.266034 -279.240087) (xy 84.220018 -279.222635) (xy 84.177397 -279.198028)
			(xy 84.139276 -279.166903) (xy 84.106641 -279.130066) (xy 84.080338 -279.08847) (xy 84.061047 -279.043194)
			(xy 84.04927 -278.99541) (xy 84.04531 -278.946356) (xy 83.716368 -278.946356) (xy 83.716368 -278.952198)
			(xy 83.715349 -278.977888) (xy 83.705775 -279.028399) (xy 83.687874 -279.076592) (xy 83.662151 -279.121105)
			(xy 83.629335 -279.160679) (xy 83.590352 -279.194196) (xy 83.546305 -279.220708) (xy 83.522566 -279.230582)
			(xy 83.512152 -279.2349) (xy 83.503516 -279.2476) (xy 83.499488 -279.254007) (xy 83.495101 -279.268483)
			(xy 83.49488 -279.276048) (xy 83.49488 -279.398476) (xy 83.495145 -279.404083) (xy 83.497846 -279.414976)
			(xy 83.500214 -279.420066) (xy 83.504786 -279.42794) (xy 83.508736 -279.432796) (xy 83.518494 -279.44063)
			(xy 83.52409 -279.443434) (xy 83.524344 -279.443688) (xy 83.605116 -279.481026) (xy 83.618832 -279.484328)
			(xy 83.631278 -279.484836) (xy 83.648042 -279.478486) (xy 83.6549 -279.475184) (xy 83.665314 -279.469342)
			(xy 83.6676 -279.467564) (xy 83.668616 -279.466802) (xy 83.66887 -279.466548) (xy 83.689157 -279.451474)
			(xy 83.733639 -279.427484) (xy 83.781454 -279.411118) (xy 83.831307 -279.40282) (xy 83.856576 -279.402286)
			(xy 83.882413 -279.402834) (xy 83.933346 -279.411548) (xy 83.982085 -279.428715) (xy 84.027237 -279.453843)
			(xy 84.067513 -279.486217) (xy 84.101762 -279.52491) (xy 84.129007 -279.568817) (xy 84.139278 -279.592532)
			(xy 84.142834 -279.599136) (xy 84.143088 -279.599644) (xy 84.15662 -279.623524) (xy 84.175879 -279.674917)
			(xy 84.185659 -279.728921) (xy 84.186268 -279.756362) (xy 84.51521 -279.756362) (xy 84.51917 -279.707308)
			(xy 84.530947 -279.659524) (xy 84.550238 -279.614248) (xy 84.576541 -279.572652) (xy 84.609176 -279.535815)
			(xy 84.647297 -279.50469) (xy 84.689918 -279.480083) (xy 84.735934 -279.462631) (xy 84.784153 -279.452787)
			(xy 84.833328 -279.450806) (xy 84.882183 -279.456738) (xy 84.929454 -279.47043) (xy 84.973916 -279.491528)
			(xy 85.014419 -279.519484) (xy 85.049912 -279.553576) (xy 85.079477 -279.59292) (xy 85.102348 -279.636497)
			(xy 85.117932 -279.683178) (xy 85.125827 -279.731755) (xy 85.126322 -279.756362) (xy 85.455264 -279.756362)
			(xy 85.459224 -279.707308) (xy 85.471001 -279.659524) (xy 85.490292 -279.614248) (xy 85.516595 -279.572652)
			(xy 85.54923 -279.535815) (xy 85.587351 -279.50469) (xy 85.629972 -279.480083) (xy 85.675988 -279.462631)
			(xy 85.724207 -279.452787) (xy 85.773382 -279.450806) (xy 85.822237 -279.456738) (xy 85.869508 -279.47043)
			(xy 85.91397 -279.491528) (xy 85.954473 -279.519484) (xy 85.989966 -279.553576) (xy 86.019531 -279.59292)
			(xy 86.042402 -279.636497) (xy 86.057986 -279.683178) (xy 86.065881 -279.731755) (xy 86.066376 -279.756362)
			(xy 86.395318 -279.756362) (xy 86.399278 -279.707308) (xy 86.411055 -279.659524) (xy 86.430346 -279.614248)
			(xy 86.456649 -279.572652) (xy 86.489284 -279.535815) (xy 86.527405 -279.50469) (xy 86.570026 -279.480083)
			(xy 86.616042 -279.462631) (xy 86.664261 -279.452787) (xy 86.713436 -279.450806) (xy 86.762291 -279.456738)
			(xy 86.809562 -279.47043) (xy 86.854024 -279.491528) (xy 86.894527 -279.519484) (xy 86.93002 -279.553576)
			(xy 86.959585 -279.59292) (xy 86.982456 -279.636497) (xy 86.99804 -279.683178) (xy 87.005935 -279.731755)
			(xy 87.00643 -279.756362) (xy 87.335118 -279.756362) (xy 87.339078 -279.707308) (xy 87.350855 -279.659524)
			(xy 87.370146 -279.614248) (xy 87.396449 -279.572652) (xy 87.429084 -279.535815) (xy 87.467205 -279.50469)
			(xy 87.509826 -279.480083) (xy 87.555842 -279.462631) (xy 87.604061 -279.452787) (xy 87.653236 -279.450806)
			(xy 87.702091 -279.456738) (xy 87.749362 -279.47043) (xy 87.793824 -279.491528) (xy 87.834327 -279.519484)
			(xy 87.86982 -279.553576) (xy 87.899385 -279.59292) (xy 87.922256 -279.636497) (xy 87.93784 -279.683178)
			(xy 87.945735 -279.731755) (xy 87.94623 -279.756362) (xy 88.275172 -279.756362) (xy 88.279132 -279.707308)
			(xy 88.290909 -279.659524) (xy 88.3102 -279.614248) (xy 88.336503 -279.572652) (xy 88.369138 -279.535815)
			(xy 88.407259 -279.50469) (xy 88.44988 -279.480083) (xy 88.495896 -279.462631) (xy 88.544115 -279.452787)
			(xy 88.59329 -279.450806) (xy 88.642145 -279.456738) (xy 88.689416 -279.47043) (xy 88.733878 -279.491528)
			(xy 88.774381 -279.519484) (xy 88.809874 -279.553576) (xy 88.839439 -279.59292) (xy 88.86231 -279.636497)
			(xy 88.877894 -279.683178) (xy 88.885789 -279.731755) (xy 88.886284 -279.756362) (xy 89.215226 -279.756362)
			(xy 89.219186 -279.707308) (xy 89.230963 -279.659524) (xy 89.250254 -279.614248) (xy 89.276557 -279.572652)
			(xy 89.309192 -279.535815) (xy 89.347313 -279.50469) (xy 89.389934 -279.480083) (xy 89.43595 -279.462631)
			(xy 89.484169 -279.452787) (xy 89.533344 -279.450806) (xy 89.582199 -279.456738) (xy 89.62947 -279.47043)
			(xy 89.673932 -279.491528) (xy 89.714435 -279.519484) (xy 89.749928 -279.553576) (xy 89.779493 -279.59292)
			(xy 89.802364 -279.636497) (xy 89.817948 -279.683178) (xy 89.825843 -279.731755) (xy 89.826338 -279.756362)
			(xy 90.15528 -279.756362) (xy 90.15924 -279.707308) (xy 90.171017 -279.659524) (xy 90.190308 -279.614248)
			(xy 90.216611 -279.572652) (xy 90.249246 -279.535815) (xy 90.287367 -279.50469) (xy 90.329988 -279.480083)
			(xy 90.376004 -279.462631) (xy 90.424223 -279.452787) (xy 90.473398 -279.450806) (xy 90.522253 -279.456738)
			(xy 90.569524 -279.47043) (xy 90.613986 -279.491528) (xy 90.654489 -279.519484) (xy 90.689982 -279.553576)
			(xy 90.719547 -279.59292) (xy 90.742418 -279.636497) (xy 90.758002 -279.683178) (xy 90.765897 -279.731755)
			(xy 90.766392 -279.756362) (xy 91.084903 -279.756362) (xy 91.088998 -279.705634) (xy 91.101177 -279.65622)
			(xy 91.121125 -279.6094) (xy 91.148326 -279.566386) (xy 91.182074 -279.528292) (xy 91.221496 -279.496105)
			(xy 91.26557 -279.470659) (xy 91.313156 -279.452612) (xy 91.36302 -279.442432) (xy 91.413872 -279.440383)
			(xy 91.464393 -279.446517) (xy 91.513277 -279.460677) (xy 91.559256 -279.482494) (xy 91.60114 -279.511404)
			(xy 91.637844 -279.546659) (xy 91.668417 -279.587345) (xy 91.692068 -279.632408) (xy 91.708184 -279.680682)
			(xy 91.716348 -279.730916) (xy 91.71686 -279.756362) (xy 92.024703 -279.756362) (xy 92.028798 -279.705634)
			(xy 92.040977 -279.65622) (xy 92.060925 -279.6094) (xy 92.088126 -279.566386) (xy 92.121874 -279.528292)
			(xy 92.161296 -279.496105) (xy 92.20537 -279.470659) (xy 92.252956 -279.452612) (xy 92.30282 -279.442432)
			(xy 92.353672 -279.440383) (xy 92.404193 -279.446517) (xy 92.453077 -279.460677) (xy 92.499056 -279.482494)
			(xy 92.54094 -279.511404) (xy 92.577644 -279.546659) (xy 92.608217 -279.587345) (xy 92.631868 -279.632408)
			(xy 92.647984 -279.680682) (xy 92.656148 -279.730916) (xy 92.65666 -279.756362) (xy 92.975188 -279.756362)
			(xy 92.979148 -279.707308) (xy 92.990925 -279.659524) (xy 93.010216 -279.614248) (xy 93.036519 -279.572652)
			(xy 93.069154 -279.535815) (xy 93.107275 -279.50469) (xy 93.149896 -279.480083) (xy 93.195912 -279.462631)
			(xy 93.244131 -279.452787) (xy 93.293306 -279.450806) (xy 93.342161 -279.456738) (xy 93.389432 -279.47043)
			(xy 93.433894 -279.491528) (xy 93.474397 -279.519484) (xy 93.50989 -279.553576) (xy 93.539455 -279.59292)
			(xy 93.562326 -279.636497) (xy 93.57791 -279.683178) (xy 93.585805 -279.731755) (xy 93.5863 -279.756362)
			(xy 93.904811 -279.756362) (xy 93.908906 -279.705634) (xy 93.921085 -279.65622) (xy 93.941033 -279.6094)
			(xy 93.968234 -279.566386) (xy 94.001982 -279.528292) (xy 94.041404 -279.496105) (xy 94.085478 -279.470659)
			(xy 94.133064 -279.452612) (xy 94.182928 -279.442432) (xy 94.23378 -279.440383) (xy 94.284301 -279.446517)
			(xy 94.333185 -279.460677) (xy 94.379164 -279.482494) (xy 94.421048 -279.511404) (xy 94.457752 -279.546659)
			(xy 94.488325 -279.587345) (xy 94.511976 -279.632408) (xy 94.528092 -279.680682) (xy 94.536256 -279.730916)
			(xy 94.536768 -279.756362) (xy 94.855296 -279.756362) (xy 94.859256 -279.707308) (xy 94.871033 -279.659524)
			(xy 94.890324 -279.614248) (xy 94.916627 -279.572652) (xy 94.949262 -279.535815) (xy 94.987383 -279.50469)
			(xy 95.030004 -279.480083) (xy 95.07602 -279.462631) (xy 95.124239 -279.452787) (xy 95.173414 -279.450806)
			(xy 95.222269 -279.456738) (xy 95.26954 -279.47043) (xy 95.314002 -279.491528) (xy 95.354505 -279.519484)
			(xy 95.389998 -279.553576) (xy 95.419563 -279.59292) (xy 95.442434 -279.636497) (xy 95.458018 -279.683178)
			(xy 95.465913 -279.731755) (xy 95.466408 -279.756362) (xy 95.465913 -279.780969) (xy 95.458018 -279.829546)
			(xy 95.442434 -279.876227) (xy 95.419563 -279.919804) (xy 95.389998 -279.959148) (xy 95.354505 -279.99324)
			(xy 95.314002 -280.021196) (xy 95.26954 -280.042294) (xy 95.222269 -280.055986) (xy 95.173414 -280.061918)
			(xy 95.124239 -280.059937) (xy 95.07602 -280.050093) (xy 95.030004 -280.032641) (xy 94.987383 -280.008034)
			(xy 94.949262 -279.976909) (xy 94.916627 -279.940072) (xy 94.890324 -279.898476) (xy 94.871033 -279.8532)
			(xy 94.859256 -279.805416) (xy 94.855296 -279.756362) (xy 94.536768 -279.756362) (xy 94.536256 -279.781808)
			(xy 94.528092 -279.832042) (xy 94.511976 -279.880316) (xy 94.488325 -279.925379) (xy 94.457752 -279.966065)
			(xy 94.421048 -280.00132) (xy 94.379164 -280.03023) (xy 94.333185 -280.052047) (xy 94.284301 -280.066207)
			(xy 94.23378 -280.072341) (xy 94.182928 -280.070292) (xy 94.133064 -280.060112) (xy 94.085478 -280.042065)
			(xy 94.041404 -280.016619) (xy 94.001982 -279.984432) (xy 93.968234 -279.946338) (xy 93.941033 -279.903324)
			(xy 93.921085 -279.856504) (xy 93.908906 -279.80709) (xy 93.904811 -279.756362) (xy 93.5863 -279.756362)
			(xy 93.585805 -279.780969) (xy 93.57791 -279.829546) (xy 93.562326 -279.876227) (xy 93.539455 -279.919804)
			(xy 93.50989 -279.959148) (xy 93.474397 -279.99324) (xy 93.433894 -280.021196) (xy 93.389432 -280.042294)
			(xy 93.342161 -280.055986) (xy 93.293306 -280.061918) (xy 93.244131 -280.059937) (xy 93.195912 -280.050093)
			(xy 93.149896 -280.032641) (xy 93.107275 -280.008034) (xy 93.069154 -279.976909) (xy 93.036519 -279.940072)
			(xy 93.010216 -279.898476) (xy 92.990925 -279.8532) (xy 92.979148 -279.805416) (xy 92.975188 -279.756362)
			(xy 92.65666 -279.756362) (xy 92.656148 -279.781808) (xy 92.647984 -279.832042) (xy 92.631868 -279.880316)
			(xy 92.608217 -279.925379) (xy 92.577644 -279.966065) (xy 92.54094 -280.00132) (xy 92.499056 -280.03023)
			(xy 92.453077 -280.052047) (xy 92.404193 -280.066207) (xy 92.353672 -280.072341) (xy 92.30282 -280.070292)
			(xy 92.252956 -280.060112) (xy 92.20537 -280.042065) (xy 92.161296 -280.016619) (xy 92.121874 -279.984432)
			(xy 92.088126 -279.946338) (xy 92.060925 -279.903324) (xy 92.040977 -279.856504) (xy 92.028798 -279.80709)
			(xy 92.024703 -279.756362) (xy 91.71686 -279.756362) (xy 91.716348 -279.781808) (xy 91.708184 -279.832042)
			(xy 91.692068 -279.880316) (xy 91.668417 -279.925379) (xy 91.637844 -279.966065) (xy 91.60114 -280.00132)
			(xy 91.559256 -280.03023) (xy 91.513277 -280.052047) (xy 91.464393 -280.066207) (xy 91.413872 -280.072341)
			(xy 91.36302 -280.070292) (xy 91.313156 -280.060112) (xy 91.26557 -280.042065) (xy 91.221496 -280.016619)
			(xy 91.182074 -279.984432) (xy 91.148326 -279.946338) (xy 91.121125 -279.903324) (xy 91.101177 -279.856504)
			(xy 91.088998 -279.80709) (xy 91.084903 -279.756362) (xy 90.766392 -279.756362) (xy 90.765897 -279.780969)
			(xy 90.758002 -279.829546) (xy 90.742418 -279.876227) (xy 90.719547 -279.919804) (xy 90.689982 -279.959148)
			(xy 90.654489 -279.99324) (xy 90.613986 -280.021196) (xy 90.569524 -280.042294) (xy 90.522253 -280.055986)
			(xy 90.473398 -280.061918) (xy 90.424223 -280.059937) (xy 90.376004 -280.050093) (xy 90.329988 -280.032641)
			(xy 90.287367 -280.008034) (xy 90.249246 -279.976909) (xy 90.216611 -279.940072) (xy 90.190308 -279.898476)
			(xy 90.171017 -279.8532) (xy 90.15924 -279.805416) (xy 90.15528 -279.756362) (xy 89.826338 -279.756362)
			(xy 89.825843 -279.780969) (xy 89.817948 -279.829546) (xy 89.802364 -279.876227) (xy 89.779493 -279.919804)
			(xy 89.749928 -279.959148) (xy 89.714435 -279.99324) (xy 89.673932 -280.021196) (xy 89.62947 -280.042294)
			(xy 89.582199 -280.055986) (xy 89.533344 -280.061918) (xy 89.484169 -280.059937) (xy 89.43595 -280.050093)
			(xy 89.389934 -280.032641) (xy 89.347313 -280.008034) (xy 89.309192 -279.976909) (xy 89.276557 -279.940072)
			(xy 89.250254 -279.898476) (xy 89.230963 -279.8532) (xy 89.219186 -279.805416) (xy 89.215226 -279.756362)
			(xy 88.886284 -279.756362) (xy 88.885789 -279.780969) (xy 88.877894 -279.829546) (xy 88.86231 -279.876227)
			(xy 88.839439 -279.919804) (xy 88.809874 -279.959148) (xy 88.774381 -279.99324) (xy 88.733878 -280.021196)
			(xy 88.689416 -280.042294) (xy 88.642145 -280.055986) (xy 88.59329 -280.061918) (xy 88.544115 -280.059937)
			(xy 88.495896 -280.050093) (xy 88.44988 -280.032641) (xy 88.407259 -280.008034) (xy 88.369138 -279.976909)
			(xy 88.336503 -279.940072) (xy 88.3102 -279.898476) (xy 88.290909 -279.8532) (xy 88.279132 -279.805416)
			(xy 88.275172 -279.756362) (xy 87.94623 -279.756362) (xy 87.945735 -279.780969) (xy 87.93784 -279.829546)
			(xy 87.922256 -279.876227) (xy 87.899385 -279.919804) (xy 87.86982 -279.959148) (xy 87.834327 -279.99324)
			(xy 87.793824 -280.021196) (xy 87.749362 -280.042294) (xy 87.702091 -280.055986) (xy 87.653236 -280.061918)
			(xy 87.604061 -280.059937) (xy 87.555842 -280.050093) (xy 87.509826 -280.032641) (xy 87.467205 -280.008034)
			(xy 87.429084 -279.976909) (xy 87.396449 -279.940072) (xy 87.370146 -279.898476) (xy 87.350855 -279.8532)
			(xy 87.339078 -279.805416) (xy 87.335118 -279.756362) (xy 87.00643 -279.756362) (xy 87.005935 -279.780969)
			(xy 86.99804 -279.829546) (xy 86.982456 -279.876227) (xy 86.959585 -279.919804) (xy 86.93002 -279.959148)
			(xy 86.894527 -279.99324) (xy 86.854024 -280.021196) (xy 86.809562 -280.042294) (xy 86.762291 -280.055986)
			(xy 86.713436 -280.061918) (xy 86.664261 -280.059937) (xy 86.616042 -280.050093) (xy 86.570026 -280.032641)
			(xy 86.527405 -280.008034) (xy 86.489284 -279.976909) (xy 86.456649 -279.940072) (xy 86.430346 -279.898476)
			(xy 86.411055 -279.8532) (xy 86.399278 -279.805416) (xy 86.395318 -279.756362) (xy 86.066376 -279.756362)
			(xy 86.065881 -279.780969) (xy 86.057986 -279.829546) (xy 86.042402 -279.876227) (xy 86.019531 -279.919804)
			(xy 85.989966 -279.959148) (xy 85.954473 -279.99324) (xy 85.91397 -280.021196) (xy 85.869508 -280.042294)
			(xy 85.822237 -280.055986) (xy 85.773382 -280.061918) (xy 85.724207 -280.059937) (xy 85.675988 -280.050093)
			(xy 85.629972 -280.032641) (xy 85.587351 -280.008034) (xy 85.54923 -279.976909) (xy 85.516595 -279.940072)
			(xy 85.490292 -279.898476) (xy 85.471001 -279.8532) (xy 85.459224 -279.805416) (xy 85.455264 -279.756362)
			(xy 85.126322 -279.756362) (xy 85.125827 -279.780969) (xy 85.117932 -279.829546) (xy 85.102348 -279.876227)
			(xy 85.079477 -279.919804) (xy 85.049912 -279.959148) (xy 85.014419 -279.99324) (xy 84.973916 -280.021196)
			(xy 84.929454 -280.042294) (xy 84.882183 -280.055986) (xy 84.833328 -280.061918) (xy 84.784153 -280.059937)
			(xy 84.735934 -280.050093) (xy 84.689918 -280.032641) (xy 84.647297 -280.008034) (xy 84.609176 -279.976909)
			(xy 84.576541 -279.940072) (xy 84.550238 -279.898476) (xy 84.530947 -279.8532) (xy 84.51917 -279.805416)
			(xy 84.51521 -279.756362) (xy 84.186268 -279.756362) (xy 84.185825 -279.780356) (xy 84.178322 -279.827754)
			(xy 84.163497 -279.873394) (xy 84.141713 -279.916152) (xy 84.113507 -279.954976) (xy 84.079574 -279.988908)
			(xy 84.040751 -280.017114) (xy 83.997992 -280.038897) (xy 83.952352 -280.053723) (xy 83.904954 -280.061225)
			(xy 83.88096 -280.06167) (xy 83.85457 -280.061118) (xy 83.802574 -280.052057) (xy 83.752909 -280.034195)
			(xy 83.707053 -280.008062) (xy 83.66637 -279.974438) (xy 83.648804 -279.954736) (xy 83.627468 -279.92959)
			(xy 83.62569 -279.92959) (xy 83.621481 -279.929671) (xy 83.613182 -279.931077) (xy 83.60918 -279.932384)
			(xy 83.521804 -279.97277) (xy 83.514021 -279.977301) (xy 83.502029 -279.990721) (xy 83.495438 -280.007469)
			(xy 83.49488 -280.016458) (xy 83.49488 -280.185368) (xy 83.494911 -280.189504) (xy 83.496183 -280.197677)
			(xy 83.49742 -280.201624) (xy 83.502246 -280.211784) (xy 83.515708 -280.232866) (xy 83.519212 -280.238125)
			(xy 83.52834 -280.246858) (xy 83.533742 -280.250138) (xy 83.533996 -280.250138) (xy 83.555754 -280.26272)
			(xy 83.595197 -280.293867) (xy 83.612482 -280.312114) (xy 83.630123 -280.332314) (xy 83.658731 -280.377669)
			(xy 83.669378 -280.402284) (xy 83.672934 -280.408888) (xy 83.673188 -280.409396) (xy 83.686698 -280.433239)
			(xy 83.705932 -280.484548) (xy 83.715718 -280.538463) (xy 83.716368 -280.56586) (xy 83.716368 -280.566368)
			(xy 84.04531 -280.566368) (xy 84.04927 -280.517314) (xy 84.061047 -280.46953) (xy 84.080338 -280.424254)
			(xy 84.106641 -280.382658) (xy 84.139276 -280.345821) (xy 84.177397 -280.314696) (xy 84.220018 -280.290089)
			(xy 84.266034 -280.272637) (xy 84.314253 -280.262793) (xy 84.363428 -280.260812) (xy 84.412283 -280.266744)
			(xy 84.459554 -280.280436) (xy 84.504016 -280.301534) (xy 84.544519 -280.32949) (xy 84.580012 -280.363582)
			(xy 84.609577 -280.402926) (xy 84.632448 -280.446503) (xy 84.648032 -280.493184) (xy 84.655927 -280.541761)
			(xy 84.656422 -280.566368) (xy 84.98511 -280.566368) (xy 84.98907 -280.517314) (xy 85.000847 -280.46953)
			(xy 85.020138 -280.424254) (xy 85.046441 -280.382658) (xy 85.079076 -280.345821) (xy 85.117197 -280.314696)
			(xy 85.159818 -280.290089) (xy 85.205834 -280.272637) (xy 85.254053 -280.262793) (xy 85.303228 -280.260812)
			(xy 85.352083 -280.266744) (xy 85.399354 -280.280436) (xy 85.443816 -280.301534) (xy 85.484319 -280.32949)
			(xy 85.519812 -280.363582) (xy 85.549377 -280.402926) (xy 85.572248 -280.446503) (xy 85.587832 -280.493184)
			(xy 85.595727 -280.541761) (xy 85.596222 -280.566368) (xy 85.925164 -280.566368) (xy 85.929124 -280.517314)
			(xy 85.940901 -280.46953) (xy 85.960192 -280.424254) (xy 85.986495 -280.382658) (xy 86.01913 -280.345821)
			(xy 86.057251 -280.314696) (xy 86.099872 -280.290089) (xy 86.145888 -280.272637) (xy 86.194107 -280.262793)
			(xy 86.243282 -280.260812) (xy 86.292137 -280.266744) (xy 86.339408 -280.280436) (xy 86.38387 -280.301534)
			(xy 86.424373 -280.32949) (xy 86.459866 -280.363582) (xy 86.489431 -280.402926) (xy 86.512302 -280.446503)
			(xy 86.527886 -280.493184) (xy 86.535781 -280.541761) (xy 86.536276 -280.566368) (xy 87.805272 -280.566368)
			(xy 87.809232 -280.517314) (xy 87.821009 -280.46953) (xy 87.8403 -280.424254) (xy 87.866603 -280.382658)
			(xy 87.899238 -280.345821) (xy 87.937359 -280.314696) (xy 87.97998 -280.290089) (xy 88.025996 -280.272637)
			(xy 88.074215 -280.262793) (xy 88.12339 -280.260812) (xy 88.172245 -280.266744) (xy 88.219516 -280.280436)
			(xy 88.263978 -280.301534) (xy 88.304481 -280.32949) (xy 88.339974 -280.363582) (xy 88.369539 -280.402926)
			(xy 88.39241 -280.446503) (xy 88.407994 -280.493184) (xy 88.415889 -280.541761) (xy 88.416384 -280.566368)
			(xy 88.745326 -280.566368) (xy 88.749286 -280.517314) (xy 88.761063 -280.46953) (xy 88.780354 -280.424254)
			(xy 88.806657 -280.382658) (xy 88.839292 -280.345821) (xy 88.877413 -280.314696) (xy 88.920034 -280.290089)
			(xy 88.96605 -280.272637) (xy 89.014269 -280.262793) (xy 89.063444 -280.260812) (xy 89.112299 -280.266744)
			(xy 89.15957 -280.280436) (xy 89.204032 -280.301534) (xy 89.244535 -280.32949) (xy 89.280028 -280.363582)
			(xy 89.309593 -280.402926) (xy 89.332464 -280.446503) (xy 89.348048 -280.493184) (xy 89.355943 -280.541761)
			(xy 89.356438 -280.566368) (xy 89.685126 -280.566368) (xy 89.689086 -280.517314) (xy 89.700863 -280.46953)
			(xy 89.720154 -280.424254) (xy 89.746457 -280.382658) (xy 89.779092 -280.345821) (xy 89.817213 -280.314696)
			(xy 89.859834 -280.290089) (xy 89.90585 -280.272637) (xy 89.954069 -280.262793) (xy 90.003244 -280.260812)
			(xy 90.052099 -280.266744) (xy 90.09937 -280.280436) (xy 90.143832 -280.301534) (xy 90.184335 -280.32949)
			(xy 90.219828 -280.363582) (xy 90.249393 -280.402926) (xy 90.272264 -280.446503) (xy 90.287848 -280.493184)
			(xy 90.295743 -280.541761) (xy 90.296238 -280.566368) (xy 90.614749 -280.566368) (xy 90.618844 -280.51564)
			(xy 90.631023 -280.466226) (xy 90.650971 -280.419406) (xy 90.678172 -280.376392) (xy 90.71192 -280.338298)
			(xy 90.751342 -280.306111) (xy 90.795416 -280.280665) (xy 90.843002 -280.262618) (xy 90.892866 -280.252438)
			(xy 90.943718 -280.250389) (xy 90.994239 -280.256523) (xy 91.043123 -280.270683) (xy 91.089102 -280.2925)
			(xy 91.130986 -280.32141) (xy 91.16769 -280.356665) (xy 91.198263 -280.397351) (xy 91.221914 -280.442414)
			(xy 91.23803 -280.490688) (xy 91.246194 -280.540922) (xy 91.246706 -280.566368) (xy 91.565234 -280.566368)
			(xy 91.569194 -280.517314) (xy 91.580971 -280.46953) (xy 91.600262 -280.424254) (xy 91.626565 -280.382658)
			(xy 91.6592 -280.345821) (xy 91.697321 -280.314696) (xy 91.739942 -280.290089) (xy 91.785958 -280.272637)
			(xy 91.834177 -280.262793) (xy 91.883352 -280.260812) (xy 91.932207 -280.266744) (xy 91.979478 -280.280436)
			(xy 92.02394 -280.301534) (xy 92.064443 -280.32949) (xy 92.099936 -280.363582) (xy 92.129501 -280.402926)
			(xy 92.152372 -280.446503) (xy 92.167956 -280.493184) (xy 92.175851 -280.541761) (xy 92.176346 -280.566368)
			(xy 92.494857 -280.566368) (xy 92.498952 -280.51564) (xy 92.511131 -280.466226) (xy 92.531079 -280.419406)
			(xy 92.55828 -280.376392) (xy 92.592028 -280.338298) (xy 92.63145 -280.306111) (xy 92.675524 -280.280665)
			(xy 92.72311 -280.262618) (xy 92.772974 -280.252438) (xy 92.823826 -280.250389) (xy 92.874347 -280.256523)
			(xy 92.923231 -280.270683) (xy 92.96921 -280.2925) (xy 93.011094 -280.32141) (xy 93.047798 -280.356665)
			(xy 93.078371 -280.397351) (xy 93.102022 -280.442414) (xy 93.118138 -280.490688) (xy 93.126302 -280.540922)
			(xy 93.126814 -280.566368) (xy 94.374711 -280.566368) (xy 94.378806 -280.51564) (xy 94.390985 -280.466226)
			(xy 94.410933 -280.419406) (xy 94.438134 -280.376392) (xy 94.471882 -280.338298) (xy 94.511304 -280.306111)
			(xy 94.555378 -280.280665) (xy 94.602964 -280.262618) (xy 94.652828 -280.252438) (xy 94.70368 -280.250389)
			(xy 94.754201 -280.256523) (xy 94.803085 -280.270683) (xy 94.849064 -280.2925) (xy 94.890948 -280.32141)
			(xy 94.927652 -280.356665) (xy 94.958225 -280.397351) (xy 94.981876 -280.442414) (xy 94.997992 -280.490688)
			(xy 95.006156 -280.540922) (xy 95.006668 -280.566368) (xy 95.314765 -280.566368) (xy 95.31886 -280.51564)
			(xy 95.331039 -280.466226) (xy 95.350987 -280.419406) (xy 95.378188 -280.376392) (xy 95.411936 -280.338298)
			(xy 95.451358 -280.306111) (xy 95.495432 -280.280665) (xy 95.543018 -280.262618) (xy 95.592882 -280.252438)
			(xy 95.643734 -280.250389) (xy 95.694255 -280.256523) (xy 95.743139 -280.270683) (xy 95.789118 -280.2925)
			(xy 95.831002 -280.32141) (xy 95.867706 -280.356665) (xy 95.898279 -280.397351) (xy 95.92193 -280.442414)
			(xy 95.938046 -280.490688) (xy 95.94621 -280.540922) (xy 95.946722 -280.566368) (xy 95.94621 -280.591814)
			(xy 95.938046 -280.642048) (xy 95.92193 -280.690322) (xy 95.898279 -280.735385) (xy 95.867706 -280.776071)
			(xy 95.831002 -280.811326) (xy 95.789118 -280.840236) (xy 95.743139 -280.862053) (xy 95.694255 -280.876213)
			(xy 95.643734 -280.882347) (xy 95.592882 -280.880298) (xy 95.543018 -280.870118) (xy 95.495432 -280.852071)
			(xy 95.451358 -280.826625) (xy 95.411936 -280.794438) (xy 95.378188 -280.756344) (xy 95.350987 -280.71333)
			(xy 95.331039 -280.66651) (xy 95.31886 -280.617096) (xy 95.314765 -280.566368) (xy 95.006668 -280.566368)
			(xy 95.006156 -280.591814) (xy 94.997992 -280.642048) (xy 94.981876 -280.690322) (xy 94.958225 -280.735385)
			(xy 94.927652 -280.776071) (xy 94.890948 -280.811326) (xy 94.849064 -280.840236) (xy 94.803085 -280.862053)
			(xy 94.754201 -280.876213) (xy 94.70368 -280.882347) (xy 94.652828 -280.880298) (xy 94.602964 -280.870118)
			(xy 94.555378 -280.852071) (xy 94.511304 -280.826625) (xy 94.471882 -280.794438) (xy 94.438134 -280.756344)
			(xy 94.410933 -280.71333) (xy 94.390985 -280.66651) (xy 94.378806 -280.617096) (xy 94.374711 -280.566368)
			(xy 93.126814 -280.566368) (xy 93.126302 -280.591814) (xy 93.118138 -280.642048) (xy 93.102022 -280.690322)
			(xy 93.078371 -280.735385) (xy 93.047798 -280.776071) (xy 93.011094 -280.811326) (xy 92.96921 -280.840236)
			(xy 92.923231 -280.862053) (xy 92.874347 -280.876213) (xy 92.823826 -280.882347) (xy 92.772974 -280.880298)
			(xy 92.72311 -280.870118) (xy 92.675524 -280.852071) (xy 92.63145 -280.826625) (xy 92.592028 -280.794438)
			(xy 92.55828 -280.756344) (xy 92.531079 -280.71333) (xy 92.511131 -280.66651) (xy 92.498952 -280.617096)
			(xy 92.494857 -280.566368) (xy 92.176346 -280.566368) (xy 92.175851 -280.590975) (xy 92.167956 -280.639552)
			(xy 92.152372 -280.686233) (xy 92.129501 -280.72981) (xy 92.099936 -280.769154) (xy 92.064443 -280.803246)
			(xy 92.02394 -280.831202) (xy 91.979478 -280.8523) (xy 91.932207 -280.865992) (xy 91.883352 -280.871924)
			(xy 91.834177 -280.869943) (xy 91.785958 -280.860099) (xy 91.739942 -280.842647) (xy 91.697321 -280.81804)
			(xy 91.6592 -280.786915) (xy 91.626565 -280.750078) (xy 91.600262 -280.708482) (xy 91.580971 -280.663206)
			(xy 91.569194 -280.615422) (xy 91.565234 -280.566368) (xy 91.246706 -280.566368) (xy 91.246194 -280.591814)
			(xy 91.23803 -280.642048) (xy 91.221914 -280.690322) (xy 91.198263 -280.735385) (xy 91.16769 -280.776071)
			(xy 91.130986 -280.811326) (xy 91.089102 -280.840236) (xy 91.043123 -280.862053) (xy 90.994239 -280.876213)
			(xy 90.943718 -280.882347) (xy 90.892866 -280.880298) (xy 90.843002 -280.870118) (xy 90.795416 -280.852071)
			(xy 90.751342 -280.826625) (xy 90.71192 -280.794438) (xy 90.678172 -280.756344) (xy 90.650971 -280.71333)
			(xy 90.631023 -280.66651) (xy 90.618844 -280.617096) (xy 90.614749 -280.566368) (xy 90.296238 -280.566368)
			(xy 90.295743 -280.590975) (xy 90.287848 -280.639552) (xy 90.272264 -280.686233) (xy 90.249393 -280.72981)
			(xy 90.219828 -280.769154) (xy 90.184335 -280.803246) (xy 90.143832 -280.831202) (xy 90.09937 -280.8523)
			(xy 90.052099 -280.865992) (xy 90.003244 -280.871924) (xy 89.954069 -280.869943) (xy 89.90585 -280.860099)
			(xy 89.859834 -280.842647) (xy 89.817213 -280.81804) (xy 89.779092 -280.786915) (xy 89.746457 -280.750078)
			(xy 89.720154 -280.708482) (xy 89.700863 -280.663206) (xy 89.689086 -280.615422) (xy 89.685126 -280.566368)
			(xy 89.356438 -280.566368) (xy 89.355943 -280.590975) (xy 89.348048 -280.639552) (xy 89.332464 -280.686233)
			(xy 89.309593 -280.72981) (xy 89.280028 -280.769154) (xy 89.244535 -280.803246) (xy 89.204032 -280.831202)
			(xy 89.15957 -280.8523) (xy 89.112299 -280.865992) (xy 89.063444 -280.871924) (xy 89.014269 -280.869943)
			(xy 88.96605 -280.860099) (xy 88.920034 -280.842647) (xy 88.877413 -280.81804) (xy 88.839292 -280.786915)
			(xy 88.806657 -280.750078) (xy 88.780354 -280.708482) (xy 88.761063 -280.663206) (xy 88.749286 -280.615422)
			(xy 88.745326 -280.566368) (xy 88.416384 -280.566368) (xy 88.415889 -280.590975) (xy 88.407994 -280.639552)
			(xy 88.39241 -280.686233) (xy 88.369539 -280.72981) (xy 88.339974 -280.769154) (xy 88.304481 -280.803246)
			(xy 88.263978 -280.831202) (xy 88.219516 -280.8523) (xy 88.172245 -280.865992) (xy 88.12339 -280.871924)
			(xy 88.074215 -280.869943) (xy 88.025996 -280.860099) (xy 87.97998 -280.842647) (xy 87.937359 -280.81804)
			(xy 87.899238 -280.786915) (xy 87.866603 -280.750078) (xy 87.8403 -280.708482) (xy 87.821009 -280.663206)
			(xy 87.809232 -280.615422) (xy 87.805272 -280.566368) (xy 86.536276 -280.566368) (xy 86.535781 -280.590975)
			(xy 86.527886 -280.639552) (xy 86.512302 -280.686233) (xy 86.489431 -280.72981) (xy 86.459866 -280.769154)
			(xy 86.424373 -280.803246) (xy 86.38387 -280.831202) (xy 86.339408 -280.8523) (xy 86.292137 -280.865992)
			(xy 86.243282 -280.871924) (xy 86.194107 -280.869943) (xy 86.145888 -280.860099) (xy 86.099872 -280.842647)
			(xy 86.057251 -280.81804) (xy 86.01913 -280.786915) (xy 85.986495 -280.750078) (xy 85.960192 -280.708482)
			(xy 85.940901 -280.663206) (xy 85.929124 -280.615422) (xy 85.925164 -280.566368) (xy 85.596222 -280.566368)
			(xy 85.595727 -280.590975) (xy 85.587832 -280.639552) (xy 85.572248 -280.686233) (xy 85.549377 -280.72981)
			(xy 85.519812 -280.769154) (xy 85.484319 -280.803246) (xy 85.443816 -280.831202) (xy 85.399354 -280.8523)
			(xy 85.352083 -280.865992) (xy 85.303228 -280.871924) (xy 85.254053 -280.869943) (xy 85.205834 -280.860099)
			(xy 85.159818 -280.842647) (xy 85.117197 -280.81804) (xy 85.079076 -280.786915) (xy 85.046441 -280.750078)
			(xy 85.020138 -280.708482) (xy 85.000847 -280.663206) (xy 84.98907 -280.615422) (xy 84.98511 -280.566368)
			(xy 84.656422 -280.566368) (xy 84.655927 -280.590975) (xy 84.648032 -280.639552) (xy 84.632448 -280.686233)
			(xy 84.609577 -280.72981) (xy 84.580012 -280.769154) (xy 84.544519 -280.803246) (xy 84.504016 -280.831202)
			(xy 84.459554 -280.8523) (xy 84.412283 -280.865992) (xy 84.363428 -280.871924) (xy 84.314253 -280.869943)
			(xy 84.266034 -280.860099) (xy 84.220018 -280.842647) (xy 84.177397 -280.81804) (xy 84.139276 -280.786915)
			(xy 84.106641 -280.750078) (xy 84.080338 -280.708482) (xy 84.061047 -280.663206) (xy 84.04927 -280.615422)
			(xy 84.04531 -280.566368) (xy 83.716368 -280.566368) (xy 83.716368 -280.57221) (xy 83.715348 -280.5979)
			(xy 83.705773 -280.64841) (xy 83.68787 -280.696601) (xy 83.662147 -280.741112) (xy 83.62933 -280.780685)
			(xy 83.590347 -280.8142) (xy 83.546301 -280.840711) (xy 83.522566 -280.850594) (xy 83.512152 -280.854912)
			(xy 83.503516 -280.867612) (xy 83.49949 -280.874019) (xy 83.495107 -280.888496) (xy 83.49488 -280.89606)
			(xy 83.49488 -281.018488) (xy 83.495135 -281.024098) (xy 83.49782 -281.034999) (xy 83.500214 -281.040078)
			(xy 83.504786 -281.047952) (xy 83.508737 -281.052807) (xy 83.518495 -281.060639) (xy 83.52409 -281.063446)
			(xy 83.524344 -281.0637) (xy 83.605116 -281.101038) (xy 83.618832 -281.10434) (xy 83.631278 -281.104848)
			(xy 83.648042 -281.098498) (xy 83.6549 -281.095196) (xy 83.665314 -281.089354) (xy 83.6676 -281.087576)
			(xy 83.668616 -281.086814) (xy 83.66887 -281.08656) (xy 83.689157 -281.071486) (xy 83.733638 -281.047494)
			(xy 83.781454 -281.031128) (xy 83.831307 -281.02283) (xy 83.856576 -281.022298) (xy 83.882414 -281.022846)
			(xy 83.933351 -281.031559) (xy 83.982095 -281.048722) (xy 84.027252 -281.073848) (xy 84.067536 -281.106217)
			(xy 84.101795 -281.144906) (xy 84.129051 -281.18881) (xy 84.139278 -281.212544) (xy 84.142834 -281.219148)
			(xy 84.143088 -281.219656) (xy 84.156619 -281.243537) (xy 84.175876 -281.294929) (xy 84.185654 -281.348933)
			(xy 84.186268 -281.376374) (xy 84.51521 -281.376374) (xy 84.51917 -281.32732) (xy 84.530947 -281.279536)
			(xy 84.550238 -281.23426) (xy 84.576541 -281.192664) (xy 84.609176 -281.155827) (xy 84.647297 -281.124702)
			(xy 84.689918 -281.100095) (xy 84.735934 -281.082643) (xy 84.784153 -281.072799) (xy 84.833328 -281.070818)
			(xy 84.882183 -281.07675) (xy 84.929454 -281.090442) (xy 84.973916 -281.11154) (xy 85.014419 -281.139496)
			(xy 85.049912 -281.173588) (xy 85.079477 -281.212932) (xy 85.102348 -281.256509) (xy 85.117932 -281.30319)
			(xy 85.125827 -281.351767) (xy 85.126322 -281.376374) (xy 85.455264 -281.376374) (xy 85.459224 -281.32732)
			(xy 85.471001 -281.279536) (xy 85.490292 -281.23426) (xy 85.516595 -281.192664) (xy 85.54923 -281.155827)
			(xy 85.587351 -281.124702) (xy 85.629972 -281.100095) (xy 85.675988 -281.082643) (xy 85.724207 -281.072799)
			(xy 85.773382 -281.070818) (xy 85.822237 -281.07675) (xy 85.869508 -281.090442) (xy 85.91397 -281.11154)
			(xy 85.954473 -281.139496) (xy 85.989966 -281.173588) (xy 86.019531 -281.212932) (xy 86.042402 -281.256509)
			(xy 86.057986 -281.30319) (xy 86.065881 -281.351767) (xy 86.066376 -281.376374) (xy 86.395318 -281.376374)
			(xy 86.399278 -281.32732) (xy 86.411055 -281.279536) (xy 86.430346 -281.23426) (xy 86.456649 -281.192664)
			(xy 86.489284 -281.155827) (xy 86.527405 -281.124702) (xy 86.570026 -281.100095) (xy 86.616042 -281.082643)
			(xy 86.664261 -281.072799) (xy 86.713436 -281.070818) (xy 86.762291 -281.07675) (xy 86.809562 -281.090442)
			(xy 86.854024 -281.11154) (xy 86.894527 -281.139496) (xy 86.93002 -281.173588) (xy 86.959585 -281.212932)
			(xy 86.982456 -281.256509) (xy 86.99804 -281.30319) (xy 87.005935 -281.351767) (xy 87.00643 -281.376374)
			(xy 87.335118 -281.376374) (xy 87.339078 -281.32732) (xy 87.350855 -281.279536) (xy 87.370146 -281.23426)
			(xy 87.396449 -281.192664) (xy 87.429084 -281.155827) (xy 87.467205 -281.124702) (xy 87.509826 -281.100095)
			(xy 87.555842 -281.082643) (xy 87.604061 -281.072799) (xy 87.653236 -281.070818) (xy 87.702091 -281.07675)
			(xy 87.749362 -281.090442) (xy 87.793824 -281.11154) (xy 87.834327 -281.139496) (xy 87.86982 -281.173588)
			(xy 87.899385 -281.212932) (xy 87.922256 -281.256509) (xy 87.93784 -281.30319) (xy 87.945735 -281.351767)
			(xy 87.94623 -281.376374) (xy 88.275172 -281.376374) (xy 88.279132 -281.32732) (xy 88.290909 -281.279536)
			(xy 88.3102 -281.23426) (xy 88.336503 -281.192664) (xy 88.369138 -281.155827) (xy 88.407259 -281.124702)
			(xy 88.44988 -281.100095) (xy 88.495896 -281.082643) (xy 88.544115 -281.072799) (xy 88.59329 -281.070818)
			(xy 88.642145 -281.07675) (xy 88.689416 -281.090442) (xy 88.733878 -281.11154) (xy 88.774381 -281.139496)
			(xy 88.809874 -281.173588) (xy 88.839439 -281.212932) (xy 88.86231 -281.256509) (xy 88.877894 -281.30319)
			(xy 88.885789 -281.351767) (xy 88.886284 -281.376374) (xy 89.215226 -281.376374) (xy 89.219186 -281.32732)
			(xy 89.230963 -281.279536) (xy 89.250254 -281.23426) (xy 89.276557 -281.192664) (xy 89.309192 -281.155827)
			(xy 89.347313 -281.124702) (xy 89.389934 -281.100095) (xy 89.43595 -281.082643) (xy 89.484169 -281.072799)
			(xy 89.533344 -281.070818) (xy 89.582199 -281.07675) (xy 89.62947 -281.090442) (xy 89.673932 -281.11154)
			(xy 89.714435 -281.139496) (xy 89.749928 -281.173588) (xy 89.779493 -281.212932) (xy 89.802364 -281.256509)
			(xy 89.817948 -281.30319) (xy 89.825843 -281.351767) (xy 89.826338 -281.376374) (xy 90.15528 -281.376374)
			(xy 90.15924 -281.32732) (xy 90.171017 -281.279536) (xy 90.190308 -281.23426) (xy 90.216611 -281.192664)
			(xy 90.249246 -281.155827) (xy 90.287367 -281.124702) (xy 90.329988 -281.100095) (xy 90.376004 -281.082643)
			(xy 90.424223 -281.072799) (xy 90.473398 -281.070818) (xy 90.522253 -281.07675) (xy 90.569524 -281.090442)
			(xy 90.613986 -281.11154) (xy 90.654489 -281.139496) (xy 90.689982 -281.173588) (xy 90.719547 -281.212932)
			(xy 90.742418 -281.256509) (xy 90.758002 -281.30319) (xy 90.765897 -281.351767) (xy 90.766392 -281.376374)
			(xy 91.084903 -281.376374) (xy 91.088998 -281.325646) (xy 91.101177 -281.276232) (xy 91.121125 -281.229412)
			(xy 91.148326 -281.186398) (xy 91.182074 -281.148304) (xy 91.221496 -281.116117) (xy 91.26557 -281.090671)
			(xy 91.313156 -281.072624) (xy 91.36302 -281.062444) (xy 91.413872 -281.060395) (xy 91.464393 -281.066529)
			(xy 91.513277 -281.080689) (xy 91.559256 -281.102506) (xy 91.60114 -281.131416) (xy 91.637844 -281.166671)
			(xy 91.668417 -281.207357) (xy 91.692068 -281.25242) (xy 91.708184 -281.300694) (xy 91.716348 -281.350928)
			(xy 91.71686 -281.376374) (xy 92.024703 -281.376374) (xy 92.028798 -281.325646) (xy 92.040977 -281.276232)
			(xy 92.060925 -281.229412) (xy 92.088126 -281.186398) (xy 92.121874 -281.148304) (xy 92.161296 -281.116117)
			(xy 92.20537 -281.090671) (xy 92.252956 -281.072624) (xy 92.30282 -281.062444) (xy 92.353672 -281.060395)
			(xy 92.404193 -281.066529) (xy 92.453077 -281.080689) (xy 92.499056 -281.102506) (xy 92.54094 -281.131416)
			(xy 92.577644 -281.166671) (xy 92.608217 -281.207357) (xy 92.631868 -281.25242) (xy 92.647984 -281.300694)
			(xy 92.656148 -281.350928) (xy 92.65666 -281.376374) (xy 92.975188 -281.376374) (xy 92.979148 -281.32732)
			(xy 92.990925 -281.279536) (xy 93.010216 -281.23426) (xy 93.036519 -281.192664) (xy 93.069154 -281.155827)
			(xy 93.107275 -281.124702) (xy 93.149896 -281.100095) (xy 93.195912 -281.082643) (xy 93.244131 -281.072799)
			(xy 93.293306 -281.070818) (xy 93.342161 -281.07675) (xy 93.389432 -281.090442) (xy 93.433894 -281.11154)
			(xy 93.474397 -281.139496) (xy 93.50989 -281.173588) (xy 93.539455 -281.212932) (xy 93.562326 -281.256509)
			(xy 93.57791 -281.30319) (xy 93.585805 -281.351767) (xy 93.5863 -281.376374) (xy 93.904811 -281.376374)
			(xy 93.908906 -281.325646) (xy 93.921085 -281.276232) (xy 93.941033 -281.229412) (xy 93.968234 -281.186398)
			(xy 94.001982 -281.148304) (xy 94.041404 -281.116117) (xy 94.085478 -281.090671) (xy 94.133064 -281.072624)
			(xy 94.182928 -281.062444) (xy 94.23378 -281.060395) (xy 94.284301 -281.066529) (xy 94.333185 -281.080689)
			(xy 94.379164 -281.102506) (xy 94.421048 -281.131416) (xy 94.457752 -281.166671) (xy 94.488325 -281.207357)
			(xy 94.511976 -281.25242) (xy 94.528092 -281.300694) (xy 94.536256 -281.350928) (xy 94.536768 -281.376374)
			(xy 94.855296 -281.376374) (xy 94.859256 -281.32732) (xy 94.871033 -281.279536) (xy 94.890324 -281.23426)
			(xy 94.916627 -281.192664) (xy 94.949262 -281.155827) (xy 94.987383 -281.124702) (xy 95.030004 -281.100095)
			(xy 95.07602 -281.082643) (xy 95.124239 -281.072799) (xy 95.173414 -281.070818) (xy 95.222269 -281.07675)
			(xy 95.26954 -281.090442) (xy 95.314002 -281.11154) (xy 95.354505 -281.139496) (xy 95.389998 -281.173588)
			(xy 95.419563 -281.212932) (xy 95.442434 -281.256509) (xy 95.458018 -281.30319) (xy 95.465913 -281.351767)
			(xy 95.466408 -281.376374) (xy 95.784919 -281.376374) (xy 95.789014 -281.325646) (xy 95.801193 -281.276232)
			(xy 95.821141 -281.229412) (xy 95.848342 -281.186398) (xy 95.88209 -281.148304) (xy 95.921512 -281.116117)
			(xy 95.965586 -281.090671) (xy 96.013172 -281.072624) (xy 96.063036 -281.062444) (xy 96.113888 -281.060395)
			(xy 96.164409 -281.066529) (xy 96.213293 -281.080689) (xy 96.259272 -281.102506) (xy 96.301156 -281.131416)
			(xy 96.33786 -281.166671) (xy 96.368433 -281.207357) (xy 96.392084 -281.25242) (xy 96.4082 -281.300694)
			(xy 96.416364 -281.350928) (xy 96.416876 -281.376374) (xy 96.416364 -281.40182) (xy 96.4082 -281.452054)
			(xy 96.392084 -281.500328) (xy 96.368433 -281.545391) (xy 96.33786 -281.586077) (xy 96.301156 -281.621332)
			(xy 96.259272 -281.650242) (xy 96.213293 -281.672059) (xy 96.164409 -281.686219) (xy 96.113888 -281.692353)
			(xy 96.063036 -281.690304) (xy 96.013172 -281.680124) (xy 95.965586 -281.662077) (xy 95.921512 -281.636631)
			(xy 95.88209 -281.604444) (xy 95.848342 -281.56635) (xy 95.821141 -281.523336) (xy 95.801193 -281.476516)
			(xy 95.789014 -281.427102) (xy 95.784919 -281.376374) (xy 95.466408 -281.376374) (xy 95.465913 -281.400981)
			(xy 95.458018 -281.449558) (xy 95.442434 -281.496239) (xy 95.419563 -281.539816) (xy 95.389998 -281.57916)
			(xy 95.354505 -281.613252) (xy 95.314002 -281.641208) (xy 95.26954 -281.662306) (xy 95.222269 -281.675998)
			(xy 95.173414 -281.68193) (xy 95.124239 -281.679949) (xy 95.07602 -281.670105) (xy 95.030004 -281.652653)
			(xy 94.987383 -281.628046) (xy 94.949262 -281.596921) (xy 94.916627 -281.560084) (xy 94.890324 -281.518488)
			(xy 94.871033 -281.473212) (xy 94.859256 -281.425428) (xy 94.855296 -281.376374) (xy 94.536768 -281.376374)
			(xy 94.536256 -281.40182) (xy 94.528092 -281.452054) (xy 94.511976 -281.500328) (xy 94.488325 -281.545391)
			(xy 94.457752 -281.586077) (xy 94.421048 -281.621332) (xy 94.379164 -281.650242) (xy 94.333185 -281.672059)
			(xy 94.284301 -281.686219) (xy 94.23378 -281.692353) (xy 94.182928 -281.690304) (xy 94.133064 -281.680124)
			(xy 94.085478 -281.662077) (xy 94.041404 -281.636631) (xy 94.001982 -281.604444) (xy 93.968234 -281.56635)
			(xy 93.941033 -281.523336) (xy 93.921085 -281.476516) (xy 93.908906 -281.427102) (xy 93.904811 -281.376374)
			(xy 93.5863 -281.376374) (xy 93.585805 -281.400981) (xy 93.57791 -281.449558) (xy 93.562326 -281.496239)
			(xy 93.539455 -281.539816) (xy 93.50989 -281.57916) (xy 93.474397 -281.613252) (xy 93.433894 -281.641208)
			(xy 93.389432 -281.662306) (xy 93.342161 -281.675998) (xy 93.293306 -281.68193) (xy 93.244131 -281.679949)
			(xy 93.195912 -281.670105) (xy 93.149896 -281.652653) (xy 93.107275 -281.628046) (xy 93.069154 -281.596921)
			(xy 93.036519 -281.560084) (xy 93.010216 -281.518488) (xy 92.990925 -281.473212) (xy 92.979148 -281.425428)
			(xy 92.975188 -281.376374) (xy 92.65666 -281.376374) (xy 92.656148 -281.40182) (xy 92.647984 -281.452054)
			(xy 92.631868 -281.500328) (xy 92.608217 -281.545391) (xy 92.577644 -281.586077) (xy 92.54094 -281.621332)
			(xy 92.499056 -281.650242) (xy 92.453077 -281.672059) (xy 92.404193 -281.686219) (xy 92.353672 -281.692353)
			(xy 92.30282 -281.690304) (xy 92.252956 -281.680124) (xy 92.20537 -281.662077) (xy 92.161296 -281.636631)
			(xy 92.121874 -281.604444) (xy 92.088126 -281.56635) (xy 92.060925 -281.523336) (xy 92.040977 -281.476516)
			(xy 92.028798 -281.427102) (xy 92.024703 -281.376374) (xy 91.71686 -281.376374) (xy 91.716348 -281.40182)
			(xy 91.708184 -281.452054) (xy 91.692068 -281.500328) (xy 91.668417 -281.545391) (xy 91.637844 -281.586077)
			(xy 91.60114 -281.621332) (xy 91.559256 -281.650242) (xy 91.513277 -281.672059) (xy 91.464393 -281.686219)
			(xy 91.413872 -281.692353) (xy 91.36302 -281.690304) (xy 91.313156 -281.680124) (xy 91.26557 -281.662077)
			(xy 91.221496 -281.636631) (xy 91.182074 -281.604444) (xy 91.148326 -281.56635) (xy 91.121125 -281.523336)
			(xy 91.101177 -281.476516) (xy 91.088998 -281.427102) (xy 91.084903 -281.376374) (xy 90.766392 -281.376374)
			(xy 90.765897 -281.400981) (xy 90.758002 -281.449558) (xy 90.742418 -281.496239) (xy 90.719547 -281.539816)
			(xy 90.689982 -281.57916) (xy 90.654489 -281.613252) (xy 90.613986 -281.641208) (xy 90.569524 -281.662306)
			(xy 90.522253 -281.675998) (xy 90.473398 -281.68193) (xy 90.424223 -281.679949) (xy 90.376004 -281.670105)
			(xy 90.329988 -281.652653) (xy 90.287367 -281.628046) (xy 90.249246 -281.596921) (xy 90.216611 -281.560084)
			(xy 90.190308 -281.518488) (xy 90.171017 -281.473212) (xy 90.15924 -281.425428) (xy 90.15528 -281.376374)
			(xy 89.826338 -281.376374) (xy 89.825843 -281.400981) (xy 89.817948 -281.449558) (xy 89.802364 -281.496239)
			(xy 89.779493 -281.539816) (xy 89.749928 -281.57916) (xy 89.714435 -281.613252) (xy 89.673932 -281.641208)
			(xy 89.62947 -281.662306) (xy 89.582199 -281.675998) (xy 89.533344 -281.68193) (xy 89.484169 -281.679949)
			(xy 89.43595 -281.670105) (xy 89.389934 -281.652653) (xy 89.347313 -281.628046) (xy 89.309192 -281.596921)
			(xy 89.276557 -281.560084) (xy 89.250254 -281.518488) (xy 89.230963 -281.473212) (xy 89.219186 -281.425428)
			(xy 89.215226 -281.376374) (xy 88.886284 -281.376374) (xy 88.885789 -281.400981) (xy 88.877894 -281.449558)
			(xy 88.86231 -281.496239) (xy 88.839439 -281.539816) (xy 88.809874 -281.57916) (xy 88.774381 -281.613252)
			(xy 88.733878 -281.641208) (xy 88.689416 -281.662306) (xy 88.642145 -281.675998) (xy 88.59329 -281.68193)
			(xy 88.544115 -281.679949) (xy 88.495896 -281.670105) (xy 88.44988 -281.652653) (xy 88.407259 -281.628046)
			(xy 88.369138 -281.596921) (xy 88.336503 -281.560084) (xy 88.3102 -281.518488) (xy 88.290909 -281.473212)
			(xy 88.279132 -281.425428) (xy 88.275172 -281.376374) (xy 87.94623 -281.376374) (xy 87.945735 -281.400981)
			(xy 87.93784 -281.449558) (xy 87.922256 -281.496239) (xy 87.899385 -281.539816) (xy 87.86982 -281.57916)
			(xy 87.834327 -281.613252) (xy 87.793824 -281.641208) (xy 87.749362 -281.662306) (xy 87.702091 -281.675998)
			(xy 87.653236 -281.68193) (xy 87.604061 -281.679949) (xy 87.555842 -281.670105) (xy 87.509826 -281.652653)
			(xy 87.467205 -281.628046) (xy 87.429084 -281.596921) (xy 87.396449 -281.560084) (xy 87.370146 -281.518488)
			(xy 87.350855 -281.473212) (xy 87.339078 -281.425428) (xy 87.335118 -281.376374) (xy 87.00643 -281.376374)
			(xy 87.005935 -281.400981) (xy 86.99804 -281.449558) (xy 86.982456 -281.496239) (xy 86.959585 -281.539816)
			(xy 86.93002 -281.57916) (xy 86.894527 -281.613252) (xy 86.854024 -281.641208) (xy 86.809562 -281.662306)
			(xy 86.762291 -281.675998) (xy 86.713436 -281.68193) (xy 86.664261 -281.679949) (xy 86.616042 -281.670105)
			(xy 86.570026 -281.652653) (xy 86.527405 -281.628046) (xy 86.489284 -281.596921) (xy 86.456649 -281.560084)
			(xy 86.430346 -281.518488) (xy 86.411055 -281.473212) (xy 86.399278 -281.425428) (xy 86.395318 -281.376374)
			(xy 86.066376 -281.376374) (xy 86.065881 -281.400981) (xy 86.057986 -281.449558) (xy 86.042402 -281.496239)
			(xy 86.019531 -281.539816) (xy 85.989966 -281.57916) (xy 85.954473 -281.613252) (xy 85.91397 -281.641208)
			(xy 85.869508 -281.662306) (xy 85.822237 -281.675998) (xy 85.773382 -281.68193) (xy 85.724207 -281.679949)
			(xy 85.675988 -281.670105) (xy 85.629972 -281.652653) (xy 85.587351 -281.628046) (xy 85.54923 -281.596921)
			(xy 85.516595 -281.560084) (xy 85.490292 -281.518488) (xy 85.471001 -281.473212) (xy 85.459224 -281.425428)
			(xy 85.455264 -281.376374) (xy 85.126322 -281.376374) (xy 85.125827 -281.400981) (xy 85.117932 -281.449558)
			(xy 85.102348 -281.496239) (xy 85.079477 -281.539816) (xy 85.049912 -281.57916) (xy 85.014419 -281.613252)
			(xy 84.973916 -281.641208) (xy 84.929454 -281.662306) (xy 84.882183 -281.675998) (xy 84.833328 -281.68193)
			(xy 84.784153 -281.679949) (xy 84.735934 -281.670105) (xy 84.689918 -281.652653) (xy 84.647297 -281.628046)
			(xy 84.609176 -281.596921) (xy 84.576541 -281.560084) (xy 84.550238 -281.518488) (xy 84.530947 -281.473212)
			(xy 84.51917 -281.425428) (xy 84.51521 -281.376374) (xy 84.186268 -281.376374) (xy 84.185824 -281.400367)
			(xy 84.17832 -281.447764) (xy 84.163493 -281.493402) (xy 84.141709 -281.536159) (xy 84.113503 -281.574981)
			(xy 84.07957 -281.608912) (xy 84.040747 -281.637116) (xy 83.997989 -281.658899) (xy 83.95235 -281.673723)
			(xy 83.904953 -281.681225) (xy 83.88096 -281.681682) (xy 83.85457 -281.68113) (xy 83.802573 -281.67207)
			(xy 83.752908 -281.654208) (xy 83.707051 -281.628076) (xy 83.666367 -281.594452) (xy 83.648804 -281.574748)
			(xy 83.627468 -281.549602) (xy 83.62569 -281.549602) (xy 83.621481 -281.549683) (xy 83.613182 -281.551089)
			(xy 83.60918 -281.552396) (xy 83.521804 -281.592782) (xy 83.514022 -281.597314) (xy 83.502033 -281.610735)
			(xy 83.495446 -281.627482) (xy 83.49488 -281.63647) (xy 83.49488 -281.80538) (xy 83.494912 -281.809516)
			(xy 83.496186 -281.817688) (xy 83.49742 -281.821636) (xy 83.502246 -281.831796) (xy 83.515708 -281.852878)
			(xy 83.519213 -281.858136) (xy 83.528342 -281.866867) (xy 83.533742 -281.87015) (xy 83.533996 -281.87015)
			(xy 83.555754 -281.882732) (xy 83.595196 -281.91388) (xy 83.612482 -281.932126) (xy 83.630122 -281.952326)
			(xy 83.658729 -281.997682) (xy 83.669378 -282.022296) (xy 83.672934 -282.0289) (xy 83.673188 -282.029408)
			(xy 83.686705 -282.053249) (xy 83.705954 -282.104557) (xy 83.715756 -282.158473) (xy 83.716368 -282.185872)
			(xy 83.716368 -282.18638) (xy 84.04531 -282.18638) (xy 84.04927 -282.137326) (xy 84.061047 -282.089542)
			(xy 84.080338 -282.044266) (xy 84.106641 -282.00267) (xy 84.139276 -281.965833) (xy 84.177397 -281.934708)
			(xy 84.220018 -281.910101) (xy 84.266034 -281.892649) (xy 84.314253 -281.882805) (xy 84.363428 -281.880824)
			(xy 84.412283 -281.886756) (xy 84.459554 -281.900448) (xy 84.504016 -281.921546) (xy 84.544519 -281.949502)
			(xy 84.580012 -281.983594) (xy 84.609577 -282.022938) (xy 84.632448 -282.066515) (xy 84.648032 -282.113196)
			(xy 84.655927 -282.161773) (xy 84.656422 -282.18638) (xy 84.98511 -282.18638) (xy 84.98907 -282.137326)
			(xy 85.000847 -282.089542) (xy 85.020138 -282.044266) (xy 85.046441 -282.00267) (xy 85.079076 -281.965833)
			(xy 85.117197 -281.934708) (xy 85.159818 -281.910101) (xy 85.205834 -281.892649) (xy 85.254053 -281.882805)
			(xy 85.303228 -281.880824) (xy 85.352083 -281.886756) (xy 85.399354 -281.900448) (xy 85.443816 -281.921546)
			(xy 85.484319 -281.949502) (xy 85.519812 -281.983594) (xy 85.549377 -282.022938) (xy 85.572248 -282.066515)
			(xy 85.587832 -282.113196) (xy 85.595727 -282.161773) (xy 85.596222 -282.18638) (xy 85.925164 -282.18638)
			(xy 85.929124 -282.137326) (xy 85.940901 -282.089542) (xy 85.960192 -282.044266) (xy 85.986495 -282.00267)
			(xy 86.01913 -281.965833) (xy 86.057251 -281.934708) (xy 86.099872 -281.910101) (xy 86.145888 -281.892649)
			(xy 86.194107 -281.882805) (xy 86.243282 -281.880824) (xy 86.292137 -281.886756) (xy 86.339408 -281.900448)
			(xy 86.38387 -281.921546) (xy 86.424373 -281.949502) (xy 86.459866 -281.983594) (xy 86.489431 -282.022938)
			(xy 86.512302 -282.066515) (xy 86.527886 -282.113196) (xy 86.535781 -282.161773) (xy 86.536276 -282.18638)
			(xy 86.865218 -282.18638) (xy 86.869178 -282.137326) (xy 86.880955 -282.089542) (xy 86.900246 -282.044266)
			(xy 86.926549 -282.00267) (xy 86.959184 -281.965833) (xy 86.997305 -281.934708) (xy 87.039926 -281.910101)
			(xy 87.085942 -281.892649) (xy 87.134161 -281.882805) (xy 87.183336 -281.880824) (xy 87.232191 -281.886756)
			(xy 87.279462 -281.900448) (xy 87.323924 -281.921546) (xy 87.364427 -281.949502) (xy 87.39992 -281.983594)
			(xy 87.429485 -282.022938) (xy 87.452356 -282.066515) (xy 87.46794 -282.113196) (xy 87.475835 -282.161773)
			(xy 87.47633 -282.18638) (xy 87.805272 -282.18638) (xy 87.809232 -282.137326) (xy 87.821009 -282.089542)
			(xy 87.8403 -282.044266) (xy 87.866603 -282.00267) (xy 87.899238 -281.965833) (xy 87.937359 -281.934708)
			(xy 87.97998 -281.910101) (xy 88.025996 -281.892649) (xy 88.074215 -281.882805) (xy 88.12339 -281.880824)
			(xy 88.172245 -281.886756) (xy 88.219516 -281.900448) (xy 88.263978 -281.921546) (xy 88.304481 -281.949502)
			(xy 88.339974 -281.983594) (xy 88.369539 -282.022938) (xy 88.39241 -282.066515) (xy 88.407994 -282.113196)
			(xy 88.415889 -282.161773) (xy 88.416384 -282.18638) (xy 88.745326 -282.18638) (xy 88.749286 -282.137326)
			(xy 88.761063 -282.089542) (xy 88.780354 -282.044266) (xy 88.806657 -282.00267) (xy 88.839292 -281.965833)
			(xy 88.877413 -281.934708) (xy 88.920034 -281.910101) (xy 88.96605 -281.892649) (xy 89.014269 -281.882805)
			(xy 89.063444 -281.880824) (xy 89.112299 -281.886756) (xy 89.15957 -281.900448) (xy 89.204032 -281.921546)
			(xy 89.244535 -281.949502) (xy 89.280028 -281.983594) (xy 89.309593 -282.022938) (xy 89.332464 -282.066515)
			(xy 89.348048 -282.113196) (xy 89.355943 -282.161773) (xy 89.356438 -282.18638) (xy 89.685126 -282.18638)
			(xy 89.689086 -282.137326) (xy 89.700863 -282.089542) (xy 89.720154 -282.044266) (xy 89.746457 -282.00267)
			(xy 89.779092 -281.965833) (xy 89.817213 -281.934708) (xy 89.859834 -281.910101) (xy 89.90585 -281.892649)
			(xy 89.954069 -281.882805) (xy 90.003244 -281.880824) (xy 90.052099 -281.886756) (xy 90.09937 -281.900448)
			(xy 90.143832 -281.921546) (xy 90.184335 -281.949502) (xy 90.219828 -281.983594) (xy 90.249393 -282.022938)
			(xy 90.272264 -282.066515) (xy 90.287848 -282.113196) (xy 90.295743 -282.161773) (xy 90.296238 -282.18638)
			(xy 90.614749 -282.18638) (xy 90.618844 -282.135652) (xy 90.631023 -282.086238) (xy 90.650971 -282.039418)
			(xy 90.678172 -281.996404) (xy 90.71192 -281.95831) (xy 90.751342 -281.926123) (xy 90.795416 -281.900677)
			(xy 90.843002 -281.88263) (xy 90.892866 -281.87245) (xy 90.943718 -281.870401) (xy 90.994239 -281.876535)
			(xy 91.043123 -281.890695) (xy 91.089102 -281.912512) (xy 91.130986 -281.941422) (xy 91.16769 -281.976677)
			(xy 91.198263 -282.017363) (xy 91.221914 -282.062426) (xy 91.23803 -282.1107) (xy 91.246194 -282.160934)
			(xy 91.246706 -282.18638) (xy 91.565234 -282.18638) (xy 91.569194 -282.137326) (xy 91.580971 -282.089542)
			(xy 91.600262 -282.044266) (xy 91.626565 -282.00267) (xy 91.6592 -281.965833) (xy 91.697321 -281.934708)
			(xy 91.739942 -281.910101) (xy 91.785958 -281.892649) (xy 91.834177 -281.882805) (xy 91.883352 -281.880824)
			(xy 91.932207 -281.886756) (xy 91.979478 -281.900448) (xy 92.02394 -281.921546) (xy 92.064443 -281.949502)
			(xy 92.099936 -281.983594) (xy 92.129501 -282.022938) (xy 92.152372 -282.066515) (xy 92.167956 -282.113196)
			(xy 92.175851 -282.161773) (xy 92.176346 -282.18638) (xy 92.494857 -282.18638) (xy 92.498952 -282.135652)
			(xy 92.511131 -282.086238) (xy 92.531079 -282.039418) (xy 92.55828 -281.996404) (xy 92.592028 -281.95831)
			(xy 92.63145 -281.926123) (xy 92.675524 -281.900677) (xy 92.72311 -281.88263) (xy 92.772974 -281.87245)
			(xy 92.823826 -281.870401) (xy 92.874347 -281.876535) (xy 92.923231 -281.890695) (xy 92.96921 -281.912512)
			(xy 93.011094 -281.941422) (xy 93.047798 -281.976677) (xy 93.078371 -282.017363) (xy 93.102022 -282.062426)
			(xy 93.118138 -282.1107) (xy 93.126302 -282.160934) (xy 93.126814 -282.18638) (xy 93.445342 -282.18638)
			(xy 93.449302 -282.137326) (xy 93.461079 -282.089542) (xy 93.48037 -282.044266) (xy 93.506673 -282.00267)
			(xy 93.539308 -281.965833) (xy 93.577429 -281.934708) (xy 93.62005 -281.910101) (xy 93.666066 -281.892649)
			(xy 93.714285 -281.882805) (xy 93.76346 -281.880824) (xy 93.812315 -281.886756) (xy 93.859586 -281.900448)
			(xy 93.904048 -281.921546) (xy 93.944551 -281.949502) (xy 93.980044 -281.983594) (xy 94.009609 -282.022938)
			(xy 94.03248 -282.066515) (xy 94.048064 -282.113196) (xy 94.055959 -282.161773) (xy 94.056454 -282.18638)
			(xy 94.374711 -282.18638) (xy 94.378806 -282.135652) (xy 94.390985 -282.086238) (xy 94.410933 -282.039418)
			(xy 94.438134 -281.996404) (xy 94.471882 -281.95831) (xy 94.511304 -281.926123) (xy 94.555378 -281.900677)
			(xy 94.602964 -281.88263) (xy 94.652828 -281.87245) (xy 94.70368 -281.870401) (xy 94.754201 -281.876535)
			(xy 94.803085 -281.890695) (xy 94.849064 -281.912512) (xy 94.890948 -281.941422) (xy 94.927652 -281.976677)
			(xy 94.958225 -282.017363) (xy 94.981876 -282.062426) (xy 94.997992 -282.1107) (xy 95.006156 -282.160934)
			(xy 95.006668 -282.18638) (xy 95.314765 -282.18638) (xy 95.31886 -282.135652) (xy 95.331039 -282.086238)
			(xy 95.350987 -282.039418) (xy 95.378188 -281.996404) (xy 95.411936 -281.95831) (xy 95.451358 -281.926123)
			(xy 95.495432 -281.900677) (xy 95.543018 -281.88263) (xy 95.592882 -281.87245) (xy 95.643734 -281.870401)
			(xy 95.694255 -281.876535) (xy 95.743139 -281.890695) (xy 95.789118 -281.912512) (xy 95.831002 -281.941422)
			(xy 95.867706 -281.976677) (xy 95.898279 -282.017363) (xy 95.92193 -282.062426) (xy 95.938046 -282.1107)
			(xy 95.94621 -282.160934) (xy 95.946722 -282.18638) (xy 95.94621 -282.211826) (xy 95.938046 -282.26206)
			(xy 95.92193 -282.310334) (xy 95.898279 -282.355397) (xy 95.867706 -282.396083) (xy 95.831002 -282.431338)
			(xy 95.789118 -282.460248) (xy 95.743139 -282.482065) (xy 95.694255 -282.496225) (xy 95.643734 -282.502359)
			(xy 95.592882 -282.50031) (xy 95.543018 -282.49013) (xy 95.495432 -282.472083) (xy 95.451358 -282.446637)
			(xy 95.411936 -282.41445) (xy 95.378188 -282.376356) (xy 95.350987 -282.333342) (xy 95.331039 -282.286522)
			(xy 95.31886 -282.237108) (xy 95.314765 -282.18638) (xy 95.006668 -282.18638) (xy 95.006156 -282.211826)
			(xy 94.997992 -282.26206) (xy 94.981876 -282.310334) (xy 94.958225 -282.355397) (xy 94.927652 -282.396083)
			(xy 94.890948 -282.431338) (xy 94.849064 -282.460248) (xy 94.803085 -282.482065) (xy 94.754201 -282.496225)
			(xy 94.70368 -282.502359) (xy 94.652828 -282.50031) (xy 94.602964 -282.49013) (xy 94.555378 -282.472083)
			(xy 94.511304 -282.446637) (xy 94.471882 -282.41445) (xy 94.438134 -282.376356) (xy 94.410933 -282.333342)
			(xy 94.390985 -282.286522) (xy 94.378806 -282.237108) (xy 94.374711 -282.18638) (xy 94.056454 -282.18638)
			(xy 94.055959 -282.210987) (xy 94.048064 -282.259564) (xy 94.03248 -282.306245) (xy 94.009609 -282.349822)
			(xy 93.980044 -282.389166) (xy 93.944551 -282.423258) (xy 93.904048 -282.451214) (xy 93.859586 -282.472312)
			(xy 93.812315 -282.486004) (xy 93.76346 -282.491936) (xy 93.714285 -282.489955) (xy 93.666066 -282.480111)
			(xy 93.62005 -282.462659) (xy 93.577429 -282.438052) (xy 93.539308 -282.406927) (xy 93.506673 -282.37009)
			(xy 93.48037 -282.328494) (xy 93.461079 -282.283218) (xy 93.449302 -282.235434) (xy 93.445342 -282.18638)
			(xy 93.126814 -282.18638) (xy 93.126302 -282.211826) (xy 93.118138 -282.26206) (xy 93.102022 -282.310334)
			(xy 93.078371 -282.355397) (xy 93.047798 -282.396083) (xy 93.011094 -282.431338) (xy 92.96921 -282.460248)
			(xy 92.923231 -282.482065) (xy 92.874347 -282.496225) (xy 92.823826 -282.502359) (xy 92.772974 -282.50031)
			(xy 92.72311 -282.49013) (xy 92.675524 -282.472083) (xy 92.63145 -282.446637) (xy 92.592028 -282.41445)
			(xy 92.55828 -282.376356) (xy 92.531079 -282.333342) (xy 92.511131 -282.286522) (xy 92.498952 -282.237108)
			(xy 92.494857 -282.18638) (xy 92.176346 -282.18638) (xy 92.175851 -282.210987) (xy 92.167956 -282.259564)
			(xy 92.152372 -282.306245) (xy 92.129501 -282.349822) (xy 92.099936 -282.389166) (xy 92.064443 -282.423258)
			(xy 92.02394 -282.451214) (xy 91.979478 -282.472312) (xy 91.932207 -282.486004) (xy 91.883352 -282.491936)
			(xy 91.834177 -282.489955) (xy 91.785958 -282.480111) (xy 91.739942 -282.462659) (xy 91.697321 -282.438052)
			(xy 91.6592 -282.406927) (xy 91.626565 -282.37009) (xy 91.600262 -282.328494) (xy 91.580971 -282.283218)
			(xy 91.569194 -282.235434) (xy 91.565234 -282.18638) (xy 91.246706 -282.18638) (xy 91.246194 -282.211826)
			(xy 91.23803 -282.26206) (xy 91.221914 -282.310334) (xy 91.198263 -282.355397) (xy 91.16769 -282.396083)
			(xy 91.130986 -282.431338) (xy 91.089102 -282.460248) (xy 91.043123 -282.482065) (xy 90.994239 -282.496225)
			(xy 90.943718 -282.502359) (xy 90.892866 -282.50031) (xy 90.843002 -282.49013) (xy 90.795416 -282.472083)
			(xy 90.751342 -282.446637) (xy 90.71192 -282.41445) (xy 90.678172 -282.376356) (xy 90.650971 -282.333342)
			(xy 90.631023 -282.286522) (xy 90.618844 -282.237108) (xy 90.614749 -282.18638) (xy 90.296238 -282.18638)
			(xy 90.295743 -282.210987) (xy 90.287848 -282.259564) (xy 90.272264 -282.306245) (xy 90.249393 -282.349822)
			(xy 90.219828 -282.389166) (xy 90.184335 -282.423258) (xy 90.143832 -282.451214) (xy 90.09937 -282.472312)
			(xy 90.052099 -282.486004) (xy 90.003244 -282.491936) (xy 89.954069 -282.489955) (xy 89.90585 -282.480111)
			(xy 89.859834 -282.462659) (xy 89.817213 -282.438052) (xy 89.779092 -282.406927) (xy 89.746457 -282.37009)
			(xy 89.720154 -282.328494) (xy 89.700863 -282.283218) (xy 89.689086 -282.235434) (xy 89.685126 -282.18638)
			(xy 89.356438 -282.18638) (xy 89.355943 -282.210987) (xy 89.348048 -282.259564) (xy 89.332464 -282.306245)
			(xy 89.309593 -282.349822) (xy 89.280028 -282.389166) (xy 89.244535 -282.423258) (xy 89.204032 -282.451214)
			(xy 89.15957 -282.472312) (xy 89.112299 -282.486004) (xy 89.063444 -282.491936) (xy 89.014269 -282.489955)
			(xy 88.96605 -282.480111) (xy 88.920034 -282.462659) (xy 88.877413 -282.438052) (xy 88.839292 -282.406927)
			(xy 88.806657 -282.37009) (xy 88.780354 -282.328494) (xy 88.761063 -282.283218) (xy 88.749286 -282.235434)
			(xy 88.745326 -282.18638) (xy 88.416384 -282.18638) (xy 88.415889 -282.210987) (xy 88.407994 -282.259564)
			(xy 88.39241 -282.306245) (xy 88.369539 -282.349822) (xy 88.339974 -282.389166) (xy 88.304481 -282.423258)
			(xy 88.263978 -282.451214) (xy 88.219516 -282.472312) (xy 88.172245 -282.486004) (xy 88.12339 -282.491936)
			(xy 88.074215 -282.489955) (xy 88.025996 -282.480111) (xy 87.97998 -282.462659) (xy 87.937359 -282.438052)
			(xy 87.899238 -282.406927) (xy 87.866603 -282.37009) (xy 87.8403 -282.328494) (xy 87.821009 -282.283218)
			(xy 87.809232 -282.235434) (xy 87.805272 -282.18638) (xy 87.47633 -282.18638) (xy 87.475835 -282.210987)
			(xy 87.46794 -282.259564) (xy 87.452356 -282.306245) (xy 87.429485 -282.349822) (xy 87.39992 -282.389166)
			(xy 87.364427 -282.423258) (xy 87.323924 -282.451214) (xy 87.279462 -282.472312) (xy 87.232191 -282.486004)
			(xy 87.183336 -282.491936) (xy 87.134161 -282.489955) (xy 87.085942 -282.480111) (xy 87.039926 -282.462659)
			(xy 86.997305 -282.438052) (xy 86.959184 -282.406927) (xy 86.926549 -282.37009) (xy 86.900246 -282.328494)
			(xy 86.880955 -282.283218) (xy 86.869178 -282.235434) (xy 86.865218 -282.18638) (xy 86.536276 -282.18638)
			(xy 86.535781 -282.210987) (xy 86.527886 -282.259564) (xy 86.512302 -282.306245) (xy 86.489431 -282.349822)
			(xy 86.459866 -282.389166) (xy 86.424373 -282.423258) (xy 86.38387 -282.451214) (xy 86.339408 -282.472312)
			(xy 86.292137 -282.486004) (xy 86.243282 -282.491936) (xy 86.194107 -282.489955) (xy 86.145888 -282.480111)
			(xy 86.099872 -282.462659) (xy 86.057251 -282.438052) (xy 86.01913 -282.406927) (xy 85.986495 -282.37009)
			(xy 85.960192 -282.328494) (xy 85.940901 -282.283218) (xy 85.929124 -282.235434) (xy 85.925164 -282.18638)
			(xy 85.596222 -282.18638) (xy 85.595727 -282.210987) (xy 85.587832 -282.259564) (xy 85.572248 -282.306245)
			(xy 85.549377 -282.349822) (xy 85.519812 -282.389166) (xy 85.484319 -282.423258) (xy 85.443816 -282.451214)
			(xy 85.399354 -282.472312) (xy 85.352083 -282.486004) (xy 85.303228 -282.491936) (xy 85.254053 -282.489955)
			(xy 85.205834 -282.480111) (xy 85.159818 -282.462659) (xy 85.117197 -282.438052) (xy 85.079076 -282.406927)
			(xy 85.046441 -282.37009) (xy 85.020138 -282.328494) (xy 85.000847 -282.283218) (xy 84.98907 -282.235434)
			(xy 84.98511 -282.18638) (xy 84.656422 -282.18638) (xy 84.655927 -282.210987) (xy 84.648032 -282.259564)
			(xy 84.632448 -282.306245) (xy 84.609577 -282.349822) (xy 84.580012 -282.389166) (xy 84.544519 -282.423258)
			(xy 84.504016 -282.451214) (xy 84.459554 -282.472312) (xy 84.412283 -282.486004) (xy 84.363428 -282.491936)
			(xy 84.314253 -282.489955) (xy 84.266034 -282.480111) (xy 84.220018 -282.462659) (xy 84.177397 -282.438052)
			(xy 84.139276 -282.406927) (xy 84.106641 -282.37009) (xy 84.080338 -282.328494) (xy 84.061047 -282.283218)
			(xy 84.04927 -282.235434) (xy 84.04531 -282.18638) (xy 83.716368 -282.18638) (xy 83.716368 -282.192222)
			(xy 83.715348 -282.217911) (xy 83.70577 -282.26842) (xy 83.687866 -282.316609) (xy 83.662142 -282.361119)
			(xy 83.629325 -282.40069) (xy 83.590343 -282.434204) (xy 83.546297 -282.460713) (xy 83.522566 -282.470606)
			(xy 83.512152 -282.474924) (xy 83.503516 -282.487624) (xy 83.499478 -282.494028) (xy 83.49507 -282.508504)
			(xy 83.49488 -282.516072) (xy 83.49488 -282.6385) (xy 83.495137 -282.644109) (xy 83.497823 -282.655009)
			(xy 83.500214 -282.66009) (xy 83.504786 -282.667964) (xy 83.508737 -282.672818) (xy 83.518497 -282.680649)
			(xy 83.52409 -282.683458) (xy 83.524344 -282.683712) (xy 83.605116 -282.72105) (xy 83.618832 -282.724352)
			(xy 83.631278 -282.72486) (xy 83.648042 -282.71851) (xy 83.6549 -282.715208) (xy 83.665314 -282.709366)
			(xy 83.6676 -282.707588) (xy 83.668616 -282.706826) (xy 83.66887 -282.706572) (xy 83.689157 -282.691497)
			(xy 83.733638 -282.667505) (xy 83.781453 -282.651137) (xy 83.831307 -282.642839) (xy 83.856576 -282.64231)
			(xy 83.882414 -282.642858) (xy 83.933351 -282.651571) (xy 83.982093 -282.668735) (xy 84.02725 -282.693861)
			(xy 84.067533 -282.72623) (xy 84.10179 -282.76492) (xy 84.129045 -282.808825) (xy 84.139278 -282.832556)
			(xy 84.142834 -282.83916) (xy 84.143088 -282.839668) (xy 84.156619 -282.863549) (xy 84.175873 -282.914942)
			(xy 84.185649 -282.968945) (xy 84.186268 -282.996386) (xy 84.51521 -282.996386) (xy 84.51917 -282.947332)
			(xy 84.530947 -282.899548) (xy 84.550238 -282.854272) (xy 84.576541 -282.812676) (xy 84.609176 -282.775839)
			(xy 84.647297 -282.744714) (xy 84.689918 -282.720107) (xy 84.735934 -282.702655) (xy 84.784153 -282.692811)
			(xy 84.833328 -282.69083) (xy 84.882183 -282.696762) (xy 84.929454 -282.710454) (xy 84.973916 -282.731552)
			(xy 85.014419 -282.759508) (xy 85.049912 -282.7936) (xy 85.079477 -282.832944) (xy 85.102348 -282.876521)
			(xy 85.117932 -282.923202) (xy 85.125827 -282.971779) (xy 85.126322 -282.996386) (xy 85.455264 -282.996386)
			(xy 85.459224 -282.947332) (xy 85.471001 -282.899548) (xy 85.490292 -282.854272) (xy 85.516595 -282.812676)
			(xy 85.54923 -282.775839) (xy 85.587351 -282.744714) (xy 85.629972 -282.720107) (xy 85.675988 -282.702655)
			(xy 85.724207 -282.692811) (xy 85.773382 -282.69083) (xy 85.822237 -282.696762) (xy 85.869508 -282.710454)
			(xy 85.91397 -282.731552) (xy 85.954473 -282.759508) (xy 85.989966 -282.7936) (xy 86.019531 -282.832944)
			(xy 86.042402 -282.876521) (xy 86.057986 -282.923202) (xy 86.065881 -282.971779) (xy 86.066376 -282.996386)
			(xy 87.335118 -282.996386) (xy 87.339078 -282.947332) (xy 87.350855 -282.899548) (xy 87.370146 -282.854272)
			(xy 87.396449 -282.812676) (xy 87.429084 -282.775839) (xy 87.467205 -282.744714) (xy 87.509826 -282.720107)
			(xy 87.555842 -282.702655) (xy 87.604061 -282.692811) (xy 87.653236 -282.69083) (xy 87.702091 -282.696762)
			(xy 87.749362 -282.710454) (xy 87.793824 -282.731552) (xy 87.834327 -282.759508) (xy 87.86982 -282.7936)
			(xy 87.899385 -282.832944) (xy 87.922256 -282.876521) (xy 87.93784 -282.923202) (xy 87.945735 -282.971779)
			(xy 87.94623 -282.996386) (xy 88.275172 -282.996386) (xy 88.279132 -282.947332) (xy 88.290909 -282.899548)
			(xy 88.3102 -282.854272) (xy 88.336503 -282.812676) (xy 88.369138 -282.775839) (xy 88.407259 -282.744714)
			(xy 88.44988 -282.720107) (xy 88.495896 -282.702655) (xy 88.544115 -282.692811) (xy 88.59329 -282.69083)
			(xy 88.642145 -282.696762) (xy 88.689416 -282.710454) (xy 88.733878 -282.731552) (xy 88.774381 -282.759508)
			(xy 88.809874 -282.7936) (xy 88.839439 -282.832944) (xy 88.86231 -282.876521) (xy 88.877894 -282.923202)
			(xy 88.885789 -282.971779) (xy 88.886284 -282.996386) (xy 89.215226 -282.996386) (xy 89.219186 -282.947332)
			(xy 89.230963 -282.899548) (xy 89.250254 -282.854272) (xy 89.276557 -282.812676) (xy 89.309192 -282.775839)
			(xy 89.347313 -282.744714) (xy 89.389934 -282.720107) (xy 89.43595 -282.702655) (xy 89.484169 -282.692811)
			(xy 89.533344 -282.69083) (xy 89.582199 -282.696762) (xy 89.62947 -282.710454) (xy 89.673932 -282.731552)
			(xy 89.714435 -282.759508) (xy 89.749928 -282.7936) (xy 89.779493 -282.832944) (xy 89.802364 -282.876521)
			(xy 89.817948 -282.923202) (xy 89.825843 -282.971779) (xy 89.826338 -282.996386) (xy 90.15528 -282.996386)
			(xy 90.15924 -282.947332) (xy 90.171017 -282.899548) (xy 90.190308 -282.854272) (xy 90.216611 -282.812676)
			(xy 90.249246 -282.775839) (xy 90.287367 -282.744714) (xy 90.329988 -282.720107) (xy 90.376004 -282.702655)
			(xy 90.424223 -282.692811) (xy 90.473398 -282.69083) (xy 90.522253 -282.696762) (xy 90.569524 -282.710454)
			(xy 90.613986 -282.731552) (xy 90.654489 -282.759508) (xy 90.689982 -282.7936) (xy 90.719547 -282.832944)
			(xy 90.742418 -282.876521) (xy 90.758002 -282.923202) (xy 90.765897 -282.971779) (xy 90.766392 -282.996386)
			(xy 91.084903 -282.996386) (xy 91.088998 -282.945658) (xy 91.101177 -282.896244) (xy 91.121125 -282.849424)
			(xy 91.148326 -282.80641) (xy 91.182074 -282.768316) (xy 91.221496 -282.736129) (xy 91.26557 -282.710683)
			(xy 91.313156 -282.692636) (xy 91.36302 -282.682456) (xy 91.413872 -282.680407) (xy 91.464393 -282.686541)
			(xy 91.513277 -282.700701) (xy 91.559256 -282.722518) (xy 91.60114 -282.751428) (xy 91.637844 -282.786683)
			(xy 91.668417 -282.827369) (xy 91.692068 -282.872432) (xy 91.708184 -282.920706) (xy 91.716348 -282.97094)
			(xy 91.71686 -282.996386) (xy 92.024703 -282.996386) (xy 92.028798 -282.945658) (xy 92.040977 -282.896244)
			(xy 92.060925 -282.849424) (xy 92.088126 -282.80641) (xy 92.121874 -282.768316) (xy 92.161296 -282.736129)
			(xy 92.20537 -282.710683) (xy 92.252956 -282.692636) (xy 92.30282 -282.682456) (xy 92.353672 -282.680407)
			(xy 92.404193 -282.686541) (xy 92.453077 -282.700701) (xy 92.499056 -282.722518) (xy 92.54094 -282.751428)
			(xy 92.577644 -282.786683) (xy 92.608217 -282.827369) (xy 92.631868 -282.872432) (xy 92.647984 -282.920706)
			(xy 92.656148 -282.97094) (xy 92.65666 -282.996386) (xy 93.904811 -282.996386) (xy 93.908906 -282.945658)
			(xy 93.921085 -282.896244) (xy 93.941033 -282.849424) (xy 93.968234 -282.80641) (xy 94.001982 -282.768316)
			(xy 94.041404 -282.736129) (xy 94.085478 -282.710683) (xy 94.133064 -282.692636) (xy 94.182928 -282.682456)
			(xy 94.23378 -282.680407) (xy 94.284301 -282.686541) (xy 94.333185 -282.700701) (xy 94.379164 -282.722518)
			(xy 94.421048 -282.751428) (xy 94.457752 -282.786683) (xy 94.488325 -282.827369) (xy 94.511976 -282.872432)
			(xy 94.528092 -282.920706) (xy 94.536256 -282.97094) (xy 94.536768 -282.996386) (xy 94.855296 -282.996386)
			(xy 94.859256 -282.947332) (xy 94.871033 -282.899548) (xy 94.890324 -282.854272) (xy 94.916627 -282.812676)
			(xy 94.949262 -282.775839) (xy 94.987383 -282.744714) (xy 95.030004 -282.720107) (xy 95.07602 -282.702655)
			(xy 95.124239 -282.692811) (xy 95.173414 -282.69083) (xy 95.222269 -282.696762) (xy 95.26954 -282.710454)
			(xy 95.314002 -282.731552) (xy 95.354505 -282.759508) (xy 95.389998 -282.7936) (xy 95.419563 -282.832944)
			(xy 95.442434 -282.876521) (xy 95.458018 -282.923202) (xy 95.465913 -282.971779) (xy 95.466408 -282.996386)
			(xy 95.784919 -282.996386) (xy 95.789014 -282.945658) (xy 95.801193 -282.896244) (xy 95.821141 -282.849424)
			(xy 95.848342 -282.80641) (xy 95.88209 -282.768316) (xy 95.921512 -282.736129) (xy 95.965586 -282.710683)
			(xy 96.013172 -282.692636) (xy 96.063036 -282.682456) (xy 96.113888 -282.680407) (xy 96.164409 -282.686541)
			(xy 96.213293 -282.700701) (xy 96.259272 -282.722518) (xy 96.301156 -282.751428) (xy 96.33786 -282.786683)
			(xy 96.368433 -282.827369) (xy 96.392084 -282.872432) (xy 96.4082 -282.920706) (xy 96.416364 -282.97094)
			(xy 96.416876 -282.996386) (xy 96.416364 -283.021832) (xy 96.4082 -283.072066) (xy 96.392084 -283.12034)
			(xy 96.368433 -283.165403) (xy 96.33786 -283.206089) (xy 96.301156 -283.241344) (xy 96.259272 -283.270254)
			(xy 96.213293 -283.292071) (xy 96.164409 -283.306231) (xy 96.113888 -283.312365) (xy 96.063036 -283.310316)
			(xy 96.013172 -283.300136) (xy 95.965586 -283.282089) (xy 95.921512 -283.256643) (xy 95.88209 -283.224456)
			(xy 95.848342 -283.186362) (xy 95.821141 -283.143348) (xy 95.801193 -283.096528) (xy 95.789014 -283.047114)
			(xy 95.784919 -282.996386) (xy 95.466408 -282.996386) (xy 95.465913 -283.020993) (xy 95.458018 -283.06957)
			(xy 95.442434 -283.116251) (xy 95.419563 -283.159828) (xy 95.389998 -283.199172) (xy 95.354505 -283.233264)
			(xy 95.314002 -283.26122) (xy 95.26954 -283.282318) (xy 95.222269 -283.29601) (xy 95.173414 -283.301942)
			(xy 95.124239 -283.299961) (xy 95.07602 -283.290117) (xy 95.030004 -283.272665) (xy 94.987383 -283.248058)
			(xy 94.949262 -283.216933) (xy 94.916627 -283.180096) (xy 94.890324 -283.1385) (xy 94.871033 -283.093224)
			(xy 94.859256 -283.04544) (xy 94.855296 -282.996386) (xy 94.536768 -282.996386) (xy 94.536256 -283.021832)
			(xy 94.528092 -283.072066) (xy 94.511976 -283.12034) (xy 94.488325 -283.165403) (xy 94.457752 -283.206089)
			(xy 94.421048 -283.241344) (xy 94.379164 -283.270254) (xy 94.333185 -283.292071) (xy 94.284301 -283.306231)
			(xy 94.23378 -283.312365) (xy 94.182928 -283.310316) (xy 94.133064 -283.300136) (xy 94.085478 -283.282089)
			(xy 94.041404 -283.256643) (xy 94.001982 -283.224456) (xy 93.968234 -283.186362) (xy 93.941033 -283.143348)
			(xy 93.921085 -283.096528) (xy 93.908906 -283.047114) (xy 93.904811 -282.996386) (xy 92.65666 -282.996386)
			(xy 92.656148 -283.021832) (xy 92.647984 -283.072066) (xy 92.631868 -283.12034) (xy 92.608217 -283.165403)
			(xy 92.577644 -283.206089) (xy 92.54094 -283.241344) (xy 92.499056 -283.270254) (xy 92.453077 -283.292071)
			(xy 92.404193 -283.306231) (xy 92.353672 -283.312365) (xy 92.30282 -283.310316) (xy 92.252956 -283.300136)
			(xy 92.20537 -283.282089) (xy 92.161296 -283.256643) (xy 92.121874 -283.224456) (xy 92.088126 -283.186362)
			(xy 92.060925 -283.143348) (xy 92.040977 -283.096528) (xy 92.028798 -283.047114) (xy 92.024703 -282.996386)
			(xy 91.71686 -282.996386) (xy 91.716348 -283.021832) (xy 91.708184 -283.072066) (xy 91.692068 -283.12034)
			(xy 91.668417 -283.165403) (xy 91.637844 -283.206089) (xy 91.60114 -283.241344) (xy 91.559256 -283.270254)
			(xy 91.513277 -283.292071) (xy 91.464393 -283.306231) (xy 91.413872 -283.312365) (xy 91.36302 -283.310316)
			(xy 91.313156 -283.300136) (xy 91.26557 -283.282089) (xy 91.221496 -283.256643) (xy 91.182074 -283.224456)
			(xy 91.148326 -283.186362) (xy 91.121125 -283.143348) (xy 91.101177 -283.096528) (xy 91.088998 -283.047114)
			(xy 91.084903 -282.996386) (xy 90.766392 -282.996386) (xy 90.765897 -283.020993) (xy 90.758002 -283.06957)
			(xy 90.742418 -283.116251) (xy 90.719547 -283.159828) (xy 90.689982 -283.199172) (xy 90.654489 -283.233264)
			(xy 90.613986 -283.26122) (xy 90.569524 -283.282318) (xy 90.522253 -283.29601) (xy 90.473398 -283.301942)
			(xy 90.424223 -283.299961) (xy 90.376004 -283.290117) (xy 90.329988 -283.272665) (xy 90.287367 -283.248058)
			(xy 90.249246 -283.216933) (xy 90.216611 -283.180096) (xy 90.190308 -283.1385) (xy 90.171017 -283.093224)
			(xy 90.15924 -283.04544) (xy 90.15528 -282.996386) (xy 89.826338 -282.996386) (xy 89.825843 -283.020993)
			(xy 89.817948 -283.06957) (xy 89.802364 -283.116251) (xy 89.779493 -283.159828) (xy 89.749928 -283.199172)
			(xy 89.714435 -283.233264) (xy 89.673932 -283.26122) (xy 89.62947 -283.282318) (xy 89.582199 -283.29601)
			(xy 89.533344 -283.301942) (xy 89.484169 -283.299961) (xy 89.43595 -283.290117) (xy 89.389934 -283.272665)
			(xy 89.347313 -283.248058) (xy 89.309192 -283.216933) (xy 89.276557 -283.180096) (xy 89.250254 -283.1385)
			(xy 89.230963 -283.093224) (xy 89.219186 -283.04544) (xy 89.215226 -282.996386) (xy 88.886284 -282.996386)
			(xy 88.885789 -283.020993) (xy 88.877894 -283.06957) (xy 88.86231 -283.116251) (xy 88.839439 -283.159828)
			(xy 88.809874 -283.199172) (xy 88.774381 -283.233264) (xy 88.733878 -283.26122) (xy 88.689416 -283.282318)
			(xy 88.642145 -283.29601) (xy 88.59329 -283.301942) (xy 88.544115 -283.299961) (xy 88.495896 -283.290117)
			(xy 88.44988 -283.272665) (xy 88.407259 -283.248058) (xy 88.369138 -283.216933) (xy 88.336503 -283.180096)
			(xy 88.3102 -283.1385) (xy 88.290909 -283.093224) (xy 88.279132 -283.04544) (xy 88.275172 -282.996386)
			(xy 87.94623 -282.996386) (xy 87.945735 -283.020993) (xy 87.93784 -283.06957) (xy 87.922256 -283.116251)
			(xy 87.899385 -283.159828) (xy 87.86982 -283.199172) (xy 87.834327 -283.233264) (xy 87.793824 -283.26122)
			(xy 87.749362 -283.282318) (xy 87.702091 -283.29601) (xy 87.653236 -283.301942) (xy 87.604061 -283.299961)
			(xy 87.555842 -283.290117) (xy 87.509826 -283.272665) (xy 87.467205 -283.248058) (xy 87.429084 -283.216933)
			(xy 87.396449 -283.180096) (xy 87.370146 -283.1385) (xy 87.350855 -283.093224) (xy 87.339078 -283.04544)
			(xy 87.335118 -282.996386) (xy 86.066376 -282.996386) (xy 86.065881 -283.020993) (xy 86.057986 -283.06957)
			(xy 86.042402 -283.116251) (xy 86.019531 -283.159828) (xy 85.989966 -283.199172) (xy 85.954473 -283.233264)
			(xy 85.91397 -283.26122) (xy 85.869508 -283.282318) (xy 85.822237 -283.29601) (xy 85.773382 -283.301942)
			(xy 85.724207 -283.299961) (xy 85.675988 -283.290117) (xy 85.629972 -283.272665) (xy 85.587351 -283.248058)
			(xy 85.54923 -283.216933) (xy 85.516595 -283.180096) (xy 85.490292 -283.1385) (xy 85.471001 -283.093224)
			(xy 85.459224 -283.04544) (xy 85.455264 -282.996386) (xy 85.126322 -282.996386) (xy 85.125827 -283.020993)
			(xy 85.117932 -283.06957) (xy 85.102348 -283.116251) (xy 85.079477 -283.159828) (xy 85.049912 -283.199172)
			(xy 85.014419 -283.233264) (xy 84.973916 -283.26122) (xy 84.929454 -283.282318) (xy 84.882183 -283.29601)
			(xy 84.833328 -283.301942) (xy 84.784153 -283.299961) (xy 84.735934 -283.290117) (xy 84.689918 -283.272665)
			(xy 84.647297 -283.248058) (xy 84.609176 -283.216933) (xy 84.576541 -283.180096) (xy 84.550238 -283.1385)
			(xy 84.530947 -283.093224) (xy 84.51917 -283.04544) (xy 84.51521 -282.996386) (xy 84.186268 -282.996386)
			(xy 84.185823 -283.020379) (xy 84.178318 -283.067774) (xy 84.16349 -283.113411) (xy 84.141705 -283.156166)
			(xy 84.113498 -283.194986) (xy 84.079566 -283.228915) (xy 84.040743 -283.257118) (xy 83.997986 -283.2789)
			(xy 83.952348 -283.293724) (xy 83.904953 -283.301225) (xy 83.88096 -283.301694) (xy 83.85457 -283.301143)
			(xy 83.802573 -283.292082) (xy 83.752907 -283.274221) (xy 83.707049 -283.24809) (xy 83.666365 -283.214467)
			(xy 83.648804 -283.19476) (xy 83.627468 -283.169614) (xy 83.62569 -283.169614) (xy 83.621481 -283.169695)
			(xy 83.613182 -283.171102) (xy 83.60918 -283.172408) (xy 83.521804 -283.212794) (xy 83.514024 -283.217327)
			(xy 83.502038 -283.230748) (xy 83.495455 -283.247495) (xy 83.49488 -283.256482) (xy 83.49488 -283.425392)
			(xy 83.494913 -283.429528) (xy 83.496189 -283.437699) (xy 83.49742 -283.441648) (xy 83.502246 -283.451808)
			(xy 83.515708 -283.47289) (xy 83.519207 -283.478154) (xy 83.528329 -283.486899) (xy 83.533742 -283.490162)
			(xy 83.533996 -283.490162) (xy 83.555757 -283.502741) (xy 83.595205 -283.533883) (xy 83.612482 -283.552138)
			(xy 83.630127 -283.572335) (xy 83.658746 -283.617686) (xy 83.669378 -283.642308) (xy 83.672934 -283.648912)
			(xy 83.673188 -283.64942) (xy 83.686704 -283.673262) (xy 83.705951 -283.724569) (xy 83.71575 -283.778485)
			(xy 83.716368 -283.805884) (xy 83.716368 -283.806392) (xy 84.04531 -283.806392) (xy 84.04927 -283.757338)
			(xy 84.061047 -283.709554) (xy 84.080338 -283.664278) (xy 84.106641 -283.622682) (xy 84.139276 -283.585845)
			(xy 84.177397 -283.55472) (xy 84.220018 -283.530113) (xy 84.266034 -283.512661) (xy 84.314253 -283.502817)
			(xy 84.363428 -283.500836) (xy 84.412283 -283.506768) (xy 84.459554 -283.52046) (xy 84.504016 -283.541558)
			(xy 84.544519 -283.569514) (xy 84.580012 -283.603606) (xy 84.609577 -283.64295) (xy 84.632448 -283.686527)
			(xy 84.648032 -283.733208) (xy 84.655927 -283.781785) (xy 84.656422 -283.806392) (xy 84.98511 -283.806392)
			(xy 84.98907 -283.757338) (xy 85.000847 -283.709554) (xy 85.020138 -283.664278) (xy 85.046441 -283.622682)
			(xy 85.079076 -283.585845) (xy 85.117197 -283.55472) (xy 85.159818 -283.530113) (xy 85.205834 -283.512661)
			(xy 85.254053 -283.502817) (xy 85.303228 -283.500836) (xy 85.352083 -283.506768) (xy 85.399354 -283.52046)
			(xy 85.443816 -283.541558) (xy 85.484319 -283.569514) (xy 85.519812 -283.603606) (xy 85.549377 -283.64295)
			(xy 85.572248 -283.686527) (xy 85.587832 -283.733208) (xy 85.595727 -283.781785) (xy 85.596222 -283.806392)
			(xy 85.925164 -283.806392) (xy 85.929124 -283.757338) (xy 85.940901 -283.709554) (xy 85.960192 -283.664278)
			(xy 85.986495 -283.622682) (xy 86.01913 -283.585845) (xy 86.057251 -283.55472) (xy 86.099872 -283.530113)
			(xy 86.145888 -283.512661) (xy 86.194107 -283.502817) (xy 86.243282 -283.500836) (xy 86.292137 -283.506768)
			(xy 86.339408 -283.52046) (xy 86.38387 -283.541558) (xy 86.424373 -283.569514) (xy 86.459866 -283.603606)
			(xy 86.489431 -283.64295) (xy 86.512302 -283.686527) (xy 86.527886 -283.733208) (xy 86.535781 -283.781785)
			(xy 86.536276 -283.806392) (xy 86.865218 -283.806392) (xy 86.869178 -283.757338) (xy 86.880955 -283.709554)
			(xy 86.900246 -283.664278) (xy 86.926549 -283.622682) (xy 86.959184 -283.585845) (xy 86.997305 -283.55472)
			(xy 87.039926 -283.530113) (xy 87.085942 -283.512661) (xy 87.134161 -283.502817) (xy 87.183336 -283.500836)
			(xy 87.232191 -283.506768) (xy 87.279462 -283.52046) (xy 87.323924 -283.541558) (xy 87.364427 -283.569514)
			(xy 87.39992 -283.603606) (xy 87.429485 -283.64295) (xy 87.452356 -283.686527) (xy 87.46794 -283.733208)
			(xy 87.475835 -283.781785) (xy 87.47633 -283.806392) (xy 87.805272 -283.806392) (xy 87.809232 -283.757338)
			(xy 87.821009 -283.709554) (xy 87.8403 -283.664278) (xy 87.866603 -283.622682) (xy 87.899238 -283.585845)
			(xy 87.937359 -283.55472) (xy 87.97998 -283.530113) (xy 88.025996 -283.512661) (xy 88.074215 -283.502817)
			(xy 88.12339 -283.500836) (xy 88.172245 -283.506768) (xy 88.219516 -283.52046) (xy 88.263978 -283.541558)
			(xy 88.304481 -283.569514) (xy 88.339974 -283.603606) (xy 88.369539 -283.64295) (xy 88.39241 -283.686527)
			(xy 88.407994 -283.733208) (xy 88.415889 -283.781785) (xy 88.416384 -283.806392) (xy 88.745326 -283.806392)
			(xy 88.749286 -283.757338) (xy 88.761063 -283.709554) (xy 88.780354 -283.664278) (xy 88.806657 -283.622682)
			(xy 88.839292 -283.585845) (xy 88.877413 -283.55472) (xy 88.920034 -283.530113) (xy 88.96605 -283.512661)
			(xy 89.014269 -283.502817) (xy 89.063444 -283.500836) (xy 89.112299 -283.506768) (xy 89.15957 -283.52046)
			(xy 89.204032 -283.541558) (xy 89.244535 -283.569514) (xy 89.280028 -283.603606) (xy 89.309593 -283.64295)
			(xy 89.332464 -283.686527) (xy 89.348048 -283.733208) (xy 89.355943 -283.781785) (xy 89.356438 -283.806392)
			(xy 89.685126 -283.806392) (xy 89.689086 -283.757338) (xy 89.700863 -283.709554) (xy 89.720154 -283.664278)
			(xy 89.746457 -283.622682) (xy 89.779092 -283.585845) (xy 89.817213 -283.55472) (xy 89.859834 -283.530113)
			(xy 89.90585 -283.512661) (xy 89.954069 -283.502817) (xy 90.003244 -283.500836) (xy 90.052099 -283.506768)
			(xy 90.09937 -283.52046) (xy 90.143832 -283.541558) (xy 90.184335 -283.569514) (xy 90.219828 -283.603606)
			(xy 90.249393 -283.64295) (xy 90.272264 -283.686527) (xy 90.287848 -283.733208) (xy 90.295743 -283.781785)
			(xy 90.296238 -283.806392) (xy 90.614749 -283.806392) (xy 90.618844 -283.755664) (xy 90.631023 -283.70625)
			(xy 90.650971 -283.65943) (xy 90.678172 -283.616416) (xy 90.71192 -283.578322) (xy 90.751342 -283.546135)
			(xy 90.795416 -283.520689) (xy 90.843002 -283.502642) (xy 90.892866 -283.492462) (xy 90.943718 -283.490413)
			(xy 90.994239 -283.496547) (xy 91.043123 -283.510707) (xy 91.089102 -283.532524) (xy 91.130986 -283.561434)
			(xy 91.16769 -283.596689) (xy 91.198263 -283.637375) (xy 91.221914 -283.682438) (xy 91.23803 -283.730712)
			(xy 91.246194 -283.780946) (xy 91.246706 -283.806392) (xy 91.565234 -283.806392) (xy 91.569194 -283.757338)
			(xy 91.580971 -283.709554) (xy 91.600262 -283.664278) (xy 91.626565 -283.622682) (xy 91.6592 -283.585845)
			(xy 91.697321 -283.55472) (xy 91.739942 -283.530113) (xy 91.785958 -283.512661) (xy 91.834177 -283.502817)
			(xy 91.883352 -283.500836) (xy 91.932207 -283.506768) (xy 91.979478 -283.52046) (xy 92.02394 -283.541558)
			(xy 92.064443 -283.569514) (xy 92.099936 -283.603606) (xy 92.129501 -283.64295) (xy 92.152372 -283.686527)
			(xy 92.167956 -283.733208) (xy 92.175851 -283.781785) (xy 92.176346 -283.806392) (xy 92.494857 -283.806392)
			(xy 92.498952 -283.755664) (xy 92.511131 -283.70625) (xy 92.531079 -283.65943) (xy 92.55828 -283.616416)
			(xy 92.592028 -283.578322) (xy 92.63145 -283.546135) (xy 92.675524 -283.520689) (xy 92.72311 -283.502642)
			(xy 92.772974 -283.492462) (xy 92.823826 -283.490413) (xy 92.874347 -283.496547) (xy 92.923231 -283.510707)
			(xy 92.96921 -283.532524) (xy 93.011094 -283.561434) (xy 93.047798 -283.596689) (xy 93.078371 -283.637375)
			(xy 93.102022 -283.682438) (xy 93.118138 -283.730712) (xy 93.126302 -283.780946) (xy 93.126814 -283.806392)
			(xy 93.445342 -283.806392) (xy 93.449302 -283.757338) (xy 93.461079 -283.709554) (xy 93.48037 -283.664278)
			(xy 93.506673 -283.622682) (xy 93.539308 -283.585845) (xy 93.577429 -283.55472) (xy 93.62005 -283.530113)
			(xy 93.666066 -283.512661) (xy 93.714285 -283.502817) (xy 93.76346 -283.500836) (xy 93.812315 -283.506768)
			(xy 93.859586 -283.52046) (xy 93.904048 -283.541558) (xy 93.944551 -283.569514) (xy 93.980044 -283.603606)
			(xy 94.009609 -283.64295) (xy 94.03248 -283.686527) (xy 94.048064 -283.733208) (xy 94.055959 -283.781785)
			(xy 94.056454 -283.806392) (xy 94.374711 -283.806392) (xy 94.378806 -283.755664) (xy 94.390985 -283.70625)
			(xy 94.410933 -283.65943) (xy 94.438134 -283.616416) (xy 94.471882 -283.578322) (xy 94.511304 -283.546135)
			(xy 94.555378 -283.520689) (xy 94.602964 -283.502642) (xy 94.652828 -283.492462) (xy 94.70368 -283.490413)
			(xy 94.754201 -283.496547) (xy 94.803085 -283.510707) (xy 94.849064 -283.532524) (xy 94.890948 -283.561434)
			(xy 94.927652 -283.596689) (xy 94.958225 -283.637375) (xy 94.981876 -283.682438) (xy 94.997992 -283.730712)
			(xy 95.006156 -283.780946) (xy 95.006668 -283.806392) (xy 95.314765 -283.806392) (xy 95.31886 -283.755664)
			(xy 95.331039 -283.70625) (xy 95.350987 -283.65943) (xy 95.378188 -283.616416) (xy 95.411936 -283.578322)
			(xy 95.451358 -283.546135) (xy 95.495432 -283.520689) (xy 95.543018 -283.502642) (xy 95.592882 -283.492462)
			(xy 95.643734 -283.490413) (xy 95.694255 -283.496547) (xy 95.743139 -283.510707) (xy 95.789118 -283.532524)
			(xy 95.831002 -283.561434) (xy 95.867706 -283.596689) (xy 95.898279 -283.637375) (xy 95.92193 -283.682438)
			(xy 95.938046 -283.730712) (xy 95.94621 -283.780946) (xy 95.946722 -283.806392) (xy 95.94621 -283.831838)
			(xy 95.938046 -283.882072) (xy 95.92193 -283.930346) (xy 95.898279 -283.975409) (xy 95.867706 -284.016095)
			(xy 95.831002 -284.05135) (xy 95.789118 -284.08026) (xy 95.743139 -284.102077) (xy 95.694255 -284.116237)
			(xy 95.643734 -284.122371) (xy 95.592882 -284.120322) (xy 95.543018 -284.110142) (xy 95.495432 -284.092095)
			(xy 95.451358 -284.066649) (xy 95.411936 -284.034462) (xy 95.378188 -283.996368) (xy 95.350987 -283.953354)
			(xy 95.331039 -283.906534) (xy 95.31886 -283.85712) (xy 95.314765 -283.806392) (xy 95.006668 -283.806392)
			(xy 95.006156 -283.831838) (xy 94.997992 -283.882072) (xy 94.981876 -283.930346) (xy 94.958225 -283.975409)
			(xy 94.927652 -284.016095) (xy 94.890948 -284.05135) (xy 94.849064 -284.08026) (xy 94.803085 -284.102077)
			(xy 94.754201 -284.116237) (xy 94.70368 -284.122371) (xy 94.652828 -284.120322) (xy 94.602964 -284.110142)
			(xy 94.555378 -284.092095) (xy 94.511304 -284.066649) (xy 94.471882 -284.034462) (xy 94.438134 -283.996368)
			(xy 94.410933 -283.953354) (xy 94.390985 -283.906534) (xy 94.378806 -283.85712) (xy 94.374711 -283.806392)
			(xy 94.056454 -283.806392) (xy 94.055959 -283.830999) (xy 94.048064 -283.879576) (xy 94.03248 -283.926257)
			(xy 94.009609 -283.969834) (xy 93.980044 -284.009178) (xy 93.944551 -284.04327) (xy 93.904048 -284.071226)
			(xy 93.859586 -284.092324) (xy 93.812315 -284.106016) (xy 93.76346 -284.111948) (xy 93.714285 -284.109967)
			(xy 93.666066 -284.100123) (xy 93.62005 -284.082671) (xy 93.577429 -284.058064) (xy 93.539308 -284.026939)
			(xy 93.506673 -283.990102) (xy 93.48037 -283.948506) (xy 93.461079 -283.90323) (xy 93.449302 -283.855446)
			(xy 93.445342 -283.806392) (xy 93.126814 -283.806392) (xy 93.126302 -283.831838) (xy 93.118138 -283.882072)
			(xy 93.102022 -283.930346) (xy 93.078371 -283.975409) (xy 93.047798 -284.016095) (xy 93.011094 -284.05135)
			(xy 92.96921 -284.08026) (xy 92.923231 -284.102077) (xy 92.874347 -284.116237) (xy 92.823826 -284.122371)
			(xy 92.772974 -284.120322) (xy 92.72311 -284.110142) (xy 92.675524 -284.092095) (xy 92.63145 -284.066649)
			(xy 92.592028 -284.034462) (xy 92.55828 -283.996368) (xy 92.531079 -283.953354) (xy 92.511131 -283.906534)
			(xy 92.498952 -283.85712) (xy 92.494857 -283.806392) (xy 92.176346 -283.806392) (xy 92.175851 -283.830999)
			(xy 92.167956 -283.879576) (xy 92.152372 -283.926257) (xy 92.129501 -283.969834) (xy 92.099936 -284.009178)
			(xy 92.064443 -284.04327) (xy 92.02394 -284.071226) (xy 91.979478 -284.092324) (xy 91.932207 -284.106016)
			(xy 91.883352 -284.111948) (xy 91.834177 -284.109967) (xy 91.785958 -284.100123) (xy 91.739942 -284.082671)
			(xy 91.697321 -284.058064) (xy 91.6592 -284.026939) (xy 91.626565 -283.990102) (xy 91.600262 -283.948506)
			(xy 91.580971 -283.90323) (xy 91.569194 -283.855446) (xy 91.565234 -283.806392) (xy 91.246706 -283.806392)
			(xy 91.246194 -283.831838) (xy 91.23803 -283.882072) (xy 91.221914 -283.930346) (xy 91.198263 -283.975409)
			(xy 91.16769 -284.016095) (xy 91.130986 -284.05135) (xy 91.089102 -284.08026) (xy 91.043123 -284.102077)
			(xy 90.994239 -284.116237) (xy 90.943718 -284.122371) (xy 90.892866 -284.120322) (xy 90.843002 -284.110142)
			(xy 90.795416 -284.092095) (xy 90.751342 -284.066649) (xy 90.71192 -284.034462) (xy 90.678172 -283.996368)
			(xy 90.650971 -283.953354) (xy 90.631023 -283.906534) (xy 90.618844 -283.85712) (xy 90.614749 -283.806392)
			(xy 90.296238 -283.806392) (xy 90.295743 -283.830999) (xy 90.287848 -283.879576) (xy 90.272264 -283.926257)
			(xy 90.249393 -283.969834) (xy 90.219828 -284.009178) (xy 90.184335 -284.04327) (xy 90.143832 -284.071226)
			(xy 90.09937 -284.092324) (xy 90.052099 -284.106016) (xy 90.003244 -284.111948) (xy 89.954069 -284.109967)
			(xy 89.90585 -284.100123) (xy 89.859834 -284.082671) (xy 89.817213 -284.058064) (xy 89.779092 -284.026939)
			(xy 89.746457 -283.990102) (xy 89.720154 -283.948506) (xy 89.700863 -283.90323) (xy 89.689086 -283.855446)
			(xy 89.685126 -283.806392) (xy 89.356438 -283.806392) (xy 89.355943 -283.830999) (xy 89.348048 -283.879576)
			(xy 89.332464 -283.926257) (xy 89.309593 -283.969834) (xy 89.280028 -284.009178) (xy 89.244535 -284.04327)
			(xy 89.204032 -284.071226) (xy 89.15957 -284.092324) (xy 89.112299 -284.106016) (xy 89.063444 -284.111948)
			(xy 89.014269 -284.109967) (xy 88.96605 -284.100123) (xy 88.920034 -284.082671) (xy 88.877413 -284.058064)
			(xy 88.839292 -284.026939) (xy 88.806657 -283.990102) (xy 88.780354 -283.948506) (xy 88.761063 -283.90323)
			(xy 88.749286 -283.855446) (xy 88.745326 -283.806392) (xy 88.416384 -283.806392) (xy 88.415889 -283.830999)
			(xy 88.407994 -283.879576) (xy 88.39241 -283.926257) (xy 88.369539 -283.969834) (xy 88.339974 -284.009178)
			(xy 88.304481 -284.04327) (xy 88.263978 -284.071226) (xy 88.219516 -284.092324) (xy 88.172245 -284.106016)
			(xy 88.12339 -284.111948) (xy 88.074215 -284.109967) (xy 88.025996 -284.100123) (xy 87.97998 -284.082671)
			(xy 87.937359 -284.058064) (xy 87.899238 -284.026939) (xy 87.866603 -283.990102) (xy 87.8403 -283.948506)
			(xy 87.821009 -283.90323) (xy 87.809232 -283.855446) (xy 87.805272 -283.806392) (xy 87.47633 -283.806392)
			(xy 87.475835 -283.830999) (xy 87.46794 -283.879576) (xy 87.452356 -283.926257) (xy 87.429485 -283.969834)
			(xy 87.39992 -284.009178) (xy 87.364427 -284.04327) (xy 87.323924 -284.071226) (xy 87.279462 -284.092324)
			(xy 87.232191 -284.106016) (xy 87.183336 -284.111948) (xy 87.134161 -284.109967) (xy 87.085942 -284.100123)
			(xy 87.039926 -284.082671) (xy 86.997305 -284.058064) (xy 86.959184 -284.026939) (xy 86.926549 -283.990102)
			(xy 86.900246 -283.948506) (xy 86.880955 -283.90323) (xy 86.869178 -283.855446) (xy 86.865218 -283.806392)
			(xy 86.536276 -283.806392) (xy 86.535781 -283.830999) (xy 86.527886 -283.879576) (xy 86.512302 -283.926257)
			(xy 86.489431 -283.969834) (xy 86.459866 -284.009178) (xy 86.424373 -284.04327) (xy 86.38387 -284.071226)
			(xy 86.339408 -284.092324) (xy 86.292137 -284.106016) (xy 86.243282 -284.111948) (xy 86.194107 -284.109967)
			(xy 86.145888 -284.100123) (xy 86.099872 -284.082671) (xy 86.057251 -284.058064) (xy 86.01913 -284.026939)
			(xy 85.986495 -283.990102) (xy 85.960192 -283.948506) (xy 85.940901 -283.90323) (xy 85.929124 -283.855446)
			(xy 85.925164 -283.806392) (xy 85.596222 -283.806392) (xy 85.595727 -283.830999) (xy 85.587832 -283.879576)
			(xy 85.572248 -283.926257) (xy 85.549377 -283.969834) (xy 85.519812 -284.009178) (xy 85.484319 -284.04327)
			(xy 85.443816 -284.071226) (xy 85.399354 -284.092324) (xy 85.352083 -284.106016) (xy 85.303228 -284.111948)
			(xy 85.254053 -284.109967) (xy 85.205834 -284.100123) (xy 85.159818 -284.082671) (xy 85.117197 -284.058064)
			(xy 85.079076 -284.026939) (xy 85.046441 -283.990102) (xy 85.020138 -283.948506) (xy 85.000847 -283.90323)
			(xy 84.98907 -283.855446) (xy 84.98511 -283.806392) (xy 84.656422 -283.806392) (xy 84.655927 -283.830999)
			(xy 84.648032 -283.879576) (xy 84.632448 -283.926257) (xy 84.609577 -283.969834) (xy 84.580012 -284.009178)
			(xy 84.544519 -284.04327) (xy 84.504016 -284.071226) (xy 84.459554 -284.092324) (xy 84.412283 -284.106016)
			(xy 84.363428 -284.111948) (xy 84.314253 -284.109967) (xy 84.266034 -284.100123) (xy 84.220018 -284.082671)
			(xy 84.177397 -284.058064) (xy 84.139276 -284.026939) (xy 84.106641 -283.990102) (xy 84.080338 -283.948506)
			(xy 84.061047 -283.90323) (xy 84.04927 -283.855446) (xy 84.04531 -283.806392) (xy 83.716368 -283.806392)
			(xy 83.716368 -283.812234) (xy 83.715347 -283.837923) (xy 83.705767 -283.88843) (xy 83.687862 -283.936618)
			(xy 83.662138 -283.981126) (xy 83.62932 -284.020695) (xy 83.590338 -284.054207) (xy 83.546292 -284.080715)
			(xy 83.522566 -284.090618) (xy 83.512152 -284.094936) (xy 83.503516 -284.107636) (xy 83.49948 -284.114041)
			(xy 83.495075 -284.128517) (xy 83.49488 -284.136084) (xy 83.49488 -284.258512) (xy 83.495138 -284.264121)
			(xy 83.497827 -284.27502) (xy 83.500214 -284.280102) (xy 83.504786 -284.287976) (xy 83.508738 -284.292829)
			(xy 83.518498 -284.300658) (xy 83.52409 -284.30347) (xy 83.524344 -284.303724) (xy 83.605116 -284.341062)
			(xy 83.618832 -284.344364) (xy 83.631278 -284.344872) (xy 83.648042 -284.338522) (xy 83.6549 -284.33522)
			(xy 83.665314 -284.329378) (xy 83.6676 -284.3276) (xy 83.668616 -284.326838) (xy 83.66887 -284.326584)
			(xy 83.689157 -284.311509) (xy 83.733638 -284.287515) (xy 83.781453 -284.271147) (xy 83.831306 -284.262849)
			(xy 83.856576 -284.262322) (xy 83.882414 -284.26287) (xy 83.93335 -284.271583) (xy 83.982092 -284.288748)
			(xy 84.027248 -284.313874) (xy 84.06753 -284.346244) (xy 84.101786 -284.384934) (xy 84.129039 -284.428839)
			(xy 84.139278 -284.452568) (xy 84.142834 -284.459172) (xy 84.143088 -284.45968) (xy 84.156618 -284.483561)
			(xy 84.17587 -284.534954) (xy 84.185644 -284.588957) (xy 84.186268 -284.616398) (xy 84.51521 -284.616398)
			(xy 84.51917 -284.567344) (xy 84.530947 -284.51956) (xy 84.550238 -284.474284) (xy 84.576541 -284.432688)
			(xy 84.609176 -284.395851) (xy 84.647297 -284.364726) (xy 84.689918 -284.340119) (xy 84.735934 -284.322667)
			(xy 84.784153 -284.312823) (xy 84.833328 -284.310842) (xy 84.882183 -284.316774) (xy 84.929454 -284.330466)
			(xy 84.973916 -284.351564) (xy 85.014419 -284.37952) (xy 85.049912 -284.413612) (xy 85.079477 -284.452956)
			(xy 85.102348 -284.496533) (xy 85.117932 -284.543214) (xy 85.125827 -284.591791) (xy 85.126322 -284.616398)
			(xy 85.455264 -284.616398) (xy 85.459224 -284.567344) (xy 85.471001 -284.51956) (xy 85.490292 -284.474284)
			(xy 85.516595 -284.432688) (xy 85.54923 -284.395851) (xy 85.587351 -284.364726) (xy 85.629972 -284.340119)
			(xy 85.675988 -284.322667) (xy 85.724207 -284.312823) (xy 85.773382 -284.310842) (xy 85.822237 -284.316774)
			(xy 85.869508 -284.330466) (xy 85.91397 -284.351564) (xy 85.954473 -284.37952) (xy 85.989966 -284.413612)
			(xy 86.019531 -284.452956) (xy 86.042402 -284.496533) (xy 86.057986 -284.543214) (xy 86.065881 -284.591791)
			(xy 86.066376 -284.616398) (xy 86.395318 -284.616398) (xy 86.399278 -284.567344) (xy 86.411055 -284.51956)
			(xy 86.430346 -284.474284) (xy 86.456649 -284.432688) (xy 86.489284 -284.395851) (xy 86.527405 -284.364726)
			(xy 86.570026 -284.340119) (xy 86.616042 -284.322667) (xy 86.664261 -284.312823) (xy 86.713436 -284.310842)
			(xy 86.762291 -284.316774) (xy 86.809562 -284.330466) (xy 86.854024 -284.351564) (xy 86.894527 -284.37952)
			(xy 86.93002 -284.413612) (xy 86.959585 -284.452956) (xy 86.982456 -284.496533) (xy 86.99804 -284.543214)
			(xy 87.005935 -284.591791) (xy 87.00643 -284.616398) (xy 87.335118 -284.616398) (xy 87.339078 -284.567344)
			(xy 87.350855 -284.51956) (xy 87.370146 -284.474284) (xy 87.396449 -284.432688) (xy 87.429084 -284.395851)
			(xy 87.467205 -284.364726) (xy 87.509826 -284.340119) (xy 87.555842 -284.322667) (xy 87.604061 -284.312823)
			(xy 87.653236 -284.310842) (xy 87.702091 -284.316774) (xy 87.749362 -284.330466) (xy 87.793824 -284.351564)
			(xy 87.834327 -284.37952) (xy 87.86982 -284.413612) (xy 87.899385 -284.452956) (xy 87.922256 -284.496533)
			(xy 87.93784 -284.543214) (xy 87.945735 -284.591791) (xy 87.94623 -284.616398) (xy 88.275172 -284.616398)
			(xy 88.279132 -284.567344) (xy 88.290909 -284.51956) (xy 88.3102 -284.474284) (xy 88.336503 -284.432688)
			(xy 88.369138 -284.395851) (xy 88.407259 -284.364726) (xy 88.44988 -284.340119) (xy 88.495896 -284.322667)
			(xy 88.544115 -284.312823) (xy 88.59329 -284.310842) (xy 88.642145 -284.316774) (xy 88.689416 -284.330466)
			(xy 88.733878 -284.351564) (xy 88.774381 -284.37952) (xy 88.809874 -284.413612) (xy 88.839439 -284.452956)
			(xy 88.86231 -284.496533) (xy 88.877894 -284.543214) (xy 88.885789 -284.591791) (xy 88.886284 -284.616398)
			(xy 89.215226 -284.616398) (xy 89.219186 -284.567344) (xy 89.230963 -284.51956) (xy 89.250254 -284.474284)
			(xy 89.276557 -284.432688) (xy 89.309192 -284.395851) (xy 89.347313 -284.364726) (xy 89.389934 -284.340119)
			(xy 89.43595 -284.322667) (xy 89.484169 -284.312823) (xy 89.533344 -284.310842) (xy 89.582199 -284.316774)
			(xy 89.62947 -284.330466) (xy 89.673932 -284.351564) (xy 89.714435 -284.37952) (xy 89.749928 -284.413612)
			(xy 89.779493 -284.452956) (xy 89.802364 -284.496533) (xy 89.817948 -284.543214) (xy 89.825843 -284.591791)
			(xy 89.826338 -284.616398) (xy 90.15528 -284.616398) (xy 90.15924 -284.567344) (xy 90.171017 -284.51956)
			(xy 90.190308 -284.474284) (xy 90.216611 -284.432688) (xy 90.249246 -284.395851) (xy 90.287367 -284.364726)
			(xy 90.329988 -284.340119) (xy 90.376004 -284.322667) (xy 90.424223 -284.312823) (xy 90.473398 -284.310842)
			(xy 90.522253 -284.316774) (xy 90.569524 -284.330466) (xy 90.613986 -284.351564) (xy 90.654489 -284.37952)
			(xy 90.689982 -284.413612) (xy 90.719547 -284.452956) (xy 90.742418 -284.496533) (xy 90.758002 -284.543214)
			(xy 90.765897 -284.591791) (xy 90.766392 -284.616398) (xy 91.084903 -284.616398) (xy 91.088998 -284.56567)
			(xy 91.101177 -284.516256) (xy 91.121125 -284.469436) (xy 91.148326 -284.426422) (xy 91.182074 -284.388328)
			(xy 91.221496 -284.356141) (xy 91.26557 -284.330695) (xy 91.313156 -284.312648) (xy 91.36302 -284.302468)
			(xy 91.413872 -284.300419) (xy 91.464393 -284.306553) (xy 91.513277 -284.320713) (xy 91.559256 -284.34253)
			(xy 91.60114 -284.37144) (xy 91.637844 -284.406695) (xy 91.668417 -284.447381) (xy 91.692068 -284.492444)
			(xy 91.708184 -284.540718) (xy 91.716348 -284.590952) (xy 91.71686 -284.616398) (xy 92.024703 -284.616398)
			(xy 92.028798 -284.56567) (xy 92.040977 -284.516256) (xy 92.060925 -284.469436) (xy 92.088126 -284.426422)
			(xy 92.121874 -284.388328) (xy 92.161296 -284.356141) (xy 92.20537 -284.330695) (xy 92.252956 -284.312648)
			(xy 92.30282 -284.302468) (xy 92.353672 -284.300419) (xy 92.404193 -284.306553) (xy 92.453077 -284.320713)
			(xy 92.499056 -284.34253) (xy 92.54094 -284.37144) (xy 92.577644 -284.406695) (xy 92.608217 -284.447381)
			(xy 92.631868 -284.492444) (xy 92.647984 -284.540718) (xy 92.656148 -284.590952) (xy 92.65666 -284.616398)
			(xy 92.975188 -284.616398) (xy 92.979148 -284.567344) (xy 92.990925 -284.51956) (xy 93.010216 -284.474284)
			(xy 93.036519 -284.432688) (xy 93.069154 -284.395851) (xy 93.107275 -284.364726) (xy 93.149896 -284.340119)
			(xy 93.195912 -284.322667) (xy 93.244131 -284.312823) (xy 93.293306 -284.310842) (xy 93.342161 -284.316774)
			(xy 93.389432 -284.330466) (xy 93.433894 -284.351564) (xy 93.474397 -284.37952) (xy 93.50989 -284.413612)
			(xy 93.539455 -284.452956) (xy 93.562326 -284.496533) (xy 93.57791 -284.543214) (xy 93.585805 -284.591791)
			(xy 93.5863 -284.616398) (xy 93.904811 -284.616398) (xy 93.908906 -284.56567) (xy 93.921085 -284.516256)
			(xy 93.941033 -284.469436) (xy 93.968234 -284.426422) (xy 94.001982 -284.388328) (xy 94.041404 -284.356141)
			(xy 94.085478 -284.330695) (xy 94.133064 -284.312648) (xy 94.182928 -284.302468) (xy 94.23378 -284.300419)
			(xy 94.284301 -284.306553) (xy 94.333185 -284.320713) (xy 94.379164 -284.34253) (xy 94.421048 -284.37144)
			(xy 94.457752 -284.406695) (xy 94.488325 -284.447381) (xy 94.511976 -284.492444) (xy 94.528092 -284.540718)
			(xy 94.536256 -284.590952) (xy 94.536768 -284.616398) (xy 94.855296 -284.616398) (xy 94.859256 -284.567344)
			(xy 94.871033 -284.51956) (xy 94.890324 -284.474284) (xy 94.916627 -284.432688) (xy 94.949262 -284.395851)
			(xy 94.987383 -284.364726) (xy 95.030004 -284.340119) (xy 95.07602 -284.322667) (xy 95.124239 -284.312823)
			(xy 95.173414 -284.310842) (xy 95.222269 -284.316774) (xy 95.26954 -284.330466) (xy 95.314002 -284.351564)
			(xy 95.354505 -284.37952) (xy 95.389998 -284.413612) (xy 95.419563 -284.452956) (xy 95.442434 -284.496533)
			(xy 95.458018 -284.543214) (xy 95.465913 -284.591791) (xy 95.466408 -284.616398) (xy 95.784919 -284.616398)
			(xy 95.789014 -284.56567) (xy 95.801193 -284.516256) (xy 95.821141 -284.469436) (xy 95.848342 -284.426422)
			(xy 95.88209 -284.388328) (xy 95.921512 -284.356141) (xy 95.965586 -284.330695) (xy 96.013172 -284.312648)
			(xy 96.063036 -284.302468) (xy 96.113888 -284.300419) (xy 96.164409 -284.306553) (xy 96.213293 -284.320713)
			(xy 96.259272 -284.34253) (xy 96.301156 -284.37144) (xy 96.33786 -284.406695) (xy 96.368433 -284.447381)
			(xy 96.392084 -284.492444) (xy 96.4082 -284.540718) (xy 96.416364 -284.590952) (xy 96.416876 -284.616398)
			(xy 96.416364 -284.641844) (xy 96.4082 -284.692078) (xy 96.392084 -284.740352) (xy 96.368433 -284.785415)
			(xy 96.33786 -284.826101) (xy 96.301156 -284.861356) (xy 96.259272 -284.890266) (xy 96.213293 -284.912083)
			(xy 96.164409 -284.926243) (xy 96.113888 -284.932377) (xy 96.063036 -284.930328) (xy 96.013172 -284.920148)
			(xy 95.965586 -284.902101) (xy 95.921512 -284.876655) (xy 95.88209 -284.844468) (xy 95.848342 -284.806374)
			(xy 95.821141 -284.76336) (xy 95.801193 -284.71654) (xy 95.789014 -284.667126) (xy 95.784919 -284.616398)
			(xy 95.466408 -284.616398) (xy 95.465913 -284.641005) (xy 95.458018 -284.689582) (xy 95.442434 -284.736263)
			(xy 95.419563 -284.77984) (xy 95.389998 -284.819184) (xy 95.354505 -284.853276) (xy 95.314002 -284.881232)
			(xy 95.26954 -284.90233) (xy 95.222269 -284.916022) (xy 95.173414 -284.921954) (xy 95.124239 -284.919973)
			(xy 95.07602 -284.910129) (xy 95.030004 -284.892677) (xy 94.987383 -284.86807) (xy 94.949262 -284.836945)
			(xy 94.916627 -284.800108) (xy 94.890324 -284.758512) (xy 94.871033 -284.713236) (xy 94.859256 -284.665452)
			(xy 94.855296 -284.616398) (xy 94.536768 -284.616398) (xy 94.536256 -284.641844) (xy 94.528092 -284.692078)
			(xy 94.511976 -284.740352) (xy 94.488325 -284.785415) (xy 94.457752 -284.826101) (xy 94.421048 -284.861356)
			(xy 94.379164 -284.890266) (xy 94.333185 -284.912083) (xy 94.284301 -284.926243) (xy 94.23378 -284.932377)
			(xy 94.182928 -284.930328) (xy 94.133064 -284.920148) (xy 94.085478 -284.902101) (xy 94.041404 -284.876655)
			(xy 94.001982 -284.844468) (xy 93.968234 -284.806374) (xy 93.941033 -284.76336) (xy 93.921085 -284.71654)
			(xy 93.908906 -284.667126) (xy 93.904811 -284.616398) (xy 93.5863 -284.616398) (xy 93.585805 -284.641005)
			(xy 93.57791 -284.689582) (xy 93.562326 -284.736263) (xy 93.539455 -284.77984) (xy 93.50989 -284.819184)
			(xy 93.474397 -284.853276) (xy 93.433894 -284.881232) (xy 93.389432 -284.90233) (xy 93.342161 -284.916022)
			(xy 93.293306 -284.921954) (xy 93.244131 -284.919973) (xy 93.195912 -284.910129) (xy 93.149896 -284.892677)
			(xy 93.107275 -284.86807) (xy 93.069154 -284.836945) (xy 93.036519 -284.800108) (xy 93.010216 -284.758512)
			(xy 92.990925 -284.713236) (xy 92.979148 -284.665452) (xy 92.975188 -284.616398) (xy 92.65666 -284.616398)
			(xy 92.656148 -284.641844) (xy 92.647984 -284.692078) (xy 92.631868 -284.740352) (xy 92.608217 -284.785415)
			(xy 92.577644 -284.826101) (xy 92.54094 -284.861356) (xy 92.499056 -284.890266) (xy 92.453077 -284.912083)
			(xy 92.404193 -284.926243) (xy 92.353672 -284.932377) (xy 92.30282 -284.930328) (xy 92.252956 -284.920148)
			(xy 92.20537 -284.902101) (xy 92.161296 -284.876655) (xy 92.121874 -284.844468) (xy 92.088126 -284.806374)
			(xy 92.060925 -284.76336) (xy 92.040977 -284.71654) (xy 92.028798 -284.667126) (xy 92.024703 -284.616398)
			(xy 91.71686 -284.616398) (xy 91.716348 -284.641844) (xy 91.708184 -284.692078) (xy 91.692068 -284.740352)
			(xy 91.668417 -284.785415) (xy 91.637844 -284.826101) (xy 91.60114 -284.861356) (xy 91.559256 -284.890266)
			(xy 91.513277 -284.912083) (xy 91.464393 -284.926243) (xy 91.413872 -284.932377) (xy 91.36302 -284.930328)
			(xy 91.313156 -284.920148) (xy 91.26557 -284.902101) (xy 91.221496 -284.876655) (xy 91.182074 -284.844468)
			(xy 91.148326 -284.806374) (xy 91.121125 -284.76336) (xy 91.101177 -284.71654) (xy 91.088998 -284.667126)
			(xy 91.084903 -284.616398) (xy 90.766392 -284.616398) (xy 90.765897 -284.641005) (xy 90.758002 -284.689582)
			(xy 90.742418 -284.736263) (xy 90.719547 -284.77984) (xy 90.689982 -284.819184) (xy 90.654489 -284.853276)
			(xy 90.613986 -284.881232) (xy 90.569524 -284.90233) (xy 90.522253 -284.916022) (xy 90.473398 -284.921954)
			(xy 90.424223 -284.919973) (xy 90.376004 -284.910129) (xy 90.329988 -284.892677) (xy 90.287367 -284.86807)
			(xy 90.249246 -284.836945) (xy 90.216611 -284.800108) (xy 90.190308 -284.758512) (xy 90.171017 -284.713236)
			(xy 90.15924 -284.665452) (xy 90.15528 -284.616398) (xy 89.826338 -284.616398) (xy 89.825843 -284.641005)
			(xy 89.817948 -284.689582) (xy 89.802364 -284.736263) (xy 89.779493 -284.77984) (xy 89.749928 -284.819184)
			(xy 89.714435 -284.853276) (xy 89.673932 -284.881232) (xy 89.62947 -284.90233) (xy 89.582199 -284.916022)
			(xy 89.533344 -284.921954) (xy 89.484169 -284.919973) (xy 89.43595 -284.910129) (xy 89.389934 -284.892677)
			(xy 89.347313 -284.86807) (xy 89.309192 -284.836945) (xy 89.276557 -284.800108) (xy 89.250254 -284.758512)
			(xy 89.230963 -284.713236) (xy 89.219186 -284.665452) (xy 89.215226 -284.616398) (xy 88.886284 -284.616398)
			(xy 88.885789 -284.641005) (xy 88.877894 -284.689582) (xy 88.86231 -284.736263) (xy 88.839439 -284.77984)
			(xy 88.809874 -284.819184) (xy 88.774381 -284.853276) (xy 88.733878 -284.881232) (xy 88.689416 -284.90233)
			(xy 88.642145 -284.916022) (xy 88.59329 -284.921954) (xy 88.544115 -284.919973) (xy 88.495896 -284.910129)
			(xy 88.44988 -284.892677) (xy 88.407259 -284.86807) (xy 88.369138 -284.836945) (xy 88.336503 -284.800108)
			(xy 88.3102 -284.758512) (xy 88.290909 -284.713236) (xy 88.279132 -284.665452) (xy 88.275172 -284.616398)
			(xy 87.94623 -284.616398) (xy 87.945735 -284.641005) (xy 87.93784 -284.689582) (xy 87.922256 -284.736263)
			(xy 87.899385 -284.77984) (xy 87.86982 -284.819184) (xy 87.834327 -284.853276) (xy 87.793824 -284.881232)
			(xy 87.749362 -284.90233) (xy 87.702091 -284.916022) (xy 87.653236 -284.921954) (xy 87.604061 -284.919973)
			(xy 87.555842 -284.910129) (xy 87.509826 -284.892677) (xy 87.467205 -284.86807) (xy 87.429084 -284.836945)
			(xy 87.396449 -284.800108) (xy 87.370146 -284.758512) (xy 87.350855 -284.713236) (xy 87.339078 -284.665452)
			(xy 87.335118 -284.616398) (xy 87.00643 -284.616398) (xy 87.005935 -284.641005) (xy 86.99804 -284.689582)
			(xy 86.982456 -284.736263) (xy 86.959585 -284.77984) (xy 86.93002 -284.819184) (xy 86.894527 -284.853276)
			(xy 86.854024 -284.881232) (xy 86.809562 -284.90233) (xy 86.762291 -284.916022) (xy 86.713436 -284.921954)
			(xy 86.664261 -284.919973) (xy 86.616042 -284.910129) (xy 86.570026 -284.892677) (xy 86.527405 -284.86807)
			(xy 86.489284 -284.836945) (xy 86.456649 -284.800108) (xy 86.430346 -284.758512) (xy 86.411055 -284.713236)
			(xy 86.399278 -284.665452) (xy 86.395318 -284.616398) (xy 86.066376 -284.616398) (xy 86.065881 -284.641005)
			(xy 86.057986 -284.689582) (xy 86.042402 -284.736263) (xy 86.019531 -284.77984) (xy 85.989966 -284.819184)
			(xy 85.954473 -284.853276) (xy 85.91397 -284.881232) (xy 85.869508 -284.90233) (xy 85.822237 -284.916022)
			(xy 85.773382 -284.921954) (xy 85.724207 -284.919973) (xy 85.675988 -284.910129) (xy 85.629972 -284.892677)
			(xy 85.587351 -284.86807) (xy 85.54923 -284.836945) (xy 85.516595 -284.800108) (xy 85.490292 -284.758512)
			(xy 85.471001 -284.713236) (xy 85.459224 -284.665452) (xy 85.455264 -284.616398) (xy 85.126322 -284.616398)
			(xy 85.125827 -284.641005) (xy 85.117932 -284.689582) (xy 85.102348 -284.736263) (xy 85.079477 -284.77984)
			(xy 85.049912 -284.819184) (xy 85.014419 -284.853276) (xy 84.973916 -284.881232) (xy 84.929454 -284.90233)
			(xy 84.882183 -284.916022) (xy 84.833328 -284.921954) (xy 84.784153 -284.919973) (xy 84.735934 -284.910129)
			(xy 84.689918 -284.892677) (xy 84.647297 -284.86807) (xy 84.609176 -284.836945) (xy 84.576541 -284.800108)
			(xy 84.550238 -284.758512) (xy 84.530947 -284.713236) (xy 84.51917 -284.665452) (xy 84.51521 -284.616398)
			(xy 84.186268 -284.616398) (xy 84.185822 -284.64039) (xy 84.178315 -284.687783) (xy 84.163486 -284.733419)
			(xy 84.1417 -284.776172) (xy 84.113494 -284.814991) (xy 84.079562 -284.848919) (xy 84.04074 -284.87712)
			(xy 83.997984 -284.898901) (xy 83.952346 -284.913724) (xy 83.904952 -284.921225) (xy 83.88096 -284.921706)
			(xy 83.85457 -284.921155) (xy 83.802573 -284.912095) (xy 83.752906 -284.894234) (xy 83.707048 -284.868103)
			(xy 83.666362 -284.834481) (xy 83.648804 -284.814772) (xy 83.627468 -284.789626) (xy 83.62569 -284.789626)
			(xy 83.621481 -284.789708) (xy 83.613182 -284.791114) (xy 83.60918 -284.79242) (xy 83.521804 -284.832806)
			(xy 83.514025 -284.837339) (xy 83.502042 -284.850761) (xy 83.495463 -284.867508) (xy 83.49488 -284.876494)
			(xy 83.49488 -285.045404) (xy 83.494914 -285.04954) (xy 83.496192 -285.057711) (xy 83.49742 -285.06166)
			(xy 83.502246 -285.07182) (xy 83.515708 -285.092902) (xy 83.519208 -285.098165) (xy 83.528331 -285.106908)
			(xy 83.533742 -285.110174) (xy 83.533996 -285.110174) (xy 83.555756 -285.122754) (xy 83.595204 -285.153896)
			(xy 83.612482 -285.17215) (xy 83.630126 -285.192348) (xy 83.658744 -285.237699) (xy 83.669378 -285.26232)
			(xy 83.672934 -285.268924) (xy 83.673188 -285.269432) (xy 83.686703 -285.293274) (xy 83.705948 -285.344582)
			(xy 83.715745 -285.398497) (xy 83.716368 -285.425896) (xy 83.716368 -285.426404) (xy 84.04531 -285.426404)
			(xy 84.04927 -285.37735) (xy 84.061047 -285.329566) (xy 84.080338 -285.28429) (xy 84.106641 -285.242694)
			(xy 84.139276 -285.205857) (xy 84.177397 -285.174732) (xy 84.220018 -285.150125) (xy 84.266034 -285.132673)
			(xy 84.314253 -285.122829) (xy 84.363428 -285.120848) (xy 84.412283 -285.12678) (xy 84.459554 -285.140472)
			(xy 84.504016 -285.16157) (xy 84.544519 -285.189526) (xy 84.580012 -285.223618) (xy 84.609577 -285.262962)
			(xy 84.632448 -285.306539) (xy 84.648032 -285.35322) (xy 84.655927 -285.401797) (xy 84.656422 -285.426404)
			(xy 84.98511 -285.426404) (xy 84.98907 -285.37735) (xy 85.000847 -285.329566) (xy 85.020138 -285.28429)
			(xy 85.046441 -285.242694) (xy 85.079076 -285.205857) (xy 85.117197 -285.174732) (xy 85.159818 -285.150125)
			(xy 85.205834 -285.132673) (xy 85.254053 -285.122829) (xy 85.303228 -285.120848) (xy 85.352083 -285.12678)
			(xy 85.399354 -285.140472) (xy 85.443816 -285.16157) (xy 85.484319 -285.189526) (xy 85.519812 -285.223618)
			(xy 85.549377 -285.262962) (xy 85.572248 -285.306539) (xy 85.587832 -285.35322) (xy 85.595727 -285.401797)
			(xy 85.596222 -285.426404) (xy 85.925164 -285.426404) (xy 85.929124 -285.37735) (xy 85.940901 -285.329566)
			(xy 85.960192 -285.28429) (xy 85.986495 -285.242694) (xy 86.01913 -285.205857) (xy 86.057251 -285.174732)
			(xy 86.099872 -285.150125) (xy 86.145888 -285.132673) (xy 86.194107 -285.122829) (xy 86.243282 -285.120848)
			(xy 86.292137 -285.12678) (xy 86.339408 -285.140472) (xy 86.38387 -285.16157) (xy 86.424373 -285.189526)
			(xy 86.459866 -285.223618) (xy 86.489431 -285.262962) (xy 86.512302 -285.306539) (xy 86.527886 -285.35322)
			(xy 86.535781 -285.401797) (xy 86.536276 -285.426404) (xy 87.805272 -285.426404) (xy 87.809232 -285.37735)
			(xy 87.821009 -285.329566) (xy 87.8403 -285.28429) (xy 87.866603 -285.242694) (xy 87.899238 -285.205857)
			(xy 87.937359 -285.174732) (xy 87.97998 -285.150125) (xy 88.025996 -285.132673) (xy 88.074215 -285.122829)
			(xy 88.12339 -285.120848) (xy 88.172245 -285.12678) (xy 88.219516 -285.140472) (xy 88.263978 -285.16157)
			(xy 88.304481 -285.189526) (xy 88.339974 -285.223618) (xy 88.369539 -285.262962) (xy 88.39241 -285.306539)
			(xy 88.407994 -285.35322) (xy 88.415889 -285.401797) (xy 88.416384 -285.426404) (xy 88.745326 -285.426404)
			(xy 88.749286 -285.37735) (xy 88.761063 -285.329566) (xy 88.780354 -285.28429) (xy 88.806657 -285.242694)
			(xy 88.839292 -285.205857) (xy 88.877413 -285.174732) (xy 88.920034 -285.150125) (xy 88.96605 -285.132673)
			(xy 89.014269 -285.122829) (xy 89.063444 -285.120848) (xy 89.112299 -285.12678) (xy 89.15957 -285.140472)
			(xy 89.204032 -285.16157) (xy 89.244535 -285.189526) (xy 89.280028 -285.223618) (xy 89.309593 -285.262962)
			(xy 89.332464 -285.306539) (xy 89.348048 -285.35322) (xy 89.355943 -285.401797) (xy 89.356438 -285.426404)
			(xy 89.685126 -285.426404) (xy 89.689086 -285.37735) (xy 89.700863 -285.329566) (xy 89.720154 -285.28429)
			(xy 89.746457 -285.242694) (xy 89.779092 -285.205857) (xy 89.817213 -285.174732) (xy 89.859834 -285.150125)
			(xy 89.90585 -285.132673) (xy 89.954069 -285.122829) (xy 90.003244 -285.120848) (xy 90.052099 -285.12678)
			(xy 90.09937 -285.140472) (xy 90.143832 -285.16157) (xy 90.184335 -285.189526) (xy 90.219828 -285.223618)
			(xy 90.249393 -285.262962) (xy 90.272264 -285.306539) (xy 90.287848 -285.35322) (xy 90.295743 -285.401797)
			(xy 90.296238 -285.426404) (xy 90.614749 -285.426404) (xy 90.618844 -285.375676) (xy 90.631023 -285.326262)
			(xy 90.650971 -285.279442) (xy 90.678172 -285.236428) (xy 90.71192 -285.198334) (xy 90.751342 -285.166147)
			(xy 90.795416 -285.140701) (xy 90.843002 -285.122654) (xy 90.892866 -285.112474) (xy 90.943718 -285.110425)
			(xy 90.994239 -285.116559) (xy 91.043123 -285.130719) (xy 91.089102 -285.152536) (xy 91.130986 -285.181446)
			(xy 91.16769 -285.216701) (xy 91.198263 -285.257387) (xy 91.221914 -285.30245) (xy 91.23803 -285.350724)
			(xy 91.246194 -285.400958) (xy 91.246706 -285.426404) (xy 91.565234 -285.426404) (xy 91.569194 -285.37735)
			(xy 91.580971 -285.329566) (xy 91.600262 -285.28429) (xy 91.626565 -285.242694) (xy 91.6592 -285.205857)
			(xy 91.697321 -285.174732) (xy 91.739942 -285.150125) (xy 91.785958 -285.132673) (xy 91.834177 -285.122829)
			(xy 91.883352 -285.120848) (xy 91.932207 -285.12678) (xy 91.979478 -285.140472) (xy 92.02394 -285.16157)
			(xy 92.064443 -285.189526) (xy 92.099936 -285.223618) (xy 92.129501 -285.262962) (xy 92.152372 -285.306539)
			(xy 92.167956 -285.35322) (xy 92.175851 -285.401797) (xy 92.176346 -285.426404) (xy 92.494857 -285.426404)
			(xy 92.498952 -285.375676) (xy 92.511131 -285.326262) (xy 92.531079 -285.279442) (xy 92.55828 -285.236428)
			(xy 92.592028 -285.198334) (xy 92.63145 -285.166147) (xy 92.675524 -285.140701) (xy 92.72311 -285.122654)
			(xy 92.772974 -285.112474) (xy 92.823826 -285.110425) (xy 92.874347 -285.116559) (xy 92.923231 -285.130719)
			(xy 92.96921 -285.152536) (xy 93.011094 -285.181446) (xy 93.047798 -285.216701) (xy 93.078371 -285.257387)
			(xy 93.102022 -285.30245) (xy 93.118138 -285.350724) (xy 93.126302 -285.400958) (xy 93.126814 -285.426404)
			(xy 94.374711 -285.426404) (xy 94.378806 -285.375676) (xy 94.390985 -285.326262) (xy 94.410933 -285.279442)
			(xy 94.438134 -285.236428) (xy 94.471882 -285.198334) (xy 94.511304 -285.166147) (xy 94.555378 -285.140701)
			(xy 94.602964 -285.122654) (xy 94.652828 -285.112474) (xy 94.70368 -285.110425) (xy 94.754201 -285.116559)
			(xy 94.803085 -285.130719) (xy 94.849064 -285.152536) (xy 94.890948 -285.181446) (xy 94.927652 -285.216701)
			(xy 94.958225 -285.257387) (xy 94.981876 -285.30245) (xy 94.997992 -285.350724) (xy 95.006156 -285.400958)
			(xy 95.006668 -285.426404) (xy 95.314765 -285.426404) (xy 95.31886 -285.375676) (xy 95.331039 -285.326262)
			(xy 95.350987 -285.279442) (xy 95.378188 -285.236428) (xy 95.411936 -285.198334) (xy 95.451358 -285.166147)
			(xy 95.495432 -285.140701) (xy 95.543018 -285.122654) (xy 95.592882 -285.112474) (xy 95.643734 -285.110425)
			(xy 95.694255 -285.116559) (xy 95.743139 -285.130719) (xy 95.789118 -285.152536) (xy 95.831002 -285.181446)
			(xy 95.867706 -285.216701) (xy 95.898279 -285.257387) (xy 95.92193 -285.30245) (xy 95.938046 -285.350724)
			(xy 95.94621 -285.400958) (xy 95.946722 -285.426404) (xy 95.94621 -285.45185) (xy 95.938046 -285.502084)
			(xy 95.92193 -285.550358) (xy 95.898279 -285.595421) (xy 95.867706 -285.636107) (xy 95.831002 -285.671362)
			(xy 95.789118 -285.700272) (xy 95.743139 -285.722089) (xy 95.694255 -285.736249) (xy 95.643734 -285.742383)
			(xy 95.592882 -285.740334) (xy 95.543018 -285.730154) (xy 95.495432 -285.712107) (xy 95.451358 -285.686661)
			(xy 95.411936 -285.654474) (xy 95.378188 -285.61638) (xy 95.350987 -285.573366) (xy 95.331039 -285.526546)
			(xy 95.31886 -285.477132) (xy 95.314765 -285.426404) (xy 95.006668 -285.426404) (xy 95.006156 -285.45185)
			(xy 94.997992 -285.502084) (xy 94.981876 -285.550358) (xy 94.958225 -285.595421) (xy 94.927652 -285.636107)
			(xy 94.890948 -285.671362) (xy 94.849064 -285.700272) (xy 94.803085 -285.722089) (xy 94.754201 -285.736249)
			(xy 94.70368 -285.742383) (xy 94.652828 -285.740334) (xy 94.602964 -285.730154) (xy 94.555378 -285.712107)
			(xy 94.511304 -285.686661) (xy 94.471882 -285.654474) (xy 94.438134 -285.61638) (xy 94.410933 -285.573366)
			(xy 94.390985 -285.526546) (xy 94.378806 -285.477132) (xy 94.374711 -285.426404) (xy 93.126814 -285.426404)
			(xy 93.126302 -285.45185) (xy 93.118138 -285.502084) (xy 93.102022 -285.550358) (xy 93.078371 -285.595421)
			(xy 93.047798 -285.636107) (xy 93.011094 -285.671362) (xy 92.96921 -285.700272) (xy 92.923231 -285.722089)
			(xy 92.874347 -285.736249) (xy 92.823826 -285.742383) (xy 92.772974 -285.740334) (xy 92.72311 -285.730154)
			(xy 92.675524 -285.712107) (xy 92.63145 -285.686661) (xy 92.592028 -285.654474) (xy 92.55828 -285.61638)
			(xy 92.531079 -285.573366) (xy 92.511131 -285.526546) (xy 92.498952 -285.477132) (xy 92.494857 -285.426404)
			(xy 92.176346 -285.426404) (xy 92.175851 -285.451011) (xy 92.167956 -285.499588) (xy 92.152372 -285.546269)
			(xy 92.129501 -285.589846) (xy 92.099936 -285.62919) (xy 92.064443 -285.663282) (xy 92.02394 -285.691238)
			(xy 91.979478 -285.712336) (xy 91.932207 -285.726028) (xy 91.883352 -285.73196) (xy 91.834177 -285.729979)
			(xy 91.785958 -285.720135) (xy 91.739942 -285.702683) (xy 91.697321 -285.678076) (xy 91.6592 -285.646951)
			(xy 91.626565 -285.610114) (xy 91.600262 -285.568518) (xy 91.580971 -285.523242) (xy 91.569194 -285.475458)
			(xy 91.565234 -285.426404) (xy 91.246706 -285.426404) (xy 91.246194 -285.45185) (xy 91.23803 -285.502084)
			(xy 91.221914 -285.550358) (xy 91.198263 -285.595421) (xy 91.16769 -285.636107) (xy 91.130986 -285.671362)
			(xy 91.089102 -285.700272) (xy 91.043123 -285.722089) (xy 90.994239 -285.736249) (xy 90.943718 -285.742383)
			(xy 90.892866 -285.740334) (xy 90.843002 -285.730154) (xy 90.795416 -285.712107) (xy 90.751342 -285.686661)
			(xy 90.71192 -285.654474) (xy 90.678172 -285.61638) (xy 90.650971 -285.573366) (xy 90.631023 -285.526546)
			(xy 90.618844 -285.477132) (xy 90.614749 -285.426404) (xy 90.296238 -285.426404) (xy 90.295743 -285.451011)
			(xy 90.287848 -285.499588) (xy 90.272264 -285.546269) (xy 90.249393 -285.589846) (xy 90.219828 -285.62919)
			(xy 90.184335 -285.663282) (xy 90.143832 -285.691238) (xy 90.09937 -285.712336) (xy 90.052099 -285.726028)
			(xy 90.003244 -285.73196) (xy 89.954069 -285.729979) (xy 89.90585 -285.720135) (xy 89.859834 -285.702683)
			(xy 89.817213 -285.678076) (xy 89.779092 -285.646951) (xy 89.746457 -285.610114) (xy 89.720154 -285.568518)
			(xy 89.700863 -285.523242) (xy 89.689086 -285.475458) (xy 89.685126 -285.426404) (xy 89.356438 -285.426404)
			(xy 89.355943 -285.451011) (xy 89.348048 -285.499588) (xy 89.332464 -285.546269) (xy 89.309593 -285.589846)
			(xy 89.280028 -285.62919) (xy 89.244535 -285.663282) (xy 89.204032 -285.691238) (xy 89.15957 -285.712336)
			(xy 89.112299 -285.726028) (xy 89.063444 -285.73196) (xy 89.014269 -285.729979) (xy 88.96605 -285.720135)
			(xy 88.920034 -285.702683) (xy 88.877413 -285.678076) (xy 88.839292 -285.646951) (xy 88.806657 -285.610114)
			(xy 88.780354 -285.568518) (xy 88.761063 -285.523242) (xy 88.749286 -285.475458) (xy 88.745326 -285.426404)
			(xy 88.416384 -285.426404) (xy 88.415889 -285.451011) (xy 88.407994 -285.499588) (xy 88.39241 -285.546269)
			(xy 88.369539 -285.589846) (xy 88.339974 -285.62919) (xy 88.304481 -285.663282) (xy 88.263978 -285.691238)
			(xy 88.219516 -285.712336) (xy 88.172245 -285.726028) (xy 88.12339 -285.73196) (xy 88.074215 -285.729979)
			(xy 88.025996 -285.720135) (xy 87.97998 -285.702683) (xy 87.937359 -285.678076) (xy 87.899238 -285.646951)
			(xy 87.866603 -285.610114) (xy 87.8403 -285.568518) (xy 87.821009 -285.523242) (xy 87.809232 -285.475458)
			(xy 87.805272 -285.426404) (xy 86.536276 -285.426404) (xy 86.535781 -285.451011) (xy 86.527886 -285.499588)
			(xy 86.512302 -285.546269) (xy 86.489431 -285.589846) (xy 86.459866 -285.62919) (xy 86.424373 -285.663282)
			(xy 86.38387 -285.691238) (xy 86.339408 -285.712336) (xy 86.292137 -285.726028) (xy 86.243282 -285.73196)
			(xy 86.194107 -285.729979) (xy 86.145888 -285.720135) (xy 86.099872 -285.702683) (xy 86.057251 -285.678076)
			(xy 86.01913 -285.646951) (xy 85.986495 -285.610114) (xy 85.960192 -285.568518) (xy 85.940901 -285.523242)
			(xy 85.929124 -285.475458) (xy 85.925164 -285.426404) (xy 85.596222 -285.426404) (xy 85.595727 -285.451011)
			(xy 85.587832 -285.499588) (xy 85.572248 -285.546269) (xy 85.549377 -285.589846) (xy 85.519812 -285.62919)
			(xy 85.484319 -285.663282) (xy 85.443816 -285.691238) (xy 85.399354 -285.712336) (xy 85.352083 -285.726028)
			(xy 85.303228 -285.73196) (xy 85.254053 -285.729979) (xy 85.205834 -285.720135) (xy 85.159818 -285.702683)
			(xy 85.117197 -285.678076) (xy 85.079076 -285.646951) (xy 85.046441 -285.610114) (xy 85.020138 -285.568518)
			(xy 85.000847 -285.523242) (xy 84.98907 -285.475458) (xy 84.98511 -285.426404) (xy 84.656422 -285.426404)
			(xy 84.655927 -285.451011) (xy 84.648032 -285.499588) (xy 84.632448 -285.546269) (xy 84.609577 -285.589846)
			(xy 84.580012 -285.62919) (xy 84.544519 -285.663282) (xy 84.504016 -285.691238) (xy 84.459554 -285.712336)
			(xy 84.412283 -285.726028) (xy 84.363428 -285.73196) (xy 84.314253 -285.729979) (xy 84.266034 -285.720135)
			(xy 84.220018 -285.702683) (xy 84.177397 -285.678076) (xy 84.139276 -285.646951) (xy 84.106641 -285.610114)
			(xy 84.080338 -285.568518) (xy 84.061047 -285.523242) (xy 84.04927 -285.475458) (xy 84.04531 -285.426404)
			(xy 83.716368 -285.426404) (xy 83.716368 -285.432246) (xy 83.715354 -285.457939) (xy 83.705786 -285.508456)
			(xy 83.68789 -285.556656) (xy 83.662171 -285.601175) (xy 83.629356 -285.640757) (xy 83.590373 -285.67428)
			(xy 83.546324 -285.700798) (xy 83.522566 -285.71063) (xy 83.512152 -285.714948) (xy 83.503516 -285.727648)
			(xy 83.499481 -285.734053) (xy 83.49508 -285.748529) (xy 83.49488 -285.756096) (xy 83.49488 -285.878524)
			(xy 83.495139 -285.884133) (xy 83.49783 -285.89503) (xy 83.500214 -285.900114) (xy 83.504786 -285.907988)
			(xy 83.508733 -285.912848) (xy 83.518488 -285.920689) (xy 83.52409 -285.923482) (xy 83.524344 -285.923736)
			(xy 83.605116 -285.961074) (xy 83.618832 -285.964376) (xy 83.631278 -285.964884) (xy 83.648042 -285.958534)
			(xy 83.6549 -285.955232) (xy 83.665314 -285.94939) (xy 83.6676 -285.947612) (xy 83.668616 -285.94685)
			(xy 83.66887 -285.946596) (xy 83.689158 -285.931524) (xy 83.733641 -285.907538) (xy 83.781456 -285.891175)
			(xy 83.831307 -285.882879) (xy 83.856576 -285.882334) (xy 83.882414 -285.882882) (xy 83.933349 -285.891595)
			(xy 83.982091 -285.90876) (xy 84.027246 -285.933887) (xy 84.067526 -285.966257) (xy 84.101781 -286.004948)
			(xy 84.129033 -286.048854) (xy 84.139278 -286.07258) (xy 84.142834 -286.079184) (xy 84.143088 -286.079692)
			(xy 84.156617 -286.103573) (xy 84.175867 -286.154966) (xy 84.185639 -286.20897) (xy 84.186268 -286.23641)
			(xy 84.51521 -286.23641) (xy 84.51917 -286.187356) (xy 84.530947 -286.139572) (xy 84.550238 -286.094296)
			(xy 84.576541 -286.0527) (xy 84.609176 -286.015863) (xy 84.647297 -285.984738) (xy 84.689918 -285.960131)
			(xy 84.735934 -285.942679) (xy 84.784153 -285.932835) (xy 84.833328 -285.930854) (xy 84.882183 -285.936786)
			(xy 84.929454 -285.950478) (xy 84.973916 -285.971576) (xy 85.014419 -285.999532) (xy 85.049912 -286.033624)
			(xy 85.079477 -286.072968) (xy 85.102348 -286.116545) (xy 85.117932 -286.163226) (xy 85.125827 -286.211803)
			(xy 85.126322 -286.23641) (xy 85.455264 -286.23641) (xy 85.459224 -286.187356) (xy 85.471001 -286.139572)
			(xy 85.490292 -286.094296) (xy 85.516595 -286.0527) (xy 85.54923 -286.015863) (xy 85.587351 -285.984738)
			(xy 85.629972 -285.960131) (xy 85.675988 -285.942679) (xy 85.724207 -285.932835) (xy 85.773382 -285.930854)
			(xy 85.822237 -285.936786) (xy 85.869508 -285.950478) (xy 85.91397 -285.971576) (xy 85.954473 -285.999532)
			(xy 85.989966 -286.033624) (xy 86.019531 -286.072968) (xy 86.042402 -286.116545) (xy 86.057986 -286.163226)
			(xy 86.065881 -286.211803) (xy 86.066376 -286.23641) (xy 86.395318 -286.23641) (xy 86.399278 -286.187356)
			(xy 86.411055 -286.139572) (xy 86.430346 -286.094296) (xy 86.456649 -286.0527) (xy 86.489284 -286.015863)
			(xy 86.527405 -285.984738) (xy 86.570026 -285.960131) (xy 86.616042 -285.942679) (xy 86.664261 -285.932835)
			(xy 86.713436 -285.930854) (xy 86.762291 -285.936786) (xy 86.809562 -285.950478) (xy 86.854024 -285.971576)
			(xy 86.894527 -285.999532) (xy 86.93002 -286.033624) (xy 86.959585 -286.072968) (xy 86.982456 -286.116545)
			(xy 86.99804 -286.163226) (xy 87.005935 -286.211803) (xy 87.00643 -286.23641) (xy 87.335118 -286.23641)
			(xy 87.339078 -286.187356) (xy 87.350855 -286.139572) (xy 87.370146 -286.094296) (xy 87.396449 -286.0527)
			(xy 87.429084 -286.015863) (xy 87.467205 -285.984738) (xy 87.509826 -285.960131) (xy 87.555842 -285.942679)
			(xy 87.604061 -285.932835) (xy 87.653236 -285.930854) (xy 87.702091 -285.936786) (xy 87.749362 -285.950478)
			(xy 87.793824 -285.971576) (xy 87.834327 -285.999532) (xy 87.86982 -286.033624) (xy 87.899385 -286.072968)
			(xy 87.922256 -286.116545) (xy 87.93784 -286.163226) (xy 87.945735 -286.211803) (xy 87.94623 -286.23641)
			(xy 88.275172 -286.23641) (xy 88.279132 -286.187356) (xy 88.290909 -286.139572) (xy 88.3102 -286.094296)
			(xy 88.336503 -286.0527) (xy 88.369138 -286.015863) (xy 88.407259 -285.984738) (xy 88.44988 -285.960131)
			(xy 88.495896 -285.942679) (xy 88.544115 -285.932835) (xy 88.59329 -285.930854) (xy 88.642145 -285.936786)
			(xy 88.689416 -285.950478) (xy 88.733878 -285.971576) (xy 88.774381 -285.999532) (xy 88.809874 -286.033624)
			(xy 88.839439 -286.072968) (xy 88.86231 -286.116545) (xy 88.877894 -286.163226) (xy 88.885789 -286.211803)
			(xy 88.886284 -286.23641) (xy 89.215226 -286.23641) (xy 89.219186 -286.187356) (xy 89.230963 -286.139572)
			(xy 89.250254 -286.094296) (xy 89.276557 -286.0527) (xy 89.309192 -286.015863) (xy 89.347313 -285.984738)
			(xy 89.389934 -285.960131) (xy 89.43595 -285.942679) (xy 89.484169 -285.932835) (xy 89.533344 -285.930854)
			(xy 89.582199 -285.936786) (xy 89.62947 -285.950478) (xy 89.673932 -285.971576) (xy 89.714435 -285.999532)
			(xy 89.749928 -286.033624) (xy 89.779493 -286.072968) (xy 89.802364 -286.116545) (xy 89.817948 -286.163226)
			(xy 89.825843 -286.211803) (xy 89.826338 -286.23641) (xy 90.15528 -286.23641) (xy 90.15924 -286.187356)
			(xy 90.171017 -286.139572) (xy 90.190308 -286.094296) (xy 90.216611 -286.0527) (xy 90.249246 -286.015863)
			(xy 90.287367 -285.984738) (xy 90.329988 -285.960131) (xy 90.376004 -285.942679) (xy 90.424223 -285.932835)
			(xy 90.473398 -285.930854) (xy 90.522253 -285.936786) (xy 90.569524 -285.950478) (xy 90.613986 -285.971576)
			(xy 90.654489 -285.999532) (xy 90.689982 -286.033624) (xy 90.719547 -286.072968) (xy 90.742418 -286.116545)
			(xy 90.758002 -286.163226) (xy 90.765897 -286.211803) (xy 90.766392 -286.23641) (xy 91.084903 -286.23641)
			(xy 91.088998 -286.185682) (xy 91.101177 -286.136268) (xy 91.121125 -286.089448) (xy 91.148326 -286.046434)
			(xy 91.182074 -286.00834) (xy 91.221496 -285.976153) (xy 91.26557 -285.950707) (xy 91.313156 -285.93266)
			(xy 91.36302 -285.92248) (xy 91.413872 -285.920431) (xy 91.464393 -285.926565) (xy 91.513277 -285.940725)
			(xy 91.559256 -285.962542) (xy 91.60114 -285.991452) (xy 91.637844 -286.026707) (xy 91.668417 -286.067393)
			(xy 91.692068 -286.112456) (xy 91.708184 -286.16073) (xy 91.716348 -286.210964) (xy 91.71686 -286.23641)
			(xy 92.024703 -286.23641) (xy 92.028798 -286.185682) (xy 92.040977 -286.136268) (xy 92.060925 -286.089448)
			(xy 92.088126 -286.046434) (xy 92.121874 -286.00834) (xy 92.161296 -285.976153) (xy 92.20537 -285.950707)
			(xy 92.252956 -285.93266) (xy 92.30282 -285.92248) (xy 92.353672 -285.920431) (xy 92.404193 -285.926565)
			(xy 92.453077 -285.940725) (xy 92.499056 -285.962542) (xy 92.54094 -285.991452) (xy 92.577644 -286.026707)
			(xy 92.608217 -286.067393) (xy 92.631868 -286.112456) (xy 92.647984 -286.16073) (xy 92.656148 -286.210964)
			(xy 92.65666 -286.23641) (xy 92.975188 -286.23641) (xy 92.979148 -286.187356) (xy 92.990925 -286.139572)
			(xy 93.010216 -286.094296) (xy 93.036519 -286.0527) (xy 93.069154 -286.015863) (xy 93.107275 -285.984738)
			(xy 93.149896 -285.960131) (xy 93.195912 -285.942679) (xy 93.244131 -285.932835) (xy 93.293306 -285.930854)
			(xy 93.342161 -285.936786) (xy 93.389432 -285.950478) (xy 93.433894 -285.971576) (xy 93.474397 -285.999532)
			(xy 93.50989 -286.033624) (xy 93.539455 -286.072968) (xy 93.562326 -286.116545) (xy 93.57791 -286.163226)
			(xy 93.585805 -286.211803) (xy 93.5863 -286.23641) (xy 93.904811 -286.23641) (xy 93.908906 -286.185682)
			(xy 93.921085 -286.136268) (xy 93.941033 -286.089448) (xy 93.968234 -286.046434) (xy 94.001982 -286.00834)
			(xy 94.041404 -285.976153) (xy 94.085478 -285.950707) (xy 94.133064 -285.93266) (xy 94.182928 -285.92248)
			(xy 94.23378 -285.920431) (xy 94.284301 -285.926565) (xy 94.333185 -285.940725) (xy 94.379164 -285.962542)
			(xy 94.421048 -285.991452) (xy 94.457752 -286.026707) (xy 94.488325 -286.067393) (xy 94.511976 -286.112456)
			(xy 94.528092 -286.16073) (xy 94.536256 -286.210964) (xy 94.536768 -286.23641) (xy 94.855296 -286.23641)
			(xy 94.859256 -286.187356) (xy 94.871033 -286.139572) (xy 94.890324 -286.094296) (xy 94.916627 -286.0527)
			(xy 94.949262 -286.015863) (xy 94.987383 -285.984738) (xy 95.030004 -285.960131) (xy 95.07602 -285.942679)
			(xy 95.124239 -285.932835) (xy 95.173414 -285.930854) (xy 95.222269 -285.936786) (xy 95.26954 -285.950478)
			(xy 95.314002 -285.971576) (xy 95.354505 -285.999532) (xy 95.389998 -286.033624) (xy 95.419563 -286.072968)
			(xy 95.442434 -286.116545) (xy 95.458018 -286.163226) (xy 95.465913 -286.211803) (xy 95.466408 -286.23641)
			(xy 95.465913 -286.261017) (xy 95.458018 -286.309594) (xy 95.442434 -286.356275) (xy 95.419563 -286.399852)
			(xy 95.389998 -286.439196) (xy 95.354505 -286.473288) (xy 95.314002 -286.501244) (xy 95.26954 -286.522342)
			(xy 95.222269 -286.536034) (xy 95.173414 -286.541966) (xy 95.124239 -286.539985) (xy 95.07602 -286.530141)
			(xy 95.030004 -286.512689) (xy 94.987383 -286.488082) (xy 94.949262 -286.456957) (xy 94.916627 -286.42012)
			(xy 94.890324 -286.378524) (xy 94.871033 -286.333248) (xy 94.859256 -286.285464) (xy 94.855296 -286.23641)
			(xy 94.536768 -286.23641) (xy 94.536256 -286.261856) (xy 94.528092 -286.31209) (xy 94.511976 -286.360364)
			(xy 94.488325 -286.405427) (xy 94.457752 -286.446113) (xy 94.421048 -286.481368) (xy 94.379164 -286.510278)
			(xy 94.333185 -286.532095) (xy 94.284301 -286.546255) (xy 94.23378 -286.552389) (xy 94.182928 -286.55034)
			(xy 94.133064 -286.54016) (xy 94.085478 -286.522113) (xy 94.041404 -286.496667) (xy 94.001982 -286.46448)
			(xy 93.968234 -286.426386) (xy 93.941033 -286.383372) (xy 93.921085 -286.336552) (xy 93.908906 -286.287138)
			(xy 93.904811 -286.23641) (xy 93.5863 -286.23641) (xy 93.585805 -286.261017) (xy 93.57791 -286.309594)
			(xy 93.562326 -286.356275) (xy 93.539455 -286.399852) (xy 93.50989 -286.439196) (xy 93.474397 -286.473288)
			(xy 93.433894 -286.501244) (xy 93.389432 -286.522342) (xy 93.342161 -286.536034) (xy 93.293306 -286.541966)
			(xy 93.244131 -286.539985) (xy 93.195912 -286.530141) (xy 93.149896 -286.512689) (xy 93.107275 -286.488082)
			(xy 93.069154 -286.456957) (xy 93.036519 -286.42012) (xy 93.010216 -286.378524) (xy 92.990925 -286.333248)
			(xy 92.979148 -286.285464) (xy 92.975188 -286.23641) (xy 92.65666 -286.23641) (xy 92.656148 -286.261856)
			(xy 92.647984 -286.31209) (xy 92.631868 -286.360364) (xy 92.608217 -286.405427) (xy 92.577644 -286.446113)
			(xy 92.54094 -286.481368) (xy 92.499056 -286.510278) (xy 92.453077 -286.532095) (xy 92.404193 -286.546255)
			(xy 92.353672 -286.552389) (xy 92.30282 -286.55034) (xy 92.252956 -286.54016) (xy 92.20537 -286.522113)
			(xy 92.161296 -286.496667) (xy 92.121874 -286.46448) (xy 92.088126 -286.426386) (xy 92.060925 -286.383372)
			(xy 92.040977 -286.336552) (xy 92.028798 -286.287138) (xy 92.024703 -286.23641) (xy 91.71686 -286.23641)
			(xy 91.716348 -286.261856) (xy 91.708184 -286.31209) (xy 91.692068 -286.360364) (xy 91.668417 -286.405427)
			(xy 91.637844 -286.446113) (xy 91.60114 -286.481368) (xy 91.559256 -286.510278) (xy 91.513277 -286.532095)
			(xy 91.464393 -286.546255) (xy 91.413872 -286.552389) (xy 91.36302 -286.55034) (xy 91.313156 -286.54016)
			(xy 91.26557 -286.522113) (xy 91.221496 -286.496667) (xy 91.182074 -286.46448) (xy 91.148326 -286.426386)
			(xy 91.121125 -286.383372) (xy 91.101177 -286.336552) (xy 91.088998 -286.287138) (xy 91.084903 -286.23641)
			(xy 90.766392 -286.23641) (xy 90.765897 -286.261017) (xy 90.758002 -286.309594) (xy 90.742418 -286.356275)
			(xy 90.719547 -286.399852) (xy 90.689982 -286.439196) (xy 90.654489 -286.473288) (xy 90.613986 -286.501244)
			(xy 90.569524 -286.522342) (xy 90.522253 -286.536034) (xy 90.473398 -286.541966) (xy 90.424223 -286.539985)
			(xy 90.376004 -286.530141) (xy 90.329988 -286.512689) (xy 90.287367 -286.488082) (xy 90.249246 -286.456957)
			(xy 90.216611 -286.42012) (xy 90.190308 -286.378524) (xy 90.171017 -286.333248) (xy 90.15924 -286.285464)
			(xy 90.15528 -286.23641) (xy 89.826338 -286.23641) (xy 89.825843 -286.261017) (xy 89.817948 -286.309594)
			(xy 89.802364 -286.356275) (xy 89.779493 -286.399852) (xy 89.749928 -286.439196) (xy 89.714435 -286.473288)
			(xy 89.673932 -286.501244) (xy 89.62947 -286.522342) (xy 89.582199 -286.536034) (xy 89.533344 -286.541966)
			(xy 89.484169 -286.539985) (xy 89.43595 -286.530141) (xy 89.389934 -286.512689) (xy 89.347313 -286.488082)
			(xy 89.309192 -286.456957) (xy 89.276557 -286.42012) (xy 89.250254 -286.378524) (xy 89.230963 -286.333248)
			(xy 89.219186 -286.285464) (xy 89.215226 -286.23641) (xy 88.886284 -286.23641) (xy 88.885789 -286.261017)
			(xy 88.877894 -286.309594) (xy 88.86231 -286.356275) (xy 88.839439 -286.399852) (xy 88.809874 -286.439196)
			(xy 88.774381 -286.473288) (xy 88.733878 -286.501244) (xy 88.689416 -286.522342) (xy 88.642145 -286.536034)
			(xy 88.59329 -286.541966) (xy 88.544115 -286.539985) (xy 88.495896 -286.530141) (xy 88.44988 -286.512689)
			(xy 88.407259 -286.488082) (xy 88.369138 -286.456957) (xy 88.336503 -286.42012) (xy 88.3102 -286.378524)
			(xy 88.290909 -286.333248) (xy 88.279132 -286.285464) (xy 88.275172 -286.23641) (xy 87.94623 -286.23641)
			(xy 87.945735 -286.261017) (xy 87.93784 -286.309594) (xy 87.922256 -286.356275) (xy 87.899385 -286.399852)
			(xy 87.86982 -286.439196) (xy 87.834327 -286.473288) (xy 87.793824 -286.501244) (xy 87.749362 -286.522342)
			(xy 87.702091 -286.536034) (xy 87.653236 -286.541966) (xy 87.604061 -286.539985) (xy 87.555842 -286.530141)
			(xy 87.509826 -286.512689) (xy 87.467205 -286.488082) (xy 87.429084 -286.456957) (xy 87.396449 -286.42012)
			(xy 87.370146 -286.378524) (xy 87.350855 -286.333248) (xy 87.339078 -286.285464) (xy 87.335118 -286.23641)
			(xy 87.00643 -286.23641) (xy 87.005935 -286.261017) (xy 86.99804 -286.309594) (xy 86.982456 -286.356275)
			(xy 86.959585 -286.399852) (xy 86.93002 -286.439196) (xy 86.894527 -286.473288) (xy 86.854024 -286.501244)
			(xy 86.809562 -286.522342) (xy 86.762291 -286.536034) (xy 86.713436 -286.541966) (xy 86.664261 -286.539985)
			(xy 86.616042 -286.530141) (xy 86.570026 -286.512689) (xy 86.527405 -286.488082) (xy 86.489284 -286.456957)
			(xy 86.456649 -286.42012) (xy 86.430346 -286.378524) (xy 86.411055 -286.333248) (xy 86.399278 -286.285464)
			(xy 86.395318 -286.23641) (xy 86.066376 -286.23641) (xy 86.065881 -286.261017) (xy 86.057986 -286.309594)
			(xy 86.042402 -286.356275) (xy 86.019531 -286.399852) (xy 85.989966 -286.439196) (xy 85.954473 -286.473288)
			(xy 85.91397 -286.501244) (xy 85.869508 -286.522342) (xy 85.822237 -286.536034) (xy 85.773382 -286.541966)
			(xy 85.724207 -286.539985) (xy 85.675988 -286.530141) (xy 85.629972 -286.512689) (xy 85.587351 -286.488082)
			(xy 85.54923 -286.456957) (xy 85.516595 -286.42012) (xy 85.490292 -286.378524) (xy 85.471001 -286.333248)
			(xy 85.459224 -286.285464) (xy 85.455264 -286.23641) (xy 85.126322 -286.23641) (xy 85.125827 -286.261017)
			(xy 85.117932 -286.309594) (xy 85.102348 -286.356275) (xy 85.079477 -286.399852) (xy 85.049912 -286.439196)
			(xy 85.014419 -286.473288) (xy 84.973916 -286.501244) (xy 84.929454 -286.522342) (xy 84.882183 -286.536034)
			(xy 84.833328 -286.541966) (xy 84.784153 -286.539985) (xy 84.735934 -286.530141) (xy 84.689918 -286.512689)
			(xy 84.647297 -286.488082) (xy 84.609176 -286.456957) (xy 84.576541 -286.42012) (xy 84.550238 -286.378524)
			(xy 84.530947 -286.333248) (xy 84.51917 -286.285464) (xy 84.51521 -286.23641) (xy 84.186268 -286.23641)
			(xy 84.185821 -286.260401) (xy 84.178313 -286.307793) (xy 84.163483 -286.353427) (xy 84.141696 -286.396179)
			(xy 84.11349 -286.434996) (xy 84.079558 -286.468922) (xy 84.040736 -286.497123) (xy 83.997981 -286.518902)
			(xy 83.952345 -286.533725) (xy 83.904952 -286.541225) (xy 83.88096 -286.541718) (xy 83.85457 -286.541167)
			(xy 83.802572 -286.532107) (xy 83.752905 -286.514246) (xy 83.707046 -286.488117) (xy 83.666359 -286.454495)
			(xy 83.648804 -286.434784) (xy 83.627468 -286.409638) (xy 83.62569 -286.409638) (xy 83.621481 -286.40972)
			(xy 83.613182 -286.411126) (xy 83.60918 -286.412432) (xy 83.521804 -286.452818) (xy 83.514026 -286.457352)
			(xy 83.502047 -286.470774) (xy 83.495471 -286.48752) (xy 83.49488 -286.496506) (xy 83.49488 -286.665162)
			(xy 83.49491 -286.669298) (xy 83.496182 -286.677471) (xy 83.49742 -286.681418) (xy 83.502246 -286.691578)
			(xy 83.515708 -286.71266) (xy 83.519212 -286.717919) (xy 83.528339 -286.726653) (xy 83.533742 -286.729932)
			(xy 83.533996 -286.729932) (xy 83.555755 -286.742513) (xy 83.595198 -286.77366) (xy 83.612482 -286.791908)
			(xy 83.630123 -286.812108) (xy 83.658732 -286.857463) (xy 83.669378 -286.882078) (xy 83.672934 -286.888682)
			(xy 83.673188 -286.88919) (xy 83.686698 -286.913033) (xy 83.705934 -286.964342) (xy 83.715721 -287.018256)
			(xy 83.716368 -287.045654) (xy 83.716368 -287.046162) (xy 84.04531 -287.046162) (xy 84.04927 -286.997108)
			(xy 84.061047 -286.949324) (xy 84.080338 -286.904048) (xy 84.106641 -286.862452) (xy 84.139276 -286.825615)
			(xy 84.177397 -286.79449) (xy 84.220018 -286.769883) (xy 84.266034 -286.752431) (xy 84.314253 -286.742587)
			(xy 84.363428 -286.740606) (xy 84.412283 -286.746538) (xy 84.459554 -286.76023) (xy 84.504016 -286.781328)
			(xy 84.544519 -286.809284) (xy 84.580012 -286.843376) (xy 84.609577 -286.88272) (xy 84.632448 -286.926297)
			(xy 84.648032 -286.972978) (xy 84.655927 -287.021555) (xy 84.656422 -287.046162) (xy 84.656412 -287.04667)
			(xy 84.985364 -287.04667) (xy 84.989324 -286.997616) (xy 85.001101 -286.949832) (xy 85.020392 -286.904556)
			(xy 85.046695 -286.86296) (xy 85.07933 -286.826123) (xy 85.117451 -286.794998) (xy 85.160072 -286.770391)
			(xy 85.206088 -286.752939) (xy 85.254307 -286.743095) (xy 85.303482 -286.741114) (xy 85.352337 -286.747046)
			(xy 85.399608 -286.760738) (xy 85.44407 -286.781836) (xy 85.484573 -286.809792) (xy 85.520066 -286.843884)
			(xy 85.549631 -286.883228) (xy 85.572502 -286.926805) (xy 85.588086 -286.973486) (xy 85.595981 -287.022063)
			(xy 85.596466 -287.046162) (xy 85.925164 -287.046162) (xy 85.929124 -286.997108) (xy 85.940901 -286.949324)
			(xy 85.960192 -286.904048) (xy 85.986495 -286.862452) (xy 86.01913 -286.825615) (xy 86.057251 -286.79449)
			(xy 86.099872 -286.769883) (xy 86.145888 -286.752431) (xy 86.194107 -286.742587) (xy 86.243282 -286.740606)
			(xy 86.292137 -286.746538) (xy 86.339408 -286.76023) (xy 86.38387 -286.781328) (xy 86.424373 -286.809284)
			(xy 86.459866 -286.843376) (xy 86.489431 -286.88272) (xy 86.512302 -286.926297) (xy 86.527886 -286.972978)
			(xy 86.535781 -287.021555) (xy 86.536276 -287.046162) (xy 86.865218 -287.046162) (xy 86.869178 -286.997108)
			(xy 86.880955 -286.949324) (xy 86.900246 -286.904048) (xy 86.926549 -286.862452) (xy 86.959184 -286.825615)
			(xy 86.997305 -286.79449) (xy 87.039926 -286.769883) (xy 87.085942 -286.752431) (xy 87.134161 -286.742587)
			(xy 87.183336 -286.740606) (xy 87.232191 -286.746538) (xy 87.279462 -286.76023) (xy 87.323924 -286.781328)
			(xy 87.364427 -286.809284) (xy 87.39992 -286.843376) (xy 87.429485 -286.88272) (xy 87.452356 -286.926297)
			(xy 87.46794 -286.972978) (xy 87.475835 -287.021555) (xy 87.47633 -287.046162) (xy 87.805272 -287.046162)
			(xy 87.809232 -286.997108) (xy 87.821009 -286.949324) (xy 87.8403 -286.904048) (xy 87.866603 -286.862452)
			(xy 87.899238 -286.825615) (xy 87.937359 -286.79449) (xy 87.97998 -286.769883) (xy 88.025996 -286.752431)
			(xy 88.074215 -286.742587) (xy 88.12339 -286.740606) (xy 88.172245 -286.746538) (xy 88.219516 -286.76023)
			(xy 88.263978 -286.781328) (xy 88.304481 -286.809284) (xy 88.339974 -286.843376) (xy 88.369539 -286.88272)
			(xy 88.39241 -286.926297) (xy 88.407994 -286.972978) (xy 88.415889 -287.021555) (xy 88.416384 -287.046162)
			(xy 88.745326 -287.046162) (xy 88.749286 -286.997108) (xy 88.761063 -286.949324) (xy 88.780354 -286.904048)
			(xy 88.806657 -286.862452) (xy 88.839292 -286.825615) (xy 88.877413 -286.79449) (xy 88.920034 -286.769883)
			(xy 88.96605 -286.752431) (xy 89.014269 -286.742587) (xy 89.063444 -286.740606) (xy 89.112299 -286.746538)
			(xy 89.15957 -286.76023) (xy 89.204032 -286.781328) (xy 89.244535 -286.809284) (xy 89.280028 -286.843376)
			(xy 89.309593 -286.88272) (xy 89.332464 -286.926297) (xy 89.348048 -286.972978) (xy 89.355943 -287.021555)
			(xy 89.356438 -287.046162) (xy 89.356428 -287.04667) (xy 89.68538 -287.04667) (xy 89.68934 -286.997616)
			(xy 89.701117 -286.949832) (xy 89.720408 -286.904556) (xy 89.746711 -286.86296) (xy 89.779346 -286.826123)
			(xy 89.817467 -286.794998) (xy 89.860088 -286.770391) (xy 89.906104 -286.752939) (xy 89.954323 -286.743095)
			(xy 90.003498 -286.741114) (xy 90.052353 -286.747046) (xy 90.099624 -286.760738) (xy 90.144086 -286.781836)
			(xy 90.184589 -286.809792) (xy 90.220082 -286.843884) (xy 90.249647 -286.883228) (xy 90.272518 -286.926805)
			(xy 90.288102 -286.973486) (xy 90.295997 -287.022063) (xy 90.296482 -287.046162) (xy 90.614749 -287.046162)
			(xy 90.618844 -286.995434) (xy 90.631023 -286.94602) (xy 90.650971 -286.8992) (xy 90.678172 -286.856186)
			(xy 90.71192 -286.818092) (xy 90.751342 -286.785905) (xy 90.795416 -286.760459) (xy 90.843002 -286.742412)
			(xy 90.892866 -286.732232) (xy 90.943718 -286.730183) (xy 90.994239 -286.736317) (xy 91.043123 -286.750477)
			(xy 91.089102 -286.772294) (xy 91.130986 -286.801204) (xy 91.16769 -286.836459) (xy 91.198263 -286.877145)
			(xy 91.221914 -286.922208) (xy 91.23803 -286.970482) (xy 91.246194 -287.020716) (xy 91.246706 -287.046162)
			(xy 91.565234 -287.046162) (xy 91.569194 -286.997108) (xy 91.580971 -286.949324) (xy 91.600262 -286.904048)
			(xy 91.626565 -286.862452) (xy 91.6592 -286.825615) (xy 91.697321 -286.79449) (xy 91.739942 -286.769883)
			(xy 91.785958 -286.752431) (xy 91.834177 -286.742587) (xy 91.883352 -286.740606) (xy 91.932207 -286.746538)
			(xy 91.979478 -286.76023) (xy 92.02394 -286.781328) (xy 92.064443 -286.809284) (xy 92.099936 -286.843376)
			(xy 92.129501 -286.88272) (xy 92.152372 -286.926297) (xy 92.167956 -286.972978) (xy 92.175851 -287.021555)
			(xy 92.176346 -287.046162) (xy 92.494857 -287.046162) (xy 92.498952 -286.995434) (xy 92.511131 -286.94602)
			(xy 92.531079 -286.8992) (xy 92.55828 -286.856186) (xy 92.592028 -286.818092) (xy 92.63145 -286.785905)
			(xy 92.675524 -286.760459) (xy 92.72311 -286.742412) (xy 92.772974 -286.732232) (xy 92.823826 -286.730183)
			(xy 92.874347 -286.736317) (xy 92.923231 -286.750477) (xy 92.96921 -286.772294) (xy 93.011094 -286.801204)
			(xy 93.047798 -286.836459) (xy 93.078371 -286.877145) (xy 93.102022 -286.922208) (xy 93.118138 -286.970482)
			(xy 93.126302 -287.020716) (xy 93.126814 -287.046162) (xy 93.445342 -287.046162) (xy 93.449302 -286.997108)
			(xy 93.461079 -286.949324) (xy 93.48037 -286.904048) (xy 93.506673 -286.862452) (xy 93.539308 -286.825615)
			(xy 93.577429 -286.79449) (xy 93.62005 -286.769883) (xy 93.666066 -286.752431) (xy 93.714285 -286.742587)
			(xy 93.76346 -286.740606) (xy 93.812315 -286.746538) (xy 93.859586 -286.76023) (xy 93.904048 -286.781328)
			(xy 93.944551 -286.809284) (xy 93.980044 -286.843376) (xy 94.009609 -286.88272) (xy 94.03248 -286.926297)
			(xy 94.048064 -286.972978) (xy 94.055959 -287.021555) (xy 94.056454 -287.046162) (xy 94.374711 -287.046162)
			(xy 94.378806 -286.995434) (xy 94.390985 -286.94602) (xy 94.410933 -286.8992) (xy 94.438134 -286.856186)
			(xy 94.471882 -286.818092) (xy 94.511304 -286.785905) (xy 94.555378 -286.760459) (xy 94.602964 -286.742412)
			(xy 94.652828 -286.732232) (xy 94.70368 -286.730183) (xy 94.754201 -286.736317) (xy 94.803085 -286.750477)
			(xy 94.849064 -286.772294) (xy 94.890948 -286.801204) (xy 94.927652 -286.836459) (xy 94.958225 -286.877145)
			(xy 94.981876 -286.922208) (xy 94.997992 -286.970482) (xy 95.006156 -287.020716) (xy 95.006668 -287.046162)
			(xy 95.314765 -287.046162) (xy 95.31886 -286.995434) (xy 95.331039 -286.94602) (xy 95.350987 -286.8992)
			(xy 95.378188 -286.856186) (xy 95.411936 -286.818092) (xy 95.451358 -286.785905) (xy 95.495432 -286.760459)
			(xy 95.543018 -286.742412) (xy 95.592882 -286.732232) (xy 95.643734 -286.730183) (xy 95.694255 -286.736317)
			(xy 95.743139 -286.750477) (xy 95.789118 -286.772294) (xy 95.831002 -286.801204) (xy 95.867706 -286.836459)
			(xy 95.898279 -286.877145) (xy 95.92193 -286.922208) (xy 95.938046 -286.970482) (xy 95.94621 -287.020716)
			(xy 95.946722 -287.046162) (xy 95.94621 -287.071608) (xy 95.938046 -287.121842) (xy 95.92193 -287.170116)
			(xy 95.898279 -287.215179) (xy 95.867706 -287.255865) (xy 95.831002 -287.29112) (xy 95.789118 -287.32003)
			(xy 95.743139 -287.341847) (xy 95.694255 -287.356007) (xy 95.643734 -287.362141) (xy 95.592882 -287.360092)
			(xy 95.543018 -287.349912) (xy 95.495432 -287.331865) (xy 95.451358 -287.306419) (xy 95.411936 -287.274232)
			(xy 95.378188 -287.236138) (xy 95.350987 -287.193124) (xy 95.331039 -287.146304) (xy 95.31886 -287.09689)
			(xy 95.314765 -287.046162) (xy 95.006668 -287.046162) (xy 95.006156 -287.071608) (xy 94.997992 -287.121842)
			(xy 94.981876 -287.170116) (xy 94.958225 -287.215179) (xy 94.927652 -287.255865) (xy 94.890948 -287.29112)
			(xy 94.849064 -287.32003) (xy 94.803085 -287.341847) (xy 94.754201 -287.356007) (xy 94.70368 -287.362141)
			(xy 94.652828 -287.360092) (xy 94.602964 -287.349912) (xy 94.555378 -287.331865) (xy 94.511304 -287.306419)
			(xy 94.471882 -287.274232) (xy 94.438134 -287.236138) (xy 94.410933 -287.193124) (xy 94.390985 -287.146304)
			(xy 94.378806 -287.09689) (xy 94.374711 -287.046162) (xy 94.056454 -287.046162) (xy 94.055959 -287.070769)
			(xy 94.048064 -287.119346) (xy 94.03248 -287.166027) (xy 94.009609 -287.209604) (xy 93.980044 -287.248948)
			(xy 93.944551 -287.28304) (xy 93.904048 -287.310996) (xy 93.859586 -287.332094) (xy 93.812315 -287.345786)
			(xy 93.76346 -287.351718) (xy 93.714285 -287.349737) (xy 93.666066 -287.339893) (xy 93.62005 -287.322441)
			(xy 93.577429 -287.297834) (xy 93.539308 -287.266709) (xy 93.506673 -287.229872) (xy 93.48037 -287.188276)
			(xy 93.461079 -287.143) (xy 93.449302 -287.095216) (xy 93.445342 -287.046162) (xy 93.126814 -287.046162)
			(xy 93.126302 -287.071608) (xy 93.118138 -287.121842) (xy 93.102022 -287.170116) (xy 93.078371 -287.215179)
			(xy 93.047798 -287.255865) (xy 93.011094 -287.29112) (xy 92.96921 -287.32003) (xy 92.923231 -287.341847)
			(xy 92.874347 -287.356007) (xy 92.823826 -287.362141) (xy 92.772974 -287.360092) (xy 92.72311 -287.349912)
			(xy 92.675524 -287.331865) (xy 92.63145 -287.306419) (xy 92.592028 -287.274232) (xy 92.55828 -287.236138)
			(xy 92.531079 -287.193124) (xy 92.511131 -287.146304) (xy 92.498952 -287.09689) (xy 92.494857 -287.046162)
			(xy 92.176346 -287.046162) (xy 92.175851 -287.070769) (xy 92.167956 -287.119346) (xy 92.152372 -287.166027)
			(xy 92.129501 -287.209604) (xy 92.099936 -287.248948) (xy 92.064443 -287.28304) (xy 92.02394 -287.310996)
			(xy 91.979478 -287.332094) (xy 91.932207 -287.345786) (xy 91.883352 -287.351718) (xy 91.834177 -287.349737)
			(xy 91.785958 -287.339893) (xy 91.739942 -287.322441) (xy 91.697321 -287.297834) (xy 91.6592 -287.266709)
			(xy 91.626565 -287.229872) (xy 91.600262 -287.188276) (xy 91.580971 -287.143) (xy 91.569194 -287.095216)
			(xy 91.565234 -287.046162) (xy 91.246706 -287.046162) (xy 91.246194 -287.071608) (xy 91.23803 -287.121842)
			(xy 91.221914 -287.170116) (xy 91.198263 -287.215179) (xy 91.16769 -287.255865) (xy 91.130986 -287.29112)
			(xy 91.089102 -287.32003) (xy 91.043123 -287.341847) (xy 90.994239 -287.356007) (xy 90.943718 -287.362141)
			(xy 90.892866 -287.360092) (xy 90.843002 -287.349912) (xy 90.795416 -287.331865) (xy 90.751342 -287.306419)
			(xy 90.71192 -287.274232) (xy 90.678172 -287.236138) (xy 90.650971 -287.193124) (xy 90.631023 -287.146304)
			(xy 90.618844 -287.09689) (xy 90.614749 -287.046162) (xy 90.296482 -287.046162) (xy 90.296492 -287.04667)
			(xy 90.295997 -287.071277) (xy 90.288102 -287.119854) (xy 90.272518 -287.166535) (xy 90.249647 -287.210112)
			(xy 90.220082 -287.249456) (xy 90.184589 -287.283548) (xy 90.144086 -287.311504) (xy 90.099624 -287.332602)
			(xy 90.052353 -287.346294) (xy 90.003498 -287.352226) (xy 89.954323 -287.350245) (xy 89.906104 -287.340401)
			(xy 89.860088 -287.322949) (xy 89.817467 -287.298342) (xy 89.779346 -287.267217) (xy 89.746711 -287.23038)
			(xy 89.720408 -287.188784) (xy 89.701117 -287.143508) (xy 89.68934 -287.095724) (xy 89.68538 -287.04667)
			(xy 89.356428 -287.04667) (xy 89.355943 -287.070769) (xy 89.348048 -287.119346) (xy 89.332464 -287.166027)
			(xy 89.309593 -287.209604) (xy 89.280028 -287.248948) (xy 89.244535 -287.28304) (xy 89.204032 -287.310996)
			(xy 89.15957 -287.332094) (xy 89.112299 -287.345786) (xy 89.063444 -287.351718) (xy 89.014269 -287.349737)
			(xy 88.96605 -287.339893) (xy 88.920034 -287.322441) (xy 88.877413 -287.297834) (xy 88.839292 -287.266709)
			(xy 88.806657 -287.229872) (xy 88.780354 -287.188276) (xy 88.761063 -287.143) (xy 88.749286 -287.095216)
			(xy 88.745326 -287.046162) (xy 88.416384 -287.046162) (xy 88.415889 -287.070769) (xy 88.407994 -287.119346)
			(xy 88.39241 -287.166027) (xy 88.369539 -287.209604) (xy 88.339974 -287.248948) (xy 88.304481 -287.28304)
			(xy 88.263978 -287.310996) (xy 88.219516 -287.332094) (xy 88.172245 -287.345786) (xy 88.12339 -287.351718)
			(xy 88.074215 -287.349737) (xy 88.025996 -287.339893) (xy 87.97998 -287.322441) (xy 87.937359 -287.297834)
			(xy 87.899238 -287.266709) (xy 87.866603 -287.229872) (xy 87.8403 -287.188276) (xy 87.821009 -287.143)
			(xy 87.809232 -287.095216) (xy 87.805272 -287.046162) (xy 87.47633 -287.046162) (xy 87.475835 -287.070769)
			(xy 87.46794 -287.119346) (xy 87.452356 -287.166027) (xy 87.429485 -287.209604) (xy 87.39992 -287.248948)
			(xy 87.364427 -287.28304) (xy 87.323924 -287.310996) (xy 87.279462 -287.332094) (xy 87.232191 -287.345786)
			(xy 87.183336 -287.351718) (xy 87.134161 -287.349737) (xy 87.085942 -287.339893) (xy 87.039926 -287.322441)
			(xy 86.997305 -287.297834) (xy 86.959184 -287.266709) (xy 86.926549 -287.229872) (xy 86.900246 -287.188276)
			(xy 86.880955 -287.143) (xy 86.869178 -287.095216) (xy 86.865218 -287.046162) (xy 86.536276 -287.046162)
			(xy 86.535781 -287.070769) (xy 86.527886 -287.119346) (xy 86.512302 -287.166027) (xy 86.489431 -287.209604)
			(xy 86.459866 -287.248948) (xy 86.424373 -287.28304) (xy 86.38387 -287.310996) (xy 86.339408 -287.332094)
			(xy 86.292137 -287.345786) (xy 86.243282 -287.351718) (xy 86.194107 -287.349737) (xy 86.145888 -287.339893)
			(xy 86.099872 -287.322441) (xy 86.057251 -287.297834) (xy 86.01913 -287.266709) (xy 85.986495 -287.229872)
			(xy 85.960192 -287.188276) (xy 85.940901 -287.143) (xy 85.929124 -287.095216) (xy 85.925164 -287.046162)
			(xy 85.596466 -287.046162) (xy 85.596476 -287.04667) (xy 85.595981 -287.071277) (xy 85.588086 -287.119854)
			(xy 85.572502 -287.166535) (xy 85.549631 -287.210112) (xy 85.520066 -287.249456) (xy 85.484573 -287.283548)
			(xy 85.44407 -287.311504) (xy 85.399608 -287.332602) (xy 85.352337 -287.346294) (xy 85.303482 -287.352226)
			(xy 85.254307 -287.350245) (xy 85.206088 -287.340401) (xy 85.160072 -287.322949) (xy 85.117451 -287.298342)
			(xy 85.07933 -287.267217) (xy 85.046695 -287.23038) (xy 85.020392 -287.188784) (xy 85.001101 -287.143508)
			(xy 84.989324 -287.095724) (xy 84.985364 -287.04667) (xy 84.656412 -287.04667) (xy 84.655927 -287.070769)
			(xy 84.648032 -287.119346) (xy 84.632448 -287.166027) (xy 84.609577 -287.209604) (xy 84.580012 -287.248948)
			(xy 84.544519 -287.28304) (xy 84.504016 -287.310996) (xy 84.459554 -287.332094) (xy 84.412283 -287.345786)
			(xy 84.363428 -287.351718) (xy 84.314253 -287.349737) (xy 84.266034 -287.339893) (xy 84.220018 -287.322441)
			(xy 84.177397 -287.297834) (xy 84.139276 -287.266709) (xy 84.106641 -287.229872) (xy 84.080338 -287.188276)
			(xy 84.061047 -287.143) (xy 84.04927 -287.095216) (xy 84.04531 -287.046162) (xy 83.716368 -287.046162)
			(xy 83.716368 -287.052004) (xy 83.715349 -287.077694) (xy 83.705774 -287.128204) (xy 83.687872 -287.176397)
			(xy 83.662149 -287.220909) (xy 83.629332 -287.260482) (xy 83.59035 -287.293998) (xy 83.546303 -287.320509)
			(xy 83.522566 -287.330388) (xy 83.512152 -287.334706) (xy 83.503516 -287.347406) (xy 83.499489 -287.353813)
			(xy 83.495104 -287.368289) (xy 83.49488 -287.375854) (xy 83.49488 -287.498536) (xy 83.49514 -287.504144)
			(xy 83.497834 -287.515041) (xy 83.500214 -287.520126) (xy 83.504786 -287.528) (xy 83.508734 -287.532859)
			(xy 83.518489 -287.540698) (xy 83.52409 -287.543494) (xy 83.524344 -287.543748) (xy 83.605116 -287.581086)
			(xy 83.618832 -287.584388) (xy 83.631278 -287.584896) (xy 83.648042 -287.578546) (xy 83.6549 -287.575244)
			(xy 83.665314 -287.569402) (xy 83.6676 -287.567624) (xy 83.668616 -287.566862) (xy 83.66887 -287.566608)
			(xy 83.689158 -287.551536) (xy 83.73364 -287.527548) (xy 83.781455 -287.511185) (xy 83.831307 -287.502889)
			(xy 83.856576 -287.502346) (xy 83.882413 -287.502894) (xy 83.933349 -287.511607) (xy 83.982089 -287.528773)
			(xy 84.027244 -287.5539) (xy 84.067523 -287.586271) (xy 84.101777 -287.624962) (xy 84.129027 -287.668868)
			(xy 84.139278 -287.692592) (xy 84.142834 -287.699196) (xy 84.143088 -287.699704) (xy 84.156624 -287.723584)
			(xy 84.175889 -287.774975) (xy 84.185676 -287.82898) (xy 84.186268 -287.856422) (xy 84.51521 -287.856422)
			(xy 84.51917 -287.807368) (xy 84.530947 -287.759584) (xy 84.550238 -287.714308) (xy 84.576541 -287.672712)
			(xy 84.609176 -287.635875) (xy 84.647297 -287.60475) (xy 84.689918 -287.580143) (xy 84.735934 -287.562691)
			(xy 84.784153 -287.552847) (xy 84.833328 -287.550866) (xy 84.882183 -287.556798) (xy 84.929454 -287.57049)
			(xy 84.973916 -287.591588) (xy 85.014419 -287.619544) (xy 85.049912 -287.653636) (xy 85.079477 -287.69298)
			(xy 85.102348 -287.736557) (xy 85.117932 -287.783238) (xy 85.125827 -287.831815) (xy 85.126322 -287.856422)
			(xy 85.455264 -287.856422) (xy 85.459224 -287.807368) (xy 85.471001 -287.759584) (xy 85.490292 -287.714308)
			(xy 85.516595 -287.672712) (xy 85.54923 -287.635875) (xy 85.587351 -287.60475) (xy 85.629972 -287.580143)
			(xy 85.675988 -287.562691) (xy 85.724207 -287.552847) (xy 85.773382 -287.550866) (xy 85.822237 -287.556798)
			(xy 85.869508 -287.57049) (xy 85.91397 -287.591588) (xy 85.954473 -287.619544) (xy 85.989966 -287.653636)
			(xy 86.019531 -287.69298) (xy 86.042402 -287.736557) (xy 86.057986 -287.783238) (xy 86.065881 -287.831815)
			(xy 86.066376 -287.856422) (xy 87.335118 -287.856422) (xy 87.339078 -287.807368) (xy 87.350855 -287.759584)
			(xy 87.370146 -287.714308) (xy 87.396449 -287.672712) (xy 87.429084 -287.635875) (xy 87.467205 -287.60475)
			(xy 87.509826 -287.580143) (xy 87.555842 -287.562691) (xy 87.604061 -287.552847) (xy 87.653236 -287.550866)
			(xy 87.702091 -287.556798) (xy 87.749362 -287.57049) (xy 87.793824 -287.591588) (xy 87.834327 -287.619544)
			(xy 87.86982 -287.653636) (xy 87.899385 -287.69298) (xy 87.922256 -287.736557) (xy 87.93784 -287.783238)
			(xy 87.945735 -287.831815) (xy 87.94623 -287.856422) (xy 88.275172 -287.856422) (xy 88.279132 -287.807368)
			(xy 88.290909 -287.759584) (xy 88.3102 -287.714308) (xy 88.336503 -287.672712) (xy 88.369138 -287.635875)
			(xy 88.407259 -287.60475) (xy 88.44988 -287.580143) (xy 88.495896 -287.562691) (xy 88.544115 -287.552847)
			(xy 88.59329 -287.550866) (xy 88.642145 -287.556798) (xy 88.689416 -287.57049) (xy 88.733878 -287.591588)
			(xy 88.774381 -287.619544) (xy 88.809874 -287.653636) (xy 88.839439 -287.69298) (xy 88.86231 -287.736557)
			(xy 88.877894 -287.783238) (xy 88.885789 -287.831815) (xy 88.886284 -287.856422) (xy 89.215226 -287.856422)
			(xy 89.219186 -287.807368) (xy 89.230963 -287.759584) (xy 89.250254 -287.714308) (xy 89.276557 -287.672712)
			(xy 89.309192 -287.635875) (xy 89.347313 -287.60475) (xy 89.389934 -287.580143) (xy 89.43595 -287.562691)
			(xy 89.484169 -287.552847) (xy 89.533344 -287.550866) (xy 89.582199 -287.556798) (xy 89.62947 -287.57049)
			(xy 89.673932 -287.591588) (xy 89.714435 -287.619544) (xy 89.749928 -287.653636) (xy 89.779493 -287.69298)
			(xy 89.802364 -287.736557) (xy 89.817948 -287.783238) (xy 89.825843 -287.831815) (xy 89.826338 -287.856422)
			(xy 90.15528 -287.856422) (xy 90.15924 -287.807368) (xy 90.171017 -287.759584) (xy 90.190308 -287.714308)
			(xy 90.216611 -287.672712) (xy 90.249246 -287.635875) (xy 90.287367 -287.60475) (xy 90.329988 -287.580143)
			(xy 90.376004 -287.562691) (xy 90.424223 -287.552847) (xy 90.473398 -287.550866) (xy 90.522253 -287.556798)
			(xy 90.569524 -287.57049) (xy 90.613986 -287.591588) (xy 90.654489 -287.619544) (xy 90.689982 -287.653636)
			(xy 90.719547 -287.69298) (xy 90.742418 -287.736557) (xy 90.758002 -287.783238) (xy 90.765897 -287.831815)
			(xy 90.766392 -287.856422) (xy 91.084903 -287.856422) (xy 91.088998 -287.805694) (xy 91.101177 -287.75628)
			(xy 91.121125 -287.70946) (xy 91.148326 -287.666446) (xy 91.182074 -287.628352) (xy 91.221496 -287.596165)
			(xy 91.26557 -287.570719) (xy 91.313156 -287.552672) (xy 91.36302 -287.542492) (xy 91.413872 -287.540443)
			(xy 91.464393 -287.546577) (xy 91.513277 -287.560737) (xy 91.559256 -287.582554) (xy 91.60114 -287.611464)
			(xy 91.637844 -287.646719) (xy 91.668417 -287.687405) (xy 91.692068 -287.732468) (xy 91.708184 -287.780742)
			(xy 91.716348 -287.830976) (xy 91.71686 -287.856422) (xy 92.024703 -287.856422) (xy 92.028798 -287.805694)
			(xy 92.040977 -287.75628) (xy 92.060925 -287.70946) (xy 92.088126 -287.666446) (xy 92.121874 -287.628352)
			(xy 92.161296 -287.596165) (xy 92.20537 -287.570719) (xy 92.252956 -287.552672) (xy 92.30282 -287.542492)
			(xy 92.353672 -287.540443) (xy 92.404193 -287.546577) (xy 92.453077 -287.560737) (xy 92.499056 -287.582554)
			(xy 92.54094 -287.611464) (xy 92.577644 -287.646719) (xy 92.608217 -287.687405) (xy 92.631868 -287.732468)
			(xy 92.647984 -287.780742) (xy 92.656148 -287.830976) (xy 92.65666 -287.856422) (xy 93.904811 -287.856422)
			(xy 93.908906 -287.805694) (xy 93.921085 -287.75628) (xy 93.941033 -287.70946) (xy 93.968234 -287.666446)
			(xy 94.001982 -287.628352) (xy 94.041404 -287.596165) (xy 94.085478 -287.570719) (xy 94.133064 -287.552672)
			(xy 94.182928 -287.542492) (xy 94.23378 -287.540443) (xy 94.284301 -287.546577) (xy 94.333185 -287.560737)
			(xy 94.379164 -287.582554) (xy 94.421048 -287.611464) (xy 94.457752 -287.646719) (xy 94.488325 -287.687405)
			(xy 94.511976 -287.732468) (xy 94.528092 -287.780742) (xy 94.536256 -287.830976) (xy 94.536768 -287.856422)
			(xy 94.855296 -287.856422) (xy 94.859256 -287.807368) (xy 94.871033 -287.759584) (xy 94.890324 -287.714308)
			(xy 94.916627 -287.672712) (xy 94.949262 -287.635875) (xy 94.987383 -287.60475) (xy 95.030004 -287.580143)
			(xy 95.07602 -287.562691) (xy 95.124239 -287.552847) (xy 95.173414 -287.550866) (xy 95.222269 -287.556798)
			(xy 95.26954 -287.57049) (xy 95.314002 -287.591588) (xy 95.354505 -287.619544) (xy 95.389998 -287.653636)
			(xy 95.419563 -287.69298) (xy 95.442434 -287.736557) (xy 95.458018 -287.783238) (xy 95.465913 -287.831815)
			(xy 95.466408 -287.856422) (xy 95.784919 -287.856422) (xy 95.789014 -287.805694) (xy 95.801193 -287.75628)
			(xy 95.821141 -287.70946) (xy 95.848342 -287.666446) (xy 95.88209 -287.628352) (xy 95.921512 -287.596165)
			(xy 95.965586 -287.570719) (xy 96.013172 -287.552672) (xy 96.063036 -287.542492) (xy 96.113888 -287.540443)
			(xy 96.164409 -287.546577) (xy 96.213293 -287.560737) (xy 96.259272 -287.582554) (xy 96.301156 -287.611464)
			(xy 96.33786 -287.646719) (xy 96.368433 -287.687405) (xy 96.392084 -287.732468) (xy 96.4082 -287.780742)
			(xy 96.416364 -287.830976) (xy 96.416876 -287.856422) (xy 96.416364 -287.881868) (xy 96.4082 -287.932102)
			(xy 96.392084 -287.980376) (xy 96.368433 -288.025439) (xy 96.33786 -288.066125) (xy 96.301156 -288.10138)
			(xy 96.259272 -288.13029) (xy 96.213293 -288.152107) (xy 96.164409 -288.166267) (xy 96.113888 -288.172401)
			(xy 96.063036 -288.170352) (xy 96.013172 -288.160172) (xy 95.965586 -288.142125) (xy 95.921512 -288.116679)
			(xy 95.88209 -288.084492) (xy 95.848342 -288.046398) (xy 95.821141 -288.003384) (xy 95.801193 -287.956564)
			(xy 95.789014 -287.90715) (xy 95.784919 -287.856422) (xy 95.466408 -287.856422) (xy 95.465913 -287.881029)
			(xy 95.458018 -287.929606) (xy 95.442434 -287.976287) (xy 95.419563 -288.019864) (xy 95.389998 -288.059208)
			(xy 95.354505 -288.0933) (xy 95.314002 -288.121256) (xy 95.26954 -288.142354) (xy 95.222269 -288.156046)
			(xy 95.173414 -288.161978) (xy 95.124239 -288.159997) (xy 95.07602 -288.150153) (xy 95.030004 -288.132701)
			(xy 94.987383 -288.108094) (xy 94.949262 -288.076969) (xy 94.916627 -288.040132) (xy 94.890324 -287.998536)
			(xy 94.871033 -287.95326) (xy 94.859256 -287.905476) (xy 94.855296 -287.856422) (xy 94.536768 -287.856422)
			(xy 94.536256 -287.881868) (xy 94.528092 -287.932102) (xy 94.511976 -287.980376) (xy 94.488325 -288.025439)
			(xy 94.457752 -288.066125) (xy 94.421048 -288.10138) (xy 94.379164 -288.13029) (xy 94.333185 -288.152107)
			(xy 94.284301 -288.166267) (xy 94.23378 -288.172401) (xy 94.182928 -288.170352) (xy 94.133064 -288.160172)
			(xy 94.085478 -288.142125) (xy 94.041404 -288.116679) (xy 94.001982 -288.084492) (xy 93.968234 -288.046398)
			(xy 93.941033 -288.003384) (xy 93.921085 -287.956564) (xy 93.908906 -287.90715) (xy 93.904811 -287.856422)
			(xy 92.65666 -287.856422) (xy 92.656148 -287.881868) (xy 92.647984 -287.932102) (xy 92.631868 -287.980376)
			(xy 92.608217 -288.025439) (xy 92.577644 -288.066125) (xy 92.54094 -288.10138) (xy 92.499056 -288.13029)
			(xy 92.453077 -288.152107) (xy 92.404193 -288.166267) (xy 92.353672 -288.172401) (xy 92.30282 -288.170352)
			(xy 92.252956 -288.160172) (xy 92.20537 -288.142125) (xy 92.161296 -288.116679) (xy 92.121874 -288.084492)
			(xy 92.088126 -288.046398) (xy 92.060925 -288.003384) (xy 92.040977 -287.956564) (xy 92.028798 -287.90715)
			(xy 92.024703 -287.856422) (xy 91.71686 -287.856422) (xy 91.716348 -287.881868) (xy 91.708184 -287.932102)
			(xy 91.692068 -287.980376) (xy 91.668417 -288.025439) (xy 91.637844 -288.066125) (xy 91.60114 -288.10138)
			(xy 91.559256 -288.13029) (xy 91.513277 -288.152107) (xy 91.464393 -288.166267) (xy 91.413872 -288.172401)
			(xy 91.36302 -288.170352) (xy 91.313156 -288.160172) (xy 91.26557 -288.142125) (xy 91.221496 -288.116679)
			(xy 91.182074 -288.084492) (xy 91.148326 -288.046398) (xy 91.121125 -288.003384) (xy 91.101177 -287.956564)
			(xy 91.088998 -287.90715) (xy 91.084903 -287.856422) (xy 90.766392 -287.856422) (xy 90.765897 -287.881029)
			(xy 90.758002 -287.929606) (xy 90.742418 -287.976287) (xy 90.719547 -288.019864) (xy 90.689982 -288.059208)
			(xy 90.654489 -288.0933) (xy 90.613986 -288.121256) (xy 90.569524 -288.142354) (xy 90.522253 -288.156046)
			(xy 90.473398 -288.161978) (xy 90.424223 -288.159997) (xy 90.376004 -288.150153) (xy 90.329988 -288.132701)
			(xy 90.287367 -288.108094) (xy 90.249246 -288.076969) (xy 90.216611 -288.040132) (xy 90.190308 -287.998536)
			(xy 90.171017 -287.95326) (xy 90.15924 -287.905476) (xy 90.15528 -287.856422) (xy 89.826338 -287.856422)
			(xy 89.825843 -287.881029) (xy 89.817948 -287.929606) (xy 89.802364 -287.976287) (xy 89.779493 -288.019864)
			(xy 89.749928 -288.059208) (xy 89.714435 -288.0933) (xy 89.673932 -288.121256) (xy 89.62947 -288.142354)
			(xy 89.582199 -288.156046) (xy 89.533344 -288.161978) (xy 89.484169 -288.159997) (xy 89.43595 -288.150153)
			(xy 89.389934 -288.132701) (xy 89.347313 -288.108094) (xy 89.309192 -288.076969) (xy 89.276557 -288.040132)
			(xy 89.250254 -287.998536) (xy 89.230963 -287.95326) (xy 89.219186 -287.905476) (xy 89.215226 -287.856422)
			(xy 88.886284 -287.856422) (xy 88.885789 -287.881029) (xy 88.877894 -287.929606) (xy 88.86231 -287.976287)
			(xy 88.839439 -288.019864) (xy 88.809874 -288.059208) (xy 88.774381 -288.0933) (xy 88.733878 -288.121256)
			(xy 88.689416 -288.142354) (xy 88.642145 -288.156046) (xy 88.59329 -288.161978) (xy 88.544115 -288.159997)
			(xy 88.495896 -288.150153) (xy 88.44988 -288.132701) (xy 88.407259 -288.108094) (xy 88.369138 -288.076969)
			(xy 88.336503 -288.040132) (xy 88.3102 -287.998536) (xy 88.290909 -287.95326) (xy 88.279132 -287.905476)
			(xy 88.275172 -287.856422) (xy 87.94623 -287.856422) (xy 87.945735 -287.881029) (xy 87.93784 -287.929606)
			(xy 87.922256 -287.976287) (xy 87.899385 -288.019864) (xy 87.86982 -288.059208) (xy 87.834327 -288.0933)
			(xy 87.793824 -288.121256) (xy 87.749362 -288.142354) (xy 87.702091 -288.156046) (xy 87.653236 -288.161978)
			(xy 87.604061 -288.159997) (xy 87.555842 -288.150153) (xy 87.509826 -288.132701) (xy 87.467205 -288.108094)
			(xy 87.429084 -288.076969) (xy 87.396449 -288.040132) (xy 87.370146 -287.998536) (xy 87.350855 -287.95326)
			(xy 87.339078 -287.905476) (xy 87.335118 -287.856422) (xy 86.066376 -287.856422) (xy 86.065881 -287.881029)
			(xy 86.057986 -287.929606) (xy 86.042402 -287.976287) (xy 86.019531 -288.019864) (xy 85.989966 -288.059208)
			(xy 85.954473 -288.0933) (xy 85.91397 -288.121256) (xy 85.869508 -288.142354) (xy 85.822237 -288.156046)
			(xy 85.773382 -288.161978) (xy 85.724207 -288.159997) (xy 85.675988 -288.150153) (xy 85.629972 -288.132701)
			(xy 85.587351 -288.108094) (xy 85.54923 -288.076969) (xy 85.516595 -288.040132) (xy 85.490292 -287.998536)
			(xy 85.471001 -287.95326) (xy 85.459224 -287.905476) (xy 85.455264 -287.856422) (xy 85.126322 -287.856422)
			(xy 85.125827 -287.881029) (xy 85.117932 -287.929606) (xy 85.102348 -287.976287) (xy 85.079477 -288.019864)
			(xy 85.049912 -288.059208) (xy 85.014419 -288.0933) (xy 84.973916 -288.121256) (xy 84.929454 -288.142354)
			(xy 84.882183 -288.156046) (xy 84.833328 -288.161978) (xy 84.784153 -288.159997) (xy 84.735934 -288.150153)
			(xy 84.689918 -288.132701) (xy 84.647297 -288.108094) (xy 84.609176 -288.076969) (xy 84.576541 -288.040132)
			(xy 84.550238 -287.998536) (xy 84.530947 -287.95326) (xy 84.51917 -287.905476) (xy 84.51521 -287.856422)
			(xy 84.186268 -287.856422) (xy 84.18582 -287.880413) (xy 84.17831 -287.927803) (xy 84.163479 -287.973436)
			(xy 84.141692 -288.016186) (xy 84.113486 -288.055001) (xy 84.079554 -288.088926) (xy 84.040733 -288.117125)
			(xy 83.997978 -288.138903) (xy 83.952343 -288.153725) (xy 83.904951 -288.161225) (xy 83.88096 -288.16173)
			(xy 83.854569 -288.161179) (xy 83.802572 -288.152119) (xy 83.752904 -288.134259) (xy 83.707045 -288.10813)
			(xy 83.666357 -288.07451) (xy 83.648804 -288.054796) (xy 83.627468 -288.02965) (xy 83.62569 -288.02965)
			(xy 83.621481 -288.029732) (xy 83.613182 -288.031139) (xy 83.60918 -288.032444) (xy 83.521804 -288.07283)
			(xy 83.514027 -288.077364) (xy 83.502051 -288.090787) (xy 83.495479 -288.107533) (xy 83.49488 -288.116518)
			(xy 83.49488 -288.285174) (xy 83.494911 -288.28931) (xy 83.496185 -288.297483) (xy 83.49742 -288.30143)
			(xy 83.502246 -288.31159) (xy 83.515708 -288.332672) (xy 83.519213 -288.33793) (xy 83.528341 -288.346662)
			(xy 83.533742 -288.349944) (xy 83.533996 -288.349944) (xy 83.555754 -288.362526) (xy 83.595197 -288.393673)
			(xy 83.612482 -288.41192) (xy 83.630122 -288.43212) (xy 83.65873 -288.477476) (xy 83.669378 -288.50209)
			(xy 83.672934 -288.508694) (xy 83.673188 -288.509202) (xy 83.686705 -288.533043) (xy 83.705955 -288.584351)
			(xy 83.715758 -288.638267) (xy 83.716368 -288.665666) (xy 83.716368 -288.666174) (xy 84.04531 -288.666174)
			(xy 84.04927 -288.61712) (xy 84.061047 -288.569336) (xy 84.080338 -288.52406) (xy 84.106641 -288.482464)
			(xy 84.139276 -288.445627) (xy 84.177397 -288.414502) (xy 84.220018 -288.389895) (xy 84.266034 -288.372443)
			(xy 84.314253 -288.362599) (xy 84.363428 -288.360618) (xy 84.412283 -288.36655) (xy 84.459554 -288.380242)
			(xy 84.504016 -288.40134) (xy 84.544519 -288.429296) (xy 84.580012 -288.463388) (xy 84.609577 -288.502732)
			(xy 84.632448 -288.546309) (xy 84.648032 -288.59299) (xy 84.655927 -288.641567) (xy 84.656422 -288.666174)
			(xy 84.98511 -288.666174) (xy 84.98907 -288.61712) (xy 85.000847 -288.569336) (xy 85.020138 -288.52406)
			(xy 85.046441 -288.482464) (xy 85.079076 -288.445627) (xy 85.117197 -288.414502) (xy 85.159818 -288.389895)
			(xy 85.205834 -288.372443) (xy 85.254053 -288.362599) (xy 85.303228 -288.360618) (xy 85.352083 -288.36655)
			(xy 85.399354 -288.380242) (xy 85.443816 -288.40134) (xy 85.484319 -288.429296) (xy 85.519812 -288.463388)
			(xy 85.549377 -288.502732) (xy 85.572248 -288.546309) (xy 85.587832 -288.59299) (xy 85.595727 -288.641567)
			(xy 85.596222 -288.666174) (xy 85.925164 -288.666174) (xy 85.929124 -288.61712) (xy 85.940901 -288.569336)
			(xy 85.960192 -288.52406) (xy 85.986495 -288.482464) (xy 86.01913 -288.445627) (xy 86.057251 -288.414502)
			(xy 86.099872 -288.389895) (xy 86.145888 -288.372443) (xy 86.194107 -288.362599) (xy 86.243282 -288.360618)
			(xy 86.292137 -288.36655) (xy 86.339408 -288.380242) (xy 86.38387 -288.40134) (xy 86.424373 -288.429296)
			(xy 86.459866 -288.463388) (xy 86.489431 -288.502732) (xy 86.512302 -288.546309) (xy 86.527886 -288.59299)
			(xy 86.535781 -288.641567) (xy 86.536276 -288.666174) (xy 86.865218 -288.666174) (xy 86.869178 -288.61712)
			(xy 86.880955 -288.569336) (xy 86.900246 -288.52406) (xy 86.926549 -288.482464) (xy 86.959184 -288.445627)
			(xy 86.997305 -288.414502) (xy 87.039926 -288.389895) (xy 87.085942 -288.372443) (xy 87.134161 -288.362599)
			(xy 87.183336 -288.360618) (xy 87.232191 -288.36655) (xy 87.279462 -288.380242) (xy 87.323924 -288.40134)
			(xy 87.364427 -288.429296) (xy 87.39992 -288.463388) (xy 87.429485 -288.502732) (xy 87.452356 -288.546309)
			(xy 87.46794 -288.59299) (xy 87.475835 -288.641567) (xy 87.47633 -288.666174) (xy 87.805272 -288.666174)
			(xy 87.809232 -288.61712) (xy 87.821009 -288.569336) (xy 87.8403 -288.52406) (xy 87.866603 -288.482464)
			(xy 87.899238 -288.445627) (xy 87.937359 -288.414502) (xy 87.97998 -288.389895) (xy 88.025996 -288.372443)
			(xy 88.074215 -288.362599) (xy 88.12339 -288.360618) (xy 88.172245 -288.36655) (xy 88.219516 -288.380242)
			(xy 88.263978 -288.40134) (xy 88.304481 -288.429296) (xy 88.339974 -288.463388) (xy 88.369539 -288.502732)
			(xy 88.39241 -288.546309) (xy 88.407994 -288.59299) (xy 88.415889 -288.641567) (xy 88.416384 -288.666174)
			(xy 88.745326 -288.666174) (xy 88.749286 -288.61712) (xy 88.761063 -288.569336) (xy 88.780354 -288.52406)
			(xy 88.806657 -288.482464) (xy 88.839292 -288.445627) (xy 88.877413 -288.414502) (xy 88.920034 -288.389895)
			(xy 88.96605 -288.372443) (xy 89.014269 -288.362599) (xy 89.063444 -288.360618) (xy 89.112299 -288.36655)
			(xy 89.15957 -288.380242) (xy 89.204032 -288.40134) (xy 89.244535 -288.429296) (xy 89.280028 -288.463388)
			(xy 89.309593 -288.502732) (xy 89.332464 -288.546309) (xy 89.348048 -288.59299) (xy 89.355943 -288.641567)
			(xy 89.356438 -288.666174) (xy 89.685126 -288.666174) (xy 89.689086 -288.61712) (xy 89.700863 -288.569336)
			(xy 89.720154 -288.52406) (xy 89.746457 -288.482464) (xy 89.779092 -288.445627) (xy 89.817213 -288.414502)
			(xy 89.859834 -288.389895) (xy 89.90585 -288.372443) (xy 89.954069 -288.362599) (xy 90.003244 -288.360618)
			(xy 90.052099 -288.36655) (xy 90.09937 -288.380242) (xy 90.143832 -288.40134) (xy 90.184335 -288.429296)
			(xy 90.219828 -288.463388) (xy 90.249393 -288.502732) (xy 90.272264 -288.546309) (xy 90.287848 -288.59299)
			(xy 90.295743 -288.641567) (xy 90.296238 -288.666174) (xy 90.614749 -288.666174) (xy 90.618844 -288.615446)
			(xy 90.631023 -288.566032) (xy 90.650971 -288.519212) (xy 90.678172 -288.476198) (xy 90.71192 -288.438104)
			(xy 90.751342 -288.405917) (xy 90.795416 -288.380471) (xy 90.843002 -288.362424) (xy 90.892866 -288.352244)
			(xy 90.943718 -288.350195) (xy 90.994239 -288.356329) (xy 91.043123 -288.370489) (xy 91.089102 -288.392306)
			(xy 91.130986 -288.421216) (xy 91.16769 -288.456471) (xy 91.198263 -288.497157) (xy 91.221914 -288.54222)
			(xy 91.23803 -288.590494) (xy 91.246194 -288.640728) (xy 91.246706 -288.666174) (xy 91.565234 -288.666174)
			(xy 91.569194 -288.61712) (xy 91.580971 -288.569336) (xy 91.600262 -288.52406) (xy 91.626565 -288.482464)
			(xy 91.6592 -288.445627) (xy 91.697321 -288.414502) (xy 91.739942 -288.389895) (xy 91.785958 -288.372443)
			(xy 91.834177 -288.362599) (xy 91.883352 -288.360618) (xy 91.932207 -288.36655) (xy 91.979478 -288.380242)
			(xy 92.02394 -288.40134) (xy 92.064443 -288.429296) (xy 92.099936 -288.463388) (xy 92.129501 -288.502732)
			(xy 92.152372 -288.546309) (xy 92.167956 -288.59299) (xy 92.175851 -288.641567) (xy 92.176346 -288.666174)
			(xy 92.494857 -288.666174) (xy 92.498952 -288.615446) (xy 92.511131 -288.566032) (xy 92.531079 -288.519212)
			(xy 92.55828 -288.476198) (xy 92.592028 -288.438104) (xy 92.63145 -288.405917) (xy 92.675524 -288.380471)
			(xy 92.72311 -288.362424) (xy 92.772974 -288.352244) (xy 92.823826 -288.350195) (xy 92.874347 -288.356329)
			(xy 92.923231 -288.370489) (xy 92.96921 -288.392306) (xy 93.011094 -288.421216) (xy 93.047798 -288.456471)
			(xy 93.078371 -288.497157) (xy 93.102022 -288.54222) (xy 93.118138 -288.590494) (xy 93.126302 -288.640728)
			(xy 93.126814 -288.666174) (xy 93.445342 -288.666174) (xy 93.449302 -288.61712) (xy 93.461079 -288.569336)
			(xy 93.48037 -288.52406) (xy 93.506673 -288.482464) (xy 93.539308 -288.445627) (xy 93.577429 -288.414502)
			(xy 93.62005 -288.389895) (xy 93.666066 -288.372443) (xy 93.714285 -288.362599) (xy 93.76346 -288.360618)
			(xy 93.812315 -288.36655) (xy 93.859586 -288.380242) (xy 93.904048 -288.40134) (xy 93.944551 -288.429296)
			(xy 93.980044 -288.463388) (xy 94.009609 -288.502732) (xy 94.03248 -288.546309) (xy 94.048064 -288.59299)
			(xy 94.055959 -288.641567) (xy 94.056454 -288.666174) (xy 94.374711 -288.666174) (xy 94.378806 -288.615446)
			(xy 94.390985 -288.566032) (xy 94.410933 -288.519212) (xy 94.438134 -288.476198) (xy 94.471882 -288.438104)
			(xy 94.511304 -288.405917) (xy 94.555378 -288.380471) (xy 94.602964 -288.362424) (xy 94.652828 -288.352244)
			(xy 94.70368 -288.350195) (xy 94.754201 -288.356329) (xy 94.803085 -288.370489) (xy 94.849064 -288.392306)
			(xy 94.890948 -288.421216) (xy 94.927652 -288.456471) (xy 94.958225 -288.497157) (xy 94.981876 -288.54222)
			(xy 94.997992 -288.590494) (xy 95.006156 -288.640728) (xy 95.006668 -288.666174) (xy 95.314765 -288.666174)
			(xy 95.31886 -288.615446) (xy 95.331039 -288.566032) (xy 95.350987 -288.519212) (xy 95.378188 -288.476198)
			(xy 95.411936 -288.438104) (xy 95.451358 -288.405917) (xy 95.495432 -288.380471) (xy 95.543018 -288.362424)
			(xy 95.592882 -288.352244) (xy 95.643734 -288.350195) (xy 95.694255 -288.356329) (xy 95.743139 -288.370489)
			(xy 95.789118 -288.392306) (xy 95.831002 -288.421216) (xy 95.867706 -288.456471) (xy 95.898279 -288.497157)
			(xy 95.92193 -288.54222) (xy 95.938046 -288.590494) (xy 95.94621 -288.640728) (xy 95.946722 -288.666174)
			(xy 95.94621 -288.69162) (xy 95.938046 -288.741854) (xy 95.92193 -288.790128) (xy 95.898279 -288.835191)
			(xy 95.867706 -288.875877) (xy 95.831002 -288.911132) (xy 95.789118 -288.940042) (xy 95.743139 -288.961859)
			(xy 95.694255 -288.976019) (xy 95.643734 -288.982153) (xy 95.592882 -288.980104) (xy 95.543018 -288.969924)
			(xy 95.495432 -288.951877) (xy 95.451358 -288.926431) (xy 95.411936 -288.894244) (xy 95.378188 -288.85615)
			(xy 95.350987 -288.813136) (xy 95.331039 -288.766316) (xy 95.31886 -288.716902) (xy 95.314765 -288.666174)
			(xy 95.006668 -288.666174) (xy 95.006156 -288.69162) (xy 94.997992 -288.741854) (xy 94.981876 -288.790128)
			(xy 94.958225 -288.835191) (xy 94.927652 -288.875877) (xy 94.890948 -288.911132) (xy 94.849064 -288.940042)
			(xy 94.803085 -288.961859) (xy 94.754201 -288.976019) (xy 94.70368 -288.982153) (xy 94.652828 -288.980104)
			(xy 94.602964 -288.969924) (xy 94.555378 -288.951877) (xy 94.511304 -288.926431) (xy 94.471882 -288.894244)
			(xy 94.438134 -288.85615) (xy 94.410933 -288.813136) (xy 94.390985 -288.766316) (xy 94.378806 -288.716902)
			(xy 94.374711 -288.666174) (xy 94.056454 -288.666174) (xy 94.055959 -288.690781) (xy 94.048064 -288.739358)
			(xy 94.03248 -288.786039) (xy 94.009609 -288.829616) (xy 93.980044 -288.86896) (xy 93.944551 -288.903052)
			(xy 93.904048 -288.931008) (xy 93.859586 -288.952106) (xy 93.812315 -288.965798) (xy 93.76346 -288.97173)
			(xy 93.714285 -288.969749) (xy 93.666066 -288.959905) (xy 93.62005 -288.942453) (xy 93.577429 -288.917846)
			(xy 93.539308 -288.886721) (xy 93.506673 -288.849884) (xy 93.48037 -288.808288) (xy 93.461079 -288.763012)
			(xy 93.449302 -288.715228) (xy 93.445342 -288.666174) (xy 93.126814 -288.666174) (xy 93.126302 -288.69162)
			(xy 93.118138 -288.741854) (xy 93.102022 -288.790128) (xy 93.078371 -288.835191) (xy 93.047798 -288.875877)
			(xy 93.011094 -288.911132) (xy 92.96921 -288.940042) (xy 92.923231 -288.961859) (xy 92.874347 -288.976019)
			(xy 92.823826 -288.982153) (xy 92.772974 -288.980104) (xy 92.72311 -288.969924) (xy 92.675524 -288.951877)
			(xy 92.63145 -288.926431) (xy 92.592028 -288.894244) (xy 92.55828 -288.85615) (xy 92.531079 -288.813136)
			(xy 92.511131 -288.766316) (xy 92.498952 -288.716902) (xy 92.494857 -288.666174) (xy 92.176346 -288.666174)
			(xy 92.175851 -288.690781) (xy 92.167956 -288.739358) (xy 92.152372 -288.786039) (xy 92.129501 -288.829616)
			(xy 92.099936 -288.86896) (xy 92.064443 -288.903052) (xy 92.02394 -288.931008) (xy 91.979478 -288.952106)
			(xy 91.932207 -288.965798) (xy 91.883352 -288.97173) (xy 91.834177 -288.969749) (xy 91.785958 -288.959905)
			(xy 91.739942 -288.942453) (xy 91.697321 -288.917846) (xy 91.6592 -288.886721) (xy 91.626565 -288.849884)
			(xy 91.600262 -288.808288) (xy 91.580971 -288.763012) (xy 91.569194 -288.715228) (xy 91.565234 -288.666174)
			(xy 91.246706 -288.666174) (xy 91.246194 -288.69162) (xy 91.23803 -288.741854) (xy 91.221914 -288.790128)
			(xy 91.198263 -288.835191) (xy 91.16769 -288.875877) (xy 91.130986 -288.911132) (xy 91.089102 -288.940042)
			(xy 91.043123 -288.961859) (xy 90.994239 -288.976019) (xy 90.943718 -288.982153) (xy 90.892866 -288.980104)
			(xy 90.843002 -288.969924) (xy 90.795416 -288.951877) (xy 90.751342 -288.926431) (xy 90.71192 -288.894244)
			(xy 90.678172 -288.85615) (xy 90.650971 -288.813136) (xy 90.631023 -288.766316) (xy 90.618844 -288.716902)
			(xy 90.614749 -288.666174) (xy 90.296238 -288.666174) (xy 90.295743 -288.690781) (xy 90.287848 -288.739358)
			(xy 90.272264 -288.786039) (xy 90.249393 -288.829616) (xy 90.219828 -288.86896) (xy 90.184335 -288.903052)
			(xy 90.143832 -288.931008) (xy 90.09937 -288.952106) (xy 90.052099 -288.965798) (xy 90.003244 -288.97173)
			(xy 89.954069 -288.969749) (xy 89.90585 -288.959905) (xy 89.859834 -288.942453) (xy 89.817213 -288.917846)
			(xy 89.779092 -288.886721) (xy 89.746457 -288.849884) (xy 89.720154 -288.808288) (xy 89.700863 -288.763012)
			(xy 89.689086 -288.715228) (xy 89.685126 -288.666174) (xy 89.356438 -288.666174) (xy 89.355943 -288.690781)
			(xy 89.348048 -288.739358) (xy 89.332464 -288.786039) (xy 89.309593 -288.829616) (xy 89.280028 -288.86896)
			(xy 89.244535 -288.903052) (xy 89.204032 -288.931008) (xy 89.15957 -288.952106) (xy 89.112299 -288.965798)
			(xy 89.063444 -288.97173) (xy 89.014269 -288.969749) (xy 88.96605 -288.959905) (xy 88.920034 -288.942453)
			(xy 88.877413 -288.917846) (xy 88.839292 -288.886721) (xy 88.806657 -288.849884) (xy 88.780354 -288.808288)
			(xy 88.761063 -288.763012) (xy 88.749286 -288.715228) (xy 88.745326 -288.666174) (xy 88.416384 -288.666174)
			(xy 88.415889 -288.690781) (xy 88.407994 -288.739358) (xy 88.39241 -288.786039) (xy 88.369539 -288.829616)
			(xy 88.339974 -288.86896) (xy 88.304481 -288.903052) (xy 88.263978 -288.931008) (xy 88.219516 -288.952106)
			(xy 88.172245 -288.965798) (xy 88.12339 -288.97173) (xy 88.074215 -288.969749) (xy 88.025996 -288.959905)
			(xy 87.97998 -288.942453) (xy 87.937359 -288.917846) (xy 87.899238 -288.886721) (xy 87.866603 -288.849884)
			(xy 87.8403 -288.808288) (xy 87.821009 -288.763012) (xy 87.809232 -288.715228) (xy 87.805272 -288.666174)
			(xy 87.47633 -288.666174) (xy 87.475835 -288.690781) (xy 87.46794 -288.739358) (xy 87.452356 -288.786039)
			(xy 87.429485 -288.829616) (xy 87.39992 -288.86896) (xy 87.364427 -288.903052) (xy 87.323924 -288.931008)
			(xy 87.279462 -288.952106) (xy 87.232191 -288.965798) (xy 87.183336 -288.97173) (xy 87.134161 -288.969749)
			(xy 87.085942 -288.959905) (xy 87.039926 -288.942453) (xy 86.997305 -288.917846) (xy 86.959184 -288.886721)
			(xy 86.926549 -288.849884) (xy 86.900246 -288.808288) (xy 86.880955 -288.763012) (xy 86.869178 -288.715228)
			(xy 86.865218 -288.666174) (xy 86.536276 -288.666174) (xy 86.535781 -288.690781) (xy 86.527886 -288.739358)
			(xy 86.512302 -288.786039) (xy 86.489431 -288.829616) (xy 86.459866 -288.86896) (xy 86.424373 -288.903052)
			(xy 86.38387 -288.931008) (xy 86.339408 -288.952106) (xy 86.292137 -288.965798) (xy 86.243282 -288.97173)
			(xy 86.194107 -288.969749) (xy 86.145888 -288.959905) (xy 86.099872 -288.942453) (xy 86.057251 -288.917846)
			(xy 86.01913 -288.886721) (xy 85.986495 -288.849884) (xy 85.960192 -288.808288) (xy 85.940901 -288.763012)
			(xy 85.929124 -288.715228) (xy 85.925164 -288.666174) (xy 85.596222 -288.666174) (xy 85.595727 -288.690781)
			(xy 85.587832 -288.739358) (xy 85.572248 -288.786039) (xy 85.549377 -288.829616) (xy 85.519812 -288.86896)
			(xy 85.484319 -288.903052) (xy 85.443816 -288.931008) (xy 85.399354 -288.952106) (xy 85.352083 -288.965798)
			(xy 85.303228 -288.97173) (xy 85.254053 -288.969749) (xy 85.205834 -288.959905) (xy 85.159818 -288.942453)
			(xy 85.117197 -288.917846) (xy 85.079076 -288.886721) (xy 85.046441 -288.849884) (xy 85.020138 -288.808288)
			(xy 85.000847 -288.763012) (xy 84.98907 -288.715228) (xy 84.98511 -288.666174) (xy 84.656422 -288.666174)
			(xy 84.655927 -288.690781) (xy 84.648032 -288.739358) (xy 84.632448 -288.786039) (xy 84.609577 -288.829616)
			(xy 84.580012 -288.86896) (xy 84.544519 -288.903052) (xy 84.504016 -288.931008) (xy 84.459554 -288.952106)
			(xy 84.412283 -288.965798) (xy 84.363428 -288.97173) (xy 84.314253 -288.969749) (xy 84.266034 -288.959905)
			(xy 84.220018 -288.942453) (xy 84.177397 -288.917846) (xy 84.139276 -288.886721) (xy 84.106641 -288.849884)
			(xy 84.080338 -288.808288) (xy 84.061047 -288.763012) (xy 84.04927 -288.715228) (xy 84.04531 -288.666174)
			(xy 83.716368 -288.666174) (xy 83.716368 -288.672016) (xy 83.715348 -288.697706) (xy 83.705771 -288.748215)
			(xy 83.687868 -288.796405) (xy 83.662144 -288.840915) (xy 83.629328 -288.880487) (xy 83.590345 -288.914002)
			(xy 83.546299 -288.940512) (xy 83.522566 -288.9504) (xy 83.512152 -288.954718) (xy 83.503516 -288.967418)
			(xy 83.499477 -288.973822) (xy 83.495067 -288.988298) (xy 83.49488 -288.995866) (xy 83.49488 -289.118294)
			(xy 83.495136 -289.123904) (xy 83.497821 -289.134804) (xy 83.500214 -289.139884) (xy 83.504786 -289.147758)
			(xy 83.508737 -289.152612) (xy 83.518496 -289.160444) (xy 83.52409 -289.163252) (xy 83.524344 -289.163506)
			(xy 83.605116 -289.200844) (xy 83.618832 -289.204146) (xy 83.631278 -289.204654) (xy 83.648042 -289.198304)
			(xy 83.6549 -289.195002) (xy 83.665314 -289.18916) (xy 83.6676 -289.187382) (xy 83.668616 -289.18662)
			(xy 83.66887 -289.186366) (xy 83.689157 -289.171291) (xy 83.733638 -289.147299) (xy 83.781454 -289.130933)
			(xy 83.831307 -289.122635) (xy 83.856576 -289.122104) (xy 83.882414 -289.122652) (xy 83.933351 -289.131365)
			(xy 83.982094 -289.148529) (xy 84.027251 -289.173654) (xy 84.067534 -289.206023) (xy 84.101792 -289.244713)
			(xy 84.129048 -289.288617) (xy 84.139278 -289.31235) (xy 84.142834 -289.318954) (xy 84.143088 -289.319462)
			(xy 84.156619 -289.343343) (xy 84.175874 -289.394735) (xy 84.185652 -289.448739) (xy 84.186268 -289.47618)
			(xy 84.51521 -289.47618) (xy 84.51917 -289.427126) (xy 84.530947 -289.379342) (xy 84.550238 -289.334066)
			(xy 84.576541 -289.29247) (xy 84.609176 -289.255633) (xy 84.647297 -289.224508) (xy 84.689918 -289.199901)
			(xy 84.735934 -289.182449) (xy 84.784153 -289.172605) (xy 84.833328 -289.170624) (xy 84.882183 -289.176556)
			(xy 84.929454 -289.190248) (xy 84.973916 -289.211346) (xy 85.014419 -289.239302) (xy 85.049912 -289.273394)
			(xy 85.079477 -289.312738) (xy 85.102348 -289.356315) (xy 85.117932 -289.402996) (xy 85.125827 -289.451573)
			(xy 85.126322 -289.47618) (xy 85.455264 -289.47618) (xy 85.459224 -289.427126) (xy 85.471001 -289.379342)
			(xy 85.490292 -289.334066) (xy 85.516595 -289.29247) (xy 85.54923 -289.255633) (xy 85.587351 -289.224508)
			(xy 85.629972 -289.199901) (xy 85.675988 -289.182449) (xy 85.724207 -289.172605) (xy 85.773382 -289.170624)
			(xy 85.822237 -289.176556) (xy 85.869508 -289.190248) (xy 85.91397 -289.211346) (xy 85.954473 -289.239302)
			(xy 85.989966 -289.273394) (xy 86.019531 -289.312738) (xy 86.042402 -289.356315) (xy 86.057986 -289.402996)
			(xy 86.065881 -289.451573) (xy 86.066376 -289.47618) (xy 86.395318 -289.47618) (xy 86.399278 -289.427126)
			(xy 86.411055 -289.379342) (xy 86.430346 -289.334066) (xy 86.456649 -289.29247) (xy 86.489284 -289.255633)
			(xy 86.527405 -289.224508) (xy 86.570026 -289.199901) (xy 86.616042 -289.182449) (xy 86.664261 -289.172605)
			(xy 86.713436 -289.170624) (xy 86.762291 -289.176556) (xy 86.809562 -289.190248) (xy 86.854024 -289.211346)
			(xy 86.894527 -289.239302) (xy 86.93002 -289.273394) (xy 86.959585 -289.312738) (xy 86.982456 -289.356315)
			(xy 86.99804 -289.402996) (xy 87.005935 -289.451573) (xy 87.00643 -289.47618) (xy 87.335118 -289.47618)
			(xy 87.339078 -289.427126) (xy 87.350855 -289.379342) (xy 87.370146 -289.334066) (xy 87.396449 -289.29247)
			(xy 87.429084 -289.255633) (xy 87.467205 -289.224508) (xy 87.509826 -289.199901) (xy 87.555842 -289.182449)
			(xy 87.604061 -289.172605) (xy 87.653236 -289.170624) (xy 87.702091 -289.176556) (xy 87.749362 -289.190248)
			(xy 87.793824 -289.211346) (xy 87.834327 -289.239302) (xy 87.86982 -289.273394) (xy 87.899385 -289.312738)
			(xy 87.922256 -289.356315) (xy 87.93784 -289.402996) (xy 87.945735 -289.451573) (xy 87.94623 -289.47618)
			(xy 88.275172 -289.47618) (xy 88.279132 -289.427126) (xy 88.290909 -289.379342) (xy 88.3102 -289.334066)
			(xy 88.336503 -289.29247) (xy 88.369138 -289.255633) (xy 88.407259 -289.224508) (xy 88.44988 -289.199901)
			(xy 88.495896 -289.182449) (xy 88.544115 -289.172605) (xy 88.59329 -289.170624) (xy 88.642145 -289.176556)
			(xy 88.689416 -289.190248) (xy 88.733878 -289.211346) (xy 88.774381 -289.239302) (xy 88.809874 -289.273394)
			(xy 88.839439 -289.312738) (xy 88.86231 -289.356315) (xy 88.877894 -289.402996) (xy 88.885789 -289.451573)
			(xy 88.886284 -289.47618) (xy 89.215226 -289.47618) (xy 89.219186 -289.427126) (xy 89.230963 -289.379342)
			(xy 89.250254 -289.334066) (xy 89.276557 -289.29247) (xy 89.309192 -289.255633) (xy 89.347313 -289.224508)
			(xy 89.389934 -289.199901) (xy 89.43595 -289.182449) (xy 89.484169 -289.172605) (xy 89.533344 -289.170624)
			(xy 89.582199 -289.176556) (xy 89.62947 -289.190248) (xy 89.673932 -289.211346) (xy 89.714435 -289.239302)
			(xy 89.749928 -289.273394) (xy 89.779493 -289.312738) (xy 89.802364 -289.356315) (xy 89.817948 -289.402996)
			(xy 89.825843 -289.451573) (xy 89.826338 -289.47618) (xy 90.15528 -289.47618) (xy 90.15924 -289.427126)
			(xy 90.171017 -289.379342) (xy 90.190308 -289.334066) (xy 90.216611 -289.29247) (xy 90.249246 -289.255633)
			(xy 90.287367 -289.224508) (xy 90.329988 -289.199901) (xy 90.376004 -289.182449) (xy 90.424223 -289.172605)
			(xy 90.473398 -289.170624) (xy 90.522253 -289.176556) (xy 90.569524 -289.190248) (xy 90.613986 -289.211346)
			(xy 90.654489 -289.239302) (xy 90.689982 -289.273394) (xy 90.719547 -289.312738) (xy 90.742418 -289.356315)
			(xy 90.758002 -289.402996) (xy 90.765897 -289.451573) (xy 90.766392 -289.47618) (xy 91.084903 -289.47618)
			(xy 91.088998 -289.425452) (xy 91.101177 -289.376038) (xy 91.121125 -289.329218) (xy 91.148326 -289.286204)
			(xy 91.182074 -289.24811) (xy 91.221496 -289.215923) (xy 91.26557 -289.190477) (xy 91.313156 -289.17243)
			(xy 91.36302 -289.16225) (xy 91.413872 -289.160201) (xy 91.464393 -289.166335) (xy 91.513277 -289.180495)
			(xy 91.559256 -289.202312) (xy 91.60114 -289.231222) (xy 91.637844 -289.266477) (xy 91.668417 -289.307163)
			(xy 91.692068 -289.352226) (xy 91.708184 -289.4005) (xy 91.716348 -289.450734) (xy 91.71686 -289.47618)
			(xy 92.024703 -289.47618) (xy 92.028798 -289.425452) (xy 92.040977 -289.376038) (xy 92.060925 -289.329218)
			(xy 92.088126 -289.286204) (xy 92.121874 -289.24811) (xy 92.161296 -289.215923) (xy 92.20537 -289.190477)
			(xy 92.252956 -289.17243) (xy 92.30282 -289.16225) (xy 92.353672 -289.160201) (xy 92.404193 -289.166335)
			(xy 92.453077 -289.180495) (xy 92.499056 -289.202312) (xy 92.54094 -289.231222) (xy 92.577644 -289.266477)
			(xy 92.608217 -289.307163) (xy 92.631868 -289.352226) (xy 92.647984 -289.4005) (xy 92.656148 -289.450734)
			(xy 92.65666 -289.47618) (xy 92.975188 -289.47618) (xy 92.979148 -289.427126) (xy 92.990925 -289.379342)
			(xy 93.010216 -289.334066) (xy 93.036519 -289.29247) (xy 93.069154 -289.255633) (xy 93.107275 -289.224508)
			(xy 93.149896 -289.199901) (xy 93.195912 -289.182449) (xy 93.244131 -289.172605) (xy 93.293306 -289.170624)
			(xy 93.342161 -289.176556) (xy 93.389432 -289.190248) (xy 93.433894 -289.211346) (xy 93.474397 -289.239302)
			(xy 93.50989 -289.273394) (xy 93.539455 -289.312738) (xy 93.562326 -289.356315) (xy 93.57791 -289.402996)
			(xy 93.585805 -289.451573) (xy 93.5863 -289.47618) (xy 93.904811 -289.47618) (xy 93.908906 -289.425452)
			(xy 93.921085 -289.376038) (xy 93.941033 -289.329218) (xy 93.968234 -289.286204) (xy 94.001982 -289.24811)
			(xy 94.041404 -289.215923) (xy 94.085478 -289.190477) (xy 94.133064 -289.17243) (xy 94.182928 -289.16225)
			(xy 94.23378 -289.160201) (xy 94.284301 -289.166335) (xy 94.333185 -289.180495) (xy 94.379164 -289.202312)
			(xy 94.421048 -289.231222) (xy 94.457752 -289.266477) (xy 94.488325 -289.307163) (xy 94.511976 -289.352226)
			(xy 94.528092 -289.4005) (xy 94.536256 -289.450734) (xy 94.536768 -289.47618) (xy 94.855296 -289.47618)
			(xy 94.859256 -289.427126) (xy 94.871033 -289.379342) (xy 94.890324 -289.334066) (xy 94.916627 -289.29247)
			(xy 94.949262 -289.255633) (xy 94.987383 -289.224508) (xy 95.030004 -289.199901) (xy 95.07602 -289.182449)
			(xy 95.124239 -289.172605) (xy 95.173414 -289.170624) (xy 95.222269 -289.176556) (xy 95.26954 -289.190248)
			(xy 95.314002 -289.211346) (xy 95.354505 -289.239302) (xy 95.389998 -289.273394) (xy 95.419563 -289.312738)
			(xy 95.442434 -289.356315) (xy 95.458018 -289.402996) (xy 95.465913 -289.451573) (xy 95.466408 -289.47618)
			(xy 95.784919 -289.47618) (xy 95.789014 -289.425452) (xy 95.801193 -289.376038) (xy 95.821141 -289.329218)
			(xy 95.848342 -289.286204) (xy 95.88209 -289.24811) (xy 95.921512 -289.215923) (xy 95.965586 -289.190477)
			(xy 96.013172 -289.17243) (xy 96.063036 -289.16225) (xy 96.113888 -289.160201) (xy 96.164409 -289.166335)
			(xy 96.213293 -289.180495) (xy 96.259272 -289.202312) (xy 96.301156 -289.231222) (xy 96.33786 -289.266477)
			(xy 96.368433 -289.307163) (xy 96.392084 -289.352226) (xy 96.4082 -289.4005) (xy 96.416364 -289.450734)
			(xy 96.416876 -289.47618) (xy 96.416364 -289.501626) (xy 96.4082 -289.55186) (xy 96.392084 -289.600134)
			(xy 96.368433 -289.645197) (xy 96.33786 -289.685883) (xy 96.301156 -289.721138) (xy 96.259272 -289.750048)
			(xy 96.213293 -289.771865) (xy 96.164409 -289.786025) (xy 96.113888 -289.792159) (xy 96.063036 -289.79011)
			(xy 96.013172 -289.77993) (xy 95.965586 -289.761883) (xy 95.921512 -289.736437) (xy 95.88209 -289.70425)
			(xy 95.848342 -289.666156) (xy 95.821141 -289.623142) (xy 95.801193 -289.576322) (xy 95.789014 -289.526908)
			(xy 95.784919 -289.47618) (xy 95.466408 -289.47618) (xy 95.465913 -289.500787) (xy 95.458018 -289.549364)
			(xy 95.442434 -289.596045) (xy 95.419563 -289.639622) (xy 95.389998 -289.678966) (xy 95.354505 -289.713058)
			(xy 95.314002 -289.741014) (xy 95.26954 -289.762112) (xy 95.222269 -289.775804) (xy 95.173414 -289.781736)
			(xy 95.124239 -289.779755) (xy 95.07602 -289.769911) (xy 95.030004 -289.752459) (xy 94.987383 -289.727852)
			(xy 94.949262 -289.696727) (xy 94.916627 -289.65989) (xy 94.890324 -289.618294) (xy 94.871033 -289.573018)
			(xy 94.859256 -289.525234) (xy 94.855296 -289.47618) (xy 94.536768 -289.47618) (xy 94.536256 -289.501626)
			(xy 94.528092 -289.55186) (xy 94.511976 -289.600134) (xy 94.488325 -289.645197) (xy 94.457752 -289.685883)
			(xy 94.421048 -289.721138) (xy 94.379164 -289.750048) (xy 94.333185 -289.771865) (xy 94.284301 -289.786025)
			(xy 94.23378 -289.792159) (xy 94.182928 -289.79011) (xy 94.133064 -289.77993) (xy 94.085478 -289.761883)
			(xy 94.041404 -289.736437) (xy 94.001982 -289.70425) (xy 93.968234 -289.666156) (xy 93.941033 -289.623142)
			(xy 93.921085 -289.576322) (xy 93.908906 -289.526908) (xy 93.904811 -289.47618) (xy 93.5863 -289.47618)
			(xy 93.585805 -289.500787) (xy 93.57791 -289.549364) (xy 93.562326 -289.596045) (xy 93.539455 -289.639622)
			(xy 93.50989 -289.678966) (xy 93.474397 -289.713058) (xy 93.433894 -289.741014) (xy 93.389432 -289.762112)
			(xy 93.342161 -289.775804) (xy 93.293306 -289.781736) (xy 93.244131 -289.779755) (xy 93.195912 -289.769911)
			(xy 93.149896 -289.752459) (xy 93.107275 -289.727852) (xy 93.069154 -289.696727) (xy 93.036519 -289.65989)
			(xy 93.010216 -289.618294) (xy 92.990925 -289.573018) (xy 92.979148 -289.525234) (xy 92.975188 -289.47618)
			(xy 92.65666 -289.47618) (xy 92.656148 -289.501626) (xy 92.647984 -289.55186) (xy 92.631868 -289.600134)
			(xy 92.608217 -289.645197) (xy 92.577644 -289.685883) (xy 92.54094 -289.721138) (xy 92.499056 -289.750048)
			(xy 92.453077 -289.771865) (xy 92.404193 -289.786025) (xy 92.353672 -289.792159) (xy 92.30282 -289.79011)
			(xy 92.252956 -289.77993) (xy 92.20537 -289.761883) (xy 92.161296 -289.736437) (xy 92.121874 -289.70425)
			(xy 92.088126 -289.666156) (xy 92.060925 -289.623142) (xy 92.040977 -289.576322) (xy 92.028798 -289.526908)
			(xy 92.024703 -289.47618) (xy 91.71686 -289.47618) (xy 91.716348 -289.501626) (xy 91.708184 -289.55186)
			(xy 91.692068 -289.600134) (xy 91.668417 -289.645197) (xy 91.637844 -289.685883) (xy 91.60114 -289.721138)
			(xy 91.559256 -289.750048) (xy 91.513277 -289.771865) (xy 91.464393 -289.786025) (xy 91.413872 -289.792159)
			(xy 91.36302 -289.79011) (xy 91.313156 -289.77993) (xy 91.26557 -289.761883) (xy 91.221496 -289.736437)
			(xy 91.182074 -289.70425) (xy 91.148326 -289.666156) (xy 91.121125 -289.623142) (xy 91.101177 -289.576322)
			(xy 91.088998 -289.526908) (xy 91.084903 -289.47618) (xy 90.766392 -289.47618) (xy 90.765897 -289.500787)
			(xy 90.758002 -289.549364) (xy 90.742418 -289.596045) (xy 90.719547 -289.639622) (xy 90.689982 -289.678966)
			(xy 90.654489 -289.713058) (xy 90.613986 -289.741014) (xy 90.569524 -289.762112) (xy 90.522253 -289.775804)
			(xy 90.473398 -289.781736) (xy 90.424223 -289.779755) (xy 90.376004 -289.769911) (xy 90.329988 -289.752459)
			(xy 90.287367 -289.727852) (xy 90.249246 -289.696727) (xy 90.216611 -289.65989) (xy 90.190308 -289.618294)
			(xy 90.171017 -289.573018) (xy 90.15924 -289.525234) (xy 90.15528 -289.47618) (xy 89.826338 -289.47618)
			(xy 89.825843 -289.500787) (xy 89.817948 -289.549364) (xy 89.802364 -289.596045) (xy 89.779493 -289.639622)
			(xy 89.749928 -289.678966) (xy 89.714435 -289.713058) (xy 89.673932 -289.741014) (xy 89.62947 -289.762112)
			(xy 89.582199 -289.775804) (xy 89.533344 -289.781736) (xy 89.484169 -289.779755) (xy 89.43595 -289.769911)
			(xy 89.389934 -289.752459) (xy 89.347313 -289.727852) (xy 89.309192 -289.696727) (xy 89.276557 -289.65989)
			(xy 89.250254 -289.618294) (xy 89.230963 -289.573018) (xy 89.219186 -289.525234) (xy 89.215226 -289.47618)
			(xy 88.886284 -289.47618) (xy 88.885789 -289.500787) (xy 88.877894 -289.549364) (xy 88.86231 -289.596045)
			(xy 88.839439 -289.639622) (xy 88.809874 -289.678966) (xy 88.774381 -289.713058) (xy 88.733878 -289.741014)
			(xy 88.689416 -289.762112) (xy 88.642145 -289.775804) (xy 88.59329 -289.781736) (xy 88.544115 -289.779755)
			(xy 88.495896 -289.769911) (xy 88.44988 -289.752459) (xy 88.407259 -289.727852) (xy 88.369138 -289.696727)
			(xy 88.336503 -289.65989) (xy 88.3102 -289.618294) (xy 88.290909 -289.573018) (xy 88.279132 -289.525234)
			(xy 88.275172 -289.47618) (xy 87.94623 -289.47618) (xy 87.945735 -289.500787) (xy 87.93784 -289.549364)
			(xy 87.922256 -289.596045) (xy 87.899385 -289.639622) (xy 87.86982 -289.678966) (xy 87.834327 -289.713058)
			(xy 87.793824 -289.741014) (xy 87.749362 -289.762112) (xy 87.702091 -289.775804) (xy 87.653236 -289.781736)
			(xy 87.604061 -289.779755) (xy 87.555842 -289.769911) (xy 87.509826 -289.752459) (xy 87.467205 -289.727852)
			(xy 87.429084 -289.696727) (xy 87.396449 -289.65989) (xy 87.370146 -289.618294) (xy 87.350855 -289.573018)
			(xy 87.339078 -289.525234) (xy 87.335118 -289.47618) (xy 87.00643 -289.47618) (xy 87.005935 -289.500787)
			(xy 86.99804 -289.549364) (xy 86.982456 -289.596045) (xy 86.959585 -289.639622) (xy 86.93002 -289.678966)
			(xy 86.894527 -289.713058) (xy 86.854024 -289.741014) (xy 86.809562 -289.762112) (xy 86.762291 -289.775804)
			(xy 86.713436 -289.781736) (xy 86.664261 -289.779755) (xy 86.616042 -289.769911) (xy 86.570026 -289.752459)
			(xy 86.527405 -289.727852) (xy 86.489284 -289.696727) (xy 86.456649 -289.65989) (xy 86.430346 -289.618294)
			(xy 86.411055 -289.573018) (xy 86.399278 -289.525234) (xy 86.395318 -289.47618) (xy 86.066376 -289.47618)
			(xy 86.065881 -289.500787) (xy 86.057986 -289.549364) (xy 86.042402 -289.596045) (xy 86.019531 -289.639622)
			(xy 85.989966 -289.678966) (xy 85.954473 -289.713058) (xy 85.91397 -289.741014) (xy 85.869508 -289.762112)
			(xy 85.822237 -289.775804) (xy 85.773382 -289.781736) (xy 85.724207 -289.779755) (xy 85.675988 -289.769911)
			(xy 85.629972 -289.752459) (xy 85.587351 -289.727852) (xy 85.54923 -289.696727) (xy 85.516595 -289.65989)
			(xy 85.490292 -289.618294) (xy 85.471001 -289.573018) (xy 85.459224 -289.525234) (xy 85.455264 -289.47618)
			(xy 85.126322 -289.47618) (xy 85.125827 -289.500787) (xy 85.117932 -289.549364) (xy 85.102348 -289.596045)
			(xy 85.079477 -289.639622) (xy 85.049912 -289.678966) (xy 85.014419 -289.713058) (xy 84.973916 -289.741014)
			(xy 84.929454 -289.762112) (xy 84.882183 -289.775804) (xy 84.833328 -289.781736) (xy 84.784153 -289.779755)
			(xy 84.735934 -289.769911) (xy 84.689918 -289.752459) (xy 84.647297 -289.727852) (xy 84.609176 -289.696727)
			(xy 84.576541 -289.65989) (xy 84.550238 -289.618294) (xy 84.530947 -289.573018) (xy 84.51917 -289.525234)
			(xy 84.51521 -289.47618) (xy 84.186268 -289.47618) (xy 84.185823 -289.500173) (xy 84.178319 -289.547569)
			(xy 84.163491 -289.593206) (xy 84.141707 -289.635962) (xy 84.113501 -289.674783) (xy 84.079568 -289.708714)
			(xy 84.040745 -289.736917) (xy 83.997988 -289.758699) (xy 83.952349 -289.773523) (xy 83.904953 -289.781025)
			(xy 83.88096 -289.781488) (xy 83.85457 -289.780936) (xy 83.802573 -289.771876) (xy 83.752907 -289.754014)
			(xy 83.70705 -289.727883) (xy 83.666366 -289.69426) (xy 83.648804 -289.674554) (xy 83.627468 -289.649408)
			(xy 83.62569 -289.649408) (xy 83.621481 -289.649489) (xy 83.613182 -289.650895) (xy 83.60918 -289.652202)
			(xy 83.521804 -289.692588) (xy 83.514023 -289.69712) (xy 83.502035 -289.710541) (xy 83.49545 -289.727288)
			(xy 83.49488 -289.736276) (xy 83.49488 -289.905186) (xy 83.494912 -289.909322) (xy 83.496187 -289.917494)
			(xy 83.49742 -289.921442) (xy 83.502246 -289.931602) (xy 83.515708 -289.952684) (xy 83.519207 -289.957949)
			(xy 83.528328 -289.966694) (xy 83.533742 -289.969956) (xy 83.533996 -289.969956) (xy 83.555754 -289.982538)
			(xy 83.595195 -290.013687) (xy 83.612482 -290.031932) (xy 83.630127 -290.052129) (xy 83.658747 -290.09748)
			(xy 83.669378 -290.122102) (xy 83.672934 -290.128706) (xy 83.673188 -290.129214) (xy 83.686704 -290.153056)
			(xy 83.705952 -290.204363) (xy 83.715753 -290.258279) (xy 83.716368 -290.285678) (xy 83.716368 -290.286186)
			(xy 84.04531 -290.286186) (xy 84.04927 -290.237132) (xy 84.061047 -290.189348) (xy 84.080338 -290.144072)
			(xy 84.106641 -290.102476) (xy 84.139276 -290.065639) (xy 84.177397 -290.034514) (xy 84.220018 -290.009907)
			(xy 84.266034 -289.992455) (xy 84.314253 -289.982611) (xy 84.363428 -289.98063) (xy 84.412283 -289.986562)
			(xy 84.459554 -290.000254) (xy 84.504016 -290.021352) (xy 84.544519 -290.049308) (xy 84.580012 -290.0834)
			(xy 84.609577 -290.122744) (xy 84.632448 -290.166321) (xy 84.648032 -290.213002) (xy 84.655927 -290.261579)
			(xy 84.656422 -290.286186) (xy 84.98511 -290.286186) (xy 84.98907 -290.237132) (xy 85.000847 -290.189348)
			(xy 85.020138 -290.144072) (xy 85.046441 -290.102476) (xy 85.079076 -290.065639) (xy 85.117197 -290.034514)
			(xy 85.159818 -290.009907) (xy 85.205834 -289.992455) (xy 85.254053 -289.982611) (xy 85.303228 -289.98063)
			(xy 85.352083 -289.986562) (xy 85.399354 -290.000254) (xy 85.443816 -290.021352) (xy 85.484319 -290.049308)
			(xy 85.519812 -290.0834) (xy 85.549377 -290.122744) (xy 85.572248 -290.166321) (xy 85.587832 -290.213002)
			(xy 85.595727 -290.261579) (xy 85.596222 -290.286186) (xy 85.925164 -290.286186) (xy 85.929124 -290.237132)
			(xy 85.940901 -290.189348) (xy 85.960192 -290.144072) (xy 85.986495 -290.102476) (xy 86.01913 -290.065639)
			(xy 86.057251 -290.034514) (xy 86.099872 -290.009907) (xy 86.145888 -289.992455) (xy 86.194107 -289.982611)
			(xy 86.243282 -289.98063) (xy 86.292137 -289.986562) (xy 86.339408 -290.000254) (xy 86.38387 -290.021352)
			(xy 86.424373 -290.049308) (xy 86.459866 -290.0834) (xy 86.489431 -290.122744) (xy 86.512302 -290.166321)
			(xy 86.527886 -290.213002) (xy 86.535781 -290.261579) (xy 86.536276 -290.286186) (xy 87.805272 -290.286186)
			(xy 87.809232 -290.237132) (xy 87.821009 -290.189348) (xy 87.8403 -290.144072) (xy 87.866603 -290.102476)
			(xy 87.899238 -290.065639) (xy 87.937359 -290.034514) (xy 87.97998 -290.009907) (xy 88.025996 -289.992455)
			(xy 88.074215 -289.982611) (xy 88.12339 -289.98063) (xy 88.172245 -289.986562) (xy 88.219516 -290.000254)
			(xy 88.263978 -290.021352) (xy 88.304481 -290.049308) (xy 88.339974 -290.0834) (xy 88.369539 -290.122744)
			(xy 88.39241 -290.166321) (xy 88.407994 -290.213002) (xy 88.415889 -290.261579) (xy 88.416384 -290.286186)
			(xy 88.745326 -290.286186) (xy 88.749286 -290.237132) (xy 88.761063 -290.189348) (xy 88.780354 -290.144072)
			(xy 88.806657 -290.102476) (xy 88.839292 -290.065639) (xy 88.877413 -290.034514) (xy 88.920034 -290.009907)
			(xy 88.96605 -289.992455) (xy 89.014269 -289.982611) (xy 89.063444 -289.98063) (xy 89.112299 -289.986562)
			(xy 89.15957 -290.000254) (xy 89.204032 -290.021352) (xy 89.244535 -290.049308) (xy 89.280028 -290.0834)
			(xy 89.309593 -290.122744) (xy 89.332464 -290.166321) (xy 89.348048 -290.213002) (xy 89.355943 -290.261579)
			(xy 89.356438 -290.286186) (xy 89.685126 -290.286186) (xy 89.689086 -290.237132) (xy 89.700863 -290.189348)
			(xy 89.720154 -290.144072) (xy 89.746457 -290.102476) (xy 89.779092 -290.065639) (xy 89.817213 -290.034514)
			(xy 89.859834 -290.009907) (xy 89.90585 -289.992455) (xy 89.954069 -289.982611) (xy 90.003244 -289.98063)
			(xy 90.052099 -289.986562) (xy 90.09937 -290.000254) (xy 90.143832 -290.021352) (xy 90.184335 -290.049308)
			(xy 90.219828 -290.0834) (xy 90.249393 -290.122744) (xy 90.272264 -290.166321) (xy 90.287848 -290.213002)
			(xy 90.295743 -290.261579) (xy 90.296238 -290.286186) (xy 90.614749 -290.286186) (xy 90.618844 -290.235458)
			(xy 90.631023 -290.186044) (xy 90.650971 -290.139224) (xy 90.678172 -290.09621) (xy 90.71192 -290.058116)
			(xy 90.751342 -290.025929) (xy 90.795416 -290.000483) (xy 90.843002 -289.982436) (xy 90.892866 -289.972256)
			(xy 90.943718 -289.970207) (xy 90.994239 -289.976341) (xy 91.043123 -289.990501) (xy 91.089102 -290.012318)
			(xy 91.130986 -290.041228) (xy 91.16769 -290.076483) (xy 91.198263 -290.117169) (xy 91.221914 -290.162232)
			(xy 91.23803 -290.210506) (xy 91.246194 -290.26074) (xy 91.246706 -290.286186) (xy 91.565234 -290.286186)
			(xy 91.569194 -290.237132) (xy 91.580971 -290.189348) (xy 91.600262 -290.144072) (xy 91.626565 -290.102476)
			(xy 91.6592 -290.065639) (xy 91.697321 -290.034514) (xy 91.739942 -290.009907) (xy 91.785958 -289.992455)
			(xy 91.834177 -289.982611) (xy 91.883352 -289.98063) (xy 91.932207 -289.986562) (xy 91.979478 -290.000254)
			(xy 92.02394 -290.021352) (xy 92.064443 -290.049308) (xy 92.099936 -290.0834) (xy 92.129501 -290.122744)
			(xy 92.152372 -290.166321) (xy 92.167956 -290.213002) (xy 92.175851 -290.261579) (xy 92.176346 -290.286186)
			(xy 92.494857 -290.286186) (xy 92.498952 -290.235458) (xy 92.511131 -290.186044) (xy 92.531079 -290.139224)
			(xy 92.55828 -290.09621) (xy 92.592028 -290.058116) (xy 92.63145 -290.025929) (xy 92.675524 -290.000483)
			(xy 92.72311 -289.982436) (xy 92.772974 -289.972256) (xy 92.823826 -289.970207) (xy 92.874347 -289.976341)
			(xy 92.923231 -289.990501) (xy 92.96921 -290.012318) (xy 93.011094 -290.041228) (xy 93.047798 -290.076483)
			(xy 93.078371 -290.117169) (xy 93.102022 -290.162232) (xy 93.118138 -290.210506) (xy 93.126302 -290.26074)
			(xy 93.126814 -290.286186) (xy 94.374711 -290.286186) (xy 94.378806 -290.235458) (xy 94.390985 -290.186044)
			(xy 94.410933 -290.139224) (xy 94.438134 -290.09621) (xy 94.471882 -290.058116) (xy 94.511304 -290.025929)
			(xy 94.555378 -290.000483) (xy 94.602964 -289.982436) (xy 94.652828 -289.972256) (xy 94.70368 -289.970207)
			(xy 94.754201 -289.976341) (xy 94.803085 -289.990501) (xy 94.849064 -290.012318) (xy 94.890948 -290.041228)
			(xy 94.927652 -290.076483) (xy 94.958225 -290.117169) (xy 94.981876 -290.162232) (xy 94.997992 -290.210506)
			(xy 95.006156 -290.26074) (xy 95.006668 -290.286186) (xy 95.314765 -290.286186) (xy 95.31886 -290.235458)
			(xy 95.331039 -290.186044) (xy 95.350987 -290.139224) (xy 95.378188 -290.09621) (xy 95.411936 -290.058116)
			(xy 95.451358 -290.025929) (xy 95.495432 -290.000483) (xy 95.543018 -289.982436) (xy 95.592882 -289.972256)
			(xy 95.643734 -289.970207) (xy 95.694255 -289.976341) (xy 95.743139 -289.990501) (xy 95.789118 -290.012318)
			(xy 95.831002 -290.041228) (xy 95.867706 -290.076483) (xy 95.898279 -290.117169) (xy 95.92193 -290.162232)
			(xy 95.938046 -290.210506) (xy 95.94621 -290.26074) (xy 95.946722 -290.286186) (xy 95.94621 -290.311632)
			(xy 95.938046 -290.361866) (xy 95.92193 -290.41014) (xy 95.898279 -290.455203) (xy 95.867706 -290.495889)
			(xy 95.831002 -290.531144) (xy 95.789118 -290.560054) (xy 95.743139 -290.581871) (xy 95.694255 -290.596031)
			(xy 95.643734 -290.602165) (xy 95.592882 -290.600116) (xy 95.543018 -290.589936) (xy 95.495432 -290.571889)
			(xy 95.451358 -290.546443) (xy 95.411936 -290.514256) (xy 95.378188 -290.476162) (xy 95.350987 -290.433148)
			(xy 95.331039 -290.386328) (xy 95.31886 -290.336914) (xy 95.314765 -290.286186) (xy 95.006668 -290.286186)
			(xy 95.006156 -290.311632) (xy 94.997992 -290.361866) (xy 94.981876 -290.41014) (xy 94.958225 -290.455203)
			(xy 94.927652 -290.495889) (xy 94.890948 -290.531144) (xy 94.849064 -290.560054) (xy 94.803085 -290.581871)
			(xy 94.754201 -290.596031) (xy 94.70368 -290.602165) (xy 94.652828 -290.600116) (xy 94.602964 -290.589936)
			(xy 94.555378 -290.571889) (xy 94.511304 -290.546443) (xy 94.471882 -290.514256) (xy 94.438134 -290.476162)
			(xy 94.410933 -290.433148) (xy 94.390985 -290.386328) (xy 94.378806 -290.336914) (xy 94.374711 -290.286186)
			(xy 93.126814 -290.286186) (xy 93.126302 -290.311632) (xy 93.118138 -290.361866) (xy 93.102022 -290.41014)
			(xy 93.078371 -290.455203) (xy 93.047798 -290.495889) (xy 93.011094 -290.531144) (xy 92.96921 -290.560054)
			(xy 92.923231 -290.581871) (xy 92.874347 -290.596031) (xy 92.823826 -290.602165) (xy 92.772974 -290.600116)
			(xy 92.72311 -290.589936) (xy 92.675524 -290.571889) (xy 92.63145 -290.546443) (xy 92.592028 -290.514256)
			(xy 92.55828 -290.476162) (xy 92.531079 -290.433148) (xy 92.511131 -290.386328) (xy 92.498952 -290.336914)
			(xy 92.494857 -290.286186) (xy 92.176346 -290.286186) (xy 92.175851 -290.310793) (xy 92.167956 -290.35937)
			(xy 92.152372 -290.406051) (xy 92.129501 -290.449628) (xy 92.099936 -290.488972) (xy 92.064443 -290.523064)
			(xy 92.02394 -290.55102) (xy 91.979478 -290.572118) (xy 91.932207 -290.58581) (xy 91.883352 -290.591742)
			(xy 91.834177 -290.589761) (xy 91.785958 -290.579917) (xy 91.739942 -290.562465) (xy 91.697321 -290.537858)
			(xy 91.6592 -290.506733) (xy 91.626565 -290.469896) (xy 91.600262 -290.4283) (xy 91.580971 -290.383024)
			(xy 91.569194 -290.33524) (xy 91.565234 -290.286186) (xy 91.246706 -290.286186) (xy 91.246194 -290.311632)
			(xy 91.23803 -290.361866) (xy 91.221914 -290.41014) (xy 91.198263 -290.455203) (xy 91.16769 -290.495889)
			(xy 91.130986 -290.531144) (xy 91.089102 -290.560054) (xy 91.043123 -290.581871) (xy 90.994239 -290.596031)
			(xy 90.943718 -290.602165) (xy 90.892866 -290.600116) (xy 90.843002 -290.589936) (xy 90.795416 -290.571889)
			(xy 90.751342 -290.546443) (xy 90.71192 -290.514256) (xy 90.678172 -290.476162) (xy 90.650971 -290.433148)
			(xy 90.631023 -290.386328) (xy 90.618844 -290.336914) (xy 90.614749 -290.286186) (xy 90.296238 -290.286186)
			(xy 90.295743 -290.310793) (xy 90.287848 -290.35937) (xy 90.272264 -290.406051) (xy 90.249393 -290.449628)
			(xy 90.219828 -290.488972) (xy 90.184335 -290.523064) (xy 90.143832 -290.55102) (xy 90.09937 -290.572118)
			(xy 90.052099 -290.58581) (xy 90.003244 -290.591742) (xy 89.954069 -290.589761) (xy 89.90585 -290.579917)
			(xy 89.859834 -290.562465) (xy 89.817213 -290.537858) (xy 89.779092 -290.506733) (xy 89.746457 -290.469896)
			(xy 89.720154 -290.4283) (xy 89.700863 -290.383024) (xy 89.689086 -290.33524) (xy 89.685126 -290.286186)
			(xy 89.356438 -290.286186) (xy 89.355943 -290.310793) (xy 89.348048 -290.35937) (xy 89.332464 -290.406051)
			(xy 89.309593 -290.449628) (xy 89.280028 -290.488972) (xy 89.244535 -290.523064) (xy 89.204032 -290.55102)
			(xy 89.15957 -290.572118) (xy 89.112299 -290.58581) (xy 89.063444 -290.591742) (xy 89.014269 -290.589761)
			(xy 88.96605 -290.579917) (xy 88.920034 -290.562465) (xy 88.877413 -290.537858) (xy 88.839292 -290.506733)
			(xy 88.806657 -290.469896) (xy 88.780354 -290.4283) (xy 88.761063 -290.383024) (xy 88.749286 -290.33524)
			(xy 88.745326 -290.286186) (xy 88.416384 -290.286186) (xy 88.415889 -290.310793) (xy 88.407994 -290.35937)
			(xy 88.39241 -290.406051) (xy 88.369539 -290.449628) (xy 88.339974 -290.488972) (xy 88.304481 -290.523064)
			(xy 88.263978 -290.55102) (xy 88.219516 -290.572118) (xy 88.172245 -290.58581) (xy 88.12339 -290.591742)
			(xy 88.074215 -290.589761) (xy 88.025996 -290.579917) (xy 87.97998 -290.562465) (xy 87.937359 -290.537858)
			(xy 87.899238 -290.506733) (xy 87.866603 -290.469896) (xy 87.8403 -290.4283) (xy 87.821009 -290.383024)
			(xy 87.809232 -290.33524) (xy 87.805272 -290.286186) (xy 86.536276 -290.286186) (xy 86.535781 -290.310793)
			(xy 86.527886 -290.35937) (xy 86.512302 -290.406051) (xy 86.489431 -290.449628) (xy 86.459866 -290.488972)
			(xy 86.424373 -290.523064) (xy 86.38387 -290.55102) (xy 86.339408 -290.572118) (xy 86.292137 -290.58581)
			(xy 86.243282 -290.591742) (xy 86.194107 -290.589761) (xy 86.145888 -290.579917) (xy 86.099872 -290.562465)
			(xy 86.057251 -290.537858) (xy 86.01913 -290.506733) (xy 85.986495 -290.469896) (xy 85.960192 -290.4283)
			(xy 85.940901 -290.383024) (xy 85.929124 -290.33524) (xy 85.925164 -290.286186) (xy 85.596222 -290.286186)
			(xy 85.595727 -290.310793) (xy 85.587832 -290.35937) (xy 85.572248 -290.406051) (xy 85.549377 -290.449628)
			(xy 85.519812 -290.488972) (xy 85.484319 -290.523064) (xy 85.443816 -290.55102) (xy 85.399354 -290.572118)
			(xy 85.352083 -290.58581) (xy 85.303228 -290.591742) (xy 85.254053 -290.589761) (xy 85.205834 -290.579917)
			(xy 85.159818 -290.562465) (xy 85.117197 -290.537858) (xy 85.079076 -290.506733) (xy 85.046441 -290.469896)
			(xy 85.020138 -290.4283) (xy 85.000847 -290.383024) (xy 84.98907 -290.33524) (xy 84.98511 -290.286186)
			(xy 84.656422 -290.286186) (xy 84.655927 -290.310793) (xy 84.648032 -290.35937) (xy 84.632448 -290.406051)
			(xy 84.609577 -290.449628) (xy 84.580012 -290.488972) (xy 84.544519 -290.523064) (xy 84.504016 -290.55102)
			(xy 84.459554 -290.572118) (xy 84.412283 -290.58581) (xy 84.363428 -290.591742) (xy 84.314253 -290.589761)
			(xy 84.266034 -290.579917) (xy 84.220018 -290.562465) (xy 84.177397 -290.537858) (xy 84.139276 -290.506733)
			(xy 84.106641 -290.469896) (xy 84.080338 -290.4283) (xy 84.061047 -290.383024) (xy 84.04927 -290.33524)
			(xy 84.04531 -290.286186) (xy 83.716368 -290.286186) (xy 83.716368 -290.292028) (xy 83.715347 -290.317717)
			(xy 83.705769 -290.368225) (xy 83.687864 -290.416414) (xy 83.66214 -290.460922) (xy 83.629323 -290.500492)
			(xy 83.59034 -290.534005) (xy 83.546294 -290.560514) (xy 83.522566 -290.570412) (xy 83.512152 -290.57473)
			(xy 83.503516 -290.58743) (xy 83.499479 -290.593834) (xy 83.495072 -290.608311) (xy 83.49488 -290.615878)
			(xy 83.49488 -290.738306) (xy 83.495137 -290.743915) (xy 83.497825 -290.754815) (xy 83.500214 -290.759896)
			(xy 83.504786 -290.76777) (xy 83.508738 -290.772624) (xy 83.518497 -290.780453) (xy 83.52409 -290.783264)
			(xy 83.524344 -290.783518) (xy 83.605116 -290.820856) (xy 83.618832 -290.824158) (xy 83.631278 -290.824666)
			(xy 83.648042 -290.818316) (xy 83.6549 -290.815014) (xy 83.665314 -290.809172) (xy 83.6676 -290.807394)
			(xy 83.668616 -290.806632) (xy 83.66887 -290.806378) (xy 83.689157 -290.791303) (xy 83.733638 -290.76731)
			(xy 83.781453 -290.750942) (xy 83.831306 -290.742644) (xy 83.856576 -290.742116) (xy 83.882414 -290.742664)
			(xy 83.93335 -290.751377) (xy 83.982093 -290.768541) (xy 84.027249 -290.793667) (xy 84.067531 -290.826037)
			(xy 84.101788 -290.864727) (xy 84.129042 -290.908632) (xy 84.139278 -290.932362) (xy 84.142834 -290.938966)
			(xy 84.143088 -290.939474) (xy 84.156618 -290.963355) (xy 84.175871 -291.014748) (xy 84.185647 -291.068751)
			(xy 84.186268 -291.096192) (xy 84.51521 -291.096192) (xy 84.51917 -291.047138) (xy 84.530947 -290.999354)
			(xy 84.550238 -290.954078) (xy 84.576541 -290.912482) (xy 84.609176 -290.875645) (xy 84.647297 -290.84452)
			(xy 84.689918 -290.819913) (xy 84.735934 -290.802461) (xy 84.784153 -290.792617) (xy 84.833328 -290.790636)
			(xy 84.882183 -290.796568) (xy 84.929454 -290.81026) (xy 84.973916 -290.831358) (xy 85.014419 -290.859314)
			(xy 85.049912 -290.893406) (xy 85.079477 -290.93275) (xy 85.102348 -290.976327) (xy 85.117932 -291.023008)
			(xy 85.125827 -291.071585) (xy 85.126322 -291.096192) (xy 85.455264 -291.096192) (xy 85.459224 -291.047138)
			(xy 85.471001 -290.999354) (xy 85.490292 -290.954078) (xy 85.516595 -290.912482) (xy 85.54923 -290.875645)
			(xy 85.587351 -290.84452) (xy 85.629972 -290.819913) (xy 85.675988 -290.802461) (xy 85.724207 -290.792617)
			(xy 85.773382 -290.790636) (xy 85.822237 -290.796568) (xy 85.869508 -290.81026) (xy 85.91397 -290.831358)
			(xy 85.954473 -290.859314) (xy 85.989966 -290.893406) (xy 86.019531 -290.93275) (xy 86.042402 -290.976327)
			(xy 86.057986 -291.023008) (xy 86.065881 -291.071585) (xy 86.066376 -291.096192) (xy 86.395318 -291.096192)
			(xy 86.399278 -291.047138) (xy 86.411055 -290.999354) (xy 86.430346 -290.954078) (xy 86.456649 -290.912482)
			(xy 86.489284 -290.875645) (xy 86.527405 -290.84452) (xy 86.570026 -290.819913) (xy 86.616042 -290.802461)
			(xy 86.664261 -290.792617) (xy 86.713436 -290.790636) (xy 86.762291 -290.796568) (xy 86.809562 -290.81026)
			(xy 86.854024 -290.831358) (xy 86.894527 -290.859314) (xy 86.93002 -290.893406) (xy 86.959585 -290.93275)
			(xy 86.982456 -290.976327) (xy 86.99804 -291.023008) (xy 87.005935 -291.071585) (xy 87.00643 -291.096192)
			(xy 87.335118 -291.096192) (xy 87.339078 -291.047138) (xy 87.350855 -290.999354) (xy 87.370146 -290.954078)
			(xy 87.396449 -290.912482) (xy 87.429084 -290.875645) (xy 87.467205 -290.84452) (xy 87.509826 -290.819913)
			(xy 87.555842 -290.802461) (xy 87.604061 -290.792617) (xy 87.653236 -290.790636) (xy 87.702091 -290.796568)
			(xy 87.749362 -290.81026) (xy 87.793824 -290.831358) (xy 87.834327 -290.859314) (xy 87.86982 -290.893406)
			(xy 87.899385 -290.93275) (xy 87.922256 -290.976327) (xy 87.93784 -291.023008) (xy 87.945735 -291.071585)
			(xy 87.94623 -291.096192) (xy 88.275172 -291.096192) (xy 88.279132 -291.047138) (xy 88.290909 -290.999354)
			(xy 88.3102 -290.954078) (xy 88.336503 -290.912482) (xy 88.369138 -290.875645) (xy 88.407259 -290.84452)
			(xy 88.44988 -290.819913) (xy 88.495896 -290.802461) (xy 88.544115 -290.792617) (xy 88.59329 -290.790636)
			(xy 88.642145 -290.796568) (xy 88.689416 -290.81026) (xy 88.733878 -290.831358) (xy 88.774381 -290.859314)
			(xy 88.809874 -290.893406) (xy 88.839439 -290.93275) (xy 88.86231 -290.976327) (xy 88.877894 -291.023008)
			(xy 88.885789 -291.071585) (xy 88.886284 -291.096192) (xy 89.215226 -291.096192) (xy 89.219186 -291.047138)
			(xy 89.230963 -290.999354) (xy 89.250254 -290.954078) (xy 89.276557 -290.912482) (xy 89.309192 -290.875645)
			(xy 89.347313 -290.84452) (xy 89.389934 -290.819913) (xy 89.43595 -290.802461) (xy 89.484169 -290.792617)
			(xy 89.533344 -290.790636) (xy 89.582199 -290.796568) (xy 89.62947 -290.81026) (xy 89.673932 -290.831358)
			(xy 89.714435 -290.859314) (xy 89.749928 -290.893406) (xy 89.779493 -290.93275) (xy 89.802364 -290.976327)
			(xy 89.817948 -291.023008) (xy 89.825843 -291.071585) (xy 89.826338 -291.096192) (xy 90.15528 -291.096192)
			(xy 90.15924 -291.047138) (xy 90.171017 -290.999354) (xy 90.190308 -290.954078) (xy 90.216611 -290.912482)
			(xy 90.249246 -290.875645) (xy 90.287367 -290.84452) (xy 90.329988 -290.819913) (xy 90.376004 -290.802461)
			(xy 90.424223 -290.792617) (xy 90.473398 -290.790636) (xy 90.522253 -290.796568) (xy 90.569524 -290.81026)
			(xy 90.613986 -290.831358) (xy 90.654489 -290.859314) (xy 90.689982 -290.893406) (xy 90.719547 -290.93275)
			(xy 90.742418 -290.976327) (xy 90.758002 -291.023008) (xy 90.765897 -291.071585) (xy 90.766392 -291.096192)
			(xy 91.084903 -291.096192) (xy 91.088998 -291.045464) (xy 91.101177 -290.99605) (xy 91.121125 -290.94923)
			(xy 91.148326 -290.906216) (xy 91.182074 -290.868122) (xy 91.221496 -290.835935) (xy 91.26557 -290.810489)
			(xy 91.313156 -290.792442) (xy 91.36302 -290.782262) (xy 91.413872 -290.780213) (xy 91.464393 -290.786347)
			(xy 91.513277 -290.800507) (xy 91.559256 -290.822324) (xy 91.60114 -290.851234) (xy 91.637844 -290.886489)
			(xy 91.668417 -290.927175) (xy 91.692068 -290.972238) (xy 91.708184 -291.020512) (xy 91.716348 -291.070746)
			(xy 91.71686 -291.096192) (xy 92.024703 -291.096192) (xy 92.028798 -291.045464) (xy 92.040977 -290.99605)
			(xy 92.060925 -290.94923) (xy 92.088126 -290.906216) (xy 92.121874 -290.868122) (xy 92.161296 -290.835935)
			(xy 92.20537 -290.810489) (xy 92.252956 -290.792442) (xy 92.30282 -290.782262) (xy 92.353672 -290.780213)
			(xy 92.404193 -290.786347) (xy 92.453077 -290.800507) (xy 92.499056 -290.822324) (xy 92.54094 -290.851234)
			(xy 92.577644 -290.886489) (xy 92.608217 -290.927175) (xy 92.631868 -290.972238) (xy 92.647984 -291.020512)
			(xy 92.656148 -291.070746) (xy 92.65666 -291.096192) (xy 92.975188 -291.096192) (xy 92.979148 -291.047138)
			(xy 92.990925 -290.999354) (xy 93.010216 -290.954078) (xy 93.036519 -290.912482) (xy 93.069154 -290.875645)
			(xy 93.107275 -290.84452) (xy 93.149896 -290.819913) (xy 93.195912 -290.802461) (xy 93.244131 -290.792617)
			(xy 93.293306 -290.790636) (xy 93.342161 -290.796568) (xy 93.389432 -290.81026) (xy 93.433894 -290.831358)
			(xy 93.474397 -290.859314) (xy 93.50989 -290.893406) (xy 93.539455 -290.93275) (xy 93.562326 -290.976327)
			(xy 93.57791 -291.023008) (xy 93.585805 -291.071585) (xy 93.5863 -291.096192) (xy 93.904811 -291.096192)
			(xy 93.908906 -291.045464) (xy 93.921085 -290.99605) (xy 93.941033 -290.94923) (xy 93.968234 -290.906216)
			(xy 94.001982 -290.868122) (xy 94.041404 -290.835935) (xy 94.085478 -290.810489) (xy 94.133064 -290.792442)
			(xy 94.182928 -290.782262) (xy 94.23378 -290.780213) (xy 94.284301 -290.786347) (xy 94.333185 -290.800507)
			(xy 94.379164 -290.822324) (xy 94.421048 -290.851234) (xy 94.457752 -290.886489) (xy 94.488325 -290.927175)
			(xy 94.511976 -290.972238) (xy 94.528092 -291.020512) (xy 94.536256 -291.070746) (xy 94.536768 -291.096192)
			(xy 94.855296 -291.096192) (xy 94.859256 -291.047138) (xy 94.871033 -290.999354) (xy 94.890324 -290.954078)
			(xy 94.916627 -290.912482) (xy 94.949262 -290.875645) (xy 94.987383 -290.84452) (xy 95.030004 -290.819913)
			(xy 95.07602 -290.802461) (xy 95.124239 -290.792617) (xy 95.173414 -290.790636) (xy 95.222269 -290.796568)
			(xy 95.26954 -290.81026) (xy 95.314002 -290.831358) (xy 95.354505 -290.859314) (xy 95.389998 -290.893406)
			(xy 95.419563 -290.93275) (xy 95.442434 -290.976327) (xy 95.458018 -291.023008) (xy 95.465913 -291.071585)
			(xy 95.466408 -291.096192) (xy 95.465913 -291.120799) (xy 95.458018 -291.169376) (xy 95.442434 -291.216057)
			(xy 95.419563 -291.259634) (xy 95.389998 -291.298978) (xy 95.354505 -291.33307) (xy 95.314002 -291.361026)
			(xy 95.26954 -291.382124) (xy 95.222269 -291.395816) (xy 95.173414 -291.401748) (xy 95.124239 -291.399767)
			(xy 95.07602 -291.389923) (xy 95.030004 -291.372471) (xy 94.987383 -291.347864) (xy 94.949262 -291.316739)
			(xy 94.916627 -291.279902) (xy 94.890324 -291.238306) (xy 94.871033 -291.19303) (xy 94.859256 -291.145246)
			(xy 94.855296 -291.096192) (xy 94.536768 -291.096192) (xy 94.536256 -291.121638) (xy 94.528092 -291.171872)
			(xy 94.511976 -291.220146) (xy 94.488325 -291.265209) (xy 94.457752 -291.305895) (xy 94.421048 -291.34115)
			(xy 94.379164 -291.37006) (xy 94.333185 -291.391877) (xy 94.284301 -291.406037) (xy 94.23378 -291.412171)
			(xy 94.182928 -291.410122) (xy 94.133064 -291.399942) (xy 94.085478 -291.381895) (xy 94.041404 -291.356449)
			(xy 94.001982 -291.324262) (xy 93.968234 -291.286168) (xy 93.941033 -291.243154) (xy 93.921085 -291.196334)
			(xy 93.908906 -291.14692) (xy 93.904811 -291.096192) (xy 93.5863 -291.096192) (xy 93.585805 -291.120799)
			(xy 93.57791 -291.169376) (xy 93.562326 -291.216057) (xy 93.539455 -291.259634) (xy 93.50989 -291.298978)
			(xy 93.474397 -291.33307) (xy 93.433894 -291.361026) (xy 93.389432 -291.382124) (xy 93.342161 -291.395816)
			(xy 93.293306 -291.401748) (xy 93.244131 -291.399767) (xy 93.195912 -291.389923) (xy 93.149896 -291.372471)
			(xy 93.107275 -291.347864) (xy 93.069154 -291.316739) (xy 93.036519 -291.279902) (xy 93.010216 -291.238306)
			(xy 92.990925 -291.19303) (xy 92.979148 -291.145246) (xy 92.975188 -291.096192) (xy 92.65666 -291.096192)
			(xy 92.656148 -291.121638) (xy 92.647984 -291.171872) (xy 92.631868 -291.220146) (xy 92.608217 -291.265209)
			(xy 92.577644 -291.305895) (xy 92.54094 -291.34115) (xy 92.499056 -291.37006) (xy 92.453077 -291.391877)
			(xy 92.404193 -291.406037) (xy 92.353672 -291.412171) (xy 92.30282 -291.410122) (xy 92.252956 -291.399942)
			(xy 92.20537 -291.381895) (xy 92.161296 -291.356449) (xy 92.121874 -291.324262) (xy 92.088126 -291.286168)
			(xy 92.060925 -291.243154) (xy 92.040977 -291.196334) (xy 92.028798 -291.14692) (xy 92.024703 -291.096192)
			(xy 91.71686 -291.096192) (xy 91.716348 -291.121638) (xy 91.708184 -291.171872) (xy 91.692068 -291.220146)
			(xy 91.668417 -291.265209) (xy 91.637844 -291.305895) (xy 91.60114 -291.34115) (xy 91.559256 -291.37006)
			(xy 91.513277 -291.391877) (xy 91.464393 -291.406037) (xy 91.413872 -291.412171) (xy 91.36302 -291.410122)
			(xy 91.313156 -291.399942) (xy 91.26557 -291.381895) (xy 91.221496 -291.356449) (xy 91.182074 -291.324262)
			(xy 91.148326 -291.286168) (xy 91.121125 -291.243154) (xy 91.101177 -291.196334) (xy 91.088998 -291.14692)
			(xy 91.084903 -291.096192) (xy 90.766392 -291.096192) (xy 90.765897 -291.120799) (xy 90.758002 -291.169376)
			(xy 90.742418 -291.216057) (xy 90.719547 -291.259634) (xy 90.689982 -291.298978) (xy 90.654489 -291.33307)
			(xy 90.613986 -291.361026) (xy 90.569524 -291.382124) (xy 90.522253 -291.395816) (xy 90.473398 -291.401748)
			(xy 90.424223 -291.399767) (xy 90.376004 -291.389923) (xy 90.329988 -291.372471) (xy 90.287367 -291.347864)
			(xy 90.249246 -291.316739) (xy 90.216611 -291.279902) (xy 90.190308 -291.238306) (xy 90.171017 -291.19303)
			(xy 90.15924 -291.145246) (xy 90.15528 -291.096192) (xy 89.826338 -291.096192) (xy 89.825843 -291.120799)
			(xy 89.817948 -291.169376) (xy 89.802364 -291.216057) (xy 89.779493 -291.259634) (xy 89.749928 -291.298978)
			(xy 89.714435 -291.33307) (xy 89.673932 -291.361026) (xy 89.62947 -291.382124) (xy 89.582199 -291.395816)
			(xy 89.533344 -291.401748) (xy 89.484169 -291.399767) (xy 89.43595 -291.389923) (xy 89.389934 -291.372471)
			(xy 89.347313 -291.347864) (xy 89.309192 -291.316739) (xy 89.276557 -291.279902) (xy 89.250254 -291.238306)
			(xy 89.230963 -291.19303) (xy 89.219186 -291.145246) (xy 89.215226 -291.096192) (xy 88.886284 -291.096192)
			(xy 88.885789 -291.120799) (xy 88.877894 -291.169376) (xy 88.86231 -291.216057) (xy 88.839439 -291.259634)
			(xy 88.809874 -291.298978) (xy 88.774381 -291.33307) (xy 88.733878 -291.361026) (xy 88.689416 -291.382124)
			(xy 88.642145 -291.395816) (xy 88.59329 -291.401748) (xy 88.544115 -291.399767) (xy 88.495896 -291.389923)
			(xy 88.44988 -291.372471) (xy 88.407259 -291.347864) (xy 88.369138 -291.316739) (xy 88.336503 -291.279902)
			(xy 88.3102 -291.238306) (xy 88.290909 -291.19303) (xy 88.279132 -291.145246) (xy 88.275172 -291.096192)
			(xy 87.94623 -291.096192) (xy 87.945735 -291.120799) (xy 87.93784 -291.169376) (xy 87.922256 -291.216057)
			(xy 87.899385 -291.259634) (xy 87.86982 -291.298978) (xy 87.834327 -291.33307) (xy 87.793824 -291.361026)
			(xy 87.749362 -291.382124) (xy 87.702091 -291.395816) (xy 87.653236 -291.401748) (xy 87.604061 -291.399767)
			(xy 87.555842 -291.389923) (xy 87.509826 -291.372471) (xy 87.467205 -291.347864) (xy 87.429084 -291.316739)
			(xy 87.396449 -291.279902) (xy 87.370146 -291.238306) (xy 87.350855 -291.19303) (xy 87.339078 -291.145246)
			(xy 87.335118 -291.096192) (xy 87.00643 -291.096192) (xy 87.005935 -291.120799) (xy 86.99804 -291.169376)
			(xy 86.982456 -291.216057) (xy 86.959585 -291.259634) (xy 86.93002 -291.298978) (xy 86.894527 -291.33307)
			(xy 86.854024 -291.361026) (xy 86.809562 -291.382124) (xy 86.762291 -291.395816) (xy 86.713436 -291.401748)
			(xy 86.664261 -291.399767) (xy 86.616042 -291.389923) (xy 86.570026 -291.372471) (xy 86.527405 -291.347864)
			(xy 86.489284 -291.316739) (xy 86.456649 -291.279902) (xy 86.430346 -291.238306) (xy 86.411055 -291.19303)
			(xy 86.399278 -291.145246) (xy 86.395318 -291.096192) (xy 86.066376 -291.096192) (xy 86.065881 -291.120799)
			(xy 86.057986 -291.169376) (xy 86.042402 -291.216057) (xy 86.019531 -291.259634) (xy 85.989966 -291.298978)
			(xy 85.954473 -291.33307) (xy 85.91397 -291.361026) (xy 85.869508 -291.382124) (xy 85.822237 -291.395816)
			(xy 85.773382 -291.401748) (xy 85.724207 -291.399767) (xy 85.675988 -291.389923) (xy 85.629972 -291.372471)
			(xy 85.587351 -291.347864) (xy 85.54923 -291.316739) (xy 85.516595 -291.279902) (xy 85.490292 -291.238306)
			(xy 85.471001 -291.19303) (xy 85.459224 -291.145246) (xy 85.455264 -291.096192) (xy 85.126322 -291.096192)
			(xy 85.125827 -291.120799) (xy 85.117932 -291.169376) (xy 85.102348 -291.216057) (xy 85.079477 -291.259634)
			(xy 85.049912 -291.298978) (xy 85.014419 -291.33307) (xy 84.973916 -291.361026) (xy 84.929454 -291.382124)
			(xy 84.882183 -291.395816) (xy 84.833328 -291.401748) (xy 84.784153 -291.399767) (xy 84.735934 -291.389923)
			(xy 84.689918 -291.372471) (xy 84.647297 -291.347864) (xy 84.609176 -291.316739) (xy 84.576541 -291.279902)
			(xy 84.550238 -291.238306) (xy 84.530947 -291.19303) (xy 84.51917 -291.145246) (xy 84.51521 -291.096192)
			(xy 84.186268 -291.096192) (xy 84.185822 -291.120184) (xy 84.178316 -291.167579) (xy 84.163488 -291.213215)
			(xy 84.141702 -291.255969) (xy 84.113496 -291.294789) (xy 84.079564 -291.328717) (xy 84.040742 -291.356919)
			(xy 83.997985 -291.3787) (xy 83.952347 -291.393524) (xy 83.904952 -291.401025) (xy 83.88096 -291.4015)
			(xy 83.85457 -291.400949) (xy 83.802573 -291.391888) (xy 83.752906 -291.374027) (xy 83.707048 -291.347897)
			(xy 83.666363 -291.314274) (xy 83.648804 -291.294566) (xy 83.627468 -291.26942) (xy 83.62569 -291.26942)
			(xy 83.621481 -291.269501) (xy 83.613182 -291.270908) (xy 83.60918 -291.272214) (xy 83.521804 -291.3126)
			(xy 83.514024 -291.317133) (xy 83.50204 -291.330554) (xy 83.495459 -291.347301) (xy 83.49488 -291.356288)
			(xy 83.49488 -291.525198) (xy 83.494913 -291.529334) (xy 83.49619 -291.537505) (xy 83.49742 -291.541454)
			(xy 83.502246 -291.551614) (xy 83.515708 -291.572696) (xy 83.519208 -291.57796) (xy 83.52833 -291.586703)
			(xy 83.533742 -291.589968) (xy 83.533996 -291.589968) (xy 83.555756 -291.602547) (xy 83.595204 -291.63369)
			(xy 83.612482 -291.651944) (xy 83.630127 -291.672141) (xy 83.658745 -291.717493) (xy 83.669378 -291.742114)
			(xy 83.672934 -291.748718) (xy 83.673188 -291.749226) (xy 83.686703 -291.773068) (xy 83.705949 -291.824376)
			(xy 83.715748 -291.878291) (xy 83.716368 -291.90569) (xy 83.716368 -291.906198) (xy 84.04531 -291.906198)
			(xy 84.04927 -291.857144) (xy 84.061047 -291.80936) (xy 84.080338 -291.764084) (xy 84.106641 -291.722488)
			(xy 84.139276 -291.685651) (xy 84.177397 -291.654526) (xy 84.220018 -291.629919) (xy 84.266034 -291.612467)
			(xy 84.314253 -291.602623) (xy 84.363428 -291.600642) (xy 84.412283 -291.606574) (xy 84.459554 -291.620266)
			(xy 84.504016 -291.641364) (xy 84.544519 -291.66932) (xy 84.580012 -291.703412) (xy 84.609577 -291.742756)
			(xy 84.632448 -291.786333) (xy 84.648032 -291.833014) (xy 84.655927 -291.881591) (xy 84.656422 -291.906198)
			(xy 84.98511 -291.906198) (xy 84.98907 -291.857144) (xy 85.000847 -291.80936) (xy 85.020138 -291.764084)
			(xy 85.046441 -291.722488) (xy 85.079076 -291.685651) (xy 85.117197 -291.654526) (xy 85.159818 -291.629919)
			(xy 85.205834 -291.612467) (xy 85.254053 -291.602623) (xy 85.303228 -291.600642) (xy 85.352083 -291.606574)
			(xy 85.399354 -291.620266) (xy 85.443816 -291.641364) (xy 85.484319 -291.66932) (xy 85.519812 -291.703412)
			(xy 85.549377 -291.742756) (xy 85.572248 -291.786333) (xy 85.587832 -291.833014) (xy 85.595727 -291.881591)
			(xy 85.596222 -291.906198) (xy 85.925164 -291.906198) (xy 85.929124 -291.857144) (xy 85.940901 -291.80936)
			(xy 85.960192 -291.764084) (xy 85.986495 -291.722488) (xy 86.01913 -291.685651) (xy 86.057251 -291.654526)
			(xy 86.099872 -291.629919) (xy 86.145888 -291.612467) (xy 86.194107 -291.602623) (xy 86.243282 -291.600642)
			(xy 86.292137 -291.606574) (xy 86.339408 -291.620266) (xy 86.38387 -291.641364) (xy 86.424373 -291.66932)
			(xy 86.459866 -291.703412) (xy 86.489431 -291.742756) (xy 86.512302 -291.786333) (xy 86.527886 -291.833014)
			(xy 86.535781 -291.881591) (xy 86.536276 -291.906198) (xy 86.865218 -291.906198) (xy 86.869178 -291.857144)
			(xy 86.880955 -291.80936) (xy 86.900246 -291.764084) (xy 86.926549 -291.722488) (xy 86.959184 -291.685651)
			(xy 86.997305 -291.654526) (xy 87.039926 -291.629919) (xy 87.085942 -291.612467) (xy 87.134161 -291.602623)
			(xy 87.183336 -291.600642) (xy 87.232191 -291.606574) (xy 87.279462 -291.620266) (xy 87.323924 -291.641364)
			(xy 87.364427 -291.66932) (xy 87.39992 -291.703412) (xy 87.429485 -291.742756) (xy 87.452356 -291.786333)
			(xy 87.46794 -291.833014) (xy 87.475835 -291.881591) (xy 87.47633 -291.906198) (xy 87.805272 -291.906198)
			(xy 87.809232 -291.857144) (xy 87.821009 -291.80936) (xy 87.8403 -291.764084) (xy 87.866603 -291.722488)
			(xy 87.899238 -291.685651) (xy 87.937359 -291.654526) (xy 87.97998 -291.629919) (xy 88.025996 -291.612467)
			(xy 88.074215 -291.602623) (xy 88.12339 -291.600642) (xy 88.172245 -291.606574) (xy 88.219516 -291.620266)
			(xy 88.263978 -291.641364) (xy 88.304481 -291.66932) (xy 88.339974 -291.703412) (xy 88.369539 -291.742756)
			(xy 88.39241 -291.786333) (xy 88.407994 -291.833014) (xy 88.415889 -291.881591) (xy 88.416384 -291.906198)
			(xy 88.745326 -291.906198) (xy 88.749286 -291.857144) (xy 88.761063 -291.80936) (xy 88.780354 -291.764084)
			(xy 88.806657 -291.722488) (xy 88.839292 -291.685651) (xy 88.877413 -291.654526) (xy 88.920034 -291.629919)
			(xy 88.96605 -291.612467) (xy 89.014269 -291.602623) (xy 89.063444 -291.600642) (xy 89.112299 -291.606574)
			(xy 89.15957 -291.620266) (xy 89.204032 -291.641364) (xy 89.244535 -291.66932) (xy 89.280028 -291.703412)
			(xy 89.309593 -291.742756) (xy 89.332464 -291.786333) (xy 89.348048 -291.833014) (xy 89.355943 -291.881591)
			(xy 89.356438 -291.906198) (xy 89.685126 -291.906198) (xy 89.689086 -291.857144) (xy 89.700863 -291.80936)
			(xy 89.720154 -291.764084) (xy 89.746457 -291.722488) (xy 89.779092 -291.685651) (xy 89.817213 -291.654526)
			(xy 89.859834 -291.629919) (xy 89.90585 -291.612467) (xy 89.954069 -291.602623) (xy 90.003244 -291.600642)
			(xy 90.052099 -291.606574) (xy 90.09937 -291.620266) (xy 90.143832 -291.641364) (xy 90.184335 -291.66932)
			(xy 90.219828 -291.703412) (xy 90.249393 -291.742756) (xy 90.272264 -291.786333) (xy 90.287848 -291.833014)
			(xy 90.295743 -291.881591) (xy 90.296238 -291.906198) (xy 90.614749 -291.906198) (xy 90.618844 -291.85547)
			(xy 90.631023 -291.806056) (xy 90.650971 -291.759236) (xy 90.678172 -291.716222) (xy 90.71192 -291.678128)
			(xy 90.751342 -291.645941) (xy 90.795416 -291.620495) (xy 90.843002 -291.602448) (xy 90.892866 -291.592268)
			(xy 90.943718 -291.590219) (xy 90.994239 -291.596353) (xy 91.043123 -291.610513) (xy 91.089102 -291.63233)
			(xy 91.130986 -291.66124) (xy 91.16769 -291.696495) (xy 91.198263 -291.737181) (xy 91.221914 -291.782244)
			(xy 91.23803 -291.830518) (xy 91.246194 -291.880752) (xy 91.246706 -291.906198) (xy 91.565234 -291.906198)
			(xy 91.569194 -291.857144) (xy 91.580971 -291.80936) (xy 91.600262 -291.764084) (xy 91.626565 -291.722488)
			(xy 91.6592 -291.685651) (xy 91.697321 -291.654526) (xy 91.739942 -291.629919) (xy 91.785958 -291.612467)
			(xy 91.834177 -291.602623) (xy 91.883352 -291.600642) (xy 91.932207 -291.606574) (xy 91.979478 -291.620266)
			(xy 92.02394 -291.641364) (xy 92.064443 -291.66932) (xy 92.099936 -291.703412) (xy 92.129501 -291.742756)
			(xy 92.152372 -291.786333) (xy 92.167956 -291.833014) (xy 92.175851 -291.881591) (xy 92.176346 -291.906198)
			(xy 92.494857 -291.906198) (xy 92.498952 -291.85547) (xy 92.511131 -291.806056) (xy 92.531079 -291.759236)
			(xy 92.55828 -291.716222) (xy 92.592028 -291.678128) (xy 92.63145 -291.645941) (xy 92.675524 -291.620495)
			(xy 92.72311 -291.602448) (xy 92.772974 -291.592268) (xy 92.823826 -291.590219) (xy 92.874347 -291.596353)
			(xy 92.923231 -291.610513) (xy 92.96921 -291.63233) (xy 93.011094 -291.66124) (xy 93.047798 -291.696495)
			(xy 93.078371 -291.737181) (xy 93.102022 -291.782244) (xy 93.118138 -291.830518) (xy 93.126302 -291.880752)
			(xy 93.126814 -291.906198) (xy 93.445342 -291.906198) (xy 93.449302 -291.857144) (xy 93.461079 -291.80936)
			(xy 93.48037 -291.764084) (xy 93.506673 -291.722488) (xy 93.539308 -291.685651) (xy 93.577429 -291.654526)
			(xy 93.62005 -291.629919) (xy 93.666066 -291.612467) (xy 93.714285 -291.602623) (xy 93.76346 -291.600642)
			(xy 93.812315 -291.606574) (xy 93.859586 -291.620266) (xy 93.904048 -291.641364) (xy 93.944551 -291.66932)
			(xy 93.980044 -291.703412) (xy 94.009609 -291.742756) (xy 94.03248 -291.786333) (xy 94.048064 -291.833014)
			(xy 94.055959 -291.881591) (xy 94.056454 -291.906198) (xy 94.374711 -291.906198) (xy 94.378806 -291.85547)
			(xy 94.390985 -291.806056) (xy 94.410933 -291.759236) (xy 94.438134 -291.716222) (xy 94.471882 -291.678128)
			(xy 94.511304 -291.645941) (xy 94.555378 -291.620495) (xy 94.602964 -291.602448) (xy 94.652828 -291.592268)
			(xy 94.70368 -291.590219) (xy 94.754201 -291.596353) (xy 94.803085 -291.610513) (xy 94.849064 -291.63233)
			(xy 94.890948 -291.66124) (xy 94.927652 -291.696495) (xy 94.958225 -291.737181) (xy 94.981876 -291.782244)
			(xy 94.997992 -291.830518) (xy 95.006156 -291.880752) (xy 95.006668 -291.906198) (xy 95.314765 -291.906198)
			(xy 95.31886 -291.85547) (xy 95.331039 -291.806056) (xy 95.350987 -291.759236) (xy 95.378188 -291.716222)
			(xy 95.411936 -291.678128) (xy 95.451358 -291.645941) (xy 95.495432 -291.620495) (xy 95.543018 -291.602448)
			(xy 95.592882 -291.592268) (xy 95.643734 -291.590219) (xy 95.694255 -291.596353) (xy 95.743139 -291.610513)
			(xy 95.789118 -291.63233) (xy 95.831002 -291.66124) (xy 95.867706 -291.696495) (xy 95.898279 -291.737181)
			(xy 95.92193 -291.782244) (xy 95.938046 -291.830518) (xy 95.94621 -291.880752) (xy 95.946722 -291.906198)
			(xy 95.94621 -291.931644) (xy 95.938046 -291.981878) (xy 95.92193 -292.030152) (xy 95.898279 -292.075215)
			(xy 95.867706 -292.115901) (xy 95.831002 -292.151156) (xy 95.789118 -292.180066) (xy 95.743139 -292.201883)
			(xy 95.694255 -292.216043) (xy 95.643734 -292.222177) (xy 95.592882 -292.220128) (xy 95.543018 -292.209948)
			(xy 95.495432 -292.191901) (xy 95.451358 -292.166455) (xy 95.411936 -292.134268) (xy 95.378188 -292.096174)
			(xy 95.350987 -292.05316) (xy 95.331039 -292.00634) (xy 95.31886 -291.956926) (xy 95.314765 -291.906198)
			(xy 95.006668 -291.906198) (xy 95.006156 -291.931644) (xy 94.997992 -291.981878) (xy 94.981876 -292.030152)
			(xy 94.958225 -292.075215) (xy 94.927652 -292.115901) (xy 94.890948 -292.151156) (xy 94.849064 -292.180066)
			(xy 94.803085 -292.201883) (xy 94.754201 -292.216043) (xy 94.70368 -292.222177) (xy 94.652828 -292.220128)
			(xy 94.602964 -292.209948) (xy 94.555378 -292.191901) (xy 94.511304 -292.166455) (xy 94.471882 -292.134268)
			(xy 94.438134 -292.096174) (xy 94.410933 -292.05316) (xy 94.390985 -292.00634) (xy 94.378806 -291.956926)
			(xy 94.374711 -291.906198) (xy 94.056454 -291.906198) (xy 94.055959 -291.930805) (xy 94.048064 -291.979382)
			(xy 94.03248 -292.026063) (xy 94.009609 -292.06964) (xy 93.980044 -292.108984) (xy 93.944551 -292.143076)
			(xy 93.904048 -292.171032) (xy 93.859586 -292.19213) (xy 93.812315 -292.205822) (xy 93.76346 -292.211754)
			(xy 93.714285 -292.209773) (xy 93.666066 -292.199929) (xy 93.62005 -292.182477) (xy 93.577429 -292.15787)
			(xy 93.539308 -292.126745) (xy 93.506673 -292.089908) (xy 93.48037 -292.048312) (xy 93.461079 -292.003036)
			(xy 93.449302 -291.955252) (xy 93.445342 -291.906198) (xy 93.126814 -291.906198) (xy 93.126302 -291.931644)
			(xy 93.118138 -291.981878) (xy 93.102022 -292.030152) (xy 93.078371 -292.075215) (xy 93.047798 -292.115901)
			(xy 93.011094 -292.151156) (xy 92.96921 -292.180066) (xy 92.923231 -292.201883) (xy 92.874347 -292.216043)
			(xy 92.823826 -292.222177) (xy 92.772974 -292.220128) (xy 92.72311 -292.209948) (xy 92.675524 -292.191901)
			(xy 92.63145 -292.166455) (xy 92.592028 -292.134268) (xy 92.55828 -292.096174) (xy 92.531079 -292.05316)
			(xy 92.511131 -292.00634) (xy 92.498952 -291.956926) (xy 92.494857 -291.906198) (xy 92.176346 -291.906198)
			(xy 92.175851 -291.930805) (xy 92.167956 -291.979382) (xy 92.152372 -292.026063) (xy 92.129501 -292.06964)
			(xy 92.099936 -292.108984) (xy 92.064443 -292.143076) (xy 92.02394 -292.171032) (xy 91.979478 -292.19213)
			(xy 91.932207 -292.205822) (xy 91.883352 -292.211754) (xy 91.834177 -292.209773) (xy 91.785958 -292.199929)
			(xy 91.739942 -292.182477) (xy 91.697321 -292.15787) (xy 91.6592 -292.126745) (xy 91.626565 -292.089908)
			(xy 91.600262 -292.048312) (xy 91.580971 -292.003036) (xy 91.569194 -291.955252) (xy 91.565234 -291.906198)
			(xy 91.246706 -291.906198) (xy 91.246194 -291.931644) (xy 91.23803 -291.981878) (xy 91.221914 -292.030152)
			(xy 91.198263 -292.075215) (xy 91.16769 -292.115901) (xy 91.130986 -292.151156) (xy 91.089102 -292.180066)
			(xy 91.043123 -292.201883) (xy 90.994239 -292.216043) (xy 90.943718 -292.222177) (xy 90.892866 -292.220128)
			(xy 90.843002 -292.209948) (xy 90.795416 -292.191901) (xy 90.751342 -292.166455) (xy 90.71192 -292.134268)
			(xy 90.678172 -292.096174) (xy 90.650971 -292.05316) (xy 90.631023 -292.00634) (xy 90.618844 -291.956926)
			(xy 90.614749 -291.906198) (xy 90.296238 -291.906198) (xy 90.295743 -291.930805) (xy 90.287848 -291.979382)
			(xy 90.272264 -292.026063) (xy 90.249393 -292.06964) (xy 90.219828 -292.108984) (xy 90.184335 -292.143076)
			(xy 90.143832 -292.171032) (xy 90.09937 -292.19213) (xy 90.052099 -292.205822) (xy 90.003244 -292.211754)
			(xy 89.954069 -292.209773) (xy 89.90585 -292.199929) (xy 89.859834 -292.182477) (xy 89.817213 -292.15787)
			(xy 89.779092 -292.126745) (xy 89.746457 -292.089908) (xy 89.720154 -292.048312) (xy 89.700863 -292.003036)
			(xy 89.689086 -291.955252) (xy 89.685126 -291.906198) (xy 89.356438 -291.906198) (xy 89.355943 -291.930805)
			(xy 89.348048 -291.979382) (xy 89.332464 -292.026063) (xy 89.309593 -292.06964) (xy 89.280028 -292.108984)
			(xy 89.244535 -292.143076) (xy 89.204032 -292.171032) (xy 89.15957 -292.19213) (xy 89.112299 -292.205822)
			(xy 89.063444 -292.211754) (xy 89.014269 -292.209773) (xy 88.96605 -292.199929) (xy 88.920034 -292.182477)
			(xy 88.877413 -292.15787) (xy 88.839292 -292.126745) (xy 88.806657 -292.089908) (xy 88.780354 -292.048312)
			(xy 88.761063 -292.003036) (xy 88.749286 -291.955252) (xy 88.745326 -291.906198) (xy 88.416384 -291.906198)
			(xy 88.415889 -291.930805) (xy 88.407994 -291.979382) (xy 88.39241 -292.026063) (xy 88.369539 -292.06964)
			(xy 88.339974 -292.108984) (xy 88.304481 -292.143076) (xy 88.263978 -292.171032) (xy 88.219516 -292.19213)
			(xy 88.172245 -292.205822) (xy 88.12339 -292.211754) (xy 88.074215 -292.209773) (xy 88.025996 -292.199929)
			(xy 87.97998 -292.182477) (xy 87.937359 -292.15787) (xy 87.899238 -292.126745) (xy 87.866603 -292.089908)
			(xy 87.8403 -292.048312) (xy 87.821009 -292.003036) (xy 87.809232 -291.955252) (xy 87.805272 -291.906198)
			(xy 87.47633 -291.906198) (xy 87.475835 -291.930805) (xy 87.46794 -291.979382) (xy 87.452356 -292.026063)
			(xy 87.429485 -292.06964) (xy 87.39992 -292.108984) (xy 87.364427 -292.143076) (xy 87.323924 -292.171032)
			(xy 87.279462 -292.19213) (xy 87.232191 -292.205822) (xy 87.183336 -292.211754) (xy 87.134161 -292.209773)
			(xy 87.085942 -292.199929) (xy 87.039926 -292.182477) (xy 86.997305 -292.15787) (xy 86.959184 -292.126745)
			(xy 86.926549 -292.089908) (xy 86.900246 -292.048312) (xy 86.880955 -292.003036) (xy 86.869178 -291.955252)
			(xy 86.865218 -291.906198) (xy 86.536276 -291.906198) (xy 86.535781 -291.930805) (xy 86.527886 -291.979382)
			(xy 86.512302 -292.026063) (xy 86.489431 -292.06964) (xy 86.459866 -292.108984) (xy 86.424373 -292.143076)
			(xy 86.38387 -292.171032) (xy 86.339408 -292.19213) (xy 86.292137 -292.205822) (xy 86.243282 -292.211754)
			(xy 86.194107 -292.209773) (xy 86.145888 -292.199929) (xy 86.099872 -292.182477) (xy 86.057251 -292.15787)
			(xy 86.01913 -292.126745) (xy 85.986495 -292.089908) (xy 85.960192 -292.048312) (xy 85.940901 -292.003036)
			(xy 85.929124 -291.955252) (xy 85.925164 -291.906198) (xy 85.596222 -291.906198) (xy 85.595727 -291.930805)
			(xy 85.587832 -291.979382) (xy 85.572248 -292.026063) (xy 85.549377 -292.06964) (xy 85.519812 -292.108984)
			(xy 85.484319 -292.143076) (xy 85.443816 -292.171032) (xy 85.399354 -292.19213) (xy 85.352083 -292.205822)
			(xy 85.303228 -292.211754) (xy 85.254053 -292.209773) (xy 85.205834 -292.199929) (xy 85.159818 -292.182477)
			(xy 85.117197 -292.15787) (xy 85.079076 -292.126745) (xy 85.046441 -292.089908) (xy 85.020138 -292.048312)
			(xy 85.000847 -292.003036) (xy 84.98907 -291.955252) (xy 84.98511 -291.906198) (xy 84.656422 -291.906198)
			(xy 84.655927 -291.930805) (xy 84.648032 -291.979382) (xy 84.632448 -292.026063) (xy 84.609577 -292.06964)
			(xy 84.580012 -292.108984) (xy 84.544519 -292.143076) (xy 84.504016 -292.171032) (xy 84.459554 -292.19213)
			(xy 84.412283 -292.205822) (xy 84.363428 -292.211754) (xy 84.314253 -292.209773) (xy 84.266034 -292.199929)
			(xy 84.220018 -292.182477) (xy 84.177397 -292.15787) (xy 84.139276 -292.126745) (xy 84.106641 -292.089908)
			(xy 84.080338 -292.048312) (xy 84.061047 -292.003036) (xy 84.04927 -291.955252) (xy 84.04531 -291.906198)
			(xy 83.716368 -291.906198) (xy 83.716368 -291.91204) (xy 83.715346 -291.937729) (xy 83.705766 -291.988235)
			(xy 83.687861 -292.036422) (xy 83.662135 -292.080929) (xy 83.629318 -292.120498) (xy 83.590336 -292.154009)
			(xy 83.54629 -292.180517) (xy 83.522566 -292.190424) (xy 83.512152 -292.194742) (xy 83.503516 -292.207442)
			(xy 83.499481 -292.213847) (xy 83.495077 -292.228323) (xy 83.49488 -292.23589) (xy 83.49488 -292.358318)
			(xy 83.495138 -292.363927) (xy 83.497829 -292.374825) (xy 83.500214 -292.379908) (xy 83.504786 -292.387782)
			(xy 83.508738 -292.392635) (xy 83.518499 -292.400463) (xy 83.52409 -292.403276) (xy 83.524344 -292.40353)
			(xy 83.605116 -292.440868) (xy 83.618832 -292.44417) (xy 83.631278 -292.444678) (xy 83.648042 -292.438328)
			(xy 83.6549 -292.435026) (xy 83.665314 -292.429184) (xy 83.6676 -292.427406) (xy 83.668616 -292.426644)
			(xy 83.66887 -292.42639) (xy 83.689157 -292.411314) (xy 83.733637 -292.38732) (xy 83.781453 -292.370952)
			(xy 83.831306 -292.362654) (xy 83.856576 -292.362128) (xy 83.882414 -292.362676) (xy 83.93335 -292.371389)
			(xy 83.982091 -292.388554) (xy 84.027247 -292.41368) (xy 84.067528 -292.446051) (xy 84.101784 -292.484741)
			(xy 84.129036 -292.528647) (xy 84.139278 -292.552374) (xy 84.142834 -292.558978) (xy 84.143088 -292.559486)
			(xy 84.156617 -292.583367) (xy 84.175868 -292.63476) (xy 84.185642 -292.688764) (xy 84.186268 -292.716204)
			(xy 84.51521 -292.716204) (xy 84.51917 -292.66715) (xy 84.530947 -292.619366) (xy 84.550238 -292.57409)
			(xy 84.576541 -292.532494) (xy 84.609176 -292.495657) (xy 84.647297 -292.464532) (xy 84.689918 -292.439925)
			(xy 84.735934 -292.422473) (xy 84.784153 -292.412629) (xy 84.833328 -292.410648) (xy 84.882183 -292.41658)
			(xy 84.929454 -292.430272) (xy 84.973916 -292.45137) (xy 85.014419 -292.479326) (xy 85.049912 -292.513418)
			(xy 85.079477 -292.552762) (xy 85.102348 -292.596339) (xy 85.117932 -292.64302) (xy 85.125827 -292.691597)
			(xy 85.126322 -292.716204) (xy 85.455264 -292.716204) (xy 85.459224 -292.66715) (xy 85.471001 -292.619366)
			(xy 85.490292 -292.57409) (xy 85.516595 -292.532494) (xy 85.54923 -292.495657) (xy 85.587351 -292.464532)
			(xy 85.629972 -292.439925) (xy 85.675988 -292.422473) (xy 85.724207 -292.412629) (xy 85.773382 -292.410648)
			(xy 85.822237 -292.41658) (xy 85.869508 -292.430272) (xy 85.91397 -292.45137) (xy 85.954473 -292.479326)
			(xy 85.989966 -292.513418) (xy 86.019531 -292.552762) (xy 86.042402 -292.596339) (xy 86.057986 -292.64302)
			(xy 86.065881 -292.691597) (xy 86.066376 -292.716204) (xy 87.335118 -292.716204) (xy 87.339078 -292.66715)
			(xy 87.350855 -292.619366) (xy 87.370146 -292.57409) (xy 87.396449 -292.532494) (xy 87.429084 -292.495657)
			(xy 87.467205 -292.464532) (xy 87.509826 -292.439925) (xy 87.555842 -292.422473) (xy 87.604061 -292.412629)
			(xy 87.653236 -292.410648) (xy 87.702091 -292.41658) (xy 87.749362 -292.430272) (xy 87.793824 -292.45137)
			(xy 87.834327 -292.479326) (xy 87.86982 -292.513418) (xy 87.899385 -292.552762) (xy 87.922256 -292.596339)
			(xy 87.93784 -292.64302) (xy 87.945735 -292.691597) (xy 87.94623 -292.716204) (xy 88.275172 -292.716204)
			(xy 88.279132 -292.66715) (xy 88.290909 -292.619366) (xy 88.3102 -292.57409) (xy 88.336503 -292.532494)
			(xy 88.369138 -292.495657) (xy 88.407259 -292.464532) (xy 88.44988 -292.439925) (xy 88.495896 -292.422473)
			(xy 88.544115 -292.412629) (xy 88.59329 -292.410648) (xy 88.642145 -292.41658) (xy 88.689416 -292.430272)
			(xy 88.733878 -292.45137) (xy 88.774381 -292.479326) (xy 88.809874 -292.513418) (xy 88.839439 -292.552762)
			(xy 88.86231 -292.596339) (xy 88.877894 -292.64302) (xy 88.885789 -292.691597) (xy 88.886284 -292.716204)
			(xy 89.215226 -292.716204) (xy 89.219186 -292.66715) (xy 89.230963 -292.619366) (xy 89.250254 -292.57409)
			(xy 89.276557 -292.532494) (xy 89.309192 -292.495657) (xy 89.347313 -292.464532) (xy 89.389934 -292.439925)
			(xy 89.43595 -292.422473) (xy 89.484169 -292.412629) (xy 89.533344 -292.410648) (xy 89.582199 -292.41658)
			(xy 89.62947 -292.430272) (xy 89.673932 -292.45137) (xy 89.714435 -292.479326) (xy 89.749928 -292.513418)
			(xy 89.779493 -292.552762) (xy 89.802364 -292.596339) (xy 89.817948 -292.64302) (xy 89.825843 -292.691597)
			(xy 89.826338 -292.716204) (xy 90.15528 -292.716204) (xy 90.15924 -292.66715) (xy 90.171017 -292.619366)
			(xy 90.190308 -292.57409) (xy 90.216611 -292.532494) (xy 90.249246 -292.495657) (xy 90.287367 -292.464532)
			(xy 90.329988 -292.439925) (xy 90.376004 -292.422473) (xy 90.424223 -292.412629) (xy 90.473398 -292.410648)
			(xy 90.522253 -292.41658) (xy 90.569524 -292.430272) (xy 90.613986 -292.45137) (xy 90.654489 -292.479326)
			(xy 90.689982 -292.513418) (xy 90.719547 -292.552762) (xy 90.742418 -292.596339) (xy 90.758002 -292.64302)
			(xy 90.765897 -292.691597) (xy 90.766392 -292.716204) (xy 91.084903 -292.716204) (xy 91.088998 -292.665476)
			(xy 91.101177 -292.616062) (xy 91.121125 -292.569242) (xy 91.148326 -292.526228) (xy 91.182074 -292.488134)
			(xy 91.221496 -292.455947) (xy 91.26557 -292.430501) (xy 91.313156 -292.412454) (xy 91.36302 -292.402274)
			(xy 91.413872 -292.400225) (xy 91.464393 -292.406359) (xy 91.513277 -292.420519) (xy 91.559256 -292.442336)
			(xy 91.60114 -292.471246) (xy 91.637844 -292.506501) (xy 91.668417 -292.547187) (xy 91.692068 -292.59225)
			(xy 91.708184 -292.640524) (xy 91.716348 -292.690758) (xy 91.71686 -292.716204) (xy 92.024703 -292.716204)
			(xy 92.028798 -292.665476) (xy 92.040977 -292.616062) (xy 92.060925 -292.569242) (xy 92.088126 -292.526228)
			(xy 92.121874 -292.488134) (xy 92.161296 -292.455947) (xy 92.20537 -292.430501) (xy 92.252956 -292.412454)
			(xy 92.30282 -292.402274) (xy 92.353672 -292.400225) (xy 92.404193 -292.406359) (xy 92.453077 -292.420519)
			(xy 92.499056 -292.442336) (xy 92.54094 -292.471246) (xy 92.577644 -292.506501) (xy 92.608217 -292.547187)
			(xy 92.631868 -292.59225) (xy 92.647984 -292.640524) (xy 92.656148 -292.690758) (xy 92.65666 -292.716204)
			(xy 93.904811 -292.716204) (xy 93.908906 -292.665476) (xy 93.921085 -292.616062) (xy 93.941033 -292.569242)
			(xy 93.968234 -292.526228) (xy 94.001982 -292.488134) (xy 94.041404 -292.455947) (xy 94.085478 -292.430501)
			(xy 94.133064 -292.412454) (xy 94.182928 -292.402274) (xy 94.23378 -292.400225) (xy 94.284301 -292.406359)
			(xy 94.333185 -292.420519) (xy 94.379164 -292.442336) (xy 94.421048 -292.471246) (xy 94.457752 -292.506501)
			(xy 94.488325 -292.547187) (xy 94.511976 -292.59225) (xy 94.528092 -292.640524) (xy 94.536256 -292.690758)
			(xy 94.536768 -292.716204) (xy 94.855296 -292.716204) (xy 94.859256 -292.66715) (xy 94.871033 -292.619366)
			(xy 94.890324 -292.57409) (xy 94.916627 -292.532494) (xy 94.949262 -292.495657) (xy 94.987383 -292.464532)
			(xy 95.030004 -292.439925) (xy 95.07602 -292.422473) (xy 95.124239 -292.412629) (xy 95.173414 -292.410648)
			(xy 95.222269 -292.41658) (xy 95.26954 -292.430272) (xy 95.314002 -292.45137) (xy 95.354505 -292.479326)
			(xy 95.389998 -292.513418) (xy 95.419563 -292.552762) (xy 95.442434 -292.596339) (xy 95.458018 -292.64302)
			(xy 95.465913 -292.691597) (xy 95.466408 -292.716204) (xy 95.784919 -292.716204) (xy 95.789014 -292.665476)
			(xy 95.801193 -292.616062) (xy 95.821141 -292.569242) (xy 95.848342 -292.526228) (xy 95.88209 -292.488134)
			(xy 95.921512 -292.455947) (xy 95.965586 -292.430501) (xy 96.013172 -292.412454) (xy 96.063036 -292.402274)
			(xy 96.113888 -292.400225) (xy 96.164409 -292.406359) (xy 96.213293 -292.420519) (xy 96.259272 -292.442336)
			(xy 96.301156 -292.471246) (xy 96.33786 -292.506501) (xy 96.368433 -292.547187) (xy 96.392084 -292.59225)
			(xy 96.4082 -292.640524) (xy 96.416364 -292.690758) (xy 96.416876 -292.716204) (xy 96.416364 -292.74165)
			(xy 96.4082 -292.791884) (xy 96.392084 -292.840158) (xy 96.368433 -292.885221) (xy 96.33786 -292.925907)
			(xy 96.301156 -292.961162) (xy 96.259272 -292.990072) (xy 96.213293 -293.011889) (xy 96.164409 -293.026049)
			(xy 96.113888 -293.032183) (xy 96.063036 -293.030134) (xy 96.013172 -293.019954) (xy 95.965586 -293.001907)
			(xy 95.921512 -292.976461) (xy 95.88209 -292.944274) (xy 95.848342 -292.90618) (xy 95.821141 -292.863166)
			(xy 95.801193 -292.816346) (xy 95.789014 -292.766932) (xy 95.784919 -292.716204) (xy 95.466408 -292.716204)
			(xy 95.465913 -292.740811) (xy 95.458018 -292.789388) (xy 95.442434 -292.836069) (xy 95.419563 -292.879646)
			(xy 95.389998 -292.91899) (xy 95.354505 -292.953082) (xy 95.314002 -292.981038) (xy 95.26954 -293.002136)
			(xy 95.222269 -293.015828) (xy 95.173414 -293.02176) (xy 95.124239 -293.019779) (xy 95.07602 -293.009935)
			(xy 95.030004 -292.992483) (xy 94.987383 -292.967876) (xy 94.949262 -292.936751) (xy 94.916627 -292.899914)
			(xy 94.890324 -292.858318) (xy 94.871033 -292.813042) (xy 94.859256 -292.765258) (xy 94.855296 -292.716204)
			(xy 94.536768 -292.716204) (xy 94.536256 -292.74165) (xy 94.528092 -292.791884) (xy 94.511976 -292.840158)
			(xy 94.488325 -292.885221) (xy 94.457752 -292.925907) (xy 94.421048 -292.961162) (xy 94.379164 -292.990072)
			(xy 94.333185 -293.011889) (xy 94.284301 -293.026049) (xy 94.23378 -293.032183) (xy 94.182928 -293.030134)
			(xy 94.133064 -293.019954) (xy 94.085478 -293.001907) (xy 94.041404 -292.976461) (xy 94.001982 -292.944274)
			(xy 93.968234 -292.90618) (xy 93.941033 -292.863166) (xy 93.921085 -292.816346) (xy 93.908906 -292.766932)
			(xy 93.904811 -292.716204) (xy 92.65666 -292.716204) (xy 92.656148 -292.74165) (xy 92.647984 -292.791884)
			(xy 92.631868 -292.840158) (xy 92.608217 -292.885221) (xy 92.577644 -292.925907) (xy 92.54094 -292.961162)
			(xy 92.499056 -292.990072) (xy 92.453077 -293.011889) (xy 92.404193 -293.026049) (xy 92.353672 -293.032183)
			(xy 92.30282 -293.030134) (xy 92.252956 -293.019954) (xy 92.20537 -293.001907) (xy 92.161296 -292.976461)
			(xy 92.121874 -292.944274) (xy 92.088126 -292.90618) (xy 92.060925 -292.863166) (xy 92.040977 -292.816346)
			(xy 92.028798 -292.766932) (xy 92.024703 -292.716204) (xy 91.71686 -292.716204) (xy 91.716348 -292.74165)
			(xy 91.708184 -292.791884) (xy 91.692068 -292.840158) (xy 91.668417 -292.885221) (xy 91.637844 -292.925907)
			(xy 91.60114 -292.961162) (xy 91.559256 -292.990072) (xy 91.513277 -293.011889) (xy 91.464393 -293.026049)
			(xy 91.413872 -293.032183) (xy 91.36302 -293.030134) (xy 91.313156 -293.019954) (xy 91.26557 -293.001907)
			(xy 91.221496 -292.976461) (xy 91.182074 -292.944274) (xy 91.148326 -292.90618) (xy 91.121125 -292.863166)
			(xy 91.101177 -292.816346) (xy 91.088998 -292.766932) (xy 91.084903 -292.716204) (xy 90.766392 -292.716204)
			(xy 90.765897 -292.740811) (xy 90.758002 -292.789388) (xy 90.742418 -292.836069) (xy 90.719547 -292.879646)
			(xy 90.689982 -292.91899) (xy 90.654489 -292.953082) (xy 90.613986 -292.981038) (xy 90.569524 -293.002136)
			(xy 90.522253 -293.015828) (xy 90.473398 -293.02176) (xy 90.424223 -293.019779) (xy 90.376004 -293.009935)
			(xy 90.329988 -292.992483) (xy 90.287367 -292.967876) (xy 90.249246 -292.936751) (xy 90.216611 -292.899914)
			(xy 90.190308 -292.858318) (xy 90.171017 -292.813042) (xy 90.15924 -292.765258) (xy 90.15528 -292.716204)
			(xy 89.826338 -292.716204) (xy 89.825843 -292.740811) (xy 89.817948 -292.789388) (xy 89.802364 -292.836069)
			(xy 89.779493 -292.879646) (xy 89.749928 -292.91899) (xy 89.714435 -292.953082) (xy 89.673932 -292.981038)
			(xy 89.62947 -293.002136) (xy 89.582199 -293.015828) (xy 89.533344 -293.02176) (xy 89.484169 -293.019779)
			(xy 89.43595 -293.009935) (xy 89.389934 -292.992483) (xy 89.347313 -292.967876) (xy 89.309192 -292.936751)
			(xy 89.276557 -292.899914) (xy 89.250254 -292.858318) (xy 89.230963 -292.813042) (xy 89.219186 -292.765258)
			(xy 89.215226 -292.716204) (xy 88.886284 -292.716204) (xy 88.885789 -292.740811) (xy 88.877894 -292.789388)
			(xy 88.86231 -292.836069) (xy 88.839439 -292.879646) (xy 88.809874 -292.91899) (xy 88.774381 -292.953082)
			(xy 88.733878 -292.981038) (xy 88.689416 -293.002136) (xy 88.642145 -293.015828) (xy 88.59329 -293.02176)
			(xy 88.544115 -293.019779) (xy 88.495896 -293.009935) (xy 88.44988 -292.992483) (xy 88.407259 -292.967876)
			(xy 88.369138 -292.936751) (xy 88.336503 -292.899914) (xy 88.3102 -292.858318) (xy 88.290909 -292.813042)
			(xy 88.279132 -292.765258) (xy 88.275172 -292.716204) (xy 87.94623 -292.716204) (xy 87.945735 -292.740811)
			(xy 87.93784 -292.789388) (xy 87.922256 -292.836069) (xy 87.899385 -292.879646) (xy 87.86982 -292.91899)
			(xy 87.834327 -292.953082) (xy 87.793824 -292.981038) (xy 87.749362 -293.002136) (xy 87.702091 -293.015828)
			(xy 87.653236 -293.02176) (xy 87.604061 -293.019779) (xy 87.555842 -293.009935) (xy 87.509826 -292.992483)
			(xy 87.467205 -292.967876) (xy 87.429084 -292.936751) (xy 87.396449 -292.899914) (xy 87.370146 -292.858318)
			(xy 87.350855 -292.813042) (xy 87.339078 -292.765258) (xy 87.335118 -292.716204) (xy 86.066376 -292.716204)
			(xy 86.065881 -292.740811) (xy 86.057986 -292.789388) (xy 86.042402 -292.836069) (xy 86.019531 -292.879646)
			(xy 85.989966 -292.91899) (xy 85.954473 -292.953082) (xy 85.91397 -292.981038) (xy 85.869508 -293.002136)
			(xy 85.822237 -293.015828) (xy 85.773382 -293.02176) (xy 85.724207 -293.019779) (xy 85.675988 -293.009935)
			(xy 85.629972 -292.992483) (xy 85.587351 -292.967876) (xy 85.54923 -292.936751) (xy 85.516595 -292.899914)
			(xy 85.490292 -292.858318) (xy 85.471001 -292.813042) (xy 85.459224 -292.765258) (xy 85.455264 -292.716204)
			(xy 85.126322 -292.716204) (xy 85.125827 -292.740811) (xy 85.117932 -292.789388) (xy 85.102348 -292.836069)
			(xy 85.079477 -292.879646) (xy 85.049912 -292.91899) (xy 85.014419 -292.953082) (xy 84.973916 -292.981038)
			(xy 84.929454 -293.002136) (xy 84.882183 -293.015828) (xy 84.833328 -293.02176) (xy 84.784153 -293.019779)
			(xy 84.735934 -293.009935) (xy 84.689918 -292.992483) (xy 84.647297 -292.967876) (xy 84.609176 -292.936751)
			(xy 84.576541 -292.899914) (xy 84.550238 -292.858318) (xy 84.530947 -292.813042) (xy 84.51917 -292.765258)
			(xy 84.51521 -292.716204) (xy 84.186268 -292.716204) (xy 84.185821 -292.740196) (xy 84.178314 -292.787588)
			(xy 84.163485 -292.833223) (xy 84.141698 -292.875976) (xy 84.113492 -292.914794) (xy 84.07956 -292.948721)
			(xy 84.040738 -292.976921) (xy 83.997982 -292.998701) (xy 83.952346 -293.013524) (xy 83.904952 -293.021025)
			(xy 83.88096 -293.021512) (xy 83.85457 -293.020961) (xy 83.802572 -293.011901) (xy 83.752906 -292.99404)
			(xy 83.707047 -292.96791) (xy 83.666361 -292.934288) (xy 83.648804 -292.914578) (xy 83.627468 -292.889432)
			(xy 83.62569 -292.889432) (xy 83.621481 -292.889514) (xy 83.613182 -292.89092) (xy 83.60918 -292.892226)
			(xy 83.521804 -292.932612) (xy 83.514026 -292.937146) (xy 83.502044 -292.950568) (xy 83.495467 -292.967314)
			(xy 83.49488 -292.9763) (xy 83.49488 -293.14521) (xy 83.494914 -293.149346) (xy 83.496193 -293.157516)
			(xy 83.49742 -293.161466) (xy 83.502246 -293.171626) (xy 83.515708 -293.192708) (xy 83.519208 -293.197971)
			(xy 83.528332 -293.206713) (xy 83.533742 -293.20998) (xy 83.533996 -293.20998) (xy 83.555756 -293.22256)
			(xy 83.595203 -293.253703) (xy 83.612482 -293.271956) (xy 83.630126 -293.292154) (xy 83.658743 -293.337506)
			(xy 83.669378 -293.362126) (xy 83.672934 -293.36873) (xy 83.673188 -293.369238) (xy 83.686703 -293.39308)
			(xy 83.705946 -293.444388) (xy 83.715743 -293.498303) (xy 83.716368 -293.525702) (xy 83.716368 -293.52621)
			(xy 84.04531 -293.52621) (xy 84.04927 -293.477156) (xy 84.061047 -293.429372) (xy 84.080338 -293.384096)
			(xy 84.106641 -293.3425) (xy 84.139276 -293.305663) (xy 84.177397 -293.274538) (xy 84.220018 -293.249931)
			(xy 84.266034 -293.232479) (xy 84.314253 -293.222635) (xy 84.363428 -293.220654) (xy 84.412283 -293.226586)
			(xy 84.459554 -293.240278) (xy 84.504016 -293.261376) (xy 84.544519 -293.289332) (xy 84.580012 -293.323424)
			(xy 84.609577 -293.362768) (xy 84.632448 -293.406345) (xy 84.648032 -293.453026) (xy 84.655927 -293.501603)
			(xy 84.656422 -293.52621) (xy 84.98511 -293.52621) (xy 84.98907 -293.477156) (xy 85.000847 -293.429372)
			(xy 85.020138 -293.384096) (xy 85.046441 -293.3425) (xy 85.079076 -293.305663) (xy 85.117197 -293.274538)
			(xy 85.159818 -293.249931) (xy 85.205834 -293.232479) (xy 85.254053 -293.222635) (xy 85.303228 -293.220654)
			(xy 85.352083 -293.226586) (xy 85.399354 -293.240278) (xy 85.443816 -293.261376) (xy 85.484319 -293.289332)
			(xy 85.519812 -293.323424) (xy 85.549377 -293.362768) (xy 85.572248 -293.406345) (xy 85.587832 -293.453026)
			(xy 85.595727 -293.501603) (xy 85.596222 -293.52621) (xy 85.925164 -293.52621) (xy 85.929124 -293.477156)
			(xy 85.940901 -293.429372) (xy 85.960192 -293.384096) (xy 85.986495 -293.3425) (xy 86.01913 -293.305663)
			(xy 86.057251 -293.274538) (xy 86.099872 -293.249931) (xy 86.145888 -293.232479) (xy 86.194107 -293.222635)
			(xy 86.243282 -293.220654) (xy 86.292137 -293.226586) (xy 86.339408 -293.240278) (xy 86.38387 -293.261376)
			(xy 86.424373 -293.289332) (xy 86.459866 -293.323424) (xy 86.489431 -293.362768) (xy 86.512302 -293.406345)
			(xy 86.527886 -293.453026) (xy 86.535781 -293.501603) (xy 86.536276 -293.52621) (xy 86.865218 -293.52621)
			(xy 86.869178 -293.477156) (xy 86.880955 -293.429372) (xy 86.900246 -293.384096) (xy 86.926549 -293.3425)
			(xy 86.959184 -293.305663) (xy 86.997305 -293.274538) (xy 87.039926 -293.249931) (xy 87.085942 -293.232479)
			(xy 87.134161 -293.222635) (xy 87.183336 -293.220654) (xy 87.232191 -293.226586) (xy 87.279462 -293.240278)
			(xy 87.323924 -293.261376) (xy 87.364427 -293.289332) (xy 87.39992 -293.323424) (xy 87.429485 -293.362768)
			(xy 87.452356 -293.406345) (xy 87.46794 -293.453026) (xy 87.475835 -293.501603) (xy 87.47633 -293.52621)
			(xy 87.805272 -293.52621) (xy 87.809232 -293.477156) (xy 87.821009 -293.429372) (xy 87.8403 -293.384096)
			(xy 87.866603 -293.3425) (xy 87.899238 -293.305663) (xy 87.937359 -293.274538) (xy 87.97998 -293.249931)
			(xy 88.025996 -293.232479) (xy 88.074215 -293.222635) (xy 88.12339 -293.220654) (xy 88.172245 -293.226586)
			(xy 88.219516 -293.240278) (xy 88.263978 -293.261376) (xy 88.304481 -293.289332) (xy 88.339974 -293.323424)
			(xy 88.369539 -293.362768) (xy 88.39241 -293.406345) (xy 88.407994 -293.453026) (xy 88.415889 -293.501603)
			(xy 88.416384 -293.52621) (xy 88.745326 -293.52621) (xy 88.749286 -293.477156) (xy 88.761063 -293.429372)
			(xy 88.780354 -293.384096) (xy 88.806657 -293.3425) (xy 88.839292 -293.305663) (xy 88.877413 -293.274538)
			(xy 88.920034 -293.249931) (xy 88.96605 -293.232479) (xy 89.014269 -293.222635) (xy 89.063444 -293.220654)
			(xy 89.112299 -293.226586) (xy 89.15957 -293.240278) (xy 89.204032 -293.261376) (xy 89.244535 -293.289332)
			(xy 89.280028 -293.323424) (xy 89.309593 -293.362768) (xy 89.332464 -293.406345) (xy 89.348048 -293.453026)
			(xy 89.355943 -293.501603) (xy 89.356438 -293.52621) (xy 89.685126 -293.52621) (xy 89.689086 -293.477156)
			(xy 89.700863 -293.429372) (xy 89.720154 -293.384096) (xy 89.746457 -293.3425) (xy 89.779092 -293.305663)
			(xy 89.817213 -293.274538) (xy 89.859834 -293.249931) (xy 89.90585 -293.232479) (xy 89.954069 -293.222635)
			(xy 90.003244 -293.220654) (xy 90.052099 -293.226586) (xy 90.09937 -293.240278) (xy 90.143832 -293.261376)
			(xy 90.184335 -293.289332) (xy 90.219828 -293.323424) (xy 90.249393 -293.362768) (xy 90.272264 -293.406345)
			(xy 90.287848 -293.453026) (xy 90.295743 -293.501603) (xy 90.296238 -293.52621) (xy 90.614749 -293.52621)
			(xy 90.618844 -293.475482) (xy 90.631023 -293.426068) (xy 90.650971 -293.379248) (xy 90.678172 -293.336234)
			(xy 90.71192 -293.29814) (xy 90.751342 -293.265953) (xy 90.795416 -293.240507) (xy 90.843002 -293.22246)
			(xy 90.892866 -293.21228) (xy 90.943718 -293.210231) (xy 90.994239 -293.216365) (xy 91.043123 -293.230525)
			(xy 91.089102 -293.252342) (xy 91.130986 -293.281252) (xy 91.16769 -293.316507) (xy 91.198263 -293.357193)
			(xy 91.221914 -293.402256) (xy 91.23803 -293.45053) (xy 91.246194 -293.500764) (xy 91.246706 -293.52621)
			(xy 91.565234 -293.52621) (xy 91.569194 -293.477156) (xy 91.580971 -293.429372) (xy 91.600262 -293.384096)
			(xy 91.626565 -293.3425) (xy 91.6592 -293.305663) (xy 91.697321 -293.274538) (xy 91.739942 -293.249931)
			(xy 91.785958 -293.232479) (xy 91.834177 -293.222635) (xy 91.883352 -293.220654) (xy 91.932207 -293.226586)
			(xy 91.979478 -293.240278) (xy 92.02394 -293.261376) (xy 92.064443 -293.289332) (xy 92.099936 -293.323424)
			(xy 92.129501 -293.362768) (xy 92.152372 -293.406345) (xy 92.167956 -293.453026) (xy 92.175851 -293.501603)
			(xy 92.176346 -293.52621) (xy 92.505288 -293.52621) (xy 92.509248 -293.477156) (xy 92.521025 -293.429372)
			(xy 92.540316 -293.384096) (xy 92.566619 -293.3425) (xy 92.599254 -293.305663) (xy 92.637375 -293.274538)
			(xy 92.679996 -293.249931) (xy 92.726012 -293.232479) (xy 92.774231 -293.222635) (xy 92.823406 -293.220654)
			(xy 92.872261 -293.226586) (xy 92.919532 -293.240278) (xy 92.963994 -293.261376) (xy 93.004497 -293.289332)
			(xy 93.03999 -293.323424) (xy 93.069555 -293.362768) (xy 93.092426 -293.406345) (xy 93.10801 -293.453026)
			(xy 93.115905 -293.501603) (xy 93.1164 -293.52621) (xy 93.445342 -293.52621) (xy 93.449302 -293.477156)
			(xy 93.461079 -293.429372) (xy 93.48037 -293.384096) (xy 93.506673 -293.3425) (xy 93.539308 -293.305663)
			(xy 93.577429 -293.274538) (xy 93.62005 -293.249931) (xy 93.666066 -293.232479) (xy 93.714285 -293.222635)
			(xy 93.76346 -293.220654) (xy 93.812315 -293.226586) (xy 93.859586 -293.240278) (xy 93.904048 -293.261376)
			(xy 93.944551 -293.289332) (xy 93.980044 -293.323424) (xy 94.009609 -293.362768) (xy 94.03248 -293.406345)
			(xy 94.048064 -293.453026) (xy 94.055959 -293.501603) (xy 94.056454 -293.52621) (xy 94.385142 -293.52621)
			(xy 94.389102 -293.477156) (xy 94.400879 -293.429372) (xy 94.42017 -293.384096) (xy 94.446473 -293.3425)
			(xy 94.479108 -293.305663) (xy 94.517229 -293.274538) (xy 94.55985 -293.249931) (xy 94.605866 -293.232479)
			(xy 94.654085 -293.222635) (xy 94.70326 -293.220654) (xy 94.752115 -293.226586) (xy 94.799386 -293.240278)
			(xy 94.843848 -293.261376) (xy 94.884351 -293.289332) (xy 94.919844 -293.323424) (xy 94.949409 -293.362768)
			(xy 94.97228 -293.406345) (xy 94.987864 -293.453026) (xy 94.995759 -293.501603) (xy 94.996254 -293.52621)
			(xy 95.314765 -293.52621) (xy 95.31886 -293.475482) (xy 95.331039 -293.426068) (xy 95.350987 -293.379248)
			(xy 95.378188 -293.336234) (xy 95.411936 -293.29814) (xy 95.451358 -293.265953) (xy 95.495432 -293.240507)
			(xy 95.543018 -293.22246) (xy 95.592882 -293.21228) (xy 95.643734 -293.210231) (xy 95.694255 -293.216365)
			(xy 95.743139 -293.230525) (xy 95.789118 -293.252342) (xy 95.831002 -293.281252) (xy 95.867706 -293.316507)
			(xy 95.898279 -293.357193) (xy 95.92193 -293.402256) (xy 95.938046 -293.45053) (xy 95.94621 -293.500764)
			(xy 95.946722 -293.52621) (xy 95.94621 -293.551656) (xy 95.938046 -293.60189) (xy 95.92193 -293.650164)
			(xy 95.898279 -293.695227) (xy 95.867706 -293.735913) (xy 95.831002 -293.771168) (xy 95.789118 -293.800078)
			(xy 95.743139 -293.821895) (xy 95.694255 -293.836055) (xy 95.643734 -293.842189) (xy 95.592882 -293.84014)
			(xy 95.543018 -293.82996) (xy 95.495432 -293.811913) (xy 95.451358 -293.786467) (xy 95.411936 -293.75428)
			(xy 95.378188 -293.716186) (xy 95.350987 -293.673172) (xy 95.331039 -293.626352) (xy 95.31886 -293.576938)
			(xy 95.314765 -293.52621) (xy 94.996254 -293.52621) (xy 94.995759 -293.550817) (xy 94.987864 -293.599394)
			(xy 94.97228 -293.646075) (xy 94.949409 -293.689652) (xy 94.919844 -293.728996) (xy 94.884351 -293.763088)
			(xy 94.843848 -293.791044) (xy 94.799386 -293.812142) (xy 94.752115 -293.825834) (xy 94.70326 -293.831766)
			(xy 94.654085 -293.829785) (xy 94.605866 -293.819941) (xy 94.55985 -293.802489) (xy 94.517229 -293.777882)
			(xy 94.479108 -293.746757) (xy 94.446473 -293.70992) (xy 94.42017 -293.668324) (xy 94.400879 -293.623048)
			(xy 94.389102 -293.575264) (xy 94.385142 -293.52621) (xy 94.056454 -293.52621) (xy 94.055959 -293.550817)
			(xy 94.048064 -293.599394) (xy 94.03248 -293.646075) (xy 94.009609 -293.689652) (xy 93.980044 -293.728996)
			(xy 93.944551 -293.763088) (xy 93.904048 -293.791044) (xy 93.859586 -293.812142) (xy 93.812315 -293.825834)
			(xy 93.76346 -293.831766) (xy 93.714285 -293.829785) (xy 93.666066 -293.819941) (xy 93.62005 -293.802489)
			(xy 93.577429 -293.777882) (xy 93.539308 -293.746757) (xy 93.506673 -293.70992) (xy 93.48037 -293.668324)
			(xy 93.461079 -293.623048) (xy 93.449302 -293.575264) (xy 93.445342 -293.52621) (xy 93.1164 -293.52621)
			(xy 93.115905 -293.550817) (xy 93.10801 -293.599394) (xy 93.092426 -293.646075) (xy 93.069555 -293.689652)
			(xy 93.03999 -293.728996) (xy 93.004497 -293.763088) (xy 92.963994 -293.791044) (xy 92.919532 -293.812142)
			(xy 92.872261 -293.825834) (xy 92.823406 -293.831766) (xy 92.774231 -293.829785) (xy 92.726012 -293.819941)
			(xy 92.679996 -293.802489) (xy 92.637375 -293.777882) (xy 92.599254 -293.746757) (xy 92.566619 -293.70992)
			(xy 92.540316 -293.668324) (xy 92.521025 -293.623048) (xy 92.509248 -293.575264) (xy 92.505288 -293.52621)
			(xy 92.176346 -293.52621) (xy 92.175851 -293.550817) (xy 92.167956 -293.599394) (xy 92.152372 -293.646075)
			(xy 92.129501 -293.689652) (xy 92.099936 -293.728996) (xy 92.064443 -293.763088) (xy 92.02394 -293.791044)
			(xy 91.979478 -293.812142) (xy 91.932207 -293.825834) (xy 91.883352 -293.831766) (xy 91.834177 -293.829785)
			(xy 91.785958 -293.819941) (xy 91.739942 -293.802489) (xy 91.697321 -293.777882) (xy 91.6592 -293.746757)
			(xy 91.626565 -293.70992) (xy 91.600262 -293.668324) (xy 91.580971 -293.623048) (xy 91.569194 -293.575264)
			(xy 91.565234 -293.52621) (xy 91.246706 -293.52621) (xy 91.246194 -293.551656) (xy 91.23803 -293.60189)
			(xy 91.221914 -293.650164) (xy 91.198263 -293.695227) (xy 91.16769 -293.735913) (xy 91.130986 -293.771168)
			(xy 91.089102 -293.800078) (xy 91.043123 -293.821895) (xy 90.994239 -293.836055) (xy 90.943718 -293.842189)
			(xy 90.892866 -293.84014) (xy 90.843002 -293.82996) (xy 90.795416 -293.811913) (xy 90.751342 -293.786467)
			(xy 90.71192 -293.75428) (xy 90.678172 -293.716186) (xy 90.650971 -293.673172) (xy 90.631023 -293.626352)
			(xy 90.618844 -293.576938) (xy 90.614749 -293.52621) (xy 90.296238 -293.52621) (xy 90.295743 -293.550817)
			(xy 90.287848 -293.599394) (xy 90.272264 -293.646075) (xy 90.249393 -293.689652) (xy 90.219828 -293.728996)
			(xy 90.184335 -293.763088) (xy 90.143832 -293.791044) (xy 90.09937 -293.812142) (xy 90.052099 -293.825834)
			(xy 90.003244 -293.831766) (xy 89.954069 -293.829785) (xy 89.90585 -293.819941) (xy 89.859834 -293.802489)
			(xy 89.817213 -293.777882) (xy 89.779092 -293.746757) (xy 89.746457 -293.70992) (xy 89.720154 -293.668324)
			(xy 89.700863 -293.623048) (xy 89.689086 -293.575264) (xy 89.685126 -293.52621) (xy 89.356438 -293.52621)
			(xy 89.355943 -293.550817) (xy 89.348048 -293.599394) (xy 89.332464 -293.646075) (xy 89.309593 -293.689652)
			(xy 89.280028 -293.728996) (xy 89.244535 -293.763088) (xy 89.204032 -293.791044) (xy 89.15957 -293.812142)
			(xy 89.112299 -293.825834) (xy 89.063444 -293.831766) (xy 89.014269 -293.829785) (xy 88.96605 -293.819941)
			(xy 88.920034 -293.802489) (xy 88.877413 -293.777882) (xy 88.839292 -293.746757) (xy 88.806657 -293.70992)
			(xy 88.780354 -293.668324) (xy 88.761063 -293.623048) (xy 88.749286 -293.575264) (xy 88.745326 -293.52621)
			(xy 88.416384 -293.52621) (xy 88.415889 -293.550817) (xy 88.407994 -293.599394) (xy 88.39241 -293.646075)
			(xy 88.369539 -293.689652) (xy 88.339974 -293.728996) (xy 88.304481 -293.763088) (xy 88.263978 -293.791044)
			(xy 88.219516 -293.812142) (xy 88.172245 -293.825834) (xy 88.12339 -293.831766) (xy 88.074215 -293.829785)
			(xy 88.025996 -293.819941) (xy 87.97998 -293.802489) (xy 87.937359 -293.777882) (xy 87.899238 -293.746757)
			(xy 87.866603 -293.70992) (xy 87.8403 -293.668324) (xy 87.821009 -293.623048) (xy 87.809232 -293.575264)
			(xy 87.805272 -293.52621) (xy 87.47633 -293.52621) (xy 87.475835 -293.550817) (xy 87.46794 -293.599394)
			(xy 87.452356 -293.646075) (xy 87.429485 -293.689652) (xy 87.39992 -293.728996) (xy 87.364427 -293.763088)
			(xy 87.323924 -293.791044) (xy 87.279462 -293.812142) (xy 87.232191 -293.825834) (xy 87.183336 -293.831766)
			(xy 87.134161 -293.829785) (xy 87.085942 -293.819941) (xy 87.039926 -293.802489) (xy 86.997305 -293.777882)
			(xy 86.959184 -293.746757) (xy 86.926549 -293.70992) (xy 86.900246 -293.668324) (xy 86.880955 -293.623048)
			(xy 86.869178 -293.575264) (xy 86.865218 -293.52621) (xy 86.536276 -293.52621) (xy 86.535781 -293.550817)
			(xy 86.527886 -293.599394) (xy 86.512302 -293.646075) (xy 86.489431 -293.689652) (xy 86.459866 -293.728996)
			(xy 86.424373 -293.763088) (xy 86.38387 -293.791044) (xy 86.339408 -293.812142) (xy 86.292137 -293.825834)
			(xy 86.243282 -293.831766) (xy 86.194107 -293.829785) (xy 86.145888 -293.819941) (xy 86.099872 -293.802489)
			(xy 86.057251 -293.777882) (xy 86.01913 -293.746757) (xy 85.986495 -293.70992) (xy 85.960192 -293.668324)
			(xy 85.940901 -293.623048) (xy 85.929124 -293.575264) (xy 85.925164 -293.52621) (xy 85.596222 -293.52621)
			(xy 85.595727 -293.550817) (xy 85.587832 -293.599394) (xy 85.572248 -293.646075) (xy 85.549377 -293.689652)
			(xy 85.519812 -293.728996) (xy 85.484319 -293.763088) (xy 85.443816 -293.791044) (xy 85.399354 -293.812142)
			(xy 85.352083 -293.825834) (xy 85.303228 -293.831766) (xy 85.254053 -293.829785) (xy 85.205834 -293.819941)
			(xy 85.159818 -293.802489) (xy 85.117197 -293.777882) (xy 85.079076 -293.746757) (xy 85.046441 -293.70992)
			(xy 85.020138 -293.668324) (xy 85.000847 -293.623048) (xy 84.98907 -293.575264) (xy 84.98511 -293.52621)
			(xy 84.656422 -293.52621) (xy 84.655927 -293.550817) (xy 84.648032 -293.599394) (xy 84.632448 -293.646075)
			(xy 84.609577 -293.689652) (xy 84.580012 -293.728996) (xy 84.544519 -293.763088) (xy 84.504016 -293.791044)
			(xy 84.459554 -293.812142) (xy 84.412283 -293.825834) (xy 84.363428 -293.831766) (xy 84.314253 -293.829785)
			(xy 84.266034 -293.819941) (xy 84.220018 -293.802489) (xy 84.177397 -293.777882) (xy 84.139276 -293.746757)
			(xy 84.106641 -293.70992) (xy 84.080338 -293.668324) (xy 84.061047 -293.623048) (xy 84.04927 -293.575264)
			(xy 84.04531 -293.52621) (xy 83.716368 -293.52621) (xy 83.716368 -293.532052) (xy 83.715353 -293.557745)
			(xy 83.705785 -293.608261) (xy 83.687888 -293.65646) (xy 83.662168 -293.700979) (xy 83.629353 -293.740559)
			(xy 83.59037 -293.774082) (xy 83.546322 -293.800599) (xy 83.522566 -293.810436) (xy 83.512152 -293.814754)
			(xy 83.503516 -293.827454) (xy 83.499482 -293.833859) (xy 83.495082 -293.848336) (xy 83.49488 -293.855902)
			(xy 83.49488 -293.97833) (xy 83.49514 -293.983939) (xy 83.497832 -293.994836) (xy 83.500214 -293.99992)
			(xy 83.504786 -294.007794) (xy 83.508733 -294.012653) (xy 83.518488 -294.020494) (xy 83.52409 -294.023288)
			(xy 83.524344 -294.023542) (xy 83.605116 -294.06088) (xy 83.618832 -294.064182) (xy 83.631278 -294.06469)
			(xy 83.648042 -294.05834) (xy 83.6549 -294.055038) (xy 83.665314 -294.049196) (xy 83.6676 -294.047418)
			(xy 83.668616 -294.046656) (xy 83.66887 -294.046402) (xy 83.689158 -294.03133) (xy 83.73364 -294.007343)
			(xy 83.781455 -293.99098) (xy 83.831307 -293.982684) (xy 83.856576 -293.98214) (xy 83.882414 -293.982688)
			(xy 83.933349 -293.991401) (xy 83.98209 -294.008566) (xy 84.027245 -294.033693) (xy 84.067525 -294.066064)
			(xy 84.101779 -294.104755) (xy 84.12903 -294.148661) (xy 84.139278 -294.172386) (xy 84.142834 -294.17899)
			(xy 84.143088 -294.179498) (xy 84.156624 -294.203377) (xy 84.17589 -294.254769) (xy 84.185679 -294.308774)
			(xy 84.186268 -294.336216) (xy 84.51521 -294.336216) (xy 84.51917 -294.287162) (xy 84.530947 -294.239378)
			(xy 84.550238 -294.194102) (xy 84.576541 -294.152506) (xy 84.609176 -294.115669) (xy 84.647297 -294.084544)
			(xy 84.689918 -294.059937) (xy 84.735934 -294.042485) (xy 84.784153 -294.032641) (xy 84.833328 -294.03066)
			(xy 84.882183 -294.036592) (xy 84.929454 -294.050284) (xy 84.973916 -294.071382) (xy 85.014419 -294.099338)
			(xy 85.049912 -294.13343) (xy 85.079477 -294.172774) (xy 85.102348 -294.216351) (xy 85.117932 -294.263032)
			(xy 85.125827 -294.311609) (xy 85.126322 -294.336216) (xy 85.455264 -294.336216) (xy 85.459224 -294.287162)
			(xy 85.471001 -294.239378) (xy 85.490292 -294.194102) (xy 85.516595 -294.152506) (xy 85.54923 -294.115669)
			(xy 85.587351 -294.084544) (xy 85.629972 -294.059937) (xy 85.675988 -294.042485) (xy 85.724207 -294.032641)
			(xy 85.773382 -294.03066) (xy 85.822237 -294.036592) (xy 85.869508 -294.050284) (xy 85.91397 -294.071382)
			(xy 85.954473 -294.099338) (xy 85.989966 -294.13343) (xy 86.019531 -294.172774) (xy 86.042402 -294.216351)
			(xy 86.057986 -294.263032) (xy 86.065881 -294.311609) (xy 86.066376 -294.336216) (xy 86.395318 -294.336216)
			(xy 86.399278 -294.287162) (xy 86.411055 -294.239378) (xy 86.430346 -294.194102) (xy 86.456649 -294.152506)
			(xy 86.489284 -294.115669) (xy 86.527405 -294.084544) (xy 86.570026 -294.059937) (xy 86.616042 -294.042485)
			(xy 86.664261 -294.032641) (xy 86.713436 -294.03066) (xy 86.762291 -294.036592) (xy 86.809562 -294.050284)
			(xy 86.854024 -294.071382) (xy 86.894527 -294.099338) (xy 86.93002 -294.13343) (xy 86.959585 -294.172774)
			(xy 86.982456 -294.216351) (xy 86.99804 -294.263032) (xy 87.005935 -294.311609) (xy 87.00643 -294.336216)
			(xy 88.275172 -294.336216) (xy 88.279132 -294.287162) (xy 88.290909 -294.239378) (xy 88.3102 -294.194102)
			(xy 88.336503 -294.152506) (xy 88.369138 -294.115669) (xy 88.407259 -294.084544) (xy 88.44988 -294.059937)
			(xy 88.495896 -294.042485) (xy 88.544115 -294.032641) (xy 88.59329 -294.03066) (xy 88.642145 -294.036592)
			(xy 88.689416 -294.050284) (xy 88.733878 -294.071382) (xy 88.774381 -294.099338) (xy 88.809874 -294.13343)
			(xy 88.839439 -294.172774) (xy 88.86231 -294.216351) (xy 88.877894 -294.263032) (xy 88.885789 -294.311609)
			(xy 88.886284 -294.336216) (xy 89.215226 -294.336216) (xy 89.219186 -294.287162) (xy 89.230963 -294.239378)
			(xy 89.250254 -294.194102) (xy 89.276557 -294.152506) (xy 89.309192 -294.115669) (xy 89.347313 -294.084544)
			(xy 89.389934 -294.059937) (xy 89.43595 -294.042485) (xy 89.484169 -294.032641) (xy 89.533344 -294.03066)
			(xy 89.582199 -294.036592) (xy 89.62947 -294.050284) (xy 89.673932 -294.071382) (xy 89.714435 -294.099338)
			(xy 89.749928 -294.13343) (xy 89.779493 -294.172774) (xy 89.802364 -294.216351) (xy 89.817948 -294.263032)
			(xy 89.825843 -294.311609) (xy 89.826338 -294.336216) (xy 90.15528 -294.336216) (xy 90.15924 -294.287162)
			(xy 90.171017 -294.239378) (xy 90.190308 -294.194102) (xy 90.216611 -294.152506) (xy 90.249246 -294.115669)
			(xy 90.287367 -294.084544) (xy 90.329988 -294.059937) (xy 90.376004 -294.042485) (xy 90.424223 -294.032641)
			(xy 90.473398 -294.03066) (xy 90.522253 -294.036592) (xy 90.569524 -294.050284) (xy 90.613986 -294.071382)
			(xy 90.654489 -294.099338) (xy 90.689982 -294.13343) (xy 90.719547 -294.172774) (xy 90.742418 -294.216351)
			(xy 90.758002 -294.263032) (xy 90.765897 -294.311609) (xy 90.766392 -294.336216) (xy 91.095334 -294.336216)
			(xy 91.099294 -294.287162) (xy 91.111071 -294.239378) (xy 91.130362 -294.194102) (xy 91.156665 -294.152506)
			(xy 91.1893 -294.115669) (xy 91.227421 -294.084544) (xy 91.270042 -294.059937) (xy 91.316058 -294.042485)
			(xy 91.364277 -294.032641) (xy 91.413452 -294.03066) (xy 91.462307 -294.036592) (xy 91.509578 -294.050284)
			(xy 91.55404 -294.071382) (xy 91.594543 -294.099338) (xy 91.630036 -294.13343) (xy 91.659601 -294.172774)
			(xy 91.682472 -294.216351) (xy 91.698056 -294.263032) (xy 91.705951 -294.311609) (xy 91.706446 -294.336216)
			(xy 92.035134 -294.336216) (xy 92.039094 -294.287162) (xy 92.050871 -294.239378) (xy 92.070162 -294.194102)
			(xy 92.096465 -294.152506) (xy 92.1291 -294.115669) (xy 92.167221 -294.084544) (xy 92.209842 -294.059937)
			(xy 92.255858 -294.042485) (xy 92.304077 -294.032641) (xy 92.353252 -294.03066) (xy 92.402107 -294.036592)
			(xy 92.449378 -294.050284) (xy 92.49384 -294.071382) (xy 92.534343 -294.099338) (xy 92.569836 -294.13343)
			(xy 92.599401 -294.172774) (xy 92.622272 -294.216351) (xy 92.637856 -294.263032) (xy 92.645751 -294.311609)
			(xy 92.646246 -294.336216) (xy 92.975188 -294.336216) (xy 92.979148 -294.287162) (xy 92.990925 -294.239378)
			(xy 93.010216 -294.194102) (xy 93.036519 -294.152506) (xy 93.069154 -294.115669) (xy 93.107275 -294.084544)
			(xy 93.149896 -294.059937) (xy 93.195912 -294.042485) (xy 93.244131 -294.032641) (xy 93.293306 -294.03066)
			(xy 93.342161 -294.036592) (xy 93.389432 -294.050284) (xy 93.433894 -294.071382) (xy 93.474397 -294.099338)
			(xy 93.50989 -294.13343) (xy 93.539455 -294.172774) (xy 93.562326 -294.216351) (xy 93.57791 -294.263032)
			(xy 93.585805 -294.311609) (xy 93.5863 -294.336216) (xy 93.915242 -294.336216) (xy 93.919202 -294.287162)
			(xy 93.930979 -294.239378) (xy 93.95027 -294.194102) (xy 93.976573 -294.152506) (xy 94.009208 -294.115669)
			(xy 94.047329 -294.084544) (xy 94.08995 -294.059937) (xy 94.135966 -294.042485) (xy 94.184185 -294.032641)
			(xy 94.23336 -294.03066) (xy 94.282215 -294.036592) (xy 94.329486 -294.050284) (xy 94.373948 -294.071382)
			(xy 94.414451 -294.099338) (xy 94.449944 -294.13343) (xy 94.479509 -294.172774) (xy 94.50238 -294.216351)
			(xy 94.517964 -294.263032) (xy 94.525859 -294.311609) (xy 94.526354 -294.336216) (xy 94.855296 -294.336216)
			(xy 94.859256 -294.287162) (xy 94.871033 -294.239378) (xy 94.890324 -294.194102) (xy 94.916627 -294.152506)
			(xy 94.949262 -294.115669) (xy 94.987383 -294.084544) (xy 95.030004 -294.059937) (xy 95.07602 -294.042485)
			(xy 95.124239 -294.032641) (xy 95.173414 -294.03066) (xy 95.222269 -294.036592) (xy 95.26954 -294.050284)
			(xy 95.314002 -294.071382) (xy 95.354505 -294.099338) (xy 95.389998 -294.13343) (xy 95.419563 -294.172774)
			(xy 95.442434 -294.216351) (xy 95.458018 -294.263032) (xy 95.465913 -294.311609) (xy 95.466408 -294.336216)
			(xy 95.79535 -294.336216) (xy 95.79931 -294.287162) (xy 95.811087 -294.239378) (xy 95.830378 -294.194102)
			(xy 95.856681 -294.152506) (xy 95.889316 -294.115669) (xy 95.927437 -294.084544) (xy 95.970058 -294.059937)
			(xy 96.016074 -294.042485) (xy 96.064293 -294.032641) (xy 96.113468 -294.03066) (xy 96.162323 -294.036592)
			(xy 96.209594 -294.050284) (xy 96.254056 -294.071382) (xy 96.294559 -294.099338) (xy 96.330052 -294.13343)
			(xy 96.359617 -294.172774) (xy 96.382488 -294.216351) (xy 96.398072 -294.263032) (xy 96.405967 -294.311609)
			(xy 96.406462 -294.336216) (xy 96.405967 -294.360823) (xy 96.398072 -294.4094) (xy 96.382488 -294.456081)
			(xy 96.359617 -294.499658) (xy 96.330052 -294.539002) (xy 96.294559 -294.573094) (xy 96.254056 -294.60105)
			(xy 96.209594 -294.622148) (xy 96.162323 -294.63584) (xy 96.113468 -294.641772) (xy 96.064293 -294.639791)
			(xy 96.016074 -294.629947) (xy 95.970058 -294.612495) (xy 95.927437 -294.587888) (xy 95.889316 -294.556763)
			(xy 95.856681 -294.519926) (xy 95.830378 -294.47833) (xy 95.811087 -294.433054) (xy 95.79931 -294.38527)
			(xy 95.79535 -294.336216) (xy 95.466408 -294.336216) (xy 95.465913 -294.360823) (xy 95.458018 -294.4094)
			(xy 95.442434 -294.456081) (xy 95.419563 -294.499658) (xy 95.389998 -294.539002) (xy 95.354505 -294.573094)
			(xy 95.314002 -294.60105) (xy 95.26954 -294.622148) (xy 95.222269 -294.63584) (xy 95.173414 -294.641772)
			(xy 95.124239 -294.639791) (xy 95.07602 -294.629947) (xy 95.030004 -294.612495) (xy 94.987383 -294.587888)
			(xy 94.949262 -294.556763) (xy 94.916627 -294.519926) (xy 94.890324 -294.47833) (xy 94.871033 -294.433054)
			(xy 94.859256 -294.38527) (xy 94.855296 -294.336216) (xy 94.526354 -294.336216) (xy 94.525859 -294.360823)
			(xy 94.517964 -294.4094) (xy 94.50238 -294.456081) (xy 94.479509 -294.499658) (xy 94.449944 -294.539002)
			(xy 94.414451 -294.573094) (xy 94.373948 -294.60105) (xy 94.329486 -294.622148) (xy 94.282215 -294.63584)
			(xy 94.23336 -294.641772) (xy 94.184185 -294.639791) (xy 94.135966 -294.629947) (xy 94.08995 -294.612495)
			(xy 94.047329 -294.587888) (xy 94.009208 -294.556763) (xy 93.976573 -294.519926) (xy 93.95027 -294.47833)
			(xy 93.930979 -294.433054) (xy 93.919202 -294.38527) (xy 93.915242 -294.336216) (xy 93.5863 -294.336216)
			(xy 93.585805 -294.360823) (xy 93.57791 -294.4094) (xy 93.562326 -294.456081) (xy 93.539455 -294.499658)
			(xy 93.50989 -294.539002) (xy 93.474397 -294.573094) (xy 93.433894 -294.60105) (xy 93.389432 -294.622148)
			(xy 93.342161 -294.63584) (xy 93.293306 -294.641772) (xy 93.244131 -294.639791) (xy 93.195912 -294.629947)
			(xy 93.149896 -294.612495) (xy 93.107275 -294.587888) (xy 93.069154 -294.556763) (xy 93.036519 -294.519926)
			(xy 93.010216 -294.47833) (xy 92.990925 -294.433054) (xy 92.979148 -294.38527) (xy 92.975188 -294.336216)
			(xy 92.646246 -294.336216) (xy 92.645751 -294.360823) (xy 92.637856 -294.4094) (xy 92.622272 -294.456081)
			(xy 92.599401 -294.499658) (xy 92.569836 -294.539002) (xy 92.534343 -294.573094) (xy 92.49384 -294.60105)
			(xy 92.449378 -294.622148) (xy 92.402107 -294.63584) (xy 92.353252 -294.641772) (xy 92.304077 -294.639791)
			(xy 92.255858 -294.629947) (xy 92.209842 -294.612495) (xy 92.167221 -294.587888) (xy 92.1291 -294.556763)
			(xy 92.096465 -294.519926) (xy 92.070162 -294.47833) (xy 92.050871 -294.433054) (xy 92.039094 -294.38527)
			(xy 92.035134 -294.336216) (xy 91.706446 -294.336216) (xy 91.705951 -294.360823) (xy 91.698056 -294.4094)
			(xy 91.682472 -294.456081) (xy 91.659601 -294.499658) (xy 91.630036 -294.539002) (xy 91.594543 -294.573094)
			(xy 91.55404 -294.60105) (xy 91.509578 -294.622148) (xy 91.462307 -294.63584) (xy 91.413452 -294.641772)
			(xy 91.364277 -294.639791) (xy 91.316058 -294.629947) (xy 91.270042 -294.612495) (xy 91.227421 -294.587888)
			(xy 91.1893 -294.556763) (xy 91.156665 -294.519926) (xy 91.130362 -294.47833) (xy 91.111071 -294.433054)
			(xy 91.099294 -294.38527) (xy 91.095334 -294.336216) (xy 90.766392 -294.336216) (xy 90.765897 -294.360823)
			(xy 90.758002 -294.4094) (xy 90.742418 -294.456081) (xy 90.719547 -294.499658) (xy 90.689982 -294.539002)
			(xy 90.654489 -294.573094) (xy 90.613986 -294.60105) (xy 90.569524 -294.622148) (xy 90.522253 -294.63584)
			(xy 90.473398 -294.641772) (xy 90.424223 -294.639791) (xy 90.376004 -294.629947) (xy 90.329988 -294.612495)
			(xy 90.287367 -294.587888) (xy 90.249246 -294.556763) (xy 90.216611 -294.519926) (xy 90.190308 -294.47833)
			(xy 90.171017 -294.433054) (xy 90.15924 -294.38527) (xy 90.15528 -294.336216) (xy 89.826338 -294.336216)
			(xy 89.825843 -294.360823) (xy 89.817948 -294.4094) (xy 89.802364 -294.456081) (xy 89.779493 -294.499658)
			(xy 89.749928 -294.539002) (xy 89.714435 -294.573094) (xy 89.673932 -294.60105) (xy 89.62947 -294.622148)
			(xy 89.582199 -294.63584) (xy 89.533344 -294.641772) (xy 89.484169 -294.639791) (xy 89.43595 -294.629947)
			(xy 89.389934 -294.612495) (xy 89.347313 -294.587888) (xy 89.309192 -294.556763) (xy 89.276557 -294.519926)
			(xy 89.250254 -294.47833) (xy 89.230963 -294.433054) (xy 89.219186 -294.38527) (xy 89.215226 -294.336216)
			(xy 88.886284 -294.336216) (xy 88.885789 -294.360823) (xy 88.877894 -294.4094) (xy 88.86231 -294.456081)
			(xy 88.839439 -294.499658) (xy 88.809874 -294.539002) (xy 88.774381 -294.573094) (xy 88.733878 -294.60105)
			(xy 88.689416 -294.622148) (xy 88.642145 -294.63584) (xy 88.59329 -294.641772) (xy 88.544115 -294.639791)
			(xy 88.495896 -294.629947) (xy 88.44988 -294.612495) (xy 88.407259 -294.587888) (xy 88.369138 -294.556763)
			(xy 88.336503 -294.519926) (xy 88.3102 -294.47833) (xy 88.290909 -294.433054) (xy 88.279132 -294.38527)
			(xy 88.275172 -294.336216) (xy 87.00643 -294.336216) (xy 87.005935 -294.360823) (xy 86.99804 -294.4094)
			(xy 86.982456 -294.456081) (xy 86.959585 -294.499658) (xy 86.93002 -294.539002) (xy 86.894527 -294.573094)
			(xy 86.854024 -294.60105) (xy 86.809562 -294.622148) (xy 86.762291 -294.63584) (xy 86.713436 -294.641772)
			(xy 86.664261 -294.639791) (xy 86.616042 -294.629947) (xy 86.570026 -294.612495) (xy 86.527405 -294.587888)
			(xy 86.489284 -294.556763) (xy 86.456649 -294.519926) (xy 86.430346 -294.47833) (xy 86.411055 -294.433054)
			(xy 86.399278 -294.38527) (xy 86.395318 -294.336216) (xy 86.066376 -294.336216) (xy 86.065881 -294.360823)
			(xy 86.057986 -294.4094) (xy 86.042402 -294.456081) (xy 86.019531 -294.499658) (xy 85.989966 -294.539002)
			(xy 85.954473 -294.573094) (xy 85.91397 -294.60105) (xy 85.869508 -294.622148) (xy 85.822237 -294.63584)
			(xy 85.773382 -294.641772) (xy 85.724207 -294.639791) (xy 85.675988 -294.629947) (xy 85.629972 -294.612495)
			(xy 85.587351 -294.587888) (xy 85.54923 -294.556763) (xy 85.516595 -294.519926) (xy 85.490292 -294.47833)
			(xy 85.471001 -294.433054) (xy 85.459224 -294.38527) (xy 85.455264 -294.336216) (xy 85.126322 -294.336216)
			(xy 85.125827 -294.360823) (xy 85.117932 -294.4094) (xy 85.102348 -294.456081) (xy 85.079477 -294.499658)
			(xy 85.049912 -294.539002) (xy 85.014419 -294.573094) (xy 84.973916 -294.60105) (xy 84.929454 -294.622148)
			(xy 84.882183 -294.63584) (xy 84.833328 -294.641772) (xy 84.784153 -294.639791) (xy 84.735934 -294.629947)
			(xy 84.689918 -294.612495) (xy 84.647297 -294.587888) (xy 84.609176 -294.556763) (xy 84.576541 -294.519926)
			(xy 84.550238 -294.47833) (xy 84.530947 -294.433054) (xy 84.51917 -294.38527) (xy 84.51521 -294.336216)
			(xy 84.186268 -294.336216) (xy 84.185821 -294.360207) (xy 84.178312 -294.407598) (xy 84.163481 -294.453231)
			(xy 84.141694 -294.495982) (xy 84.113488 -294.534799) (xy 84.079556 -294.568724) (xy 84.040735 -294.596924)
			(xy 83.99798 -294.618703) (xy 83.952344 -294.633525) (xy 83.904951 -294.641025) (xy 83.88096 -294.641524)
			(xy 83.855094 -294.640977) (xy 83.804103 -294.632256) (xy 83.75531 -294.615068) (xy 83.71011 -294.589907)
			(xy 83.669794 -294.55749) (xy 83.635516 -294.518744) (xy 83.608255 -294.474778) (xy 83.598004 -294.451024)
			(xy 83.594956 -294.445182) (xy 83.584283 -294.42671) (xy 83.567584 -294.387452) (xy 83.561682 -294.36695)
			(xy 83.56092 -294.36441) (xy 83.558962 -294.358805) (xy 83.552807 -294.348657) (xy 83.548728 -294.344344)
			(xy 83.546188 -294.341804) (xy 83.541698 -294.338138) (xy 83.531434 -294.332755) (xy 83.525868 -294.331136)
			(xy 83.497928 -294.32377) (xy 83.440778 -294.30853) (xy 83.439 -294.308276) (xy 83.43392 -294.307514)
			(xy 83.427316 -294.307514) (xy 83.418128 -294.308325) (xy 83.401203 -294.315624) (xy 83.394296 -294.321738)
			(xy 82.754724 -294.96131) (xy 82.748039 -294.968719) (xy 82.740457 -294.987155) (xy 82.739992 -294.997124)
			(xy 82.739992 -295.00068) (xy 82.747358 -295.016174) (xy 82.756427 -295.036423) (xy 82.769271 -295.07889)
			(xy 82.775832 -295.12277) (xy 82.776314 -295.144952) (xy 82.776314 -295.14546) (xy 82.776314 -295.146222)
			(xy 83.105256 -295.146222) (xy 83.109216 -295.097168) (xy 83.120993 -295.049384) (xy 83.140284 -295.004108)
			(xy 83.166587 -294.962512) (xy 83.199222 -294.925675) (xy 83.237343 -294.89455) (xy 83.279964 -294.869943)
			(xy 83.32598 -294.852491) (xy 83.374199 -294.842647) (xy 83.423374 -294.840666) (xy 83.472229 -294.846598)
			(xy 83.5195 -294.86029) (xy 83.563962 -294.881388) (xy 83.604465 -294.909344) (xy 83.639958 -294.943436)
			(xy 83.669523 -294.98278) (xy 83.692394 -295.026357) (xy 83.707978 -295.073038) (xy 83.715873 -295.121615)
			(xy 83.716368 -295.146222) (xy 84.04531 -295.146222) (xy 84.04927 -295.097168) (xy 84.061047 -295.049384)
			(xy 84.080338 -295.004108) (xy 84.106641 -294.962512) (xy 84.139276 -294.925675) (xy 84.177397 -294.89455)
			(xy 84.220018 -294.869943) (xy 84.266034 -294.852491) (xy 84.314253 -294.842647) (xy 84.363428 -294.840666)
			(xy 84.412283 -294.846598) (xy 84.459554 -294.86029) (xy 84.504016 -294.881388) (xy 84.544519 -294.909344)
			(xy 84.580012 -294.943436) (xy 84.609577 -294.98278) (xy 84.632448 -295.026357) (xy 84.648032 -295.073038)
			(xy 84.655927 -295.121615) (xy 84.656422 -295.146222) (xy 84.98511 -295.146222) (xy 84.98907 -295.097168)
			(xy 85.000847 -295.049384) (xy 85.020138 -295.004108) (xy 85.046441 -294.962512) (xy 85.079076 -294.925675)
			(xy 85.117197 -294.89455) (xy 85.159818 -294.869943) (xy 85.205834 -294.852491) (xy 85.254053 -294.842647)
			(xy 85.303228 -294.840666) (xy 85.352083 -294.846598) (xy 85.399354 -294.86029) (xy 85.443816 -294.881388)
			(xy 85.484319 -294.909344) (xy 85.519812 -294.943436) (xy 85.549377 -294.98278) (xy 85.572248 -295.026357)
			(xy 85.587832 -295.073038) (xy 85.595727 -295.121615) (xy 85.596222 -295.146222) (xy 85.925164 -295.146222)
			(xy 85.929124 -295.097168) (xy 85.940901 -295.049384) (xy 85.960192 -295.004108) (xy 85.986495 -294.962512)
			(xy 86.01913 -294.925675) (xy 86.057251 -294.89455) (xy 86.099872 -294.869943) (xy 86.145888 -294.852491)
			(xy 86.194107 -294.842647) (xy 86.243282 -294.840666) (xy 86.292137 -294.846598) (xy 86.339408 -294.86029)
			(xy 86.38387 -294.881388) (xy 86.424373 -294.909344) (xy 86.459866 -294.943436) (xy 86.489431 -294.98278)
			(xy 86.512302 -295.026357) (xy 86.527886 -295.073038) (xy 86.535781 -295.121615) (xy 86.536276 -295.146222)
			(xy 86.865218 -295.146222) (xy 86.869178 -295.097168) (xy 86.880955 -295.049384) (xy 86.900246 -295.004108)
			(xy 86.926549 -294.962512) (xy 86.959184 -294.925675) (xy 86.997305 -294.89455) (xy 87.039926 -294.869943)
			(xy 87.085942 -294.852491) (xy 87.134161 -294.842647) (xy 87.183336 -294.840666) (xy 87.232191 -294.846598)
			(xy 87.279462 -294.86029) (xy 87.323924 -294.881388) (xy 87.364427 -294.909344) (xy 87.39992 -294.943436)
			(xy 87.429485 -294.98278) (xy 87.452356 -295.026357) (xy 87.46794 -295.073038) (xy 87.475835 -295.121615)
			(xy 87.47633 -295.146222) (xy 87.805272 -295.146222) (xy 87.809232 -295.097168) (xy 87.821009 -295.049384)
			(xy 87.8403 -295.004108) (xy 87.866603 -294.962512) (xy 87.899238 -294.925675) (xy 87.937359 -294.89455)
			(xy 87.97998 -294.869943) (xy 88.025996 -294.852491) (xy 88.074215 -294.842647) (xy 88.12339 -294.840666)
			(xy 88.172245 -294.846598) (xy 88.219516 -294.86029) (xy 88.263978 -294.881388) (xy 88.304481 -294.909344)
			(xy 88.339974 -294.943436) (xy 88.369539 -294.98278) (xy 88.39241 -295.026357) (xy 88.407994 -295.073038)
			(xy 88.415889 -295.121615) (xy 88.416384 -295.146222) (xy 88.745326 -295.146222) (xy 88.749286 -295.097168)
			(xy 88.761063 -295.049384) (xy 88.780354 -295.004108) (xy 88.806657 -294.962512) (xy 88.839292 -294.925675)
			(xy 88.877413 -294.89455) (xy 88.920034 -294.869943) (xy 88.96605 -294.852491) (xy 89.014269 -294.842647)
			(xy 89.063444 -294.840666) (xy 89.112299 -294.846598) (xy 89.15957 -294.86029) (xy 89.204032 -294.881388)
			(xy 89.244535 -294.909344) (xy 89.280028 -294.943436) (xy 89.309593 -294.98278) (xy 89.332464 -295.026357)
			(xy 89.348048 -295.073038) (xy 89.355943 -295.121615) (xy 89.356438 -295.146222) (xy 89.685126 -295.146222)
			(xy 89.689086 -295.097168) (xy 89.700863 -295.049384) (xy 89.720154 -295.004108) (xy 89.746457 -294.962512)
			(xy 89.779092 -294.925675) (xy 89.817213 -294.89455) (xy 89.859834 -294.869943) (xy 89.90585 -294.852491)
			(xy 89.954069 -294.842647) (xy 90.003244 -294.840666) (xy 90.052099 -294.846598) (xy 90.09937 -294.86029)
			(xy 90.143832 -294.881388) (xy 90.184335 -294.909344) (xy 90.219828 -294.943436) (xy 90.249393 -294.98278)
			(xy 90.272264 -295.026357) (xy 90.287848 -295.073038) (xy 90.295743 -295.121615) (xy 90.296238 -295.146222)
			(xy 90.62518 -295.146222) (xy 90.62914 -295.097168) (xy 90.640917 -295.049384) (xy 90.660208 -295.004108)
			(xy 90.686511 -294.962512) (xy 90.719146 -294.925675) (xy 90.757267 -294.89455) (xy 90.799888 -294.869943)
			(xy 90.845904 -294.852491) (xy 90.894123 -294.842647) (xy 90.943298 -294.840666) (xy 90.992153 -294.846598)
			(xy 91.039424 -294.86029) (xy 91.083886 -294.881388) (xy 91.124389 -294.909344) (xy 91.159882 -294.943436)
			(xy 91.189447 -294.98278) (xy 91.212318 -295.026357) (xy 91.227902 -295.073038) (xy 91.235797 -295.121615)
			(xy 91.236292 -295.146222) (xy 91.565234 -295.146222) (xy 91.569194 -295.097168) (xy 91.580971 -295.049384)
			(xy 91.600262 -295.004108) (xy 91.626565 -294.962512) (xy 91.6592 -294.925675) (xy 91.697321 -294.89455)
			(xy 91.739942 -294.869943) (xy 91.785958 -294.852491) (xy 91.834177 -294.842647) (xy 91.883352 -294.840666)
			(xy 91.932207 -294.846598) (xy 91.979478 -294.86029) (xy 92.02394 -294.881388) (xy 92.064443 -294.909344)
			(xy 92.099936 -294.943436) (xy 92.129501 -294.98278) (xy 92.152372 -295.026357) (xy 92.167956 -295.073038)
			(xy 92.175851 -295.121615) (xy 92.176346 -295.146222) (xy 92.505288 -295.146222) (xy 92.509248 -295.097168)
			(xy 92.521025 -295.049384) (xy 92.540316 -295.004108) (xy 92.566619 -294.962512) (xy 92.599254 -294.925675)
			(xy 92.637375 -294.89455) (xy 92.679996 -294.869943) (xy 92.726012 -294.852491) (xy 92.774231 -294.842647)
			(xy 92.823406 -294.840666) (xy 92.872261 -294.846598) (xy 92.919532 -294.86029) (xy 92.963994 -294.881388)
			(xy 93.004497 -294.909344) (xy 93.03999 -294.943436) (xy 93.069555 -294.98278) (xy 93.092426 -295.026357)
			(xy 93.10801 -295.073038) (xy 93.115905 -295.121615) (xy 93.1164 -295.146222) (xy 93.445342 -295.146222)
			(xy 93.449302 -295.097168) (xy 93.461079 -295.049384) (xy 93.48037 -295.004108) (xy 93.506673 -294.962512)
			(xy 93.539308 -294.925675) (xy 93.577429 -294.89455) (xy 93.62005 -294.869943) (xy 93.666066 -294.852491)
			(xy 93.714285 -294.842647) (xy 93.76346 -294.840666) (xy 93.812315 -294.846598) (xy 93.859586 -294.86029)
			(xy 93.904048 -294.881388) (xy 93.944551 -294.909344) (xy 93.980044 -294.943436) (xy 94.009609 -294.98278)
			(xy 94.03248 -295.026357) (xy 94.048064 -295.073038) (xy 94.055959 -295.121615) (xy 94.056454 -295.146222)
			(xy 94.385142 -295.146222) (xy 94.389102 -295.097168) (xy 94.400879 -295.049384) (xy 94.42017 -295.004108)
			(xy 94.446473 -294.962512) (xy 94.479108 -294.925675) (xy 94.517229 -294.89455) (xy 94.55985 -294.869943)
			(xy 94.605866 -294.852491) (xy 94.654085 -294.842647) (xy 94.70326 -294.840666) (xy 94.752115 -294.846598)
			(xy 94.799386 -294.86029) (xy 94.843848 -294.881388) (xy 94.884351 -294.909344) (xy 94.919844 -294.943436)
			(xy 94.949409 -294.98278) (xy 94.97228 -295.026357) (xy 94.987864 -295.073038) (xy 94.995759 -295.121615)
			(xy 94.996254 -295.146222) (xy 95.325196 -295.146222) (xy 95.329156 -295.097168) (xy 95.340933 -295.049384)
			(xy 95.360224 -295.004108) (xy 95.386527 -294.962512) (xy 95.419162 -294.925675) (xy 95.457283 -294.89455)
			(xy 95.499904 -294.869943) (xy 95.54592 -294.852491) (xy 95.594139 -294.842647) (xy 95.643314 -294.840666)
			(xy 95.692169 -294.846598) (xy 95.73944 -294.86029) (xy 95.783902 -294.881388) (xy 95.824405 -294.909344)
			(xy 95.859898 -294.943436) (xy 95.889463 -294.98278) (xy 95.912334 -295.026357) (xy 95.927918 -295.073038)
			(xy 95.935813 -295.121615) (xy 95.936308 -295.146222) (xy 95.935813 -295.170829) (xy 95.927918 -295.219406)
			(xy 95.912334 -295.266087) (xy 95.889463 -295.309664) (xy 95.859898 -295.349008) (xy 95.824405 -295.3831)
			(xy 95.783902 -295.411056) (xy 95.73944 -295.432154) (xy 95.692169 -295.445846) (xy 95.643314 -295.451778)
			(xy 95.594139 -295.449797) (xy 95.54592 -295.439953) (xy 95.499904 -295.422501) (xy 95.457283 -295.397894)
			(xy 95.419162 -295.366769) (xy 95.386527 -295.329932) (xy 95.360224 -295.288336) (xy 95.340933 -295.24306)
			(xy 95.329156 -295.195276) (xy 95.325196 -295.146222) (xy 94.996254 -295.146222) (xy 94.995759 -295.170829)
			(xy 94.987864 -295.219406) (xy 94.97228 -295.266087) (xy 94.949409 -295.309664) (xy 94.919844 -295.349008)
			(xy 94.884351 -295.3831) (xy 94.843848 -295.411056) (xy 94.799386 -295.432154) (xy 94.752115 -295.445846)
			(xy 94.70326 -295.451778) (xy 94.654085 -295.449797) (xy 94.605866 -295.439953) (xy 94.55985 -295.422501)
			(xy 94.517229 -295.397894) (xy 94.479108 -295.366769) (xy 94.446473 -295.329932) (xy 94.42017 -295.288336)
			(xy 94.400879 -295.24306) (xy 94.389102 -295.195276) (xy 94.385142 -295.146222) (xy 94.056454 -295.146222)
			(xy 94.055959 -295.170829) (xy 94.048064 -295.219406) (xy 94.03248 -295.266087) (xy 94.009609 -295.309664)
			(xy 93.980044 -295.349008) (xy 93.944551 -295.3831) (xy 93.904048 -295.411056) (xy 93.859586 -295.432154)
			(xy 93.812315 -295.445846) (xy 93.76346 -295.451778) (xy 93.714285 -295.449797) (xy 93.666066 -295.439953)
			(xy 93.62005 -295.422501) (xy 93.577429 -295.397894) (xy 93.539308 -295.366769) (xy 93.506673 -295.329932)
			(xy 93.48037 -295.288336) (xy 93.461079 -295.24306) (xy 93.449302 -295.195276) (xy 93.445342 -295.146222)
			(xy 93.1164 -295.146222) (xy 93.115905 -295.170829) (xy 93.10801 -295.219406) (xy 93.092426 -295.266087)
			(xy 93.069555 -295.309664) (xy 93.03999 -295.349008) (xy 93.004497 -295.3831) (xy 92.963994 -295.411056)
			(xy 92.919532 -295.432154) (xy 92.872261 -295.445846) (xy 92.823406 -295.451778) (xy 92.774231 -295.449797)
			(xy 92.726012 -295.439953) (xy 92.679996 -295.422501) (xy 92.637375 -295.397894) (xy 92.599254 -295.366769)
			(xy 92.566619 -295.329932) (xy 92.540316 -295.288336) (xy 92.521025 -295.24306) (xy 92.509248 -295.195276)
			(xy 92.505288 -295.146222) (xy 92.176346 -295.146222) (xy 92.175851 -295.170829) (xy 92.167956 -295.219406)
			(xy 92.152372 -295.266087) (xy 92.129501 -295.309664) (xy 92.099936 -295.349008) (xy 92.064443 -295.3831)
			(xy 92.02394 -295.411056) (xy 91.979478 -295.432154) (xy 91.932207 -295.445846) (xy 91.883352 -295.451778)
			(xy 91.834177 -295.449797) (xy 91.785958 -295.439953) (xy 91.739942 -295.422501) (xy 91.697321 -295.397894)
			(xy 91.6592 -295.366769) (xy 91.626565 -295.329932) (xy 91.600262 -295.288336) (xy 91.580971 -295.24306)
			(xy 91.569194 -295.195276) (xy 91.565234 -295.146222) (xy 91.236292 -295.146222) (xy 91.235797 -295.170829)
			(xy 91.227902 -295.219406) (xy 91.212318 -295.266087) (xy 91.189447 -295.309664) (xy 91.159882 -295.349008)
			(xy 91.124389 -295.3831) (xy 91.083886 -295.411056) (xy 91.039424 -295.432154) (xy 90.992153 -295.445846)
			(xy 90.943298 -295.451778) (xy 90.894123 -295.449797) (xy 90.845904 -295.439953) (xy 90.799888 -295.422501)
			(xy 90.757267 -295.397894) (xy 90.719146 -295.366769) (xy 90.686511 -295.329932) (xy 90.660208 -295.288336)
			(xy 90.640917 -295.24306) (xy 90.62914 -295.195276) (xy 90.62518 -295.146222) (xy 90.296238 -295.146222)
			(xy 90.295743 -295.170829) (xy 90.287848 -295.219406) (xy 90.272264 -295.266087) (xy 90.249393 -295.309664)
			(xy 90.219828 -295.349008) (xy 90.184335 -295.3831) (xy 90.143832 -295.411056) (xy 90.09937 -295.432154)
			(xy 90.052099 -295.445846) (xy 90.003244 -295.451778) (xy 89.954069 -295.449797) (xy 89.90585 -295.439953)
			(xy 89.859834 -295.422501) (xy 89.817213 -295.397894) (xy 89.779092 -295.366769) (xy 89.746457 -295.329932)
			(xy 89.720154 -295.288336) (xy 89.700863 -295.24306) (xy 89.689086 -295.195276) (xy 89.685126 -295.146222)
			(xy 89.356438 -295.146222) (xy 89.355943 -295.170829) (xy 89.348048 -295.219406) (xy 89.332464 -295.266087)
			(xy 89.309593 -295.309664) (xy 89.280028 -295.349008) (xy 89.244535 -295.3831) (xy 89.204032 -295.411056)
			(xy 89.15957 -295.432154) (xy 89.112299 -295.445846) (xy 89.063444 -295.451778) (xy 89.014269 -295.449797)
			(xy 88.96605 -295.439953) (xy 88.920034 -295.422501) (xy 88.877413 -295.397894) (xy 88.839292 -295.366769)
			(xy 88.806657 -295.329932) (xy 88.780354 -295.288336) (xy 88.761063 -295.24306) (xy 88.749286 -295.195276)
			(xy 88.745326 -295.146222) (xy 88.416384 -295.146222) (xy 88.415889 -295.170829) (xy 88.407994 -295.219406)
			(xy 88.39241 -295.266087) (xy 88.369539 -295.309664) (xy 88.339974 -295.349008) (xy 88.304481 -295.3831)
			(xy 88.263978 -295.411056) (xy 88.219516 -295.432154) (xy 88.172245 -295.445846) (xy 88.12339 -295.451778)
			(xy 88.074215 -295.449797) (xy 88.025996 -295.439953) (xy 87.97998 -295.422501) (xy 87.937359 -295.397894)
			(xy 87.899238 -295.366769) (xy 87.866603 -295.329932) (xy 87.8403 -295.288336) (xy 87.821009 -295.24306)
			(xy 87.809232 -295.195276) (xy 87.805272 -295.146222) (xy 87.47633 -295.146222) (xy 87.475835 -295.170829)
			(xy 87.46794 -295.219406) (xy 87.452356 -295.266087) (xy 87.429485 -295.309664) (xy 87.39992 -295.349008)
			(xy 87.364427 -295.3831) (xy 87.323924 -295.411056) (xy 87.279462 -295.432154) (xy 87.232191 -295.445846)
			(xy 87.183336 -295.451778) (xy 87.134161 -295.449797) (xy 87.085942 -295.439953) (xy 87.039926 -295.422501)
			(xy 86.997305 -295.397894) (xy 86.959184 -295.366769) (xy 86.926549 -295.329932) (xy 86.900246 -295.288336)
			(xy 86.880955 -295.24306) (xy 86.869178 -295.195276) (xy 86.865218 -295.146222) (xy 86.536276 -295.146222)
			(xy 86.535781 -295.170829) (xy 86.527886 -295.219406) (xy 86.512302 -295.266087) (xy 86.489431 -295.309664)
			(xy 86.459866 -295.349008) (xy 86.424373 -295.3831) (xy 86.38387 -295.411056) (xy 86.339408 -295.432154)
			(xy 86.292137 -295.445846) (xy 86.243282 -295.451778) (xy 86.194107 -295.449797) (xy 86.145888 -295.439953)
			(xy 86.099872 -295.422501) (xy 86.057251 -295.397894) (xy 86.01913 -295.366769) (xy 85.986495 -295.329932)
			(xy 85.960192 -295.288336) (xy 85.940901 -295.24306) (xy 85.929124 -295.195276) (xy 85.925164 -295.146222)
			(xy 85.596222 -295.146222) (xy 85.595727 -295.170829) (xy 85.587832 -295.219406) (xy 85.572248 -295.266087)
			(xy 85.549377 -295.309664) (xy 85.519812 -295.349008) (xy 85.484319 -295.3831) (xy 85.443816 -295.411056)
			(xy 85.399354 -295.432154) (xy 85.352083 -295.445846) (xy 85.303228 -295.451778) (xy 85.254053 -295.449797)
			(xy 85.205834 -295.439953) (xy 85.159818 -295.422501) (xy 85.117197 -295.397894) (xy 85.079076 -295.366769)
			(xy 85.046441 -295.329932) (xy 85.020138 -295.288336) (xy 85.000847 -295.24306) (xy 84.98907 -295.195276)
			(xy 84.98511 -295.146222) (xy 84.656422 -295.146222) (xy 84.655927 -295.170829) (xy 84.648032 -295.219406)
			(xy 84.632448 -295.266087) (xy 84.609577 -295.309664) (xy 84.580012 -295.349008) (xy 84.544519 -295.3831)
			(xy 84.504016 -295.411056) (xy 84.459554 -295.432154) (xy 84.412283 -295.445846) (xy 84.363428 -295.451778)
			(xy 84.314253 -295.449797) (xy 84.266034 -295.439953) (xy 84.220018 -295.422501) (xy 84.177397 -295.397894)
			(xy 84.139276 -295.366769) (xy 84.106641 -295.329932) (xy 84.080338 -295.288336) (xy 84.061047 -295.24306)
			(xy 84.04927 -295.195276) (xy 84.04531 -295.146222) (xy 83.716368 -295.146222) (xy 83.715873 -295.170829)
			(xy 83.707978 -295.219406) (xy 83.692394 -295.266087) (xy 83.669523 -295.309664) (xy 83.639958 -295.349008)
			(xy 83.604465 -295.3831) (xy 83.563962 -295.411056) (xy 83.5195 -295.432154) (xy 83.472229 -295.445846)
			(xy 83.423374 -295.451778) (xy 83.374199 -295.449797) (xy 83.32598 -295.439953) (xy 83.279964 -295.422501)
			(xy 83.237343 -295.397894) (xy 83.199222 -295.366769) (xy 83.166587 -295.329932) (xy 83.140284 -295.288336)
			(xy 83.120993 -295.24306) (xy 83.109216 -295.195276) (xy 83.105256 -295.146222) (xy 82.776314 -295.146222)
			(xy 82.776314 -295.151302) (xy 82.775346 -295.177389) (xy 82.765614 -295.228672) (xy 82.747306 -295.277555)
			(xy 82.720954 -295.322614) (xy 82.687326 -295.362538) (xy 82.647401 -295.396164) (xy 82.602341 -295.422513)
			(xy 82.553457 -295.440818) (xy 82.502173 -295.450547) (xy 82.476086 -295.45153) (xy 82.470498 -295.45153)
			(xy 82.448188 -295.451102) (xy 82.404049 -295.444565) (xy 82.361331 -295.431676) (xy 82.340958 -295.422574)
			(xy 82.333815 -295.419522) (xy 82.318427 -295.41745) (xy 82.310732 -295.41851) (xy 82.303112 -295.41978)
			(xy 82.289142 -295.426892) (xy 81.759815 -295.956228) (xy 82.635102 -295.956228) (xy 82.639062 -295.907174)
			(xy 82.650839 -295.85939) (xy 82.67013 -295.814114) (xy 82.696433 -295.772518) (xy 82.729068 -295.735681)
			(xy 82.767189 -295.704556) (xy 82.80981 -295.679949) (xy 82.855826 -295.662497) (xy 82.904045 -295.652653)
			(xy 82.95322 -295.650672) (xy 83.002075 -295.656604) (xy 83.049346 -295.670296) (xy 83.093808 -295.691394)
			(xy 83.134311 -295.71935) (xy 83.169804 -295.753442) (xy 83.199369 -295.792786) (xy 83.22224 -295.836363)
			(xy 83.237824 -295.883044) (xy 83.245719 -295.931621) (xy 83.246214 -295.956228) (xy 83.575156 -295.956228)
			(xy 83.579116 -295.907174) (xy 83.590893 -295.85939) (xy 83.610184 -295.814114) (xy 83.636487 -295.772518)
			(xy 83.669122 -295.735681) (xy 83.707243 -295.704556) (xy 83.749864 -295.679949) (xy 83.79588 -295.662497)
			(xy 83.844099 -295.652653) (xy 83.893274 -295.650672) (xy 83.942129 -295.656604) (xy 83.9894 -295.670296)
			(xy 84.033862 -295.691394) (xy 84.074365 -295.71935) (xy 84.109858 -295.753442) (xy 84.139423 -295.792786)
			(xy 84.162294 -295.836363) (xy 84.177878 -295.883044) (xy 84.185773 -295.931621) (xy 84.186268 -295.956228)
			(xy 84.51521 -295.956228) (xy 84.51917 -295.907174) (xy 84.530947 -295.85939) (xy 84.550238 -295.814114)
			(xy 84.576541 -295.772518) (xy 84.609176 -295.735681) (xy 84.647297 -295.704556) (xy 84.689918 -295.679949)
			(xy 84.735934 -295.662497) (xy 84.784153 -295.652653) (xy 84.833328 -295.650672) (xy 84.882183 -295.656604)
			(xy 84.929454 -295.670296) (xy 84.973916 -295.691394) (xy 85.014419 -295.71935) (xy 85.049912 -295.753442)
			(xy 85.079477 -295.792786) (xy 85.102348 -295.836363) (xy 85.117932 -295.883044) (xy 85.125827 -295.931621)
			(xy 85.126322 -295.956228) (xy 85.455264 -295.956228) (xy 85.459224 -295.907174) (xy 85.471001 -295.85939)
			(xy 85.490292 -295.814114) (xy 85.516595 -295.772518) (xy 85.54923 -295.735681) (xy 85.587351 -295.704556)
			(xy 85.629972 -295.679949) (xy 85.675988 -295.662497) (xy 85.724207 -295.652653) (xy 85.773382 -295.650672)
			(xy 85.822237 -295.656604) (xy 85.869508 -295.670296) (xy 85.91397 -295.691394) (xy 85.954473 -295.71935)
			(xy 85.989966 -295.753442) (xy 86.019531 -295.792786) (xy 86.042402 -295.836363) (xy 86.057986 -295.883044)
			(xy 86.065881 -295.931621) (xy 86.066376 -295.956228) (xy 86.395318 -295.956228) (xy 86.399278 -295.907174)
			(xy 86.411055 -295.85939) (xy 86.430346 -295.814114) (xy 86.456649 -295.772518) (xy 86.489284 -295.735681)
			(xy 86.527405 -295.704556) (xy 86.570026 -295.679949) (xy 86.616042 -295.662497) (xy 86.664261 -295.652653)
			(xy 86.713436 -295.650672) (xy 86.762291 -295.656604) (xy 86.809562 -295.670296) (xy 86.854024 -295.691394)
			(xy 86.894527 -295.71935) (xy 86.93002 -295.753442) (xy 86.959585 -295.792786) (xy 86.982456 -295.836363)
			(xy 86.99804 -295.883044) (xy 87.005935 -295.931621) (xy 87.00643 -295.956228) (xy 88.275172 -295.956228)
			(xy 88.279132 -295.907174) (xy 88.290909 -295.85939) (xy 88.3102 -295.814114) (xy 88.336503 -295.772518)
			(xy 88.369138 -295.735681) (xy 88.407259 -295.704556) (xy 88.44988 -295.679949) (xy 88.495896 -295.662497)
			(xy 88.544115 -295.652653) (xy 88.59329 -295.650672) (xy 88.642145 -295.656604) (xy 88.689416 -295.670296)
			(xy 88.733878 -295.691394) (xy 88.774381 -295.71935) (xy 88.809874 -295.753442) (xy 88.839439 -295.792786)
			(xy 88.86231 -295.836363) (xy 88.877894 -295.883044) (xy 88.885789 -295.931621) (xy 88.886284 -295.956228)
			(xy 89.215226 -295.956228) (xy 89.219186 -295.907174) (xy 89.230963 -295.85939) (xy 89.250254 -295.814114)
			(xy 89.276557 -295.772518) (xy 89.309192 -295.735681) (xy 89.347313 -295.704556) (xy 89.389934 -295.679949)
			(xy 89.43595 -295.662497) (xy 89.484169 -295.652653) (xy 89.533344 -295.650672) (xy 89.582199 -295.656604)
			(xy 89.62947 -295.670296) (xy 89.673932 -295.691394) (xy 89.714435 -295.71935) (xy 89.749928 -295.753442)
			(xy 89.779493 -295.792786) (xy 89.802364 -295.836363) (xy 89.817948 -295.883044) (xy 89.825843 -295.931621)
			(xy 89.826338 -295.956228) (xy 90.15528 -295.956228) (xy 90.15924 -295.907174) (xy 90.171017 -295.85939)
			(xy 90.190308 -295.814114) (xy 90.216611 -295.772518) (xy 90.249246 -295.735681) (xy 90.287367 -295.704556)
			(xy 90.329988 -295.679949) (xy 90.376004 -295.662497) (xy 90.424223 -295.652653) (xy 90.473398 -295.650672)
			(xy 90.522253 -295.656604) (xy 90.569524 -295.670296) (xy 90.613986 -295.691394) (xy 90.654489 -295.71935)
			(xy 90.689982 -295.753442) (xy 90.719547 -295.792786) (xy 90.742418 -295.836363) (xy 90.758002 -295.883044)
			(xy 90.765897 -295.931621) (xy 90.766392 -295.956228) (xy 91.095334 -295.956228) (xy 91.099294 -295.907174)
			(xy 91.111071 -295.85939) (xy 91.130362 -295.814114) (xy 91.156665 -295.772518) (xy 91.1893 -295.735681)
			(xy 91.227421 -295.704556) (xy 91.270042 -295.679949) (xy 91.316058 -295.662497) (xy 91.364277 -295.652653)
			(xy 91.413452 -295.650672) (xy 91.462307 -295.656604) (xy 91.509578 -295.670296) (xy 91.55404 -295.691394)
			(xy 91.594543 -295.71935) (xy 91.630036 -295.753442) (xy 91.659601 -295.792786) (xy 91.682472 -295.836363)
			(xy 91.698056 -295.883044) (xy 91.705951 -295.931621) (xy 91.706446 -295.956228) (xy 92.035134 -295.956228)
			(xy 92.039094 -295.907174) (xy 92.050871 -295.85939) (xy 92.070162 -295.814114) (xy 92.096465 -295.772518)
			(xy 92.1291 -295.735681) (xy 92.167221 -295.704556) (xy 92.209842 -295.679949) (xy 92.255858 -295.662497)
			(xy 92.304077 -295.652653) (xy 92.353252 -295.650672) (xy 92.402107 -295.656604) (xy 92.449378 -295.670296)
			(xy 92.49384 -295.691394) (xy 92.534343 -295.71935) (xy 92.569836 -295.753442) (xy 92.599401 -295.792786)
			(xy 92.622272 -295.836363) (xy 92.637856 -295.883044) (xy 92.645751 -295.931621) (xy 92.646246 -295.956228)
			(xy 94.855296 -295.956228) (xy 94.859256 -295.907174) (xy 94.871033 -295.85939) (xy 94.890324 -295.814114)
			(xy 94.916627 -295.772518) (xy 94.949262 -295.735681) (xy 94.987383 -295.704556) (xy 95.030004 -295.679949)
			(xy 95.07602 -295.662497) (xy 95.124239 -295.652653) (xy 95.173414 -295.650672) (xy 95.222269 -295.656604)
			(xy 95.26954 -295.670296) (xy 95.314002 -295.691394) (xy 95.354505 -295.71935) (xy 95.389998 -295.753442)
			(xy 95.419563 -295.792786) (xy 95.442434 -295.836363) (xy 95.458018 -295.883044) (xy 95.465913 -295.931621)
			(xy 95.466408 -295.956228) (xy 95.465913 -295.980835) (xy 95.458018 -296.029412) (xy 95.442434 -296.076093)
			(xy 95.419563 -296.11967) (xy 95.389998 -296.159014) (xy 95.354505 -296.193106) (xy 95.314002 -296.221062)
			(xy 95.26954 -296.24216) (xy 95.222269 -296.255852) (xy 95.173414 -296.261784) (xy 95.124239 -296.259803)
			(xy 95.07602 -296.249959) (xy 95.030004 -296.232507) (xy 94.987383 -296.2079) (xy 94.949262 -296.176775)
			(xy 94.916627 -296.139938) (xy 94.890324 -296.098342) (xy 94.871033 -296.053066) (xy 94.859256 -296.005282)
			(xy 94.855296 -295.956228) (xy 92.646246 -295.956228) (xy 92.645751 -295.980835) (xy 92.637856 -296.029412)
			(xy 92.622272 -296.076093) (xy 92.599401 -296.11967) (xy 92.569836 -296.159014) (xy 92.534343 -296.193106)
			(xy 92.49384 -296.221062) (xy 92.449378 -296.24216) (xy 92.402107 -296.255852) (xy 92.353252 -296.261784)
			(xy 92.304077 -296.259803) (xy 92.255858 -296.249959) (xy 92.209842 -296.232507) (xy 92.167221 -296.2079)
			(xy 92.1291 -296.176775) (xy 92.096465 -296.139938) (xy 92.070162 -296.098342) (xy 92.050871 -296.053066)
			(xy 92.039094 -296.005282) (xy 92.035134 -295.956228) (xy 91.706446 -295.956228) (xy 91.705951 -295.980835)
			(xy 91.698056 -296.029412) (xy 91.682472 -296.076093) (xy 91.659601 -296.11967) (xy 91.630036 -296.159014)
			(xy 91.594543 -296.193106) (xy 91.55404 -296.221062) (xy 91.509578 -296.24216) (xy 91.462307 -296.255852)
			(xy 91.413452 -296.261784) (xy 91.364277 -296.259803) (xy 91.316058 -296.249959) (xy 91.270042 -296.232507)
			(xy 91.227421 -296.2079) (xy 91.1893 -296.176775) (xy 91.156665 -296.139938) (xy 91.130362 -296.098342)
			(xy 91.111071 -296.053066) (xy 91.099294 -296.005282) (xy 91.095334 -295.956228) (xy 90.766392 -295.956228)
			(xy 90.765897 -295.980835) (xy 90.758002 -296.029412) (xy 90.742418 -296.076093) (xy 90.719547 -296.11967)
			(xy 90.689982 -296.159014) (xy 90.654489 -296.193106) (xy 90.613986 -296.221062) (xy 90.569524 -296.24216)
			(xy 90.522253 -296.255852) (xy 90.473398 -296.261784) (xy 90.424223 -296.259803) (xy 90.376004 -296.249959)
			(xy 90.329988 -296.232507) (xy 90.287367 -296.2079) (xy 90.249246 -296.176775) (xy 90.216611 -296.139938)
			(xy 90.190308 -296.098342) (xy 90.171017 -296.053066) (xy 90.15924 -296.005282) (xy 90.15528 -295.956228)
			(xy 89.826338 -295.956228) (xy 89.825843 -295.980835) (xy 89.817948 -296.029412) (xy 89.802364 -296.076093)
			(xy 89.779493 -296.11967) (xy 89.749928 -296.159014) (xy 89.714435 -296.193106) (xy 89.673932 -296.221062)
			(xy 89.62947 -296.24216) (xy 89.582199 -296.255852) (xy 89.533344 -296.261784) (xy 89.484169 -296.259803)
			(xy 89.43595 -296.249959) (xy 89.389934 -296.232507) (xy 89.347313 -296.2079) (xy 89.309192 -296.176775)
			(xy 89.276557 -296.139938) (xy 89.250254 -296.098342) (xy 89.230963 -296.053066) (xy 89.219186 -296.005282)
			(xy 89.215226 -295.956228) (xy 88.886284 -295.956228) (xy 88.885789 -295.980835) (xy 88.877894 -296.029412)
			(xy 88.86231 -296.076093) (xy 88.839439 -296.11967) (xy 88.809874 -296.159014) (xy 88.774381 -296.193106)
			(xy 88.733878 -296.221062) (xy 88.689416 -296.24216) (xy 88.642145 -296.255852) (xy 88.59329 -296.261784)
			(xy 88.544115 -296.259803) (xy 88.495896 -296.249959) (xy 88.44988 -296.232507) (xy 88.407259 -296.2079)
			(xy 88.369138 -296.176775) (xy 88.336503 -296.139938) (xy 88.3102 -296.098342) (xy 88.290909 -296.053066)
			(xy 88.279132 -296.005282) (xy 88.275172 -295.956228) (xy 87.00643 -295.956228) (xy 87.005935 -295.980835)
			(xy 86.99804 -296.029412) (xy 86.982456 -296.076093) (xy 86.959585 -296.11967) (xy 86.93002 -296.159014)
			(xy 86.894527 -296.193106) (xy 86.854024 -296.221062) (xy 86.809562 -296.24216) (xy 86.762291 -296.255852)
			(xy 86.713436 -296.261784) (xy 86.664261 -296.259803) (xy 86.616042 -296.249959) (xy 86.570026 -296.232507)
			(xy 86.527405 -296.2079) (xy 86.489284 -296.176775) (xy 86.456649 -296.139938) (xy 86.430346 -296.098342)
			(xy 86.411055 -296.053066) (xy 86.399278 -296.005282) (xy 86.395318 -295.956228) (xy 86.066376 -295.956228)
			(xy 86.065881 -295.980835) (xy 86.057986 -296.029412) (xy 86.042402 -296.076093) (xy 86.019531 -296.11967)
			(xy 85.989966 -296.159014) (xy 85.954473 -296.193106) (xy 85.91397 -296.221062) (xy 85.869508 -296.24216)
			(xy 85.822237 -296.255852) (xy 85.773382 -296.261784) (xy 85.724207 -296.259803) (xy 85.675988 -296.249959)
			(xy 85.629972 -296.232507) (xy 85.587351 -296.2079) (xy 85.54923 -296.176775) (xy 85.516595 -296.139938)
			(xy 85.490292 -296.098342) (xy 85.471001 -296.053066) (xy 85.459224 -296.005282) (xy 85.455264 -295.956228)
			(xy 85.126322 -295.956228) (xy 85.125827 -295.980835) (xy 85.117932 -296.029412) (xy 85.102348 -296.076093)
			(xy 85.079477 -296.11967) (xy 85.049912 -296.159014) (xy 85.014419 -296.193106) (xy 84.973916 -296.221062)
			(xy 84.929454 -296.24216) (xy 84.882183 -296.255852) (xy 84.833328 -296.261784) (xy 84.784153 -296.259803)
			(xy 84.735934 -296.249959) (xy 84.689918 -296.232507) (xy 84.647297 -296.2079) (xy 84.609176 -296.176775)
			(xy 84.576541 -296.139938) (xy 84.550238 -296.098342) (xy 84.530947 -296.053066) (xy 84.51917 -296.005282)
			(xy 84.51521 -295.956228) (xy 84.186268 -295.956228) (xy 84.185773 -295.980835) (xy 84.177878 -296.029412)
			(xy 84.162294 -296.076093) (xy 84.139423 -296.11967) (xy 84.109858 -296.159014) (xy 84.074365 -296.193106)
			(xy 84.033862 -296.221062) (xy 83.9894 -296.24216) (xy 83.942129 -296.255852) (xy 83.893274 -296.261784)
			(xy 83.844099 -296.259803) (xy 83.79588 -296.249959) (xy 83.749864 -296.232507) (xy 83.707243 -296.2079)
			(xy 83.669122 -296.176775) (xy 83.636487 -296.139938) (xy 83.610184 -296.098342) (xy 83.590893 -296.053066)
			(xy 83.579116 -296.005282) (xy 83.575156 -295.956228) (xy 83.246214 -295.956228) (xy 83.245719 -295.980835)
			(xy 83.237824 -296.029412) (xy 83.22224 -296.076093) (xy 83.199369 -296.11967) (xy 83.169804 -296.159014)
			(xy 83.134311 -296.193106) (xy 83.093808 -296.221062) (xy 83.049346 -296.24216) (xy 83.002075 -296.255852)
			(xy 82.95322 -296.261784) (xy 82.904045 -296.259803) (xy 82.855826 -296.249959) (xy 82.80981 -296.232507)
			(xy 82.767189 -296.2079) (xy 82.729068 -296.176775) (xy 82.696433 -296.139938) (xy 82.67013 -296.098342)
			(xy 82.650839 -296.053066) (xy 82.639062 -296.005282) (xy 82.635102 -295.956228) (xy 81.759815 -295.956228)
			(xy 79.401 -298.315083) (xy 87.657172 -298.315083) (xy 87.657172 -298.251161) (xy 87.665183 -298.187743)
			(xy 87.68108 -298.125829) (xy 87.704612 -298.066396) (xy 87.735406 -298.010381) (xy 87.772979 -297.958666)
			(xy 87.816736 -297.912069) (xy 87.865989 -297.871324) (xy 87.91996 -297.837073) (xy 87.977799 -297.809856)
			(xy 88.038592 -297.790103) (xy 88.101382 -297.778125) (xy 88.165178 -297.774112) (xy 88.228974 -297.778125)
			(xy 88.291764 -297.790103) (xy 88.352557 -297.809856) (xy 88.410396 -297.837073) (xy 88.464367 -297.871324)
			(xy 88.51362 -297.912069) (xy 88.557377 -297.958666) (xy 88.59495 -298.010381) (xy 88.625744 -298.066396)
			(xy 88.649276 -298.125829) (xy 88.665173 -298.187743) (xy 88.673184 -298.251161) (xy 88.673686 -298.283122)
			(xy 88.673184 -298.315083) (xy 88.665173 -298.378501) (xy 88.649276 -298.440415) (xy 88.625744 -298.499848)
			(xy 88.59495 -298.555863) (xy 88.557377 -298.607578) (xy 88.51362 -298.654175) (xy 88.464367 -298.69492)
			(xy 88.410396 -298.729171) (xy 88.352557 -298.756388) (xy 88.291764 -298.776141) (xy 88.228974 -298.788119)
			(xy 88.165178 -298.792133) (xy 88.101382 -298.788119) (xy 88.038592 -298.776141) (xy 87.977799 -298.756388)
			(xy 87.91996 -298.729171) (xy 87.865989 -298.69492) (xy 87.816736 -298.654175) (xy 87.772979 -298.607578)
			(xy 87.735406 -298.555863) (xy 87.704612 -298.499848) (xy 87.68108 -298.440415) (xy 87.665183 -298.378501)
			(xy 87.657172 -298.315083) (xy 79.401 -298.315083) (xy 75.936455 -301.779686) (xy 92.19006 -301.779686)
			(xy 92.194131 -301.724064) (xy 92.206257 -301.669627) (xy 92.22618 -301.617536) (xy 92.253476 -301.568901)
			(xy 92.287562 -301.524758) (xy 92.327711 -301.486049) (xy 92.373069 -301.453598) (xy 92.422669 -301.428097)
			(xy 92.475453 -301.41009) (xy 92.530296 -301.39996) (xy 92.58603 -301.397923) (xy 92.641467 -301.404023)
			(xy 92.695424 -301.418129) (xy 92.746753 -301.439941) (xy 92.794359 -301.468995) (xy 92.837227 -301.50467)
			(xy 92.874444 -301.546207) (xy 92.905217 -301.59272) (xy 92.928889 -301.643217) (xy 92.944957 -301.696624)
			(xy 92.953077 -301.7518) (xy 92.953586 -301.779686) (xy 92.953077 -301.807572) (xy 92.944957 -301.862748)
			(xy 92.928889 -301.916155) (xy 92.905217 -301.966652) (xy 92.874444 -302.013165) (xy 92.837227 -302.054702)
			(xy 92.794359 -302.090377) (xy 92.746753 -302.119431) (xy 92.695424 -302.141243) (xy 92.641467 -302.155349)
			(xy 92.58603 -302.161449) (xy 92.530296 -302.159412) (xy 92.475453 -302.149282) (xy 92.422669 -302.131275)
			(xy 92.373069 -302.105774) (xy 92.327711 -302.073323) (xy 92.287562 -302.034614) (xy 92.253476 -301.990471)
			(xy 92.22618 -301.941836) (xy 92.206257 -301.889745) (xy 92.194131 -301.835308) (xy 92.19006 -301.779686)
			(xy 75.936455 -301.779686) (xy 72.93575 -304.780442) (xy 78.81214 -304.780442) (xy 78.81617 -304.638107)
			(xy 78.828245 -304.496227) (xy 78.848328 -304.355259) (xy 78.876355 -304.215652) (xy 78.912235 -304.077854)
			(xy 78.955853 -303.942307) (xy 79.00707 -303.809445) (xy 79.065721 -303.679693) (xy 79.131619 -303.553467)
			(xy 79.204553 -303.431171) (xy 79.28429 -303.313198) (xy 79.370572 -303.199925) (xy 79.463125 -303.091714)
			(xy 79.561652 -302.988913) (xy 79.665837 -302.891851) (xy 79.775346 -302.800839) (xy 79.889829 -302.716167)
			(xy 80.008919 -302.638109) (xy 80.132234 -302.566913) (xy 80.25938 -302.502807) (xy 80.389949 -302.445998)
			(xy 80.523523 -302.396666) (xy 80.659674 -302.35497) (xy 80.797965 -302.321044) (xy 80.937955 -302.294996)
			(xy 81.079194 -302.27691) (xy 81.22123 -302.266843) (xy 81.363608 -302.264828) (xy 81.505872 -302.270871)
			(xy 81.647566 -302.284953) (xy 81.788236 -302.307029) (xy 81.927433 -302.337029) (xy 82.064709 -302.374855)
			(xy 82.199625 -302.420387) (xy 82.331749 -302.473478) (xy 82.460658 -302.53396) (xy 82.585939 -302.601638)
			(xy 82.70719 -302.676295) (xy 82.824023 -302.757693) (xy 82.873373 -302.7964) (xy 84.778634 -302.7964)
			(xy 84.782549 -302.719211) (xy 84.794252 -302.642815) (xy 84.813625 -302.567994) (xy 84.840468 -302.495517)
			(xy 84.874505 -302.426128) (xy 84.915388 -302.360538) (xy 84.962697 -302.299421) (xy 85.015946 -302.243403)
			(xy 85.074589 -302.193061) (xy 85.138025 -302.148909) (xy 85.205602 -302.111402) (xy 85.276627 -302.080924)
			(xy 85.35037 -302.057788) (xy 85.426076 -302.042231) (xy 85.502968 -302.034413) (xy 85.541612 -302.03394)
			(xy 85.579854 -302.034414) (xy 85.655949 -302.042117) (xy 85.730889 -302.057403) (xy 85.803921 -302.08012)
			(xy 85.8393 -302.094646) (xy 85.848893 -302.098199) (xy 85.869331 -302.098199) (xy 85.878924 -302.094646)
			(xy 85.91431 -302.08014) (xy 85.987342 -302.057433) (xy 86.06228 -302.042148) (xy 86.138372 -302.034437)
			(xy 86.176612 -302.03394) (xy 86.215259 -302.034334) (xy 86.292157 -302.042155) (xy 86.367869 -302.057715)
			(xy 86.441619 -302.080855) (xy 86.512649 -302.111338) (xy 86.58023 -302.148849) (xy 86.643671 -302.193006)
			(xy 86.702318 -302.243354) (xy 86.755571 -302.299377) (xy 86.802883 -302.3605) (xy 86.843769 -302.426096)
			(xy 86.877808 -302.495491) (xy 86.904653 -302.567974) (xy 86.924027 -302.642801) (xy 86.935731 -302.719205)
			(xy 86.939646 -302.7964) (xy 86.935731 -302.873595) (xy 86.924027 -302.949999) (xy 86.904653 -303.024826)
			(xy 86.877808 -303.097309) (xy 86.843769 -303.166704) (xy 86.802883 -303.2323) (xy 86.785179 -303.255172)
			(xy 92.274134 -303.255172) (xy 92.278205 -303.19955) (xy 92.290331 -303.145113) (xy 92.310254 -303.093022)
			(xy 92.33755 -303.044387) (xy 92.371636 -303.000244) (xy 92.411785 -302.961535) (xy 92.457143 -302.929084)
			(xy 92.506743 -302.903583) (xy 92.559527 -302.885576) (xy 92.61437 -302.875446) (xy 92.670104 -302.873409)
			(xy 92.725541 -302.879509) (xy 92.779498 -302.893615) (xy 92.830827 -302.915427) (xy 92.878433 -302.944481)
			(xy 92.921301 -302.980156) (xy 92.958518 -303.021693) (xy 92.989291 -303.068206) (xy 93.012963 -303.118703)
			(xy 93.029031 -303.17211) (xy 93.037151 -303.227286) (xy 93.03766 -303.255172) (xy 93.037151 -303.283058)
			(xy 93.029031 -303.338234) (xy 93.012963 -303.391641) (xy 92.989291 -303.442138) (xy 92.958518 -303.488651)
			(xy 92.921301 -303.530188) (xy 92.878433 -303.565863) (xy 92.830827 -303.594917) (xy 92.779498 -303.616729)
			(xy 92.725541 -303.630835) (xy 92.670104 -303.636935) (xy 92.61437 -303.634898) (xy 92.559527 -303.624768)
			(xy 92.506743 -303.606761) (xy 92.457143 -303.58126) (xy 92.411785 -303.548809) (xy 92.371636 -303.5101)
			(xy 92.33755 -303.465957) (xy 92.310254 -303.417322) (xy 92.290331 -303.365231) (xy 92.278205 -303.310794)
			(xy 92.274134 -303.255172) (xy 86.785179 -303.255172) (xy 86.755571 -303.293423) (xy 86.702318 -303.349446)
			(xy 86.643671 -303.399794) (xy 86.58023 -303.443951) (xy 86.512649 -303.481462) (xy 86.441619 -303.511945)
			(xy 86.367869 -303.535085) (xy 86.292157 -303.550645) (xy 86.215259 -303.558466) (xy 86.176612 -303.558956)
			(xy 86.138371 -303.558474) (xy 86.062276 -303.550774) (xy 85.987335 -303.53549) (xy 85.914303 -303.512775)
			(xy 85.878924 -303.49825) (xy 85.869331 -303.494697) (xy 85.848893 -303.494697) (xy 85.8393 -303.49825)
			(xy 85.803924 -303.512781) (xy 85.730888 -303.535481) (xy 85.655947 -303.550759) (xy 85.579853 -303.558462)
			(xy 85.541612 -303.558956) (xy 85.502968 -303.558387) (xy 85.426076 -303.550569) (xy 85.35037 -303.535012)
			(xy 85.276627 -303.511876) (xy 85.205602 -303.481398) (xy 85.138025 -303.443891) (xy 85.074589 -303.399739)
			(xy 85.015946 -303.349397) (xy 84.962697 -303.293379) (xy 84.915388 -303.232262) (xy 84.874505 -303.166672)
			(xy 84.840468 -303.097283) (xy 84.813625 -303.024806) (xy 84.794252 -302.949985) (xy 84.782549 -302.873589)
			(xy 84.778634 -302.7964) (xy 82.873373 -302.7964) (xy 82.936064 -302.84557) (xy 83.042954 -302.939645)
			(xy 83.144351 -303.039617) (xy 83.239929 -303.145165) (xy 83.329383 -303.255951) (xy 83.412425 -303.37162)
			(xy 83.488791 -303.491803) (xy 83.558235 -303.616113) (xy 83.620535 -303.744154) (xy 83.675491 -303.875513)
			(xy 83.722928 -304.009772) (xy 83.729734 -304.033174) (xy 92.945966 -304.033174) (xy 92.946468 -304.001213)
			(xy 92.954479 -303.937795) (xy 92.970376 -303.875881) (xy 92.993908 -303.816448) (xy 93.024702 -303.760433)
			(xy 93.062275 -303.708718) (xy 93.106032 -303.662121) (xy 93.155285 -303.621376) (xy 93.209256 -303.587125)
			(xy 93.267095 -303.559908) (xy 93.327888 -303.540155) (xy 93.390678 -303.528177) (xy 93.454474 -303.524164)
			(xy 93.51827 -303.528177) (xy 93.58106 -303.540155) (xy 93.641853 -303.559908) (xy 93.699692 -303.587125)
			(xy 93.753663 -303.621376) (xy 93.802916 -303.662121) (xy 93.846673 -303.708718) (xy 93.884246 -303.760433)
			(xy 93.91504 -303.816448) (xy 93.938572 -303.875881) (xy 93.954469 -303.937795) (xy 93.96248 -304.001213)
			(xy 93.962982 -304.033174) (xy 93.962469 -304.065957) (xy 93.954045 -304.13098) (xy 93.937332 -304.19438)
			(xy 93.912609 -304.255106) (xy 93.880284 -304.312151) (xy 93.840896 -304.364567) (xy 93.795096 -304.411486)
			(xy 93.769688 -304.432208) (xy 93.762771 -304.438106) (xy 93.753283 -304.453598) (xy 93.751146 -304.462434)
			(xy 93.745304 -304.492152) (xy 93.743955 -304.500954) (xy 93.74683 -304.518517) (xy 93.750892 -304.526442)
			(xy 93.765761 -304.554834) (xy 93.786839 -304.615355) (xy 93.797504 -304.678548) (xy 93.798136 -304.710592)
			(xy 93.79765 -304.737843) (xy 93.789894 -304.791791) (xy 93.774539 -304.844086) (xy 93.751897 -304.893663)
			(xy 93.722431 -304.939513) (xy 93.68674 -304.980704) (xy 93.645549 -305.016395) (xy 93.599699 -305.045861)
			(xy 93.550122 -305.068503) (xy 93.497827 -305.083858) (xy 93.443879 -305.091614) (xy 93.389377 -305.091614)
			(xy 93.335429 -305.083858) (xy 93.283134 -305.068503) (xy 93.233557 -305.045861) (xy 93.187707 -305.016395)
			(xy 93.146516 -304.980704) (xy 93.110825 -304.939513) (xy 93.081359 -304.893663) (xy 93.058717 -304.844086)
			(xy 93.043362 -304.791791) (xy 93.035606 -304.737843) (xy 93.03512 -304.710592) (xy 93.035659 -304.681226)
			(xy 93.0447 -304.623194) (xy 93.062521 -304.567231) (xy 93.088702 -304.514657) (xy 93.105224 -304.490374)
			(xy 93.110038 -304.482893) (xy 93.114699 -304.465737) (xy 93.114368 -304.456846) (xy 93.111574 -304.426366)
			(xy 93.110508 -304.417453) (xy 93.102963 -304.401181) (xy 93.096842 -304.394616) (xy 93.073395 -304.370658)
			(xy 93.032348 -304.317659) (xy 92.99862 -304.259726) (xy 92.972796 -304.197864) (xy 92.955324 -304.133145)
			(xy 92.946506 -304.066692) (xy 92.945966 -304.033174) (xy 83.729734 -304.033174) (xy 83.762692 -304.146499)
			(xy 83.794658 -304.285257) (xy 83.818723 -304.425601) (xy 83.834809 -304.567082) (xy 83.842864 -304.709246)
			(xy 83.843071 -304.738489) (xy 91.753938 -304.738489) (xy 91.753938 -304.674567) (xy 91.761949 -304.611149)
			(xy 91.777846 -304.549235) (xy 91.801378 -304.489802) (xy 91.832172 -304.433787) (xy 91.869745 -304.382072)
			(xy 91.913502 -304.335475) (xy 91.962755 -304.29473) (xy 92.016726 -304.260479) (xy 92.074565 -304.233262)
			(xy 92.135358 -304.213509) (xy 92.198148 -304.201531) (xy 92.261944 -304.197518) (xy 92.32574 -304.201531)
			(xy 92.38853 -304.213509) (xy 92.449323 -304.233262) (xy 92.507162 -304.260479) (xy 92.561133 -304.29473)
			(xy 92.610386 -304.335475) (xy 92.654143 -304.382072) (xy 92.691716 -304.433787) (xy 92.72251 -304.489802)
			(xy 92.746042 -304.549235) (xy 92.761939 -304.611149) (xy 92.76995 -304.674567) (xy 92.770452 -304.706528)
			(xy 92.76995 -304.738489) (xy 92.761939 -304.801907) (xy 92.746042 -304.863821) (xy 92.72251 -304.923254)
			(xy 92.691716 -304.979269) (xy 92.654143 -305.030984) (xy 92.610386 -305.077581) (xy 92.561133 -305.118326)
			(xy 92.507162 -305.152577) (xy 92.449323 -305.179794) (xy 92.38853 -305.199547) (xy 92.32574 -305.211525)
			(xy 92.261944 -305.215539) (xy 92.198148 -305.211525) (xy 92.135358 -305.199547) (xy 92.074565 -305.179794)
			(xy 92.016726 -305.152577) (xy 91.962755 -305.118326) (xy 91.913502 -305.077581) (xy 91.869745 -305.030984)
			(xy 91.832172 -304.979269) (xy 91.801378 -304.923254) (xy 91.777846 -304.863821) (xy 91.761949 -304.801907)
			(xy 91.753938 -304.738489) (xy 83.843071 -304.738489) (xy 83.843368 -304.780442) (xy 83.842864 -304.851638)
			(xy 83.834809 -304.993802) (xy 83.818723 -305.135283) (xy 83.794658 -305.275627) (xy 83.762692 -305.414385)
			(xy 83.722928 -305.551112) (xy 83.675491 -305.685371) (xy 83.620535 -305.81673) (xy 83.558235 -305.944771)
			(xy 83.488791 -306.069081) (xy 83.412425 -306.189264) (xy 83.329383 -306.304933) (xy 83.239929 -306.415719)
			(xy 83.196059 -306.464165) (xy 87.854784 -306.464165) (xy 87.854784 -306.400243) (xy 87.862795 -306.336825)
			(xy 87.878692 -306.274911) (xy 87.902224 -306.215478) (xy 87.933018 -306.159463) (xy 87.970591 -306.107748)
			(xy 88.014348 -306.061151) (xy 88.063601 -306.020406) (xy 88.117572 -305.986155) (xy 88.175411 -305.958938)
			(xy 88.236204 -305.939185) (xy 88.298994 -305.927207) (xy 88.36279 -305.923194) (xy 88.426586 -305.927207)
			(xy 88.489376 -305.939185) (xy 88.550169 -305.958938) (xy 88.608008 -305.986155) (xy 88.659611 -306.018903)
			(xy 93.552258 -306.018903) (xy 93.552258 -305.954981) (xy 93.560269 -305.891563) (xy 93.576166 -305.829649)
			(xy 93.599698 -305.770216) (xy 93.630492 -305.714201) (xy 93.668065 -305.662486) (xy 93.711822 -305.615889)
			(xy 93.761075 -305.575144) (xy 93.815046 -305.540893) (xy 93.872885 -305.513676) (xy 93.933678 -305.493923)
			(xy 93.996468 -305.481945) (xy 94.060264 -305.477932) (xy 94.12406 -305.481945) (xy 94.18685 -305.493923)
			(xy 94.247643 -305.513676) (xy 94.305482 -305.540893) (xy 94.359453 -305.575144) (xy 94.408706 -305.615889)
			(xy 94.452463 -305.662486) (xy 94.490036 -305.714201) (xy 94.52083 -305.770216) (xy 94.544362 -305.829649)
			(xy 94.560259 -305.891563) (xy 94.56827 -305.954981) (xy 94.568772 -305.986942) (xy 94.56827 -306.018903)
			(xy 94.560259 -306.082321) (xy 94.544362 -306.144235) (xy 94.52083 -306.203668) (xy 94.490036 -306.259683)
			(xy 94.452463 -306.311398) (xy 94.408706 -306.357995) (xy 94.359453 -306.39874) (xy 94.305482 -306.432991)
			(xy 94.247643 -306.460208) (xy 94.18685 -306.479961) (xy 94.12406 -306.491939) (xy 94.060264 -306.495953)
			(xy 93.996468 -306.491939) (xy 93.933678 -306.479961) (xy 93.872885 -306.460208) (xy 93.815046 -306.432991)
			(xy 93.761075 -306.39874) (xy 93.711822 -306.357995) (xy 93.668065 -306.311398) (xy 93.630492 -306.259683)
			(xy 93.599698 -306.203668) (xy 93.576166 -306.144235) (xy 93.560269 -306.082321) (xy 93.552258 -306.018903)
			(xy 88.659611 -306.018903) (xy 88.661979 -306.020406) (xy 88.711232 -306.061151) (xy 88.754989 -306.107748)
			(xy 88.792562 -306.159463) (xy 88.823356 -306.215478) (xy 88.846888 -306.274911) (xy 88.862785 -306.336825)
			(xy 88.870796 -306.400243) (xy 88.871298 -306.432204) (xy 88.870796 -306.464165) (xy 88.862785 -306.527583)
			(xy 88.846888 -306.589497) (xy 88.823356 -306.64893) (xy 88.792562 -306.704945) (xy 88.754989 -306.75666)
			(xy 88.711232 -306.803257) (xy 88.661979 -306.844002) (xy 88.608008 -306.878253) (xy 88.550169 -306.90547)
			(xy 88.489376 -306.925223) (xy 88.426586 -306.937201) (xy 88.36279 -306.941215) (xy 88.298994 -306.937201)
			(xy 88.236204 -306.925223) (xy 88.175411 -306.90547) (xy 88.117572 -306.878253) (xy 88.063601 -306.844002)
			(xy 88.014348 -306.803257) (xy 87.970591 -306.75666) (xy 87.933018 -306.704945) (xy 87.902224 -306.64893)
			(xy 87.878692 -306.589497) (xy 87.862795 -306.527583) (xy 87.854784 -306.464165) (xy 83.196059 -306.464165)
			(xy 83.144351 -306.521267) (xy 83.042954 -306.621239) (xy 82.936064 -306.715314) (xy 82.824023 -306.803191)
			(xy 82.70719 -306.884589) (xy 82.585939 -306.959246) (xy 82.460658 -307.026924) (xy 82.331749 -307.087406)
			(xy 82.199625 -307.140497) (xy 82.064709 -307.186029) (xy 81.927433 -307.223855) (xy 81.788236 -307.253855)
			(xy 81.647566 -307.275931) (xy 81.505872 -307.290013) (xy 81.363608 -307.296056) (xy 81.22123 -307.294041)
			(xy 81.079194 -307.283974) (xy 80.937955 -307.265888) (xy 80.797965 -307.23984) (xy 80.659674 -307.205914)
			(xy 80.523523 -307.164218) (xy 80.389949 -307.114886) (xy 80.25938 -307.058077) (xy 80.132234 -306.993971)
			(xy 80.008919 -306.922775) (xy 79.889829 -306.844717) (xy 79.775346 -306.760045) (xy 79.665837 -306.669033)
			(xy 79.561652 -306.571971) (xy 79.463125 -306.46917) (xy 79.370572 -306.360959) (xy 79.28429 -306.247686)
			(xy 79.204553 -306.129713) (xy 79.131619 -306.007417) (xy 79.065721 -305.881191) (xy 79.00707 -305.751439)
			(xy 78.955853 -305.618577) (xy 78.912235 -305.48303) (xy 78.876355 -305.345232) (xy 78.848328 -305.205625)
			(xy 78.828245 -305.064657) (xy 78.81617 -304.922777) (xy 78.81214 -304.780442) (xy 72.93575 -304.780442)
			(xy 70.331067 -307.385169) (xy 88.750896 -307.385169) (xy 88.750896 -307.321247) (xy 88.758907 -307.257829)
			(xy 88.774804 -307.195915) (xy 88.798336 -307.136482) (xy 88.82913 -307.080467) (xy 88.866703 -307.028752)
			(xy 88.91046 -306.982155) (xy 88.959713 -306.94141) (xy 89.013684 -306.907159) (xy 89.071523 -306.879942)
			(xy 89.132316 -306.860189) (xy 89.195106 -306.848211) (xy 89.258902 -306.844198) (xy 89.322698 -306.848211)
			(xy 89.385488 -306.860189) (xy 89.446281 -306.879942) (xy 89.50412 -306.907159) (xy 89.558091 -306.94141)
			(xy 89.607344 -306.982155) (xy 89.651101 -307.028752) (xy 89.688674 -307.080467) (xy 89.707611 -307.114913)
			(xy 90.238828 -307.114913) (xy 90.238828 -307.050991) (xy 90.246839 -306.987573) (xy 90.262736 -306.925659)
			(xy 90.286268 -306.866226) (xy 90.317062 -306.810211) (xy 90.354635 -306.758496) (xy 90.398392 -306.711899)
			(xy 90.447645 -306.671154) (xy 90.501616 -306.636903) (xy 90.559455 -306.609686) (xy 90.620248 -306.589933)
			(xy 90.683038 -306.577955) (xy 90.746834 -306.573942) (xy 90.81063 -306.577955) (xy 90.833276 -306.582275)
			(xy 91.420182 -306.582275) (xy 91.420182 -306.518353) (xy 91.428193 -306.454935) (xy 91.44409 -306.393021)
			(xy 91.467622 -306.333588) (xy 91.498416 -306.277573) (xy 91.535989 -306.225858) (xy 91.579746 -306.179261)
			(xy 91.628999 -306.138516) (xy 91.68297 -306.104265) (xy 91.740809 -306.077048) (xy 91.801602 -306.057295)
			(xy 91.864392 -306.045317) (xy 91.928188 -306.041304) (xy 91.991984 -306.045317) (xy 92.054774 -306.057295)
			(xy 92.115567 -306.077048) (xy 92.173406 -306.104265) (xy 92.227377 -306.138516) (xy 92.27663 -306.179261)
			(xy 92.320387 -306.225858) (xy 92.35796 -306.277573) (xy 92.388754 -306.333588) (xy 92.412286 -306.393021)
			(xy 92.428183 -306.454935) (xy 92.436194 -306.518353) (xy 92.436696 -306.550314) (xy 92.436194 -306.582275)
			(xy 92.428183 -306.645693) (xy 92.412286 -306.707607) (xy 92.40187 -306.733913) (xy 95.064828 -306.733913)
			(xy 95.064828 -306.669991) (xy 95.072839 -306.606573) (xy 95.088736 -306.544659) (xy 95.112268 -306.485226)
			(xy 95.143062 -306.429211) (xy 95.180635 -306.377496) (xy 95.224392 -306.330899) (xy 95.273645 -306.290154)
			(xy 95.327616 -306.255903) (xy 95.385455 -306.228686) (xy 95.446248 -306.208933) (xy 95.509038 -306.196955)
			(xy 95.572834 -306.192942) (xy 95.63663 -306.196955) (xy 95.69942 -306.208933) (xy 95.760213 -306.228686)
			(xy 95.818052 -306.255903) (xy 95.872023 -306.290154) (xy 95.921276 -306.330899) (xy 95.965033 -306.377496)
			(xy 96.002606 -306.429211) (xy 96.0334 -306.485226) (xy 96.056932 -306.544659) (xy 96.072829 -306.606573)
			(xy 96.08084 -306.669991) (xy 96.081342 -306.701952) (xy 96.08084 -306.733913) (xy 96.072829 -306.797331)
			(xy 96.056932 -306.859245) (xy 96.0334 -306.918678) (xy 96.002606 -306.974693) (xy 95.965033 -307.026408)
			(xy 95.921276 -307.073005) (xy 95.872023 -307.11375) (xy 95.818052 -307.148001) (xy 95.760213 -307.175218)
			(xy 95.69942 -307.194971) (xy 95.63663 -307.206949) (xy 95.572834 -307.210963) (xy 95.509038 -307.206949)
			(xy 95.446248 -307.194971) (xy 95.385455 -307.175218) (xy 95.327616 -307.148001) (xy 95.273645 -307.11375)
			(xy 95.224392 -307.073005) (xy 95.180635 -307.026408) (xy 95.143062 -306.974693) (xy 95.112268 -306.918678)
			(xy 95.088736 -306.859245) (xy 95.072839 -306.797331) (xy 95.064828 -306.733913) (xy 92.40187 -306.733913)
			(xy 92.388754 -306.76704) (xy 92.35796 -306.823055) (xy 92.320387 -306.87477) (xy 92.27663 -306.921367)
			(xy 92.227377 -306.962112) (xy 92.173406 -306.996363) (xy 92.115567 -307.02358) (xy 92.054774 -307.043333)
			(xy 91.991984 -307.055311) (xy 91.928188 -307.059325) (xy 91.864392 -307.055311) (xy 91.801602 -307.043333)
			(xy 91.740809 -307.02358) (xy 91.68297 -306.996363) (xy 91.628999 -306.962112) (xy 91.579746 -306.921367)
			(xy 91.535989 -306.87477) (xy 91.498416 -306.823055) (xy 91.467622 -306.76704) (xy 91.44409 -306.707607)
			(xy 91.428193 -306.645693) (xy 91.420182 -306.582275) (xy 90.833276 -306.582275) (xy 90.87342 -306.589933)
			(xy 90.934213 -306.609686) (xy 90.992052 -306.636903) (xy 91.046023 -306.671154) (xy 91.095276 -306.711899)
			(xy 91.139033 -306.758496) (xy 91.176606 -306.810211) (xy 91.2074 -306.866226) (xy 91.230932 -306.925659)
			(xy 91.246829 -306.987573) (xy 91.25484 -307.050991) (xy 91.255342 -307.082952) (xy 91.25484 -307.114913)
			(xy 91.246829 -307.178331) (xy 91.237536 -307.214524) (xy 93.048326 -307.214524) (xy 93.052397 -307.158902)
			(xy 93.064523 -307.104465) (xy 93.084446 -307.052374) (xy 93.111742 -307.003739) (xy 93.145828 -306.959596)
			(xy 93.185977 -306.920887) (xy 93.231335 -306.888436) (xy 93.280935 -306.862935) (xy 93.333719 -306.844928)
			(xy 93.388562 -306.834798) (xy 93.444296 -306.832761) (xy 93.499733 -306.838861) (xy 93.55369 -306.852967)
			(xy 93.605019 -306.874779) (xy 93.652625 -306.903833) (xy 93.695493 -306.939508) (xy 93.73271 -306.981045)
			(xy 93.763483 -307.027558) (xy 93.787155 -307.078055) (xy 93.803223 -307.131462) (xy 93.811343 -307.186638)
			(xy 93.811852 -307.214524) (xy 93.811343 -307.24241) (xy 93.803223 -307.297586) (xy 93.787155 -307.350993)
			(xy 93.763483 -307.40149) (xy 93.73271 -307.448003) (xy 93.695493 -307.48954) (xy 93.652625 -307.525215)
			(xy 93.605019 -307.554269) (xy 93.55369 -307.576081) (xy 93.499733 -307.590187) (xy 93.444296 -307.596287)
			(xy 93.388562 -307.59425) (xy 93.333719 -307.58412) (xy 93.280935 -307.566113) (xy 93.231335 -307.540612)
			(xy 93.185977 -307.508161) (xy 93.145828 -307.469452) (xy 93.111742 -307.425309) (xy 93.084446 -307.376674)
			(xy 93.064523 -307.324583) (xy 93.052397 -307.270146) (xy 93.048326 -307.214524) (xy 91.237536 -307.214524)
			(xy 91.230932 -307.240245) (xy 91.2074 -307.299678) (xy 91.176606 -307.355693) (xy 91.139033 -307.407408)
			(xy 91.095276 -307.454005) (xy 91.046023 -307.49475) (xy 90.992052 -307.529001) (xy 90.934213 -307.556218)
			(xy 90.87342 -307.575971) (xy 90.81063 -307.587949) (xy 90.746834 -307.591963) (xy 90.683038 -307.587949)
			(xy 90.620248 -307.575971) (xy 90.559455 -307.556218) (xy 90.501616 -307.529001) (xy 90.447645 -307.49475)
			(xy 90.398392 -307.454005) (xy 90.354635 -307.407408) (xy 90.317062 -307.355693) (xy 90.286268 -307.299678)
			(xy 90.262736 -307.240245) (xy 90.246839 -307.178331) (xy 90.238828 -307.114913) (xy 89.707611 -307.114913)
			(xy 89.719468 -307.136482) (xy 89.743 -307.195915) (xy 89.758897 -307.257829) (xy 89.766908 -307.321247)
			(xy 89.76741 -307.353208) (xy 89.766908 -307.385169) (xy 89.758897 -307.448587) (xy 89.743 -307.510501)
			(xy 89.719468 -307.569934) (xy 89.688674 -307.625949) (xy 89.651101 -307.677664) (xy 89.607344 -307.724261)
			(xy 89.558091 -307.765006) (xy 89.50412 -307.799257) (xy 89.446281 -307.826474) (xy 89.385488 -307.846227)
			(xy 89.322698 -307.858205) (xy 89.258902 -307.862219) (xy 89.195106 -307.858205) (xy 89.132316 -307.846227)
			(xy 89.071523 -307.826474) (xy 89.013684 -307.799257) (xy 88.959713 -307.765006) (xy 88.91046 -307.724261)
			(xy 88.866703 -307.677664) (xy 88.82913 -307.625949) (xy 88.798336 -307.569934) (xy 88.774804 -307.510501)
			(xy 88.758907 -307.448587) (xy 88.750896 -307.385169) (xy 70.331067 -307.385169) (xy 68.032289 -309.683986)
			(xy 78.652905 -309.683986) (xy 78.652905 -309.632014) (xy 78.661035 -309.580682) (xy 78.677095 -309.531254)
			(xy 78.700688 -309.484947) (xy 78.731235 -309.4429) (xy 78.767984 -309.40615) (xy 78.810028 -309.3756)
			(xy 78.856334 -309.352003) (xy 78.905761 -309.33594) (xy 78.957092 -309.327807) (xy 78.983078 -309.327296)
			(xy 78.999899 -309.32751) (xy 79.033366 -309.330946) (xy 79.04988 -309.334154) (xy 79.061407 -309.335998)
			(xy 79.083983 -309.330144) (xy 79.101664 -309.314933) (xy 79.106776 -309.304436) (xy 79.121518 -309.271638)
			(xy 79.158868 -309.210193) (xy 79.181198 -309.182008) (xy 79.186433 -309.175061) (xy 79.192281 -309.158695)
			(xy 79.192628 -309.150004) (xy 79.192628 -308.995826) (xy 79.192246 -308.987081) (xy 79.186421 -308.97059)
			(xy 79.181198 -308.963568) (xy 79.162531 -308.940162) (xy 79.130217 -308.889761) (xy 79.104057 -308.835909)
			(xy 79.084417 -308.779352) (xy 79.077566 -308.750208) (xy 79.074502 -308.738946) (xy 79.06001 -308.720689)
			(xy 79.038937 -308.710723) (xy 79.027274 -308.71033) (xy 79.023464 -308.71033) (xy 79.02321 -308.71033)
			(xy 78.997222 -308.709804) (xy 78.945886 -308.701674) (xy 78.896453 -308.685614) (xy 78.850141 -308.662018)
			(xy 78.808091 -308.631468) (xy 78.771338 -308.594716) (xy 78.740787 -308.552667) (xy 78.71719 -308.506356)
			(xy 78.701128 -308.456924) (xy 78.692997 -308.405588) (xy 78.692997 -308.353612) (xy 78.701128 -308.302276)
			(xy 78.71719 -308.252844) (xy 78.740787 -308.206533) (xy 78.771338 -308.164484) (xy 78.808091 -308.127732)
			(xy 78.850141 -308.097182) (xy 78.896453 -308.073586) (xy 78.945886 -308.057526) (xy 78.997222 -308.049396)
			(xy 79.02321 -308.048914) (xy 79.047989 -308.049367) (xy 79.096992 -308.056757) (xy 79.144345 -308.07137)
			(xy 79.188991 -308.092881) (xy 79.22993 -308.120807) (xy 79.266249 -308.154525) (xy 79.282036 -308.173628)
			(xy 79.289703 -308.182366) (xy 79.310676 -308.192336) (xy 79.333897 -308.192065) (xy 79.34452 -308.187344)
			(xy 79.371291 -308.174267) (xy 79.427222 -308.153727) (xy 79.485172 -308.139877) (xy 79.544345 -308.132906)
			(xy 79.574136 -308.13248) (xy 79.604867 -308.132922) (xy 79.665881 -308.140334) (xy 79.725557 -308.155046)
			(xy 79.783025 -308.176844) (xy 79.837446 -308.20541) (xy 79.888028 -308.240326) (xy 79.934032 -308.281085)
			(xy 79.974789 -308.327091) (xy 80.009703 -308.377674) (xy 80.038266 -308.432097) (xy 80.060061 -308.489566)
			(xy 80.062386 -308.499) (xy 88.375291 -308.499) (xy 88.379305 -308.435208) (xy 88.391281 -308.372422)
			(xy 88.411032 -308.311632) (xy 88.438245 -308.253797) (xy 88.472492 -308.199828) (xy 88.513233 -308.150577)
			(xy 88.559825 -308.106819) (xy 88.611534 -308.069246) (xy 88.667543 -308.03845) (xy 88.726971 -308.014916)
			(xy 88.78888 -307.999015) (xy 88.852293 -307.990999) (xy 88.884252 -307.990494) (xy 88.915807 -307.990985)
			(xy 88.978432 -307.998793) (xy 89.039608 -308.014296) (xy 89.098393 -308.037255) (xy 89.153883 -308.067316)
			(xy 89.205224 -308.104017) (xy 89.251626 -308.146792) (xy 89.272364 -308.17058) (xy 89.279033 -308.177673)
			(xy 89.296261 -308.186696) (xy 89.305892 -308.188106) (xy 89.386156 -308.196488) (xy 89.404698 -308.191154)
			(xy 89.412572 -308.185058) (xy 89.432771 -308.169776) (xy 89.476437 -308.144108) (xy 89.523118 -308.124452)
			(xy 89.571992 -308.111153) (xy 89.622197 -308.104446) (xy 89.647522 -308.104032) (xy 89.674775 -308.104439)
			(xy 89.728726 -308.112199) (xy 89.781024 -308.127558) (xy 89.830603 -308.150203) (xy 89.876456 -308.179673)
			(xy 89.917648 -308.215368) (xy 89.953341 -308.256562) (xy 89.982808 -308.302416) (xy 90.00545 -308.351997)
			(xy 90.020805 -308.404295) (xy 90.028562 -308.458247) (xy 90.028562 -308.512753) (xy 90.020805 -308.566705)
			(xy 90.00545 -308.619003) (xy 89.982808 -308.668584) (xy 89.953341 -308.714438) (xy 89.917648 -308.755632)
			(xy 89.876456 -308.791327) (xy 89.830603 -308.820797) (xy 89.781024 -308.843442) (xy 89.728726 -308.858801)
			(xy 89.674775 -308.866561) (xy 89.647522 -308.867048) (xy 89.617533 -308.866515) (xy 89.558297 -308.85712)
			(xy 89.501259 -308.838573) (xy 89.447825 -308.811331) (xy 89.42324 -308.79415) (xy 89.415112 -308.788308)
			(xy 89.396316 -308.783736) (xy 89.306908 -308.795928) (xy 89.290144 -308.80558) (xy 89.283794 -308.813454)
			(xy 89.263071 -308.838942) (xy 89.216142 -308.884911) (xy 89.163684 -308.924452) (xy 89.10657 -308.956907)
			(xy 89.045751 -308.981735) (xy 88.982241 -308.998523) (xy 88.917098 -309.006991) (xy 88.884252 -309.00751)
			(xy 88.852293 -309.007001) (xy 88.78888 -308.998985) (xy 88.726971 -308.983084) (xy 88.667543 -308.95955)
			(xy 88.611534 -308.928754) (xy 88.559825 -308.891181) (xy 88.513233 -308.847423) (xy 88.472492 -308.798172)
			(xy 88.438245 -308.744203) (xy 88.411032 -308.686368) (xy 88.391281 -308.625578) (xy 88.379305 -308.562792)
			(xy 88.375291 -308.499) (xy 80.062386 -308.499) (xy 80.07477 -308.549242) (xy 80.08218 -308.610257)
			(xy 80.082644 -308.640988) (xy 80.082051 -308.675953) (xy 80.072452 -308.745222) (xy 80.053446 -308.81252)
			(xy 80.025393 -308.876577) (xy 79.988823 -308.936184) (xy 79.967074 -308.963568) (xy 79.961814 -308.970574)
			(xy 79.955962 -308.987071) (xy 79.955644 -308.995826) (xy 79.955644 -309.14975) (xy 79.955977 -309.1585)
			(xy 79.961834 -309.174992) (xy 79.967074 -309.182008) (xy 79.988812 -309.209399) (xy 80.025366 -309.269012)
			(xy 80.053413 -309.333068) (xy 80.072425 -309.400362) (xy 80.082043 -309.469625) (xy 80.082644 -309.504588)
			(xy 80.082133 -309.535317) (xy 80.079424 -309.557631) (xy 85.733122 -309.557631) (xy 85.733122 -309.493709)
			(xy 85.741133 -309.430291) (xy 85.75703 -309.368377) (xy 85.780562 -309.308944) (xy 85.811356 -309.252929)
			(xy 85.848929 -309.201214) (xy 85.892686 -309.154617) (xy 85.941939 -309.113872) (xy 85.99591 -309.079621)
			(xy 86.053749 -309.052404) (xy 86.114542 -309.032651) (xy 86.177332 -309.020673) (xy 86.241128 -309.01666)
			(xy 86.304924 -309.020673) (xy 86.31448 -309.022496) (xy 93.06433 -309.022496) (xy 93.064781 -308.997717)
			(xy 93.07217 -308.948714) (xy 93.086784 -308.90136) (xy 93.108295 -308.856714) (xy 93.136221 -308.815775)
			(xy 93.16994 -308.779457) (xy 93.189044 -308.76367) (xy 93.197771 -308.75599) (xy 93.207755 -308.735026)
			(xy 93.207484 -308.711807) (xy 93.20276 -308.701186) (xy 93.189687 -308.674413) (xy 93.169146 -308.618484)
			(xy 93.155294 -308.560534) (xy 93.148322 -308.501361) (xy 93.147896 -308.47157) (xy 93.148328 -308.440838)
			(xy 93.15574 -308.379823) (xy 93.170452 -308.320146) (xy 93.19225 -308.262678) (xy 93.220816 -308.208256)
			(xy 93.255733 -308.157674) (xy 93.296493 -308.111669) (xy 93.3425 -308.070912) (xy 93.393085 -308.035998)
			(xy 93.447509 -308.007436) (xy 93.504979 -307.985642) (xy 93.564657 -307.970934) (xy 93.625672 -307.963526)
			(xy 93.656404 -307.963062) (xy 93.691359 -307.96365) (xy 93.760612 -307.973211) (xy 93.827902 -307.992167)
			(xy 93.891963 -308.020161) (xy 93.951585 -308.056664) (xy 93.978984 -308.078378) (xy 93.985926 -308.083618)
			(xy 94.002297 -308.089461) (xy 94.010988 -308.089808) (xy 94.16542 -308.089808) (xy 94.174105 -308.089439)
			(xy 94.190462 -308.083585) (xy 94.197424 -308.078378) (xy 94.224812 -308.056651) (xy 94.284441 -308.020156)
			(xy 94.348505 -307.992167) (xy 94.415796 -307.973209) (xy 94.485049 -307.963641) (xy 94.520004 -307.963062)
			(xy 94.550734 -307.963552) (xy 94.611746 -307.970961) (xy 94.67142 -307.985669) (xy 94.728886 -308.007462)
			(xy 94.783306 -308.036023) (xy 94.833887 -308.070936) (xy 94.879892 -308.11169) (xy 94.920648 -308.157692)
			(xy 94.955563 -308.208272) (xy 94.984127 -308.26269) (xy 95.005923 -308.320156) (xy 95.020635 -308.379829)
			(xy 95.028046 -308.44084) (xy 95.028512 -308.47157) (xy 95.027985 -308.50506) (xy 95.019202 -308.571463)
			(xy 95.001785 -308.636139) (xy 94.976033 -308.697971) (xy 94.942393 -308.755891) (xy 94.92234 -308.78272)
			(xy 94.915633 -308.792284) (xy 94.910912 -308.815137) (xy 94.916721 -308.837738) (xy 94.923864 -308.846982)
			(xy 94.938905 -308.865058) (xy 94.964266 -308.904657) (xy 94.98376 -308.947449) (xy 94.996992 -308.992573)
			(xy 95.003694 -309.039117) (xy 95.004128 -309.062628) (xy 95.003618 -309.088615) (xy 94.995488 -309.13995)
			(xy 94.979427 -309.18938) (xy 94.955831 -309.23569) (xy 94.925281 -309.277738) (xy 94.88853 -309.314489)
			(xy 94.846482 -309.345039) (xy 94.800172 -309.368635) (xy 94.750742 -309.384696) (xy 94.699407 -309.392826)
			(xy 94.647433 -309.392826) (xy 94.596098 -309.384696) (xy 94.546668 -309.368635) (xy 94.500358 -309.345039)
			(xy 94.45831 -309.314489) (xy 94.421559 -309.277738) (xy 94.391009 -309.23569) (xy 94.367413 -309.18938)
			(xy 94.351352 -309.13995) (xy 94.343222 -309.088615) (xy 94.342712 -309.062628) (xy 94.342928 -309.045807)
			(xy 94.346363 -309.01234) (xy 94.34957 -308.995826) (xy 94.351399 -308.984299) (xy 94.345549 -308.961725)
			(xy 94.330346 -308.944044) (xy 94.319852 -308.93893) (xy 94.287059 -308.924257) (xy 94.225612 -308.887035)
			(xy 94.197424 -308.864762) (xy 94.190476 -308.85953) (xy 94.17411 -308.853682) (xy 94.16542 -308.853332)
			(xy 94.010988 -308.853332) (xy 94.002303 -308.853696) (xy 93.985945 -308.859553) (xy 93.978984 -308.864762)
			(xy 93.955564 -308.883387) (xy 93.905149 -308.915622) (xy 93.851298 -308.941716) (xy 93.794756 -308.961308)
			(xy 93.765624 -308.96814) (xy 93.754345 -308.971151) (xy 93.736094 -308.985673) (xy 93.726136 -309.006763)
			(xy 93.725746 -309.018432) (xy 93.725746 -309.022242) (xy 93.725746 -309.022496) (xy 93.725236 -309.048483)
			(xy 93.717106 -309.099818) (xy 93.701045 -309.149248) (xy 93.677449 -309.195558) (xy 93.646899 -309.237606)
			(xy 93.610148 -309.274357) (xy 93.5681 -309.304907) (xy 93.52179 -309.328503) (xy 93.47236 -309.344564)
			(xy 93.421025 -309.352694) (xy 93.369051 -309.352694) (xy 93.317716 -309.344564) (xy 93.268286 -309.328503)
			(xy 93.221976 -309.304907) (xy 93.179928 -309.274357) (xy 93.143177 -309.237606) (xy 93.112627 -309.195558)
			(xy 93.089031 -309.149248) (xy 93.07297 -309.099818) (xy 93.06484 -309.048483) (xy 93.06433 -309.022496)
			(xy 86.31448 -309.022496) (xy 86.367714 -309.032651) (xy 86.428507 -309.052404) (xy 86.486346 -309.079621)
			(xy 86.540317 -309.113872) (xy 86.58957 -309.154617) (xy 86.633327 -309.201214) (xy 86.6709 -309.252929)
			(xy 86.701694 -309.308944) (xy 86.725226 -309.368377) (xy 86.741123 -309.430291) (xy 86.749134 -309.493709)
			(xy 86.749636 -309.52567) (xy 86.749134 -309.557631) (xy 86.741123 -309.621049) (xy 86.725226 -309.682963)
			(xy 86.701694 -309.742396) (xy 86.6709 -309.798411) (xy 86.633327 -309.850126) (xy 86.58957 -309.896723)
			(xy 86.540317 -309.937468) (xy 86.486346 -309.971719) (xy 86.428507 -309.998936) (xy 86.367714 -310.018689)
			(xy 86.304924 -310.030667) (xy 86.241128 -310.034681) (xy 86.177332 -310.030667) (xy 86.114542 -310.018689)
			(xy 86.053749 -309.998936) (xy 85.99591 -309.971719) (xy 85.941939 -309.937468) (xy 85.892686 -309.896723)
			(xy 85.848929 -309.850126) (xy 85.811356 -309.798411) (xy 85.780562 -309.742396) (xy 85.75703 -309.682963)
			(xy 85.741133 -309.621049) (xy 85.733122 -309.557631) (xy 80.079424 -309.557631) (xy 80.074726 -309.596328)
			(xy 80.06002 -309.656001) (xy 80.038229 -309.713467) (xy 80.009669 -309.767887) (xy 79.974759 -309.818468)
			(xy 79.934006 -309.864472) (xy 79.888006 -309.905229) (xy 79.837428 -309.940145) (xy 79.783011 -309.968709)
			(xy 79.725547 -309.990506) (xy 79.665875 -310.005218) (xy 79.604865 -310.01263) (xy 79.574136 -310.013096)
			(xy 79.540646 -310.012569) (xy 79.474243 -310.003787) (xy 79.409567 -309.986369) (xy 79.347734 -309.960618)
			(xy 79.289815 -309.926977) (xy 79.262986 -309.906924) (xy 79.253418 -309.900225) (xy 79.230568 -309.895504)
			(xy 79.207968 -309.901308) (xy 79.198724 -309.908448) (xy 79.180643 -309.923484) (xy 79.141047 -309.948846)
			(xy 79.098255 -309.968341) (xy 79.053132 -309.981574) (xy 79.006589 -309.988278) (xy 78.983078 -309.988712)
			(xy 78.957092 -309.988193) (xy 78.905761 -309.98006) (xy 78.856334 -309.963997) (xy 78.810028 -309.9404)
			(xy 78.767984 -309.90985) (xy 78.731235 -309.8731) (xy 78.700688 -309.831053) (xy 78.677095 -309.784746)
			(xy 78.661035 -309.735318) (xy 78.652905 -309.683986) (xy 68.032289 -309.683986) (xy 67.2719 -310.444388)
			(xy 67.267836 -310.44896) (xy 67.265804 -310.451754) (xy 67.262697 -310.456685) (xy 67.262353 -310.457596)
			(xy 95.560134 -310.457596) (xy 95.560638 -310.430439) (xy 95.569513 -310.376856) (xy 95.587025 -310.325444)
			(xy 95.612702 -310.277583) (xy 95.645854 -310.234562) (xy 95.68559 -310.197535) (xy 95.730842 -310.1675)
			(xy 95.780394 -310.145262) (xy 95.806514 -310.13781) (xy 95.81769 -310.135016) (xy 95.834962 -310.12003)
			(xy 95.876872 -310.026304) (xy 95.87611 -310.003444) (xy 95.870776 -309.99303) (xy 95.857253 -309.965923)
			(xy 95.836061 -309.90917) (xy 95.821766 -309.8503) (xy 95.81457 -309.790148) (xy 95.814134 -309.759858)
			(xy 95.814636 -309.727897) (xy 95.822647 -309.664479) (xy 95.838544 -309.602565) (xy 95.862076 -309.543132)
			(xy 95.89287 -309.487117) (xy 95.930443 -309.435402) (xy 95.9742 -309.388805) (xy 96.023453 -309.34806)
			(xy 96.077424 -309.313809) (xy 96.135263 -309.286592) (xy 96.196056 -309.266839) (xy 96.258846 -309.254861)
			(xy 96.322642 -309.250848) (xy 96.386438 -309.254861) (xy 96.449228 -309.266839) (xy 96.510021 -309.286592)
			(xy 96.56786 -309.313809) (xy 96.621831 -309.34806) (xy 96.671084 -309.388805) (xy 96.714841 -309.435402)
			(xy 96.752414 -309.487117) (xy 96.783208 -309.543132) (xy 96.80674 -309.602565) (xy 96.822637 -309.664479)
			(xy 96.830648 -309.727897) (xy 96.83115 -309.759858) (xy 96.831022 -309.776543) (xy 96.828861 -309.809844)
			(xy 96.826832 -309.826406) (xy 96.825922 -309.838178) (xy 96.833566 -309.860481) (xy 96.850359 -309.877031)
			(xy 96.861376 -309.88127) (xy 96.891489 -309.89168) (xy 96.949054 -309.918993) (xy 97.002753 -309.953287)
			(xy 97.051746 -309.994023) (xy 97.095262 -310.040563) (xy 97.132621 -310.092178) (xy 97.163235 -310.148057)
			(xy 97.186626 -310.207324) (xy 97.202425 -310.26905) (xy 97.210386 -310.332266) (xy 97.21088 -310.364124)
			(xy 97.210485 -310.394858) (xy 97.203073 -310.455877) (xy 97.18836 -310.515557) (xy 97.16656 -310.573029)
			(xy 97.137992 -310.627454) (xy 97.103072 -310.678039) (xy 97.06231 -310.724046) (xy 97.016298 -310.764804)
			(xy 96.989798 -310.783094) (xy 98.386037 -310.783094) (xy 98.386037 -310.731106) (xy 98.394171 -310.679758)
			(xy 98.410237 -310.630314) (xy 98.433841 -310.583993) (xy 98.464401 -310.541935) (xy 98.501164 -310.505176)
			(xy 98.543226 -310.474621) (xy 98.589549 -310.451023) (xy 98.638995 -310.434962) (xy 98.690344 -310.426834)
			(xy 98.716338 -310.426354) (xy 98.733159 -310.426574) (xy 98.766626 -310.430006) (xy 98.78314 -310.433212)
			(xy 98.794671 -310.434985) (xy 98.817233 -310.429154) (xy 98.834916 -310.413976) (xy 98.840036 -310.403494)
			(xy 98.854775 -310.370695) (xy 98.892127 -310.309251) (xy 98.914458 -310.281066) (xy 98.919717 -310.274136)
			(xy 98.925549 -310.257756) (xy 98.925888 -310.249062) (xy 98.925888 -310.094884) (xy 98.925533 -310.086136)
			(xy 98.919691 -310.069645) (xy 98.914458 -310.062626) (xy 98.895773 -310.039234) (xy 98.863464 -309.988828)
			(xy 98.837309 -309.934971) (xy 98.817674 -309.878411) (xy 98.810826 -309.849266) (xy 98.807821 -309.837984)
			(xy 98.793301 -309.819727) (xy 98.772205 -309.809772) (xy 98.760534 -309.809388) (xy 98.756724 -309.809388)
			(xy 98.75647 -309.809388) (xy 98.730483 -309.808916) (xy 98.679149 -309.800781) (xy 98.629719 -309.784717)
			(xy 98.583411 -309.761118) (xy 98.541365 -309.730566) (xy 98.504615 -309.693813) (xy 98.474066 -309.651763)
			(xy 98.450472 -309.605453) (xy 98.434412 -309.556022) (xy 98.426281 -309.504687) (xy 98.426281 -309.452713)
			(xy 98.434412 -309.401378) (xy 98.450472 -309.351947) (xy 98.474066 -309.305637) (xy 98.504615 -309.263587)
			(xy 98.541365 -309.226834) (xy 98.583411 -309.196282) (xy 98.629719 -309.172683) (xy 98.679149 -309.156619)
			(xy 98.730483 -309.148484) (xy 98.75647 -309.147972) (xy 98.781249 -309.148398) (xy 98.830253 -309.155796)
			(xy 98.877606 -309.170416) (xy 98.922251 -309.191931) (xy 98.96319 -309.219861) (xy 98.999509 -309.253582)
			(xy 99.015296 -309.272686) (xy 99.022997 -309.28139) (xy 99.043951 -309.291373) (xy 99.06716 -309.291115)
			(xy 99.07778 -309.286402) (xy 99.104543 -309.273308) (xy 99.160476 -309.252771) (xy 99.218429 -309.238925)
			(xy 99.277604 -309.23196) (xy 99.307396 -309.231538) (xy 99.33813 -309.231941) (xy 99.399149 -309.239351)
			(xy 99.458831 -309.254061) (xy 99.516303 -309.275859) (xy 99.57073 -309.304425) (xy 99.621315 -309.339344)
			(xy 99.667323 -309.380107) (xy 99.708081 -309.426118) (xy 99.742996 -309.476706) (xy 99.771559 -309.531135)
			(xy 99.793351 -309.58861) (xy 99.808057 -309.648292) (xy 99.815461 -309.709312) (xy 99.815904 -309.740046)
			(xy 99.815297 -309.775011) (xy 99.805702 -309.844279) (xy 99.7867 -309.911578) (xy 99.75865 -309.975635)
			(xy 99.722082 -310.035242) (xy 99.700334 -310.062626) (xy 99.695045 -310.069613) (xy 99.689211 -310.086125)
			(xy 99.688904 -310.094884) (xy 99.688904 -310.248808) (xy 99.689264 -310.257555) (xy 99.695103 -310.274046)
			(xy 99.700334 -310.281066) (xy 99.722061 -310.308465) (xy 99.758615 -310.368076) (xy 99.786664 -310.432131)
			(xy 99.805678 -310.499422) (xy 99.8153 -310.568683) (xy 99.815904 -310.603646) (xy 99.815488 -310.634378)
			(xy 99.808074 -310.695394) (xy 99.79336 -310.755071) (xy 99.77156 -310.81254) (xy 99.742993 -310.866962)
			(xy 99.708074 -310.917544) (xy 99.667313 -310.963548) (xy 99.621304 -311.004305) (xy 99.570719 -311.039219)
			(xy 99.516294 -311.067781) (xy 99.458823 -311.089575) (xy 99.399145 -311.104283) (xy 99.338128 -311.111691)
			(xy 99.307396 -311.112154) (xy 99.273905 -311.111637) (xy 99.207503 -311.102851) (xy 99.142827 -311.08543)
			(xy 99.080995 -311.059677) (xy 99.023075 -311.026035) (xy 98.996246 -311.005982) (xy 98.986703 -310.999238)
			(xy 98.963836 -310.994523) (xy 98.941226 -311.000351) (xy 98.931984 -311.007506) (xy 98.913926 -311.022569)
			(xy 98.874322 -311.047926) (xy 98.831524 -311.067414) (xy 98.786397 -311.080641) (xy 98.739851 -311.087339)
			(xy 98.716338 -311.08777) (xy 98.690344 -311.087366) (xy 98.638995 -311.079238) (xy 98.589549 -311.063177)
			(xy 98.543226 -311.039579) (xy 98.501164 -311.009024) (xy 98.464401 -310.972265) (xy 98.433841 -310.930207)
			(xy 98.410237 -310.883886) (xy 98.394171 -310.834442) (xy 98.386037 -310.783094) (xy 96.989798 -310.783094)
			(xy 96.96571 -310.799719) (xy 96.911282 -310.828282) (xy 96.853807 -310.850075) (xy 96.794125 -310.864782)
			(xy 96.733106 -310.872188) (xy 96.702372 -310.872632) (xy 96.669241 -310.872089) (xy 96.603542 -310.863473)
			(xy 96.539516 -310.846403) (xy 96.478248 -310.821168) (xy 96.420773 -310.788194) (xy 96.368063 -310.74804)
			(xy 96.321011 -310.701385) (xy 96.30029 -310.675528) (xy 96.293432 -310.666638) (xy 96.272858 -310.656224)
			(xy 96.171004 -310.653684) (xy 96.150176 -310.663082) (xy 96.14281 -310.671972) (xy 96.126999 -310.689866)
			(xy 96.091127 -310.721383) (xy 96.0511 -310.747419) (xy 96.007748 -310.767436) (xy 95.961971 -310.781018)
			(xy 95.914717 -310.787883) (xy 95.890842 -310.788304) (xy 95.864854 -310.787786) (xy 95.813516 -310.779661)
			(xy 95.764082 -310.763604) (xy 95.717769 -310.740011) (xy 95.675716 -310.709463) (xy 95.638961 -310.672713)
			(xy 95.608408 -310.630664) (xy 95.58481 -310.584353) (xy 95.568748 -310.534921) (xy 95.560617 -310.483584)
			(xy 95.560134 -310.457596) (xy 67.262353 -310.457596) (xy 67.258585 -310.467587) (xy 67.257676 -310.473344)
			(xy 67.257168 -310.480202) (xy 67.257168 -310.601868) (xy 67.256724 -310.634464) (xy 67.249416 -310.699244)
			(xy 67.2349 -310.762799) (xy 67.213358 -310.824328) (xy 67.185062 -310.883058) (xy 67.150366 -310.93825)
			(xy 67.109709 -310.98921) (xy 67.086988 -311.012586) (xy 62.922785 -315.176789) (xy 97.790756 -315.176789)
			(xy 97.790756 -315.124811) (xy 97.798886 -315.073473) (xy 97.814947 -315.024039) (xy 97.838543 -314.977726)
			(xy 97.869093 -314.935673) (xy 97.905844 -314.898917) (xy 97.947893 -314.868363) (xy 97.994204 -314.844762)
			(xy 98.043636 -314.828695) (xy 98.094973 -314.820559) (xy 98.120962 -314.820046) (xy 98.137783 -314.820263)
			(xy 98.17125 -314.823697) (xy 98.187764 -314.826904) (xy 98.199293 -314.828703) (xy 98.221859 -314.822862)
			(xy 98.239541 -314.807673) (xy 98.24466 -314.797186) (xy 98.259395 -314.764385) (xy 98.29675 -314.702942)
			(xy 98.319082 -314.674758) (xy 98.324305 -314.667804) (xy 98.330158 -314.651443) (xy 98.330512 -314.642754)
			(xy 98.330512 -314.488576) (xy 98.330156 -314.479828) (xy 98.324314 -314.463337) (xy 98.319082 -314.456318)
			(xy 98.300398 -314.432925) (xy 98.268088 -314.38252) (xy 98.241933 -314.328663) (xy 98.222298 -314.272103)
			(xy 98.21545 -314.242958) (xy 98.212428 -314.231682) (xy 98.197914 -314.213428) (xy 98.176827 -314.203469)
			(xy 98.165158 -314.20308) (xy 98.161348 -314.20308) (xy 98.161094 -314.20308) (xy 98.135105 -314.202626)
			(xy 98.083767 -314.194494) (xy 98.034333 -314.178431) (xy 97.98802 -314.154833) (xy 97.945969 -314.12428)
			(xy 97.909216 -314.087526) (xy 97.878664 -314.045475) (xy 97.855067 -313.999162) (xy 97.839005 -313.949727)
			(xy 97.830874 -313.898389) (xy 97.830874 -313.846411) (xy 97.839005 -313.795073) (xy 97.855067 -313.745638)
			(xy 97.878664 -313.699325) (xy 97.909216 -313.657274) (xy 97.945969 -313.62052) (xy 97.98802 -313.589967)
			(xy 98.034333 -313.566369) (xy 98.083767 -313.550306) (xy 98.135105 -313.542174) (xy 98.161094 -313.541664)
			(xy 98.185871 -313.542147) (xy 98.234872 -313.549533) (xy 98.282224 -313.564142) (xy 98.32687 -313.585647)
			(xy 98.36781 -313.613567) (xy 98.404131 -313.647278) (xy 98.41992 -313.666378) (xy 98.427604 -313.6751)
			(xy 98.448567 -313.68508) (xy 98.471783 -313.684814) (xy 98.482404 -313.680094) (xy 98.509163 -313.666991)
			(xy 98.565097 -313.646457) (xy 98.623051 -313.632613) (xy 98.682228 -313.625651) (xy 98.71202 -313.62523)
			(xy 98.742754 -313.625619) (xy 98.803774 -313.633031) (xy 98.863455 -313.647744) (xy 98.920927 -313.669543)
			(xy 98.975353 -313.698112) (xy 99.025938 -313.733032) (xy 99.071946 -313.773795) (xy 99.112704 -313.819807)
			(xy 99.147619 -313.870397) (xy 99.176181 -313.924826) (xy 99.197974 -313.982301) (xy 99.21268 -314.041984)
			(xy 99.220085 -314.103004) (xy 99.220528 -314.133738) (xy 99.219911 -314.168702) (xy 99.210318 -314.23797)
			(xy 99.191318 -314.305268) (xy 99.16327 -314.369326) (xy 99.126705 -314.428933) (xy 99.104958 -314.456318)
			(xy 99.099675 -314.463309) (xy 99.093837 -314.479818) (xy 99.093528 -314.488576) (xy 99.093528 -314.6425)
			(xy 99.093887 -314.651247) (xy 99.099726 -314.667739) (xy 99.104958 -314.674758) (xy 99.12667 -314.702169)
			(xy 99.163229 -314.761775) (xy 99.191282 -314.825827) (xy 99.210299 -314.893116) (xy 99.219924 -314.962376)
			(xy 99.220528 -314.997338) (xy 99.22008 -315.028069) (xy 99.212668 -315.089083) (xy 99.197955 -315.148758)
			(xy 99.176158 -315.206225) (xy 99.147593 -315.260646) (xy 99.112677 -315.311227) (xy 99.071919 -315.357232)
			(xy 99.025913 -315.397988) (xy 98.975331 -315.432902) (xy 98.920909 -315.461465) (xy 98.863441 -315.483261)
			(xy 98.803765 -315.497971) (xy 98.742751 -315.505381) (xy 98.71202 -315.505846) (xy 98.67853 -315.505318)
			(xy 98.612128 -315.496534) (xy 98.547452 -315.479116) (xy 98.485619 -315.453365) (xy 98.427699 -315.419726)
			(xy 98.40087 -315.399674) (xy 98.391313 -315.392954) (xy 98.368455 -315.388232) (xy 98.34585 -315.394049)
			(xy 98.336608 -315.401198) (xy 98.31854 -315.416249) (xy 98.278939 -315.441608) (xy 98.236144 -315.461099)
			(xy 98.191019 -315.474328) (xy 98.144474 -315.481029) (xy 98.120962 -315.481462) (xy 98.094973 -315.481041)
			(xy 98.043636 -315.472905) (xy 97.994204 -315.456838) (xy 97.947893 -315.433237) (xy 97.905844 -315.402683)
			(xy 97.869093 -315.365927) (xy 97.838543 -315.323874) (xy 97.814947 -315.277561) (xy 97.798886 -315.228127)
			(xy 97.790756 -315.176789) (xy 62.922785 -315.176789) (xy 60.10275 -317.996824) (xy 60.077936 -318.020921)
			(xy 60.023551 -318.06366) (xy 59.964471 -318.099633) (xy 59.901535 -318.128329) (xy 59.835634 -318.149343)
			(xy 59.80176 -318.156336) (xy 59.798264 -318.157051) (xy 59.791508 -318.159348) (xy 59.788298 -318.160908)
			(xy 59.780732 -318.165172) (xy 59.768789 -318.177766) (xy 59.76493 -318.185546) (xy 59.753695 -318.209607)
			(xy 59.725338 -318.254504) (xy 59.690837 -318.294871) (xy 59.650904 -318.329874) (xy 59.606366 -318.35879)
			(xy 59.558141 -318.381021) (xy 59.507228 -318.396109) (xy 59.454677 -318.40374) (xy 59.428126 -318.40424)
			(xy 59.427872 -318.40424) (xy 59.408808 -318.404) (xy 59.370886 -318.40005) (xy 59.35218 -318.396366)
			(xy 59.341766 -318.39535) (xy 59.331802 -318.395832) (xy 59.313374 -318.403417) (xy 59.305952 -318.410082)
			(xy 58.352182 -319.363852) (xy 58.344942 -319.37056) (xy 58.326737 -319.378146) (xy 58.316876 -319.378584)
			(xy 24.525224 -319.378584) (xy 24.515476 -319.379102) (xy 24.497452 -319.386556) (xy 24.490172 -319.393062)
			(xy 22.860508 -321.022726) (xy 22.853951 -321.029974) (xy 22.846491 -321.048016) (xy 22.84603 -321.057778)
			(xy 22.84603 -323.030342) (xy 67.354958 -323.030342) (xy 67.35539 -322.99962) (xy 67.362797 -322.938625)
			(xy 67.377496 -322.878965) (xy 67.399274 -322.821511) (xy 67.427813 -322.767097) (xy 67.444874 -322.741544)
			(xy 67.450234 -322.732841) (xy 67.45431 -322.712835) (xy 67.450261 -322.692823) (xy 67.444874 -322.68414)
			(xy 67.427854 -322.658562) (xy 67.399319 -322.604151) (xy 67.377545 -322.5467) (xy 67.362849 -322.487045)
			(xy 67.355445 -322.426054) (xy 67.355441 -322.364615) (xy 67.362837 -322.303623) (xy 67.377525 -322.243966)
			(xy 67.399291 -322.186512) (xy 67.427818 -322.132098) (xy 67.444874 -322.106544) (xy 67.450234 -322.097841)
			(xy 67.45431 -322.077835) (xy 67.450261 -322.057823) (xy 67.444874 -322.04914) (xy 67.427854 -322.023562)
			(xy 67.399319 -321.969151) (xy 67.377545 -321.9117) (xy 67.362849 -321.852045) (xy 67.355445 -321.791054)
			(xy 67.355441 -321.729615) (xy 67.362837 -321.668623) (xy 67.377525 -321.608966) (xy 67.399291 -321.551512)
			(xy 67.427818 -321.497098) (xy 67.444874 -321.471544) (xy 67.450234 -321.462841) (xy 67.45431 -321.442835)
			(xy 67.450261 -321.422823) (xy 67.444874 -321.41414) (xy 67.427854 -321.388562) (xy 67.399319 -321.334151)
			(xy 67.377545 -321.2767) (xy 67.362849 -321.217045) (xy 67.355445 -321.156054) (xy 67.355441 -321.094615)
			(xy 67.362837 -321.033623) (xy 67.377525 -320.973966) (xy 67.399291 -320.916512) (xy 67.427818 -320.862098)
			(xy 67.444874 -320.836544) (xy 67.450234 -320.827841) (xy 67.45431 -320.807835) (xy 67.450261 -320.787823)
			(xy 67.444874 -320.77914) (xy 67.427835 -320.753574) (xy 67.399299 -320.699163) (xy 67.377525 -320.641711)
			(xy 67.362828 -320.582054) (xy 67.355423 -320.521062) (xy 67.354958 -320.490342) (xy 67.355477 -320.459612)
			(xy 67.36288 -320.3986) (xy 67.377584 -320.338925) (xy 67.399373 -320.281457) (xy 67.427931 -320.227035)
			(xy 67.46284 -320.176452) (xy 67.503592 -320.130446) (xy 67.549592 -320.089687) (xy 67.60017 -320.05477)
			(xy 67.654588 -320.026204) (xy 67.712052 -320.004406) (xy 67.771725 -319.989694) (xy 67.832736 -319.982282)
			(xy 67.863466 -319.981834) (xy 67.882262 -319.982088) (xy 67.89293 -319.982596) (xy 67.91325 -319.974468)
			(xy 67.980814 -319.904872) (xy 67.98818 -319.884806) (xy 67.987418 -319.874138) (xy 67.986402 -319.840864)
			(xy 67.986822 -319.810132) (xy 67.994235 -319.749116) (xy 68.008948 -319.689439) (xy 68.030747 -319.63197)
			(xy 68.059314 -319.577547) (xy 68.094232 -319.526965) (xy 68.134993 -319.48096) (xy 68.181001 -319.440204)
			(xy 68.231587 -319.40529) (xy 68.286012 -319.376728) (xy 68.343483 -319.354934) (xy 68.403161 -319.340226)
			(xy 68.464178 -319.332819) (xy 68.49491 -319.332356) (xy 68.515992 -319.332864) (xy 68.516246 -319.332864)
			(xy 68.526679 -319.332722) (xy 68.546088 -319.325118) (xy 68.553838 -319.318132) (xy 68.607178 -319.264792)
			(xy 68.614181 -319.257054) (xy 68.621779 -319.237637) (xy 68.62191 -319.2272) (xy 68.62191 -319.226692)
			(xy 68.621402 -319.205864) (xy 68.621904 -319.173903) (xy 68.629915 -319.110485) (xy 68.645812 -319.048571)
			(xy 68.669344 -318.989138) (xy 68.700138 -318.933123) (xy 68.737711 -318.881408) (xy 68.781468 -318.834811)
			(xy 68.830721 -318.794066) (xy 68.884692 -318.759815) (xy 68.942531 -318.732598) (xy 69.003324 -318.712845)
			(xy 69.066114 -318.700867) (xy 69.12991 -318.696854) (xy 69.193706 -318.700867) (xy 69.256496 -318.712845)
			(xy 69.317289 -318.732598) (xy 69.375128 -318.759815) (xy 69.429099 -318.794066) (xy 69.478352 -318.834811)
			(xy 69.522109 -318.881408) (xy 69.559682 -318.933123) (xy 69.590476 -318.989138) (xy 69.614008 -319.048571)
			(xy 69.629905 -319.110485) (xy 69.637916 -319.173903) (xy 69.638418 -319.205864) (xy 69.637925 -319.236584)
			(xy 69.63053 -319.297576) (xy 69.615844 -319.357235) (xy 69.594081 -319.41469) (xy 69.565556 -319.469107)
			(xy 69.548502 -319.494662) (xy 69.543139 -319.503363) (xy 69.539067 -319.52337) (xy 69.543116 -319.543382)
			(xy 69.548502 -319.552066) (xy 69.565541 -319.577632) (xy 69.594077 -319.632043) (xy 69.615852 -319.689495)
			(xy 69.630549 -319.749152) (xy 69.637953 -319.810144) (xy 69.638418 -319.840864) (xy 69.638013 -319.869819)
			(xy 69.631415 -319.927353) (xy 69.618325 -319.983765) (xy 69.598911 -320.038324) (xy 69.573424 -320.090325)
			(xy 69.558154 -320.11493) (xy 69.553005 -320.123943) (xy 69.549624 -320.144398) (xy 69.554581 -320.16453)
			(xy 69.56044 -320.173096) (xy 69.579985 -320.199677) (xy 69.61272 -320.256965) (xy 69.637771 -320.318004)
			(xy 69.654719 -320.38177) (xy 69.663279 -320.447192) (xy 69.663818 -320.480182) (xy 69.663818 -320.480436)
			(xy 69.663361 -320.511157) (xy 69.655958 -320.572151) (xy 69.641264 -320.63181) (xy 69.619492 -320.689265)
			(xy 69.59096 -320.74368) (xy 69.573902 -320.769234) (xy 69.568478 -320.777902) (xy 69.564426 -320.79793)
			(xy 69.568501 -320.817953) (xy 69.573902 -320.826638) (xy 69.590994 -320.85217) (xy 69.619526 -320.906589)
			(xy 69.641295 -320.964047) (xy 69.655986 -321.02371) (xy 69.663383 -321.084707) (xy 69.663379 -321.146152)
			(xy 69.655975 -321.207149) (xy 69.641278 -321.266809) (xy 69.619501 -321.324266) (xy 69.590963 -321.378681)
			(xy 69.573902 -321.404234) (xy 69.568478 -321.412902) (xy 69.564426 -321.43293) (xy 69.568501 -321.452953)
			(xy 69.573902 -321.461638) (xy 69.590994 -321.48717) (xy 69.619526 -321.541589) (xy 69.641295 -321.599047)
			(xy 69.655986 -321.65871) (xy 69.663383 -321.719707) (xy 69.663379 -321.781152) (xy 69.655975 -321.842149)
			(xy 69.641278 -321.901809) (xy 69.619501 -321.959266) (xy 69.590963 -322.013681) (xy 69.573902 -322.039234)
			(xy 69.568478 -322.047902) (xy 69.564426 -322.06793) (xy 69.568501 -322.087953) (xy 69.573902 -322.096638)
			(xy 69.590972 -322.122184) (xy 69.619503 -322.176601) (xy 69.641272 -322.234058) (xy 69.655961 -322.293719)
			(xy 69.663358 -322.354715) (xy 69.663818 -322.385436) (xy 69.663818 -322.38569) (xy 69.663335 -322.418673)
			(xy 69.654825 -322.484087) (xy 69.637919 -322.547849) (xy 69.612903 -322.608886) (xy 69.580198 -322.666173)
			(xy 69.560694 -322.692776) (xy 69.554784 -322.701377) (xy 69.549864 -322.721639) (xy 69.553386 -322.74219)
			(xy 69.558662 -322.751196) (xy 69.574487 -322.776129) (xy 69.600945 -322.828926) (xy 69.621108 -322.884433)
			(xy 69.634703 -322.941903) (xy 69.641547 -323.00056) (xy 69.641974 -323.030088) (xy 69.641974 -323.030342)
			(xy 71.368158 -323.030342) (xy 71.368158 -323.030088) (xy 71.368688 -322.997107) (xy 71.377188 -322.931695)
			(xy 71.394083 -322.867934) (xy 71.419088 -322.806895) (xy 71.451783 -322.749607) (xy 71.471282 -322.723002)
			(xy 71.477122 -322.714362) (xy 71.482056 -322.694124) (xy 71.478568 -322.673588) (xy 71.473314 -322.664582)
			(xy 71.457477 -322.639656) (xy 71.431021 -322.586857) (xy 71.410862 -322.531348) (xy 71.39727 -322.473877)
			(xy 71.390428 -322.415218) (xy 71.390002 -322.38569) (xy 71.390002 -322.385436) (xy 71.390492 -322.354716)
			(xy 71.397886 -322.293723) (xy 71.412573 -322.234065) (xy 71.434338 -322.176609) (xy 71.462863 -322.122193)
			(xy 71.479918 -322.096638) (xy 71.485279 -322.087937) (xy 71.48935 -322.06793) (xy 71.485303 -322.047919)
			(xy 71.479918 -322.039234) (xy 71.462894 -322.013658) (xy 71.434363 -321.959247) (xy 71.412592 -321.901795)
			(xy 71.397898 -321.84214) (xy 71.390495 -321.781149) (xy 71.390492 -321.71971) (xy 71.397887 -321.658719)
			(xy 71.412574 -321.599062) (xy 71.434338 -321.541607) (xy 71.462863 -321.487192) (xy 71.479918 -321.461638)
			(xy 71.485279 -321.452937) (xy 71.48935 -321.43293) (xy 71.485303 -321.412919) (xy 71.479918 -321.404234)
			(xy 71.462894 -321.378658) (xy 71.434363 -321.324247) (xy 71.412592 -321.266795) (xy 71.397898 -321.20714)
			(xy 71.390495 -321.146149) (xy 71.390492 -321.08471) (xy 71.397887 -321.023719) (xy 71.412574 -320.964062)
			(xy 71.434338 -320.906607) (xy 71.462863 -320.852192) (xy 71.479918 -320.826638) (xy 71.485279 -320.817937)
			(xy 71.48935 -320.79793) (xy 71.485303 -320.777919) (xy 71.479918 -320.769234) (xy 71.462881 -320.743666)
			(xy 71.434344 -320.689256) (xy 71.412569 -320.631804) (xy 71.397871 -320.572148) (xy 71.390467 -320.511156)
			(xy 71.390002 -320.480436) (xy 71.390002 -320.480182) (xy 71.390471 -320.449243) (xy 71.397972 -320.38782)
			(xy 71.412872 -320.327762) (xy 71.434952 -320.269957) (xy 71.463885 -320.215259) (xy 71.481188 -320.189606)
			(xy 71.486635 -320.180837) (xy 71.490796 -320.160642) (xy 71.486668 -320.14044) (xy 71.481188 -320.131694)
			(xy 71.463891 -320.106037) (xy 71.434959 -320.051339) (xy 71.412877 -319.993535) (xy 71.397971 -319.933478)
			(xy 71.390461 -319.872057) (xy 71.390002 -319.841118) (xy 71.390002 -319.840864) (xy 71.390455 -319.810143)
			(xy 71.397859 -319.749149) (xy 71.412554 -319.68949) (xy 71.434326 -319.632035) (xy 71.462859 -319.57762)
			(xy 71.479918 -319.552066) (xy 71.48534 -319.543397) (xy 71.489391 -319.52337) (xy 71.485317 -319.503347)
			(xy 71.479918 -319.494662) (xy 71.462828 -319.469129) (xy 71.434301 -319.414709) (xy 71.412535 -319.357251)
			(xy 71.397847 -319.297589) (xy 71.390451 -319.236592) (xy 71.390455 -319.175149) (xy 71.397858 -319.114153)
			(xy 71.412553 -319.054493) (xy 71.434325 -318.997036) (xy 71.462859 -318.94262) (xy 71.479918 -318.917066)
			(xy 71.48534 -318.908397) (xy 71.489391 -318.88837) (xy 71.485317 -318.868347) (xy 71.479918 -318.859662)
			(xy 71.462828 -318.834129) (xy 71.434301 -318.779709) (xy 71.412535 -318.722251) (xy 71.397847 -318.662589)
			(xy 71.390451 -318.601592) (xy 71.390455 -318.540149) (xy 71.397858 -318.479153) (xy 71.412553 -318.419493)
			(xy 71.434325 -318.362036) (xy 71.462859 -318.30762) (xy 71.479918 -318.282066) (xy 71.48534 -318.273397)
			(xy 71.489391 -318.25337) (xy 71.485317 -318.233347) (xy 71.479918 -318.224662) (xy 71.462828 -318.199129)
			(xy 71.434301 -318.144709) (xy 71.412535 -318.087251) (xy 71.397847 -318.027589) (xy 71.390451 -317.966592)
			(xy 71.390455 -317.905149) (xy 71.397858 -317.844153) (xy 71.412553 -317.784493) (xy 71.434325 -317.727036)
			(xy 71.462859 -317.67262) (xy 71.479918 -317.647066) (xy 71.48534 -317.638397) (xy 71.489391 -317.61837)
			(xy 71.485317 -317.598347) (xy 71.479918 -317.589662) (xy 71.462828 -317.564129) (xy 71.434301 -317.509709)
			(xy 71.412535 -317.452251) (xy 71.397847 -317.392589) (xy 71.390451 -317.331592) (xy 71.390455 -317.270149)
			(xy 71.397858 -317.209153) (xy 71.412553 -317.149493) (xy 71.434325 -317.092036) (xy 71.462859 -317.03762)
			(xy 71.479918 -317.012066) (xy 71.48534 -317.003397) (xy 71.489391 -316.98337) (xy 71.485317 -316.963347)
			(xy 71.479918 -316.954662) (xy 71.46285 -316.929114) (xy 71.434318 -316.874698) (xy 71.412549 -316.817241)
			(xy 71.397859 -316.757581) (xy 71.390462 -316.696585) (xy 71.390002 -316.665864) (xy 71.390422 -316.635132)
			(xy 71.397835 -316.574116) (xy 71.412548 -316.514439) (xy 71.434347 -316.45697) (xy 71.462914 -316.402547)
			(xy 71.497832 -316.351965) (xy 71.538593 -316.30596) (xy 71.584601 -316.265204) (xy 71.635187 -316.23029)
			(xy 71.689612 -316.201728) (xy 71.747083 -316.179934) (xy 71.806761 -316.165226) (xy 71.867778 -316.157819)
			(xy 71.89851 -316.157356) (xy 71.929231 -316.157813) (xy 71.990226 -316.165214) (xy 72.049885 -316.179908)
			(xy 72.10734 -316.20168) (xy 72.161754 -316.230213) (xy 72.187308 -316.247272) (xy 72.195993 -316.252665)
			(xy 72.21601 -316.256726) (xy 72.236027 -316.252665) (xy 72.244712 -316.247272) (xy 72.270266 -316.230214)
			(xy 72.324681 -316.201683) (xy 72.382136 -316.179912) (xy 72.441795 -316.16522) (xy 72.502789 -316.15782)
			(xy 72.564231 -316.15782) (xy 72.625225 -316.16522) (xy 72.684884 -316.179912) (xy 72.742339 -316.201683)
			(xy 72.796754 -316.230214) (xy 72.822308 -316.247272) (xy 72.830993 -316.252665) (xy 72.85101 -316.256726)
			(xy 72.871027 -316.252665) (xy 72.879712 -316.247272) (xy 72.905263 -316.23021) (xy 72.959679 -316.201678)
			(xy 73.017135 -316.179908) (xy 73.076794 -316.165217) (xy 73.137789 -316.157818) (xy 73.16851 -316.157356)
			(xy 73.19924 -316.157847) (xy 73.260251 -316.165256) (xy 73.319925 -316.179964) (xy 73.377391 -316.201758)
			(xy 73.431811 -316.230319) (xy 73.482392 -316.265232) (xy 73.528396 -316.305986) (xy 73.569152 -316.351988)
			(xy 73.604067 -316.402567) (xy 73.632631 -316.456986) (xy 73.654428 -316.51445) (xy 73.66914 -316.574123)
			(xy 73.676552 -316.635134) (xy 73.677018 -316.665864) (xy 73.676525 -316.696584) (xy 73.66913 -316.757576)
			(xy 73.654444 -316.817235) (xy 73.632681 -316.87469) (xy 73.604156 -316.929107) (xy 73.587102 -316.954662)
			(xy 73.581739 -316.963363) (xy 73.577667 -316.98337) (xy 73.581716 -317.003382) (xy 73.587102 -317.012066)
			(xy 73.604128 -317.037641) (xy 73.632664 -317.092051) (xy 73.654439 -317.149503) (xy 73.669135 -317.209159)
			(xy 73.676539 -317.270151) (xy 73.676542 -317.33159) (xy 73.669145 -317.392583) (xy 73.654456 -317.452241)
			(xy 73.632689 -317.509695) (xy 73.604159 -317.564109) (xy 73.587102 -317.589662) (xy 73.581739 -317.598363)
			(xy 73.577667 -317.61837) (xy 73.581716 -317.638382) (xy 73.587102 -317.647066) (xy 73.604128 -317.672641)
			(xy 73.632664 -317.727051) (xy 73.654439 -317.784503) (xy 73.669135 -317.844159) (xy 73.676539 -317.905151)
			(xy 73.676542 -317.96659) (xy 73.669145 -318.027583) (xy 73.654456 -318.087241) (xy 73.632689 -318.144695)
			(xy 73.604159 -318.199109) (xy 73.587102 -318.224662) (xy 73.581739 -318.233363) (xy 73.577667 -318.25337)
			(xy 73.581716 -318.273382) (xy 73.587102 -318.282066) (xy 73.604128 -318.307641) (xy 73.632664 -318.362051)
			(xy 73.654439 -318.419503) (xy 73.669135 -318.479159) (xy 73.676539 -318.540151) (xy 73.676542 -318.60159)
			(xy 73.669145 -318.662583) (xy 73.654456 -318.722241) (xy 73.632689 -318.779695) (xy 73.604159 -318.834109)
			(xy 73.587102 -318.859662) (xy 73.581739 -318.868363) (xy 73.577667 -318.88837) (xy 73.581716 -318.908382)
			(xy 73.587102 -318.917066) (xy 73.604128 -318.942641) (xy 73.632664 -318.997051) (xy 73.654439 -319.054503)
			(xy 73.669135 -319.114159) (xy 73.676539 -319.175151) (xy 73.676542 -319.23659) (xy 73.669145 -319.297583)
			(xy 73.654456 -319.357241) (xy 73.632689 -319.414695) (xy 73.604159 -319.469109) (xy 73.587102 -319.494662)
			(xy 73.581739 -319.503363) (xy 73.577667 -319.52337) (xy 73.581716 -319.543382) (xy 73.587102 -319.552066)
			(xy 73.604128 -319.577641) (xy 73.632664 -319.632051) (xy 73.654439 -319.689503) (xy 73.669135 -319.749159)
			(xy 73.676539 -319.810151) (xy 73.676542 -319.87159) (xy 73.669145 -319.932583) (xy 73.654456 -319.992241)
			(xy 73.632689 -320.049695) (xy 73.604159 -320.104109) (xy 73.587102 -320.129662) (xy 73.581739 -320.138363)
			(xy 73.577667 -320.15837) (xy 73.581716 -320.178382) (xy 73.587102 -320.187066) (xy 73.604128 -320.212641)
			(xy 73.632664 -320.267051) (xy 73.654439 -320.324503) (xy 73.669135 -320.384159) (xy 73.676539 -320.445151)
			(xy 73.676542 -320.50659) (xy 73.669145 -320.567583) (xy 73.654456 -320.627241) (xy 73.632689 -320.684695)
			(xy 73.604159 -320.739109) (xy 73.587102 -320.764662) (xy 73.581739 -320.773363) (xy 73.577667 -320.79337)
			(xy 73.581716 -320.813382) (xy 73.587102 -320.822066) (xy 73.604128 -320.847641) (xy 73.632664 -320.902051)
			(xy 73.654439 -320.959503) (xy 73.669135 -321.019159) (xy 73.676539 -321.080151) (xy 73.676542 -321.14159)
			(xy 73.669145 -321.202583) (xy 73.654456 -321.262241) (xy 73.632689 -321.319695) (xy 73.604159 -321.374109)
			(xy 73.587102 -321.399662) (xy 73.581739 -321.408363) (xy 73.577667 -321.42837) (xy 73.581716 -321.448382)
			(xy 73.587102 -321.457066) (xy 73.604128 -321.482641) (xy 73.632664 -321.537051) (xy 73.654439 -321.594503)
			(xy 73.669135 -321.654159) (xy 73.676539 -321.715151) (xy 73.676542 -321.77659) (xy 73.669145 -321.837583)
			(xy 73.654456 -321.897241) (xy 73.632689 -321.954695) (xy 73.604159 -322.009109) (xy 73.587102 -322.034662)
			(xy 73.581739 -322.043363) (xy 73.577667 -322.06337) (xy 73.581716 -322.083382) (xy 73.587102 -322.092066)
			(xy 73.604141 -322.117632) (xy 73.632677 -322.172043) (xy 73.654452 -322.229495) (xy 73.669149 -322.289152)
			(xy 73.676553 -322.350144) (xy 73.676695 -322.359528) (xy 75.706986 -322.359528) (xy 75.706986 -322.359274)
			(xy 75.707447 -322.328553) (xy 75.714849 -322.267559) (xy 75.729542 -322.207901) (xy 75.751313 -322.150445)
			(xy 75.779844 -322.09603) (xy 75.796902 -322.070476) (xy 75.802317 -322.061803) (xy 75.806372 -322.041778)
			(xy 75.8023 -322.021757) (xy 75.796902 -322.013072) (xy 75.779819 -321.987534) (xy 75.751286 -321.933117)
			(xy 75.729516 -321.875659) (xy 75.714825 -321.815997) (xy 75.707427 -321.755001) (xy 75.707429 -321.693557)
			(xy 75.714832 -321.632561) (xy 75.729529 -321.5729) (xy 75.751304 -321.515444) (xy 75.779841 -321.461029)
			(xy 75.796902 -321.435476) (xy 75.802317 -321.426803) (xy 75.806372 -321.406778) (xy 75.8023 -321.386757)
			(xy 75.796902 -321.378072) (xy 75.779819 -321.352534) (xy 75.751286 -321.298117) (xy 75.729516 -321.240659)
			(xy 75.714825 -321.180997) (xy 75.707427 -321.120001) (xy 75.707429 -321.058557) (xy 75.714832 -320.997561)
			(xy 75.729529 -320.9379) (xy 75.751304 -320.880444) (xy 75.779841 -320.826029) (xy 75.796902 -320.800476)
			(xy 75.802317 -320.791803) (xy 75.806372 -320.771778) (xy 75.8023 -320.751757) (xy 75.796902 -320.743072)
			(xy 75.779819 -320.717534) (xy 75.751286 -320.663117) (xy 75.729516 -320.605659) (xy 75.714825 -320.545997)
			(xy 75.707427 -320.485001) (xy 75.707429 -320.423557) (xy 75.714832 -320.362561) (xy 75.729529 -320.3029)
			(xy 75.751304 -320.245444) (xy 75.779841 -320.191029) (xy 75.796902 -320.165476) (xy 75.802317 -320.156803)
			(xy 75.806372 -320.136778) (xy 75.8023 -320.116757) (xy 75.796902 -320.108072) (xy 75.779819 -320.082534)
			(xy 75.751286 -320.028117) (xy 75.729516 -319.970659) (xy 75.714825 -319.910997) (xy 75.707427 -319.850001)
			(xy 75.707429 -319.788557) (xy 75.714832 -319.727561) (xy 75.729529 -319.6679) (xy 75.751304 -319.610444)
			(xy 75.779841 -319.556029) (xy 75.796902 -319.530476) (xy 75.802317 -319.521803) (xy 75.806372 -319.501778)
			(xy 75.8023 -319.481757) (xy 75.796902 -319.473072) (xy 75.779819 -319.447534) (xy 75.751286 -319.393117)
			(xy 75.729516 -319.335659) (xy 75.714825 -319.275997) (xy 75.707427 -319.215001) (xy 75.707429 -319.153557)
			(xy 75.714832 -319.092561) (xy 75.729529 -319.0329) (xy 75.751304 -318.975444) (xy 75.779841 -318.921029)
			(xy 75.796902 -318.895476) (xy 75.802317 -318.886803) (xy 75.806372 -318.866778) (xy 75.8023 -318.846757)
			(xy 75.796902 -318.838072) (xy 75.779819 -318.812534) (xy 75.751286 -318.758117) (xy 75.729516 -318.700659)
			(xy 75.714825 -318.640997) (xy 75.707427 -318.580001) (xy 75.707429 -318.518557) (xy 75.714832 -318.457561)
			(xy 75.729529 -318.3979) (xy 75.751304 -318.340444) (xy 75.779841 -318.286029) (xy 75.796902 -318.260476)
			(xy 75.802317 -318.251803) (xy 75.806372 -318.231778) (xy 75.8023 -318.211757) (xy 75.796902 -318.203072)
			(xy 75.779819 -318.177534) (xy 75.751286 -318.123117) (xy 75.729516 -318.065659) (xy 75.714825 -318.005997)
			(xy 75.707427 -317.945001) (xy 75.707429 -317.883557) (xy 75.714832 -317.822561) (xy 75.729529 -317.7629)
			(xy 75.751304 -317.705444) (xy 75.779841 -317.651029) (xy 75.796902 -317.625476) (xy 75.802317 -317.616803)
			(xy 75.806372 -317.596778) (xy 75.8023 -317.576757) (xy 75.796902 -317.568072) (xy 75.779819 -317.542534)
			(xy 75.751286 -317.488117) (xy 75.729516 -317.430659) (xy 75.714825 -317.370997) (xy 75.707427 -317.310001)
			(xy 75.707429 -317.248557) (xy 75.714832 -317.187561) (xy 75.729529 -317.1279) (xy 75.751304 -317.070444)
			(xy 75.779841 -317.016029) (xy 75.796902 -316.990476) (xy 75.802317 -316.981803) (xy 75.806372 -316.961778)
			(xy 75.8023 -316.941757) (xy 75.796902 -316.933072) (xy 75.779836 -316.907523) (xy 75.751305 -316.853107)
			(xy 75.729535 -316.795651) (xy 75.714845 -316.73599) (xy 75.707447 -316.674995) (xy 75.706986 -316.644274)
			(xy 75.707432 -316.613543) (xy 75.714843 -316.552528) (xy 75.729554 -316.492852) (xy 75.751351 -316.435385)
			(xy 75.779916 -316.380963) (xy 75.814832 -316.330381) (xy 75.855591 -316.284377) (xy 75.901597 -316.24362)
			(xy 75.95218 -316.208706) (xy 76.006603 -316.180143) (xy 76.064072 -316.158348) (xy 76.123748 -316.143639)
			(xy 76.184763 -316.13623) (xy 76.215494 -316.135766) (xy 76.246214 -316.136247) (xy 76.307207 -316.143645)
			(xy 76.366866 -316.158334) (xy 76.424321 -316.1801) (xy 76.478737 -316.208627) (xy 76.504292 -316.225682)
			(xy 76.512977 -316.231075) (xy 76.532994 -316.235136) (xy 76.553011 -316.231075) (xy 76.561696 -316.225682)
			(xy 76.58725 -316.208624) (xy 76.641665 -316.180093) (xy 76.69912 -316.158322) (xy 76.758779 -316.14363)
			(xy 76.819773 -316.13623) (xy 76.881215 -316.13623) (xy 76.942209 -316.14363) (xy 77.001868 -316.158322)
			(xy 77.059323 -316.180093) (xy 77.113738 -316.208624) (xy 77.139292 -316.225682) (xy 77.147977 -316.231075)
			(xy 77.167994 -316.235136) (xy 77.188011 -316.231075) (xy 77.196696 -316.225682) (xy 77.222253 -316.208628)
			(xy 77.276667 -316.180095) (xy 77.334121 -316.158323) (xy 77.39378 -316.14363) (xy 77.454773 -316.136229)
			(xy 77.485494 -316.135766) (xy 77.516224 -316.136262) (xy 77.577236 -316.143669) (xy 77.63691 -316.158376)
			(xy 77.694376 -316.180169) (xy 77.748797 -316.208729) (xy 77.799378 -316.243641) (xy 77.845382 -316.284395)
			(xy 77.886139 -316.330397) (xy 77.921054 -316.380976) (xy 77.949618 -316.435395) (xy 77.971414 -316.49286)
			(xy 77.986125 -316.552533) (xy 77.993536 -316.613544) (xy 77.994002 -316.644274) (xy 77.993517 -316.674994)
			(xy 77.986121 -316.735987) (xy 77.971433 -316.795646) (xy 77.949668 -316.853101) (xy 77.921141 -316.907517)
			(xy 77.904086 -316.933072) (xy 77.898716 -316.941769) (xy 77.894648 -316.961778) (xy 77.898699 -316.981791)
			(xy 77.904086 -316.990476) (xy 77.921119 -317.016046) (xy 77.94965 -317.070459) (xy 77.97142 -317.127911)
			(xy 77.986112 -317.187568) (xy 77.993514 -317.248559) (xy 77.993517 -317.309998) (xy 77.98612 -317.37099)
			(xy 77.971432 -317.430648) (xy 77.949667 -317.488102) (xy 77.921141 -317.542518) (xy 77.904086 -317.568072)
			(xy 77.898716 -317.576769) (xy 77.894648 -317.596778) (xy 77.898699 -317.616791) (xy 77.904086 -317.625476)
			(xy 77.921119 -317.651046) (xy 77.94965 -317.705459) (xy 77.97142 -317.762911) (xy 77.986112 -317.822568)
			(xy 77.993514 -317.883559) (xy 77.993517 -317.944998) (xy 77.98612 -318.00599) (xy 77.971432 -318.065648)
			(xy 77.949667 -318.123102) (xy 77.921141 -318.177518) (xy 77.904086 -318.203072) (xy 77.898716 -318.211769)
			(xy 77.894648 -318.231778) (xy 77.898699 -318.251791) (xy 77.904086 -318.260476) (xy 77.921119 -318.286046)
			(xy 77.94965 -318.340459) (xy 77.97142 -318.397911) (xy 77.986112 -318.457568) (xy 77.993514 -318.518559)
			(xy 77.993517 -318.579998) (xy 77.98612 -318.64099) (xy 77.971432 -318.700648) (xy 77.949667 -318.758102)
			(xy 77.921141 -318.812518) (xy 77.904086 -318.838072) (xy 77.898716 -318.846769) (xy 77.894648 -318.866778)
			(xy 77.898699 -318.886791) (xy 77.904086 -318.895476) (xy 77.921119 -318.921046) (xy 77.94965 -318.975459)
			(xy 77.97142 -319.032911) (xy 77.986112 -319.092568) (xy 77.993514 -319.153559) (xy 77.993517 -319.214998)
			(xy 77.98612 -319.27599) (xy 77.971432 -319.335648) (xy 77.949667 -319.393102) (xy 77.921141 -319.447518)
			(xy 77.904086 -319.473072) (xy 77.898716 -319.481769) (xy 77.894648 -319.501778) (xy 77.898699 -319.521791)
			(xy 77.904086 -319.530476) (xy 77.921127 -319.556041) (xy 77.949664 -319.610452) (xy 77.971438 -319.667904)
			(xy 77.986134 -319.727561) (xy 77.993538 -319.788554) (xy 77.994002 -319.819274) (xy 77.993604 -319.848229)
			(xy 77.987005 -319.905764) (xy 77.973913 -319.962175) (xy 77.954497 -320.016735) (xy 77.929009 -320.068735)
			(xy 77.913738 -320.09334) (xy 77.90857 -320.102345) (xy 77.905186 -320.122807) (xy 77.910155 -320.142943)
			(xy 77.916024 -320.151506) (xy 77.935526 -320.178118) (xy 77.968268 -320.235396) (xy 77.993329 -320.296427)
			(xy 78.010287 -320.360187) (xy 78.018858 -320.425604) (xy 78.019402 -320.458592) (xy 78.019402 -320.458846)
			(xy 78.018953 -320.489567) (xy 78.011549 -320.550562) (xy 77.996853 -320.610221) (xy 77.975079 -320.667675)
			(xy 77.946545 -320.72209) (xy 77.929486 -320.747644) (xy 77.924055 -320.756308) (xy 77.920007 -320.776338)
			(xy 77.924085 -320.796363) (xy 77.929486 -320.805048) (xy 77.946585 -320.830575) (xy 77.975111 -320.884996)
			(xy 77.996876 -320.942456) (xy 78.011563 -321.002119) (xy 78.018958 -321.063116) (xy 78.018954 -321.12456)
			(xy 78.01155 -321.185556) (xy 77.996854 -321.245217) (xy 77.97508 -321.302673) (xy 77.946545 -321.35709)
			(xy 77.929486 -321.382644) (xy 77.924055 -321.391308) (xy 77.920007 -321.411338) (xy 77.924085 -321.431363)
			(xy 77.929486 -321.440048) (xy 77.946585 -321.465575) (xy 77.975111 -321.519996) (xy 77.996876 -321.577456)
			(xy 78.011563 -321.637119) (xy 78.018958 -321.698116) (xy 78.018954 -321.75956) (xy 78.01155 -321.820556)
			(xy 77.996854 -321.880217) (xy 77.97508 -321.937673) (xy 77.946545 -321.99209) (xy 77.929486 -322.017644)
			(xy 77.924055 -322.026308) (xy 77.920007 -322.046338) (xy 77.924085 -322.066363) (xy 77.929486 -322.075048)
			(xy 77.946559 -322.100593) (xy 77.97509 -322.15501) (xy 77.996858 -322.212467) (xy 78.011547 -322.272128)
			(xy 78.018942 -322.333125) (xy 78.019402 -322.363846) (xy 78.019402 -322.3641) (xy 78.018874 -322.397081)
			(xy 78.010374 -322.462493) (xy 77.99348 -322.526255) (xy 77.968474 -322.587293) (xy 77.935777 -322.644582)
			(xy 77.916278 -322.671186) (xy 77.91036 -322.679782) (xy 77.905444 -322.700047) (xy 77.90897 -322.7206)
			(xy 77.914246 -322.729606) (xy 77.930085 -322.754531) (xy 77.956539 -322.807331) (xy 77.976697 -322.86284)
			(xy 77.990289 -322.920311) (xy 77.997131 -322.97897) (xy 77.997558 -323.008498) (xy 77.997558 -323.008752)
			(xy 79.723742 -323.008752) (xy 79.723742 -323.008498) (xy 79.72428 -322.975517) (xy 79.732779 -322.910106)
			(xy 79.749672 -322.846345) (xy 79.774675 -322.785306) (xy 79.807369 -322.728017) (xy 79.826866 -322.701412)
			(xy 79.832783 -322.692817) (xy 79.837694 -322.672551) (xy 79.834171 -322.652) (xy 79.828898 -322.642992)
			(xy 79.813063 -322.618065) (xy 79.786608 -322.565266) (xy 79.766448 -322.509757) (xy 79.752855 -322.452287)
			(xy 79.746012 -322.393628) (xy 79.745586 -322.3641) (xy 79.745586 -322.363846) (xy 79.746033 -322.333125)
			(xy 79.753438 -322.27213) (xy 79.768135 -322.212471) (xy 79.789909 -322.155017) (xy 79.818443 -322.100602)
			(xy 79.835502 -322.075048) (xy 79.840856 -322.066342) (xy 79.844931 -322.046338) (xy 79.840886 -322.026328)
			(xy 79.835502 -322.017644) (xy 79.818485 -321.992064) (xy 79.789948 -321.937654) (xy 79.768173 -321.880203)
			(xy 79.753476 -321.820548) (xy 79.746071 -321.759557) (xy 79.746066 -321.698118) (xy 79.753462 -321.637126)
			(xy 79.76815 -321.577469) (xy 79.789917 -321.520015) (xy 79.818445 -321.465601) (xy 79.835502 -321.440048)
			(xy 79.840856 -321.431342) (xy 79.844931 -321.411338) (xy 79.840886 -321.391328) (xy 79.835502 -321.382644)
			(xy 79.818485 -321.357064) (xy 79.789948 -321.302654) (xy 79.768173 -321.245203) (xy 79.753476 -321.185548)
			(xy 79.746071 -321.124557) (xy 79.746066 -321.063118) (xy 79.753462 -321.002126) (xy 79.76815 -320.942469)
			(xy 79.789917 -320.885015) (xy 79.818445 -320.830601) (xy 79.835502 -320.805048) (xy 79.840856 -320.796342)
			(xy 79.844931 -320.776338) (xy 79.840886 -320.756328) (xy 79.835502 -320.747644) (xy 79.818424 -320.722103)
			(xy 79.789895 -320.667685) (xy 79.768128 -320.610226) (xy 79.75344 -320.550564) (xy 79.746045 -320.489568)
			(xy 79.745586 -320.458846) (xy 79.745586 -320.458592) (xy 79.746063 -320.427653) (xy 79.753562 -320.366231)
			(xy 79.768461 -320.306173) (xy 79.790539 -320.248368) (xy 79.81947 -320.193669) (xy 79.836772 -320.168016)
			(xy 79.842298 -320.159289) (xy 79.846434 -320.139067) (xy 79.842272 -320.11885) (xy 79.836772 -320.110104)
			(xy 79.819477 -320.084446) (xy 79.790545 -320.029748) (xy 79.768462 -319.971944) (xy 79.753556 -319.911888)
			(xy 79.746045 -319.850467) (xy 79.745586 -319.819528) (xy 79.745586 -319.819274) (xy 79.746047 -319.788553)
			(xy 79.753449 -319.727559) (xy 79.768142 -319.667901) (xy 79.789913 -319.610445) (xy 79.818444 -319.55603)
			(xy 79.835502 -319.530476) (xy 79.840917 -319.521803) (xy 79.844972 -319.501778) (xy 79.8409 -319.481757)
			(xy 79.835502 -319.473072) (xy 79.818419 -319.447534) (xy 79.789886 -319.393117) (xy 79.768116 -319.335659)
			(xy 79.753425 -319.275997) (xy 79.746027 -319.215001) (xy 79.746029 -319.153557) (xy 79.753432 -319.092561)
			(xy 79.768129 -319.0329) (xy 79.789904 -318.975444) (xy 79.818441 -318.921029) (xy 79.835502 -318.895476)
			(xy 79.840917 -318.886803) (xy 79.844972 -318.866778) (xy 79.8409 -318.846757) (xy 79.835502 -318.838072)
			(xy 79.818419 -318.812534) (xy 79.789886 -318.758117) (xy 79.768116 -318.700659) (xy 79.753425 -318.640997)
			(xy 79.746027 -318.580001) (xy 79.746029 -318.518557) (xy 79.753432 -318.457561) (xy 79.768129 -318.3979)
			(xy 79.789904 -318.340444) (xy 79.818441 -318.286029) (xy 79.835502 -318.260476) (xy 79.840917 -318.251803)
			(xy 79.844972 -318.231778) (xy 79.8409 -318.211757) (xy 79.835502 -318.203072) (xy 79.818419 -318.177534)
			(xy 79.789886 -318.123117) (xy 79.768116 -318.065659) (xy 79.753425 -318.005997) (xy 79.746027 -317.945001)
			(xy 79.746029 -317.883557) (xy 79.753432 -317.822561) (xy 79.768129 -317.7629) (xy 79.789904 -317.705444)
			(xy 79.818441 -317.651029) (xy 79.835502 -317.625476) (xy 79.840917 -317.616803) (xy 79.844972 -317.596778)
			(xy 79.8409 -317.576757) (xy 79.835502 -317.568072) (xy 79.818419 -317.542534) (xy 79.789886 -317.488117)
			(xy 79.768116 -317.430659) (xy 79.753425 -317.370997) (xy 79.746027 -317.310001) (xy 79.746029 -317.248557)
			(xy 79.753432 -317.187561) (xy 79.768129 -317.1279) (xy 79.789904 -317.070444) (xy 79.818441 -317.016029)
			(xy 79.835502 -316.990476) (xy 79.840917 -316.981803) (xy 79.844972 -316.961778) (xy 79.8409 -316.941757)
			(xy 79.835502 -316.933072) (xy 79.818436 -316.907523) (xy 79.789905 -316.853107) (xy 79.768135 -316.795651)
			(xy 79.753445 -316.73599) (xy 79.746047 -316.674995) (xy 79.745586 -316.644274) (xy 79.746032 -316.613543)
			(xy 79.753443 -316.552528) (xy 79.768154 -316.492852) (xy 79.789951 -316.435385) (xy 79.818516 -316.380963)
			(xy 79.853432 -316.330381) (xy 79.894191 -316.284377) (xy 79.940197 -316.24362) (xy 79.99078 -316.208706)
			(xy 80.045203 -316.180143) (xy 80.102672 -316.158348) (xy 80.162348 -316.143639) (xy 80.223363 -316.13623)
			(xy 80.254094 -316.135766) (xy 80.284814 -316.136247) (xy 80.345807 -316.143645) (xy 80.405466 -316.158334)
			(xy 80.462921 -316.1801) (xy 80.517337 -316.208627) (xy 80.542892 -316.225682) (xy 80.551577 -316.231075)
			(xy 80.571594 -316.235136) (xy 80.591611 -316.231075) (xy 80.600296 -316.225682) (xy 80.62585 -316.208624)
			(xy 80.680265 -316.180093) (xy 80.73772 -316.158322) (xy 80.797379 -316.14363) (xy 80.858373 -316.13623)
			(xy 80.919815 -316.13623) (xy 80.980809 -316.14363) (xy 81.040468 -316.158322) (xy 81.097923 -316.180093)
			(xy 81.152338 -316.208624) (xy 81.177892 -316.225682) (xy 81.186577 -316.231075) (xy 81.206594 -316.235136)
			(xy 81.226611 -316.231075) (xy 81.235296 -316.225682) (xy 81.260853 -316.208628) (xy 81.315267 -316.180095)
			(xy 81.372721 -316.158323) (xy 81.43238 -316.14363) (xy 81.493373 -316.136229) (xy 81.524094 -316.135766)
			(xy 81.554824 -316.136262) (xy 81.615836 -316.143669) (xy 81.67551 -316.158376) (xy 81.732976 -316.180169)
			(xy 81.787397 -316.208729) (xy 81.837978 -316.243641) (xy 81.883982 -316.284395) (xy 81.924739 -316.330397)
			(xy 81.959654 -316.380976) (xy 81.988218 -316.435395) (xy 82.010014 -316.49286) (xy 82.024725 -316.552533)
			(xy 82.032136 -316.613544) (xy 82.032602 -316.644274) (xy 82.032117 -316.674994) (xy 82.024721 -316.735987)
			(xy 82.010033 -316.795646) (xy 81.988268 -316.853101) (xy 81.959741 -316.907517) (xy 81.942686 -316.933072)
			(xy 81.937316 -316.941769) (xy 81.933248 -316.961778) (xy 81.937299 -316.981791) (xy 81.942686 -316.990476)
			(xy 81.959719 -317.016046) (xy 81.98825 -317.070459) (xy 82.01002 -317.127911) (xy 82.024712 -317.187568)
			(xy 82.032114 -317.248559) (xy 82.032117 -317.309998) (xy 82.02472 -317.37099) (xy 82.010032 -317.430648)
			(xy 81.988267 -317.488102) (xy 81.959741 -317.542518) (xy 81.942686 -317.568072) (xy 81.937316 -317.576769)
			(xy 81.933248 -317.596778) (xy 81.937299 -317.616791) (xy 81.942686 -317.625476) (xy 81.959719 -317.651046)
			(xy 81.98825 -317.705459) (xy 82.01002 -317.762911) (xy 82.024712 -317.822568) (xy 82.032114 -317.883559)
			(xy 82.032117 -317.944998) (xy 82.02472 -318.00599) (xy 82.010032 -318.065648) (xy 81.988267 -318.123102)
			(xy 81.959741 -318.177518) (xy 81.942686 -318.203072) (xy 81.937316 -318.211769) (xy 81.933248 -318.231778)
			(xy 81.937299 -318.251791) (xy 81.942686 -318.260476) (xy 81.959719 -318.286046) (xy 81.98825 -318.340459)
			(xy 82.01002 -318.397911) (xy 82.024712 -318.457568) (xy 82.032114 -318.518559) (xy 82.032117 -318.579998)
			(xy 82.02472 -318.64099) (xy 82.010032 -318.700648) (xy 81.988267 -318.758102) (xy 81.959741 -318.812518)
			(xy 81.942686 -318.838072) (xy 81.937316 -318.846769) (xy 81.933248 -318.866778) (xy 81.937299 -318.886791)
			(xy 81.942686 -318.895476) (xy 81.959719 -318.921046) (xy 81.98825 -318.975459) (xy 82.01002 -319.032911)
			(xy 82.024712 -319.092568) (xy 82.032114 -319.153559) (xy 82.032117 -319.214998) (xy 82.02472 -319.27599)
			(xy 82.010032 -319.335648) (xy 81.988267 -319.393102) (xy 81.959741 -319.447518) (xy 81.942686 -319.473072)
			(xy 81.937316 -319.481769) (xy 81.933248 -319.501778) (xy 81.937299 -319.521791) (xy 81.942686 -319.530476)
			(xy 81.959719 -319.556046) (xy 81.98825 -319.610459) (xy 82.01002 -319.667911) (xy 82.024712 -319.727568)
			(xy 82.032114 -319.788559) (xy 82.032117 -319.849998) (xy 82.02472 -319.91099) (xy 82.010032 -319.970648)
			(xy 81.988267 -320.028102) (xy 81.959741 -320.082518) (xy 81.942686 -320.108072) (xy 81.937316 -320.116769)
			(xy 81.933248 -320.136778) (xy 81.937299 -320.156791) (xy 81.942686 -320.165476) (xy 81.959719 -320.191046)
			(xy 81.98825 -320.245459) (xy 82.01002 -320.302911) (xy 82.024712 -320.362568) (xy 82.032114 -320.423559)
			(xy 82.032117 -320.484998) (xy 82.02472 -320.54599) (xy 82.010032 -320.605648) (xy 81.988267 -320.663102)
			(xy 81.959741 -320.717518) (xy 81.942686 -320.743072) (xy 81.937316 -320.751769) (xy 81.933248 -320.771778)
			(xy 81.937299 -320.791791) (xy 81.942686 -320.800476) (xy 81.959719 -320.826046) (xy 81.98825 -320.880459)
			(xy 82.01002 -320.937911) (xy 82.024712 -320.997568) (xy 82.032114 -321.058559) (xy 82.032117 -321.119998)
			(xy 82.02472 -321.18099) (xy 82.010032 -321.240648) (xy 81.988267 -321.298102) (xy 81.959741 -321.352518)
			(xy 81.942686 -321.378072) (xy 81.937316 -321.386769) (xy 81.933248 -321.406778) (xy 81.937299 -321.426791)
			(xy 81.942686 -321.435476) (xy 81.959719 -321.461046) (xy 81.98825 -321.515459) (xy 82.01002 -321.572911)
			(xy 82.024712 -321.632568) (xy 82.032114 -321.693559) (xy 82.032117 -321.754998) (xy 82.02472 -321.81599)
			(xy 82.010032 -321.875648) (xy 81.988267 -321.933102) (xy 81.959741 -321.987518) (xy 81.942686 -322.013072)
			(xy 81.937316 -322.021769) (xy 81.933248 -322.041778) (xy 81.937299 -322.061791) (xy 81.942686 -322.070476)
			(xy 81.959727 -322.096041) (xy 81.988264 -322.150452) (xy 82.010038 -322.207904) (xy 82.024734 -322.267561)
			(xy 82.032138 -322.328554) (xy 82.032602 -322.359274) (xy 82.032036 -322.392517) (xy 82.023356 -322.458436)
			(xy 82.006153 -322.522659) (xy 81.980722 -322.58409) (xy 81.947496 -322.64168) (xy 81.9277 -322.668392)
			(xy 81.921752 -322.67709) (xy 81.916824 -322.697554) (xy 81.920512 -322.718277) (xy 81.925922 -322.72732)
			(xy 81.942068 -322.752405) (xy 81.969026 -322.805626) (xy 81.989566 -322.861638) (xy 82.003404 -322.919669)
			(xy 82.01035 -322.978922) (xy 82.010758 -323.008752) (xy 84.063586 -323.008752) (xy 84.064036 -322.978031)
			(xy 84.07144 -322.917037) (xy 84.086136 -322.857378) (xy 84.10791 -322.799923) (xy 84.136443 -322.745508)
			(xy 84.153502 -322.719954) (xy 84.158936 -322.711291) (xy 84.162984 -322.69126) (xy 84.158905 -322.671235)
			(xy 84.153502 -322.66255) (xy 84.136399 -322.637025) (xy 84.107868 -322.582605) (xy 84.086099 -322.525145)
			(xy 84.071409 -322.465482) (xy 84.064013 -322.404483) (xy 84.064018 -322.343038) (xy 84.071423 -322.28204)
			(xy 84.086122 -322.222379) (xy 84.1079 -322.164923) (xy 84.13644 -322.110507) (xy 84.153502 -322.084954)
			(xy 84.158936 -322.076291) (xy 84.162984 -322.05626) (xy 84.158905 -322.036235) (xy 84.153502 -322.02755)
			(xy 84.136399 -322.002025) (xy 84.107868 -321.947605) (xy 84.086099 -321.890145) (xy 84.071409 -321.830482)
			(xy 84.064013 -321.769483) (xy 84.064018 -321.708038) (xy 84.071423 -321.64704) (xy 84.086122 -321.587379)
			(xy 84.1079 -321.529923) (xy 84.13644 -321.475507) (xy 84.153502 -321.449954) (xy 84.158936 -321.441291)
			(xy 84.162984 -321.42126) (xy 84.158905 -321.401235) (xy 84.153502 -321.39255) (xy 84.136399 -321.367025)
			(xy 84.107868 -321.312605) (xy 84.086099 -321.255145) (xy 84.071409 -321.195482) (xy 84.064013 -321.134483)
			(xy 84.064018 -321.073038) (xy 84.071423 -321.01204) (xy 84.086122 -320.952379) (xy 84.1079 -320.894923)
			(xy 84.13644 -320.840507) (xy 84.153502 -320.814954) (xy 84.158936 -320.806291) (xy 84.162984 -320.78626)
			(xy 84.158905 -320.766235) (xy 84.153502 -320.75755) (xy 84.136427 -320.732007) (xy 84.107897 -320.677589)
			(xy 84.086129 -320.620131) (xy 84.071441 -320.56047) (xy 84.064046 -320.499474) (xy 84.063586 -320.468752)
			(xy 84.063586 -320.468498) (xy 84.064065 -320.436929) (xy 84.071928 -320.374281) (xy 84.087483 -320.313089)
			(xy 84.110491 -320.254291) (xy 84.140598 -320.198792) (xy 84.158582 -320.172842) (xy 84.164278 -320.163981)
			(xy 84.16858 -320.143382) (xy 84.164263 -320.122786) (xy 84.158582 -320.113914) (xy 84.140777 -320.088004)
			(xy 84.110968 -320.032654) (xy 84.088202 -319.974053) (xy 84.072826 -319.913095) (xy 84.065074 -319.850708)
			(xy 84.064602 -319.819274) (xy 84.06506 -319.788553) (xy 84.072462 -319.727559) (xy 84.087156 -319.6679)
			(xy 84.108928 -319.610445) (xy 84.13746 -319.55603) (xy 84.154518 -319.530476) (xy 84.159932 -319.521803)
			(xy 84.163985 -319.501778) (xy 84.159915 -319.481757) (xy 84.154518 -319.473072) (xy 84.137438 -319.447533)
			(xy 84.10891 -319.393115) (xy 84.087143 -319.335657) (xy 84.072454 -319.275996) (xy 84.065057 -319.215)
			(xy 84.06506 -319.153557) (xy 84.072462 -319.092562) (xy 84.087156 -319.032902) (xy 84.108927 -318.975446)
			(xy 84.13746 -318.92103) (xy 84.154518 -318.895476) (xy 84.159932 -318.886803) (xy 84.163985 -318.866778)
			(xy 84.159915 -318.846757) (xy 84.154518 -318.838072) (xy 84.137438 -318.812533) (xy 84.10891 -318.758115)
			(xy 84.087143 -318.700657) (xy 84.072454 -318.640996) (xy 84.065057 -318.58) (xy 84.06506 -318.518557)
			(xy 84.072462 -318.457562) (xy 84.087156 -318.397902) (xy 84.108927 -318.340446) (xy 84.13746 -318.28603)
			(xy 84.154518 -318.260476) (xy 84.159932 -318.251803) (xy 84.163985 -318.231778) (xy 84.159915 -318.211757)
			(xy 84.154518 -318.203072) (xy 84.137438 -318.177533) (xy 84.10891 -318.123115) (xy 84.087143 -318.065657)
			(xy 84.072454 -318.005996) (xy 84.065057 -317.945) (xy 84.06506 -317.883557) (xy 84.072462 -317.822562)
			(xy 84.087156 -317.762902) (xy 84.108927 -317.705446) (xy 84.13746 -317.65103) (xy 84.154518 -317.625476)
			(xy 84.159932 -317.616803) (xy 84.163985 -317.596778) (xy 84.159915 -317.576757) (xy 84.154518 -317.568072)
			(xy 84.137438 -317.542533) (xy 84.10891 -317.488115) (xy 84.087143 -317.430657) (xy 84.072454 -317.370996)
			(xy 84.065057 -317.31) (xy 84.06506 -317.248557) (xy 84.072462 -317.187562) (xy 84.087156 -317.127902)
			(xy 84.108927 -317.070446) (xy 84.13746 -317.01603) (xy 84.154518 -316.990476) (xy 84.159932 -316.981803)
			(xy 84.163985 -316.961778) (xy 84.159915 -316.941757) (xy 84.154518 -316.933072) (xy 84.137454 -316.907522)
			(xy 84.108922 -316.853106) (xy 84.087152 -316.79565) (xy 84.072461 -316.73599) (xy 84.065063 -316.674995)
			(xy 84.064602 -316.644274) (xy 84.065032 -316.613542) (xy 84.072443 -316.552527) (xy 84.087155 -316.492849)
			(xy 84.108953 -316.435381) (xy 84.137519 -316.380958) (xy 84.172437 -316.330376) (xy 84.213196 -316.284371)
			(xy 84.259204 -316.243614) (xy 84.309789 -316.208701) (xy 84.364214 -316.180138) (xy 84.421684 -316.158345)
			(xy 84.481362 -316.143637) (xy 84.542378 -316.136229) (xy 84.57311 -316.135766) (xy 84.60383 -316.136238)
			(xy 84.664824 -316.143638) (xy 84.724482 -316.158329) (xy 84.781937 -316.180097) (xy 84.836353 -316.208626)
			(xy 84.861908 -316.225682) (xy 84.870593 -316.231075) (xy 84.89061 -316.235136) (xy 84.910627 -316.231075)
			(xy 84.919312 -316.225682) (xy 84.944866 -316.208624) (xy 84.999281 -316.180093) (xy 85.056736 -316.158322)
			(xy 85.116395 -316.14363) (xy 85.177389 -316.13623) (xy 85.238831 -316.13623) (xy 85.299825 -316.14363)
			(xy 85.359484 -316.158322) (xy 85.416939 -316.180093) (xy 85.471354 -316.208624) (xy 85.496908 -316.225682)
			(xy 85.505593 -316.231075) (xy 85.52561 -316.235136) (xy 85.545627 -316.231075) (xy 85.554312 -316.225682)
			(xy 85.579864 -316.208621) (xy 85.634279 -316.180089) (xy 85.691735 -316.158319) (xy 85.751394 -316.143627)
			(xy 85.812389 -316.136228) (xy 85.84311 -316.135766) (xy 85.87384 -316.136247) (xy 85.934852 -316.143656)
			(xy 85.994527 -316.158365) (xy 86.051993 -316.180159) (xy 86.106414 -316.208721) (xy 86.156995 -316.243634)
			(xy 86.202999 -316.284389) (xy 86.243756 -316.330392) (xy 86.278671 -316.380973) (xy 86.307234 -316.435392)
			(xy 86.329031 -316.492858) (xy 86.343741 -316.552532) (xy 86.351152 -316.613544) (xy 86.351618 -316.644274)
			(xy 86.35113 -316.674994) (xy 86.343734 -316.735987) (xy 86.329047 -316.795645) (xy 86.307282 -316.853101)
			(xy 86.278757 -316.907517) (xy 86.261702 -316.933072) (xy 86.256331 -316.941768) (xy 86.252261 -316.961778)
			(xy 86.256314 -316.981792) (xy 86.261702 -316.990476) (xy 86.278738 -317.016045) (xy 86.307273 -317.070456)
			(xy 86.329047 -317.127909) (xy 86.343742 -317.187566) (xy 86.351145 -317.248559) (xy 86.351147 -317.309999)
			(xy 86.34375 -317.370992) (xy 86.329059 -317.43065) (xy 86.30729 -317.488104) (xy 86.27876 -317.542519)
			(xy 86.261702 -317.568072) (xy 86.256331 -317.576768) (xy 86.252261 -317.596778) (xy 86.256314 -317.616792)
			(xy 86.261702 -317.625476) (xy 86.278738 -317.651045) (xy 86.307273 -317.705456) (xy 86.329047 -317.762909)
			(xy 86.343742 -317.822566) (xy 86.351145 -317.883559) (xy 86.351147 -317.944999) (xy 86.34375 -318.005992)
			(xy 86.329059 -318.06565) (xy 86.30729 -318.123104) (xy 86.27876 -318.177519) (xy 86.261702 -318.203072)
			(xy 86.256331 -318.211768) (xy 86.252261 -318.231778) (xy 86.256314 -318.251792) (xy 86.261702 -318.260476)
			(xy 86.278738 -318.286045) (xy 86.307273 -318.340456) (xy 86.329047 -318.397909) (xy 86.343742 -318.457566)
			(xy 86.351145 -318.518559) (xy 86.351147 -318.579999) (xy 86.34375 -318.640992) (xy 86.329059 -318.70065)
			(xy 86.30729 -318.758104) (xy 86.27876 -318.812519) (xy 86.261702 -318.838072) (xy 86.256331 -318.846768)
			(xy 86.252261 -318.866778) (xy 86.256314 -318.886792) (xy 86.261702 -318.895476) (xy 86.278738 -318.921045)
			(xy 86.307273 -318.975456) (xy 86.329047 -319.032909) (xy 86.343742 -319.092566) (xy 86.351145 -319.153559)
			(xy 86.351147 -319.214999) (xy 86.34375 -319.275992) (xy 86.329059 -319.33565) (xy 86.30729 -319.393104)
			(xy 86.27876 -319.447519) (xy 86.261702 -319.473072) (xy 86.256331 -319.481768) (xy 86.252261 -319.501778)
			(xy 86.256314 -319.521792) (xy 86.261702 -319.530476) (xy 86.278745 -319.556039) (xy 86.307281 -319.610451)
			(xy 86.329055 -319.667904) (xy 86.343751 -319.727561) (xy 86.351154 -319.788554) (xy 86.351618 -319.819274)
			(xy 86.351217 -319.848229) (xy 86.344619 -319.905763) (xy 86.331527 -319.962175) (xy 86.312112 -320.016735)
			(xy 86.286625 -320.068735) (xy 86.271354 -320.09334) (xy 86.266197 -320.102348) (xy 86.262818 -320.122807)
			(xy 86.267779 -320.14294) (xy 86.27364 -320.151506) (xy 86.293144 -320.178116) (xy 86.325886 -320.235395)
			(xy 86.350945 -320.296427) (xy 86.367903 -320.360187) (xy 86.376474 -320.425604) (xy 86.377018 -320.458592)
			(xy 86.377018 -320.458846) (xy 86.376567 -320.489567) (xy 86.369162 -320.550561) (xy 86.354467 -320.61022)
			(xy 86.332694 -320.667675) (xy 86.30416 -320.72209) (xy 86.287102 -320.747644) (xy 86.281669 -320.756308)
			(xy 86.27762 -320.776338) (xy 86.281699 -320.796363) (xy 86.287102 -320.805048) (xy 86.304203 -320.830574)
			(xy 86.332734 -320.884994) (xy 86.354503 -320.942454) (xy 86.369193 -321.002117) (xy 86.376589 -321.063115)
			(xy 86.376584 -321.12456) (xy 86.369179 -321.185558) (xy 86.354481 -321.245219) (xy 86.332703 -321.302675)
			(xy 86.304164 -321.357091) (xy 86.287102 -321.382644) (xy 86.281669 -321.391308) (xy 86.27762 -321.411338)
			(xy 86.281699 -321.431363) (xy 86.287102 -321.440048) (xy 86.304203 -321.465574) (xy 86.332734 -321.519994)
			(xy 86.354503 -321.577454) (xy 86.369193 -321.637117) (xy 86.376589 -321.698115) (xy 86.376584 -321.75956)
			(xy 86.369179 -321.820558) (xy 86.354481 -321.880219) (xy 86.332703 -321.937675) (xy 86.304164 -321.992091)
			(xy 86.287102 -322.017644) (xy 86.281669 -322.026308) (xy 86.27762 -322.046338) (xy 86.281699 -322.066363)
			(xy 86.287102 -322.075048) (xy 86.304177 -322.100591) (xy 86.332707 -322.155009) (xy 86.354474 -322.212467)
			(xy 86.369163 -322.272128) (xy 86.376558 -322.333124) (xy 86.377018 -322.363846) (xy 86.376482 -322.397208)
			(xy 86.36776 -322.463359) (xy 86.350471 -322.527804) (xy 86.324911 -322.589439) (xy 86.291519 -322.647206)
			(xy 86.271608 -322.67398) (xy 86.265601 -322.682573) (xy 86.260479 -322.702886) (xy 86.263842 -322.723563)
			(xy 86.269068 -322.732654) (xy 86.284604 -322.757378) (xy 86.310496 -322.809719) (xy 86.330218 -322.864682)
			(xy 86.34351 -322.921544) (xy 86.350197 -322.979555) (xy 86.350602 -323.008752) (xy 88.102186 -323.008752)
			(xy 88.102661 -322.977411) (xy 88.110367 -322.915203) (xy 88.125656 -322.854414) (xy 88.148297 -322.795963)
			(xy 88.177947 -322.740736) (xy 88.195658 -322.714874) (xy 88.201288 -322.706087) (xy 88.20552 -322.68567)
			(xy 88.201264 -322.665258) (xy 88.195658 -322.656454) (xy 88.178122 -322.630665) (xy 88.14877 -322.575639)
			(xy 88.12637 -322.517436) (xy 88.111257 -322.456929) (xy 88.10366 -322.395029) (xy 88.103202 -322.363846)
			(xy 88.103646 -322.333125) (xy 88.111052 -322.27213) (xy 88.125749 -322.212471) (xy 88.147523 -322.155016)
			(xy 88.176059 -322.100602) (xy 88.193118 -322.075048) (xy 88.198471 -322.066342) (xy 88.202544 -322.046338)
			(xy 88.1985 -322.026329) (xy 88.193118 -322.017644) (xy 88.176103 -321.992063) (xy 88.147571 -321.937652)
			(xy 88.1258 -321.880201) (xy 88.111105 -321.820547) (xy 88.103702 -321.759557) (xy 88.103697 -321.698119)
			(xy 88.111091 -321.637128) (xy 88.125777 -321.577471) (xy 88.14754 -321.520017) (xy 88.176064 -321.465602)
			(xy 88.193118 -321.440048) (xy 88.198471 -321.431342) (xy 88.202544 -321.411338) (xy 88.1985 -321.391329)
			(xy 88.193118 -321.382644) (xy 88.176103 -321.357063) (xy 88.147571 -321.302652) (xy 88.1258 -321.245201)
			(xy 88.111105 -321.185547) (xy 88.103702 -321.124557) (xy 88.103697 -321.063119) (xy 88.111091 -321.002128)
			(xy 88.125777 -320.942471) (xy 88.14754 -320.885017) (xy 88.176064 -320.830602) (xy 88.193118 -320.805048)
			(xy 88.198471 -320.796342) (xy 88.202544 -320.776338) (xy 88.1985 -320.756329) (xy 88.193118 -320.747644)
			(xy 88.176042 -320.722101) (xy 88.147512 -320.667684) (xy 88.125744 -320.610226) (xy 88.111056 -320.550564)
			(xy 88.103661 -320.489568) (xy 88.103202 -320.458846) (xy 88.103202 -320.458592) (xy 88.103676 -320.427653)
			(xy 88.111176 -320.36623) (xy 88.126075 -320.306173) (xy 88.148154 -320.248367) (xy 88.177086 -320.193669)
			(xy 88.194388 -320.168016) (xy 88.199912 -320.159288) (xy 88.204047 -320.139067) (xy 88.199886 -320.118851)
			(xy 88.194388 -320.110104) (xy 88.177096 -320.084444) (xy 88.148163 -320.029747) (xy 88.126079 -319.971943)
			(xy 88.111172 -319.911888) (xy 88.103662 -319.850467) (xy 88.103202 -319.819528) (xy 88.103202 -319.819274)
			(xy 88.10366 -319.788553) (xy 88.111062 -319.727559) (xy 88.125756 -319.6679) (xy 88.147528 -319.610445)
			(xy 88.17606 -319.55603) (xy 88.193118 -319.530476) (xy 88.198532 -319.521803) (xy 88.202585 -319.501778)
			(xy 88.198515 -319.481757) (xy 88.193118 -319.473072) (xy 88.176038 -319.447533) (xy 88.14751 -319.393115)
			(xy 88.125743 -319.335657) (xy 88.111054 -319.275996) (xy 88.103657 -319.215) (xy 88.10366 -319.153557)
			(xy 88.111062 -319.092562) (xy 88.125756 -319.032902) (xy 88.147527 -318.975446) (xy 88.17606 -318.92103)
			(xy 88.193118 -318.895476) (xy 88.198532 -318.886803) (xy 88.202585 -318.866778) (xy 88.198515 -318.846757)
			(xy 88.193118 -318.838072) (xy 88.176038 -318.812533) (xy 88.14751 -318.758115) (xy 88.125743 -318.700657)
			(xy 88.111054 -318.640996) (xy 88.103657 -318.58) (xy 88.10366 -318.518557) (xy 88.111062 -318.457562)
			(xy 88.125756 -318.397902) (xy 88.147527 -318.340446) (xy 88.17606 -318.28603) (xy 88.193118 -318.260476)
			(xy 88.198532 -318.251803) (xy 88.202585 -318.231778) (xy 88.198515 -318.211757) (xy 88.193118 -318.203072)
			(xy 88.176038 -318.177533) (xy 88.14751 -318.123115) (xy 88.125743 -318.065657) (xy 88.111054 -318.005996)
			(xy 88.103657 -317.945) (xy 88.10366 -317.883557) (xy 88.111062 -317.822562) (xy 88.125756 -317.762902)
			(xy 88.147527 -317.705446) (xy 88.17606 -317.65103) (xy 88.193118 -317.625476) (xy 88.198532 -317.616803)
			(xy 88.202585 -317.596778) (xy 88.198515 -317.576757) (xy 88.193118 -317.568072) (xy 88.176038 -317.542533)
			(xy 88.14751 -317.488115) (xy 88.125743 -317.430657) (xy 88.111054 -317.370996) (xy 88.103657 -317.31)
			(xy 88.10366 -317.248557) (xy 88.111062 -317.187562) (xy 88.125756 -317.127902) (xy 88.147527 -317.070446)
			(xy 88.17606 -317.01603) (xy 88.193118 -316.990476) (xy 88.198532 -316.981803) (xy 88.202585 -316.961778)
			(xy 88.198515 -316.941757) (xy 88.193118 -316.933072) (xy 88.176054 -316.907522) (xy 88.147522 -316.853106)
			(xy 88.125752 -316.79565) (xy 88.111061 -316.73599) (xy 88.103663 -316.674995) (xy 88.103202 -316.644274)
			(xy 88.103632 -316.613542) (xy 88.111043 -316.552527) (xy 88.125755 -316.492849) (xy 88.147553 -316.435381)
			(xy 88.176119 -316.380958) (xy 88.211037 -316.330376) (xy 88.251796 -316.284371) (xy 88.297804 -316.243614)
			(xy 88.348389 -316.208701) (xy 88.402814 -316.180138) (xy 88.460284 -316.158345) (xy 88.519962 -316.143637)
			(xy 88.580978 -316.136229) (xy 88.61171 -316.135766) (xy 88.64243 -316.136238) (xy 88.703424 -316.143638)
			(xy 88.763082 -316.158329) (xy 88.820537 -316.180097) (xy 88.874953 -316.208626) (xy 88.900508 -316.225682)
			(xy 88.909193 -316.231075) (xy 88.92921 -316.235136) (xy 88.949227 -316.231075) (xy 88.957912 -316.225682)
			(xy 88.983466 -316.208624) (xy 89.037881 -316.180093) (xy 89.095336 -316.158322) (xy 89.154995 -316.14363)
			(xy 89.215989 -316.13623) (xy 89.277431 -316.13623) (xy 89.338425 -316.14363) (xy 89.398084 -316.158322)
			(xy 89.455539 -316.180093) (xy 89.509954 -316.208624) (xy 89.535508 -316.225682) (xy 89.544193 -316.231075)
			(xy 89.56421 -316.235136) (xy 89.584227 -316.231075) (xy 89.592912 -316.225682) (xy 89.618464 -316.208621)
			(xy 89.672879 -316.180089) (xy 89.730335 -316.158319) (xy 89.789994 -316.143627) (xy 89.850989 -316.136228)
			(xy 89.88171 -316.135766) (xy 89.91244 -316.136247) (xy 89.973452 -316.143656) (xy 90.033127 -316.158365)
			(xy 90.090593 -316.180159) (xy 90.145014 -316.208721) (xy 90.195595 -316.243634) (xy 90.241599 -316.284389)
			(xy 90.282356 -316.330392) (xy 90.317271 -316.380973) (xy 90.345834 -316.435392) (xy 90.367631 -316.492858)
			(xy 90.382341 -316.552532) (xy 90.389752 -316.613544) (xy 90.390218 -316.644274) (xy 90.38973 -316.674994)
			(xy 90.382334 -316.735987) (xy 90.367647 -316.795645) (xy 90.345882 -316.853101) (xy 90.317357 -316.907517)
			(xy 90.300302 -316.933072) (xy 90.294931 -316.941768) (xy 90.290861 -316.961778) (xy 90.294914 -316.981792)
			(xy 90.300302 -316.990476) (xy 90.317338 -317.016045) (xy 90.345873 -317.070456) (xy 90.367647 -317.127909)
			(xy 90.382342 -317.187566) (xy 90.389745 -317.248559) (xy 90.389747 -317.309999) (xy 90.38235 -317.370992)
			(xy 90.367659 -317.43065) (xy 90.34589 -317.488104) (xy 90.31736 -317.542519) (xy 90.300302 -317.568072)
			(xy 90.294931 -317.576768) (xy 90.290861 -317.596778) (xy 90.294914 -317.616792) (xy 90.300302 -317.625476)
			(xy 90.317338 -317.651045) (xy 90.345873 -317.705456) (xy 90.367647 -317.762909) (xy 90.382342 -317.822566)
			(xy 90.389745 -317.883559) (xy 90.389747 -317.944999) (xy 90.38235 -318.005992) (xy 90.367659 -318.06565)
			(xy 90.34589 -318.123104) (xy 90.31736 -318.177519) (xy 90.300302 -318.203072) (xy 90.294931 -318.211768)
			(xy 90.290861 -318.231778) (xy 90.294914 -318.251792) (xy 90.300302 -318.260476) (xy 90.317338 -318.286045)
			(xy 90.345873 -318.340456) (xy 90.367647 -318.397909) (xy 90.382342 -318.457566) (xy 90.389745 -318.518559)
			(xy 90.389747 -318.579999) (xy 90.38235 -318.640992) (xy 90.367659 -318.70065) (xy 90.34589 -318.758104)
			(xy 90.31736 -318.812519) (xy 90.300302 -318.838072) (xy 90.294931 -318.846768) (xy 90.290861 -318.866778)
			(xy 90.294914 -318.886792) (xy 90.300302 -318.895476) (xy 90.317338 -318.921045) (xy 90.345873 -318.975456)
			(xy 90.367647 -319.032909) (xy 90.382342 -319.092566) (xy 90.389745 -319.153559) (xy 90.389747 -319.214999)
			(xy 90.38235 -319.275992) (xy 90.367659 -319.33565) (xy 90.34589 -319.393104) (xy 90.31736 -319.447519)
			(xy 90.300302 -319.473072) (xy 90.294931 -319.481768) (xy 90.290861 -319.501778) (xy 90.294914 -319.521792)
			(xy 90.300302 -319.530476) (xy 90.317338 -319.556045) (xy 90.345873 -319.610456) (xy 90.367647 -319.667909)
			(xy 90.382342 -319.727566) (xy 90.389745 -319.788559) (xy 90.389746 -319.833752) (xy 92.318586 -319.833752)
			(xy 92.319036 -319.803031) (xy 92.32644 -319.742037) (xy 92.341136 -319.682378) (xy 92.36291 -319.624923)
			(xy 92.391443 -319.570508) (xy 92.408502 -319.544954) (xy 92.413936 -319.536291) (xy 92.417984 -319.51626)
			(xy 92.413905 -319.496235) (xy 92.408502 -319.48755) (xy 92.391399 -319.462025) (xy 92.362868 -319.407605)
			(xy 92.341099 -319.350145) (xy 92.326409 -319.290482) (xy 92.319013 -319.229483) (xy 92.319018 -319.168038)
			(xy 92.326423 -319.10704) (xy 92.341122 -319.047379) (xy 92.3629 -318.989923) (xy 92.39144 -318.935507)
			(xy 92.408502 -318.909954) (xy 92.413936 -318.901291) (xy 92.417984 -318.88126) (xy 92.413905 -318.861235)
			(xy 92.408502 -318.85255) (xy 92.391399 -318.827025) (xy 92.362868 -318.772605) (xy 92.341099 -318.715145)
			(xy 92.326409 -318.655482) (xy 92.319013 -318.594483) (xy 92.319018 -318.533038) (xy 92.326423 -318.47204)
			(xy 92.341122 -318.412379) (xy 92.3629 -318.354923) (xy 92.39144 -318.300507) (xy 92.408502 -318.274954)
			(xy 92.413936 -318.266291) (xy 92.417984 -318.24626) (xy 92.413905 -318.226235) (xy 92.408502 -318.21755)
			(xy 92.391399 -318.192025) (xy 92.362868 -318.137605) (xy 92.341099 -318.080145) (xy 92.326409 -318.020482)
			(xy 92.319013 -317.959483) (xy 92.319018 -317.898038) (xy 92.326423 -317.83704) (xy 92.341122 -317.777379)
			(xy 92.3629 -317.719923) (xy 92.39144 -317.665507) (xy 92.408502 -317.639954) (xy 92.413936 -317.631291)
			(xy 92.417984 -317.61126) (xy 92.413905 -317.591235) (xy 92.408502 -317.58255) (xy 92.391399 -317.557025)
			(xy 92.362868 -317.502605) (xy 92.341099 -317.445145) (xy 92.326409 -317.385482) (xy 92.319013 -317.324483)
			(xy 92.319018 -317.263038) (xy 92.326423 -317.20204) (xy 92.341122 -317.142379) (xy 92.3629 -317.084923)
			(xy 92.39144 -317.030507) (xy 92.408502 -317.004954) (xy 92.413936 -316.996291) (xy 92.417984 -316.97626)
			(xy 92.413905 -316.956235) (xy 92.408502 -316.94755) (xy 92.391427 -316.922007) (xy 92.362897 -316.867589)
			(xy 92.341129 -316.810131) (xy 92.326441 -316.75047) (xy 92.319046 -316.689474) (xy 92.318586 -316.658752)
			(xy 92.31901 -316.62802) (xy 92.326424 -316.567005) (xy 92.341138 -316.507329) (xy 92.362938 -316.449861)
			(xy 92.391505 -316.395439) (xy 92.426423 -316.344857) (xy 92.467183 -316.298853) (xy 92.51319 -316.258097)
			(xy 92.563775 -316.223183) (xy 92.618199 -316.19462) (xy 92.675669 -316.172826) (xy 92.735347 -316.158117)
			(xy 92.796362 -316.150708) (xy 92.827094 -316.150244) (xy 92.857815 -316.150711) (xy 92.918809 -316.15811)
			(xy 92.978468 -316.172802) (xy 93.035923 -316.194571) (xy 93.090338 -316.223102) (xy 93.115892 -316.24016)
			(xy 93.124577 -316.245553) (xy 93.144594 -316.249614) (xy 93.164611 -316.245553) (xy 93.173296 -316.24016)
			(xy 93.19885 -316.223102) (xy 93.253265 -316.194571) (xy 93.31072 -316.1728) (xy 93.370379 -316.158108)
			(xy 93.431373 -316.150708) (xy 93.492815 -316.150708) (xy 93.553809 -316.158108) (xy 93.613468 -316.1728)
			(xy 93.670923 -316.194571) (xy 93.725338 -316.223102) (xy 93.750892 -316.24016) (xy 93.759577 -316.245553)
			(xy 93.779594 -316.249614) (xy 93.799611 -316.245553) (xy 93.808296 -316.24016) (xy 93.833851 -316.223103)
			(xy 93.888265 -316.194571) (xy 93.94572 -316.1728) (xy 94.005379 -316.158107) (xy 94.066373 -316.150707)
			(xy 94.097094 -316.150244) (xy 94.127823 -316.150762) (xy 94.188833 -316.158168) (xy 94.248506 -316.172875)
			(xy 94.305971 -316.194666) (xy 94.36039 -316.223225) (xy 94.410971 -316.258135) (xy 94.456975 -316.298887)
			(xy 94.497731 -316.344887) (xy 94.532647 -316.395464) (xy 94.561211 -316.44988) (xy 94.583009 -316.507343)
			(xy 94.597722 -316.567014) (xy 94.605135 -316.628023) (xy 94.605602 -316.658752) (xy 94.605156 -316.689473)
			(xy 94.597751 -316.750468) (xy 94.583054 -316.810127) (xy 94.56128 -316.867582) (xy 94.532745 -316.921996)
			(xy 94.515686 -316.94755) (xy 94.510335 -316.956257) (xy 94.506261 -316.97626) (xy 94.510304 -316.996269)
			(xy 94.515686 -317.004954) (xy 94.532699 -317.030537) (xy 94.561231 -317.084947) (xy 94.583002 -317.142398)
			(xy 94.597697 -317.202052) (xy 94.6051 -317.263042) (xy 94.605105 -317.324479) (xy 94.597711 -317.38547)
			(xy 94.583026 -317.445127) (xy 94.561263 -317.502581) (xy 94.53274 -317.556996) (xy 94.515686 -317.58255)
			(xy 94.510335 -317.591257) (xy 94.506261 -317.61126) (xy 94.510304 -317.631269) (xy 94.515686 -317.639954)
			(xy 94.532699 -317.665537) (xy 94.561231 -317.719947) (xy 94.583002 -317.777398) (xy 94.597697 -317.837052)
			(xy 94.6051 -317.898042) (xy 94.605105 -317.959479) (xy 94.597711 -318.02047) (xy 94.583026 -318.080127)
			(xy 94.561263 -318.137581) (xy 94.53274 -318.191996) (xy 94.515686 -318.21755) (xy 94.510335 -318.226257)
			(xy 94.506261 -318.24626) (xy 94.510304 -318.266269) (xy 94.515686 -318.274954) (xy 94.532699 -318.300537)
			(xy 94.561231 -318.354947) (xy 94.583002 -318.412398) (xy 94.597697 -318.472052) (xy 94.6051 -318.533042)
			(xy 94.605105 -318.594479) (xy 94.597711 -318.65547) (xy 94.583026 -318.715127) (xy 94.561263 -318.772581)
			(xy 94.53274 -318.826996) (xy 94.515686 -318.85255) (xy 94.510335 -318.861257) (xy 94.506261 -318.88126)
			(xy 94.510304 -318.901269) (xy 94.515686 -318.909954) (xy 94.532699 -318.935537) (xy 94.561231 -318.989947)
			(xy 94.583002 -319.047398) (xy 94.597697 -319.107052) (xy 94.6051 -319.168042) (xy 94.605105 -319.229479)
			(xy 94.597711 -319.29047) (xy 94.583026 -319.350127) (xy 94.561263 -319.407581) (xy 94.53274 -319.461996)
			(xy 94.515686 -319.48755) (xy 94.510335 -319.496257) (xy 94.506261 -319.51626) (xy 94.510304 -319.536269)
			(xy 94.515686 -319.544954) (xy 94.532761 -319.570497) (xy 94.561292 -319.624914) (xy 94.583059 -319.682372)
			(xy 94.597748 -319.742034) (xy 94.605142 -319.80303) (xy 94.605602 -319.833752) (xy 94.605193 -319.862707)
			(xy 94.598597 -319.920241) (xy 94.585508 -319.976653) (xy 94.566094 -320.031212) (xy 94.540608 -320.083213)
			(xy 94.525338 -320.107818) (xy 94.52019 -320.116832) (xy 94.516799 -320.137288) (xy 94.52176 -320.157421)
			(xy 94.527624 -320.165984) (xy 94.547161 -320.192571) (xy 94.579898 -320.249856) (xy 94.604951 -320.310894)
			(xy 94.621901 -320.374659) (xy 94.630463 -320.440081) (xy 94.631002 -320.47307) (xy 94.631002 -320.473324)
			(xy 94.630542 -320.504045) (xy 94.62314 -320.565039) (xy 94.608447 -320.624698) (xy 94.586676 -320.682153)
			(xy 94.558144 -320.736568) (xy 94.541086 -320.762122) (xy 94.535673 -320.770796) (xy 94.531619 -320.79082)
			(xy 94.535689 -320.810841) (xy 94.541086 -320.819526) (xy 94.558165 -320.845066) (xy 94.586692 -320.899484)
			(xy 94.608459 -320.956942) (xy 94.623148 -321.016603) (xy 94.630545 -321.077599) (xy 94.630542 -321.139041)
			(xy 94.623141 -321.200036) (xy 94.608447 -321.259696) (xy 94.586676 -321.317152) (xy 94.558144 -321.371568)
			(xy 94.541086 -321.397122) (xy 94.535673 -321.405796) (xy 94.531619 -321.42582) (xy 94.535689 -321.445841)
			(xy 94.541086 -321.454526) (xy 94.558165 -321.480066) (xy 94.586692 -321.534484) (xy 94.608459 -321.591942)
			(xy 94.623148 -321.651603) (xy 94.630545 -321.712599) (xy 94.630542 -321.774041) (xy 94.623141 -321.835036)
			(xy 94.608447 -321.894696) (xy 94.586676 -321.952152) (xy 94.558144 -322.006568) (xy 94.541086 -322.032122)
			(xy 94.535673 -322.040796) (xy 94.531619 -322.06082) (xy 94.535689 -322.080841) (xy 94.541086 -322.089526)
			(xy 94.558149 -322.115077) (xy 94.586682 -322.169492) (xy 94.608452 -322.226948) (xy 94.623143 -322.286608)
			(xy 94.630541 -322.347603) (xy 94.631002 -322.378324) (xy 94.630515 -322.410195) (xy 94.622544 -322.473437)
			(xy 94.606742 -322.535189) (xy 94.583357 -322.594487) (xy 94.552753 -322.650402) (xy 94.534482 -322.67652)
			(xy 94.528667 -322.685432) (xy 94.524278 -322.706231) (xy 94.528693 -322.727025) (xy 94.534482 -322.735956)
			(xy 94.55276 -322.762073) (xy 94.583398 -322.817973) (xy 94.606797 -322.877269) (xy 94.622589 -322.939028)
			(xy 94.630526 -323.002279) (xy 94.631002 -323.034152) (xy 96.357186 -323.034152) (xy 96.357663 -323.002281)
			(xy 96.365637 -322.939039) (xy 96.381441 -322.877286) (xy 96.404829 -322.817989) (xy 96.435434 -322.762074)
			(xy 96.453706 -322.735956) (xy 96.459455 -322.727008) (xy 96.463868 -322.706231) (xy 96.459481 -322.685449)
			(xy 96.453706 -322.67652) (xy 96.435416 -322.650412) (xy 96.40478 -322.594509) (xy 96.381384 -322.53521)
			(xy 96.365594 -322.473449) (xy 96.357661 -322.410198) (xy 96.357186 -322.378324) (xy 96.357672 -322.347604)
			(xy 96.365068 -322.286611) (xy 96.379756 -322.226953) (xy 96.401521 -322.169497) (xy 96.430047 -322.115081)
			(xy 96.447102 -322.089526) (xy 96.452475 -322.08083) (xy 96.456543 -322.06082) (xy 96.45249 -322.040806)
			(xy 96.447102 -322.032122) (xy 96.430065 -322.006555) (xy 96.401529 -321.952143) (xy 96.379755 -321.89469)
			(xy 96.36506 -321.835033) (xy 96.357657 -321.77404) (xy 96.357655 -321.7126) (xy 96.365053 -321.651606)
			(xy 96.379744 -321.591948) (xy 96.401513 -321.534493) (xy 96.430044 -321.480079) (xy 96.447102 -321.454526)
			(xy 96.452475 -321.44583) (xy 96.456543 -321.42582) (xy 96.45249 -321.405806) (xy 96.447102 -321.397122)
			(xy 96.430065 -321.371555) (xy 96.401529 -321.317143) (xy 96.379755 -321.25969) (xy 96.36506 -321.200033)
			(xy 96.357657 -321.13904) (xy 96.357655 -321.0776) (xy 96.365053 -321.016606) (xy 96.379744 -320.956948)
			(xy 96.401513 -320.899493) (xy 96.430044 -320.845079) (xy 96.447102 -320.819526) (xy 96.452475 -320.81083)
			(xy 96.456543 -320.79082) (xy 96.45249 -320.770806) (xy 96.447102 -320.762122) (xy 96.430058 -320.736559)
			(xy 96.401523 -320.682147) (xy 96.379749 -320.624694) (xy 96.365053 -320.565037) (xy 96.35765 -320.504044)
			(xy 96.357186 -320.473324) (xy 96.357186 -320.47307) (xy 96.357652 -320.44213) (xy 96.365154 -320.380708)
			(xy 96.380055 -320.32065) (xy 96.402136 -320.262845) (xy 96.431069 -320.208147) (xy 96.448372 -320.182494)
			(xy 96.453831 -320.173731) (xy 96.457989 -320.153532) (xy 96.453856 -320.133327) (xy 96.448372 -320.124582)
			(xy 96.431068 -320.09893) (xy 96.402137 -320.04423) (xy 96.380056 -319.986425) (xy 96.365152 -319.926368)
			(xy 96.357644 -319.864946) (xy 96.357186 -319.834006) (xy 96.357186 -319.833752) (xy 96.357636 -319.803031)
			(xy 96.36504 -319.742037) (xy 96.379736 -319.682378) (xy 96.40151 -319.624923) (xy 96.430043 -319.570508)
			(xy 96.447102 -319.544954) (xy 96.452536 -319.536291) (xy 96.456584 -319.51626) (xy 96.452505 -319.496235)
			(xy 96.447102 -319.48755) (xy 96.429999 -319.462025) (xy 96.401468 -319.407605) (xy 96.379699 -319.350145)
			(xy 96.365009 -319.290482) (xy 96.357613 -319.229483) (xy 96.357618 -319.168038) (xy 96.365023 -319.10704)
			(xy 96.379722 -319.047379) (xy 96.4015 -318.989923) (xy 96.43004 -318.935507) (xy 96.447102 -318.909954)
			(xy 96.452536 -318.901291) (xy 96.456584 -318.88126) (xy 96.452505 -318.861235) (xy 96.447102 -318.85255)
			(xy 96.429999 -318.827025) (xy 96.401468 -318.772605) (xy 96.379699 -318.715145) (xy 96.365009 -318.655482)
			(xy 96.357613 -318.594483) (xy 96.357618 -318.533038) (xy 96.365023 -318.47204) (xy 96.379722 -318.412379)
			(xy 96.4015 -318.354923) (xy 96.43004 -318.300507) (xy 96.447102 -318.274954) (xy 96.452536 -318.266291)
			(xy 96.456584 -318.24626) (xy 96.452505 -318.226235) (xy 96.447102 -318.21755) (xy 96.429999 -318.192025)
			(xy 96.401468 -318.137605) (xy 96.379699 -318.080145) (xy 96.365009 -318.020482) (xy 96.357613 -317.959483)
			(xy 96.357618 -317.898038) (xy 96.365023 -317.83704) (xy 96.379722 -317.777379) (xy 96.4015 -317.719923)
			(xy 96.43004 -317.665507) (xy 96.447102 -317.639954) (xy 96.452536 -317.631291) (xy 96.456584 -317.61126)
			(xy 96.452505 -317.591235) (xy 96.447102 -317.58255) (xy 96.429999 -317.557025) (xy 96.401468 -317.502605)
			(xy 96.379699 -317.445145) (xy 96.365009 -317.385482) (xy 96.357613 -317.324483) (xy 96.357618 -317.263038)
			(xy 96.365023 -317.20204) (xy 96.379722 -317.142379) (xy 96.4015 -317.084923) (xy 96.43004 -317.030507)
			(xy 96.447102 -317.004954) (xy 96.452536 -316.996291) (xy 96.456584 -316.97626) (xy 96.452505 -316.956235)
			(xy 96.447102 -316.94755) (xy 96.430027 -316.922007) (xy 96.401497 -316.867589) (xy 96.379729 -316.810131)
			(xy 96.365041 -316.75047) (xy 96.357646 -316.689474) (xy 96.357186 -316.658752) (xy 96.35761 -316.62802)
			(xy 96.365024 -316.567005) (xy 96.379738 -316.507329) (xy 96.401538 -316.449861) (xy 96.430105 -316.395439)
			(xy 96.465023 -316.344857) (xy 96.505783 -316.298853) (xy 96.55179 -316.258097) (xy 96.602375 -316.223183)
			(xy 96.656799 -316.19462) (xy 96.714269 -316.172826) (xy 96.773947 -316.158117) (xy 96.834962 -316.150708)
			(xy 96.865694 -316.150244) (xy 96.896415 -316.150711) (xy 96.957409 -316.15811) (xy 97.017068 -316.172802)
			(xy 97.074523 -316.194571) (xy 97.128938 -316.223102) (xy 97.154492 -316.24016) (xy 97.163177 -316.245553)
			(xy 97.183194 -316.249614) (xy 97.203211 -316.245553) (xy 97.211896 -316.24016) (xy 97.23745 -316.223102)
			(xy 97.291865 -316.194571) (xy 97.34932 -316.1728) (xy 97.408979 -316.158108) (xy 97.469973 -316.150708)
			(xy 97.531415 -316.150708) (xy 97.592409 -316.158108) (xy 97.652068 -316.1728) (xy 97.709523 -316.194571)
			(xy 97.763938 -316.223102) (xy 97.789492 -316.24016) (xy 97.798177 -316.245553) (xy 97.818194 -316.249614)
			(xy 97.838211 -316.245553) (xy 97.846896 -316.24016) (xy 97.872451 -316.223103) (xy 97.926865 -316.194571)
			(xy 97.98432 -316.1728) (xy 98.043979 -316.158107) (xy 98.104973 -316.150707) (xy 98.135694 -316.150244)
			(xy 98.166423 -316.150762) (xy 98.227433 -316.158168) (xy 98.287106 -316.172875) (xy 98.344571 -316.194666)
			(xy 98.39899 -316.223225) (xy 98.449571 -316.258135) (xy 98.495575 -316.298887) (xy 98.536331 -316.344887)
			(xy 98.571247 -316.395464) (xy 98.599811 -316.44988) (xy 98.621609 -316.507343) (xy 98.636322 -316.567014)
			(xy 98.643735 -316.628023) (xy 98.644202 -316.658752) (xy 98.643756 -316.689473) (xy 98.636351 -316.750468)
			(xy 98.621654 -316.810127) (xy 98.59988 -316.867582) (xy 98.571345 -316.921996) (xy 98.554286 -316.94755)
			(xy 98.548935 -316.956257) (xy 98.544861 -316.97626) (xy 98.548904 -316.996269) (xy 98.554286 -317.004954)
			(xy 98.571299 -317.030537) (xy 98.599831 -317.084947) (xy 98.621602 -317.142398) (xy 98.636297 -317.202052)
			(xy 98.6437 -317.263042) (xy 98.643705 -317.324479) (xy 98.636311 -317.38547) (xy 98.621626 -317.445127)
			(xy 98.599863 -317.502581) (xy 98.57134 -317.556996) (xy 98.554286 -317.58255) (xy 98.548935 -317.591257)
			(xy 98.544861 -317.61126) (xy 98.548904 -317.631269) (xy 98.554286 -317.639954) (xy 98.571299 -317.665537)
			(xy 98.599831 -317.719947) (xy 98.621602 -317.777398) (xy 98.636297 -317.837052) (xy 98.6437 -317.898042)
			(xy 98.643705 -317.959479) (xy 98.636311 -318.02047) (xy 98.621626 -318.080127) (xy 98.599863 -318.137581)
			(xy 98.57134 -318.191996) (xy 98.554286 -318.21755) (xy 98.548935 -318.226257) (xy 98.544861 -318.24626)
			(xy 98.548904 -318.266269) (xy 98.554286 -318.274954) (xy 98.571299 -318.300537) (xy 98.599831 -318.354947)
			(xy 98.621602 -318.412398) (xy 98.636297 -318.472052) (xy 98.6437 -318.533042) (xy 98.643705 -318.594479)
			(xy 98.636311 -318.65547) (xy 98.621626 -318.715127) (xy 98.599863 -318.772581) (xy 98.57134 -318.826996)
			(xy 98.554286 -318.85255) (xy 98.548935 -318.861257) (xy 98.544861 -318.88126) (xy 98.548904 -318.901269)
			(xy 98.554286 -318.909954) (xy 98.571299 -318.935537) (xy 98.599831 -318.989947) (xy 98.621602 -319.047398)
			(xy 98.636297 -319.107052) (xy 98.6437 -319.168042) (xy 98.643705 -319.229479) (xy 98.636311 -319.29047)
			(xy 98.621626 -319.350127) (xy 98.599863 -319.407581) (xy 98.57134 -319.461996) (xy 98.554286 -319.48755)
			(xy 98.548935 -319.496257) (xy 98.544861 -319.51626) (xy 98.548904 -319.536269) (xy 98.554286 -319.544954)
			(xy 98.571361 -319.570497) (xy 98.599892 -319.624914) (xy 98.621659 -319.682372) (xy 98.636348 -319.742034)
			(xy 98.643742 -319.80303) (xy 98.644202 -319.833752) (xy 98.64369 -319.865885) (xy 98.635551 -319.929636)
			(xy 98.619448 -319.991853) (xy 98.595636 -320.051546) (xy 98.564495 -320.107765) (xy 98.545904 -320.13398)
			(xy 98.540003 -320.142965) (xy 98.53551 -320.163961) (xy 98.539971 -320.184964) (xy 98.545904 -320.193924)
			(xy 98.564488 -320.220144) (xy 98.59564 -320.276357) (xy 98.619458 -320.336049) (xy 98.635562 -320.398267)
			(xy 98.643694 -320.462018) (xy 98.644202 -320.494152) (xy 98.643756 -320.524873) (xy 98.636351 -320.585868)
			(xy 98.621654 -320.645527) (xy 98.59988 -320.702982) (xy 98.571345 -320.757396) (xy 98.554286 -320.78295)
			(xy 98.548935 -320.791657) (xy 98.544861 -320.81166) (xy 98.548904 -320.831669) (xy 98.554286 -320.840354)
			(xy 98.571299 -320.865937) (xy 98.599831 -320.920347) (xy 98.621602 -320.977798) (xy 98.636297 -321.037452)
			(xy 98.6437 -321.098442) (xy 98.643705 -321.159879) (xy 98.636311 -321.22087) (xy 98.621626 -321.280527)
			(xy 98.599863 -321.337981) (xy 98.57134 -321.392396) (xy 98.554286 -321.41795) (xy 98.548935 -321.426657)
			(xy 98.544861 -321.44666) (xy 98.548904 -321.466669) (xy 98.554286 -321.475354) (xy 98.571299 -321.500937)
			(xy 98.599831 -321.555347) (xy 98.621602 -321.612798) (xy 98.636297 -321.672452) (xy 98.6437 -321.733442)
			(xy 98.643705 -321.794879) (xy 98.636311 -321.85587) (xy 98.621626 -321.915527) (xy 98.599863 -321.972981)
			(xy 98.57134 -322.027396) (xy 98.554286 -322.05295) (xy 98.548935 -322.061657) (xy 98.544861 -322.08166)
			(xy 98.548904 -322.101669) (xy 98.554286 -322.110354) (xy 98.571299 -322.135937) (xy 98.599831 -322.190347)
			(xy 98.621602 -322.247798) (xy 98.636297 -322.307452) (xy 98.6437 -322.368442) (xy 98.643705 -322.429879)
			(xy 98.636311 -322.49087) (xy 98.621626 -322.550527) (xy 98.599863 -322.607981) (xy 98.57134 -322.662396)
			(xy 98.554286 -322.68795) (xy 98.548935 -322.696657) (xy 98.544861 -322.71666) (xy 98.548904 -322.736669)
			(xy 98.554286 -322.745354) (xy 98.571361 -322.770897) (xy 98.599892 -322.825314) (xy 98.621659 -322.882772)
			(xy 98.636348 -322.942434) (xy 98.643742 -323.00343) (xy 98.644202 -323.034152) (xy 98.643717 -323.064883)
			(xy 98.636314 -323.125898) (xy 98.62161 -323.185576) (xy 98.599819 -323.243046) (xy 98.571259 -323.29747)
			(xy 98.536347 -323.348055) (xy 98.495592 -323.394062) (xy 98.449588 -323.434821) (xy 98.399006 -323.469737)
			(xy 98.344585 -323.498302) (xy 98.287116 -323.520097) (xy 98.22744 -323.534806) (xy 98.166425 -323.542215)
			(xy 98.135694 -323.54266) (xy 98.104973 -323.542198) (xy 98.043979 -323.534798) (xy 97.98432 -323.520105)
			(xy 97.926865 -323.498334) (xy 97.87245 -323.469802) (xy 97.846896 -323.452744) (xy 97.838211 -323.447351)
			(xy 97.818194 -323.44329) (xy 97.798177 -323.447351) (xy 97.789492 -323.452744) (xy 97.763938 -323.469802)
			(xy 97.709523 -323.498333) (xy 97.652068 -323.520104) (xy 97.592409 -323.534796) (xy 97.531415 -323.542196)
			(xy 97.469973 -323.542196) (xy 97.408979 -323.534796) (xy 97.34932 -323.520104) (xy 97.291865 -323.498333)
			(xy 97.23745 -323.469802) (xy 97.211896 -323.452744) (xy 97.203211 -323.447351) (xy 97.183194 -323.44329)
			(xy 97.163177 -323.447351) (xy 97.154492 -323.452744) (xy 97.128941 -323.469806) (xy 97.074525 -323.498337)
			(xy 97.017069 -323.520107) (xy 96.95741 -323.534799) (xy 96.896415 -323.542198) (xy 96.865694 -323.54266)
			(xy 96.83496 -323.542268) (xy 96.77394 -323.534858) (xy 96.714258 -323.520146) (xy 96.656785 -323.498347)
			(xy 96.602359 -323.469779) (xy 96.551773 -323.434859) (xy 96.505766 -323.394096) (xy 96.465007 -323.348084)
			(xy 96.430093 -323.297495) (xy 96.401531 -323.243065) (xy 96.379738 -323.18559) (xy 96.365033 -323.125907)
			(xy 96.357629 -323.064886) (xy 96.357186 -323.034152) (xy 94.631002 -323.034152) (xy 94.630517 -323.064883)
			(xy 94.623114 -323.125898) (xy 94.60841 -323.185576) (xy 94.586619 -323.243046) (xy 94.558059 -323.29747)
			(xy 94.523147 -323.348055) (xy 94.482392 -323.394062) (xy 94.436388 -323.434821) (xy 94.385806 -323.469737)
			(xy 94.331385 -323.498302) (xy 94.273916 -323.520097) (xy 94.21424 -323.534806) (xy 94.153225 -323.542215)
			(xy 94.122494 -323.54266) (xy 94.091773 -323.542198) (xy 94.030779 -323.534798) (xy 93.97112 -323.520105)
			(xy 93.913665 -323.498334) (xy 93.85925 -323.469802) (xy 93.833696 -323.452744) (xy 93.825011 -323.447351)
			(xy 93.804994 -323.44329) (xy 93.784977 -323.447351) (xy 93.776292 -323.452744) (xy 93.750738 -323.469802)
			(xy 93.696323 -323.498333) (xy 93.638868 -323.520104) (xy 93.579209 -323.534796) (xy 93.518215 -323.542196)
			(xy 93.456773 -323.542196) (xy 93.395779 -323.534796) (xy 93.33612 -323.520104) (xy 93.278665 -323.498333)
			(xy 93.22425 -323.469802) (xy 93.198696 -323.452744) (xy 93.190011 -323.447351) (xy 93.169994 -323.44329)
			(xy 93.149977 -323.447351) (xy 93.141292 -323.452744) (xy 93.115741 -323.469806) (xy 93.061325 -323.498337)
			(xy 93.003869 -323.520107) (xy 92.94421 -323.534799) (xy 92.883215 -323.542198) (xy 92.852494 -323.54266)
			(xy 92.82176 -323.542268) (xy 92.76074 -323.534858) (xy 92.701058 -323.520146) (xy 92.643585 -323.498347)
			(xy 92.589159 -323.469779) (xy 92.538573 -323.434859) (xy 92.492566 -323.394096) (xy 92.451807 -323.348084)
			(xy 92.416893 -323.297495) (xy 92.388331 -323.243065) (xy 92.366538 -323.18559) (xy 92.351833 -323.125907)
			(xy 92.344429 -323.064886) (xy 92.343986 -323.034152) (xy 92.344436 -323.003431) (xy 92.35184 -322.942437)
			(xy 92.366536 -322.882778) (xy 92.38831 -322.825323) (xy 92.416843 -322.770908) (xy 92.433902 -322.745354)
			(xy 92.439336 -322.736691) (xy 92.443384 -322.71666) (xy 92.439305 -322.696635) (xy 92.433902 -322.68795)
			(xy 92.416799 -322.662425) (xy 92.388268 -322.608005) (xy 92.366499 -322.550545) (xy 92.351809 -322.490882)
			(xy 92.344413 -322.429883) (xy 92.344418 -322.368438) (xy 92.351823 -322.30744) (xy 92.366522 -322.247779)
			(xy 92.3883 -322.190323) (xy 92.41684 -322.135907) (xy 92.433902 -322.110354) (xy 92.439336 -322.101691)
			(xy 92.443384 -322.08166) (xy 92.439305 -322.061635) (xy 92.433902 -322.05295) (xy 92.416799 -322.027425)
			(xy 92.388268 -321.973005) (xy 92.366499 -321.915545) (xy 92.351809 -321.855882) (xy 92.344413 -321.794883)
			(xy 92.344418 -321.733438) (xy 92.351823 -321.67244) (xy 92.366522 -321.612779) (xy 92.3883 -321.555323)
			(xy 92.41684 -321.500907) (xy 92.433902 -321.475354) (xy 92.439336 -321.466691) (xy 92.443384 -321.44666)
			(xy 92.439305 -321.426635) (xy 92.433902 -321.41795) (xy 92.416799 -321.392425) (xy 92.388268 -321.338005)
			(xy 92.366499 -321.280545) (xy 92.351809 -321.220882) (xy 92.344413 -321.159883) (xy 92.344418 -321.098438)
			(xy 92.351823 -321.03744) (xy 92.366522 -320.977779) (xy 92.3883 -320.920323) (xy 92.41684 -320.865907)
			(xy 92.433902 -320.840354) (xy 92.439336 -320.831691) (xy 92.443384 -320.81166) (xy 92.439305 -320.791635)
			(xy 92.433902 -320.78295) (xy 92.416827 -320.757407) (xy 92.388297 -320.702989) (xy 92.366529 -320.645531)
			(xy 92.351841 -320.58587) (xy 92.344446 -320.524874) (xy 92.343986 -320.494152) (xy 92.343986 -320.493644)
			(xy 92.344446 -320.4635) (xy 92.351614 -320.40364) (xy 92.365807 -320.345047) (xy 92.386826 -320.288542)
			(xy 92.414376 -320.234917) (xy 92.430854 -320.209672) (xy 92.436483 -320.200499) (xy 92.44015 -320.179308)
			(xy 92.434858 -320.158463) (xy 92.428568 -320.149728) (xy 92.407844 -320.122637) (xy 92.373019 -320.063991)
			(xy 92.346335 -320.00122) (xy 92.328268 -319.935449) (xy 92.319143 -319.867855) (xy 92.318586 -319.833752)
			(xy 90.389746 -319.833752) (xy 90.389747 -319.849999) (xy 90.38235 -319.910992) (xy 90.367659 -319.97065)
			(xy 90.34589 -320.028104) (xy 90.31736 -320.082519) (xy 90.300302 -320.108072) (xy 90.294931 -320.116768)
			(xy 90.290861 -320.136778) (xy 90.294914 -320.156792) (xy 90.300302 -320.165476) (xy 90.317338 -320.191045)
			(xy 90.345873 -320.245456) (xy 90.367647 -320.302909) (xy 90.382342 -320.362566) (xy 90.389745 -320.423559)
			(xy 90.389747 -320.484999) (xy 90.38235 -320.545992) (xy 90.367659 -320.60565) (xy 90.34589 -320.663104)
			(xy 90.31736 -320.717519) (xy 90.300302 -320.743072) (xy 90.294931 -320.751768) (xy 90.290861 -320.771778)
			(xy 90.294914 -320.791792) (xy 90.300302 -320.800476) (xy 90.317338 -320.826045) (xy 90.345873 -320.880456)
			(xy 90.367647 -320.937909) (xy 90.382342 -320.997566) (xy 90.389745 -321.058559) (xy 90.389747 -321.119999)
			(xy 90.38235 -321.180992) (xy 90.367659 -321.24065) (xy 90.34589 -321.298104) (xy 90.31736 -321.352519)
			(xy 90.300302 -321.378072) (xy 90.294931 -321.386768) (xy 90.290861 -321.406778) (xy 90.294914 -321.426792)
			(xy 90.300302 -321.435476) (xy 90.317338 -321.461045) (xy 90.345873 -321.515456) (xy 90.367647 -321.572909)
			(xy 90.382342 -321.632566) (xy 90.389745 -321.693559) (xy 90.389747 -321.754999) (xy 90.38235 -321.815992)
			(xy 90.367659 -321.87565) (xy 90.34589 -321.933104) (xy 90.31736 -321.987519) (xy 90.300302 -322.013072)
			(xy 90.294931 -322.021768) (xy 90.290861 -322.041778) (xy 90.294914 -322.061792) (xy 90.300302 -322.070476)
			(xy 90.317345 -322.096039) (xy 90.345881 -322.150451) (xy 90.367655 -322.207904) (xy 90.382351 -322.267561)
			(xy 90.389754 -322.328554) (xy 90.390218 -322.359274) (xy 90.390218 -322.359528) (xy 90.3897 -322.391096)
			(xy 90.381846 -322.453742) (xy 90.3663 -322.514934) (xy 90.343301 -322.573732) (xy 90.313202 -322.629232)
			(xy 90.295222 -322.655184) (xy 90.289504 -322.664032) (xy 90.285208 -322.68464) (xy 90.289535 -322.70524)
			(xy 90.295222 -322.714112) (xy 90.313026 -322.740022) (xy 90.342838 -322.795372) (xy 90.365606 -322.853972)
			(xy 90.380981 -322.91493) (xy 90.388731 -322.977318) (xy 90.389202 -323.008752) (xy 90.388717 -323.039483)
			(xy 90.381314 -323.100498) (xy 90.36661 -323.160176) (xy 90.344819 -323.217646) (xy 90.316259 -323.27207)
			(xy 90.281347 -323.322655) (xy 90.240592 -323.368662) (xy 90.194588 -323.409421) (xy 90.144006 -323.444337)
			(xy 90.089585 -323.472902) (xy 90.032116 -323.494697) (xy 89.97244 -323.509406) (xy 89.911425 -323.516815)
			(xy 89.880694 -323.51726) (xy 89.849973 -323.516798) (xy 89.788979 -323.509398) (xy 89.72932 -323.494705)
			(xy 89.671865 -323.472934) (xy 89.61745 -323.444402) (xy 89.591896 -323.427344) (xy 89.583211 -323.421951)
			(xy 89.563194 -323.41789) (xy 89.543177 -323.421951) (xy 89.534492 -323.427344) (xy 89.508938 -323.444402)
			(xy 89.454523 -323.472933) (xy 89.397068 -323.494704) (xy 89.337409 -323.509396) (xy 89.276415 -323.516796)
			(xy 89.214973 -323.516796) (xy 89.153979 -323.509396) (xy 89.09432 -323.494704) (xy 89.036865 -323.472933)
			(xy 88.98245 -323.444402) (xy 88.956896 -323.427344) (xy 88.948211 -323.421951) (xy 88.928194 -323.41789)
			(xy 88.908177 -323.421951) (xy 88.899492 -323.427344) (xy 88.873941 -323.444406) (xy 88.819525 -323.472937)
			(xy 88.762069 -323.494707) (xy 88.70241 -323.509399) (xy 88.641415 -323.516798) (xy 88.610694 -323.51726)
			(xy 88.57996 -323.516868) (xy 88.51894 -323.509458) (xy 88.459258 -323.494746) (xy 88.401785 -323.472947)
			(xy 88.347359 -323.444379) (xy 88.296773 -323.409459) (xy 88.250766 -323.368696) (xy 88.210007 -323.322684)
			(xy 88.175093 -323.272095) (xy 88.146531 -323.217665) (xy 88.124738 -323.16019) (xy 88.110033 -323.100507)
			(xy 88.102629 -323.039486) (xy 88.102186 -323.008752) (xy 86.350602 -323.008752) (xy 86.350117 -323.039483)
			(xy 86.342714 -323.100498) (xy 86.32801 -323.160176) (xy 86.306219 -323.217646) (xy 86.277659 -323.27207)
			(xy 86.242747 -323.322655) (xy 86.201992 -323.368662) (xy 86.155988 -323.409421) (xy 86.105406 -323.444337)
			(xy 86.050985 -323.472902) (xy 85.993516 -323.494697) (xy 85.93384 -323.509406) (xy 85.872825 -323.516815)
			(xy 85.842094 -323.51726) (xy 85.811373 -323.516798) (xy 85.750379 -323.509398) (xy 85.69072 -323.494705)
			(xy 85.633265 -323.472934) (xy 85.57885 -323.444402) (xy 85.553296 -323.427344) (xy 85.544611 -323.421951)
			(xy 85.524594 -323.41789) (xy 85.504577 -323.421951) (xy 85.495892 -323.427344) (xy 85.470338 -323.444402)
			(xy 85.415923 -323.472933) (xy 85.358468 -323.494704) (xy 85.298809 -323.509396) (xy 85.237815 -323.516796)
			(xy 85.176373 -323.516796) (xy 85.115379 -323.509396) (xy 85.05572 -323.494704) (xy 84.998265 -323.472933)
			(xy 84.94385 -323.444402) (xy 84.918296 -323.427344) (xy 84.909611 -323.421951) (xy 84.889594 -323.41789)
			(xy 84.869577 -323.421951) (xy 84.860892 -323.427344) (xy 84.835341 -323.444406) (xy 84.780925 -323.472937)
			(xy 84.723469 -323.494707) (xy 84.66381 -323.509399) (xy 84.602815 -323.516798) (xy 84.572094 -323.51726)
			(xy 84.54136 -323.516868) (xy 84.48034 -323.509458) (xy 84.420658 -323.494746) (xy 84.363185 -323.472947)
			(xy 84.308759 -323.444379) (xy 84.258173 -323.409459) (xy 84.212166 -323.368696) (xy 84.171407 -323.322684)
			(xy 84.136493 -323.272095) (xy 84.107931 -323.217665) (xy 84.086138 -323.16019) (xy 84.071433 -323.100507)
			(xy 84.064029 -323.039486) (xy 84.063586 -323.008752) (xy 82.010758 -323.008752) (xy 82.010199 -323.03948)
			(xy 82.002797 -323.100489) (xy 81.988095 -323.16016) (xy 81.966308 -323.217625) (xy 81.937753 -323.272044)
			(xy 81.902847 -323.322625) (xy 81.862099 -323.368629) (xy 81.816102 -323.409387) (xy 81.765528 -323.444303)
			(xy 81.711114 -323.472868) (xy 81.653654 -323.494666) (xy 81.593985 -323.509379) (xy 81.532978 -323.516793)
			(xy 81.50225 -323.51726) (xy 81.471529 -323.516821) (xy 81.410533 -323.509415) (xy 81.350874 -323.494717)
			(xy 81.293419 -323.472941) (xy 81.239005 -323.444404) (xy 81.213452 -323.427344) (xy 81.204767 -323.421951)
			(xy 81.18475 -323.41789) (xy 81.164733 -323.421951) (xy 81.156048 -323.427344) (xy 81.130494 -323.444402)
			(xy 81.076079 -323.472933) (xy 81.018624 -323.494704) (xy 80.958965 -323.509396) (xy 80.897971 -323.516796)
			(xy 80.836529 -323.516796) (xy 80.775535 -323.509396) (xy 80.715876 -323.494704) (xy 80.658421 -323.472933)
			(xy 80.604006 -323.444402) (xy 80.578452 -323.427344) (xy 80.569767 -323.421951) (xy 80.54975 -323.41789)
			(xy 80.529733 -323.421951) (xy 80.521048 -323.427344) (xy 80.495509 -323.444425) (xy 80.44109 -323.472953)
			(xy 80.383631 -323.494719) (xy 80.323969 -323.509406) (xy 80.262972 -323.5168) (xy 80.23225 -323.51726)
			(xy 80.201516 -323.516891) (xy 80.140497 -323.509476) (xy 80.080817 -323.49476) (xy 80.023345 -323.472958)
			(xy 79.968921 -323.444387) (xy 79.918337 -323.409464) (xy 79.872332 -323.368699) (xy 79.831575 -323.322686)
			(xy 79.796662 -323.272095) (xy 79.768102 -323.217665) (xy 79.746311 -323.16019) (xy 79.731606 -323.100506)
			(xy 79.724203 -323.039486) (xy 79.723742 -323.008752) (xy 77.997558 -323.008752) (xy 77.996999 -323.03948)
			(xy 77.989597 -323.100489) (xy 77.974895 -323.16016) (xy 77.953108 -323.217625) (xy 77.924553 -323.272044)
			(xy 77.889647 -323.322625) (xy 77.848899 -323.368629) (xy 77.802902 -323.409387) (xy 77.752328 -323.444303)
			(xy 77.697914 -323.472868) (xy 77.640454 -323.494666) (xy 77.580785 -323.509379) (xy 77.519778 -323.516793)
			(xy 77.48905 -323.51726) (xy 77.458329 -323.516821) (xy 77.397333 -323.509415) (xy 77.337674 -323.494717)
			(xy 77.280219 -323.472941) (xy 77.225805 -323.444404) (xy 77.200252 -323.427344) (xy 77.191567 -323.421951)
			(xy 77.17155 -323.41789) (xy 77.151533 -323.421951) (xy 77.142848 -323.427344) (xy 77.117294 -323.444402)
			(xy 77.062879 -323.472933) (xy 77.005424 -323.494704) (xy 76.945765 -323.509396) (xy 76.884771 -323.516796)
			(xy 76.823329 -323.516796) (xy 76.762335 -323.509396) (xy 76.702676 -323.494704) (xy 76.645221 -323.472933)
			(xy 76.590806 -323.444402) (xy 76.565252 -323.427344) (xy 76.556567 -323.421951) (xy 76.53655 -323.41789)
			(xy 76.516533 -323.421951) (xy 76.507848 -323.427344) (xy 76.482309 -323.444425) (xy 76.42789 -323.472953)
			(xy 76.370431 -323.494719) (xy 76.310769 -323.509406) (xy 76.249772 -323.5168) (xy 76.21905 -323.51726)
			(xy 76.188316 -323.516891) (xy 76.127297 -323.509476) (xy 76.067617 -323.49476) (xy 76.010145 -323.472958)
			(xy 75.955721 -323.444387) (xy 75.905137 -323.409464) (xy 75.859132 -323.368699) (xy 75.818375 -323.322686)
			(xy 75.783462 -323.272095) (xy 75.754902 -323.217665) (xy 75.733111 -323.16019) (xy 75.718406 -323.100506)
			(xy 75.711003 -323.039486) (xy 75.710542 -323.008752) (xy 75.711034 -322.977538) (xy 75.718673 -322.915578)
			(xy 75.73383 -322.855018) (xy 75.756279 -322.796765) (xy 75.785681 -322.741693) (xy 75.803252 -322.71589)
			(xy 75.808947 -322.706971) (xy 75.813191 -322.68626) (xy 75.808754 -322.665589) (xy 75.802998 -322.656708)
			(xy 75.784835 -322.630658) (xy 75.75441 -322.574914) (xy 75.731156 -322.515818) (xy 75.715436 -322.454288)
			(xy 75.707494 -322.391281) (xy 75.706986 -322.359528) (xy 73.676695 -322.359528) (xy 73.677018 -322.380864)
			(xy 73.676444 -322.414107) (xy 73.667765 -322.480025) (xy 73.650564 -322.544248) (xy 73.625134 -322.605679)
			(xy 73.591911 -322.663269) (xy 73.572116 -322.689982) (xy 73.566176 -322.698685) (xy 73.561244 -322.719146)
			(xy 73.564929 -322.739868) (xy 73.570338 -322.74891) (xy 73.58647 -322.774004) (xy 73.613433 -322.827222)
			(xy 73.633976 -322.883231) (xy 73.647817 -322.941261) (xy 73.654765 -323.000513) (xy 73.655174 -323.030342)
			(xy 73.654784 -323.061075) (xy 73.64737 -323.122093) (xy 73.632655 -323.181772) (xy 73.610854 -323.239243)
			(xy 73.582285 -323.293666) (xy 73.547364 -323.34425) (xy 73.506601 -323.390255) (xy 73.46059 -323.431011)
			(xy 73.410001 -323.465925) (xy 73.355573 -323.494486) (xy 73.2981 -323.516278) (xy 73.238418 -323.530984)
			(xy 73.177399 -323.538388) (xy 73.146666 -323.53885) (xy 73.115945 -323.538404) (xy 73.05495 -323.531)
			(xy 72.995291 -323.516304) (xy 72.937836 -323.49453) (xy 72.883421 -323.465994) (xy 72.857868 -323.448934)
			(xy 72.849183 -323.443541) (xy 72.829166 -323.43948) (xy 72.809149 -323.443541) (xy 72.800464 -323.448934)
			(xy 72.77491 -323.465992) (xy 72.720495 -323.494523) (xy 72.66304 -323.516294) (xy 72.603381 -323.530986)
			(xy 72.542387 -323.538386) (xy 72.480945 -323.538386) (xy 72.419951 -323.530986) (xy 72.360292 -323.516294)
			(xy 72.302837 -323.494523) (xy 72.248422 -323.465992) (xy 72.222868 -323.448934) (xy 72.214183 -323.443541)
			(xy 72.194166 -323.43948) (xy 72.174149 -323.443541) (xy 72.165464 -323.448934) (xy 72.13992 -323.466007)
			(xy 72.085502 -323.494537) (xy 72.028045 -323.516304) (xy 71.968383 -323.530993) (xy 71.907387 -323.538389)
			(xy 71.876666 -323.53885) (xy 71.845936 -323.538376) (xy 71.784924 -323.530965) (xy 71.72525 -323.516254)
			(xy 71.667785 -323.494458) (xy 71.613365 -323.465895) (xy 71.562784 -323.430981) (xy 71.516781 -323.390225)
			(xy 71.476024 -323.344222) (xy 71.441109 -323.293642) (xy 71.412545 -323.239223) (xy 71.390749 -323.181757)
			(xy 71.376037 -323.122084) (xy 71.368624 -323.061072) (xy 71.368158 -323.030342) (xy 69.641974 -323.030342)
			(xy 69.641584 -323.061075) (xy 69.63417 -323.122093) (xy 69.619455 -323.181772) (xy 69.597654 -323.239243)
			(xy 69.569085 -323.293666) (xy 69.534164 -323.34425) (xy 69.493401 -323.390255) (xy 69.44739 -323.431011)
			(xy 69.396801 -323.465925) (xy 69.342373 -323.494486) (xy 69.2849 -323.516278) (xy 69.225218 -323.530984)
			(xy 69.164199 -323.538388) (xy 69.133466 -323.53885) (xy 69.102745 -323.538404) (xy 69.04175 -323.531)
			(xy 68.982091 -323.516304) (xy 68.924636 -323.49453) (xy 68.870221 -323.465994) (xy 68.844668 -323.448934)
			(xy 68.835983 -323.443541) (xy 68.815966 -323.43948) (xy 68.795949 -323.443541) (xy 68.787264 -323.448934)
			(xy 68.76171 -323.465992) (xy 68.707295 -323.494523) (xy 68.64984 -323.516294) (xy 68.590181 -323.530986)
			(xy 68.529187 -323.538386) (xy 68.467745 -323.538386) (xy 68.406751 -323.530986) (xy 68.347092 -323.516294)
			(xy 68.289637 -323.494523) (xy 68.235222 -323.465992) (xy 68.209668 -323.448934) (xy 68.200983 -323.443541)
			(xy 68.180966 -323.43948) (xy 68.160949 -323.443541) (xy 68.152264 -323.448934) (xy 68.12672 -323.466007)
			(xy 68.072302 -323.494537) (xy 68.014845 -323.516304) (xy 67.955183 -323.530993) (xy 67.894187 -323.538389)
			(xy 67.863466 -323.53885) (xy 67.832736 -323.538376) (xy 67.771724 -323.530965) (xy 67.71205 -323.516254)
			(xy 67.654585 -323.494458) (xy 67.600165 -323.465895) (xy 67.549584 -323.430981) (xy 67.503581 -323.390225)
			(xy 67.462824 -323.344222) (xy 67.427909 -323.293642) (xy 67.399345 -323.239223) (xy 67.377549 -323.181757)
			(xy 67.362837 -323.122084) (xy 67.355424 -323.061072) (xy 67.354958 -323.030342) (xy 22.84603 -323.030342)
			(xy 22.84603 -324.647517) (xy 23.822654 -324.647517) (xy 23.822654 -324.583595) (xy 23.830665 -324.520177)
			(xy 23.846562 -324.458263) (xy 23.870094 -324.39883) (xy 23.900888 -324.342815) (xy 23.938461 -324.2911)
			(xy 23.982218 -324.244503) (xy 24.031471 -324.203758) (xy 24.085442 -324.169507) (xy 24.143281 -324.14229)
			(xy 24.204074 -324.122537) (xy 24.266864 -324.110559) (xy 24.33066 -324.106546) (xy 24.394456 -324.110559)
			(xy 24.457246 -324.122537) (xy 24.518039 -324.14229) (xy 24.575878 -324.169507) (xy 24.629849 -324.203758)
			(xy 24.679102 -324.244503) (xy 24.722859 -324.2911) (xy 24.760432 -324.342815) (xy 24.791226 -324.39883)
			(xy 24.814758 -324.458263) (xy 24.830655 -324.520177) (xy 24.832564 -324.53529) (xy 25.334225 -324.53529)
			(xy 25.338216 -324.446403) (xy 25.35016 -324.358232) (xy 25.369959 -324.271486) (xy 25.397454 -324.186865)
			(xy 25.432424 -324.105048) (xy 25.474587 -324.026696) (xy 25.523604 -323.952439) (xy 25.57908 -323.882874)
			(xy 25.640568 -323.818563) (xy 25.707574 -323.760022) (xy 25.779558 -323.707723) (xy 25.855939 -323.662087)
			(xy 25.936104 -323.623481) (xy 26.019407 -323.592217) (xy 26.105177 -323.568546) (xy 26.192724 -323.552659)
			(xy 26.281342 -323.544683) (xy 26.32583 -323.544184) (xy 28.07843 -323.544184) (xy 28.122918 -323.544679)
			(xy 28.211537 -323.552655) (xy 28.299084 -323.568542) (xy 28.384854 -323.592213) (xy 28.468157 -323.623478)
			(xy 28.548323 -323.662083) (xy 28.624705 -323.707719) (xy 28.696688 -323.760018) (xy 28.763694 -323.81856)
			(xy 28.825183 -323.882872) (xy 28.880659 -323.952437) (xy 28.929676 -324.026694) (xy 28.971839 -324.105047)
			(xy 29.006809 -324.186863) (xy 29.034305 -324.271485) (xy 29.054104 -324.358231) (xy 29.066048 -324.446403)
			(xy 29.07004 -324.53529) (xy 32.878025 -324.53529) (xy 32.882016 -324.446403) (xy 32.89396 -324.358232)
			(xy 32.913759 -324.271486) (xy 32.941254 -324.186865) (xy 32.976224 -324.105048) (xy 33.018387 -324.026696)
			(xy 33.067404 -323.952439) (xy 33.12288 -323.882874) (xy 33.184368 -323.818563) (xy 33.251374 -323.760022)
			(xy 33.323358 -323.707723) (xy 33.399739 -323.662087) (xy 33.479904 -323.623481) (xy 33.563207 -323.592217)
			(xy 33.648977 -323.568546) (xy 33.736524 -323.552659) (xy 33.825142 -323.544683) (xy 33.86963 -323.544184)
			(xy 35.62223 -323.544184) (xy 35.666718 -323.544679) (xy 35.755337 -323.552655) (xy 35.842884 -323.568542)
			(xy 35.928654 -323.592213) (xy 36.011957 -323.623478) (xy 36.092123 -323.662083) (xy 36.168505 -323.707719)
			(xy 36.240488 -323.760018) (xy 36.307494 -323.81856) (xy 36.368983 -323.882872) (xy 36.424459 -323.952437)
			(xy 36.473476 -324.026694) (xy 36.515639 -324.105047) (xy 36.550609 -324.186863) (xy 36.578105 -324.271485)
			(xy 36.597904 -324.358231) (xy 36.609848 -324.446403) (xy 36.61384 -324.53529) (xy 36.61384 -324.5353)
			(xy 40.422084 -324.5353) (xy 40.426076 -324.446413) (xy 40.43802 -324.358242) (xy 40.457819 -324.271496)
			(xy 40.485314 -324.186875) (xy 40.520283 -324.105058) (xy 40.562446 -324.026706) (xy 40.611462 -323.952448)
			(xy 40.666938 -323.882883) (xy 40.728426 -323.818571) (xy 40.795431 -323.760029) (xy 40.867414 -323.70773)
			(xy 40.943795 -323.662093) (xy 41.023959 -323.623487) (xy 41.107262 -323.592222) (xy 41.193031 -323.568549)
			(xy 41.280578 -323.552661) (xy 41.369196 -323.544684) (xy 41.413684 -323.544184) (xy 43.166284 -323.544184)
			(xy 43.210773 -323.544684) (xy 43.299393 -323.552658) (xy 43.386941 -323.568545) (xy 43.472713 -323.592215)
			(xy 43.556018 -323.623479) (xy 43.636185 -323.662084) (xy 43.712569 -323.70772) (xy 43.784554 -323.760019)
			(xy 43.851561 -323.818561) (xy 43.913051 -323.882873) (xy 43.968529 -323.952439) (xy 44.017547 -324.026697)
			(xy 44.059711 -324.105051) (xy 44.094682 -324.186868) (xy 44.122178 -324.271491) (xy 44.141978 -324.358239)
			(xy 44.153922 -324.446411) (xy 44.157914 -324.53529) (xy 47.966134 -324.53529) (xy 47.970126 -324.446403)
			(xy 47.98207 -324.358232) (xy 48.001869 -324.271487) (xy 48.029364 -324.186865) (xy 48.064334 -324.105049)
			(xy 48.106497 -324.026697) (xy 48.155514 -323.95244) (xy 48.21099 -323.882875) (xy 48.272478 -323.818563)
			(xy 48.339483 -323.760022) (xy 48.411466 -323.707723) (xy 48.487848 -323.662087) (xy 48.568013 -323.623482)
			(xy 48.651316 -323.592218) (xy 48.737085 -323.568547) (xy 48.824632 -323.552659) (xy 48.91325 -323.544683)
			(xy 48.957738 -323.544184) (xy 50.710338 -323.544184) (xy 50.754827 -323.544664) (xy 50.843447 -323.55264)
			(xy 50.930995 -323.568528) (xy 51.016767 -323.592199) (xy 51.100072 -323.623464) (xy 51.180238 -323.66207)
			(xy 51.256622 -323.707706) (xy 51.328607 -323.760006) (xy 51.395614 -323.818549) (xy 51.457103 -323.882861)
			(xy 51.51258 -323.952427) (xy 51.561598 -324.026686) (xy 51.603762 -324.10504) (xy 51.638733 -324.186858)
			(xy 51.666229 -324.271481) (xy 51.686028 -324.358228) (xy 51.697972 -324.446401) (xy 51.701964 -324.53529)
			(xy 51.701964 -324.5353) (xy 55.510184 -324.5353) (xy 55.514176 -324.446413) (xy 55.52612 -324.358241)
			(xy 55.545919 -324.271495) (xy 55.573414 -324.186873) (xy 55.608384 -324.105056) (xy 55.650547 -324.026703)
			(xy 55.699564 -323.952446) (xy 55.75504 -323.882881) (xy 55.816529 -323.818568) (xy 55.883534 -323.760027)
			(xy 55.955518 -323.707727) (xy 56.0319 -323.66209) (xy 56.112065 -323.623484) (xy 56.195368 -323.59222)
			(xy 56.281138 -323.568548) (xy 56.368685 -323.55266) (xy 56.457304 -323.544683) (xy 56.501792 -323.544184)
			(xy 58.254392 -323.544184) (xy 58.298881 -323.544684) (xy 58.3875 -323.552659) (xy 58.475048 -323.568546)
			(xy 58.560819 -323.592217) (xy 58.644124 -323.623481) (xy 58.72429 -323.662087) (xy 58.800673 -323.707723)
			(xy 58.872658 -323.760022) (xy 58.939664 -323.818564) (xy 59.001154 -323.882876) (xy 59.056631 -323.952441)
			(xy 59.105648 -324.0267) (xy 59.147812 -324.105053) (xy 59.182783 -324.18687) (xy 59.210279 -324.271493)
			(xy 59.230078 -324.35824) (xy 59.242022 -324.446412) (xy 59.246014 -324.5353) (xy 59.242022 -324.624188)
			(xy 59.230078 -324.71236) (xy 59.210279 -324.799107) (xy 59.182783 -324.88373) (xy 59.147812 -324.965547)
			(xy 59.105648 -325.0439) (xy 59.056631 -325.118159) (xy 59.001154 -325.187724) (xy 58.939664 -325.252036)
			(xy 58.872658 -325.310578) (xy 58.800673 -325.362877) (xy 58.72429 -325.408513) (xy 58.644124 -325.447119)
			(xy 58.560819 -325.478383) (xy 58.475048 -325.502054) (xy 58.3875 -325.517941) (xy 58.298881 -325.525916)
			(xy 58.254392 -325.5264) (xy 56.501792 -325.5264) (xy 56.457304 -325.525917) (xy 56.368685 -325.51794)
			(xy 56.281138 -325.502052) (xy 56.195368 -325.47838) (xy 56.112065 -325.447116) (xy 56.0319 -325.40851)
			(xy 55.955518 -325.362873) (xy 55.883534 -325.310573) (xy 55.816529 -325.252032) (xy 55.75504 -325.187719)
			(xy 55.699564 -325.118154) (xy 55.650547 -325.043897) (xy 55.608384 -324.965544) (xy 55.573414 -324.883727)
			(xy 55.545919 -324.799105) (xy 55.52612 -324.712359) (xy 55.514176 -324.624187) (xy 55.510184 -324.5353)
			(xy 51.701964 -324.5353) (xy 51.697972 -324.624179) (xy 51.686028 -324.712352) (xy 51.666229 -324.799099)
			(xy 51.638733 -324.883722) (xy 51.603762 -324.96554) (xy 51.561598 -325.043894) (xy 51.51258 -325.118153)
			(xy 51.457103 -325.187719) (xy 51.395614 -325.252031) (xy 51.328607 -325.310574) (xy 51.256622 -325.362874)
			(xy 51.180238 -325.40851) (xy 51.100072 -325.447116) (xy 51.016767 -325.478381) (xy 50.930995 -325.502052)
			(xy 50.843447 -325.51794) (xy 50.754827 -325.525916) (xy 50.710338 -325.5264) (xy 48.957738 -325.5264)
			(xy 48.91325 -325.525897) (xy 48.824632 -325.517921) (xy 48.737085 -325.502033) (xy 48.651316 -325.478362)
			(xy 48.568013 -325.447098) (xy 48.487848 -325.408493) (xy 48.411466 -325.362857) (xy 48.339483 -325.310558)
			(xy 48.272478 -325.252017) (xy 48.21099 -325.187705) (xy 48.155514 -325.11814) (xy 48.106497 -325.043883)
			(xy 48.064334 -324.965531) (xy 48.029364 -324.883715) (xy 48.001869 -324.799093) (xy 47.98207 -324.712348)
			(xy 47.970126 -324.624177) (xy 47.966134 -324.53529) (xy 44.157914 -324.53529) (xy 44.157914 -324.5353)
			(xy 44.153922 -324.624189) (xy 44.141978 -324.712361) (xy 44.122178 -324.799109) (xy 44.094682 -324.883732)
			(xy 44.059711 -324.965549) (xy 44.017547 -325.043903) (xy 43.968529 -325.118161) (xy 43.913051 -325.187727)
			(xy 43.851561 -325.252039) (xy 43.784554 -325.310581) (xy 43.712569 -325.36288) (xy 43.636185 -325.408516)
			(xy 43.556018 -325.447121) (xy 43.472713 -325.478385) (xy 43.386941 -325.502055) (xy 43.299393 -325.517942)
			(xy 43.210773 -325.525916) (xy 43.166284 -325.5264) (xy 41.413684 -325.5264) (xy 41.369196 -325.525916)
			(xy 41.280578 -325.517939) (xy 41.193031 -325.502051) (xy 41.107262 -325.478378) (xy 41.023959 -325.447113)
			(xy 40.943795 -325.408507) (xy 40.867414 -325.36287) (xy 40.795431 -325.310571) (xy 40.728426 -325.252029)
			(xy 40.666938 -325.187717) (xy 40.611462 -325.118152) (xy 40.562446 -325.043894) (xy 40.520283 -324.965542)
			(xy 40.485314 -324.883725) (xy 40.457819 -324.799104) (xy 40.43802 -324.712358) (xy 40.426076 -324.624187)
			(xy 40.422084 -324.5353) (xy 36.61384 -324.5353) (xy 36.609848 -324.624177) (xy 36.597904 -324.712349)
			(xy 36.578105 -324.799095) (xy 36.550609 -324.883717) (xy 36.515639 -324.965533) (xy 36.473476 -325.043886)
			(xy 36.424459 -325.118143) (xy 36.368983 -325.187708) (xy 36.307494 -325.25202) (xy 36.240488 -325.310562)
			(xy 36.168505 -325.362861) (xy 36.092123 -325.408497) (xy 36.011957 -325.447102) (xy 35.928654 -325.478367)
			(xy 35.842884 -325.502038) (xy 35.755337 -325.517925) (xy 35.666718 -325.525901) (xy 35.62223 -325.5264)
			(xy 33.86963 -325.5264) (xy 33.825142 -325.525897) (xy 33.736524 -325.517921) (xy 33.648977 -325.502034)
			(xy 33.563207 -325.478363) (xy 33.479904 -325.447099) (xy 33.399739 -325.408493) (xy 33.323358 -325.362857)
			(xy 33.251374 -325.310558) (xy 33.184368 -325.252017) (xy 33.12288 -325.187706) (xy 33.067404 -325.118141)
			(xy 33.018387 -325.043884) (xy 32.976224 -324.965532) (xy 32.941254 -324.883715) (xy 32.913759 -324.799094)
			(xy 32.89396 -324.712348) (xy 32.882016 -324.624177) (xy 32.878025 -324.53529) (xy 29.07004 -324.53529)
			(xy 29.066048 -324.624177) (xy 29.054104 -324.712349) (xy 29.034305 -324.799095) (xy 29.006809 -324.883717)
			(xy 28.971839 -324.965533) (xy 28.929676 -325.043886) (xy 28.880659 -325.118143) (xy 28.825183 -325.187708)
			(xy 28.763694 -325.25202) (xy 28.696688 -325.310562) (xy 28.624705 -325.362861) (xy 28.548323 -325.408497)
			(xy 28.468157 -325.447102) (xy 28.384854 -325.478367) (xy 28.299084 -325.502038) (xy 28.211537 -325.517925)
			(xy 28.122918 -325.525901) (xy 28.07843 -325.5264) (xy 26.32583 -325.5264) (xy 26.281342 -325.525897)
			(xy 26.192724 -325.517921) (xy 26.105177 -325.502034) (xy 26.019407 -325.478363) (xy 25.936104 -325.447099)
			(xy 25.855939 -325.408493) (xy 25.779558 -325.362857) (xy 25.707574 -325.310558) (xy 25.640568 -325.252017)
			(xy 25.57908 -325.187706) (xy 25.523604 -325.118141) (xy 25.474587 -325.043884) (xy 25.432424 -324.965532)
			(xy 25.397454 -324.883715) (xy 25.369959 -324.799094) (xy 25.35016 -324.712348) (xy 25.338216 -324.624177)
			(xy 25.334225 -324.53529) (xy 24.832564 -324.53529) (xy 24.838666 -324.583595) (xy 24.839168 -324.615556)
			(xy 24.838666 -324.647517) (xy 24.830655 -324.710935) (xy 24.814758 -324.772849) (xy 24.791226 -324.832282)
			(xy 24.760432 -324.888297) (xy 24.722859 -324.940012) (xy 24.679102 -324.986609) (xy 24.629849 -325.027354)
			(xy 24.575878 -325.061605) (xy 24.518039 -325.088822) (xy 24.457246 -325.108575) (xy 24.394456 -325.120553)
			(xy 24.33066 -325.124567) (xy 24.266864 -325.120553) (xy 24.204074 -325.108575) (xy 24.143281 -325.088822)
			(xy 24.085442 -325.061605) (xy 24.031471 -325.027354) (xy 23.982218 -324.986609) (xy 23.938461 -324.940012)
			(xy 23.900888 -324.888297) (xy 23.870094 -324.832282) (xy 23.846562 -324.772849) (xy 23.830665 -324.710935)
			(xy 23.822654 -324.647517) (xy 22.84603 -324.647517) (xy 22.84603 -333.44485) (xy 22.84603 -333.447136)
			(xy 22.846738 -333.455466) (xy 22.852832 -333.47102) (xy 22.857968 -333.477616) (xy 22.858984 -333.478886)
			(xy 22.860762 -333.480664) (xy 22.882606 -333.502508) (xy 22.885654 -333.505302) (xy 22.892255 -333.510428)
			(xy 22.907808 -333.516517) (xy 22.916134 -333.51724) (xy 22.927556 -333.517853) (xy 22.950303 -333.520271)
			(xy 22.9616 -333.522066) (xy 22.989315 -333.527259) (xy 23.042927 -333.544728) (xy 23.093382 -333.569898)
			(xy 23.139583 -333.602221) (xy 23.180523 -333.640994) (xy 23.215308 -333.685371) (xy 23.243183 -333.734385)
			(xy 23.263538 -333.786968) (xy 23.275931 -333.841975) (xy 23.280091 -333.898207) (xy 23.275929 -333.954438)
			(xy 23.263534 -334.009445) (xy 23.243177 -334.062027) (xy 23.217872 -334.10652) (xy 58.664602 -334.10652)
			(xy 58.665083 -334.0758) (xy 58.67248 -334.014807) (xy 58.687169 -333.955148) (xy 58.708935 -333.897693)
			(xy 58.737462 -333.843277) (xy 58.754518 -333.817722) (xy 58.759893 -333.809028) (xy 58.763959 -333.789017)
			(xy 58.759906 -333.769003) (xy 58.754518 -333.760318) (xy 58.737479 -333.734752) (xy 58.708949 -333.680338)
			(xy 58.687179 -333.622885) (xy 58.672487 -333.563228) (xy 58.665086 -333.502236) (xy 58.665084 -333.440797)
			(xy 58.672481 -333.379804) (xy 58.687169 -333.320146) (xy 58.708935 -333.262692) (xy 58.737462 -333.208276)
			(xy 58.754518 -333.182722) (xy 58.759893 -333.174028) (xy 58.763959 -333.154017) (xy 58.759906 -333.134003)
			(xy 58.754518 -333.125318) (xy 58.737479 -333.099752) (xy 58.708949 -333.045338) (xy 58.687179 -332.987885)
			(xy 58.672487 -332.928228) (xy 58.665086 -332.867236) (xy 58.665084 -332.805797) (xy 58.672481 -332.744804)
			(xy 58.687169 -332.685146) (xy 58.708935 -332.627692) (xy 58.737462 -332.573276) (xy 58.754518 -332.547722)
			(xy 58.759893 -332.539028) (xy 58.763959 -332.519017) (xy 58.759906 -332.499003) (xy 58.754518 -332.490318)
			(xy 58.737479 -332.464752) (xy 58.708949 -332.410338) (xy 58.687179 -332.352885) (xy 58.672487 -332.293228)
			(xy 58.665086 -332.232236) (xy 58.665084 -332.170797) (xy 58.672481 -332.109804) (xy 58.687169 -332.050146)
			(xy 58.708935 -331.992692) (xy 58.737462 -331.938276) (xy 58.754518 -331.912722) (xy 58.759893 -331.904028)
			(xy 58.763959 -331.884017) (xy 58.759906 -331.864003) (xy 58.754518 -331.855318) (xy 58.737479 -331.829752)
			(xy 58.708949 -331.775338) (xy 58.687179 -331.717885) (xy 58.672487 -331.658228) (xy 58.665086 -331.597236)
			(xy 58.665084 -331.535797) (xy 58.672481 -331.474804) (xy 58.687169 -331.415146) (xy 58.708935 -331.357692)
			(xy 58.737462 -331.303276) (xy 58.754518 -331.277722) (xy 58.759893 -331.269028) (xy 58.763959 -331.249017)
			(xy 58.759906 -331.229003) (xy 58.754518 -331.220318) (xy 58.737479 -331.194752) (xy 58.708949 -331.140338)
			(xy 58.687179 -331.082885) (xy 58.672487 -331.023228) (xy 58.665086 -330.962236) (xy 58.665084 -330.900797)
			(xy 58.672481 -330.839804) (xy 58.687169 -330.780146) (xy 58.708935 -330.722692) (xy 58.737462 -330.668276)
			(xy 58.754518 -330.642722) (xy 58.759893 -330.634028) (xy 58.763959 -330.614017) (xy 58.759906 -330.594003)
			(xy 58.754518 -330.585318) (xy 58.737479 -330.559752) (xy 58.708949 -330.505338) (xy 58.687179 -330.447885)
			(xy 58.672487 -330.388228) (xy 58.665086 -330.327236) (xy 58.665084 -330.265797) (xy 58.672481 -330.204804)
			(xy 58.687169 -330.145146) (xy 58.708935 -330.087692) (xy 58.737462 -330.033276) (xy 58.754518 -330.007722)
			(xy 58.759893 -329.999028) (xy 58.763959 -329.979017) (xy 58.759906 -329.959003) (xy 58.754518 -329.950318)
			(xy 58.737474 -329.924755) (xy 58.708939 -329.870343) (xy 58.687164 -329.81289) (xy 58.672469 -329.753233)
			(xy 58.665066 -329.69224) (xy 58.664602 -329.66152) (xy 58.665056 -329.630788) (xy 58.672463 -329.569772)
			(xy 58.687171 -329.510093) (xy 58.708965 -329.452623) (xy 58.737527 -329.398198) (xy 58.772442 -329.347614)
			(xy 58.8132 -329.301607) (xy 58.859206 -329.260848) (xy 58.90979 -329.225932) (xy 58.964214 -329.197369)
			(xy 59.021684 -329.175574) (xy 59.081362 -329.160865) (xy 59.142378 -329.153457) (xy 59.17311 -329.153012)
			(xy 59.203831 -329.153476) (xy 59.264825 -329.160877) (xy 59.324483 -329.175569) (xy 59.381939 -329.197339)
			(xy 59.436354 -329.22587) (xy 59.461908 -329.242928) (xy 59.470593 -329.248321) (xy 59.49061 -329.252382)
			(xy 59.510627 -329.248321) (xy 59.519312 -329.242928) (xy 59.544866 -329.22587) (xy 59.599281 -329.197339)
			(xy 59.656736 -329.175568) (xy 59.716395 -329.160876) (xy 59.777389 -329.153476) (xy 59.838831 -329.153476)
			(xy 59.899825 -329.160876) (xy 59.959484 -329.175568) (xy 60.016939 -329.197339) (xy 60.071354 -329.22587)
			(xy 60.096908 -329.242928) (xy 60.105593 -329.248321) (xy 60.12561 -329.252382) (xy 60.145627 -329.248321)
			(xy 60.154312 -329.242928) (xy 60.179868 -329.225873) (xy 60.234282 -329.197338) (xy 60.291736 -329.175567)
			(xy 60.351395 -329.160874) (xy 60.412389 -329.153474) (xy 60.44311 -329.153012) (xy 60.473843 -329.153428)
			(xy 60.534861 -329.160838) (xy 60.594541 -329.17555) (xy 60.652012 -329.197347) (xy 60.706437 -329.225913)
			(xy 60.757022 -329.260832) (xy 60.803029 -329.301593) (xy 60.843787 -329.347602) (xy 60.878702 -329.398189)
			(xy 60.907265 -329.452615) (xy 60.929059 -329.510088) (xy 60.943767 -329.569769) (xy 60.951174 -329.630787)
			(xy 60.951618 -329.66152) (xy 60.951153 -329.692241) (xy 60.943752 -329.753234) (xy 60.929059 -329.812893)
			(xy 60.90729 -329.870348) (xy 60.878759 -329.924764) (xy 60.861702 -329.950318) (xy 60.856291 -329.958993)
			(xy 60.852235 -329.979017) (xy 60.856304 -329.999037) (xy 60.861702 -330.007722) (xy 60.878779 -330.033264)
			(xy 60.907312 -330.08768) (xy 60.929083 -330.145137) (xy 60.943774 -330.204799) (xy 60.951173 -330.265795)
			(xy 60.951171 -330.327238) (xy 60.943768 -330.388234) (xy 60.929073 -330.447894) (xy 60.907299 -330.50535)
			(xy 60.878762 -330.559765) (xy 60.861702 -330.585318) (xy 60.856291 -330.593993) (xy 60.852235 -330.614017)
			(xy 60.856304 -330.634037) (xy 60.861702 -330.642722) (xy 60.878779 -330.668264) (xy 60.907312 -330.72268)
			(xy 60.929083 -330.780137) (xy 60.943774 -330.839799) (xy 60.951173 -330.900795) (xy 60.951171 -330.962238)
			(xy 60.943768 -331.023234) (xy 60.929073 -331.082894) (xy 60.907299 -331.14035) (xy 60.878762 -331.194765)
			(xy 60.861702 -331.220318) (xy 60.856291 -331.228993) (xy 60.852235 -331.249017) (xy 60.856304 -331.269037)
			(xy 60.861702 -331.277722) (xy 60.878779 -331.303264) (xy 60.907312 -331.35768) (xy 60.929083 -331.415137)
			(xy 60.943774 -331.474799) (xy 60.951173 -331.535795) (xy 60.951171 -331.597238) (xy 60.943768 -331.658234)
			(xy 60.929073 -331.717894) (xy 60.907299 -331.77535) (xy 60.878762 -331.829765) (xy 60.861702 -331.855318)
			(xy 60.856291 -331.863993) (xy 60.852235 -331.884017) (xy 60.856304 -331.904037) (xy 60.861702 -331.912722)
			(xy 60.878779 -331.938264) (xy 60.907312 -331.99268) (xy 60.929083 -332.050137) (xy 60.943774 -332.109799)
			(xy 60.951173 -332.170795) (xy 60.951171 -332.232238) (xy 60.943768 -332.293234) (xy 60.929073 -332.352894)
			(xy 60.907299 -332.41035) (xy 60.878762 -332.464765) (xy 60.861702 -332.490318) (xy 60.856291 -332.498993)
			(xy 60.852235 -332.519017) (xy 60.856304 -332.539037) (xy 60.861702 -332.547722) (xy 60.878779 -332.573264)
			(xy 60.907312 -332.62768) (xy 60.929083 -332.685137) (xy 60.943774 -332.744799) (xy 60.951173 -332.805795)
			(xy 60.951171 -332.867238) (xy 60.943768 -332.928234) (xy 60.929073 -332.987894) (xy 60.907299 -333.04535)
			(xy 60.878762 -333.099765) (xy 60.861702 -333.125318) (xy 60.856291 -333.133993) (xy 60.852235 -333.154017)
			(xy 60.856304 -333.174037) (xy 60.861702 -333.182722) (xy 60.878779 -333.208264) (xy 60.907312 -333.26268)
			(xy 60.929083 -333.320137) (xy 60.943774 -333.379799) (xy 60.951173 -333.440795) (xy 60.951171 -333.502238)
			(xy 60.943768 -333.563234) (xy 60.929073 -333.622894) (xy 60.907299 -333.68035) (xy 60.878762 -333.734765)
			(xy 60.861702 -333.760318) (xy 60.856291 -333.768993) (xy 60.852235 -333.789017) (xy 60.856304 -333.809037)
			(xy 60.861702 -333.817722) (xy 60.878765 -333.843273) (xy 60.907297 -333.897688) (xy 60.929067 -333.955144)
			(xy 60.943758 -334.014804) (xy 60.951157 -334.075799) (xy 60.951618 -334.10652) (xy 60.951163 -334.137251)
			(xy 60.943752 -334.198265) (xy 60.929042 -334.25794) (xy 60.907245 -334.315408) (xy 60.878681 -334.369829)
			(xy 60.843766 -334.420411) (xy 60.803009 -334.466416) (xy 60.757003 -334.507172) (xy 60.706421 -334.542086)
			(xy 60.651999 -334.570649) (xy 60.594531 -334.592445) (xy 60.534855 -334.607154) (xy 60.473841 -334.614563)
			(xy 60.44311 -334.615028) (xy 60.41239 -334.614546) (xy 60.351397 -334.607149) (xy 60.291738 -334.59246)
			(xy 60.234283 -334.570694) (xy 60.179867 -334.542167) (xy 60.154312 -334.525112) (xy 60.145627 -334.519719)
			(xy 60.12561 -334.515658) (xy 60.105593 -334.519719) (xy 60.096908 -334.525112) (xy 60.071354 -334.54217)
			(xy 60.016939 -334.570701) (xy 59.959484 -334.592472) (xy 59.899825 -334.607164) (xy 59.838831 -334.614564)
			(xy 59.777389 -334.614564) (xy 59.716395 -334.607164) (xy 59.656736 -334.592472) (xy 59.599281 -334.570701)
			(xy 59.544866 -334.54217) (xy 59.519312 -334.525112) (xy 59.510627 -334.519719) (xy 59.49061 -334.515658)
			(xy 59.470593 -334.519719) (xy 59.461908 -334.525112) (xy 59.43635 -334.542164) (xy 59.381936 -334.570697)
			(xy 59.324482 -334.59247) (xy 59.264824 -334.607163) (xy 59.203831 -334.614565) (xy 59.17311 -334.615028)
			(xy 59.14238 -334.614535) (xy 59.081368 -334.607128) (xy 59.021693 -334.592421) (xy 58.964227 -334.570628)
			(xy 58.909806 -334.542068) (xy 58.859224 -334.507156) (xy 58.81322 -334.466401) (xy 58.772463 -334.420399)
			(xy 58.737548 -334.36982) (xy 58.708984 -334.315401) (xy 58.687188 -334.257935) (xy 58.672478 -334.198262)
			(xy 58.665067 -334.13725) (xy 58.664602 -334.10652) (xy 23.217872 -334.10652) (xy 23.215301 -334.11104)
			(xy 23.180514 -334.155416) (xy 23.139573 -334.194187) (xy 23.093371 -334.226509) (xy 23.042914 -334.251677)
			(xy 22.989302 -334.269144) (xy 22.9616 -334.274414) (xy 22.950305 -334.276221) (xy 22.927557 -334.278637)
			(xy 22.916134 -334.27924) (xy 22.907805 -334.27995) (xy 22.89225 -334.286043) (xy 22.885654 -334.291178)
			(xy 22.882606 -334.293972) (xy 22.861016 -334.315562) (xy 22.85365 -334.324706) (xy 22.85029 -334.330458)
			(xy 22.846428 -334.343202) (xy 22.84603 -334.349852) (xy 22.84603 -335.783936) (xy 22.846539 -335.793742)
			(xy 22.853999 -335.811887) (xy 22.860508 -335.819242) (xy 24.160988 -337.119722) (xy 24.166486 -337.124712)
			(xy 24.179651 -337.131563) (xy 24.186896 -337.133184) (xy 24.196548 -337.1342)
		)
		(stroke
			(width 0)
			(type solid)
		)
		(fill yes)
		(layer "In6.Cu")
		(net "PVDDIO_P1")
	)
	(gr_arc
		(start 0.508 -77.67193)
		(mid 0.621601 -78.242658)
		(end 0.94488 -78.726538)
		(stroke
			(width 0.2)
			(type default)
		)
		(layer "In6.Cu")
	)
	(gr_line
		(start 0.508 -13.780008)
		(end 0.508 -77.67193)
		(stroke
			(width 0.2)
			(type default)
		)
		(layer "In6.Cu")
	)
	(gr_arc
		(start 0.508 -7.78002)
		(mid 0.944996 -8.83502)
		(end 1.999996 -9.272016)
		(stroke
			(width 0.2)
			(type default)
		)
		(layer "In6.Cu")
	)
	(gr_line
		(start 0.508 10.40003)
		(end 0.508 -7.78002)
		(stroke
			(width 0.2)
			(type default)
		)
		(layer "In6.Cu")
	)
	(gr_line
		(start 0.94488 -78.726538)
		(end 1.773428 -79.555086)
		(stroke
			(width 0.2)
			(type default)
		)
		(layer "In6.Cu")
	)
	(gr_arc
		(start 1.999996 -12.288012)
		(mid 0.944996 -12.725008)
		(end 0.508 -13.780008)
		(stroke
			(width 0.2)
			(type default)
		)
		(layer "In6.Cu")
	)
	(gr_line
		(start 1.999996 -9.272016)
		(end 9.10209 -9.272016)
		(stroke
			(width 0.2)
			(type default)
		)
		(layer "In6.Cu")
	)
	(gr_arc
		(start 1.999996 11.892026)
		(mid 0.944996 11.45503)
		(end 0.508 10.40003)
		(stroke
			(width 0.2)
			(type default)
		)
		(layer "In6.Cu")
	)
	(gr_arc
		(start 2.507996 -403.371812)
		(mid 2.621533 -403.942691)
		(end 2.944876 -404.426674)
		(stroke
			(width 0.2)
			(type default)
		)
		(layer "In6.Cu")
	)
	(gr_arc
		(start 2.507996 -81.32826)
		(mid 2.317045 -80.368624)
		(end 1.773428 -79.555086)
		(stroke
			(width 0.2)
			(type default)
		)
		(layer "In6.Cu")
	)
	(gr_line
		(start 2.507996 -81.32826)
		(end 2.507996 -403.371812)
		(stroke
			(width 0.2)
			(type default)
		)
		(layer "In6.Cu")
	)
	(gr_line
		(start 2.944876 -404.426674)
		(end 6.273292 -407.75509)
		(stroke
			(width 0.2)
			(type default)
		)
		(layer "In6.Cu")
	)
	(gr_arc
		(start 7.008114 -439.989976)
		(mid 7.44511 -441.044976)
		(end 8.50011 -441.481972)
		(stroke
			(width 0.2)
			(type default)
		)
		(layer "In6.Cu")
	)
	(gr_arc
		(start 7.008114 -409.528518)
		(mid 6.817049 -408.568734)
		(end 6.273292 -407.75509)
		(stroke
			(width 0.2)
			(type default)
		)
		(layer "In6.Cu")
	)
	(gr_line
		(start 7.008114 -409.528518)
		(end 7.008114 -439.989976)
		(stroke
			(width 0.2)
			(type default)
		)
		(layer "In6.Cu")
	)
	(gr_line
		(start 8.50011 -441.481972)
		(end 194.496944 -441.481972)
		(stroke
			(width 0.2)
			(type default)
		)
		(layer "In6.Cu")
	)
	(gr_arc
		(start 9.10209 -9.272016)
		(mid 10.15709 -8.83502)
		(end 10.594086 -7.78002)
		(stroke
			(width 0.2)
			(type default)
		)
		(layer "In6.Cu")
	)
	(gr_line
		(start 9.106408 -178.618388)
		(end 9.397238 -178.327558)
		(stroke
			(width 0.07112)
			(type default)
		)
		(layer "In6.Cu")
	)
	(gr_line
		(start 9.106408 -177.754788)
		(end 9.397238 -178.045618)
		(stroke
			(width 0.07112)
			(type default)
		)
		(layer "In6.Cu")
	)
	(gr_line
		(start 9.106408 -175.848264)
		(end 9.397238 -175.557434)
		(stroke
			(width 0.07112)
			(type default)
		)
		(layer "In6.Cu")
	)
	(gr_line
		(start 9.106408 -174.984664)
		(end 9.397238 -175.275494)
		(stroke
			(width 0.07112)
			(type default)
		)
		(layer "In6.Cu")
	)
	(gr_line
		(start 9.106408 -173.07814)
		(end 9.397238 -172.78731)
		(stroke
			(width 0.07112)
			(type default)
		)
		(layer "In6.Cu")
	)
	(gr_line
		(start 9.106408 -172.21454)
		(end 9.397238 -172.50537)
		(stroke
			(width 0.07112)
			(type default)
		)
		(layer "In6.Cu")
	)
	(gr_line
		(start 9.106408 -170.29303)
		(end 9.397238 -170.0022)
		(stroke
			(width 0.07112)
			(type default)
		)
		(layer "In6.Cu")
	)
	(gr_line
		(start 9.106408 -169.42943)
		(end 9.397238 -169.72026)
		(stroke
			(width 0.07112)
			(type default)
		)
		(layer "In6.Cu")
	)
	(gr_line
		(start 10.594086 -7.78002)
		(end 10.594086 0.40005)
		(stroke
			(width 0.2)
			(type default)
		)
		(layer "In6.Cu")
	)
	(gr_line
		(start 10.791952 -190.829946)
		(end 10.599928 -190.829946)
		(stroke
			(width 0.07112)
			(type default)
		)
		(layer "In6.Cu")
	)
	(gr_line
		(start 10.894568 -190.134748)
		(end 10.39876 -190.630556)
		(stroke
			(width 0.07112)
			(type default)
		)
		(layer "In6.Cu")
	)
	(gr_line
		(start 11.093958 -190.52794)
		(end 10.791952 -190.829946)
		(stroke
			(width 0.07112)
			(type default)
		)
		(layer "In6.Cu")
	)
	(gr_line
		(start 11.093958 -190.335916)
		(end 11.093958 -190.52794)
		(stroke
			(width 0.07112)
			(type default)
		)
		(layer "In6.Cu")
	)
	(gr_line
		(start 11.102086 -12.288012)
		(end 1.999996 -12.288012)
		(stroke
			(width 0.2)
			(type default)
		)
		(layer "In6.Cu")
	)
	(gr_arc
		(start 11.102086 -12.288012)
		(mid 12.875508 -11.553438)
		(end 13.610082 -9.780016)
		(stroke
			(width 0.2)
			(type default)
		)
		(layer "In6.Cu")
	)
	(gr_line
		(start 11.318494 -192.80886)
		(end 11.126216 -192.80886)
		(stroke
			(width 0.07112)
			(type default)
		)
		(layer "In6.Cu")
	)
	(gr_line
		(start 11.42111 -192.113408)
		(end 10.925048 -192.60947)
		(stroke
			(width 0.07112)
			(type default)
		)
		(layer "In6.Cu")
	)
	(gr_line
		(start 11.589512 -190.03264)
		(end 11.397234 -190.03264)
		(stroke
			(width 0.07112)
			(type default)
		)
		(layer "In6.Cu")
	)
	(gr_line
		(start 11.6205 -192.506854)
		(end 11.318494 -192.80886)
		(stroke
			(width 0.07112)
			(type default)
		)
		(layer "In6.Cu")
	)
	(gr_line
		(start 11.6205 -192.314576)
		(end 11.6205 -192.506854)
		(stroke
			(width 0.07112)
			(type default)
		)
		(layer "In6.Cu")
	)
	(gr_line
		(start 11.692128 -189.337188)
		(end 11.196066 -189.83325)
		(stroke
			(width 0.07112)
			(type default)
		)
		(layer "In6.Cu")
	)
	(gr_line
		(start 11.891518 -189.730634)
		(end 11.589512 -190.03264)
		(stroke
			(width 0.07112)
			(type default)
		)
		(layer "In6.Cu")
	)
	(gr_line
		(start 11.891518 -189.538356)
		(end 11.891518 -189.730634)
		(stroke
			(width 0.07112)
			(type default)
		)
		(layer "In6.Cu")
	)
	(gr_line
		(start 12.116054 -192.0113)
		(end 11.923776 -192.0113)
		(stroke
			(width 0.07112)
			(type default)
		)
		(layer "In6.Cu")
	)
	(gr_line
		(start 12.21867 -191.315848)
		(end 11.722608 -191.81191)
		(stroke
			(width 0.07112)
			(type default)
		)
		(layer "In6.Cu")
	)
	(gr_line
		(start 12.387072 -189.23508)
		(end 12.194794 -189.23508)
		(stroke
			(width 0.07112)
			(type default)
		)
		(layer "In6.Cu")
	)
	(gr_line
		(start 12.41806 -191.709294)
		(end 12.116054 -192.0113)
		(stroke
			(width 0.07112)
			(type default)
		)
		(layer "In6.Cu")
	)
	(gr_line
		(start 12.41806 -191.517016)
		(end 12.41806 -191.709294)
		(stroke
			(width 0.07112)
			(type default)
		)
		(layer "In6.Cu")
	)
	(gr_line
		(start 12.489688 -188.539628)
		(end 11.993626 -189.03569)
		(stroke
			(width 0.07112)
			(type default)
		)
		(layer "In6.Cu")
	)
	(gr_line
		(start 12.689078 -188.933074)
		(end 12.387072 -189.23508)
		(stroke
			(width 0.07112)
			(type default)
		)
		(layer "In6.Cu")
	)
	(gr_line
		(start 12.689078 -188.740796)
		(end 12.689078 -188.933074)
		(stroke
			(width 0.07112)
			(type default)
		)
		(layer "In6.Cu")
	)
	(gr_line
		(start 12.913614 -191.21374)
		(end 12.721336 -191.21374)
		(stroke
			(width 0.07112)
			(type default)
		)
		(layer "In6.Cu")
	)
	(gr_line
		(start 12.92352 -360.416602)
		(end 13.216128 -360.123994)
		(stroke
			(width 0.07112)
			(type default)
		)
		(layer "In6.Cu")
	)
	(gr_line
		(start 12.92352 -359.553002)
		(end 13.211302 -359.840784)
		(stroke
			(width 0.07112)
			(type default)
		)
		(layer "In6.Cu")
	)
	(gr_line
		(start 13.01623 -190.518288)
		(end 12.520168 -191.01435)
		(stroke
			(width 0.07112)
			(type default)
		)
		(layer "In6.Cu")
	)
	(gr_arc
		(start 13.102082 2.908046)
		(mid 11.32866 2.173472)
		(end 10.594086 0.40005)
		(stroke
			(width 0.2)
			(type default)
		)
		(layer "In6.Cu")
	)
	(gr_line
		(start 13.102082 2.908046)
		(end 81.701894 2.908046)
		(stroke
			(width 0.2)
			(type default)
		)
		(layer "In6.Cu")
	)
	(gr_line
		(start 13.211302 -359.840784)
		(end 13.217398 -359.840784)
		(stroke
			(width 0.07112)
			(type default)
		)
		(layer "In6.Cu")
	)
	(gr_line
		(start 13.21562 -190.911734)
		(end 12.913614 -191.21374)
		(stroke
			(width 0.07112)
			(type default)
		)
		(layer "In6.Cu")
	)
	(gr_line
		(start 13.21562 -190.719456)
		(end 13.21562 -190.911734)
		(stroke
			(width 0.07112)
			(type default)
		)
		(layer "In6.Cu")
	)
	(gr_line
		(start 13.610082 -0.508)
		(end 13.610082 -9.780016)
		(stroke
			(width 0.2)
			(type default)
		)
		(layer "In6.Cu")
	)
	(gr_line
		(start 13.711174 -190.41618)
		(end 13.518896 -190.41618)
		(stroke
			(width 0.07112)
			(type default)
		)
		(layer "In6.Cu")
	)
	(gr_line
		(start 13.81379 -189.720728)
		(end 13.317728 -190.21679)
		(stroke
			(width 0.07112)
			(type default)
		)
		(layer "In6.Cu")
	)
	(gr_line
		(start 14.01318 -190.114174)
		(end 13.711174 -190.41618)
		(stroke
			(width 0.07112)
			(type default)
		)
		(layer "In6.Cu")
	)
	(gr_line
		(start 14.01318 -189.921896)
		(end 14.01318 -190.114174)
		(stroke
			(width 0.07112)
			(type default)
		)
		(layer "In6.Cu")
	)
	(gr_line
		(start 14.820646 -358.071674)
		(end 15.111476 -357.780844)
		(stroke
			(width 0.07112)
			(type default)
		)
		(layer "In6.Cu")
	)
	(gr_line
		(start 14.820646 -357.208074)
		(end 15.111476 -357.498904)
		(stroke
			(width 0.07112)
			(type default)
		)
		(layer "In6.Cu")
	)
	(gr_line
		(start 36.428426 -401.115784)
		(end 36.42868 -401.116038)
		(stroke
			(width 0.07112)
			(type default)
		)
		(layer "In6.Cu")
	)
	(gr_line
		(start 36.428934 -401.11553)
		(end 36.42868 -401.116038)
		(stroke
			(width 0.07112)
			(type default)
		)
		(layer "In6.Cu")
	)
	(gr_line
		(start 36.428934 -401.114768)
		(end 36.428934 -401.11553)
		(stroke
			(width 0.07112)
			(type default)
		)
		(layer "In6.Cu")
	)
	(gr_line
		(start 36.46297 -400.943064)
		(end 36.428934 -401.114768)
		(stroke
			(width 0.07112)
			(type default)
		)
		(layer "In6.Cu")
	)
	(gr_line
		(start 36.565586 -400.427698)
		(end 36.46297 -400.943064)
		(stroke
			(width 0.07112)
			(type default)
		)
		(layer "In6.Cu")
	)
	(gr_line
		(start 36.67125 -401.342098)
		(end 36.670996 -401.343114)
		(stroke
			(width 0.07112)
			(type default)
		)
		(layer "In6.Cu")
	)
	(gr_line
		(start 36.706302 -401.169632)
		(end 36.705286 -401.170394)
		(stroke
			(width 0.07112)
			(type default)
		)
		(layer "In6.Cu")
	)
	(gr_line
		(start 36.842954 -400.483832)
		(end 36.950142 -400.643852)
		(stroke
			(width 0.07112)
			(type default)
		)
		(layer "In6.Cu")
	)
	(gr_line
		(start 36.847018 -399.012156)
		(end 36.710112 -399.700242)
		(stroke
			(width 0.07112)
			(type default)
		)
		(layer "In6.Cu")
	)
	(gr_line
		(start 36.86683 -401.062444)
		(end 36.70681 -401.169378)
		(stroke
			(width 0.07112)
			(type default)
		)
		(layer "In6.Cu")
	)
	(gr_line
		(start 36.928298 -407.662126)
		(end 37.317172 -408.246072)
		(stroke
			(width 0.07112)
			(type default)
		)
		(layer "In6.Cu")
	)
	(gr_line
		(start 36.950142 -400.643852)
		(end 36.86683 -401.062444)
		(stroke
			(width 0.07112)
			(type default)
		)
		(layer "In6.Cu")
	)
	(gr_line
		(start 37.12464 -399.06829)
		(end 37.231574 -399.228564)
		(stroke
			(width 0.07112)
			(type default)
		)
		(layer "In6.Cu")
	)
	(gr_line
		(start 37.148262 -399.64741)
		(end 36.988242 -399.75409)
		(stroke
			(width 0.07112)
			(type default)
		)
		(layer "In6.Cu")
	)
	(gr_line
		(start 37.162994 -407.50617)
		(end 37.162994 -407.505916)
		(stroke
			(width 0.07112)
			(type default)
		)
		(layer "In6.Cu")
	)
	(gr_line
		(start 37.164772 -407.506424)
		(end 37.35324 -407.54427)
		(stroke
			(width 0.07112)
			(type default)
		)
		(layer "In6.Cu")
	)
	(gr_line
		(start 37.231574 -399.228564)
		(end 37.148262 -399.64741)
		(stroke
			(width 0.07112)
			(type default)
		)
		(layer "In6.Cu")
	)
	(gr_line
		(start 37.35324 -407.54427)
		(end 37.589968 -407.899616)
		(stroke
			(width 0.07112)
			(type default)
		)
		(layer "In6.Cu")
	)
	(gr_line
		(start 37.553646 -408.601418)
		(end 37.942266 -409.184856)
		(stroke
			(width 0.07112)
			(type default)
		)
		(layer "In6.Cu")
	)
	(gr_line
		(start 37.589968 -407.899616)
		(end 37.552122 -408.088338)
		(stroke
			(width 0.07112)
			(type default)
		)
		(layer "In6.Cu")
	)
	(gr_line
		(start 37.789866 -408.445208)
		(end 37.978334 -408.483054)
		(stroke
			(width 0.07112)
			(type default)
		)
		(layer "In6.Cu")
	)
	(gr_line
		(start 37.978334 -408.483054)
		(end 38.215316 -408.8384)
		(stroke
			(width 0.07112)
			(type default)
		)
		(layer "In6.Cu")
	)
	(gr_line
		(start 38.215316 -408.8384)
		(end 38.177216 -409.026868)
		(stroke
			(width 0.07112)
			(type default)
		)
		(layer "In6.Cu")
	)
	(gr_line
		(start 38.426136 -409.91155)
		(end 38.814756 -410.495496)
		(stroke
			(width 0.07112)
			(type default)
		)
		(layer "In6.Cu")
	)
	(gr_line
		(start 38.66261 -409.755594)
		(end 38.851078 -409.79344)
		(stroke
			(width 0.07112)
			(type default)
		)
		(layer "In6.Cu")
	)
	(gr_line
		(start 38.851078 -409.79344)
		(end 39.087806 -410.148786)
		(stroke
			(width 0.07112)
			(type default)
		)
		(layer "In6.Cu")
	)
	(gr_line
		(start 39.05758 -413.16529)
		(end 39.07282 -413.16529)
		(stroke
			(width 0.07112)
			(type default)
		)
		(layer "In6.Cu")
	)
	(gr_line
		(start 39.05885 -412.88208)
		(end 39.35603 -412.5849)
		(stroke
			(width 0.07112)
			(type default)
		)
		(layer "In6.Cu")
	)
	(gr_line
		(start 39.07282 -413.16529)
		(end 39.35603 -413.4485)
		(stroke
			(width 0.07112)
			(type default)
		)
		(layer "In6.Cu")
	)
	(gr_line
		(start 39.087806 -410.148786)
		(end 39.04996 -410.337508)
		(stroke
			(width 0.07112)
			(type default)
		)
		(layer "In6.Cu")
	)
	(gr_line
		(start 39.183056 -411.0482)
		(end 39.571676 -411.632146)
		(stroke
			(width 0.07112)
			(type default)
		)
		(layer "In6.Cu")
	)
	(gr_line
		(start 39.419276 -410.89199)
		(end 39.607998 -410.93009)
		(stroke
			(width 0.07112)
			(type default)
		)
		(layer "In6.Cu")
	)
	(gr_line
		(start 39.607998 -410.93009)
		(end 39.844726 -411.285436)
		(stroke
			(width 0.07112)
			(type default)
		)
		(layer "In6.Cu")
	)
	(gr_line
		(start 39.736776 -380.141734)
		(end 39.736776 -380.842774)
		(stroke
			(width 0.07112)
			(type default)
		)
		(layer "In6.Cu")
	)
	(gr_line
		(start 39.736776 -378.855732)
		(end 39.736776 -379.556772)
		(stroke
			(width 0.07112)
			(type default)
		)
		(layer "In6.Cu")
	)
	(gr_line
		(start 39.736776 -377.647962)
		(end 39.736776 -378.349002)
		(stroke
			(width 0.07112)
			(type default)
		)
		(layer "In6.Cu")
	)
	(gr_line
		(start 39.736776 -376.289062)
		(end 39.736776 -376.990102)
		(stroke
			(width 0.07112)
			(type default)
		)
		(layer "In6.Cu")
	)
	(gr_line
		(start 39.844726 -411.285436)
		(end 39.80688 -411.474158)
		(stroke
			(width 0.07112)
			(type default)
		)
		(layer "In6.Cu")
	)
	(gr_line
		(start 40.019986 -380.143004)
		(end 40.155876 -380.278894)
		(stroke
			(width 0.07112)
			(type default)
		)
		(layer "In6.Cu")
	)
	(gr_line
		(start 40.019986 -378.857002)
		(end 40.155876 -378.992892)
		(stroke
			(width 0.07112)
			(type default)
		)
		(layer "In6.Cu")
	)
	(gr_line
		(start 40.019986 -377.649232)
		(end 40.155876 -377.785122)
		(stroke
			(width 0.07112)
			(type default)
		)
		(layer "In6.Cu")
	)
	(gr_line
		(start 40.019986 -376.290332)
		(end 40.155876 -376.426222)
		(stroke
			(width 0.07112)
			(type default)
		)
		(layer "In6.Cu")
	)
	(gr_line
		(start 40.067992 -381.343916)
		(end 40.067992 -381.34417)
		(stroke
			(width 0.07112)
			(type default)
		)
		(layer "In6.Cu")
	)
	(gr_line
		(start 40.155876 -380.705614)
		(end 40.019986 -380.841504)
		(stroke
			(width 0.07112)
			(type default)
		)
		(layer "In6.Cu")
	)
	(gr_line
		(start 40.155876 -380.278894)
		(end 40.155876 -380.705614)
		(stroke
			(width 0.07112)
			(type default)
		)
		(layer "In6.Cu")
	)
	(gr_line
		(start 40.155876 -379.419612)
		(end 40.019986 -379.555502)
		(stroke
			(width 0.07112)
			(type default)
		)
		(layer "In6.Cu")
	)
	(gr_line
		(start 40.155876 -378.992892)
		(end 40.155876 -379.419612)
		(stroke
			(width 0.07112)
			(type default)
		)
		(layer "In6.Cu")
	)
	(gr_line
		(start 40.155876 -378.211842)
		(end 40.019986 -378.347732)
		(stroke
			(width 0.07112)
			(type default)
		)
		(layer "In6.Cu")
	)
	(gr_line
		(start 40.155876 -377.785122)
		(end 40.155876 -378.211842)
		(stroke
			(width 0.07112)
			(type default)
		)
		(layer "In6.Cu")
	)
	(gr_line
		(start 40.155876 -376.852942)
		(end 40.019986 -376.988832)
		(stroke
			(width 0.07112)
			(type default)
		)
		(layer "In6.Cu")
	)
	(gr_line
		(start 40.155876 -376.426222)
		(end 40.155876 -376.852942)
		(stroke
			(width 0.07112)
			(type default)
		)
		(layer "In6.Cu")
	)
	(gr_line
		(start 41.139872 -382.07823)
		(end 41.430702 -382.36906)
		(stroke
			(width 0.07112)
			(type default)
		)
		(layer "In6.Cu")
	)
	(gr_line
		(start 41.139872 -381.79629)
		(end 41.430702 -381.50546)
		(stroke
			(width 0.07112)
			(type default)
		)
		(layer "In6.Cu")
	)
	(gr_line
		(start 41.291002 -414.804098)
		(end 41.304718 -414.804098)
		(stroke
			(width 0.07112)
			(type default)
		)
		(layer "In6.Cu")
	)
	(gr_line
		(start 41.292272 -415.087308)
		(end 41.58869 -415.383726)
		(stroke
			(width 0.07112)
			(type default)
		)
		(layer "In6.Cu")
	)
	(gr_line
		(start 41.304718 -414.804098)
		(end 41.58869 -414.520126)
		(stroke
			(width 0.07112)
			(type default)
		)
		(layer "In6.Cu")
	)
	(gr_line
		(start 41.367964 -371.779038)
		(end 41.503854 -371.914928)
		(stroke
			(width 0.07112)
			(type default)
		)
		(layer "In6.Cu")
	)
	(gr_line
		(start 41.367964 -371.352318)
		(end 41.367964 -371.779038)
		(stroke
			(width 0.07112)
			(type default)
		)
		(layer "In6.Cu")
	)
	(gr_line
		(start 41.367964 -370.651278)
		(end 41.503854 -370.787168)
		(stroke
			(width 0.07112)
			(type default)
		)
		(layer "In6.Cu")
	)
	(gr_line
		(start 41.367964 -370.224558)
		(end 41.367964 -370.651278)
		(stroke
			(width 0.07112)
			(type default)
		)
		(layer "In6.Cu")
	)
	(gr_line
		(start 41.367964 -369.523518)
		(end 41.503854 -369.659408)
		(stroke
			(width 0.07112)
			(type default)
		)
		(layer "In6.Cu")
	)
	(gr_line
		(start 41.367964 -369.096798)
		(end 41.367964 -369.523518)
		(stroke
			(width 0.07112)
			(type default)
		)
		(layer "In6.Cu")
	)
	(gr_line
		(start 41.503854 -371.216428)
		(end 41.367964 -371.352318)
		(stroke
			(width 0.07112)
			(type default)
		)
		(layer "In6.Cu")
	)
	(gr_line
		(start 41.503854 -370.088668)
		(end 41.367964 -370.224558)
		(stroke
			(width 0.07112)
			(type default)
		)
		(layer "In6.Cu")
	)
	(gr_line
		(start 41.503854 -368.960908)
		(end 41.367964 -369.096798)
		(stroke
			(width 0.07112)
			(type default)
		)
		(layer "In6.Cu")
	)
	(gr_line
		(start 41.573704 -387.498844)
		(end 41.282874 -387.789674)
		(stroke
			(width 0.07112)
			(type default)
		)
		(layer "In6.Cu")
	)
	(gr_line
		(start 41.573704 -387.216904)
		(end 41.282874 -386.926074)
		(stroke
			(width 0.07112)
			(type default)
		)
		(layer "In6.Cu")
	)
	(gr_line
		(start 41.71823 -376.255788)
		(end 41.430702 -375.96826)
		(stroke
			(width 0.07112)
			(type default)
		)
		(layer "In6.Cu")
	)
	(gr_line
		(start 41.723564 -376.538998)
		(end 41.430702 -376.83186)
		(stroke
			(width 0.07112)
			(type default)
		)
		(layer "In6.Cu")
	)
	(gr_line
		(start 41.724834 -376.255788)
		(end 41.71823 -376.255788)
		(stroke
			(width 0.07112)
			(type default)
		)
		(layer "In6.Cu")
	)
	(gr_line
		(start 41.787064 -371.215158)
		(end 41.787064 -371.916198)
		(stroke
			(width 0.07112)
			(type default)
		)
		(layer "In6.Cu")
	)
	(gr_line
		(start 41.787064 -370.087398)
		(end 41.787064 -370.788438)
		(stroke
			(width 0.07112)
			(type default)
		)
		(layer "In6.Cu")
	)
	(gr_line
		(start 41.787064 -368.959638)
		(end 41.787064 -369.660678)
		(stroke
			(width 0.07112)
			(type default)
		)
		(layer "In6.Cu")
	)
	(gr_line
		(start 42.222674 -387.636004)
		(end 42.086784 -387.500114)
		(stroke
			(width 0.07112)
			(type default)
		)
		(layer "In6.Cu")
	)
	(gr_line
		(start 42.432732 -375.27357)
		(end 42.568622 -375.40946)
		(stroke
			(width 0.07112)
			(type default)
		)
		(layer "In6.Cu")
	)
	(gr_line
		(start 42.432732 -374.84685)
		(end 42.432732 -375.27357)
		(stroke
			(width 0.07112)
			(type default)
		)
		(layer "In6.Cu")
	)
	(gr_line
		(start 42.568622 -374.71096)
		(end 42.432732 -374.84685)
		(stroke
			(width 0.07112)
			(type default)
		)
		(layer "In6.Cu")
	)
	(gr_line
		(start 42.649394 -387.636004)
		(end 42.222674 -387.636004)
		(stroke
			(width 0.07112)
			(type default)
		)
		(layer "In6.Cu")
	)
	(gr_line
		(start 42.785284 -387.500114)
		(end 42.649394 -387.636004)
		(stroke
			(width 0.07112)
			(type default)
		)
		(layer "In6.Cu")
	)
	(gr_line
		(start 42.786554 -387.216904)
		(end 42.085514 -387.216904)
		(stroke
			(width 0.07112)
			(type default)
		)
		(layer "In6.Cu")
	)
	(gr_line
		(start 42.851832 -374.70969)
		(end 42.851832 -375.41073)
		(stroke
			(width 0.07112)
			(type default)
		)
		(layer "In6.Cu")
	)
	(gr_line
		(start 43.305984 -371.2083)
		(end 43.015154 -371.49913)
		(stroke
			(width 0.07112)
			(type default)
		)
		(layer "In6.Cu")
	)
	(gr_line
		(start 43.587924 -371.2083)
		(end 43.878754 -371.49913)
		(stroke
			(width 0.07112)
			(type default)
		)
		(layer "In6.Cu")
	)
	(gr_line
		(start 45.007784 -368.7445)
		(end 44.716954 -369.03533)
		(stroke
			(width 0.07112)
			(type default)
		)
		(layer "In6.Cu")
	)
	(gr_line
		(start 45.289724 -368.7445)
		(end 45.580554 -369.03533)
		(stroke
			(width 0.07112)
			(type default)
		)
		(layer "In6.Cu")
	)
	(gr_line
		(start 45.954188 -385.97205)
		(end 45.954188 -386.67309)
		(stroke
			(width 0.07112)
			(type default)
		)
		(layer "In6.Cu")
	)
	(gr_line
		(start 46.237398 -385.97332)
		(end 46.373288 -386.10921)
		(stroke
			(width 0.07112)
			(type default)
		)
		(layer "In6.Cu")
	)
	(gr_line
		(start 46.373288 -386.53593)
		(end 46.237398 -386.67182)
		(stroke
			(width 0.07112)
			(type default)
		)
		(layer "In6.Cu")
	)
	(gr_line
		(start 46.373288 -386.10921)
		(end 46.373288 -386.53593)
		(stroke
			(width 0.07112)
			(type default)
		)
		(layer "In6.Cu")
	)
	(gr_line
		(start 47.79137 -388.774432)
		(end 47.843694 -388.826756)
		(stroke
			(width 0.07112)
			(type default)
		)
		(layer "In6.Cu")
	)
	(gr_line
		(start 47.807118 -389.564118)
		(end 47.807372 -389.564118)
		(stroke
			(width 0.07112)
			(type default)
		)
		(layer "In6.Cu")
	)
	(gr_line
		(start 47.843694 -389.006588)
		(end 47.697136 -389.153146)
		(stroke
			(width 0.07112)
			(type default)
		)
		(layer "In6.Cu")
	)
	(gr_line
		(start 47.843694 -388.826756)
		(end 47.843694 -389.006588)
		(stroke
			(width 0.07112)
			(type default)
		)
		(layer "In6.Cu")
	)
	(gr_line
		(start 48.076612 -389.352536)
		(end 47.898304 -389.352536)
		(stroke
			(width 0.07112)
			(type default)
		)
		(layer "In6.Cu")
	)
	(gr_line
		(start 48.084994 -404.17369)
		(end 47.794164 -404.46452)
		(stroke
			(width 0.07112)
			(type default)
		)
		(layer "In6.Cu")
	)
	(gr_line
		(start 48.19142 -389.467344)
		(end 48.076612 -389.352536)
		(stroke
			(width 0.07112)
			(type default)
		)
		(layer "In6.Cu")
	)
	(gr_line
		(start 48.271938 -400.246088)
		(end 48.271938 -400.947128)
		(stroke
			(width 0.07112)
			(type default)
		)
		(layer "In6.Cu")
	)
	(gr_line
		(start 48.271938 -399.118328)
		(end 48.271938 -399.819368)
		(stroke
			(width 0.07112)
			(type default)
		)
		(layer "In6.Cu")
	)
	(gr_line
		(start 48.271938 -397.990568)
		(end 48.271938 -398.691608)
		(stroke
			(width 0.07112)
			(type default)
		)
		(layer "In6.Cu")
	)
	(gr_line
		(start 48.36414 -373.719344)
		(end 48.120554 -373.96293)
		(stroke
			(width 0.07112)
			(type default)
		)
		(layer "In6.Cu")
	)
	(gr_arc
		(start 48.36414 -373.719344)
		(mid 48.395581 -373.674933)
		(end 48.410368 -373.62257)
		(stroke
			(width 0.07112)
			(type default)
		)
		(layer "In6.Cu")
	)
	(gr_line
		(start 48.366934 -404.17369)
		(end 48.657764 -404.46452)
		(stroke
			(width 0.07112)
			(type default)
		)
		(layer "In6.Cu")
	)
	(gr_line
		(start 48.555148 -400.247358)
		(end 48.691038 -400.383248)
		(stroke
			(width 0.07112)
			(type default)
		)
		(layer "In6.Cu")
	)
	(gr_line
		(start 48.555148 -399.119598)
		(end 48.691038 -399.255488)
		(stroke
			(width 0.07112)
			(type default)
		)
		(layer "In6.Cu")
	)
	(gr_line
		(start 48.555148 -397.991838)
		(end 48.691038 -398.127728)
		(stroke
			(width 0.07112)
			(type default)
		)
		(layer "In6.Cu")
	)
	(gr_line
		(start 48.691038 -400.809968)
		(end 48.555148 -400.945858)
		(stroke
			(width 0.07112)
			(type default)
		)
		(layer "In6.Cu")
	)
	(gr_line
		(start 48.691038 -400.383248)
		(end 48.691038 -400.809968)
		(stroke
			(width 0.07112)
			(type default)
		)
		(layer "In6.Cu")
	)
	(gr_line
		(start 48.691038 -399.682208)
		(end 48.555148 -399.818098)
		(stroke
			(width 0.07112)
			(type default)
		)
		(layer "In6.Cu")
	)
	(gr_line
		(start 48.691038 -399.255488)
		(end 48.691038 -399.682208)
		(stroke
			(width 0.07112)
			(type default)
		)
		(layer "In6.Cu")
	)
	(gr_line
		(start 48.691038 -398.554448)
		(end 48.555148 -398.690338)
		(stroke
			(width 0.07112)
			(type default)
		)
		(layer "In6.Cu")
	)
	(gr_line
		(start 48.691038 -398.127728)
		(end 48.691038 -398.554448)
		(stroke
			(width 0.07112)
			(type default)
		)
		(layer "In6.Cu")
	)
	(gr_arc
		(start 48.69434 -373.62257)
		(mid 48.709198 -373.6749)
		(end 48.740568 -373.719344)
		(stroke
			(width 0.07112)
			(type default)
		)
		(layer "In6.Cu")
	)
	(gr_line
		(start 48.740568 -373.719344)
		(end 48.984154 -373.96293)
		(stroke
			(width 0.07112)
			(type default)
		)
		(layer "In6.Cu")
	)
	(gr_line
		(start 48.991266 -388.774432)
		(end 49.04359 -388.826756)
		(stroke
			(width 0.07112)
			(type default)
		)
		(layer "In6.Cu")
	)
	(gr_line
		(start 49.04359 -389.006588)
		(end 48.897032 -389.153146)
		(stroke
			(width 0.07112)
			(type default)
		)
		(layer "In6.Cu")
	)
	(gr_line
		(start 49.04359 -388.826756)
		(end 49.04359 -389.006588)
		(stroke
			(width 0.07112)
			(type default)
		)
		(layer "In6.Cu")
	)
	(gr_line
		(start 49.276508 -389.352536)
		(end 49.0982 -389.352536)
		(stroke
			(width 0.07112)
			(type default)
		)
		(layer "In6.Cu")
	)
	(gr_line
		(start 49.325784 -410.030168)
		(end 49.616614 -410.320998)
		(stroke
			(width 0.07112)
			(type default)
		)
		(layer "In6.Cu")
	)
	(gr_line
		(start 49.391316 -389.467344)
		(end 49.276508 -389.352536)
		(stroke
			(width 0.07112)
			(type default)
		)
		(layer "In6.Cu")
	)
	(gr_line
		(start 49.616614 -411.183582)
		(end 49.616614 -411.884622)
		(stroke
			(width 0.07112)
			(type default)
		)
		(layer "In6.Cu")
	)
	(gr_line
		(start 49.899824 -411.184852)
		(end 50.035714 -411.320742)
		(stroke
			(width 0.07112)
			(type default)
		)
		(layer "In6.Cu")
	)
	(gr_line
		(start 50.035714 -411.747462)
		(end 49.899824 -411.883352)
		(stroke
			(width 0.07112)
			(type default)
		)
		(layer "In6.Cu")
	)
	(gr_line
		(start 50.035714 -411.320742)
		(end 50.035714 -411.747462)
		(stroke
			(width 0.07112)
			(type default)
		)
		(layer "In6.Cu")
	)
	(gr_line
		(start 50.113184 -371.2083)
		(end 49.822354 -371.49913)
		(stroke
			(width 0.07112)
			(type default)
		)
		(layer "In6.Cu")
	)
	(gr_line
		(start 50.189384 -410.030168)
		(end 49.898554 -410.320998)
		(stroke
			(width 0.07112)
			(type default)
		)
		(layer "In6.Cu")
	)
	(gr_line
		(start 50.191416 -388.774432)
		(end 50.24374 -388.826756)
		(stroke
			(width 0.07112)
			(type default)
		)
		(layer "In6.Cu")
	)
	(gr_line
		(start 50.216308 -398.448784)
		(end 50.516282 -399.082768)
		(stroke
			(width 0.07112)
			(type default)
		)
		(layer "In6.Cu")
	)
	(gr_line
		(start 50.24374 -389.030972)
		(end 50.121566 -389.153146)
		(stroke
			(width 0.07112)
			(type default)
		)
		(layer "In6.Cu")
	)
	(gr_line
		(start 50.24374 -388.826756)
		(end 50.24374 -389.030972)
		(stroke
			(width 0.07112)
			(type default)
		)
		(layer "In6.Cu")
	)
	(gr_line
		(start 50.395124 -371.2083)
		(end 50.685954 -371.49913)
		(stroke
			(width 0.07112)
			(type default)
		)
		(layer "In6.Cu")
	)
	(gr_line
		(start 50.473102 -398.328642)
		(end 50.654204 -398.393412)
		(stroke
			(width 0.07112)
			(type default)
		)
		(layer "In6.Cu")
	)
	(gr_line
		(start 50.476404 -389.352536)
		(end 50.322734 -389.352536)
		(stroke
			(width 0.07112)
			(type default)
		)
		(layer "In6.Cu")
	)
	(gr_line
		(start 50.583084 -414.965896)
		(end 51.000914 -415.529268)
		(stroke
			(width 0.07112)
			(type default)
		)
		(layer "In6.Cu")
	)
	(gr_line
		(start 50.591212 -389.467344)
		(end 50.476404 -389.352536)
		(stroke
			(width 0.07112)
			(type default)
		)
		(layer "In6.Cu")
	)
	(gr_line
		(start 50.654204 -398.393412)
		(end 50.836576 -398.779238)
		(stroke
			(width 0.07112)
			(type default)
		)
		(layer "In6.Cu")
	)
	(gr_line
		(start 50.671984 -395.455648)
		(end 50.671984 -396.156688)
		(stroke
			(width 0.07112)
			(type default)
		)
		(layer "In6.Cu")
	)
	(gr_line
		(start 50.671984 -394.327888)
		(end 50.671984 -395.028928)
		(stroke
			(width 0.07112)
			(type default)
		)
		(layer "In6.Cu")
	)
	(gr_line
		(start 50.698654 -399.46834)
		(end 50.998628 -400.102324)
		(stroke
			(width 0.07112)
			(type default)
		)
		(layer "In6.Cu")
	)
	(gr_line
		(start 50.811176 -414.798002)
		(end 51.001422 -414.826196)
		(stroke
			(width 0.07112)
			(type default)
		)
		(layer "In6.Cu")
	)
	(gr_line
		(start 50.836576 -398.779238)
		(end 50.771806 -398.960594)
		(stroke
			(width 0.07112)
			(type default)
		)
		(layer "In6.Cu")
	)
	(gr_line
		(start 50.955194 -399.348198)
		(end 51.13655 -399.412968)
		(stroke
			(width 0.07112)
			(type default)
		)
		(layer "In6.Cu")
	)
	(gr_line
		(start 50.955194 -395.456918)
		(end 51.091084 -395.592808)
		(stroke
			(width 0.07112)
			(type default)
		)
		(layer "In6.Cu")
	)
	(gr_line
		(start 50.955194 -394.329158)
		(end 51.091084 -394.465048)
		(stroke
			(width 0.07112)
			(type default)
		)
		(layer "In6.Cu")
	)
	(gr_line
		(start 51.001422 -414.826196)
		(end 51.25593 -415.169096)
		(stroke
			(width 0.07112)
			(type default)
		)
		(layer "In6.Cu")
	)
	(gr_line
		(start 51.091084 -396.019528)
		(end 50.955194 -396.155418)
		(stroke
			(width 0.07112)
			(type default)
		)
		(layer "In6.Cu")
	)
	(gr_line
		(start 51.091084 -395.592808)
		(end 51.091084 -396.019528)
		(stroke
			(width 0.07112)
			(type default)
		)
		(layer "In6.Cu")
	)
	(gr_line
		(start 51.091084 -394.891768)
		(end 50.955194 -395.027658)
		(stroke
			(width 0.07112)
			(type default)
		)
		(layer "In6.Cu")
	)
	(gr_line
		(start 51.091084 -394.465048)
		(end 51.091084 -394.891768)
		(stroke
			(width 0.07112)
			(type default)
		)
		(layer "In6.Cu")
	)
	(gr_line
		(start 51.136042 -400.3929)
		(end 51.136042 -400.392646)
		(stroke
			(width 0.07112)
			(type default)
		)
		(layer "In6.Cu")
	)
	(gr_line
		(start 51.13655 -399.412968)
		(end 51.318922 -399.799048)
		(stroke
			(width 0.07112)
			(type default)
		)
		(layer "In6.Cu")
	)
	(gr_line
		(start 51.148234 -404.17369)
		(end 50.857404 -404.46452)
		(stroke
			(width 0.07112)
			(type default)
		)
		(layer "In6.Cu")
	)
	(gr_line
		(start 51.148234 -402.144992)
		(end 51.148234 -402.846032)
		(stroke
			(width 0.07112)
			(type default)
		)
		(layer "In6.Cu")
	)
	(gr_line
		(start 51.25593 -415.169096)
		(end 51.227736 -415.359596)
		(stroke
			(width 0.07112)
			(type default)
		)
		(layer "In6.Cu")
	)
	(gr_line
		(start 51.318922 -399.799048)
		(end 51.254152 -399.98015)
		(stroke
			(width 0.07112)
			(type default)
		)
		(layer "In6.Cu")
	)
	(gr_line
		(start 51.391312 -388.774432)
		(end 51.443636 -388.826756)
		(stroke
			(width 0.07112)
			(type default)
		)
		(layer "In6.Cu")
	)
	(gr_line
		(start 51.430174 -404.17369)
		(end 51.721004 -404.46452)
		(stroke
			(width 0.07112)
			(type default)
		)
		(layer "In6.Cu")
	)
	(gr_line
		(start 51.431444 -402.146262)
		(end 51.567334 -402.282152)
		(stroke
			(width 0.07112)
			(type default)
		)
		(layer "In6.Cu")
	)
	(gr_line
		(start 51.443636 -389.006588)
		(end 51.297078 -389.153146)
		(stroke
			(width 0.07112)
			(type default)
		)
		(layer "In6.Cu")
	)
	(gr_line
		(start 51.443636 -388.826756)
		(end 51.443636 -389.006588)
		(stroke
			(width 0.07112)
			(type default)
		)
		(layer "In6.Cu")
	)
	(gr_line
		(start 51.541934 -416.258502)
		(end 51.959764 -416.821874)
		(stroke
			(width 0.07112)
			(type default)
		)
		(layer "In6.Cu")
	)
	(gr_line
		(start 51.567334 -402.708872)
		(end 51.431444 -402.844762)
		(stroke
			(width 0.07112)
			(type default)
		)
		(layer "In6.Cu")
	)
	(gr_line
		(start 51.567334 -402.282152)
		(end 51.567334 -402.708872)
		(stroke
			(width 0.07112)
			(type default)
		)
		(layer "In6.Cu")
	)
	(gr_line
		(start 51.676554 -389.352536)
		(end 51.498246 -389.352536)
		(stroke
			(width 0.07112)
			(type default)
		)
		(layer "In6.Cu")
	)
	(gr_line
		(start 51.680618 -366.879378)
		(end 51.666902 -366.893094)
		(stroke
			(width 0.07112)
			(type default)
		)
		(layer "In6.Cu")
	)
	(gr_arc
		(start 51.710082 -366.851946)
		(mid 51.695105 -366.865399)
		(end 51.680618 -366.879378)
		(stroke
			(width 0.07112)
			(type default)
		)
		(layer "In6.Cu")
	)
	(gr_line
		(start 51.758342 -366.83188)
		(end 51.710082 -366.851946)
		(stroke
			(width 0.07112)
			(type default)
		)
		(layer "In6.Cu")
	)
	(gr_line
		(start 51.770026 -416.090608)
		(end 51.960272 -416.118802)
		(stroke
			(width 0.07112)
			(type default)
		)
		(layer "In6.Cu")
	)
	(gr_line
		(start 51.791362 -389.467344)
		(end 51.676554 -389.352536)
		(stroke
			(width 0.07112)
			(type default)
		)
		(layer "In6.Cu")
	)
	(gr_line
		(start 51.814984 -368.7445)
		(end 51.524154 -369.03533)
		(stroke
			(width 0.07112)
			(type default)
		)
		(layer "In6.Cu")
	)
	(gr_line
		(start 51.87188 -395.429232)
		(end 51.87188 -396.130272)
		(stroke
			(width 0.07112)
			(type default)
		)
		(layer "In6.Cu")
	)
	(gr_line
		(start 51.87188 -394.301472)
		(end 51.87188 -395.002512)
		(stroke
			(width 0.07112)
			(type default)
		)
		(layer "In6.Cu")
	)
	(gr_line
		(start 51.960272 -416.118802)
		(end 52.21478 -416.461956)
		(stroke
			(width 0.07112)
			(type default)
		)
		(layer "In6.Cu")
	)
	(gr_line
		(start 52.096924 -368.7445)
		(end 52.387754 -369.03533)
		(stroke
			(width 0.07112)
			(type default)
		)
		(layer "In6.Cu")
	)
	(gr_line
		(start 52.15509 -395.430502)
		(end 52.29098 -395.566392)
		(stroke
			(width 0.07112)
			(type default)
		)
		(layer "In6.Cu")
	)
	(gr_line
		(start 52.15509 -394.302742)
		(end 52.29098 -394.438632)
		(stroke
			(width 0.07112)
			(type default)
		)
		(layer "In6.Cu")
	)
	(gr_line
		(start 52.21478 -416.461956)
		(end 52.186586 -416.652202)
		(stroke
			(width 0.07112)
			(type default)
		)
		(layer "In6.Cu")
	)
	(gr_line
		(start 52.29098 -395.993112)
		(end 52.15509 -396.129002)
		(stroke
			(width 0.07112)
			(type default)
		)
		(layer "In6.Cu")
	)
	(gr_line
		(start 52.29098 -395.566392)
		(end 52.29098 -395.993112)
		(stroke
			(width 0.07112)
			(type default)
		)
		(layer "In6.Cu")
	)
	(gr_line
		(start 52.29098 -394.865352)
		(end 52.15509 -395.001242)
		(stroke
			(width 0.07112)
			(type default)
		)
		(layer "In6.Cu")
	)
	(gr_line
		(start 52.29098 -394.438632)
		(end 52.29098 -394.865352)
		(stroke
			(width 0.07112)
			(type default)
		)
		(layer "In6.Cu")
	)
	(gr_line
		(start 52.389024 -410.030168)
		(end 52.679854 -410.320998)
		(stroke
			(width 0.07112)
			(type default)
		)
		(layer "In6.Cu")
	)
	(gr_line
		(start 52.389532 -417.401248)
		(end 52.807616 -417.964874)
		(stroke
			(width 0.07112)
			(type default)
		)
		(layer "In6.Cu")
	)
	(gr_line
		(start 52.591208 -388.774432)
		(end 52.643532 -388.826756)
		(stroke
			(width 0.07112)
			(type default)
		)
		(layer "In6.Cu")
	)
	(gr_line
		(start 52.617878 -417.233608)
		(end 52.808124 -417.261802)
		(stroke
			(width 0.07112)
			(type default)
		)
		(layer "In6.Cu")
	)
	(gr_line
		(start 52.643532 -389.006588)
		(end 52.496974 -389.153146)
		(stroke
			(width 0.07112)
			(type default)
		)
		(layer "In6.Cu")
	)
	(gr_line
		(start 52.643532 -388.826756)
		(end 52.643532 -389.006588)
		(stroke
			(width 0.07112)
			(type default)
		)
		(layer "In6.Cu")
	)
	(gr_line
		(start 52.807616 -417.964874)
		(end 52.80787 -417.96462)
		(stroke
			(width 0.07112)
			(type default)
		)
		(layer "In6.Cu")
	)
	(gr_line
		(start 52.808124 -417.261802)
		(end 53.062632 -417.604702)
		(stroke
			(width 0.07112)
			(type default)
		)
		(layer "In6.Cu")
	)
	(gr_line
		(start 52.87645 -389.352536)
		(end 52.698142 -389.352536)
		(stroke
			(width 0.07112)
			(type default)
		)
		(layer "In6.Cu")
	)
	(gr_line
		(start 52.991258 -389.467344)
		(end 52.87645 -389.352536)
		(stroke
			(width 0.07112)
			(type default)
		)
		(layer "In6.Cu")
	)
	(gr_line
		(start 53.062632 -417.604702)
		(end 53.034438 -417.795202)
		(stroke
			(width 0.07112)
			(type default)
		)
		(layer "In6.Cu")
	)
	(gr_line
		(start 53.071776 -394.539978)
		(end 53.071776 -395.241018)
		(stroke
			(width 0.07112)
			(type default)
		)
		(layer "In6.Cu")
	)
	(gr_line
		(start 53.252624 -410.030168)
		(end 52.961794 -410.320998)
		(stroke
			(width 0.07112)
			(type default)
		)
		(layer "In6.Cu")
	)
	(gr_line
		(start 53.354986 -394.541248)
		(end 53.490876 -394.677138)
		(stroke
			(width 0.07112)
			(type default)
		)
		(layer "In6.Cu")
	)
	(gr_line
		(start 53.490876 -395.103858)
		(end 53.354986 -395.239748)
		(stroke
			(width 0.07112)
			(type default)
		)
		(layer "In6.Cu")
	)
	(gr_line
		(start 53.490876 -394.677138)
		(end 53.490876 -395.103858)
		(stroke
			(width 0.07112)
			(type default)
		)
		(layer "In6.Cu")
	)
	(gr_line
		(start 53.791358 -388.774432)
		(end 53.843682 -388.826756)
		(stroke
			(width 0.07112)
			(type default)
		)
		(layer "In6.Cu")
	)
	(gr_line
		(start 53.843682 -389.006588)
		(end 53.697124 -389.153146)
		(stroke
			(width 0.07112)
			(type default)
		)
		(layer "In6.Cu")
	)
	(gr_line
		(start 53.843682 -388.826756)
		(end 53.843682 -389.006588)
		(stroke
			(width 0.07112)
			(type default)
		)
		(layer "In6.Cu")
	)
	(gr_line
		(start 53.996844 -397.954246)
		(end 54.464204 -398.421606)
		(stroke
			(width 0.07112)
			(type default)
		)
		(layer "In6.Cu")
	)
	(gr_line
		(start 54.016656 -414.193736)
		(end 54.635654 -414.524444)
		(stroke
			(width 0.07112)
			(type default)
		)
		(layer "In6.Cu")
	)
	(gr_line
		(start 54.0766 -389.352536)
		(end 53.898292 -389.352536)
		(stroke
			(width 0.07112)
			(type default)
		)
		(layer "In6.Cu")
	)
	(gr_line
		(start 54.08041 -420.032688)
		(end 54.403498 -420.655242)
		(stroke
			(width 0.07112)
			(type default)
		)
		(layer "In6.Cu")
	)
	(gr_line
		(start 54.149752 -413.944816)
		(end 54.150006 -413.944816)
		(stroke
			(width 0.07112)
			(type default)
		)
		(layer "In6.Cu")
	)
	(gr_line
		(start 54.151276 -413.944562)
		(end 54.33568 -413.888428)
		(stroke
			(width 0.07112)
			(type default)
		)
		(layer "In6.Cu")
	)
	(gr_line
		(start 54.191408 -389.467344)
		(end 54.0766 -389.352536)
		(stroke
			(width 0.07112)
			(type default)
		)
		(layer "In6.Cu")
	)
	(gr_line
		(start 54.198012 -397.754856)
		(end 54.39029 -397.754856)
		(stroke
			(width 0.07112)
			(type default)
		)
		(layer "In6.Cu")
	)
	(gr_line
		(start 54.211474 -404.17369)
		(end 53.920644 -404.46452)
		(stroke
			(width 0.07112)
			(type default)
		)
		(layer "In6.Cu")
	)
	(gr_line
		(start 54.211474 -402.749258)
		(end 54.211474 -403.409658)
		(stroke
			(width 0.07112)
			(type default)
		)
		(layer "In6.Cu")
	)
	(gr_line
		(start 54.271926 -394.805154)
		(end 54.271926 -395.506194)
		(stroke
			(width 0.07112)
			(type default)
		)
		(layer "In6.Cu")
	)
	(gr_line
		(start 54.332378 -419.903148)
		(end 54.51602 -419.961314)
		(stroke
			(width 0.07112)
			(type default)
		)
		(layer "In6.Cu")
	)
	(gr_line
		(start 54.33568 -413.888428)
		(end 54.712108 -414.089596)
		(stroke
			(width 0.07112)
			(type default)
		)
		(layer "In6.Cu")
	)
	(gr_line
		(start 54.39029 -397.754856)
		(end 54.663594 -398.02816)
		(stroke
			(width 0.07112)
			(type default)
		)
		(layer "In6.Cu")
	)
	(gr_line
		(start 54.493414 -404.17369)
		(end 54.784244 -404.46452)
		(stroke
			(width 0.07112)
			(type default)
		)
		(layer "In6.Cu")
	)
	(gr_line
		(start 54.494684 -402.750528)
		(end 54.630574 -402.886418)
		(stroke
			(width 0.07112)
			(type default)
		)
		(layer "In6.Cu")
	)
	(gr_line
		(start 54.51602 -419.961314)
		(end 54.712616 -420.340282)
		(stroke
			(width 0.07112)
			(type default)
		)
		(layer "In6.Cu")
	)
	(gr_line
		(start 54.555136 -394.806424)
		(end 54.691026 -394.942314)
		(stroke
			(width 0.07112)
			(type default)
		)
		(layer "In6.Cu")
	)
	(gr_line
		(start 54.572408 -188.439806)
		(end 54.439058 -188.306456)
		(stroke
			(width 0.07112)
			(type default)
		)
		(layer "In6.Cu")
	)
	(gr_line
		(start 54.630574 -403.272498)
		(end 54.494684 -403.408388)
		(stroke
			(width 0.07112)
			(type default)
		)
		(layer "In6.Cu")
	)
	(gr_line
		(start 54.630574 -402.886418)
		(end 54.630574 -403.272498)
		(stroke
			(width 0.07112)
			(type default)
		)
		(layer "In6.Cu")
	)
	(gr_line
		(start 54.663594 -398.02816)
		(end 54.663594 -398.220438)
		(stroke
			(width 0.07112)
			(type default)
		)
		(layer "In6.Cu")
	)
	(gr_line
		(start 54.691026 -395.369034)
		(end 54.555136 -395.504924)
		(stroke
			(width 0.07112)
			(type default)
		)
		(layer "In6.Cu")
	)
	(gr_line
		(start 54.691026 -394.942314)
		(end 54.691026 -395.369034)
		(stroke
			(width 0.07112)
			(type default)
		)
		(layer "In6.Cu")
	)
	(gr_line
		(start 54.712108 -414.089596)
		(end 54.767988 -414.274254)
		(stroke
			(width 0.07112)
			(type default)
		)
		(layer "In6.Cu")
	)
	(gr_line
		(start 54.712616 -420.340282)
		(end 54.65445 -420.523924)
		(stroke
			(width 0.07112)
			(type default)
		)
		(layer "In6.Cu")
	)
	(gr_line
		(start 54.737 -398.694402)
		(end 55.20436 -399.161762)
		(stroke
			(width 0.07112)
			(type default)
		)
		(layer "In6.Cu")
	)
	(gr_line
		(start 54.906672 -359.974134)
		(end 54.906418 -359.974134)
		(stroke
			(width 0.07112)
			(type default)
		)
		(layer "In6.Cu")
	)
	(gr_line
		(start 54.938168 -398.495012)
		(end 55.130446 -398.495012)
		(stroke
			(width 0.07112)
			(type default)
		)
		(layer "In6.Cu")
	)
	(gr_line
		(start 54.991254 -388.774432)
		(end 55.043578 -388.826756)
		(stroke
			(width 0.07112)
			(type default)
		)
		(layer "In6.Cu")
	)
	(gr_line
		(start 54.999128 -188.439806)
		(end 54.572408 -188.439806)
		(stroke
			(width 0.07112)
			(type default)
		)
		(layer "In6.Cu")
	)
	(gr_line
		(start 55.011574 -414.725612)
		(end 55.630064 -415.056066)
		(stroke
			(width 0.07112)
			(type default)
		)
		(layer "In6.Cu")
	)
	(gr_line
		(start 55.043578 -389.006588)
		(end 54.89702 -389.153146)
		(stroke
			(width 0.07112)
			(type default)
		)
		(layer "In6.Cu")
	)
	(gr_line
		(start 55.043578 -388.826756)
		(end 55.043578 -389.006588)
		(stroke
			(width 0.07112)
			(type default)
		)
		(layer "In6.Cu")
	)
	(gr_line
		(start 55.130446 -398.495012)
		(end 55.40375 -398.768316)
		(stroke
			(width 0.07112)
			(type default)
		)
		(layer "In6.Cu")
	)
	(gr_line
		(start 55.132478 -188.306456)
		(end 54.999128 -188.439806)
		(stroke
			(width 0.07112)
			(type default)
		)
		(layer "In6.Cu")
	)
	(gr_line
		(start 55.133748 -188.023246)
		(end 54.437788 -188.023246)
		(stroke
			(width 0.07112)
			(type default)
		)
		(layer "In6.Cu")
	)
	(gr_line
		(start 55.14594 -414.476184)
		(end 55.330344 -414.420304)
		(stroke
			(width 0.07112)
			(type default)
		)
		(layer "In6.Cu")
	)
	(gr_line
		(start 55.17134 -373.719344)
		(end 54.927754 -373.96293)
		(stroke
			(width 0.07112)
			(type default)
		)
		(layer "In6.Cu")
	)
	(gr_arc
		(start 55.17134 -373.719344)
		(mid 55.202781 -373.674933)
		(end 55.217568 -373.62257)
		(stroke
			(width 0.07112)
			(type default)
		)
		(layer "In6.Cu")
	)
	(gr_line
		(start 55.22468 -397.666464)
		(end 55.691786 -398.13357)
		(stroke
			(width 0.07112)
			(type default)
		)
		(layer "In6.Cu")
	)
	(gr_line
		(start 55.276496 -389.352536)
		(end 55.098188 -389.352536)
		(stroke
			(width 0.07112)
			(type default)
		)
		(layer "In6.Cu")
	)
	(gr_line
		(start 55.330344 -414.420304)
		(end 55.707026 -414.621472)
		(stroke
			(width 0.07112)
			(type default)
		)
		(layer "In6.Cu")
	)
	(gr_line
		(start 55.391304 -389.467344)
		(end 55.276496 -389.352536)
		(stroke
			(width 0.07112)
			(type default)
		)
		(layer "In6.Cu")
	)
	(gr_line
		(start 55.40375 -398.768316)
		(end 55.40375 -398.960594)
		(stroke
			(width 0.07112)
			(type default)
		)
		(layer "In6.Cu")
	)
	(gr_line
		(start 55.425848 -397.467074)
		(end 55.617872 -397.467074)
		(stroke
			(width 0.07112)
			(type default)
		)
		(layer "In6.Cu")
	)
	(gr_line
		(start 55.452264 -410.030168)
		(end 55.743094 -410.320998)
		(stroke
			(width 0.07112)
			(type default)
		)
		(layer "In6.Cu")
	)
	(gr_line
		(start 55.471822 -394.530834)
		(end 55.471822 -395.231874)
		(stroke
			(width 0.07112)
			(type default)
		)
		(layer "In6.Cu")
	)
	(gr_arc
		(start 55.50154 -373.62257)
		(mid 55.516398 -373.6749)
		(end 55.547768 -373.719344)
		(stroke
			(width 0.07112)
			(type default)
		)
		(layer "In6.Cu")
	)
	(gr_line
		(start 55.547768 -373.719344)
		(end 55.791354 -373.96293)
		(stroke
			(width 0.07112)
			(type default)
		)
		(layer "In6.Cu")
	)
	(gr_line
		(start 55.617872 -397.467074)
		(end 55.891176 -397.740378)
		(stroke
			(width 0.07112)
			(type default)
		)
		(layer "In6.Cu")
	)
	(gr_line
		(start 55.697628 -188.442346)
		(end 55.561738 -188.306456)
		(stroke
			(width 0.07112)
			(type default)
		)
		(layer "In6.Cu")
	)
	(gr_line
		(start 55.707026 -414.621472)
		(end 55.762652 -414.805876)
		(stroke
			(width 0.07112)
			(type default)
		)
		(layer "In6.Cu")
	)
	(gr_line
		(start 55.743094 -411.248606)
		(end 55.743094 -411.949646)
		(stroke
			(width 0.07112)
			(type default)
		)
		(layer "In6.Cu")
	)
	(gr_line
		(start 55.755032 -394.532104)
		(end 55.890922 -394.667994)
		(stroke
			(width 0.07112)
			(type default)
		)
		(layer "In6.Cu")
	)
	(gr_line
		(start 55.890922 -395.094714)
		(end 55.755032 -395.230604)
		(stroke
			(width 0.07112)
			(type default)
		)
		(layer "In6.Cu")
	)
	(gr_line
		(start 55.890922 -394.667994)
		(end 55.890922 -395.094714)
		(stroke
			(width 0.07112)
			(type default)
		)
		(layer "In6.Cu")
	)
	(gr_line
		(start 55.891176 -397.740378)
		(end 55.891176 -397.932402)
		(stroke
			(width 0.07112)
			(type default)
		)
		(layer "In6.Cu")
	)
	(gr_line
		(start 55.964582 -398.406366)
		(end 56.431942 -398.873726)
		(stroke
			(width 0.07112)
			(type default)
		)
		(layer "In6.Cu")
	)
	(gr_line
		(start 56.026304 -411.249876)
		(end 56.162194 -411.385766)
		(stroke
			(width 0.07112)
			(type default)
		)
		(layer "In6.Cu")
	)
	(gr_line
		(start 56.124348 -188.442346)
		(end 55.697628 -188.442346)
		(stroke
			(width 0.07112)
			(type default)
		)
		(layer "In6.Cu")
	)
	(gr_line
		(start 56.162194 -411.812486)
		(end 56.026304 -411.948376)
		(stroke
			(width 0.07112)
			(type default)
		)
		(layer "In6.Cu")
	)
	(gr_line
		(start 56.162194 -411.385766)
		(end 56.162194 -411.812486)
		(stroke
			(width 0.07112)
			(type default)
		)
		(layer "In6.Cu")
	)
	(gr_line
		(start 56.16575 -398.206976)
		(end 56.358028 -398.206976)
		(stroke
			(width 0.07112)
			(type default)
		)
		(layer "In6.Cu")
	)
	(gr_line
		(start 56.191404 -388.774432)
		(end 56.243728 -388.826756)
		(stroke
			(width 0.07112)
			(type default)
		)
		(layer "In6.Cu")
	)
	(gr_line
		(start 56.220868 -415.371788)
		(end 56.839358 -415.702496)
		(stroke
			(width 0.07112)
			(type default)
		)
		(layer "In6.Cu")
	)
	(gr_line
		(start 56.243728 -389.019796)
		(end 56.110378 -389.153146)
		(stroke
			(width 0.07112)
			(type default)
		)
		(layer "In6.Cu")
	)
	(gr_line
		(start 56.243728 -388.826756)
		(end 56.243728 -389.019796)
		(stroke
			(width 0.07112)
			(type default)
		)
		(layer "In6.Cu")
	)
	(gr_line
		(start 56.260238 -188.306456)
		(end 56.124348 -188.442346)
		(stroke
			(width 0.07112)
			(type default)
		)
		(layer "In6.Cu")
	)
	(gr_line
		(start 56.261508 -188.023246)
		(end 55.560468 -188.023246)
		(stroke
			(width 0.07112)
			(type default)
		)
		(layer "In6.Cu")
	)
	(gr_line
		(start 56.315864 -410.030168)
		(end 56.025034 -410.320998)
		(stroke
			(width 0.07112)
			(type default)
		)
		(layer "In6.Cu")
	)
	(gr_line
		(start 56.355234 -415.122614)
		(end 56.539638 -415.06648)
		(stroke
			(width 0.07112)
			(type default)
		)
		(layer "In6.Cu")
	)
	(gr_line
		(start 56.358028 -398.206976)
		(end 56.631332 -398.48028)
		(stroke
			(width 0.07112)
			(type default)
		)
		(layer "In6.Cu")
	)
	(gr_line
		(start 56.476392 -389.352536)
		(end 56.311546 -389.352536)
		(stroke
			(width 0.07112)
			(type default)
		)
		(layer "In6.Cu")
	)
	(gr_line
		(start 56.539638 -415.06648)
		(end 56.91632 -415.267648)
		(stroke
			(width 0.07112)
			(type default)
		)
		(layer "In6.Cu")
	)
	(gr_line
		(start 56.5912 -389.467344)
		(end 56.476392 -389.352536)
		(stroke
			(width 0.07112)
			(type default)
		)
		(layer "In6.Cu")
	)
	(gr_line
		(start 56.631332 -398.48028)
		(end 56.631332 -398.672558)
		(stroke
			(width 0.07112)
			(type default)
		)
		(layer "In6.Cu")
	)
	(gr_line
		(start 56.671972 -394.504418)
		(end 56.671972 -395.205458)
		(stroke
			(width 0.07112)
			(type default)
		)
		(layer "In6.Cu")
	)
	(gr_line
		(start 56.818022 -414.115504)
		(end 57.400952 -414.50514)
		(stroke
			(width 0.07112)
			(type default)
		)
		(layer "In6.Cu")
	)
	(gr_line
		(start 56.825388 -188.442346)
		(end 56.689498 -188.306456)
		(stroke
			(width 0.07112)
			(type default)
		)
		(layer "In6.Cu")
	)
	(gr_line
		(start 56.839358 -415.702496)
		(end 56.839358 -415.702242)
		(stroke
			(width 0.07112)
			(type default)
		)
		(layer "In6.Cu")
	)
	(gr_line
		(start 56.91632 -415.267648)
		(end 56.971946 -415.452306)
		(stroke
			(width 0.07112)
			(type default)
		)
		(layer "In6.Cu")
	)
	(gr_line
		(start 56.920384 -371.2083)
		(end 56.629554 -371.49913)
		(stroke
			(width 0.07112)
			(type default)
		)
		(layer "In6.Cu")
	)
	(gr_line
		(start 56.955182 -394.505688)
		(end 57.091072 -394.641578)
		(stroke
			(width 0.07112)
			(type default)
		)
		(layer "In6.Cu")
	)
	(gr_line
		(start 56.976264 -413.880808)
		(end 57.164986 -413.843216)
		(stroke
			(width 0.07112)
			(type default)
		)
		(layer "In6.Cu")
	)
	(gr_line
		(start 57.091072 -395.068298)
		(end 56.955182 -395.204188)
		(stroke
			(width 0.07112)
			(type default)
		)
		(layer "In6.Cu")
	)
	(gr_line
		(start 57.091072 -394.641578)
		(end 57.091072 -395.068298)
		(stroke
			(width 0.07112)
			(type default)
		)
		(layer "In6.Cu")
	)
	(gr_line
		(start 57.164986 -413.843216)
		(end 57.519824 -414.080452)
		(stroke
			(width 0.07112)
			(type default)
		)
		(layer "In6.Cu")
	)
	(gr_line
		(start 57.202324 -371.2083)
		(end 57.493154 -371.49913)
		(stroke
			(width 0.07112)
			(type default)
		)
		(layer "In6.Cu")
	)
	(gr_line
		(start 57.252108 -188.442346)
		(end 56.825388 -188.442346)
		(stroke
			(width 0.07112)
			(type default)
		)
		(layer "In6.Cu")
	)
	(gr_line
		(start 57.274714 -404.17369)
		(end 56.983884 -404.46452)
		(stroke
			(width 0.07112)
			(type default)
		)
		(layer "In6.Cu")
	)
	(gr_line
		(start 57.274714 -402.860256)
		(end 57.274714 -403.520656)
		(stroke
			(width 0.07112)
			(type default)
		)
		(layer "In6.Cu")
	)
	(gr_line
		(start 57.387998 -188.306456)
		(end 57.252108 -188.442346)
		(stroke
			(width 0.07112)
			(type default)
		)
		(layer "In6.Cu")
	)
	(gr_line
		(start 57.389268 -188.023246)
		(end 56.688228 -188.023246)
		(stroke
			(width 0.07112)
			(type default)
		)
		(layer "In6.Cu")
	)
	(gr_line
		(start 57.3913 -388.774432)
		(end 57.443624 -388.826756)
		(stroke
			(width 0.07112)
			(type default)
		)
		(layer "In6.Cu")
	)
	(gr_line
		(start 57.409842 -414.510982)
		(end 57.755536 -414.742122)
		(stroke
			(width 0.07112)
			(type default)
		)
		(layer "In6.Cu")
	)
	(gr_line
		(start 57.443624 -389.006588)
		(end 57.297066 -389.153146)
		(stroke
			(width 0.07112)
			(type default)
		)
		(layer "In6.Cu")
	)
	(gr_line
		(start 57.443624 -388.826756)
		(end 57.443624 -389.006588)
		(stroke
			(width 0.07112)
			(type default)
		)
		(layer "In6.Cu")
	)
	(gr_line
		(start 57.519824 -414.080452)
		(end 57.557416 -414.26892)
		(stroke
			(width 0.07112)
			(type default)
		)
		(layer "In6.Cu")
	)
	(gr_line
		(start 57.556654 -404.17369)
		(end 57.847484 -404.46452)
		(stroke
			(width 0.07112)
			(type default)
		)
		(layer "In6.Cu")
	)
	(gr_line
		(start 57.557924 -402.861526)
		(end 57.693814 -402.997416)
		(stroke
			(width 0.07112)
			(type default)
		)
		(layer "In6.Cu")
	)
	(gr_line
		(start 57.56656 -414.27654)
		(end 57.912254 -414.50768)
		(stroke
			(width 0.07112)
			(type default)
		)
		(layer "In6.Cu")
	)
	(gr_line
		(start 57.676542 -389.352536)
		(end 57.498234 -389.352536)
		(stroke
			(width 0.07112)
			(type default)
		)
		(layer "In6.Cu")
	)
	(gr_line
		(start 57.693814 -403.383496)
		(end 57.557924 -403.519386)
		(stroke
			(width 0.07112)
			(type default)
		)
		(layer "In6.Cu")
	)
	(gr_line
		(start 57.693814 -402.997416)
		(end 57.693814 -403.383496)
		(stroke
			(width 0.07112)
			(type default)
		)
		(layer "In6.Cu")
	)
	(gr_line
		(start 57.755536 -414.742122)
		(end 58.33872 -415.131758)
		(stroke
			(width 0.07112)
			(type default)
		)
		(layer "In6.Cu")
	)
	(gr_line
		(start 57.79135 -389.467344)
		(end 57.676542 -389.352536)
		(stroke
			(width 0.07112)
			(type default)
		)
		(layer "In6.Cu")
	)
	(gr_line
		(start 57.843674 -394.495782)
		(end 57.843674 -395.196822)
		(stroke
			(width 0.07112)
			(type default)
		)
		(layer "In6.Cu")
	)
	(gr_line
		(start 57.914032 -414.507426)
		(end 58.1025 -414.469834)
		(stroke
			(width 0.07112)
			(type default)
		)
		(layer "In6.Cu")
	)
	(gr_line
		(start 57.953148 -188.442346)
		(end 57.817258 -188.306456)
		(stroke
			(width 0.07112)
			(type default)
		)
		(layer "In6.Cu")
	)
	(gr_line
		(start 58.1025 -414.469834)
		(end 58.457592 -414.70707)
		(stroke
			(width 0.07112)
			(type default)
		)
		(layer "In6.Cu")
	)
	(gr_line
		(start 58.126884 -394.497052)
		(end 58.262774 -394.632942)
		(stroke
			(width 0.07112)
			(type default)
		)
		(layer "In6.Cu")
	)
	(gr_line
		(start 58.262774 -395.059662)
		(end 58.126884 -395.195552)
		(stroke
			(width 0.07112)
			(type default)
		)
		(layer "In6.Cu")
	)
	(gr_line
		(start 58.262774 -394.632942)
		(end 58.262774 -395.059662)
		(stroke
			(width 0.07112)
			(type default)
		)
		(layer "In6.Cu")
	)
	(gr_line
		(start 58.379868 -188.442346)
		(end 57.953148 -188.442346)
		(stroke
			(width 0.07112)
			(type default)
		)
		(layer "In6.Cu")
	)
	(gr_line
		(start 58.457592 -414.70707)
		(end 58.495184 -414.895538)
		(stroke
			(width 0.07112)
			(type default)
		)
		(layer "In6.Cu")
	)
	(gr_line
		(start 58.515504 -410.030168)
		(end 58.806334 -410.320998)
		(stroke
			(width 0.07112)
			(type default)
		)
		(layer "In6.Cu")
	)
	(gr_line
		(start 58.515758 -188.306456)
		(end 58.379868 -188.442346)
		(stroke
			(width 0.07112)
			(type default)
		)
		(layer "In6.Cu")
	)
	(gr_line
		(start 58.517028 -188.023246)
		(end 57.815988 -188.023246)
		(stroke
			(width 0.07112)
			(type default)
		)
		(layer "In6.Cu")
	)
	(gr_line
		(start 58.522616 -426.830998)
		(end 58.64987 -426.958252)
		(stroke
			(width 0.07112)
			(type default)
		)
		(layer "In6.Cu")
	)
	(gr_line
		(start 58.522616 -426.548804)
		(end 58.64987 -426.42155)
		(stroke
			(width 0.07112)
			(type default)
		)
		(layer "In6.Cu")
	)
	(gr_line
		(start 58.541666 -415.267394)
		(end 58.693304 -415.36874)
		(stroke
			(width 0.07112)
			(type default)
		)
		(layer "In6.Cu")
	)
	(gr_line
		(start 58.591196 -388.774432)
		(end 58.64352 -388.826756)
		(stroke
			(width 0.07112)
			(type default)
		)
		(layer "In6.Cu")
	)
	(gr_line
		(start 58.622184 -368.7445)
		(end 58.331354 -369.03533)
		(stroke
			(width 0.07112)
			(type default)
		)
		(layer "In6.Cu")
	)
	(gr_line
		(start 58.64352 -389.006588)
		(end 58.496962 -389.153146)
		(stroke
			(width 0.07112)
			(type default)
		)
		(layer "In6.Cu")
	)
	(gr_line
		(start 58.64352 -388.826756)
		(end 58.64352 -389.006588)
		(stroke
			(width 0.07112)
			(type default)
		)
		(layer "In6.Cu")
	)
	(gr_line
		(start 58.64987 -426.958252)
		(end 58.64987 -427.289976)
		(stroke
			(width 0.07112)
			(type default)
		)
		(layer "In6.Cu")
	)
	(gr_line
		(start 58.64987 -426.42155)
		(end 58.64987 -426.089826)
		(stroke
			(width 0.07112)
			(type default)
		)
		(layer "In6.Cu")
	)
	(gr_line
		(start 58.693304 -415.36874)
		(end 59.276488 -415.758376)
		(stroke
			(width 0.07112)
			(type default)
		)
		(layer "In6.Cu")
	)
	(gr_line
		(start 58.698384 -415.032952)
		(end 58.850022 -415.134298)
		(stroke
			(width 0.07112)
			(type default)
		)
		(layer "In6.Cu")
	)
	(gr_line
		(start 58.8518 -415.134044)
		(end 59.040268 -415.096452)
		(stroke
			(width 0.07112)
			(type default)
		)
		(layer "In6.Cu")
	)
	(gr_line
		(start 58.876438 -389.352536)
		(end 58.69813 -389.352536)
		(stroke
			(width 0.07112)
			(type default)
		)
		(layer "In6.Cu")
	)
	(gr_line
		(start 58.904124 -368.7445)
		(end 59.194954 -369.03533)
		(stroke
			(width 0.07112)
			(type default)
		)
		(layer "In6.Cu")
	)
	(gr_line
		(start 58.991246 -389.467344)
		(end 58.876438 -389.352536)
		(stroke
			(width 0.07112)
			(type default)
		)
		(layer "In6.Cu")
	)
	(gr_line
		(start 59.040268 -415.096452)
		(end 59.39536 -415.333688)
		(stroke
			(width 0.07112)
			(type default)
		)
		(layer "In6.Cu")
	)
	(gr_line
		(start 59.379104 -410.030168)
		(end 59.088274 -410.320998)
		(stroke
			(width 0.07112)
			(type default)
		)
		(layer "In6.Cu")
	)
	(gr_line
		(start 59.39536 -415.333688)
		(end 59.432952 -415.522156)
		(stroke
			(width 0.07112)
			(type default)
		)
		(layer "In6.Cu")
	)
	(gr_line
		(start 59.631072 -415.995358)
		(end 60.214256 -416.384994)
		(stroke
			(width 0.07112)
			(type default)
		)
		(layer "In6.Cu")
	)
	(gr_line
		(start 59.732672 -414.092898)
		(end 60.249308 -414.567116)
		(stroke
			(width 0.07112)
			(type default)
		)
		(layer "In6.Cu")
	)
	(gr_line
		(start 59.752738 -359.997502)
		(end 59.752738 -359.997756)
		(stroke
			(width 0.07112)
			(type default)
		)
		(layer "In6.Cu")
	)
	(gr_line
		(start 59.789568 -415.760662)
		(end 59.978036 -415.72307)
		(stroke
			(width 0.07112)
			(type default)
		)
		(layer "In6.Cu")
	)
	(gr_line
		(start 59.791346 -388.774432)
		(end 59.84367 -388.826756)
		(stroke
			(width 0.07112)
			(type default)
		)
		(layer "In6.Cu")
	)
	(gr_line
		(start 59.84367 -389.006588)
		(end 59.697112 -389.153146)
		(stroke
			(width 0.07112)
			(type default)
		)
		(layer "In6.Cu")
	)
	(gr_line
		(start 59.84367 -388.826756)
		(end 59.84367 -389.006588)
		(stroke
			(width 0.07112)
			(type default)
		)
		(layer "In6.Cu")
	)
	(gr_line
		(start 59.92495 -413.885126)
		(end 60.117228 -413.876744)
		(stroke
			(width 0.07112)
			(type default)
		)
		(layer "In6.Cu")
	)
	(gr_line
		(start 59.978036 -415.72307)
		(end 60.333128 -415.960306)
		(stroke
			(width 0.07112)
			(type default)
		)
		(layer "In6.Cu")
	)
	(gr_line
		(start 60.076588 -389.352536)
		(end 59.89828 -389.352536)
		(stroke
			(width 0.07112)
			(type default)
		)
		(layer "In6.Cu")
	)
	(gr_line
		(start 60.117228 -413.876744)
		(end 60.43168 -414.165542)
		(stroke
			(width 0.07112)
			(type default)
		)
		(layer "In6.Cu")
	)
	(gr_line
		(start 60.191396 -389.467344)
		(end 60.076588 -389.352536)
		(stroke
			(width 0.07112)
			(type default)
		)
		(layer "In6.Cu")
	)
	(gr_line
		(start 60.333128 -415.960306)
		(end 60.37072 -416.148774)
		(stroke
			(width 0.07112)
			(type default)
		)
		(layer "In6.Cu")
	)
	(gr_line
		(start 60.337954 -404.17369)
		(end 60.047124 -404.46452)
		(stroke
			(width 0.07112)
			(type default)
		)
		(layer "In6.Cu")
	)
	(gr_line
		(start 60.43168 -414.165542)
		(end 60.440062 -414.357566)
		(stroke
			(width 0.07112)
			(type default)
		)
		(layer "In6.Cu")
	)
	(gr_line
		(start 60.522612 -427.830742)
		(end 60.649866 -427.957996)
		(stroke
			(width 0.07112)
			(type default)
		)
		(layer "In6.Cu")
	)
	(gr_line
		(start 60.522612 -427.548802)
		(end 60.649866 -427.421548)
		(stroke
			(width 0.07112)
			(type default)
		)
		(layer "In6.Cu")
	)
	(gr_line
		(start 60.563506 -414.855406)
		(end 61.080396 -415.329878)
		(stroke
			(width 0.07112)
			(type default)
		)
		(layer "In6.Cu")
	)
	(gr_line
		(start 60.619894 -404.17369)
		(end 60.910724 -404.46452)
		(stroke
			(width 0.07112)
			(type default)
		)
		(layer "In6.Cu")
	)
	(gr_line
		(start 60.649866 -427.957996)
		(end 60.649866 -428.28972)
		(stroke
			(width 0.07112)
			(type default)
		)
		(layer "In6.Cu")
	)
	(gr_line
		(start 60.649866 -427.421548)
		(end 60.649866 -427.089824)
		(stroke
			(width 0.07112)
			(type default)
		)
		(layer "In6.Cu")
	)
	(gr_line
		(start 60.755784 -414.647634)
		(end 60.948062 -414.639506)
		(stroke
			(width 0.07112)
			(type default)
		)
		(layer "In6.Cu")
	)
	(gr_line
		(start 60.869576 -187.164218)
		(end 60.831984 -186.97575)
		(stroke
			(width 0.07112)
			(type default)
		)
		(layer "In6.Cu")
	)
	(gr_line
		(start 60.948062 -414.639506)
		(end 61.262768 -414.928304)
		(stroke
			(width 0.07112)
			(type default)
		)
		(layer "In6.Cu")
	)
	(gr_line
		(start 60.991242 -389.100568)
		(end 60.936886 -389.154924)
		(stroke
			(width 0.07112)
			(type default)
		)
		(layer "In6.Cu")
	)
	(gr_line
		(start 60.991242 -388.774432)
		(end 60.991242 -389.100568)
		(stroke
			(width 0.07112)
			(type default)
		)
		(layer "In6.Cu")
	)
	(gr_line
		(start 61.224668 -187.401454)
		(end 60.869576 -187.164218)
		(stroke
			(width 0.07112)
			(type default)
		)
		(layer "In6.Cu")
	)
	(gr_line
		(start 61.262768 -414.928304)
		(end 61.27115 -415.120328)
		(stroke
			(width 0.07112)
			(type default)
		)
		(layer "In6.Cu")
	)
	(gr_line
		(start 61.278262 -389.354314)
		(end 61.1378 -389.354314)
		(stroke
			(width 0.07112)
			(type default)
		)
		(layer "In6.Cu")
	)
	(gr_line
		(start 61.391292 -389.467344)
		(end 61.278262 -389.354314)
		(stroke
			(width 0.07112)
			(type default)
		)
		(layer "In6.Cu")
	)
	(gr_line
		(start 61.394594 -415.618168)
		(end 61.911484 -416.09264)
		(stroke
			(width 0.07112)
			(type default)
		)
		(layer "In6.Cu")
	)
	(gr_line
		(start 61.413136 -187.363862)
		(end 61.224668 -187.401454)
		(stroke
			(width 0.07112)
			(type default)
		)
		(layer "In6.Cu")
	)
	(gr_line
		(start 61.571632 -187.129166)
		(end 60.988448 -186.73953)
		(stroke
			(width 0.07112)
			(type default)
		)
		(layer "In6.Cu")
	)
	(gr_line
		(start 61.578744 -410.030168)
		(end 61.869574 -410.320998)
		(stroke
			(width 0.07112)
			(type default)
		)
		(layer "In6.Cu")
	)
	(gr_line
		(start 61.586872 -415.410396)
		(end 61.77915 -415.402268)
		(stroke
			(width 0.07112)
			(type default)
		)
		(layer "In6.Cu")
	)
	(gr_line
		(start 61.634624 -187.17133)
		(end 61.571632 -187.129166)
		(stroke
			(width 0.07112)
			(type default)
		)
		(layer "In6.Cu")
	)
	(gr_line
		(start 61.77915 -415.402268)
		(end 62.093856 -415.691066)
		(stroke
			(width 0.07112)
			(type default)
		)
		(layer "In6.Cu")
	)
	(gr_line
		(start 61.807344 -187.790836)
		(end 61.769752 -187.602368)
		(stroke
			(width 0.07112)
			(type default)
		)
		(layer "In6.Cu")
	)
	(gr_line
		(start 61.869574 -411.125924)
		(end 61.869574 -411.826964)
		(stroke
			(width 0.07112)
			(type default)
		)
		(layer "In6.Cu")
	)
	(gr_line
		(start 61.883544 -395.955012)
		(end 62.379606 -396.451074)
		(stroke
			(width 0.07112)
			(type default)
		)
		(layer "In6.Cu")
	)
	(gr_line
		(start 61.97854 -373.719344)
		(end 61.734954 -373.96293)
		(stroke
			(width 0.07112)
			(type default)
		)
		(layer "In6.Cu")
	)
	(gr_arc
		(start 61.97854 -373.719344)
		(mid 62.009981 -373.674933)
		(end 62.024768 -373.62257)
		(stroke
			(width 0.07112)
			(type default)
		)
		(layer "In6.Cu")
	)
	(gr_line
		(start 62.084712 -395.755622)
		(end 62.27699 -395.755622)
		(stroke
			(width 0.07112)
			(type default)
		)
		(layer "In6.Cu")
	)
	(gr_line
		(start 62.093856 -415.691066)
		(end 62.102238 -415.88309)
		(stroke
			(width 0.07112)
			(type default)
		)
		(layer "In6.Cu")
	)
	(gr_line
		(start 62.152784 -411.127194)
		(end 62.288674 -411.263084)
		(stroke
			(width 0.07112)
			(type default)
		)
		(layer "In6.Cu")
	)
	(gr_line
		(start 62.162436 -188.028072)
		(end 61.807344 -187.790836)
		(stroke
			(width 0.07112)
			(type default)
		)
		(layer "In6.Cu")
	)
	(gr_line
		(start 62.191392 -388.774432)
		(end 62.243716 -388.826756)
		(stroke
			(width 0.07112)
			(type default)
		)
		(layer "In6.Cu")
	)
	(gr_line
		(start 62.243716 -389.023352)
		(end 62.113922 -389.153146)
		(stroke
			(width 0.07112)
			(type default)
		)
		(layer "In6.Cu")
	)
	(gr_line
		(start 62.243716 -388.826756)
		(end 62.243716 -389.023352)
		(stroke
			(width 0.07112)
			(type default)
		)
		(layer "In6.Cu")
	)
	(gr_line
		(start 62.27699 -395.755622)
		(end 62.578996 -396.057628)
		(stroke
			(width 0.07112)
			(type default)
		)
		(layer "In6.Cu")
	)
	(gr_line
		(start 62.288674 -411.689804)
		(end 62.152784 -411.825694)
		(stroke
			(width 0.07112)
			(type default)
		)
		(layer "In6.Cu")
	)
	(gr_line
		(start 62.288674 -411.263084)
		(end 62.288674 -411.689804)
		(stroke
			(width 0.07112)
			(type default)
		)
		(layer "In6.Cu")
	)
	(gr_arc
		(start 62.30874 -373.62257)
		(mid 62.323598 -373.6749)
		(end 62.354968 -373.719344)
		(stroke
			(width 0.07112)
			(type default)
		)
		(layer "In6.Cu")
	)
	(gr_line
		(start 62.350904 -187.99048)
		(end 62.162436 -188.028072)
		(stroke
			(width 0.07112)
			(type default)
		)
		(layer "In6.Cu")
	)
	(gr_line
		(start 62.354968 -373.719344)
		(end 62.598554 -373.96293)
		(stroke
			(width 0.07112)
			(type default)
		)
		(layer "In6.Cu")
	)
	(gr_line
		(start 62.442344 -410.030168)
		(end 62.151514 -410.320998)
		(stroke
			(width 0.07112)
			(type default)
		)
		(layer "In6.Cu")
	)
	(gr_line
		(start 62.47638 -389.352536)
		(end 62.31509 -389.352536)
		(stroke
			(width 0.07112)
			(type default)
		)
		(layer "In6.Cu")
	)
	(gr_line
		(start 62.5094 -187.755784)
		(end 61.926216 -187.366148)
		(stroke
			(width 0.07112)
			(type default)
		)
		(layer "In6.Cu")
	)
	(gr_line
		(start 62.522608 -426.830998)
		(end 62.649862 -426.958252)
		(stroke
			(width 0.07112)
			(type default)
		)
		(layer "In6.Cu")
	)
	(gr_line
		(start 62.522608 -426.548804)
		(end 62.649862 -426.42155)
		(stroke
			(width 0.07112)
			(type default)
		)
		(layer "In6.Cu")
	)
	(gr_line
		(start 62.578996 -396.057628)
		(end 62.578996 -396.249906)
		(stroke
			(width 0.07112)
			(type default)
		)
		(layer "In6.Cu")
	)
	(gr_line
		(start 62.591188 -389.467344)
		(end 62.47638 -389.352536)
		(stroke
			(width 0.07112)
			(type default)
		)
		(layer "In6.Cu")
	)
	(gr_line
		(start 62.649862 -426.958252)
		(end 62.649862 -427.289976)
		(stroke
			(width 0.07112)
			(type default)
		)
		(layer "In6.Cu")
	)
	(gr_line
		(start 62.649862 -426.42155)
		(end 62.649862 -426.089826)
		(stroke
			(width 0.07112)
			(type default)
		)
		(layer "In6.Cu")
	)
	(gr_line
		(start 62.73927 -414.148524)
		(end 63.185802 -414.68929)
		(stroke
			(width 0.07112)
			(type default)
		)
		(layer "In6.Cu")
	)
	(gr_line
		(start 62.745112 -188.417454)
		(end 62.70752 -188.228986)
		(stroke
			(width 0.07112)
			(type default)
		)
		(layer "In6.Cu")
	)
	(gr_line
		(start 62.958218 -413.9692)
		(end 63.149988 -413.987488)
		(stroke
			(width 0.07112)
			(type default)
		)
		(layer "In6.Cu")
	)
	(gr_line
		(start 63.055754 -395.350492)
		(end 63.551816 -395.846554)
		(stroke
			(width 0.07112)
			(type default)
		)
		(layer "In6.Cu")
	)
	(gr_line
		(start 63.100204 -188.65469)
		(end 62.745112 -188.417454)
		(stroke
			(width 0.07112)
			(type default)
		)
		(layer "In6.Cu")
	)
	(gr_line
		(start 63.149988 -413.987488)
		(end 63.421768 -414.316672)
		(stroke
			(width 0.07112)
			(type default)
		)
		(layer "In6.Cu")
	)
	(gr_line
		(start 63.256922 -395.151102)
		(end 63.4492 -395.151102)
		(stroke
			(width 0.07112)
			(type default)
		)
		(layer "In6.Cu")
	)
	(gr_line
		(start 63.288672 -188.617098)
		(end 63.100204 -188.65469)
		(stroke
			(width 0.07112)
			(type default)
		)
		(layer "In6.Cu")
	)
	(gr_line
		(start 63.391288 -388.774432)
		(end 63.443612 -388.826756)
		(stroke
			(width 0.07112)
			(type default)
		)
		(layer "In6.Cu")
	)
	(gr_line
		(start 63.401194 -404.17369)
		(end 63.110364 -404.46452)
		(stroke
			(width 0.07112)
			(type default)
		)
		(layer "In6.Cu")
	)
	(gr_line
		(start 63.421768 -414.316672)
		(end 63.403734 -414.508188)
		(stroke
			(width 0.07112)
			(type default)
		)
		(layer "In6.Cu")
	)
	(gr_line
		(start 63.443612 -389.006588)
		(end 63.297054 -389.153146)
		(stroke
			(width 0.07112)
			(type default)
		)
		(layer "In6.Cu")
	)
	(gr_line
		(start 63.443612 -388.826756)
		(end 63.443612 -389.006588)
		(stroke
			(width 0.07112)
			(type default)
		)
		(layer "In6.Cu")
	)
	(gr_line
		(start 63.447168 -188.382402)
		(end 62.863984 -187.992766)
		(stroke
			(width 0.07112)
			(type default)
		)
		(layer "In6.Cu")
	)
	(gr_line
		(start 63.4492 -395.151102)
		(end 63.751206 -395.453108)
		(stroke
			(width 0.07112)
			(type default)
		)
		(layer "In6.Cu")
	)
	(gr_line
		(start 63.457582 -415.01822)
		(end 63.904114 -415.558986)
		(stroke
			(width 0.07112)
			(type default)
		)
		(layer "In6.Cu")
	)
	(gr_line
		(start 63.67653 -414.838896)
		(end 63.8683 -414.85693)
		(stroke
			(width 0.07112)
			(type default)
		)
		(layer "In6.Cu")
	)
	(gr_line
		(start 63.67653 -389.352536)
		(end 63.498222 -389.352536)
		(stroke
			(width 0.07112)
			(type default)
		)
		(layer "In6.Cu")
	)
	(gr_line
		(start 63.683134 -404.17369)
		(end 63.973964 -404.46452)
		(stroke
			(width 0.07112)
			(type default)
		)
		(layer "In6.Cu")
	)
	(gr_line
		(start 63.727584 -371.2083)
		(end 63.436754 -371.49913)
		(stroke
			(width 0.07112)
			(type default)
		)
		(layer "In6.Cu")
	)
	(gr_line
		(start 63.751206 -395.453108)
		(end 63.751206 -395.645386)
		(stroke
			(width 0.07112)
			(type default)
		)
		(layer "In6.Cu")
	)
	(gr_line
		(start 63.78702 -402.273516)
		(end 64.400684 -402.51888)
		(stroke
			(width 0.07112)
			(type default)
		)
		(layer "In6.Cu")
	)
	(gr_line
		(start 63.791338 -389.467344)
		(end 63.67653 -389.352536)
		(stroke
			(width 0.07112)
			(type default)
		)
		(layer "In6.Cu")
	)
	(gr_line
		(start 63.8683 -414.85693)
		(end 64.14008 -415.186368)
		(stroke
			(width 0.07112)
			(type default)
		)
		(layer "In6.Cu")
	)
	(gr_line
		(start 63.893192 -402.01088)
		(end 64.07023 -401.935188)
		(stroke
			(width 0.07112)
			(type default)
		)
		(layer "In6.Cu")
	)
	(gr_line
		(start 64.009524 -371.2083)
		(end 64.300354 -371.49913)
		(stroke
			(width 0.07112)
			(type default)
		)
		(layer "In6.Cu")
	)
	(gr_line
		(start 64.07023 -401.935188)
		(end 64.428878 -402.078444)
		(stroke
			(width 0.07112)
			(type default)
		)
		(layer "In6.Cu")
	)
	(gr_line
		(start 64.14008 -415.186368)
		(end 64.122046 -415.377884)
		(stroke
			(width 0.07112)
			(type default)
		)
		(layer "In6.Cu")
	)
	(gr_line
		(start 64.175894 -415.887916)
		(end 64.62268 -416.428682)
		(stroke
			(width 0.07112)
			(type default)
		)
		(layer "In6.Cu")
	)
	(gr_line
		(start 64.395096 -415.708592)
		(end 64.586612 -415.726626)
		(stroke
			(width 0.07112)
			(type default)
		)
		(layer "In6.Cu")
	)
	(gr_line
		(start 64.428878 -402.078444)
		(end 64.50457 -402.255482)
		(stroke
			(width 0.07112)
			(type default)
		)
		(layer "In6.Cu")
	)
	(gr_line
		(start 64.50838 -361.398312)
		(end 64.508126 -361.398312)
		(stroke
			(width 0.07112)
			(type default)
		)
		(layer "In6.Cu")
	)
	(gr_line
		(start 64.522604 -427.830742)
		(end 64.649858 -427.957996)
		(stroke
			(width 0.07112)
			(type default)
		)
		(layer "In6.Cu")
	)
	(gr_line
		(start 64.522604 -427.548802)
		(end 64.649858 -427.421548)
		(stroke
			(width 0.07112)
			(type default)
		)
		(layer "In6.Cu")
	)
	(gr_line
		(start 64.586612 -415.726626)
		(end 64.858646 -416.05581)
		(stroke
			(width 0.07112)
			(type default)
		)
		(layer "In6.Cu")
	)
	(gr_line
		(start 64.591438 -388.774432)
		(end 64.63665 -388.819644)
		(stroke
			(width 0.07112)
			(type default)
		)
		(layer "In6.Cu")
	)
	(gr_line
		(start 64.63665 -388.999476)
		(end 64.48298 -389.153146)
		(stroke
			(width 0.07112)
			(type default)
		)
		(layer "In6.Cu")
	)
	(gr_line
		(start 64.63665 -388.819644)
		(end 64.63665 -388.999476)
		(stroke
			(width 0.07112)
			(type default)
		)
		(layer "In6.Cu")
	)
	(gr_line
		(start 64.641984 -410.030168)
		(end 64.932814 -410.320998)
		(stroke
			(width 0.07112)
			(type default)
		)
		(layer "In6.Cu")
	)
	(gr_line
		(start 64.649858 -427.957996)
		(end 64.649858 -428.28972)
		(stroke
			(width 0.07112)
			(type default)
		)
		(layer "In6.Cu")
	)
	(gr_line
		(start 64.649858 -427.421548)
		(end 64.649858 -427.089824)
		(stroke
			(width 0.07112)
			(type default)
		)
		(layer "In6.Cu")
	)
	(gr_line
		(start 64.759078 -402.66239)
		(end 65.372488 -402.907754)
		(stroke
			(width 0.07112)
			(type default)
		)
		(layer "In6.Cu")
	)
	(gr_line
		(start 64.79159 -362.3056)
		(end 64.791336 -362.3056)
		(stroke
			(width 0.07112)
			(type default)
		)
		(layer "In6.Cu")
	)
	(gr_line
		(start 64.858646 -416.05581)
		(end 64.840358 -416.247326)
		(stroke
			(width 0.07112)
			(type default)
		)
		(layer "In6.Cu")
	)
	(gr_line
		(start 64.864996 -402.399754)
		(end 65.042034 -402.323808)
		(stroke
			(width 0.07112)
			(type default)
		)
		(layer "In6.Cu")
	)
	(gr_line
		(start 64.876426 -389.352536)
		(end 64.684148 -389.352536)
		(stroke
			(width 0.07112)
			(type default)
		)
		(layer "In6.Cu")
	)
	(gr_line
		(start 64.894206 -416.757358)
		(end 65.340992 -417.298378)
		(stroke
			(width 0.07112)
			(type default)
		)
		(layer "In6.Cu")
	)
	(gr_line
		(start 64.932814 -410.994098)
		(end 64.932814 -411.695138)
		(stroke
			(width 0.07112)
			(type default)
		)
		(layer "In6.Cu")
	)
	(gr_line
		(start 64.991234 -389.467344)
		(end 64.876426 -389.352536)
		(stroke
			(width 0.07112)
			(type default)
		)
		(layer "In6.Cu")
	)
	(gr_line
		(start 65.042034 -402.323808)
		(end 65.400682 -402.467318)
		(stroke
			(width 0.07112)
			(type default)
		)
		(layer "In6.Cu")
	)
	(gr_line
		(start 65.113408 -416.578288)
		(end 65.304924 -416.596322)
		(stroke
			(width 0.07112)
			(type default)
		)
		(layer "In6.Cu")
	)
	(gr_line
		(start 65.216024 -410.995368)
		(end 65.351914 -411.131258)
		(stroke
			(width 0.07112)
			(type default)
		)
		(layer "In6.Cu")
	)
	(gr_line
		(start 65.304924 -416.596322)
		(end 65.576958 -416.925506)
		(stroke
			(width 0.07112)
			(type default)
		)
		(layer "In6.Cu")
	)
	(gr_line
		(start 65.351914 -411.557978)
		(end 65.216024 -411.693868)
		(stroke
			(width 0.07112)
			(type default)
		)
		(layer "In6.Cu")
	)
	(gr_line
		(start 65.351914 -411.131258)
		(end 65.351914 -411.557978)
		(stroke
			(width 0.07112)
			(type default)
		)
		(layer "In6.Cu")
	)
	(gr_line
		(start 65.400682 -402.467318)
		(end 65.476374 -402.644356)
		(stroke
			(width 0.07112)
			(type default)
		)
		(layer "In6.Cu")
	)
	(gr_line
		(start 65.429384 -368.7445)
		(end 65.138554 -369.03533)
		(stroke
			(width 0.07112)
			(type default)
		)
		(layer "In6.Cu")
	)
	(gr_line
		(start 65.505584 -410.030168)
		(end 65.214754 -410.320998)
		(stroke
			(width 0.07112)
			(type default)
		)
		(layer "In6.Cu")
	)
	(gr_line
		(start 65.558416 -417.1188)
		(end 65.597532 -417.166044)
		(stroke
			(width 0.07112)
			(type default)
		)
		(layer "In6.Cu")
	)
	(gr_line
		(start 65.56629 -414.019746)
		(end 65.911984 -414.629854)
		(stroke
			(width 0.07112)
			(type default)
		)
		(layer "In6.Cu")
	)
	(gr_line
		(start 65.576958 -416.925506)
		(end 65.55867 -417.117022)
		(stroke
			(width 0.07112)
			(type default)
		)
		(layer "In6.Cu")
	)
	(gr_line
		(start 65.711324 -368.7445)
		(end 66.002154 -369.03533)
		(stroke
			(width 0.07112)
			(type default)
		)
		(layer "In6.Cu")
	)
	(gr_line
		(start 65.791334 -388.774432)
		(end 65.843658 -388.826756)
		(stroke
			(width 0.07112)
			(type default)
		)
		(layer "In6.Cu")
	)
	(gr_line
		(start 65.813178 -413.881316)
		(end 65.998852 -413.932624)
		(stroke
			(width 0.07112)
			(type default)
		)
		(layer "In6.Cu")
	)
	(gr_line
		(start 65.843658 -389.006588)
		(end 65.6971 -389.153146)
		(stroke
			(width 0.07112)
			(type default)
		)
		(layer "In6.Cu")
	)
	(gr_line
		(start 65.843658 -388.826756)
		(end 65.843658 -389.006588)
		(stroke
			(width 0.07112)
			(type default)
		)
		(layer "In6.Cu")
	)
	(gr_line
		(start 65.998852 -413.932624)
		(end 66.209164 -414.303972)
		(stroke
			(width 0.07112)
			(type default)
		)
		(layer "In6.Cu")
	)
	(gr_line
		(start 66.076576 -389.352536)
		(end 65.898268 -389.352536)
		(stroke
			(width 0.07112)
			(type default)
		)
		(layer "In6.Cu")
	)
	(gr_line
		(start 66.122296 -415.001202)
		(end 66.46799 -415.611056)
		(stroke
			(width 0.07112)
			(type default)
		)
		(layer "In6.Cu")
	)
	(gr_line
		(start 66.191384 -389.467344)
		(end 66.076576 -389.352536)
		(stroke
			(width 0.07112)
			(type default)
		)
		(layer "In6.Cu")
	)
	(gr_line
		(start 66.209164 -414.303972)
		(end 66.157856 -414.489392)
		(stroke
			(width 0.07112)
			(type default)
		)
		(layer "In6.Cu")
	)
	(gr_line
		(start 66.223896 -401.890738)
		(end 66.853816 -402.091144)
		(stroke
			(width 0.07112)
			(type default)
		)
		(layer "In6.Cu")
	)
	(gr_line
		(start 66.310764 -401.62099)
		(end 66.48196 -401.532598)
		(stroke
			(width 0.07112)
			(type default)
		)
		(layer "In6.Cu")
	)
	(gr_line
		(start 66.369184 -414.862518)
		(end 66.554858 -414.913826)
		(stroke
			(width 0.07112)
			(type default)
		)
		(layer "In6.Cu")
	)
	(gr_line
		(start 66.464434 -404.17369)
		(end 66.173604 -404.46452)
		(stroke
			(width 0.07112)
			(type default)
		)
		(layer "In6.Cu")
	)
	(gr_line
		(start 66.48196 -401.532598)
		(end 66.850006 -401.649692)
		(stroke
			(width 0.07112)
			(type default)
		)
		(layer "In6.Cu")
	)
	(gr_line
		(start 66.5226 -426.830998)
		(end 66.649854 -426.958252)
		(stroke
			(width 0.07112)
			(type default)
		)
		(layer "In6.Cu")
	)
	(gr_line
		(start 66.5226 -426.548804)
		(end 66.649854 -426.42155)
		(stroke
			(width 0.07112)
			(type default)
		)
		(layer "In6.Cu")
	)
	(gr_line
		(start 66.554858 -414.913826)
		(end 66.76517 -415.285174)
		(stroke
			(width 0.07112)
			(type default)
		)
		(layer "In6.Cu")
	)
	(gr_line
		(start 66.649854 -426.958252)
		(end 66.649854 -427.289976)
		(stroke
			(width 0.07112)
			(type default)
		)
		(layer "In6.Cu")
	)
	(gr_line
		(start 66.649854 -426.42155)
		(end 66.649854 -426.089826)
		(stroke
			(width 0.07112)
			(type default)
		)
		(layer "In6.Cu")
	)
	(gr_line
		(start 66.678302 -415.982404)
		(end 67.023996 -416.592512)
		(stroke
			(width 0.07112)
			(type default)
		)
		(layer "In6.Cu")
	)
	(gr_line
		(start 66.737992 -394.979398)
		(end 67.378834 -395.139926)
		(stroke
			(width 0.07112)
			(type default)
		)
		(layer "In6.Cu")
	)
	(gr_line
		(start 66.746374 -404.17369)
		(end 67.037204 -404.46452)
		(stroke
			(width 0.07112)
			(type default)
		)
		(layer "In6.Cu")
	)
	(gr_line
		(start 66.76517 -415.285174)
		(end 66.713862 -415.470594)
		(stroke
			(width 0.07112)
			(type default)
		)
		(layer "In6.Cu")
	)
	(gr_line
		(start 66.807842 -394.704824)
		(end 66.972942 -394.606018)
		(stroke
			(width 0.07112)
			(type default)
		)
		(layer "In6.Cu")
	)
	(gr_line
		(start 66.850006 -401.649692)
		(end 66.938398 -401.820888)
		(stroke
			(width 0.07112)
			(type default)
		)
		(layer "In6.Cu")
	)
	(gr_line
		(start 66.92519 -415.84372)
		(end 67.110864 -415.895028)
		(stroke
			(width 0.07112)
			(type default)
		)
		(layer "In6.Cu")
	)
	(gr_line
		(start 66.972942 -394.606018)
		(end 67.347592 -394.699744)
		(stroke
			(width 0.07112)
			(type default)
		)
		(layer "In6.Cu")
	)
	(gr_line
		(start 67.110864 -415.895028)
		(end 67.321176 -416.266376)
		(stroke
			(width 0.07112)
			(type default)
		)
		(layer "In6.Cu")
	)
	(gr_line
		(start 67.221608 -402.208238)
		(end 67.332606 -402.243544)
		(stroke
			(width 0.07112)
			(type default)
		)
		(layer "In6.Cu")
	)
	(gr_line
		(start 67.308222 -401.93849)
		(end 67.479418 -401.850098)
		(stroke
			(width 0.07112)
			(type default)
		)
		(layer "In6.Cu")
	)
	(gr_line
		(start 67.321176 -416.266376)
		(end 67.269868 -416.451796)
		(stroke
			(width 0.07112)
			(type default)
		)
		(layer "In6.Cu")
	)
	(gr_line
		(start 67.332606 -402.243544)
		(end 67.33286 -402.243544)
		(stroke
			(width 0.07112)
			(type default)
		)
		(layer "In6.Cu")
	)
	(gr_line
		(start 67.33286 -402.243544)
		(end 67.851274 -402.408644)
		(stroke
			(width 0.07112)
			(type default)
		)
		(layer "In6.Cu")
	)
	(gr_line
		(start 67.347592 -394.699744)
		(end 67.446652 -394.864844)
		(stroke
			(width 0.07112)
			(type default)
		)
		(layer "In6.Cu")
	)
	(gr_line
		(start 67.479418 -401.850098)
		(end 67.847464 -401.967192)
		(stroke
			(width 0.07112)
			(type default)
		)
		(layer "In6.Cu")
	)
	(gr_line
		(start 67.705224 -410.030168)
		(end 67.996054 -410.320998)
		(stroke
			(width 0.07112)
			(type default)
		)
		(layer "In6.Cu")
	)
	(gr_line
		(start 67.847464 -401.967192)
		(end 67.935856 -402.138388)
		(stroke
			(width 0.07112)
			(type default)
		)
		(layer "In6.Cu")
	)
	(gr_line
		(start 67.851274 -402.408644)
		(end 67.90817 -402.426678)
		(stroke
			(width 0.07112)
			(type default)
		)
		(layer "In6.Cu")
	)
	(gr_line
		(start 67.936618 -402.139912)
		(end 67.993514 -402.157946)
		(stroke
			(width 0.07112)
			(type default)
		)
		(layer "In6.Cu")
	)
	(gr_line
		(start 67.996054 -411.08884)
		(end 67.996054 -411.78988)
		(stroke
			(width 0.07112)
			(type default)
		)
		(layer "In6.Cu")
	)
	(gr_line
		(start 68.089018 -413.20466)
		(end 68.273676 -413.720788)
		(stroke
			(width 0.07112)
			(type default)
		)
		(layer "In6.Cu")
	)
	(gr_line
		(start 68.219066 -402.525738)
		(end 68.848732 -402.726144)
		(stroke
			(width 0.07112)
			(type default)
		)
		(layer "In6.Cu")
	)
	(gr_line
		(start 68.273676 -413.720788)
		(end 68.509896 -414.380934)
		(stroke
			(width 0.07112)
			(type default)
		)
		(layer "In6.Cu")
	)
	(gr_line
		(start 68.279264 -411.09011)
		(end 68.415154 -411.226)
		(stroke
			(width 0.07112)
			(type default)
		)
		(layer "In6.Cu")
	)
	(gr_line
		(start 68.30568 -402.25599)
		(end 68.476622 -402.167598)
		(stroke
			(width 0.07112)
			(type default)
		)
		(layer "In6.Cu")
	)
	(gr_line
		(start 68.354448 -413.109664)
		(end 68.539106 -413.625792)
		(stroke
			(width 0.07112)
			(type default)
		)
		(layer "In6.Cu")
	)
	(gr_line
		(start 68.415154 -411.65272)
		(end 68.279264 -411.78861)
		(stroke
			(width 0.07112)
			(type default)
		)
		(layer "In6.Cu")
	)
	(gr_line
		(start 68.415154 -411.226)
		(end 68.415154 -411.65272)
		(stroke
			(width 0.07112)
			(type default)
		)
		(layer "In6.Cu")
	)
	(gr_line
		(start 68.476622 -402.167598)
		(end 68.844922 -402.284692)
		(stroke
			(width 0.07112)
			(type default)
		)
		(layer "In6.Cu")
	)
	(gr_line
		(start 68.516754 -427.54296)
		(end 68.52285 -427.54296)
		(stroke
			(width 0.07112)
			(type default)
		)
		(layer "In6.Cu")
	)
	(gr_line
		(start 68.518024 -427.82617)
		(end 68.64985 -427.957996)
		(stroke
			(width 0.07112)
			(type default)
		)
		(layer "In6.Cu")
	)
	(gr_line
		(start 68.52285 -427.54296)
		(end 68.64985 -427.41596)
		(stroke
			(width 0.07112)
			(type default)
		)
		(layer "In6.Cu")
	)
	(gr_line
		(start 68.540884 -413.626554)
		(end 68.71462 -413.708596)
		(stroke
			(width 0.07112)
			(type default)
		)
		(layer "In6.Cu")
	)
	(gr_line
		(start 68.568824 -410.030168)
		(end 68.277994 -410.320998)
		(stroke
			(width 0.07112)
			(type default)
		)
		(layer "In6.Cu")
	)
	(gr_line
		(start 68.628514 -414.712404)
		(end 68.65366 -414.782508)
		(stroke
			(width 0.07112)
			(type default)
		)
		(layer "In6.Cu")
	)
	(gr_line
		(start 68.64985 -427.957996)
		(end 68.64985 -428.28972)
		(stroke
			(width 0.07112)
			(type default)
		)
		(layer "In6.Cu")
	)
	(gr_line
		(start 68.64985 -427.41596)
		(end 68.64985 -427.089824)
		(stroke
			(width 0.07112)
			(type default)
		)
		(layer "In6.Cu")
	)
	(gr_line
		(start 68.65366 -414.782508)
		(end 68.88988 -415.442908)
		(stroke
			(width 0.07112)
			(type default)
		)
		(layer "In6.Cu")
	)
	(gr_line
		(start 68.71462 -413.708596)
		(end 68.858384 -414.110678)
		(stroke
			(width 0.07112)
			(type default)
		)
		(layer "In6.Cu")
	)
	(gr_line
		(start 68.832984 -369.32616)
		(end 68.542154 -369.03533)
		(stroke
			(width 0.07112)
			(type default)
		)
		(layer "In6.Cu")
	)
	(gr_line
		(start 68.844922 -402.284692)
		(end 68.933314 -402.455888)
		(stroke
			(width 0.07112)
			(type default)
		)
		(layer "In6.Cu")
	)
	(gr_line
		(start 68.858384 -414.110678)
		(end 68.776342 -414.284414)
		(stroke
			(width 0.07112)
			(type default)
		)
		(layer "In6.Cu")
	)
	(gr_line
		(start 68.894198 -414.617662)
		(end 68.91909 -414.687512)
		(stroke
			(width 0.07112)
			(type default)
		)
		(layer "In6.Cu")
	)
	(gr_line
		(start 68.920868 -414.688274)
		(end 69.094858 -414.77057)
		(stroke
			(width 0.07112)
			(type default)
		)
		(layer "In6.Cu")
	)
	(gr_line
		(start 68.934076 -402.457158)
		(end 68.93433 -402.457412)
		(stroke
			(width 0.07112)
			(type default)
		)
		(layer "In6.Cu")
	)
	(gr_line
		(start 68.977256 -415.686494)
		(end 69.033644 -415.844228)
		(stroke
			(width 0.07112)
			(type default)
		)
		(layer "In6.Cu")
	)
	(gr_line
		(start 69.033644 -415.844228)
		(end 69.270118 -416.504882)
		(stroke
			(width 0.07112)
			(type default)
		)
		(layer "In6.Cu")
	)
	(gr_line
		(start 69.094858 -414.77057)
		(end 69.238622 -415.172652)
		(stroke
			(width 0.07112)
			(type default)
		)
		(layer "In6.Cu")
	)
	(gr_line
		(start 69.114924 -369.32616)
		(end 69.405754 -369.03533)
		(stroke
			(width 0.07112)
			(type default)
		)
		(layer "In6.Cu")
	)
	(gr_line
		(start 69.238622 -415.172652)
		(end 69.156326 -415.346388)
		(stroke
			(width 0.07112)
			(type default)
		)
		(layer "In6.Cu")
	)
	(gr_line
		(start 69.242686 -415.591498)
		(end 69.299074 -415.749486)
		(stroke
			(width 0.07112)
			(type default)
		)
		(layer "In6.Cu")
	)
	(gr_line
		(start 69.300852 -415.750248)
		(end 69.474842 -415.832544)
		(stroke
			(width 0.07112)
			(type default)
		)
		(layer "In6.Cu")
	)
	(gr_line
		(start 69.371718 -395.63929)
		(end 70.012814 -395.799818)
		(stroke
			(width 0.07112)
			(type default)
		)
		(layer "In6.Cu")
	)
	(gr_line
		(start 69.441568 -395.364716)
		(end 69.606668 -395.26591)
		(stroke
			(width 0.07112)
			(type default)
		)
		(layer "In6.Cu")
	)
	(gr_line
		(start 69.474842 -415.832544)
		(end 69.618606 -416.234626)
		(stroke
			(width 0.07112)
			(type default)
		)
		(layer "In6.Cu")
	)
	(gr_line
		(start 69.48043 -404.220934)
		(end 69.236844 -404.46452)
		(stroke
			(width 0.07112)
			(type default)
		)
		(layer "In6.Cu")
	)
	(gr_arc
		(start 69.48043 -404.220934)
		(mid 69.515392 -404.168609)
		(end 69.527674 -404.106888)
		(stroke
			(width 0.07112)
			(type default)
		)
		(layer "In6.Cu")
	)
	(gr_line
		(start 69.541644 -404.106888)
		(end 69.527674 -404.106888)
		(stroke
			(width 0.07112)
			(type default)
		)
		(layer "In6.Cu")
	)
	(gr_line
		(start 69.606668 -395.26591)
		(end 69.981572 -395.359636)
		(stroke
			(width 0.07112)
			(type default)
		)
		(layer "In6.Cu")
	)
	(gr_line
		(start 69.618606 -416.234626)
		(end 69.53631 -416.408362)
		(stroke
			(width 0.07112)
			(type default)
		)
		(layer "In6.Cu")
	)
	(gr_arc
		(start 69.824854 -404.122128)
		(mid 69.837137 -404.183848)
		(end 69.872098 -404.236174)
		(stroke
			(width 0.07112)
			(type default)
		)
		(layer "In6.Cu")
	)
	(gr_line
		(start 69.824854 -404.106888)
		(end 69.824854 -404.122128)
		(stroke
			(width 0.07112)
			(type default)
		)
		(layer "In6.Cu")
	)
	(gr_line
		(start 69.872098 -404.236174)
		(end 70.100444 -404.46452)
		(stroke
			(width 0.07112)
			(type default)
		)
		(layer "In6.Cu")
	)
	(gr_line
		(start 69.981572 -395.359636)
		(end 70.080632 -395.524736)
		(stroke
			(width 0.07112)
			(type default)
		)
		(layer "In6.Cu")
	)
	(gr_line
		(start 70.493128 -426.860208)
		(end 70.522846 -426.860208)
		(stroke
			(width 0.07112)
			(type default)
		)
		(layer "In6.Cu")
	)
	(gr_line
		(start 70.494398 -426.576998)
		(end 70.649846 -426.42155)
		(stroke
			(width 0.07112)
			(type default)
		)
		(layer "In6.Cu")
	)
	(gr_line
		(start 70.522846 -426.860208)
		(end 70.649846 -426.987208)
		(stroke
			(width 0.07112)
			(type default)
		)
		(layer "In6.Cu")
	)
	(gr_line
		(start 70.562216 -402.271738)
		(end 71.172578 -402.524722)
		(stroke
			(width 0.07112)
			(type default)
		)
		(layer "In6.Cu")
	)
	(gr_line
		(start 70.649846 -426.987208)
		(end 70.649846 -427.289976)
		(stroke
			(width 0.07112)
			(type default)
		)
		(layer "In6.Cu")
	)
	(gr_line
		(start 70.649846 -426.42155)
		(end 70.649846 -426.089826)
		(stroke
			(width 0.07112)
			(type default)
		)
		(layer "In6.Cu")
	)
	(gr_line
		(start 70.671436 -402.010626)
		(end 70.84949 -401.936966)
		(stroke
			(width 0.07112)
			(type default)
		)
		(layer "In6.Cu")
	)
	(gr_line
		(start 70.751192 -370.25199)
		(end 70.737476 -370.251228)
		(stroke
			(width 0.07112)
			(type default)
		)
		(layer "In6.Cu")
	)
	(gr_arc
		(start 70.751192 -369.97005)
		(mid 70.744344 -369.969487)
		(end 70.737476 -369.969288)
		(stroke
			(width 0.07112)
			(type default)
		)
		(layer "In6.Cu")
	)
	(gr_line
		(start 70.759066 -370.25199)
		(end 70.751192 -370.25199)
		(stroke
			(width 0.07112)
			(type default)
		)
		(layer "In6.Cu")
	)
	(gr_line
		(start 70.768464 -410.030168)
		(end 71.059294 -410.320998)
		(stroke
			(width 0.07112)
			(type default)
		)
		(layer "In6.Cu")
	)
	(gr_line
		(start 70.778624 -401.216368)
		(end 71.400416 -401.439888)
		(stroke
			(width 0.07112)
			(type default)
		)
		(layer "In6.Cu")
	)
	(gr_line
		(start 70.84949 -401.936966)
		(end 71.20636 -402.08454)
		(stroke
			(width 0.07112)
			(type default)
		)
		(layer "In6.Cu")
	)
	(gr_arc
		(start 70.851014 -361.975146)
		(mid 70.851268 -361.975146)
		(end 70.851522 -361.975146)
		(stroke
			(width 0.07112)
			(type default)
		)
		(layer "In6.Cu")
	)
	(gr_line
		(start 70.875398 -400.950176)
		(end 71.049642 -400.868134)
		(stroke
			(width 0.07112)
			(type default)
		)
		(layer "In6.Cu")
	)
	(gr_line
		(start 71.049642 -400.868134)
		(end 71.413116 -400.99869)
		(stroke
			(width 0.07112)
			(type default)
		)
		(layer "In6.Cu")
	)
	(gr_line
		(start 71.059294 -411.292548)
		(end 71.059294 -411.993588)
		(stroke
			(width 0.07112)
			(type default)
		)
		(layer "In6.Cu")
	)
	(gr_line
		(start 71.06539 -413.149796)
		(end 71.142098 -413.927544)
		(stroke
			(width 0.07112)
			(type default)
		)
		(layer "In6.Cu")
	)
	(gr_line
		(start 71.142098 -413.927544)
		(end 71.210932 -414.62579)
		(stroke
			(width 0.07112)
			(type default)
		)
		(layer "In6.Cu")
	)
	(gr_line
		(start 71.20636 -402.08454)
		(end 71.28002 -402.262594)
		(stroke
			(width 0.07112)
			(type default)
		)
		(layer "In6.Cu")
	)
	(gr_line
		(start 71.25462 -415.070544)
		(end 71.323454 -415.768536)
		(stroke
			(width 0.07112)
			(type default)
		)
		(layer "In6.Cu")
	)
	(gr_line
		(start 71.342504 -411.293818)
		(end 71.478394 -411.429708)
		(stroke
			(width 0.07112)
			(type default)
		)
		(layer "In6.Cu")
	)
	(gr_line
		(start 71.34606 -413.12211)
		(end 71.422514 -413.900112)
		(stroke
			(width 0.07112)
			(type default)
		)
		(layer "In6.Cu")
	)
	(gr_line
		(start 71.413116 -400.99869)
		(end 71.495412 -401.173188)
		(stroke
			(width 0.07112)
			(type default)
		)
		(layer "In6.Cu")
	)
	(gr_line
		(start 71.424038 -413.901382)
		(end 71.572882 -414.023048)
		(stroke
			(width 0.07112)
			(type default)
		)
		(layer "In6.Cu")
	)
	(gr_line
		(start 71.478394 -411.856428)
		(end 71.342504 -411.992318)
		(stroke
			(width 0.07112)
			(type default)
		)
		(layer "In6.Cu")
	)
	(gr_line
		(start 71.478394 -411.429708)
		(end 71.478394 -411.856428)
		(stroke
			(width 0.07112)
			(type default)
		)
		(layer "In6.Cu")
	)
	(gr_line
		(start 71.529194 -402.67255)
		(end 72.139556 -402.92528)
		(stroke
			(width 0.07112)
			(type default)
		)
		(layer "In6.Cu")
	)
	(gr_line
		(start 71.53656 -415.043874)
		(end 71.685404 -415.165794)
		(stroke
			(width 0.07112)
			(type default)
		)
		(layer "In6.Cu")
	)
	(gr_line
		(start 71.557134 -380.081028)
		(end 71.277734 -380.360428)
		(stroke
			(width 0.07112)
			(type default)
		)
		(layer "In6.Cu")
	)
	(gr_line
		(start 71.568564 -376.665998)
		(end 71.277734 -376.956828)
		(stroke
			(width 0.07112)
			(type default)
		)
		(layer "In6.Cu")
	)
	(gr_line
		(start 71.568564 -376.384058)
		(end 71.277734 -376.093228)
		(stroke
			(width 0.07112)
			(type default)
		)
		(layer "In6.Cu")
	)
	(gr_line
		(start 71.572882 -414.023048)
		(end 71.614538 -414.44799)
		(stroke
			(width 0.07112)
			(type default)
		)
		(layer "In6.Cu")
	)
	(gr_line
		(start 71.578724 -379.797818)
		(end 71.277734 -379.496828)
		(stroke
			(width 0.07112)
			(type default)
		)
		(layer "In6.Cu")
	)
	(gr_line
		(start 71.579994 -380.081028)
		(end 71.557134 -380.081028)
		(stroke
			(width 0.07112)
			(type default)
		)
		(layer "In6.Cu")
	)
	(gr_line
		(start 71.614538 -414.44799)
		(end 71.492618 -414.596834)
		(stroke
			(width 0.07112)
			(type default)
		)
		(layer "In6.Cu")
	)
	(gr_line
		(start 71.632064 -410.030168)
		(end 71.341234 -410.320998)
		(stroke
			(width 0.07112)
			(type default)
		)
		(layer "In6.Cu")
	)
	(gr_line
		(start 71.638414 -402.411184)
		(end 71.816468 -402.337524)
		(stroke
			(width 0.07112)
			(type default)
		)
		(layer "In6.Cu")
	)
	(gr_line
		(start 71.685404 -415.165794)
		(end 71.727314 -415.590736)
		(stroke
			(width 0.07112)
			(type default)
		)
		(layer "In6.Cu")
	)
	(gr_line
		(start 71.727314 -415.590736)
		(end 71.60514 -415.73958)
		(stroke
			(width 0.07112)
			(type default)
		)
		(layer "In6.Cu")
	)
	(gr_line
		(start 71.816468 -402.337524)
		(end 72.173338 -402.485098)
		(stroke
			(width 0.07112)
			(type default)
		)
		(layer "In6.Cu")
	)
	(gr_line
		(start 72.063356 -364.438184)
		(end 72.063102 -364.438184)
		(stroke
			(width 0.07112)
			(type default)
		)
		(layer "In6.Cu")
	)
	(gr_line
		(start 72.173338 -402.485098)
		(end 72.246998 -402.663152)
		(stroke
			(width 0.07112)
			(type default)
		)
		(layer "In6.Cu")
	)
	(gr_line
		(start 72.372728 -370.487448)
		(end 72.18045 -370.487448)
		(stroke
			(width 0.07112)
			(type default)
		)
		(layer "In6.Cu")
	)
	(gr_line
		(start 72.475344 -371.1829)
		(end 71.979282 -370.686838)
		(stroke
			(width 0.07112)
			(type default)
		)
		(layer "In6.Cu")
	)
	(gr_line
		(start 72.522588 -427.830742)
		(end 72.649842 -427.957996)
		(stroke
			(width 0.07112)
			(type default)
		)
		(layer "In6.Cu")
	)
	(gr_line
		(start 72.522588 -427.548802)
		(end 72.649842 -427.421548)
		(stroke
			(width 0.07112)
			(type default)
		)
		(layer "In6.Cu")
	)
	(gr_line
		(start 72.571102 -395.294104)
		(end 72.683624 -395.325346)
		(stroke
			(width 0.07112)
			(type default)
		)
		(layer "In6.Cu")
	)
	(gr_line
		(start 72.590914 -404.17369)
		(end 72.300084 -404.46452)
		(stroke
			(width 0.07112)
			(type default)
		)
		(layer "In6.Cu")
	)
	(gr_line
		(start 72.647556 -395.021562)
		(end 72.815196 -394.92682)
		(stroke
			(width 0.07112)
			(type default)
		)
		(layer "In6.Cu")
	)
	(gr_line
		(start 72.649842 -427.957996)
		(end 72.649842 -428.28972)
		(stroke
			(width 0.07112)
			(type default)
		)
		(layer "In6.Cu")
	)
	(gr_line
		(start 72.649842 -427.421548)
		(end 72.649842 -427.089824)
		(stroke
			(width 0.07112)
			(type default)
		)
		(layer "In6.Cu")
	)
	(gr_line
		(start 72.674734 -370.981732)
		(end 72.674734 -370.789454)
		(stroke
			(width 0.07112)
			(type default)
		)
		(layer "In6.Cu")
	)
	(gr_line
		(start 72.674734 -370.789454)
		(end 72.372728 -370.487448)
		(stroke
			(width 0.07112)
			(type default)
		)
		(layer "In6.Cu")
	)
	(gr_line
		(start 72.683624 -395.3256)
		(end 73.246996 -395.481556)
		(stroke
			(width 0.07112)
			(type default)
		)
		(layer "In6.Cu")
	)
	(gr_line
		(start 72.683624 -395.325346)
		(end 72.683624 -395.3256)
		(stroke
			(width 0.07112)
			(type default)
		)
		(layer "In6.Cu")
	)
	(gr_line
		(start 72.720962 -401.915122)
		(end 73.3425 -402.138896)
		(stroke
			(width 0.07112)
			(type default)
		)
		(layer "In6.Cu")
	)
	(gr_line
		(start 72.815196 -394.92682)
		(end 73.226676 -395.040612)
		(stroke
			(width 0.07112)
			(type default)
		)
		(layer "In6.Cu")
	)
	(gr_line
		(start 72.81799 -401.64893)
		(end 72.99198 -401.566888)
		(stroke
			(width 0.07112)
			(type default)
		)
		(layer "In6.Cu")
	)
	(gr_line
		(start 72.872854 -404.17369)
		(end 73.163684 -404.46452)
		(stroke
			(width 0.07112)
			(type default)
		)
		(layer "In6.Cu")
	)
	(gr_line
		(start 72.99198 -401.566888)
		(end 73.355454 -401.697698)
		(stroke
			(width 0.07112)
			(type default)
		)
		(layer "In6.Cu")
	)
	(gr_line
		(start 73.170288 -371.285008)
		(end 72.97801 -371.285008)
		(stroke
			(width 0.07112)
			(type default)
		)
		(layer "In6.Cu")
	)
	(gr_line
		(start 73.226676 -395.040612)
		(end 73.321418 -395.208252)
		(stroke
			(width 0.07112)
			(type default)
		)
		(layer "In6.Cu")
	)
	(gr_line
		(start 73.272904 -371.98046)
		(end 72.776842 -371.484398)
		(stroke
			(width 0.07112)
			(type default)
		)
		(layer "In6.Cu")
	)
	(gr_line
		(start 73.355454 -401.697698)
		(end 73.437242 -401.871942)
		(stroke
			(width 0.07112)
			(type default)
		)
		(layer "In6.Cu")
	)
	(gr_line
		(start 73.472294 -371.779292)
		(end 73.472294 -371.587014)
		(stroke
			(width 0.07112)
			(type default)
		)
		(layer "In6.Cu")
	)
	(gr_line
		(start 73.472294 -371.587014)
		(end 73.170288 -371.285008)
		(stroke
			(width 0.07112)
			(type default)
		)
		(layer "In6.Cu")
	)
	(gr_line
		(start 73.831704 -410.030168)
		(end 74.122534 -410.320998)
		(stroke
			(width 0.07112)
			(type default)
		)
		(layer "In6.Cu")
	)
	(gr_line
		(start 73.967848 -372.082568)
		(end 73.77557 -372.082568)
		(stroke
			(width 0.07112)
			(type default)
		)
		(layer "In6.Cu")
	)
	(gr_line
		(start 74.070464 -372.77802)
		(end 73.574402 -372.281958)
		(stroke
			(width 0.07112)
			(type default)
		)
		(layer "In6.Cu")
	)
	(gr_line
		(start 74.101452 -387.498844)
		(end 73.810622 -387.789674)
		(stroke
			(width 0.07112)
			(type default)
		)
		(layer "In6.Cu")
	)
	(gr_line
		(start 74.101452 -387.216904)
		(end 73.810622 -386.926074)
		(stroke
			(width 0.07112)
			(type default)
		)
		(layer "In6.Cu")
	)
	(gr_line
		(start 74.122534 -411.217618)
		(end 74.122534 -411.918658)
		(stroke
			(width 0.07112)
			(type default)
		)
		(layer "In6.Cu")
	)
	(gr_line
		(start 74.14387 -413.671004)
		(end 74.178414 -414.371536)
		(stroke
			(width 0.07112)
			(type default)
		)
		(layer "In6.Cu")
	)
	(gr_line
		(start 74.199242 -414.797494)
		(end 74.233532 -415.498026)
		(stroke
			(width 0.07112)
			(type default)
		)
		(layer "In6.Cu")
	)
	(gr_line
		(start 74.25436 -415.923984)
		(end 74.288904 -416.624516)
		(stroke
			(width 0.07112)
			(type default)
		)
		(layer "In6.Cu")
	)
	(gr_line
		(start 74.269854 -372.576852)
		(end 74.269854 -372.384574)
		(stroke
			(width 0.07112)
			(type default)
		)
		(layer "In6.Cu")
	)
	(gr_line
		(start 74.269854 -372.384574)
		(end 73.967848 -372.082568)
		(stroke
			(width 0.07112)
			(type default)
		)
		(layer "In6.Cu")
	)
	(gr_line
		(start 74.309732 -417.050474)
		(end 74.344022 -417.750752)
		(stroke
			(width 0.07112)
			(type default)
		)
		(layer "In6.Cu")
	)
	(gr_line
		(start 74.344022 -417.750752)
		(end 74.34453 -417.751006)
		(stroke
			(width 0.07112)
			(type default)
		)
		(layer "In6.Cu")
	)
	(gr_line
		(start 74.367898 -402.626576)
		(end 74.921618 -402.985986)
		(stroke
			(width 0.07112)
			(type default)
		)
		(layer "In6.Cu")
	)
	(gr_line
		(start 74.404728 -413.23133)
		(end 74.404474 -413.23133)
		(stroke
			(width 0.07112)
			(type default)
		)
		(layer "In6.Cu")
	)
	(gr_line
		(start 74.405744 -411.218888)
		(end 74.541634 -411.354778)
		(stroke
			(width 0.07112)
			(type default)
		)
		(layer "In6.Cu")
	)
	(gr_line
		(start 74.426826 -413.658558)
		(end 74.569574 -413.78759)
		(stroke
			(width 0.07112)
			(type default)
		)
		(layer "In6.Cu")
	)
	(gr_line
		(start 74.482198 -414.784794)
		(end 74.624946 -414.91408)
		(stroke
			(width 0.07112)
			(type default)
		)
		(layer "In6.Cu")
	)
	(gr_line
		(start 74.522584 -402.38934)
		(end 74.710798 -402.349208)
		(stroke
			(width 0.07112)
			(type default)
		)
		(layer "In6.Cu")
	)
	(gr_line
		(start 74.537316 -415.911284)
		(end 74.680318 -416.04057)
		(stroke
			(width 0.07112)
			(type default)
		)
		(layer "In6.Cu")
	)
	(gr_line
		(start 74.541634 -411.781498)
		(end 74.405744 -411.917388)
		(stroke
			(width 0.07112)
			(type default)
		)
		(layer "In6.Cu")
	)
	(gr_line
		(start 74.541634 -411.354778)
		(end 74.541634 -411.781498)
		(stroke
			(width 0.07112)
			(type default)
		)
		(layer "In6.Cu")
	)
	(gr_line
		(start 74.569574 -413.78759)
		(end 74.590402 -414.214056)
		(stroke
			(width 0.07112)
			(type default)
		)
		(layer "In6.Cu")
	)
	(gr_line
		(start 74.590402 -414.214056)
		(end 74.461116 -414.356804)
		(stroke
			(width 0.07112)
			(type default)
		)
		(layer "In6.Cu")
	)
	(gr_line
		(start 74.592688 -417.03752)
		(end 74.73569 -417.16706)
		(stroke
			(width 0.07112)
			(type default)
		)
		(layer "In6.Cu")
	)
	(gr_line
		(start 74.624946 -414.91408)
		(end 74.645774 -415.340546)
		(stroke
			(width 0.07112)
			(type default)
		)
		(layer "In6.Cu")
	)
	(gr_line
		(start 74.645774 -415.340546)
		(end 74.516488 -415.483294)
		(stroke
			(width 0.07112)
			(type default)
		)
		(layer "In6.Cu")
	)
	(gr_line
		(start 74.680318 -416.04057)
		(end 74.701146 -416.467036)
		(stroke
			(width 0.07112)
			(type default)
		)
		(layer "In6.Cu")
	)
	(gr_line
		(start 74.695304 -410.030168)
		(end 74.404474 -410.320998)
		(stroke
			(width 0.07112)
			(type default)
		)
		(layer "In6.Cu")
	)
	(gr_line
		(start 74.701146 -416.467036)
		(end 74.571606 -416.610038)
		(stroke
			(width 0.07112)
			(type default)
		)
		(layer "In6.Cu")
	)
	(gr_line
		(start 74.710798 -402.349208)
		(end 75.034902 -402.55952)
		(stroke
			(width 0.07112)
			(type default)
		)
		(layer "In6.Cu")
	)
	(gr_line
		(start 74.73569 -417.16706)
		(end 74.756518 -417.593526)
		(stroke
			(width 0.07112)
			(type default)
		)
		(layer "In6.Cu")
	)
	(gr_line
		(start 74.756518 -417.593526)
		(end 74.626216 -417.73729)
		(stroke
			(width 0.07112)
			(type default)
		)
		(layer "In6.Cu")
	)
	(gr_line
		(start 74.765408 -372.880128)
		(end 74.57313 -372.880128)
		(stroke
			(width 0.07112)
			(type default)
		)
		(layer "In6.Cu")
	)
	(gr_line
		(start 74.868024 -373.57558)
		(end 74.371962 -373.079518)
		(stroke
			(width 0.07112)
			(type default)
		)
		(layer "In6.Cu")
	)
	(gr_line
		(start 74.921618 -402.985986)
		(end 74.922126 -402.98624)
		(stroke
			(width 0.07112)
			(type default)
		)
		(layer "In6.Cu")
	)
	(gr_line
		(start 75.034902 -402.55952)
		(end 75.075034 -402.747988)
		(stroke
			(width 0.07112)
			(type default)
		)
		(layer "In6.Cu")
	)
	(gr_line
		(start 75.067414 -373.374412)
		(end 75.067414 -373.182134)
		(stroke
			(width 0.07112)
			(type default)
		)
		(layer "In6.Cu")
	)
	(gr_line
		(start 75.067414 -373.182134)
		(end 74.765408 -372.880128)
		(stroke
			(width 0.07112)
			(type default)
		)
		(layer "In6.Cu")
	)
	(gr_line
		(start 75.075288 -402.749512)
		(end 75.075796 -402.749766)
		(stroke
			(width 0.07112)
			(type default)
		)
		(layer "In6.Cu")
	)
	(gr_line
		(start 75.345798 -387.636004)
		(end 75.209908 -387.500114)
		(stroke
			(width 0.07112)
			(type default)
		)
		(layer "In6.Cu")
	)
	(gr_line
		(start 75.522836 -426.830998)
		(end 75.65009 -426.958252)
		(stroke
			(width 0.07112)
			(type default)
		)
		(layer "In6.Cu")
	)
	(gr_line
		(start 75.522836 -426.548804)
		(end 75.65009 -426.42155)
		(stroke
			(width 0.07112)
			(type default)
		)
		(layer "In6.Cu")
	)
	(gr_line
		(start 75.562968 -373.677688)
		(end 75.37069 -373.677688)
		(stroke
			(width 0.07112)
			(type default)
		)
		(layer "In6.Cu")
	)
	(gr_line
		(start 75.65009 -426.958252)
		(end 75.65009 -427.289976)
		(stroke
			(width 0.07112)
			(type default)
		)
		(layer "In6.Cu")
	)
	(gr_line
		(start 75.65009 -426.42155)
		(end 75.65009 -426.089826)
		(stroke
			(width 0.07112)
			(type default)
		)
		(layer "In6.Cu")
	)
	(gr_line
		(start 75.654154 -404.17369)
		(end 75.363324 -404.46452)
		(stroke
			(width 0.07112)
			(type default)
		)
		(layer "In6.Cu")
	)
	(gr_line
		(start 75.665584 -374.37314)
		(end 75.169522 -373.877078)
		(stroke
			(width 0.07112)
			(type default)
		)
		(layer "In6.Cu")
	)
	(gr_line
		(start 75.772518 -387.636004)
		(end 75.345798 -387.636004)
		(stroke
			(width 0.07112)
			(type default)
		)
		(layer "In6.Cu")
	)
	(gr_line
		(start 75.864974 -374.171972)
		(end 75.864974 -373.979694)
		(stroke
			(width 0.07112)
			(type default)
		)
		(layer "In6.Cu")
	)
	(gr_line
		(start 75.864974 -373.979694)
		(end 75.562968 -373.677688)
		(stroke
			(width 0.07112)
			(type default)
		)
		(layer "In6.Cu")
	)
	(gr_line
		(start 75.869546 -401.832572)
		(end 76.480162 -402.085048)
		(stroke
			(width 0.07112)
			(type default)
		)
		(layer "In6.Cu")
	)
	(gr_line
		(start 75.908408 -387.500114)
		(end 75.772518 -387.636004)
		(stroke
			(width 0.07112)
			(type default)
		)
		(layer "In6.Cu")
	)
	(gr_line
		(start 75.909678 -387.216904)
		(end 75.208638 -387.216904)
		(stroke
			(width 0.07112)
			(type default)
		)
		(layer "In6.Cu")
	)
	(gr_line
		(start 75.936094 -404.17369)
		(end 76.226924 -404.46452)
		(stroke
			(width 0.07112)
			(type default)
		)
		(layer "In6.Cu")
	)
	(gr_line
		(start 75.978258 -401.571206)
		(end 76.156312 -401.497292)
		(stroke
			(width 0.07112)
			(type default)
		)
		(layer "In6.Cu")
	)
	(gr_line
		(start 76.156312 -401.497292)
		(end 76.513436 -401.644866)
		(stroke
			(width 0.07112)
			(type default)
		)
		(layer "In6.Cu")
	)
	(gr_line
		(start 76.513436 -401.644866)
		(end 76.58735 -401.82292)
		(stroke
			(width 0.07112)
			(type default)
		)
		(layer "In6.Cu")
	)
	(gr_line
		(start 76.836778 -402.232368)
		(end 77.447394 -402.48459)
		(stroke
			(width 0.07112)
			(type default)
		)
		(layer "In6.Cu")
	)
	(gr_line
		(start 76.894944 -410.030168)
		(end 77.185774 -410.320998)
		(stroke
			(width 0.07112)
			(type default)
		)
		(layer "In6.Cu")
	)
	(gr_line
		(start 76.945744 -401.971002)
		(end 77.123544 -401.897088)
		(stroke
			(width 0.07112)
			(type default)
		)
		(layer "In6.Cu")
	)
	(gr_line
		(start 77.007974 -416.634422)
		(end 77.007466 -416.634676)
		(stroke
			(width 0.07112)
			(type default)
		)
		(layer "In6.Cu")
	)
	(gr_line
		(start 77.007974 -416.63239)
		(end 77.007974 -416.634422)
		(stroke
			(width 0.07112)
			(type default)
		)
		(layer "In6.Cu")
	)
	(gr_line
		(start 77.042518 -415.931858)
		(end 77.007974 -416.63239)
		(stroke
			(width 0.07112)
			(type default)
		)
		(layer "In6.Cu")
	)
	(gr_line
		(start 77.063346 -415.5059)
		(end 77.042518 -415.931858)
		(stroke
			(width 0.07112)
			(type default)
		)
		(layer "In6.Cu")
	)
	(gr_line
		(start 77.09789 -414.805368)
		(end 77.063346 -415.5059)
		(stroke
			(width 0.07112)
			(type default)
		)
		(layer "In6.Cu")
	)
	(gr_line
		(start 77.118718 -414.37941)
		(end 77.09789 -414.805368)
		(stroke
			(width 0.07112)
			(type default)
		)
		(layer "In6.Cu")
	)
	(gr_line
		(start 77.123544 -401.897088)
		(end 77.480668 -402.044662)
		(stroke
			(width 0.07112)
			(type default)
		)
		(layer "In6.Cu")
	)
	(gr_line
		(start 77.153262 -413.678878)
		(end 77.118718 -414.37941)
		(stroke
			(width 0.07112)
			(type default)
		)
		(layer "In6.Cu")
	)
	(gr_line
		(start 77.185774 -411.19425)
		(end 77.185774 -411.89529)
		(stroke
			(width 0.07112)
			(type default)
		)
		(layer "In6.Cu")
	)
	(gr_line
		(start 77.289406 -416.646106)
		(end 77.289406 -416.648392)
		(stroke
			(width 0.07112)
			(type default)
		)
		(layer "In6.Cu")
	)
	(gr_line
		(start 77.32522 -415.947098)
		(end 77.454252 -416.089338)
		(stroke
			(width 0.07112)
			(type default)
		)
		(layer "In6.Cu")
	)
	(gr_line
		(start 77.344778 -415.519616)
		(end 77.32395 -415.945574)
		(stroke
			(width 0.07112)
			(type default)
		)
		(layer "In6.Cu")
	)
	(gr_line
		(start 77.380592 -414.820608)
		(end 77.509624 -414.962848)
		(stroke
			(width 0.07112)
			(type default)
		)
		(layer "In6.Cu")
	)
	(gr_line
		(start 77.40015 -414.393126)
		(end 77.379322 -414.819084)
		(stroke
			(width 0.07112)
			(type default)
		)
		(layer "In6.Cu")
	)
	(gr_line
		(start 77.433424 -416.515804)
		(end 77.29093 -416.644582)
		(stroke
			(width 0.07112)
			(type default)
		)
		(layer "In6.Cu")
	)
	(gr_line
		(start 77.435964 -413.693864)
		(end 77.56525 -413.836358)
		(stroke
			(width 0.07112)
			(type default)
		)
		(layer "In6.Cu")
	)
	(gr_line
		(start 77.454252 -416.089338)
		(end 77.433424 -416.515804)
		(stroke
			(width 0.07112)
			(type default)
		)
		(layer "In6.Cu")
	)
	(gr_line
		(start 77.468984 -411.19552)
		(end 77.604874 -411.33141)
		(stroke
			(width 0.07112)
			(type default)
		)
		(layer "In6.Cu")
	)
	(gr_line
		(start 77.480668 -402.044662)
		(end 77.554582 -402.222462)
		(stroke
			(width 0.07112)
			(type default)
		)
		(layer "In6.Cu")
	)
	(gr_line
		(start 77.488796 -415.389314)
		(end 77.346302 -415.518092)
		(stroke
			(width 0.07112)
			(type default)
		)
		(layer "In6.Cu")
	)
	(gr_line
		(start 77.509624 -414.962848)
		(end 77.488796 -415.389314)
		(stroke
			(width 0.07112)
			(type default)
		)
		(layer "In6.Cu")
	)
	(gr_line
		(start 77.51699 -427.54296)
		(end 77.523086 -427.54296)
		(stroke
			(width 0.07112)
			(type default)
		)
		(layer "In6.Cu")
	)
	(gr_line
		(start 77.51826 -427.82617)
		(end 77.650086 -427.957996)
		(stroke
			(width 0.07112)
			(type default)
		)
		(layer "In6.Cu")
	)
	(gr_line
		(start 77.523086 -427.54296)
		(end 77.650086 -427.41596)
		(stroke
			(width 0.07112)
			(type default)
		)
		(layer "In6.Cu")
	)
	(gr_line
		(start 77.544168 -414.262824)
		(end 77.401674 -414.391602)
		(stroke
			(width 0.07112)
			(type default)
		)
		(layer "In6.Cu")
	)
	(gr_line
		(start 77.56525 -413.836358)
		(end 77.544168 -414.262824)
		(stroke
			(width 0.07112)
			(type default)
		)
		(layer "In6.Cu")
	)
	(gr_line
		(start 77.604874 -411.75813)
		(end 77.468984 -411.89402)
		(stroke
			(width 0.07112)
			(type default)
		)
		(layer "In6.Cu")
	)
	(gr_line
		(start 77.604874 -411.33141)
		(end 77.604874 -411.75813)
		(stroke
			(width 0.07112)
			(type default)
		)
		(layer "In6.Cu")
	)
	(gr_line
		(start 77.650086 -427.957996)
		(end 77.650086 -428.28972)
		(stroke
			(width 0.07112)
			(type default)
		)
		(layer "In6.Cu")
	)
	(gr_line
		(start 77.650086 -427.41596)
		(end 77.650086 -427.089824)
		(stroke
			(width 0.07112)
			(type default)
		)
		(layer "In6.Cu")
	)
	(gr_line
		(start 77.758544 -410.030168)
		(end 77.467714 -410.320998)
		(stroke
			(width 0.07112)
			(type default)
		)
		(layer "In6.Cu")
	)
	(gr_line
		(start 78.160118 -402.960586)
		(end 78.627478 -403.427946)
		(stroke
			(width 0.07112)
			(type default)
		)
		(layer "In6.Cu")
	)
	(gr_line
		(start 78.16723 -401.363942)
		(end 78.847188 -401.645628)
		(stroke
			(width 0.07112)
			(type default)
		)
		(layer "In6.Cu")
	)
	(gr_line
		(start 78.275942 -401.102576)
		(end 78.453996 -401.028916)
		(stroke
			(width 0.07112)
			(type default)
		)
		(layer "In6.Cu")
	)
	(gr_line
		(start 78.361286 -402.761196)
		(end 78.553564 -402.761196)
		(stroke
			(width 0.07112)
			(type default)
		)
		(layer "In6.Cu")
	)
	(gr_line
		(start 78.444598 -399.307812)
		(end 79.094838 -399.540222)
		(stroke
			(width 0.07112)
			(type default)
		)
		(layer "In6.Cu")
	)
	(gr_line
		(start 78.453996 -401.028916)
		(end 78.848458 -401.192238)
		(stroke
			(width 0.07112)
			(type default)
		)
		(layer "In6.Cu")
	)
	(gr_line
		(start 78.507082 -399.030698)
		(end 78.52029 -399.034762)
		(stroke
			(width 0.07112)
			(type default)
		)
		(layer "In6.Cu")
	)
	(gr_line
		(start 78.529942 -399.037556)
		(end 78.705202 -398.954752)
		(stroke
			(width 0.07112)
			(type default)
		)
		(layer "In6.Cu")
	)
	(gr_line
		(start 78.53299 -375.094754)
		(end 78.3971 -375.230644)
		(stroke
			(width 0.07112)
			(type default)
		)
		(layer "In6.Cu")
	)
	(gr_line
		(start 78.545436 -389.5217)
		(end 78.545436 -389.09498)
		(stroke
			(width 0.07112)
			(type default)
		)
		(layer "In6.Cu")
	)
	(gr_line
		(start 78.545436 -389.09498)
		(end 78.681326 -388.95909)
		(stroke
			(width 0.07112)
			(type default)
		)
		(layer "In6.Cu")
	)
	(gr_line
		(start 78.553564 -402.761196)
		(end 78.826868 -403.0345)
		(stroke
			(width 0.07112)
			(type default)
		)
		(layer "In6.Cu")
	)
	(gr_line
		(start 78.681326 -389.65759)
		(end 78.545436 -389.5217)
		(stroke
			(width 0.07112)
			(type default)
		)
		(layer "In6.Cu")
	)
	(gr_line
		(start 78.705202 -398.954752)
		(end 79.10703 -399.098516)
		(stroke
			(width 0.07112)
			(type default)
		)
		(layer "In6.Cu")
	)
	(gr_line
		(start 78.717394 -404.17369)
		(end 78.426564 -404.46452)
		(stroke
			(width 0.07112)
			(type default)
		)
		(layer "In6.Cu")
	)
	(gr_line
		(start 78.826868 -403.0345)
		(end 78.826868 -403.226778)
		(stroke
			(width 0.07112)
			(type default)
		)
		(layer "In6.Cu")
	)
	(gr_line
		(start 78.848458 -401.192238)
		(end 78.897226 -401.310094)
		(stroke
			(width 0.07112)
			(type default)
		)
		(layer "In6.Cu")
	)
	(gr_arc
		(start 78.897226 -401.310094)
		(mid 78.925533 -401.355332)
		(end 78.967076 -401.388834)
		(stroke
			(width 0.07112)
			(type default)
		)
		(layer "In6.Cu")
	)
	(gr_line
		(start 78.907894 -397.048228)
		(end 79.584042 -397.235172)
		(stroke
			(width 0.07112)
			(type default)
		)
		(layer "In6.Cu")
	)
	(gr_line
		(start 78.95971 -375.094754)
		(end 78.53299 -375.094754)
		(stroke
			(width 0.07112)
			(type default)
		)
		(layer "In6.Cu")
	)
	(gr_line
		(start 78.964536 -389.65886)
		(end 78.964536 -388.95782)
		(stroke
			(width 0.07112)
			(type default)
		)
		(layer "In6.Cu")
	)
	(gr_line
		(start 78.984348 -396.775432)
		(end 79.151734 -396.680436)
		(stroke
			(width 0.07112)
			(type default)
		)
		(layer "In6.Cu")
	)
	(gr_line
		(start 78.999334 -404.17369)
		(end 79.290164 -404.46452)
		(stroke
			(width 0.07112)
			(type default)
		)
		(layer "In6.Cu")
	)
	(gr_line
		(start 79.0956 -375.230644)
		(end 78.95971 -375.094754)
		(stroke
			(width 0.07112)
			(type default)
		)
		(layer "In6.Cu")
	)
	(gr_line
		(start 79.09687 -375.513854)
		(end 78.39583 -375.513854)
		(stroke
			(width 0.07112)
			(type default)
		)
		(layer "In6.Cu")
	)
	(gr_line
		(start 79.10703 -399.098516)
		(end 79.189834 -399.273522)
		(stroke
			(width 0.07112)
			(type default)
		)
		(layer "In6.Cu")
	)
	(gr_line
		(start 79.151734 -396.680436)
		(end 79.563468 -396.794228)
		(stroke
			(width 0.07112)
			(type default)
		)
		(layer "In6.Cu")
	)
	(gr_line
		(start 79.384906 -419.048438)
		(end 79.384652 -419.048946)
		(stroke
			(width 0.07112)
			(type default)
		)
		(layer "In6.Cu")
	)
	(gr_line
		(start 79.522828 -426.830998)
		(end 79.650082 -426.958252)
		(stroke
			(width 0.07112)
			(type default)
		)
		(layer "In6.Cu")
	)
	(gr_line
		(start 79.522828 -426.548804)
		(end 79.650082 -426.42155)
		(stroke
			(width 0.07112)
			(type default)
		)
		(layer "In6.Cu")
	)
	(gr_line
		(start 79.551022 -417.933124)
		(end 79.550514 -417.933378)
		(stroke
			(width 0.07112)
			(type default)
		)
		(layer "In6.Cu")
	)
	(gr_line
		(start 79.563468 -396.794228)
		(end 79.65821 -396.961868)
		(stroke
			(width 0.07112)
			(type default)
		)
		(layer "In6.Cu")
	)
	(gr_line
		(start 79.650082 -426.958252)
		(end 79.650082 -427.289976)
		(stroke
			(width 0.07112)
			(type default)
		)
		(layer "In6.Cu")
	)
	(gr_line
		(start 79.650082 -426.42155)
		(end 79.650082 -426.089826)
		(stroke
			(width 0.07112)
			(type default)
		)
		(layer "In6.Cu")
	)
	(gr_line
		(start 79.653892 -417.239958)
		(end 79.551022 -417.933124)
		(stroke
			(width 0.07112)
			(type default)
		)
		(layer "In6.Cu")
	)
	(gr_line
		(start 79.658718 -401.981924)
		(end 80.269334 -402.234654)
		(stroke
			(width 0.07112)
			(type default)
		)
		(layer "In6.Cu")
	)
	(gr_line
		(start 79.658972 -396.963392)
		(end 79.659226 -396.963392)
		(stroke
			(width 0.07112)
			(type default)
		)
		(layer "In6.Cu")
	)
	(gr_line
		(start 79.66075 -375.094754)
		(end 79.52486 -375.230644)
		(stroke
			(width 0.07112)
			(type default)
		)
		(layer "In6.Cu")
	)
	(gr_line
		(start 79.678022 -418.997638)
		(end 79.677768 -418.998146)
		(stroke
			(width 0.07112)
			(type default)
		)
		(layer "In6.Cu")
	)
	(gr_line
		(start 79.716376 -416.818064)
		(end 79.653892 -417.239958)
		(stroke
			(width 0.07112)
			(type default)
		)
		(layer "In6.Cu")
	)
	(gr_line
		(start 79.768192 -401.720558)
		(end 79.945992 -401.646898)
		(stroke
			(width 0.07112)
			(type default)
		)
		(layer "In6.Cu")
	)
	(gr_line
		(start 79.819246 -416.124136)
		(end 79.716376 -416.818064)
		(stroke
			(width 0.07112)
			(type default)
		)
		(layer "In6.Cu")
	)
	(gr_line
		(start 79.829914 -417.974526)
		(end 79.829406 -417.97478)
		(stroke
			(width 0.07112)
			(type default)
		)
		(layer "In6.Cu")
	)
	(gr_line
		(start 79.91221 -415.49828)
		(end 79.819246 -416.124136)
		(stroke
			(width 0.07112)
			(type default)
		)
		(layer "In6.Cu")
	)
	(gr_line
		(start 79.9338 -417.282884)
		(end 80.0481 -417.437062)
		(stroke
			(width 0.07112)
			(type default)
		)
		(layer "In6.Cu")
	)
	(gr_line
		(start 79.945992 -401.646898)
		(end 80.302862 -401.794726)
		(stroke
			(width 0.07112)
			(type default)
		)
		(layer "In6.Cu")
	)
	(gr_line
		(start 79.958184 -410.030168)
		(end 80.249014 -410.320998)
		(stroke
			(width 0.07112)
			(type default)
		)
		(layer "In6.Cu")
	)
	(gr_line
		(start 79.985616 -417.859464)
		(end 79.831438 -417.973256)
		(stroke
			(width 0.07112)
			(type default)
		)
		(layer "In6.Cu")
	)
	(gr_line
		(start 79.995014 -416.859212)
		(end 79.93253 -417.281106)
		(stroke
			(width 0.07112)
			(type default)
		)
		(layer "In6.Cu")
	)
	(gr_line
		(start 80.01508 -414.804352)
		(end 79.91221 -415.49828)
		(stroke
			(width 0.07112)
			(type default)
		)
		(layer "In6.Cu")
	)
	(gr_line
		(start 80.0481 -417.437062)
		(end 79.985616 -417.859464)
		(stroke
			(width 0.07112)
			(type default)
		)
		(layer "In6.Cu")
	)
	(gr_line
		(start 80.084676 -414.334706)
		(end 80.01508 -414.804352)
		(stroke
			(width 0.07112)
			(type default)
		)
		(layer "In6.Cu")
	)
	(gr_line
		(start 80.08747 -375.094754)
		(end 79.66075 -375.094754)
		(stroke
			(width 0.07112)
			(type default)
		)
		(layer "In6.Cu")
	)
	(gr_line
		(start 80.099408 -416.167062)
		(end 80.213708 -416.32124)
		(stroke
			(width 0.07112)
			(type default)
		)
		(layer "In6.Cu")
	)
	(gr_line
		(start 80.15097 -416.743642)
		(end 79.996792 -416.857942)
		(stroke
			(width 0.07112)
			(type default)
		)
		(layer "In6.Cu")
	)
	(gr_line
		(start 80.187546 -413.641032)
		(end 80.084676 -414.334706)
		(stroke
			(width 0.07112)
			(type default)
		)
		(layer "In6.Cu")
	)
	(gr_line
		(start 80.190848 -415.539428)
		(end 80.098138 -416.165538)
		(stroke
			(width 0.07112)
			(type default)
		)
		(layer "In6.Cu")
	)
	(gr_line
		(start 80.213708 -416.32124)
		(end 80.15097 -416.743642)
		(stroke
			(width 0.07112)
			(type default)
		)
		(layer "In6.Cu")
	)
	(gr_line
		(start 80.22336 -375.230644)
		(end 80.08747 -375.094754)
		(stroke
			(width 0.07112)
			(type default)
		)
		(layer "In6.Cu")
	)
	(gr_line
		(start 80.22463 -375.513854)
		(end 79.52359 -375.513854)
		(stroke
			(width 0.07112)
			(type default)
		)
		(layer "In6.Cu")
	)
	(gr_line
		(start 80.249014 -411.123892)
		(end 80.249014 -411.824932)
		(stroke
			(width 0.07112)
			(type default)
		)
		(layer "In6.Cu")
	)
	(gr_line
		(start 80.294988 -414.847278)
		(end 80.409542 -415.001456)
		(stroke
			(width 0.07112)
			(type default)
		)
		(layer "In6.Cu")
	)
	(gr_line
		(start 80.302862 -401.794726)
		(end 80.376776 -401.972526)
		(stroke
			(width 0.07112)
			(type default)
		)
		(layer "In6.Cu")
	)
	(gr_line
		(start 80.347058 -415.423858)
		(end 80.192626 -415.538158)
		(stroke
			(width 0.07112)
			(type default)
		)
		(layer "In6.Cu")
	)
	(gr_line
		(start 80.363568 -414.376108)
		(end 80.293972 -414.845754)
		(stroke
			(width 0.07112)
			(type default)
		)
		(layer "In6.Cu")
	)
	(gr_line
		(start 80.409542 -415.001456)
		(end 80.347058 -415.423858)
		(stroke
			(width 0.07112)
			(type default)
		)
		(layer "In6.Cu")
	)
	(gr_line
		(start 80.467708 -413.683704)
		(end 80.582262 -413.83839)
		(stroke
			(width 0.07112)
			(type default)
		)
		(layer "In6.Cu")
	)
	(gr_line
		(start 80.519524 -414.260792)
		(end 80.365092 -414.374838)
		(stroke
			(width 0.07112)
			(type default)
		)
		(layer "In6.Cu")
	)
	(gr_line
		(start 80.532224 -411.125162)
		(end 80.668114 -411.261052)
		(stroke
			(width 0.07112)
			(type default)
		)
		(layer "In6.Cu")
	)
	(gr_line
		(start 80.582262 -413.83839)
		(end 80.519524 -414.260792)
		(stroke
			(width 0.07112)
			(type default)
		)
		(layer "In6.Cu")
	)
	(gr_line
		(start 80.668114 -411.687772)
		(end 80.532224 -411.823662)
		(stroke
			(width 0.07112)
			(type default)
		)
		(layer "In6.Cu")
	)
	(gr_line
		(start 80.668114 -411.261052)
		(end 80.668114 -411.687772)
		(stroke
			(width 0.07112)
			(type default)
		)
		(layer "In6.Cu")
	)
	(gr_line
		(start 80.821784 -410.030168)
		(end 80.530954 -410.320998)
		(stroke
			(width 0.07112)
			(type default)
		)
		(layer "In6.Cu")
	)
	(gr_line
		(start 81.193894 -9.780016)
		(end 81.193894 -0.508)
		(stroke
			(width 0.2)
			(type default)
		)
		(layer "In6.Cu")
	)
	(gr_arc
		(start 81.193894 -9.780016)
		(mid 81.928474 -11.55343)
		(end 83.70189 -12.288012)
		(stroke
			(width 0.2)
			(type default)
		)
		(layer "In6.Cu")
	)
	(gr_line
		(start 81.193894 -0.508)
		(end 13.610082 -0.508)
		(stroke
			(width 0.2)
			(type default)
		)
		(layer "In6.Cu")
	)
	(gr_line
		(start 81.522824 -427.830742)
		(end 81.650078 -427.957996)
		(stroke
			(width 0.07112)
			(type default)
		)
		(layer "In6.Cu")
	)
	(gr_line
		(start 81.522824 -427.548802)
		(end 81.650078 -427.421548)
		(stroke
			(width 0.07112)
			(type default)
		)
		(layer "In6.Cu")
	)
	(gr_line
		(start 81.604866 -394.798804)
		(end 81.468976 -394.662914)
		(stroke
			(width 0.07112)
			(type default)
		)
		(layer "In6.Cu")
	)
	(gr_line
		(start 81.643474 -397.805148)
		(end 82.319368 -397.992092)
		(stroke
			(width 0.07112)
			(type default)
		)
		(layer "In6.Cu")
	)
	(gr_line
		(start 81.650078 -427.957996)
		(end 81.650078 -428.28972)
		(stroke
			(width 0.07112)
			(type default)
		)
		(layer "In6.Cu")
	)
	(gr_line
		(start 81.650078 -427.421548)
		(end 81.650078 -427.089824)
		(stroke
			(width 0.07112)
			(type default)
		)
		(layer "In6.Cu")
	)
	(gr_line
		(start 81.710276 -399.128488)
		(end 82.342482 -399.320258)
		(stroke
			(width 0.07112)
			(type default)
		)
		(layer "In6.Cu")
	)
	(gr_line
		(start 81.720182 -397.532606)
		(end 81.887314 -397.43761)
		(stroke
			(width 0.07112)
			(type default)
		)
		(layer "In6.Cu")
	)
	(gr_line
		(start 81.780634 -404.17369)
		(end 81.489804 -404.46452)
		(stroke
			(width 0.07112)
			(type default)
		)
		(layer "In6.Cu")
	)
	(gr_line
		(start 81.793334 -398.857724)
		(end 81.91754 -398.79143)
		(stroke
			(width 0.07112)
			(type default)
		)
		(layer "In6.Cu")
	)
	(gr_line
		(start 81.887314 -397.43761)
		(end 82.298794 -397.551402)
		(stroke
			(width 0.07112)
			(type default)
		)
		(layer "In6.Cu")
	)
	(gr_line
		(start 81.91754 -398.79143)
		(end 82.357214 -398.92478)
		(stroke
			(width 0.07112)
			(type default)
		)
		(layer "In6.Cu")
	)
	(gr_line
		(start 82.031586 -394.798804)
		(end 81.604866 -394.798804)
		(stroke
			(width 0.07112)
			(type default)
		)
		(layer "In6.Cu")
	)
	(gr_line
		(start 82.062574 -404.17369)
		(end 82.353404 -404.46452)
		(stroke
			(width 0.07112)
			(type default)
		)
		(layer "In6.Cu")
	)
	(gr_line
		(start 82.167476 -394.662914)
		(end 82.031586 -394.798804)
		(stroke
			(width 0.07112)
			(type default)
		)
		(layer "In6.Cu")
	)
	(gr_line
		(start 82.168746 -394.379704)
		(end 81.467706 -394.379704)
		(stroke
			(width 0.07112)
			(type default)
		)
		(layer "In6.Cu")
	)
	(gr_line
		(start 82.216752 -375.094754)
		(end 82.080862 -375.230644)
		(stroke
			(width 0.07112)
			(type default)
		)
		(layer "In6.Cu")
	)
	(gr_line
		(start 82.298794 -397.551402)
		(end 82.393536 -397.719042)
		(stroke
			(width 0.07112)
			(type default)
		)
		(layer "In6.Cu")
	)
	(gr_line
		(start 82.304128 -395.918944)
		(end 82.168238 -395.783054)
		(stroke
			(width 0.07112)
			(type default)
		)
		(layer "In6.Cu")
	)
	(gr_line
		(start 82.357214 -398.92478)
		(end 82.423508 -399.048986)
		(stroke
			(width 0.07112)
			(type default)
		)
		(layer "In6.Cu")
	)
	(gr_line
		(start 82.394552 -416.99815)
		(end 82.224118 -417.678362)
		(stroke
			(width 0.07112)
			(type default)
		)
		(layer "In6.Cu")
	)
	(gr_line
		(start 82.394552 -397.720566)
		(end 82.394552 -397.720312)
		(stroke
			(width 0.07112)
			(type default)
		)
		(layer "In6.Cu")
	)
	(gr_line
		(start 82.431128 -401.913598)
		(end 83.079336 -402.182076)
		(stroke
			(width 0.07112)
			(type default)
		)
		(layer "In6.Cu")
	)
	(gr_line
		(start 82.512154 -400.76247)
		(end 83.172808 -400.99869)
		(stroke
			(width 0.07112)
			(type default)
		)
		(layer "In6.Cu")
	)
	(gr_line
		(start 82.539078 -401.65274)
		(end 82.539078 -401.652994)
		(stroke
			(width 0.07112)
			(type default)
		)
		(layer "In6.Cu")
	)
	(gr_line
		(start 82.540602 -401.652232)
		(end 82.718148 -401.578572)
		(stroke
			(width 0.07112)
			(type default)
		)
		(layer "In6.Cu")
	)
	(gr_line
		(start 82.60842 -400.496024)
		(end 82.782664 -400.413728)
		(stroke
			(width 0.07112)
			(type default)
		)
		(layer "In6.Cu")
	)
	(gr_line
		(start 82.643472 -375.094754)
		(end 82.216752 -375.094754)
		(stroke
			(width 0.07112)
			(type default)
		)
		(layer "In6.Cu")
	)
	(gr_line
		(start 82.664554 -417.647374)
		(end 82.498946 -417.74618)
		(stroke
			(width 0.07112)
			(type default)
		)
		(layer "In6.Cu")
	)
	(gr_line
		(start 82.668364 -415.904172)
		(end 82.498184 -416.584384)
		(stroke
			(width 0.07112)
			(type default)
		)
		(layer "In6.Cu")
	)
	(gr_line
		(start 82.668872 -417.067746)
		(end 82.768186 -417.2331)
		(stroke
			(width 0.07112)
			(type default)
		)
		(layer "In6.Cu")
	)
	(gr_line
		(start 82.718148 -401.578572)
		(end 83.11261 -401.741894)
		(stroke
			(width 0.07112)
			(type default)
		)
		(layer "In6.Cu")
	)
	(gr_line
		(start 82.730848 -395.918944)
		(end 82.304128 -395.918944)
		(stroke
			(width 0.07112)
			(type default)
		)
		(layer "In6.Cu")
	)
	(gr_line
		(start 82.732626 -394.798804)
		(end 82.596736 -394.662914)
		(stroke
			(width 0.07112)
			(type default)
		)
		(layer "In6.Cu")
	)
	(gr_line
		(start 82.768186 -417.2331)
		(end 82.664554 -417.647374)
		(stroke
			(width 0.07112)
			(type default)
		)
		(layer "In6.Cu")
	)
	(gr_line
		(start 82.779362 -375.230644)
		(end 82.643472 -375.094754)
		(stroke
			(width 0.07112)
			(type default)
		)
		(layer "In6.Cu")
	)
	(gr_line
		(start 82.780632 -375.513854)
		(end 82.079592 -375.513854)
		(stroke
			(width 0.07112)
			(type default)
		)
		(layer "In6.Cu")
	)
	(gr_line
		(start 82.782664 -400.413728)
		(end 83.184746 -400.557492)
		(stroke
			(width 0.07112)
			(type default)
		)
		(layer "In6.Cu")
	)
	(gr_line
		(start 82.866738 -395.783054)
		(end 82.730848 -395.918944)
		(stroke
			(width 0.07112)
			(type default)
		)
		(layer "In6.Cu")
	)
	(gr_line
		(start 82.868008 -395.499844)
		(end 82.166968 -395.499844)
		(stroke
			(width 0.07112)
			(type default)
		)
		(layer "In6.Cu")
	)
	(gr_line
		(start 82.93862 -416.553396)
		(end 82.773012 -416.652456)
		(stroke
			(width 0.07112)
			(type default)
		)
		(layer "In6.Cu")
	)
	(gr_line
		(start 82.94243 -414.810194)
		(end 82.771996 -415.490406)
		(stroke
			(width 0.07112)
			(type default)
		)
		(layer "In6.Cu")
	)
	(gr_line
		(start 82.942938 -415.973768)
		(end 83.042252 -416.139122)
		(stroke
			(width 0.07112)
			(type default)
		)
		(layer "In6.Cu")
	)
	(gr_line
		(start 83.021424 -410.030168)
		(end 83.312254 -410.320998)
		(stroke
			(width 0.07112)
			(type default)
		)
		(layer "In6.Cu")
	)
	(gr_line
		(start 83.042252 -416.139122)
		(end 82.93862 -416.553396)
		(stroke
			(width 0.07112)
			(type default)
		)
		(layer "In6.Cu")
	)
	(gr_line
		(start 83.11261 -401.741894)
		(end 83.18627 -401.919948)
		(stroke
			(width 0.07112)
			(type default)
		)
		(layer "In6.Cu")
	)
	(gr_line
		(start 83.159346 -394.798804)
		(end 82.732626 -394.798804)
		(stroke
			(width 0.07112)
			(type default)
		)
		(layer "In6.Cu")
	)
	(gr_line
		(start 83.172808 -400.99869)
		(end 83.173062 -400.99869)
		(stroke
			(width 0.07112)
			(type default)
		)
		(layer "In6.Cu")
	)
	(gr_line
		(start 83.184746 -400.557492)
		(end 83.267042 -400.731736)
		(stroke
			(width 0.07112)
			(type default)
		)
		(layer "In6.Cu")
	)
	(gr_line
		(start 83.212686 -415.459418)
		(end 83.047078 -415.558478)
		(stroke
			(width 0.07112)
			(type default)
		)
		(layer "In6.Cu")
	)
	(gr_line
		(start 83.216496 -413.716216)
		(end 83.046062 -414.396428)
		(stroke
			(width 0.07112)
			(type default)
		)
		(layer "In6.Cu")
	)
	(gr_line
		(start 83.217004 -414.879536)
		(end 83.316318 -415.045144)
		(stroke
			(width 0.07112)
			(type default)
		)
		(layer "In6.Cu")
	)
	(gr_line
		(start 83.295236 -394.662914)
		(end 83.159346 -394.798804)
		(stroke
			(width 0.07112)
			(type default)
		)
		(layer "In6.Cu")
	)
	(gr_line
		(start 83.296506 -394.379704)
		(end 82.595466 -394.379704)
		(stroke
			(width 0.07112)
			(type default)
		)
		(layer "In6.Cu")
	)
	(gr_line
		(start 83.316318 -415.045144)
		(end 83.212686 -415.459418)
		(stroke
			(width 0.07112)
			(type default)
		)
		(layer "In6.Cu")
	)
	(gr_line
		(start 83.431888 -395.918944)
		(end 83.295998 -395.783054)
		(stroke
			(width 0.07112)
			(type default)
		)
		(layer "In6.Cu")
	)
	(gr_line
		(start 83.47329 -402.345398)
		(end 84.12099 -402.613368)
		(stroke
			(width 0.07112)
			(type default)
		)
		(layer "In6.Cu")
	)
	(gr_line
		(start 83.486752 -414.36544)
		(end 83.32089 -414.4645)
		(stroke
			(width 0.07112)
			(type default)
		)
		(layer "In6.Cu")
	)
	(gr_line
		(start 83.49107 -413.785558)
		(end 83.590384 -413.951166)
		(stroke
			(width 0.07112)
			(type default)
		)
		(layer "In6.Cu")
	)
	(gr_line
		(start 83.52282 -426.830998)
		(end 83.650074 -426.958252)
		(stroke
			(width 0.07112)
			(type default)
		)
		(layer "In6.Cu")
	)
	(gr_line
		(start 83.52282 -426.548804)
		(end 83.650074 -426.42155)
		(stroke
			(width 0.07112)
			(type default)
		)
		(layer "In6.Cu")
	)
	(gr_line
		(start 83.58251 -402.084032)
		(end 83.76031 -402.010372)
		(stroke
			(width 0.07112)
			(type default)
		)
		(layer "In6.Cu")
	)
	(gr_line
		(start 83.590384 -413.951166)
		(end 83.486752 -414.36544)
		(stroke
			(width 0.07112)
			(type default)
		)
		(layer "In6.Cu")
	)
	(gr_line
		(start 83.621372 -401.158964)
		(end 84.243418 -401.381468)
		(stroke
			(width 0.07112)
			(type default)
		)
		(layer "In6.Cu")
	)
	(gr_line
		(start 83.650074 -426.958252)
		(end 83.650074 -427.289976)
		(stroke
			(width 0.07112)
			(type default)
		)
		(layer "In6.Cu")
	)
	(gr_line
		(start 83.650074 -426.42155)
		(end 83.650074 -426.089826)
		(stroke
			(width 0.07112)
			(type default)
		)
		(layer "In6.Cu")
	)
	(gr_line
		(start 83.717892 -400.892772)
		(end 83.891882 -400.810476)
		(stroke
			(width 0.07112)
			(type default)
		)
		(layer "In6.Cu")
	)
	(gr_line
		(start 83.76031 -402.010372)
		(end 84.154772 -402.173694)
		(stroke
			(width 0.07112)
			(type default)
		)
		(layer "In6.Cu")
	)
	(gr_line
		(start 83.858608 -395.918944)
		(end 83.431888 -395.918944)
		(stroke
			(width 0.07112)
			(type default)
		)
		(layer "In6.Cu")
	)
	(gr_line
		(start 83.860386 -394.798804)
		(end 83.724496 -394.662914)
		(stroke
			(width 0.07112)
			(type default)
		)
		(layer "In6.Cu")
	)
	(gr_line
		(start 83.885024 -410.030168)
		(end 83.594194 -410.320998)
		(stroke
			(width 0.07112)
			(type default)
		)
		(layer "In6.Cu")
	)
	(gr_line
		(start 83.891882 -400.810476)
		(end 84.25561 -400.940524)
		(stroke
			(width 0.07112)
			(type default)
		)
		(layer "In6.Cu")
	)
	(gr_line
		(start 83.994498 -395.783054)
		(end 83.858608 -395.918944)
		(stroke
			(width 0.07112)
			(type default)
		)
		(layer "In6.Cu")
	)
	(gr_line
		(start 83.995768 -395.499844)
		(end 83.294728 -395.499844)
		(stroke
			(width 0.07112)
			(type default)
		)
		(layer "In6.Cu")
	)
	(gr_line
		(start 84.154772 -402.173694)
		(end 84.228178 -402.351494)
		(stroke
			(width 0.07112)
			(type default)
		)
		(layer "In6.Cu")
	)
	(gr_arc
		(start 84.20989 -7.78002)
		(mid 84.646886 -8.83502)
		(end 85.701886 -9.272016)
		(stroke
			(width 0.2)
			(type default)
		)
		(layer "In6.Cu")
	)
	(gr_arc
		(start 84.20989 0.40005)
		(mid 83.475332 2.173501)
		(end 81.701894 2.908046)
		(stroke
			(width 0.2)
			(type default)
		)
		(layer "In6.Cu")
	)
	(gr_line
		(start 84.20989 0.40005)
		(end 84.20989 -7.78002)
		(stroke
			(width 0.2)
			(type default)
		)
		(layer "In6.Cu")
	)
	(gr_line
		(start 84.22894 -402.353272)
		(end 84.22894 -402.352764)
		(stroke
			(width 0.07112)
			(type default)
		)
		(layer "In6.Cu")
	)
	(gr_line
		(start 84.25561 -400.940524)
		(end 84.337652 -401.114514)
		(stroke
			(width 0.07112)
			(type default)
		)
		(layer "In6.Cu")
	)
	(gr_line
		(start 84.287106 -394.798804)
		(end 83.860386 -394.798804)
		(stroke
			(width 0.07112)
			(type default)
		)
		(layer "In6.Cu")
	)
	(gr_line
		(start 84.422996 -394.662914)
		(end 84.287106 -394.798804)
		(stroke
			(width 0.07112)
			(type default)
		)
		(layer "In6.Cu")
	)
	(gr_line
		(start 84.424266 -394.379704)
		(end 83.723226 -394.379704)
		(stroke
			(width 0.07112)
			(type default)
		)
		(layer "In6.Cu")
	)
	(gr_line
		(start 84.843874 -404.17369)
		(end 84.553044 -404.46452)
		(stroke
			(width 0.07112)
			(type default)
		)
		(layer "In6.Cu")
	)
	(gr_line
		(start 84.978748 -417.663122)
		(end 84.944712 -417.775136)
		(stroke
			(width 0.07112)
			(type default)
		)
		(layer "In6.Cu")
	)
	(gr_line
		(start 84.987638 -417.658296)
		(end 84.978748 -417.663122)
		(stroke
			(width 0.07112)
			(type default)
		)
		(layer "In6.Cu")
	)
	(gr_line
		(start 84.988146 -394.798804)
		(end 84.852256 -394.662914)
		(stroke
			(width 0.07112)
			(type default)
		)
		(layer "In6.Cu")
	)
	(gr_line
		(start 85.125814 -404.17369)
		(end 85.416644 -404.46452)
		(stroke
			(width 0.07112)
			(type default)
		)
		(layer "In6.Cu")
	)
	(gr_line
		(start 85.157056 -417.09975)
		(end 84.987638 -417.658296)
		(stroke
			(width 0.07112)
			(type default)
		)
		(layer "In6.Cu")
	)
	(gr_line
		(start 85.15731 -417.098988)
		(end 85.157056 -417.09975)
		(stroke
			(width 0.07112)
			(type default)
		)
		(layer "In6.Cu")
	)
	(gr_line
		(start 85.281008 -416.691318)
		(end 85.237066 -416.835844)
		(stroke
			(width 0.07112)
			(type default)
		)
		(layer "In6.Cu")
	)
	(gr_line
		(start 85.394546 -417.760912)
		(end 85.216238 -417.856162)
		(stroke
			(width 0.07112)
			(type default)
		)
		(layer "In6.Cu")
	)
	(gr_line
		(start 85.414866 -394.798804)
		(end 84.988146 -394.798804)
		(stroke
			(width 0.07112)
			(type default)
		)
		(layer "In6.Cu")
	)
	(gr_line
		(start 85.427312 -417.180522)
		(end 85.427058 -417.181284)
		(stroke
			(width 0.07112)
			(type default)
		)
		(layer "In6.Cu")
	)
	(gr_line
		(start 85.42782 -417.182808)
		(end 85.518498 -417.35248)
		(stroke
			(width 0.07112)
			(type default)
		)
		(layer "In6.Cu")
	)
	(gr_line
		(start 85.484716 -416.02025)
		(end 85.281008 -416.691318)
		(stroke
			(width 0.07112)
			(type default)
		)
		(layer "In6.Cu")
	)
	(gr_line
		(start 85.518498 -417.35248)
		(end 85.394546 -417.760912)
		(stroke
			(width 0.07112)
			(type default)
		)
		(layer "In6.Cu")
	)
	(gr_line
		(start 85.522816 -427.830742)
		(end 85.65007 -427.957996)
		(stroke
			(width 0.07112)
			(type default)
		)
		(layer "In6.Cu")
	)
	(gr_line
		(start 85.522816 -427.548802)
		(end 85.65007 -427.421548)
		(stroke
			(width 0.07112)
			(type default)
		)
		(layer "In6.Cu")
	)
	(gr_line
		(start 85.550756 -416.773106)
		(end 85.507068 -416.917632)
		(stroke
			(width 0.07112)
			(type default)
		)
		(layer "In6.Cu")
	)
	(gr_line
		(start 85.550756 -394.662914)
		(end 85.414866 -394.798804)
		(stroke
			(width 0.07112)
			(type default)
		)
		(layer "In6.Cu")
	)
	(gr_line
		(start 85.552026 -394.379704)
		(end 84.850986 -394.379704)
		(stroke
			(width 0.07112)
			(type default)
		)
		(layer "In6.Cu")
	)
	(gr_line
		(start 85.65007 -427.957996)
		(end 85.65007 -428.28972)
		(stroke
			(width 0.07112)
			(type default)
		)
		(layer "In6.Cu")
	)
	(gr_line
		(start 85.65007 -427.421548)
		(end 85.65007 -427.089824)
		(stroke
			(width 0.07112)
			(type default)
		)
		(layer "In6.Cu")
	)
	(gr_line
		(start 85.701886 -9.272016)
		(end 122.102118 -9.272016)
		(stroke
			(width 0.2)
			(type default)
		)
		(layer "In6.Cu")
	)
	(gr_line
		(start 85.722206 -416.681666)
		(end 85.552534 -416.772344)
		(stroke
			(width 0.07112)
			(type default)
		)
		(layer "In6.Cu")
	)
	(gr_line
		(start 85.755226 -416.103562)
		(end 85.845904 -416.273234)
		(stroke
			(width 0.07112)
			(type default)
		)
		(layer "In6.Cu")
	)
	(gr_line
		(start 85.845904 -416.273234)
		(end 85.722206 -416.681666)
		(stroke
			(width 0.07112)
			(type default)
		)
		(layer "In6.Cu")
	)
	(gr_line
		(start 85.880194 -414.716214)
		(end 85.67674 -415.387282)
		(stroke
			(width 0.07112)
			(type default)
		)
		(layer "In6.Cu")
	)
	(gr_line
		(start 86.004146 -414.308036)
		(end 85.985096 -414.37052)
		(stroke
			(width 0.07112)
			(type default)
		)
		(layer "In6.Cu")
	)
	(gr_line
		(start 86.084664 -410.030168)
		(end 86.375494 -410.320998)
		(stroke
			(width 0.07112)
			(type default)
		)
		(layer "In6.Cu")
	)
	(gr_line
		(start 86.115906 -394.798804)
		(end 85.980016 -394.662914)
		(stroke
			(width 0.07112)
			(type default)
		)
		(layer "In6.Cu")
	)
	(gr_line
		(start 86.117684 -415.37763)
		(end 85.948012 -415.468308)
		(stroke
			(width 0.07112)
			(type default)
		)
		(layer "In6.Cu")
	)
	(gr_line
		(start 86.150958 -414.799526)
		(end 86.241636 -414.969198)
		(stroke
			(width 0.07112)
			(type default)
		)
		(layer "In6.Cu")
	)
	(gr_line
		(start 86.207854 -413.63646)
		(end 86.004146 -414.308036)
		(stroke
			(width 0.07112)
			(type default)
		)
		(layer "In6.Cu")
	)
	(gr_line
		(start 86.241636 -414.969198)
		(end 86.117684 -415.37763)
		(stroke
			(width 0.07112)
			(type default)
		)
		(layer "In6.Cu")
	)
	(gr_line
		(start 86.273894 -414.389824)
		(end 86.255098 -414.452308)
		(stroke
			(width 0.07112)
			(type default)
		)
		(layer "In6.Cu")
	)
	(gr_line
		(start 86.375494 -413.028384)
		(end 86.37524 -413.028384)
		(stroke
			(width 0.07112)
			(type default)
		)
		(layer "In6.Cu")
	)
	(gr_line
		(start 86.375494 -411.24124)
		(end 86.375494 -411.94228)
		(stroke
			(width 0.07112)
			(type default)
		)
		(layer "In6.Cu")
	)
	(gr_line
		(start 86.445344 -414.298384)
		(end 86.275418 -414.389062)
		(stroke
			(width 0.07112)
			(type default)
		)
		(layer "In6.Cu")
	)
	(gr_line
		(start 86.478364 -413.720026)
		(end 86.569042 -413.889698)
		(stroke
			(width 0.07112)
			(type default)
		)
		(layer "In6.Cu")
	)
	(gr_line
		(start 86.542626 -394.798804)
		(end 86.115906 -394.798804)
		(stroke
			(width 0.07112)
			(type default)
		)
		(layer "In6.Cu")
	)
	(gr_line
		(start 86.569042 -413.889698)
		(end 86.445344 -414.298384)
		(stroke
			(width 0.07112)
			(type default)
		)
		(layer "In6.Cu")
	)
	(gr_line
		(start 86.658704 -411.24251)
		(end 86.794594 -411.3784)
		(stroke
			(width 0.07112)
			(type default)
		)
		(layer "In6.Cu")
	)
	(gr_line
		(start 86.678516 -394.662914)
		(end 86.542626 -394.798804)
		(stroke
			(width 0.07112)
			(type default)
		)
		(layer "In6.Cu")
	)
	(gr_line
		(start 86.679786 -394.379704)
		(end 85.978746 -394.379704)
		(stroke
			(width 0.07112)
			(type default)
		)
		(layer "In6.Cu")
	)
	(gr_line
		(start 86.784942 -401.094448)
		(end 87.395304 -401.347178)
		(stroke
			(width 0.07112)
			(type default)
		)
		(layer "In6.Cu")
	)
	(gr_line
		(start 86.794594 -411.80512)
		(end 86.658704 -411.94101)
		(stroke
			(width 0.07112)
			(type default)
		)
		(layer "In6.Cu")
	)
	(gr_line
		(start 86.794594 -411.3784)
		(end 86.794594 -411.80512)
		(stroke
			(width 0.07112)
			(type default)
		)
		(layer "In6.Cu")
	)
	(gr_line
		(start 86.894162 -400.833082)
		(end 87.034116 -400.77517)
		(stroke
			(width 0.07112)
			(type default)
		)
		(layer "In6.Cu")
	)
	(gr_line
		(start 86.948264 -410.030168)
		(end 86.657434 -410.320998)
		(stroke
			(width 0.07112)
			(type default)
		)
		(layer "In6.Cu")
	)
	(gr_line
		(start 87.034116 -400.77517)
		(end 87.44458 -400.945096)
		(stroke
			(width 0.07112)
			(type default)
		)
		(layer "In6.Cu")
	)
	(gr_line
		(start 87.201248 -205.543404)
		(end 87.065358 -205.407514)
		(stroke
			(width 0.07112)
			(type default)
		)
		(layer "In6.Cu")
	)
	(gr_line
		(start 87.44458 -400.945096)
		(end 87.502746 -401.08505)
		(stroke
			(width 0.07112)
			(type default)
		)
		(layer "In6.Cu")
	)
	(gr_line
		(start 87.522812 -426.830998)
		(end 87.650066 -426.958252)
		(stroke
			(width 0.07112)
			(type default)
		)
		(layer "In6.Cu")
	)
	(gr_line
		(start 87.522812 -426.548804)
		(end 87.650066 -426.42155)
		(stroke
			(width 0.07112)
			(type default)
		)
		(layer "In6.Cu")
	)
	(gr_line
		(start 87.627968 -205.543404)
		(end 87.201248 -205.543404)
		(stroke
			(width 0.07112)
			(type default)
		)
		(layer "In6.Cu")
	)
	(gr_line
		(start 87.650066 -426.958252)
		(end 87.650066 -427.289976)
		(stroke
			(width 0.07112)
			(type default)
		)
		(layer "In6.Cu")
	)
	(gr_line
		(start 87.650066 -426.42155)
		(end 87.650066 -426.089826)
		(stroke
			(width 0.07112)
			(type default)
		)
		(layer "In6.Cu")
	)
	(gr_line
		(start 87.763858 -205.407514)
		(end 87.627968 -205.543404)
		(stroke
			(width 0.07112)
			(type default)
		)
		(layer "In6.Cu")
	)
	(gr_line
		(start 87.765128 -205.124304)
		(end 87.064088 -205.124304)
		(stroke
			(width 0.07112)
			(type default)
		)
		(layer "In6.Cu")
	)
	(gr_line
		(start 87.845646 -416.608768)
		(end 87.577168 -417.256722)
		(stroke
			(width 0.07112)
			(type default)
		)
		(layer "In6.Cu")
	)
	(gr_line
		(start 87.907114 -404.17369)
		(end 87.616284 -404.46452)
		(stroke
			(width 0.07112)
			(type default)
		)
		(layer "In6.Cu")
	)
	(gr_line
		(start 88.01735 -417.290504)
		(end 87.839296 -417.36391)
		(stroke
			(width 0.07112)
			(type default)
		)
		(layer "In6.Cu")
	)
	(gr_line
		(start 88.107012 -416.717988)
		(end 88.180672 -416.895788)
		(stroke
			(width 0.07112)
			(type default)
		)
		(layer "In6.Cu")
	)
	(gr_line
		(start 88.180672 -416.895788)
		(end 88.01735 -417.290504)
		(stroke
			(width 0.07112)
			(type default)
		)
		(layer "In6.Cu")
	)
	(gr_line
		(start 88.189054 -404.17369)
		(end 88.479884 -404.46452)
		(stroke
			(width 0.07112)
			(type default)
		)
		(layer "In6.Cu")
	)
	(gr_line
		(start 88.277446 -415.566606)
		(end 88.008968 -416.214814)
		(stroke
			(width 0.07112)
			(type default)
		)
		(layer "In6.Cu")
	)
	(gr_line
		(start 88.329008 -205.543404)
		(end 88.193118 -205.407514)
		(stroke
			(width 0.07112)
			(type default)
		)
		(layer "In6.Cu")
	)
	(gr_line
		(start 88.44915 -416.248342)
		(end 88.271096 -416.322002)
		(stroke
			(width 0.07112)
			(type default)
		)
		(layer "In6.Cu")
	)
	(gr_line
		(start 88.538558 -415.675826)
		(end 88.612218 -415.85388)
		(stroke
			(width 0.07112)
			(type default)
		)
		(layer "In6.Cu")
	)
	(gr_line
		(start 88.612218 -415.85388)
		(end 88.44915 -416.248342)
		(stroke
			(width 0.07112)
			(type default)
		)
		(layer "In6.Cu")
	)
	(gr_line
		(start 88.755728 -205.543404)
		(end 88.329008 -205.543404)
		(stroke
			(width 0.07112)
			(type default)
		)
		(layer "In6.Cu")
	)
	(gr_line
		(start 88.891618 -205.407514)
		(end 88.755728 -205.543404)
		(stroke
			(width 0.07112)
			(type default)
		)
		(layer "In6.Cu")
	)
	(gr_line
		(start 88.892888 -205.124304)
		(end 88.191848 -205.124304)
		(stroke
			(width 0.07112)
			(type default)
		)
		(layer "In6.Cu")
	)
	(gr_line
		(start 89.147904 -410.030168)
		(end 89.438734 -410.320998)
		(stroke
			(width 0.07112)
			(type default)
		)
		(layer "In6.Cu")
	)
	(gr_line
		(start 89.428828 -413.083502)
		(end 89.428828 -413.083756)
		(stroke
			(width 0.07112)
			(type default)
		)
		(layer "In6.Cu")
	)
	(gr_line
		(start 89.438734 -411.178756)
		(end 89.438734 -411.879796)
		(stroke
			(width 0.07112)
			(type default)
		)
		(layer "In6.Cu")
	)
	(gr_line
		(start 89.522808 -427.830742)
		(end 89.650062 -427.957996)
		(stroke
			(width 0.07112)
			(type default)
		)
		(layer "In6.Cu")
	)
	(gr_line
		(start 89.522808 -427.548802)
		(end 89.650062 -427.421548)
		(stroke
			(width 0.07112)
			(type default)
		)
		(layer "In6.Cu")
	)
	(gr_line
		(start 89.650062 -427.957996)
		(end 89.650062 -428.28972)
		(stroke
			(width 0.07112)
			(type default)
		)
		(layer "In6.Cu")
	)
	(gr_line
		(start 89.650062 -427.421548)
		(end 89.650062 -427.089824)
		(stroke
			(width 0.07112)
			(type default)
		)
		(layer "In6.Cu")
	)
	(gr_line
		(start 89.720674 -413.034988)
		(end 89.720674 -413.03575)
		(stroke
			(width 0.07112)
			(type default)
		)
		(layer "In6.Cu")
	)
	(gr_line
		(start 89.721944 -411.180026)
		(end 89.857834 -411.315916)
		(stroke
			(width 0.07112)
			(type default)
		)
		(layer "In6.Cu")
	)
	(gr_line
		(start 89.857834 -411.742636)
		(end 89.721944 -411.878526)
		(stroke
			(width 0.07112)
			(type default)
		)
		(layer "In6.Cu")
	)
	(gr_line
		(start 89.857834 -411.315916)
		(end 89.857834 -411.742636)
		(stroke
			(width 0.07112)
			(type default)
		)
		(layer "In6.Cu")
	)
	(gr_line
		(start 90.011504 -410.030168)
		(end 89.720674 -410.320998)
		(stroke
			(width 0.07112)
			(type default)
		)
		(layer "In6.Cu")
	)
	(gr_line
		(start 90.353388 -417.437062)
		(end 90.022934 -418.055552)
		(stroke
			(width 0.07112)
			(type default)
		)
		(layer "In6.Cu")
	)
	(gr_line
		(start 90.457274 -418.13226)
		(end 90.273124 -418.187886)
		(stroke
			(width 0.07112)
			(type default)
		)
		(layer "In6.Cu")
	)
	(gr_line
		(start 90.602816 -417.571428)
		(end 90.658442 -417.755578)
		(stroke
			(width 0.07112)
			(type default)
		)
		(layer "In6.Cu")
	)
	(gr_line
		(start 90.658442 -417.755578)
		(end 90.457274 -418.13226)
		(stroke
			(width 0.07112)
			(type default)
		)
		(layer "In6.Cu")
	)
	(gr_line
		(start 90.88501 -416.442398)
		(end 90.554556 -417.060888)
		(stroke
			(width 0.07112)
			(type default)
		)
		(layer "In6.Cu")
	)
	(gr_line
		(start 90.970354 -404.17369)
		(end 90.679524 -404.46452)
		(stroke
			(width 0.07112)
			(type default)
		)
		(layer "In6.Cu")
	)
	(gr_line
		(start 90.988896 -417.137596)
		(end 90.804746 -417.193222)
		(stroke
			(width 0.07112)
			(type default)
		)
		(layer "In6.Cu")
	)
	(gr_line
		(start 91.134438 -416.576764)
		(end 91.190064 -416.760914)
		(stroke
			(width 0.07112)
			(type default)
		)
		(layer "In6.Cu")
	)
	(gr_line
		(start 91.190064 -416.760914)
		(end 90.988896 -417.137596)
		(stroke
			(width 0.07112)
			(type default)
		)
		(layer "In6.Cu")
	)
	(gr_line
		(start 91.252294 -404.17369)
		(end 91.543124 -404.46452)
		(stroke
			(width 0.07112)
			(type default)
		)
		(layer "In6.Cu")
	)
	(gr_line
		(start 91.416632 -415.44748)
		(end 91.086178 -416.066224)
		(stroke
			(width 0.07112)
			(type default)
		)
		(layer "In6.Cu")
	)
	(gr_line
		(start 91.520772 -416.142678)
		(end 91.336622 -416.198558)
		(stroke
			(width 0.07112)
			(type default)
		)
		(layer "In6.Cu")
	)
	(gr_line
		(start 91.66606 -415.5821)
		(end 91.72194 -415.76625)
		(stroke
			(width 0.07112)
			(type default)
		)
		(layer "In6.Cu")
	)
	(gr_line
		(start 91.72194 -415.76625)
		(end 91.520772 -416.142678)
		(stroke
			(width 0.07112)
			(type default)
		)
		(layer "In6.Cu")
	)
	(gr_line
		(start 92.211144 -410.030168)
		(end 92.501974 -410.320998)
		(stroke
			(width 0.07112)
			(type default)
		)
		(layer "In6.Cu")
	)
	(gr_line
		(start 92.33408 -413.731456)
		(end 92.003626 -414.349946)
		(stroke
			(width 0.07112)
			(type default)
		)
		(layer "In6.Cu")
	)
	(gr_line
		(start 92.437966 -414.426654)
		(end 92.253816 -414.48228)
		(stroke
			(width 0.07112)
			(type default)
		)
		(layer "In6.Cu")
	)
	(gr_line
		(start 92.501974 -411.100524)
		(end 92.501974 -411.801564)
		(stroke
			(width 0.07112)
			(type default)
		)
		(layer "In6.Cu")
	)
	(gr_line
		(start 92.583508 -413.865568)
		(end 92.639134 -414.049972)
		(stroke
			(width 0.07112)
			(type default)
		)
		(layer "In6.Cu")
	)
	(gr_line
		(start 92.639134 -414.049972)
		(end 92.437966 -414.426654)
		(stroke
			(width 0.07112)
			(type default)
		)
		(layer "In6.Cu")
	)
	(gr_line
		(start 92.785184 -411.101794)
		(end 92.921074 -411.237684)
		(stroke
			(width 0.07112)
			(type default)
		)
		(layer "In6.Cu")
	)
	(gr_line
		(start 92.921074 -411.664404)
		(end 92.785184 -411.800294)
		(stroke
			(width 0.07112)
			(type default)
		)
		(layer "In6.Cu")
	)
	(gr_line
		(start 92.921074 -411.237684)
		(end 92.921074 -411.664404)
		(stroke
			(width 0.07112)
			(type default)
		)
		(layer "In6.Cu")
	)
	(gr_line
		(start 93.074744 -410.030168)
		(end 92.783914 -410.320998)
		(stroke
			(width 0.07112)
			(type default)
		)
		(layer "In6.Cu")
	)
	(gr_line
		(start 93.962474 -415.854642)
		(end 93.572838 -416.437826)
		(stroke
			(width 0.07112)
			(type default)
		)
		(layer "In6.Cu")
	)
	(gr_line
		(start 93.997526 -416.556698)
		(end 93.808804 -416.59429)
		(stroke
			(width 0.07112)
			(type default)
		)
		(layer "In6.Cu")
	)
	(gr_line
		(start 94.033594 -404.17369)
		(end 93.742764 -404.46452)
		(stroke
			(width 0.07112)
			(type default)
		)
		(layer "In6.Cu")
	)
	(gr_line
		(start 94.184978 -211.555076)
		(end 94.209362 -211.555076)
		(stroke
			(width 0.07112)
			(type default)
		)
		(layer "In6.Cu")
	)
	(gr_line
		(start 94.186248 -211.838286)
		(end 94.488 -212.140038)
		(stroke
			(width 0.07112)
			(type default)
		)
		(layer "In6.Cu")
	)
	(gr_line
		(start 94.19209 -208.737454)
		(end 94.201742 -208.737454)
		(stroke
			(width 0.07112)
			(type default)
		)
		(layer "In6.Cu")
	)
	(gr_line
		(start 94.19336 -208.454244)
		(end 94.487746 -208.159858)
		(stroke
			(width 0.07112)
			(type default)
		)
		(layer "In6.Cu")
	)
	(gr_line
		(start 94.19717 -416.013138)
		(end 94.234762 -416.201606)
		(stroke
			(width 0.07112)
			(type default)
		)
		(layer "In6.Cu")
	)
	(gr_line
		(start 94.201742 -208.737454)
		(end 94.487746 -209.023458)
		(stroke
			(width 0.07112)
			(type default)
		)
		(layer "In6.Cu")
	)
	(gr_line
		(start 94.209362 -211.555076)
		(end 94.488 -211.276438)
		(stroke
			(width 0.07112)
			(type default)
		)
		(layer "In6.Cu")
	)
	(gr_line
		(start 94.234762 -416.201606)
		(end 93.997526 -416.556698)
		(stroke
			(width 0.07112)
			(type default)
		)
		(layer "In6.Cu")
	)
	(gr_line
		(start 94.315534 -404.17369)
		(end 94.606364 -404.46452)
		(stroke
			(width 0.07112)
			(type default)
		)
		(layer "In6.Cu")
	)
	(gr_line
		(start 94.488 -214.992458)
		(end 94.770194 -214.710264)
		(stroke
			(width 0.07112)
			(type default)
		)
		(layer "In6.Cu")
	)
	(gr_line
		(start 94.488 -214.128858)
		(end 94.786196 -214.427054)
		(stroke
			(width 0.07112)
			(type default)
		)
		(layer "In6.Cu")
	)
	(gr_line
		(start 94.770194 -214.710264)
		(end 94.787466 -214.710264)
		(stroke
			(width 0.07112)
			(type default)
		)
		(layer "In6.Cu")
	)
	(gr_line
		(start 95.179388 -414.033462)
		(end 94.789752 -414.616646)
		(stroke
			(width 0.07112)
			(type default)
		)
		(layer "In6.Cu")
	)
	(gr_line
		(start 95.21444 -414.735518)
		(end 95.025718 -414.77311)
		(stroke
			(width 0.07112)
			(type default)
		)
		(layer "In6.Cu")
	)
	(gr_line
		(start 95.274384 -410.030168)
		(end 95.565214 -410.320998)
		(stroke
			(width 0.07112)
			(type default)
		)
		(layer "In6.Cu")
	)
	(gr_line
		(start 95.339154 -213.512146)
		(end 95.339154 -213.085426)
		(stroke
			(width 0.07112)
			(type default)
		)
		(layer "In6.Cu")
	)
	(gr_line
		(start 95.339154 -213.085426)
		(end 95.475044 -212.949536)
		(stroke
			(width 0.07112)
			(type default)
		)
		(layer "In6.Cu")
	)
	(gr_line
		(start 95.339154 -210.553046)
		(end 95.339154 -210.126326)
		(stroke
			(width 0.07112)
			(type default)
		)
		(layer "In6.Cu")
	)
	(gr_line
		(start 95.339154 -210.126326)
		(end 95.475044 -209.990436)
		(stroke
			(width 0.07112)
			(type default)
		)
		(layer "In6.Cu")
	)
	(gr_line
		(start 95.414084 -414.191704)
		(end 95.451676 -414.380426)
		(stroke
			(width 0.07112)
			(type default)
		)
		(layer "In6.Cu")
	)
	(gr_line
		(start 95.451676 -414.380426)
		(end 95.21444 -414.735518)
		(stroke
			(width 0.07112)
			(type default)
		)
		(layer "In6.Cu")
	)
	(gr_line
		(start 95.475044 -213.648036)
		(end 95.339154 -213.512146)
		(stroke
			(width 0.07112)
			(type default)
		)
		(layer "In6.Cu")
	)
	(gr_line
		(start 95.475044 -210.688936)
		(end 95.339154 -210.553046)
		(stroke
			(width 0.07112)
			(type default)
		)
		(layer "In6.Cu")
	)
	(gr_line
		(start 95.565214 -411.069536)
		(end 95.565214 -411.770576)
		(stroke
			(width 0.07112)
			(type default)
		)
		(layer "In6.Cu")
	)
	(gr_line
		(start 95.758254 -213.649306)
		(end 95.758254 -212.948266)
		(stroke
			(width 0.07112)
			(type default)
		)
		(layer "In6.Cu")
	)
	(gr_line
		(start 95.758254 -210.690206)
		(end 95.758254 -209.989166)
		(stroke
			(width 0.07112)
			(type default)
		)
		(layer "In6.Cu")
	)
	(gr_line
		(start 95.848424 -411.070806)
		(end 95.984314 -411.206696)
		(stroke
			(width 0.07112)
			(type default)
		)
		(layer "In6.Cu")
	)
	(gr_line
		(start 95.984314 -411.633416)
		(end 95.848424 -411.769306)
		(stroke
			(width 0.07112)
			(type default)
		)
		(layer "In6.Cu")
	)
	(gr_line
		(start 95.984314 -411.206696)
		(end 95.984314 -411.633416)
		(stroke
			(width 0.07112)
			(type default)
		)
		(layer "In6.Cu")
	)
	(gr_line
		(start 96.137984 -410.030168)
		(end 95.847154 -410.320998)
		(stroke
			(width 0.07112)
			(type default)
		)
		(layer "In6.Cu")
	)
	(gr_line
		(start 96.430084 -296.340276)
		(end 96.430084 -296.354754)
		(stroke
			(width 0.05715)
			(type default)
		)
		(layer "In6.Cu")
	)
	(gr_line
		(start 96.475804 -296.294556)
		(end 96.430084 -296.340276)
		(stroke
			(width 0.05715)
			(type default)
		)
		(layer "In6.Cu")
	)
	(gr_line
		(start 96.475804 -296.280586)
		(end 96.475804 -296.294556)
		(stroke
			(width 0.05715)
			(type default)
		)
		(layer "In6.Cu")
	)
	(gr_line
		(start 96.667574 -296.281856)
		(end 96.712024 -296.326306)
		(stroke
			(width 0.05715)
			(type default)
		)
		(layer "In6.Cu")
	)
	(gr_line
		(start 96.712024 -296.326306)
		(end 96.712024 -296.354754)
		(stroke
			(width 0.05715)
			(type default)
		)
		(layer "In6.Cu")
	)
	(gr_line
		(start 96.758506 -285.74873)
		(end 96.756982 -285.749746)
		(stroke
			(width 0.05715)
			(type default)
		)
		(layer "In6.Cu")
	)
	(gr_line
		(start 96.853248 -285.914338)
		(end 96.852232 -285.914846)
		(stroke
			(width 0.05715)
			(type default)
		)
		(layer "In6.Cu")
	)
	(gr_line
		(start 97.370138 -296.26687)
		(end 97.370138 -296.281348)
		(stroke
			(width 0.05715)
			(type default)
		)
		(layer "In6.Cu")
	)
	(gr_line
		(start 97.415858 -296.22115)
		(end 97.370138 -296.26687)
		(stroke
			(width 0.05715)
			(type default)
		)
		(layer "In6.Cu")
	)
	(gr_line
		(start 97.415858 -296.20718)
		(end 97.415858 -296.22115)
		(stroke
			(width 0.05715)
			(type default)
		)
		(layer "In6.Cu")
	)
	(gr_line
		(start 97.502726 -206.923386)
		(end 97.496122 -206.923386)
		(stroke
			(width 0.07112)
			(type default)
		)
		(layer "In6.Cu")
	)
	(gr_line
		(start 97.607628 -296.20845)
		(end 97.652078 -296.2529)
		(stroke
			(width 0.05715)
			(type default)
		)
		(layer "In6.Cu")
	)
	(gr_line
		(start 97.650808 -285.777178)
		(end 97.651062 -285.777432)
		(stroke
			(width 0.05715)
			(type default)
		)
		(layer "In6.Cu")
	)
	(gr_line
		(start 97.652078 -296.2529)
		(end 97.652078 -296.281348)
		(stroke
			(width 0.05715)
			(type default)
		)
		(layer "In6.Cu")
	)
	(gr_arc
		(start 97.662238 -285.769304)
		(mid 97.6565 -285.773207)
		(end 97.650808 -285.777178)
		(stroke
			(width 0.05715)
			(type default)
		)
		(layer "In6.Cu")
	)
	(gr_line
		(start 97.669096 -285.765748)
		(end 97.662238 -285.769304)
		(stroke
			(width 0.05715)
			(type default)
		)
		(layer "In6.Cu")
	)
	(gr_line
		(start 97.693734 -284.131512)
		(end 97.690686 -284.13329)
		(stroke
			(width 0.05715)
			(type default)
		)
		(layer "In6.Cu")
	)
	(gr_line
		(start 97.697036 -284.12948)
		(end 97.695512 -284.130496)
		(stroke
			(width 0.05715)
			(type default)
		)
		(layer "In6.Cu")
	)
	(gr_line
		(start 97.698052 -284.128972)
		(end 97.697036 -284.12948)
		(stroke
			(width 0.05715)
			(type default)
		)
		(layer "In6.Cu")
	)
	(gr_line
		(start 97.772474 -285.926276)
		(end 97.768918 -285.928308)
		(stroke
			(width 0.05715)
			(type default)
		)
		(layer "In6.Cu")
	)
	(gr_line
		(start 97.785174 -284.298898)
		(end 97.78365 -284.29966)
		(stroke
			(width 0.05715)
			(type default)
		)
		(layer "In6.Cu")
	)
	(gr_line
		(start 97.790254 -207.499458)
		(end 97.497392 -207.206596)
		(stroke
			(width 0.07112)
			(type default)
		)
		(layer "In6.Cu")
	)
	(gr_line
		(start 97.790254 -206.635858)
		(end 97.502726 -206.923386)
		(stroke
			(width 0.07112)
			(type default)
		)
		(layer "In6.Cu")
	)
	(gr_line
		(start 97.790508 -284.29585)
		(end 97.789746 -284.296358)
		(stroke
			(width 0.05715)
			(type default)
		)
		(layer "In6.Cu")
	)
	(gr_line
		(start 97.794064 -284.293818)
		(end 97.793302 -284.294326)
		(stroke
			(width 0.05715)
			(type default)
		)
		(layer "In6.Cu")
	)
	(gr_line
		(start 97.795842 -285.913322)
		(end 97.790508 -285.91637)
		(stroke
			(width 0.05715)
			(type default)
		)
		(layer "In6.Cu")
	)
	(gr_line
		(start 97.796604 -284.292294)
		(end 97.795842 -284.292802)
		(stroke
			(width 0.05715)
			(type default)
		)
		(layer "In6.Cu")
	)
	(gr_line
		(start 97.797366 -284.291786)
		(end 97.796604 -284.292294)
		(stroke
			(width 0.05715)
			(type default)
		)
		(layer "In6.Cu")
	)
	(gr_line
		(start 97.80397 -285.90875)
		(end 97.802954 -285.909258)
		(stroke
			(width 0.05715)
			(type default)
		)
		(layer "In6.Cu")
	)
	(gr_line
		(start 97.804224 -285.907226)
		(end 97.80397 -285.90875)
		(stroke
			(width 0.05715)
			(type default)
		)
		(layer "In6.Cu")
	)
	(gr_line
		(start 97.804986 -285.906718)
		(end 97.804224 -285.907226)
		(stroke
			(width 0.05715)
			(type default)
		)
		(layer "In6.Cu")
	)
	(gr_line
		(start 97.981008 -284.616398)
		(end 98.194114 -284.616398)
		(stroke
			(width 0.05715)
			(type default)
		)
		(layer "In6.Cu")
	)
	(gr_line
		(start 97.981008 -282.996386)
		(end 98.27895 -282.996386)
		(stroke
			(width 0.05715)
			(type default)
		)
		(layer "In6.Cu")
	)
	(gr_line
		(start 97.981008 -281.376374)
		(end 98.27895 -281.376374)
		(stroke
			(width 0.05715)
			(type default)
		)
		(layer "In6.Cu")
	)
	(gr_line
		(start 98.076258 -295.190164)
		(end 98.076258 -295.191434)
		(stroke
			(width 0.05715)
			(type default)
		)
		(layer "In6.Cu")
	)
	(gr_line
		(start 98.27895 -282.996386)
		(end 98.348292 -283.065728)
		(stroke
			(width 0.05715)
			(type default)
		)
		(layer "In6.Cu")
	)
	(gr_line
		(start 98.27895 -281.376374)
		(end 98.361754 -281.459178)
		(stroke
			(width 0.05715)
			(type default)
		)
		(layer "In6.Cu")
	)
	(gr_line
		(start 98.310192 -296.2529)
		(end 98.310192 -296.281348)
		(stroke
			(width 0.05715)
			(type default)
		)
		(layer "In6.Cu")
	)
	(gr_arc
		(start 98.312224 -284.789372)
		(mid 98.298844 -284.671689)
		(end 98.194114 -284.616398)
		(stroke
			(width 0.05715)
			(type default)
		)
		(layer "In6.Cu")
	)
	(gr_line
		(start 98.355912 -296.20718)
		(end 98.310192 -296.2529)
		(stroke
			(width 0.05715)
			(type default)
		)
		(layer "In6.Cu")
	)
	(gr_arc
		(start 98.361754 -281.459178)
		(mid 98.363546 -281.4705)
		(end 98.365564 -281.481784)
		(stroke
			(width 0.05715)
			(type default)
		)
		(layer "In6.Cu")
	)
	(gr_arc
		(start 98.486468 -284.870144)
		(mid 98.520228 -284.786826)
		(end 98.540316 -284.699202)
		(stroke
			(width 0.05715)
			(type default)
		)
		(layer "In6.Cu")
	)
	(gr_arc
		(start 98.536506 -283.10205)
		(mid 98.538528 -283.09064)
		(end 98.540316 -283.07919)
		(stroke
			(width 0.05715)
			(type default)
		)
		(layer "In6.Cu")
	)
	(gr_line
		(start 98.546412 -296.20718)
		(end 98.592132 -296.2529)
		(stroke
			(width 0.05715)
			(type default)
		)
		(layer "In6.Cu")
	)
	(gr_line
		(start 98.592132 -296.2529)
		(end 98.592132 -296.281348)
		(stroke
			(width 0.05715)
			(type default)
		)
		(layer "In6.Cu")
	)
	(gr_line
		(start 98.62312 -284.616398)
		(end 98.540316 -284.699202)
		(stroke
			(width 0.05715)
			(type default)
		)
		(layer "In6.Cu")
	)
	(gr_line
		(start 98.62312 -282.996386)
		(end 98.540316 -283.07919)
		(stroke
			(width 0.05715)
			(type default)
		)
		(layer "In6.Cu")
	)
	(gr_line
		(start 98.62312 -281.376374)
		(end 98.553778 -281.445716)
		(stroke
			(width 0.05715)
			(type default)
		)
		(layer "In6.Cu")
	)
	(gr_line
		(start 98.638868 -281.864308)
		(end 98.638868 -281.864054)
		(stroke
			(width 0.05715)
			(type default)
		)
		(layer "In6.Cu")
	)
	(gr_line
		(start 98.6409 -281.86507)
		(end 98.641154 -281.86507)
		(stroke
			(width 0.05715)
			(type default)
		)
		(layer "In6.Cu")
	)
	(gr_arc
		(start 98.737166 -281.700224)
		(mid 98.735897 -281.69946)
		(end 98.734626 -281.6987)
		(stroke
			(width 0.05715)
			(type default)
		)
		(layer "In6.Cu")
	)
	(gr_line
		(start 98.825558 -288.673032)
		(end 98.825558 -288.66973)
		(stroke
			(width 0.05715)
			(type default)
		)
		(layer "In6.Cu")
	)
	(gr_line
		(start 98.825558 -288.66973)
		(end 98.825558 -288.666174)
		(stroke
			(width 0.05715)
			(type default)
		)
		(layer "In6.Cu")
	)
	(gr_line
		(start 98.825812 -295.151048)
		(end 98.825558 -295.150794)
		(stroke
			(width 0.05715)
			(type default)
		)
		(layer "In6.Cu")
	)
	(gr_line
		(start 98.921062 -284.616398)
		(end 98.62312 -284.616398)
		(stroke
			(width 0.05715)
			(type default)
		)
		(layer "In6.Cu")
	)
	(gr_line
		(start 98.921062 -282.996386)
		(end 98.62312 -282.996386)
		(stroke
			(width 0.05715)
			(type default)
		)
		(layer "In6.Cu")
	)
	(gr_line
		(start 98.921062 -281.376374)
		(end 98.62312 -281.376374)
		(stroke
			(width 0.05715)
			(type default)
		)
		(layer "In6.Cu")
	)
	(gr_line
		(start 99.056952 -400.633438)
		(end 99.056952 -400.44116)
		(stroke
			(width 0.07112)
			(type default)
		)
		(layer "In6.Cu")
	)
	(gr_line
		(start 99.120452 -283.312108)
		(end 99.120706 -283.311854)
		(stroke
			(width 0.05715)
			(type default)
		)
		(layer "In6.Cu")
	)
	(gr_line
		(start 99.120706 -283.311854)
		(end 99.116642 -283.314394)
		(stroke
			(width 0.05715)
			(type default)
		)
		(layer "In6.Cu")
	)
	(gr_line
		(start 99.122738 -283.310584)
		(end 99.120452 -283.312108)
		(stroke
			(width 0.05715)
			(type default)
		)
		(layer "In6.Cu")
	)
	(gr_line
		(start 99.177602 -284.343348)
		(end 99.17811 -284.343856)
		(stroke
			(width 0.05715)
			(type default)
		)
		(layer "In6.Cu")
	)
	(gr_arc
		(start 99.179888 -284.34538)
		(mid 99.179 -284.344616)
		(end 99.17811 -284.343856)
		(stroke
			(width 0.05715)
			(type default)
		)
		(layer "In6.Cu")
	)
	(gr_line
		(start 99.202494 -293.848028)
		(end 99.204018 -293.84879)
		(stroke
			(width 0.05715)
			(type default)
		)
		(layer "In6.Cu")
	)
	(gr_line
		(start 99.202494 -290.608004)
		(end 99.204018 -290.608766)
		(stroke
			(width 0.05715)
			(type default)
		)
		(layer "In6.Cu")
	)
	(gr_line
		(start 99.202748 -292.228016)
		(end 99.204018 -292.228778)
		(stroke
			(width 0.05715)
			(type default)
		)
		(layer "In6.Cu")
	)
	(gr_line
		(start 99.203256 -294.82415)
		(end 99.200716 -294.825674)
		(stroke
			(width 0.05715)
			(type default)
		)
		(layer "In6.Cu")
	)
	(gr_line
		(start 99.204018 -294.823642)
		(end 99.203256 -294.82415)
		(stroke
			(width 0.05715)
			(type default)
		)
		(layer "In6.Cu")
	)
	(gr_line
		(start 99.204018 -293.84879)
		(end 99.205796 -293.849806)
		(stroke
			(width 0.05715)
			(type default)
		)
		(layer "In6.Cu")
	)
	(gr_line
		(start 99.204018 -292.228778)
		(end 99.205796 -292.229794)
		(stroke
			(width 0.05715)
			(type default)
		)
		(layer "In6.Cu")
	)
	(gr_line
		(start 99.204018 -290.608766)
		(end 99.205796 -290.609782)
		(stroke
			(width 0.05715)
			(type default)
		)
		(layer "In6.Cu")
	)
	(gr_line
		(start 99.205034 -294.823134)
		(end 99.204018 -294.823642)
		(stroke
			(width 0.05715)
			(type default)
		)
		(layer "In6.Cu")
	)
	(gr_line
		(start 99.208336 -294.821356)
		(end 99.205034 -294.823134)
		(stroke
			(width 0.05715)
			(type default)
		)
		(layer "In6.Cu")
	)
	(gr_line
		(start 99.21367 -283.478478)
		(end 99.21113 -283.480002)
		(stroke
			(width 0.05715)
			(type default)
		)
		(layer "In6.Cu")
	)
	(gr_line
		(start 99.214686 -283.47797)
		(end 99.21367 -283.478478)
		(stroke
			(width 0.05715)
			(type default)
		)
		(layer "In6.Cu")
	)
	(gr_line
		(start 99.21621 -283.476954)
		(end 99.214686 -283.47797)
		(stroke
			(width 0.05715)
			(type default)
		)
		(layer "In6.Cu")
	)
	(gr_line
		(start 99.217734 -283.475938)
		(end 99.21621 -283.476954)
		(stroke
			(width 0.05715)
			(type default)
		)
		(layer "In6.Cu")
	)
	(gr_line
		(start 99.228656 -284.143196)
		(end 99.229672 -284.143958)
		(stroke
			(width 0.05715)
			(type default)
		)
		(layer "In6.Cu")
	)
	(gr_line
		(start 99.229672 -284.143958)
		(end 99.23018 -284.144212)
		(stroke
			(width 0.05715)
			(type default)
		)
		(layer "In6.Cu")
	)
	(gr_line
		(start 99.2505 -296.334688)
		(end 99.2505 -296.363136)
		(stroke
			(width 0.05715)
			(type default)
		)
		(layer "In6.Cu")
	)
	(gr_line
		(start 99.263708 -284.779212)
		(end 99.2632 -284.780228)
		(stroke
			(width 0.05715)
			(type default)
		)
		(layer "In6.Cu")
	)
	(gr_line
		(start 99.29622 -296.288968)
		(end 99.2505 -296.334688)
		(stroke
			(width 0.05715)
			(type default)
		)
		(layer "In6.Cu")
	)
	(gr_line
		(start 99.314 -284.209998)
		(end 99.314508 -284.210252)
		(stroke
			(width 0.05715)
			(type default)
		)
		(layer "In6.Cu")
	)
	(gr_line
		(start 99.358958 -400.935444)
		(end 99.056952 -400.633438)
		(stroke
			(width 0.07112)
			(type default)
		)
		(layer "In6.Cu")
	)
	(gr_line
		(start 99.430586 -284.871922)
		(end 99.430078 -284.872938)
		(stroke
			(width 0.05715)
			(type default)
		)
		(layer "In6.Cu")
	)
	(gr_line
		(start 99.48672 -296.288968)
		(end 99.53244 -296.334688)
		(stroke
			(width 0.05715)
			(type default)
		)
		(layer "In6.Cu")
	)
	(gr_line
		(start 99.53244 -296.334688)
		(end 99.53244 -296.363136)
		(stroke
			(width 0.05715)
			(type default)
		)
		(layer "In6.Cu")
	)
	(gr_line
		(start 99.551236 -400.935444)
		(end 99.358958 -400.935444)
		(stroke
			(width 0.07112)
			(type default)
		)
		(layer "In6.Cu")
	)
	(gr_line
		(start 99.752404 -400.736054)
		(end 99.256342 -400.239992)
		(stroke
			(width 0.07112)
			(type default)
		)
		(layer "In6.Cu")
	)
	(gr_line
		(start 100.009198 -294.681402)
		(end 100.009198 -294.681148)
		(stroke
			(width 0.05715)
			(type default)
		)
		(layer "In6.Cu")
	)
	(gr_arc
		(start 100.009198 -294.681148)
		(mid 100.004993 -294.684049)
		(end 100.000816 -294.68699)
		(stroke
			(width 0.05715)
			(type default)
		)
		(layer "In6.Cu")
	)
	(gr_line
		(start 100.016564 -294.677084)
		(end 100.009198 -294.681402)
		(stroke
			(width 0.05715)
			(type default)
		)
		(layer "In6.Cu")
	)
	(gr_line
		(start 100.043742 -293.040816)
		(end 100.040186 -293.043356)
		(stroke
			(width 0.05715)
			(type default)
		)
		(layer "In6.Cu")
	)
	(gr_line
		(start 100.043742 -291.420804)
		(end 100.040186 -291.423344)
		(stroke
			(width 0.05715)
			(type default)
		)
		(layer "In6.Cu")
	)
	(gr_line
		(start 100.043742 -289.800792)
		(end 100.040186 -289.803332)
		(stroke
			(width 0.05715)
			(type default)
		)
		(layer "In6.Cu")
	)
	(gr_line
		(start 100.043742 -284.94101)
		(end 100.040186 -284.94355)
		(stroke
			(width 0.05715)
			(type default)
		)
		(layer "In6.Cu")
	)
	(gr_line
		(start 100.046536 -293.039292)
		(end 100.044504 -293.040308)
		(stroke
			(width 0.05715)
			(type default)
		)
		(layer "In6.Cu")
	)
	(gr_line
		(start 100.046536 -291.41928)
		(end 100.044504 -291.420296)
		(stroke
			(width 0.05715)
			(type default)
		)
		(layer "In6.Cu")
	)
	(gr_line
		(start 100.046536 -289.799268)
		(end 100.044504 -289.800284)
		(stroke
			(width 0.05715)
			(type default)
		)
		(layer "In6.Cu")
	)
	(gr_line
		(start 100.046536 -284.939486)
		(end 100.044504 -284.940502)
		(stroke
			(width 0.05715)
			(type default)
		)
		(layer "In6.Cu")
	)
	(gr_line
		(start 100.04806 -293.038276)
		(end 100.046536 -293.039292)
		(stroke
			(width 0.05715)
			(type default)
		)
		(layer "In6.Cu")
	)
	(gr_line
		(start 100.04806 -291.418264)
		(end 100.046536 -291.41928)
		(stroke
			(width 0.05715)
			(type default)
		)
		(layer "In6.Cu")
	)
	(gr_line
		(start 100.04806 -289.798252)
		(end 100.046536 -289.799268)
		(stroke
			(width 0.05715)
			(type default)
		)
		(layer "In6.Cu")
	)
	(gr_line
		(start 100.04806 -284.93847)
		(end 100.046536 -284.939486)
		(stroke
			(width 0.05715)
			(type default)
		)
		(layer "In6.Cu")
	)
	(gr_line
		(start 100.048568 -294.658542)
		(end 100.048314 -294.658542)
		(stroke
			(width 0.05715)
			(type default)
		)
		(layer "In6.Cu")
	)
	(gr_line
		(start 100.048822 -294.658288)
		(end 100.048568 -294.658542)
		(stroke
			(width 0.05715)
			(type default)
		)
		(layer "In6.Cu")
	)
	(gr_line
		(start 100.048822 -294.658034)
		(end 100.048822 -294.658288)
		(stroke
			(width 0.05715)
			(type default)
		)
		(layer "In6.Cu")
	)
	(gr_line
		(start 100.053648 -294.016938)
		(end 100.055934 -294.018462)
		(stroke
			(width 0.05715)
			(type default)
		)
		(layer "In6.Cu")
	)
	(gr_line
		(start 100.053648 -292.396926)
		(end 100.055934 -292.39845)
		(stroke
			(width 0.05715)
			(type default)
		)
		(layer "In6.Cu")
	)
	(gr_line
		(start 100.053648 -290.776914)
		(end 100.055934 -290.778438)
		(stroke
			(width 0.05715)
			(type default)
		)
		(layer "In6.Cu")
	)
	(gr_line
		(start 100.130356 -293.211758)
		(end 100.129086 -293.21252)
		(stroke
			(width 0.05715)
			(type default)
		)
		(layer "In6.Cu")
	)
	(gr_line
		(start 100.130356 -291.591746)
		(end 100.129086 -291.592508)
		(stroke
			(width 0.05715)
			(type default)
		)
		(layer "In6.Cu")
	)
	(gr_line
		(start 100.130356 -289.971734)
		(end 100.129086 -289.972496)
		(stroke
			(width 0.05715)
			(type default)
		)
		(layer "In6.Cu")
	)
	(gr_line
		(start 100.130356 -285.111952)
		(end 100.129086 -285.112714)
		(stroke
			(width 0.05715)
			(type default)
		)
		(layer "In6.Cu")
	)
	(gr_line
		(start 100.133912 -293.209726)
		(end 100.132642 -293.210488)
		(stroke
			(width 0.05715)
			(type default)
		)
		(layer "In6.Cu")
	)
	(gr_line
		(start 100.133912 -291.589714)
		(end 100.132642 -291.590476)
		(stroke
			(width 0.05715)
			(type default)
		)
		(layer "In6.Cu")
	)
	(gr_line
		(start 100.133912 -289.969702)
		(end 100.132642 -289.970464)
		(stroke
			(width 0.05715)
			(type default)
		)
		(layer "In6.Cu")
	)
	(gr_line
		(start 100.133912 -285.10992)
		(end 100.132642 -285.110682)
		(stroke
			(width 0.05715)
			(type default)
		)
		(layer "In6.Cu")
	)
	(gr_line
		(start 100.14204 -293.2049)
		(end 100.140516 -293.205662)
		(stroke
			(width 0.05715)
			(type default)
		)
		(layer "In6.Cu")
	)
	(gr_line
		(start 100.14204 -291.584888)
		(end 100.140516 -291.58565)
		(stroke
			(width 0.05715)
			(type default)
		)
		(layer "In6.Cu")
	)
	(gr_line
		(start 100.14204 -289.964876)
		(end 100.140516 -289.965638)
		(stroke
			(width 0.05715)
			(type default)
		)
		(layer "In6.Cu")
	)
	(gr_line
		(start 100.14204 -285.105094)
		(end 100.141024 -285.105602)
		(stroke
			(width 0.05715)
			(type default)
		)
		(layer "In6.Cu")
	)
	(gr_line
		(start 100.14331 -293.204138)
		(end 100.14204 -293.2049)
		(stroke
			(width 0.05715)
			(type default)
		)
		(layer "In6.Cu")
	)
	(gr_line
		(start 100.14331 -291.584126)
		(end 100.14204 -291.584888)
		(stroke
			(width 0.05715)
			(type default)
		)
		(layer "In6.Cu")
	)
	(gr_line
		(start 100.14331 -289.964114)
		(end 100.14204 -289.964876)
		(stroke
			(width 0.05715)
			(type default)
		)
		(layer "In6.Cu")
	)
	(gr_line
		(start 100.14331 -285.104332)
		(end 100.14204 -285.105094)
		(stroke
			(width 0.05715)
			(type default)
		)
		(layer "In6.Cu")
	)
	(gr_line
		(start 100.144072 -293.20363)
		(end 100.14331 -293.204138)
		(stroke
			(width 0.05715)
			(type default)
		)
		(layer "In6.Cu")
	)
	(gr_line
		(start 100.144072 -291.583618)
		(end 100.14331 -291.584126)
		(stroke
			(width 0.05715)
			(type default)
		)
		(layer "In6.Cu")
	)
	(gr_line
		(start 100.144072 -289.963606)
		(end 100.14331 -289.964114)
		(stroke
			(width 0.05715)
			(type default)
		)
		(layer "In6.Cu")
	)
	(gr_line
		(start 100.144072 -285.103824)
		(end 100.14331 -285.104332)
		(stroke
			(width 0.05715)
			(type default)
		)
		(layer "In6.Cu")
	)
	(gr_line
		(start 100.145088 -293.203122)
		(end 100.144072 -293.20363)
		(stroke
			(width 0.05715)
			(type default)
		)
		(layer "In6.Cu")
	)
	(gr_line
		(start 100.145088 -291.58311)
		(end 100.144072 -291.583618)
		(stroke
			(width 0.05715)
			(type default)
		)
		(layer "In6.Cu")
	)
	(gr_line
		(start 100.145088 -289.963098)
		(end 100.144072 -289.963606)
		(stroke
			(width 0.05715)
			(type default)
		)
		(layer "In6.Cu")
	)
	(gr_line
		(start 100.145088 -285.103316)
		(end 100.144072 -285.103824)
		(stroke
			(width 0.05715)
			(type default)
		)
		(layer "In6.Cu")
	)
	(gr_line
		(start 100.145596 -293.202868)
		(end 100.145088 -293.203122)
		(stroke
			(width 0.05715)
			(type default)
		)
		(layer "In6.Cu")
	)
	(gr_line
		(start 100.145596 -291.582856)
		(end 100.145088 -291.58311)
		(stroke
			(width 0.05715)
			(type default)
		)
		(layer "In6.Cu")
	)
	(gr_line
		(start 100.145596 -289.962844)
		(end 100.145088 -289.963098)
		(stroke
			(width 0.05715)
			(type default)
		)
		(layer "In6.Cu")
	)
	(gr_line
		(start 100.145596 -285.103062)
		(end 100.145088 -285.103316)
		(stroke
			(width 0.05715)
			(type default)
		)
		(layer "In6.Cu")
	)
	(gr_line
		(start 100.152708 -294.818562)
		(end 100.146104 -294.822372)
		(stroke
			(width 0.05715)
			(type default)
		)
		(layer "In6.Cu")
	)
	(gr_line
		(start 100.18522 -296.404538)
		(end 100.18522 -296.432986)
		(stroke
			(width 0.05715)
			(type default)
		)
		(layer "In6.Cu")
	)
	(gr_line
		(start 100.23094 -296.358818)
		(end 100.18522 -296.404538)
		(stroke
			(width 0.05715)
			(type default)
		)
		(layer "In6.Cu")
	)
	(gr_line
		(start 100.42144 -296.358818)
		(end 100.46716 -296.404538)
		(stroke
			(width 0.05715)
			(type default)
		)
		(layer "In6.Cu")
	)
	(gr_line
		(start 100.46716 -296.404538)
		(end 100.46716 -296.432986)
		(stroke
			(width 0.05715)
			(type default)
		)
		(layer "In6.Cu")
	)
	(gr_line
		(start 100.518976 -285.748476)
		(end 100.518214 -285.748984)
		(stroke
			(width 0.05715)
			(type default)
		)
		(layer "In6.Cu")
	)
	(gr_line
		(start 100.712778 -402.28901)
		(end 100.712778 -402.096986)
		(stroke
			(width 0.07112)
			(type default)
		)
		(layer "In6.Cu")
	)
	(gr_line
		(start 100.80117 -286.23641)
		(end 101.099112 -286.23641)
		(stroke
			(width 0.05715)
			(type default)
		)
		(layer "In6.Cu")
	)
	(gr_line
		(start 100.80117 -284.616398)
		(end 101.099112 -284.616398)
		(stroke
			(width 0.05715)
			(type default)
		)
		(layer "In6.Cu")
	)
	(gr_line
		(start 100.80117 -282.996386)
		(end 101.099112 -282.996386)
		(stroke
			(width 0.05715)
			(type default)
		)
		(layer "In6.Cu")
	)
	(gr_line
		(start 100.80117 -281.376374)
		(end 101.099112 -281.376374)
		(stroke
			(width 0.05715)
			(type default)
		)
		(layer "In6.Cu")
	)
	(gr_line
		(start 100.95357 -293.99357)
		(end 100.955856 -293.99484)
		(stroke
			(width 0.05715)
			(type default)
		)
		(layer "In6.Cu")
	)
	(gr_line
		(start 100.95357 -292.373558)
		(end 100.955856 -292.374828)
		(stroke
			(width 0.05715)
			(type default)
		)
		(layer "In6.Cu")
	)
	(gr_line
		(start 100.95357 -290.753546)
		(end 100.955856 -290.754816)
		(stroke
			(width 0.05715)
			(type default)
		)
		(layer "In6.Cu")
	)
	(gr_line
		(start 100.955856 -293.99484)
		(end 100.956618 -293.995348)
		(stroke
			(width 0.05715)
			(type default)
		)
		(layer "In6.Cu")
	)
	(gr_line
		(start 100.955856 -292.374828)
		(end 100.956618 -292.375336)
		(stroke
			(width 0.05715)
			(type default)
		)
		(layer "In6.Cu")
	)
	(gr_line
		(start 100.955856 -290.754816)
		(end 100.956618 -290.755324)
		(stroke
			(width 0.05715)
			(type default)
		)
		(layer "In6.Cu")
	)
	(gr_line
		(start 100.956618 -293.995348)
		(end 100.962714 -293.998904)
		(stroke
			(width 0.05715)
			(type default)
		)
		(layer "In6.Cu")
	)
	(gr_line
		(start 100.956618 -292.375336)
		(end 100.961698 -292.378384)
		(stroke
			(width 0.05715)
			(type default)
		)
		(layer "In6.Cu")
	)
	(gr_line
		(start 100.956618 -290.755324)
		(end 100.961698 -290.758372)
		(stroke
			(width 0.05715)
			(type default)
		)
		(layer "In6.Cu")
	)
	(gr_line
		(start 100.960428 -287.51784)
		(end 100.96246 -287.518856)
		(stroke
			(width 0.05715)
			(type default)
		)
		(layer "In6.Cu")
	)
	(gr_line
		(start 100.985574 -293.040308)
		(end 100.98405 -293.041324)
		(stroke
			(width 0.05715)
			(type default)
		)
		(layer "In6.Cu")
	)
	(gr_line
		(start 100.985574 -291.420296)
		(end 100.98405 -291.421312)
		(stroke
			(width 0.05715)
			(type default)
		)
		(layer "In6.Cu")
	)
	(gr_line
		(start 100.985574 -289.800284)
		(end 100.985066 -289.800538)
		(stroke
			(width 0.05715)
			(type default)
		)
		(layer "In6.Cu")
	)
	(gr_line
		(start 100.987098 -293.039292)
		(end 100.985574 -293.040308)
		(stroke
			(width 0.05715)
			(type default)
		)
		(layer "In6.Cu")
	)
	(gr_line
		(start 100.987098 -291.41928)
		(end 100.985574 -291.420296)
		(stroke
			(width 0.05715)
			(type default)
		)
		(layer "In6.Cu")
	)
	(gr_line
		(start 100.987098 -289.799268)
		(end 100.985574 -289.800284)
		(stroke
			(width 0.05715)
			(type default)
		)
		(layer "In6.Cu")
	)
	(gr_line
		(start 100.987352 -287.533588)
		(end 100.989892 -287.534858)
		(stroke
			(width 0.05715)
			(type default)
		)
		(layer "In6.Cu")
	)
	(gr_line
		(start 100.988114 -293.038784)
		(end 100.987098 -293.039292)
		(stroke
			(width 0.05715)
			(type default)
		)
		(layer "In6.Cu")
	)
	(gr_line
		(start 100.988114 -291.418772)
		(end 100.987098 -291.41928)
		(stroke
			(width 0.05715)
			(type default)
		)
		(layer "In6.Cu")
	)
	(gr_line
		(start 100.988114 -289.79876)
		(end 100.987098 -289.799268)
		(stroke
			(width 0.05715)
			(type default)
		)
		(layer "In6.Cu")
	)
	(gr_line
		(start 100.988876 -293.038276)
		(end 100.988114 -293.038784)
		(stroke
			(width 0.05715)
			(type default)
		)
		(layer "In6.Cu")
	)
	(gr_line
		(start 100.988876 -291.418264)
		(end 100.988114 -291.418772)
		(stroke
			(width 0.05715)
			(type default)
		)
		(layer "In6.Cu")
	)
	(gr_line
		(start 100.988876 -289.798252)
		(end 100.988114 -289.79876)
		(stroke
			(width 0.05715)
			(type default)
		)
		(layer "In6.Cu")
	)
	(gr_line
		(start 100.9904 -284.9372)
		(end 100.987606 -284.938724)
		(stroke
			(width 0.05715)
			(type default)
		)
		(layer "In6.Cu")
	)
	(gr_line
		(start 100.9904 -283.317188)
		(end 100.987606 -283.318712)
		(stroke
			(width 0.05715)
			(type default)
		)
		(layer "In6.Cu")
	)
	(gr_line
		(start 100.991924 -293.036498)
		(end 100.988876 -293.038276)
		(stroke
			(width 0.05715)
			(type default)
		)
		(layer "In6.Cu")
	)
	(gr_line
		(start 100.991924 -291.416486)
		(end 100.988876 -291.418264)
		(stroke
			(width 0.05715)
			(type default)
		)
		(layer "In6.Cu")
	)
	(gr_line
		(start 100.991924 -289.796474)
		(end 100.988876 -289.798252)
		(stroke
			(width 0.05715)
			(type default)
		)
		(layer "In6.Cu")
	)
	(gr_line
		(start 100.993194 -292.396672)
		(end 100.994464 -292.397434)
		(stroke
			(width 0.05715)
			(type default)
		)
		(layer "In6.Cu")
	)
	(gr_line
		(start 100.993194 -290.77666)
		(end 100.994464 -290.777422)
		(stroke
			(width 0.05715)
			(type default)
		)
		(layer "In6.Cu")
	)
	(gr_line
		(start 100.993448 -289.156648)
		(end 100.99421 -289.157156)
		(stroke
			(width 0.05715)
			(type default)
		)
		(layer "In6.Cu")
	)
	(gr_line
		(start 101.00437 -292.403022)
		(end 101.00564 -292.403784)
		(stroke
			(width 0.05715)
			(type default)
		)
		(layer "In6.Cu")
	)
	(gr_line
		(start 101.00437 -290.78301)
		(end 101.00564 -290.783772)
		(stroke
			(width 0.05715)
			(type default)
		)
		(layer "In6.Cu")
	)
	(gr_line
		(start 101.00564 -292.403784)
		(end 101.007164 -292.404546)
		(stroke
			(width 0.05715)
			(type default)
		)
		(layer "In6.Cu")
	)
	(gr_line
		(start 101.00564 -290.783772)
		(end 101.007164 -290.784534)
		(stroke
			(width 0.05715)
			(type default)
		)
		(layer "In6.Cu")
	)
	(gr_line
		(start 101.014784 -402.591016)
		(end 100.712778 -402.28901)
		(stroke
			(width 0.07112)
			(type default)
		)
		(layer "In6.Cu")
	)
	(gr_line
		(start 101.057456 -293.833296)
		(end 101.057456 -293.83355)
		(stroke
			(width 0.05715)
			(type default)
		)
		(layer "In6.Cu")
	)
	(gr_line
		(start 101.057456 -292.213284)
		(end 101.057456 -292.213538)
		(stroke
			(width 0.05715)
			(type default)
		)
		(layer "In6.Cu")
	)
	(gr_line
		(start 101.057456 -290.593272)
		(end 101.057456 -290.593526)
		(stroke
			(width 0.05715)
			(type default)
		)
		(layer "In6.Cu")
	)
	(gr_line
		(start 101.082348 -285.104078)
		(end 101.082856 -285.103824)
		(stroke
			(width 0.05715)
			(type default)
		)
		(layer "In6.Cu")
	)
	(gr_line
		(start 101.082348 -283.484066)
		(end 101.082856 -283.483812)
		(stroke
			(width 0.05715)
			(type default)
		)
		(layer "In6.Cu")
	)
	(gr_line
		(start 101.08311 -287.368488)
		(end 101.085142 -287.369758)
		(stroke
			(width 0.05715)
			(type default)
		)
		(layer "In6.Cu")
	)
	(gr_line
		(start 101.083872 -285.103316)
		(end 101.082856 -285.103824)
		(stroke
			(width 0.05715)
			(type default)
		)
		(layer "In6.Cu")
	)
	(gr_line
		(start 101.083872 -283.483304)
		(end 101.082856 -283.483812)
		(stroke
			(width 0.05715)
			(type default)
		)
		(layer "In6.Cu")
	)
	(gr_line
		(start 101.084126 -293.204138)
		(end 101.079046 -293.206678)
		(stroke
			(width 0.05715)
			(type default)
		)
		(layer "In6.Cu")
	)
	(gr_line
		(start 101.084126 -291.584126)
		(end 101.079046 -291.586666)
		(stroke
			(width 0.05715)
			(type default)
		)
		(layer "In6.Cu")
	)
	(gr_line
		(start 101.084126 -289.964114)
		(end 101.079046 -289.966654)
		(stroke
			(width 0.05715)
			(type default)
		)
		(layer "In6.Cu")
	)
	(gr_line
		(start 101.085396 -292.229794)
		(end 101.087428 -292.231064)
		(stroke
			(width 0.05715)
			(type default)
		)
		(layer "In6.Cu")
	)
	(gr_line
		(start 101.085396 -290.609782)
		(end 101.087428 -290.611052)
		(stroke
			(width 0.05715)
			(type default)
		)
		(layer "In6.Cu")
	)
	(gr_line
		(start 101.087936 -285.10103)
		(end 101.083872 -285.103316)
		(stroke
			(width 0.05715)
			(type default)
		)
		(layer "In6.Cu")
	)
	(gr_arc
		(start 101.087936 -285.10103)
		(mid 101.088698 -285.10065)
		(end 101.08946 -285.100268)
		(stroke
			(width 0.05715)
			(type default)
		)
		(layer "In6.Cu")
	)
	(gr_line
		(start 101.087936 -283.481018)
		(end 101.083872 -283.483304)
		(stroke
			(width 0.05715)
			(type default)
		)
		(layer "In6.Cu")
	)
	(gr_arc
		(start 101.087936 -283.481018)
		(mid 101.088698 -283.480638)
		(end 101.08946 -283.480256)
		(stroke
			(width 0.05715)
			(type default)
		)
		(layer "In6.Cu")
	)
	(gr_line
		(start 101.088952 -292.231826)
		(end 101.08946 -292.231826)
		(stroke
			(width 0.05715)
			(type default)
		)
		(layer "In6.Cu")
	)
	(gr_line
		(start 101.088952 -290.611814)
		(end 101.08946 -290.611814)
		(stroke
			(width 0.05715)
			(type default)
		)
		(layer "In6.Cu")
	)
	(gr_line
		(start 101.089206 -288.991548)
		(end 101.088952 -288.991802)
		(stroke
			(width 0.05715)
			(type default)
		)
		(layer "In6.Cu")
	)
	(gr_line
		(start 101.08946 -292.231826)
		(end 101.089968 -292.23208)
		(stroke
			(width 0.05715)
			(type default)
		)
		(layer "In6.Cu")
	)
	(gr_line
		(start 101.08946 -290.611814)
		(end 101.089968 -290.612068)
		(stroke
			(width 0.05715)
			(type default)
		)
		(layer "In6.Cu")
	)
	(gr_line
		(start 101.092762 -292.233604)
		(end 101.094286 -292.234366)
		(stroke
			(width 0.05715)
			(type default)
		)
		(layer "In6.Cu")
	)
	(gr_line
		(start 101.092762 -290.613592)
		(end 101.094286 -290.614354)
		(stroke
			(width 0.05715)
			(type default)
		)
		(layer "In6.Cu")
	)
	(gr_line
		(start 101.095048 -292.234874)
		(end 101.099112 -292.23716)
		(stroke
			(width 0.05715)
			(type default)
		)
		(layer "In6.Cu")
	)
	(gr_line
		(start 101.095048 -290.614862)
		(end 101.099112 -290.617148)
		(stroke
			(width 0.05715)
			(type default)
		)
		(layer "In6.Cu")
	)
	(gr_line
		(start 101.099112 -286.23641)
		(end 101.181916 -286.319214)
		(stroke
			(width 0.05715)
			(type default)
		)
		(layer "In6.Cu")
	)
	(gr_line
		(start 101.099112 -284.616398)
		(end 101.1682 -284.685486)
		(stroke
			(width 0.05715)
			(type default)
		)
		(layer "In6.Cu")
	)
	(gr_line
		(start 101.099112 -282.996386)
		(end 101.1682 -283.065474)
		(stroke
			(width 0.05715)
			(type default)
		)
		(layer "In6.Cu")
	)
	(gr_line
		(start 101.099112 -281.376374)
		(end 101.181916 -281.459178)
		(stroke
			(width 0.05715)
			(type default)
		)
		(layer "In6.Cu")
	)
	(gr_line
		(start 101.100382 -292.237922)
		(end 101.101906 -292.238938)
		(stroke
			(width 0.05715)
			(type default)
		)
		(layer "In6.Cu")
	)
	(gr_line
		(start 101.100382 -290.61791)
		(end 101.101906 -290.618926)
		(stroke
			(width 0.05715)
			(type default)
		)
		(layer "In6.Cu")
	)
	(gr_line
		(start 101.101906 -292.238938)
		(end 101.102668 -292.239446)
		(stroke
			(width 0.05715)
			(type default)
		)
		(layer "In6.Cu")
	)
	(gr_line
		(start 101.101906 -290.618926)
		(end 101.102668 -290.619434)
		(stroke
			(width 0.05715)
			(type default)
		)
		(layer "In6.Cu")
	)
	(gr_line
		(start 101.115622 -292.246812)
		(end 101.124004 -292.251892)
		(stroke
			(width 0.05715)
			(type default)
		)
		(layer "In6.Cu")
	)
	(gr_line
		(start 101.115622 -290.6268)
		(end 101.124004 -290.63188)
		(stroke
			(width 0.05715)
			(type default)
		)
		(layer "In6.Cu")
	)
	(gr_line
		(start 101.130354 -296.435018)
		(end 101.130354 -296.463466)
		(stroke
			(width 0.05715)
			(type default)
		)
		(layer "In6.Cu")
	)
	(gr_arc
		(start 101.134672 -292.259766)
		(mid 101.12936 -292.255799)
		(end 101.124004 -292.251892)
		(stroke
			(width 0.05715)
			(type default)
		)
		(layer "In6.Cu")
	)
	(gr_arc
		(start 101.134672 -290.639754)
		(mid 101.12936 -290.635788)
		(end 101.124004 -290.63188)
		(stroke
			(width 0.05715)
			(type default)
		)
		(layer "In6.Cu")
	)
	(gr_line
		(start 101.168962 -284.686248)
		(end 101.169216 -284.686248)
		(stroke
			(width 0.05715)
			(type default)
		)
		(layer "In6.Cu")
	)
	(gr_line
		(start 101.168962 -283.066236)
		(end 101.169216 -283.066236)
		(stroke
			(width 0.05715)
			(type default)
		)
		(layer "In6.Cu")
	)
	(gr_line
		(start 101.176074 -296.389298)
		(end 101.130354 -296.435018)
		(stroke
			(width 0.05715)
			(type default)
		)
		(layer "In6.Cu")
	)
	(gr_arc
		(start 101.181916 -286.319214)
		(mid 101.183706 -286.330536)
		(end 101.185726 -286.34182)
		(stroke
			(width 0.05715)
			(type default)
		)
		(layer "In6.Cu")
	)
	(gr_line
		(start 101.181916 -281.47772)
		(end 101.18598 -281.481784)
		(stroke
			(width 0.05715)
			(type default)
		)
		(layer "In6.Cu")
	)
	(gr_arc
		(start 101.181916 -281.459178)
		(mid 101.181842 -281.468449)
		(end 101.181916 -281.47772)
		(stroke
			(width 0.05715)
			(type default)
		)
		(layer "In6.Cu")
	)
	(gr_line
		(start 101.206808 -402.591016)
		(end 101.014784 -402.591016)
		(stroke
			(width 0.07112)
			(type default)
		)
		(layer "In6.Cu")
	)
	(gr_arc
		(start 101.356414 -284.721808)
		(mid 101.358436 -284.710525)
		(end 101.360224 -284.699202)
		(stroke
			(width 0.05715)
			(type default)
		)
		(layer "In6.Cu")
	)
	(gr_arc
		(start 101.356414 -283.101796)
		(mid 101.358435 -283.090513)
		(end 101.360224 -283.07919)
		(stroke
			(width 0.05715)
			(type default)
		)
		(layer "In6.Cu")
	)
	(gr_line
		(start 101.366574 -296.389298)
		(end 101.412294 -296.435018)
		(stroke
			(width 0.05715)
			(type default)
		)
		(layer "In6.Cu")
	)
	(gr_line
		(start 101.407976 -402.391626)
		(end 100.912168 -401.895818)
		(stroke
			(width 0.07112)
			(type default)
		)
		(layer "In6.Cu")
	)
	(gr_line
		(start 101.412294 -296.435018)
		(end 101.412294 -296.463466)
		(stroke
			(width 0.05715)
			(type default)
		)
		(layer "In6.Cu")
	)
	(gr_line
		(start 101.443028 -286.23641)
		(end 101.37394 -286.305498)
		(stroke
			(width 0.05715)
			(type default)
		)
		(layer "In6.Cu")
	)
	(gr_line
		(start 101.443028 -284.616398)
		(end 101.360224 -284.699202)
		(stroke
			(width 0.05715)
			(type default)
		)
		(layer "In6.Cu")
	)
	(gr_line
		(start 101.443028 -282.996386)
		(end 101.360224 -283.07919)
		(stroke
			(width 0.05715)
			(type default)
		)
		(layer "In6.Cu")
	)
	(gr_line
		(start 101.443028 -281.376374)
		(end 101.373178 -281.446224)
		(stroke
			(width 0.05715)
			(type default)
		)
		(layer "In6.Cu")
	)
	(gr_line
		(start 101.553518 -281.700224)
		(end 101.558344 -281.703018)
		(stroke
			(width 0.05715)
			(type default)
		)
		(layer "In6.Cu")
	)
	(gr_line
		(start 101.74097 -286.23641)
		(end 101.443028 -286.23641)
		(stroke
			(width 0.05715)
			(type default)
		)
		(layer "In6.Cu")
	)
	(gr_line
		(start 101.74097 -284.616398)
		(end 101.443028 -284.616398)
		(stroke
			(width 0.05715)
			(type default)
		)
		(layer "In6.Cu")
	)
	(gr_line
		(start 101.74097 -282.996386)
		(end 101.443028 -282.996386)
		(stroke
			(width 0.05715)
			(type default)
		)
		(layer "In6.Cu")
	)
	(gr_line
		(start 101.74097 -281.376374)
		(end 101.443028 -281.376374)
		(stroke
			(width 0.05715)
			(type default)
		)
		(layer "In6.Cu")
	)
	(gr_line
		(start 102.075234 -296.521378)
		(end 102.075234 -296.549826)
		(stroke
			(width 0.05715)
			(type default)
		)
		(layer "In6.Cu")
	)
	(gr_line
		(start 102.119684 -296.476928)
		(end 102.075234 -296.521378)
		(stroke
			(width 0.05715)
			(type default)
		)
		(layer "In6.Cu")
	)
	(gr_line
		(start 102.311454 -296.489628)
		(end 102.357174 -296.535348)
		(stroke
			(width 0.05715)
			(type default)
		)
		(layer "In6.Cu")
	)
	(gr_line
		(start 102.311454 -296.475658)
		(end 102.311454 -296.489628)
		(stroke
			(width 0.05715)
			(type default)
		)
		(layer "In6.Cu")
	)
	(gr_arc
		(start 102.351078 -283.455364)
		(mid 102.355003 -283.458175)
		(end 102.358952 -283.460952)
		(stroke
			(width 0.05715)
			(type default)
		)
		(layer "In6.Cu")
	)
	(gr_line
		(start 102.357174 -296.535348)
		(end 102.357174 -296.549826)
		(stroke
			(width 0.05715)
			(type default)
		)
		(layer "In6.Cu")
	)
	(gr_line
		(start 102.358952 -283.460952)
		(end 102.36581 -283.465016)
		(stroke
			(width 0.05715)
			(type default)
		)
		(layer "In6.Cu")
	)
	(gr_line
		(start 102.36581 -283.465016)
		(end 102.366572 -283.465524)
		(stroke
			(width 0.05715)
			(type default)
		)
		(layer "In6.Cu")
	)
	(gr_line
		(start 102.366572 -283.465524)
		(end 102.367334 -283.466032)
		(stroke
			(width 0.05715)
			(type default)
		)
		(layer "In6.Cu")
	)
	(gr_line
		(start 102.390956 -285.753048)
		(end 102.390448 -285.753302)
		(stroke
			(width 0.05715)
			(type default)
		)
		(layer "In6.Cu")
	)
	(gr_line
		(start 102.390956 -284.133036)
		(end 102.390448 -284.13329)
		(stroke
			(width 0.05715)
			(type default)
		)
		(layer "In6.Cu")
	)
	(gr_line
		(start 102.397052 -285.749492)
		(end 102.395528 -285.750508)
		(stroke
			(width 0.05715)
			(type default)
		)
		(layer "In6.Cu")
	)
	(gr_line
		(start 102.397052 -284.12948)
		(end 102.395528 -284.130496)
		(stroke
			(width 0.05715)
			(type default)
		)
		(layer "In6.Cu")
	)
	(gr_line
		(start 102.398068 -285.748984)
		(end 102.397052 -285.749492)
		(stroke
			(width 0.05715)
			(type default)
		)
		(layer "In6.Cu")
	)
	(gr_line
		(start 102.398068 -284.128972)
		(end 102.397052 -284.12948)
		(stroke
			(width 0.05715)
			(type default)
		)
		(layer "In6.Cu")
	)
	(gr_line
		(start 102.398322 -283.484066)
		(end 102.39883 -283.48432)
		(stroke
			(width 0.05715)
			(type default)
		)
		(layer "In6.Cu")
	)
	(gr_line
		(start 102.39883 -285.748476)
		(end 102.398068 -285.748984)
		(stroke
			(width 0.05715)
			(type default)
		)
		(layer "In6.Cu")
	)
	(gr_line
		(start 102.39883 -285.104332)
		(end 102.4001 -285.105094)
		(stroke
			(width 0.05715)
			(type default)
		)
		(layer "In6.Cu")
	)
	(gr_line
		(start 102.39883 -284.128464)
		(end 102.398068 -284.128972)
		(stroke
			(width 0.05715)
			(type default)
		)
		(layer "In6.Cu")
	)
	(gr_line
		(start 102.39883 -283.48432)
		(end 102.401624 -283.485844)
		(stroke
			(width 0.05715)
			(type default)
		)
		(layer "In6.Cu")
	)
	(gr_line
		(start 102.4001 -285.747714)
		(end 102.39883 -285.748476)
		(stroke
			(width 0.05715)
			(type default)
		)
		(layer "In6.Cu")
	)
	(gr_line
		(start 102.4001 -284.127702)
		(end 102.39883 -284.128464)
		(stroke
			(width 0.05715)
			(type default)
		)
		(layer "In6.Cu")
	)
	(gr_line
		(start 102.48519 -285.919164)
		(end 102.483666 -285.92018)
		(stroke
			(width 0.05715)
			(type default)
		)
		(layer "In6.Cu")
	)
	(gr_line
		(start 102.48519 -284.299152)
		(end 102.483666 -284.300168)
		(stroke
			(width 0.05715)
			(type default)
		)
		(layer "In6.Cu")
	)
	(gr_line
		(start 102.493318 -285.914338)
		(end 102.49281 -285.914592)
		(stroke
			(width 0.05715)
			(type default)
		)
		(layer "In6.Cu")
	)
	(gr_line
		(start 102.493318 -284.294326)
		(end 102.49281 -284.29458)
		(stroke
			(width 0.05715)
			(type default)
		)
		(layer "In6.Cu")
	)
	(gr_line
		(start 102.493572 -284.938724)
		(end 102.49408 -284.938978)
		(stroke
			(width 0.05715)
			(type default)
		)
		(layer "In6.Cu")
	)
	(gr_line
		(start 102.49408 -285.91383)
		(end 102.493318 -285.914338)
		(stroke
			(width 0.05715)
			(type default)
		)
		(layer "In6.Cu")
	)
	(gr_line
		(start 102.49408 -284.938978)
		(end 102.495096 -284.939486)
		(stroke
			(width 0.05715)
			(type default)
		)
		(layer "In6.Cu")
	)
	(gr_line
		(start 102.49408 -284.293818)
		(end 102.493318 -284.294326)
		(stroke
			(width 0.05715)
			(type default)
		)
		(layer "In6.Cu")
	)
	(gr_line
		(start 102.49408 -283.318966)
		(end 102.495096 -283.319474)
		(stroke
			(width 0.05715)
			(type default)
		)
		(layer "In6.Cu")
	)
	(gr_line
		(start 102.495096 -285.913322)
		(end 102.49408 -285.91383)
		(stroke
			(width 0.05715)
			(type default)
		)
		(layer "In6.Cu")
	)
	(gr_line
		(start 102.495096 -284.29331)
		(end 102.49408 -284.293818)
		(stroke
			(width 0.05715)
			(type default)
		)
		(layer "In6.Cu")
	)
	(gr_line
		(start 102.495096 -283.319474)
		(end 102.49662 -283.32049)
		(stroke
			(width 0.05715)
			(type default)
		)
		(layer "In6.Cu")
	)
	(gr_line
		(start 102.49662 -283.32049)
		(end 102.497636 -283.320998)
		(stroke
			(width 0.05715)
			(type default)
		)
		(layer "In6.Cu")
	)
	(gr_line
		(start 102.497636 -283.320998)
		(end 102.502716 -283.324046)
		(stroke
			(width 0.05715)
			(type default)
		)
		(layer "In6.Cu")
	)
	(gr_line
		(start 102.574598 -409.563824)
		(end 102.283768 -409.272994)
		(stroke
			(width 0.07112)
			(type default)
		)
		(layer "In6.Cu")
	)
	(gr_line
		(start 102.574598 -408.700224)
		(end 102.283768 -408.991054)
		(stroke
			(width 0.07112)
			(type default)
		)
		(layer "In6.Cu")
	)
	(gr_line
		(start 103.020114 -296.2529)
		(end 103.020114 -296.281348)
		(stroke
			(width 0.05715)
			(type default)
		)
		(layer "In6.Cu")
	)
	(gr_line
		(start 103.065834 -296.20718)
		(end 103.020114 -296.2529)
		(stroke
			(width 0.05715)
			(type default)
		)
		(layer "In6.Cu")
	)
	(gr_line
		(start 103.256334 -296.20718)
		(end 103.302054 -296.2529)
		(stroke
			(width 0.05715)
			(type default)
		)
		(layer "In6.Cu")
	)
	(gr_line
		(start 103.302054 -296.2529)
		(end 103.302054 -296.281348)
		(stroke
			(width 0.05715)
			(type default)
		)
		(layer "In6.Cu")
	)
	(gr_line
		(start 103.338122 -285.748984)
		(end 103.337106 -285.749492)
		(stroke
			(width 0.05715)
			(type default)
		)
		(layer "In6.Cu")
	)
	(gr_line
		(start 103.433372 -285.914338)
		(end 103.432102 -285.9151)
		(stroke
			(width 0.05715)
			(type default)
		)
		(layer "In6.Cu")
	)
	(gr_line
		(start 103.43388 -285.914084)
		(end 103.433372 -285.914338)
		(stroke
			(width 0.05715)
			(type default)
		)
		(layer "In6.Cu")
	)
	(gr_line
		(start 103.446834 -295.411652)
		(end 103.446834 -295.411906)
		(stroke
			(width 0.05715)
			(type default)
		)
		(layer "In6.Cu")
	)
	(gr_arc
		(start 103.525828 -287.046162)
		(mid 103.525824 -287.048321)
		(end 103.525828 -287.05048)
		(stroke
			(width 0.05715)
			(type default)
		)
		(layer "In6.Cu")
	)
	(gr_line
		(start 103.621078 -286.23641)
		(end 103.91902 -286.23641)
		(stroke
			(width 0.05715)
			(type default)
		)
		(layer "In6.Cu")
	)
	(gr_line
		(start 103.621078 -284.616398)
		(end 103.91902 -284.616398)
		(stroke
			(width 0.05715)
			(type default)
		)
		(layer "In6.Cu")
	)
	(gr_line
		(start 103.621078 -282.996386)
		(end 103.91902 -282.996386)
		(stroke
			(width 0.05715)
			(type default)
		)
		(layer "In6.Cu")
	)
	(gr_arc
		(start 103.716074 -285.436818)
		(mid 103.716204 -285.434913)
		(end 103.716328 -285.433008)
		(stroke
			(width 0.05715)
			(type default)
		)
		(layer "In6.Cu")
	)
	(gr_line
		(start 103.716328 -285.42742)
		(end 103.716328 -285.433008)
		(stroke
			(width 0.05715)
			(type default)
		)
		(layer "In6.Cu")
	)
	(gr_line
		(start 103.91902 -286.23641)
		(end 104.001824 -286.319214)
		(stroke
			(width 0.05715)
			(type default)
		)
		(layer "In6.Cu")
	)
	(gr_line
		(start 103.91902 -284.616398)
		(end 103.988362 -284.68574)
		(stroke
			(width 0.05715)
			(type default)
		)
		(layer "In6.Cu")
	)
	(gr_line
		(start 103.91902 -282.996386)
		(end 104.001824 -283.07919)
		(stroke
			(width 0.05715)
			(type default)
		)
		(layer "In6.Cu")
	)
	(gr_line
		(start 103.935276 -289.007042)
		(end 103.942388 -289.011106)
		(stroke
			(width 0.05715)
			(type default)
		)
		(layer "In6.Cu")
	)
	(gr_arc
		(start 103.942388 -289.011106)
		(mid 103.942769 -289.01136)
		(end 103.94315 -289.011614)
		(stroke
			(width 0.05715)
			(type default)
		)
		(layer "In6.Cu")
	)
	(gr_arc
		(start 103.951024 -289.017202)
		(mid 103.947099 -289.014391)
		(end 103.94315 -289.011614)
		(stroke
			(width 0.05715)
			(type default)
		)
		(layer "In6.Cu")
	)
	(gr_arc
		(start 104.001824 -286.319214)
		(mid 104.003617 -286.330536)
		(end 104.005634 -286.34182)
		(stroke
			(width 0.05715)
			(type default)
		)
		(layer "In6.Cu")
	)
	(gr_arc
		(start 104.001824 -283.07919)
		(mid 104.003611 -283.09064)
		(end 104.005634 -283.10205)
		(stroke
			(width 0.05715)
			(type default)
		)
		(layer "In6.Cu")
	)
	(gr_line
		(start 104.035352 -296.203878)
		(end 104.035352 -296.232326)
		(stroke
			(width 0.05715)
			(type default)
		)
		(layer "In6.Cu")
	)
	(gr_line
		(start 104.081072 -296.158158)
		(end 104.035352 -296.203878)
		(stroke
			(width 0.05715)
			(type default)
		)
		(layer "In6.Cu")
	)
	(gr_arc
		(start 104.176576 -284.722062)
		(mid 104.178598 -284.710652)
		(end 104.180386 -284.699202)
		(stroke
			(width 0.05715)
			(type default)
		)
		(layer "In6.Cu")
	)
	(gr_line
		(start 104.26319 -286.23641)
		(end 104.193848 -286.305752)
		(stroke
			(width 0.05715)
			(type default)
		)
		(layer "In6.Cu")
	)
	(gr_line
		(start 104.26319 -284.616398)
		(end 104.180386 -284.699202)
		(stroke
			(width 0.05715)
			(type default)
		)
		(layer "In6.Cu")
	)
	(gr_line
		(start 104.26319 -282.996386)
		(end 104.193848 -283.065728)
		(stroke
			(width 0.05715)
			(type default)
		)
		(layer "In6.Cu")
	)
	(gr_line
		(start 104.271572 -296.158158)
		(end 104.317292 -296.203878)
		(stroke
			(width 0.05715)
			(type default)
		)
		(layer "In6.Cu")
	)
	(gr_line
		(start 104.317292 -296.203878)
		(end 104.317292 -296.232326)
		(stroke
			(width 0.05715)
			(type default)
		)
		(layer "In6.Cu")
	)
	(gr_line
		(start 104.391714 -405.638508)
		(end 104.391714 -405.227282)
		(stroke
			(width 0.07112)
			(type default)
		)
		(layer "In6.Cu")
	)
	(gr_line
		(start 104.523794 -393.17676)
		(end 104.523794 -392.75004)
		(stroke
			(width 0.07112)
			(type default)
		)
		(layer "In6.Cu")
	)
	(gr_line
		(start 104.523794 -392.75004)
		(end 104.64038 -392.633454)
		(stroke
			(width 0.07112)
			(type default)
		)
		(layer "In6.Cu")
	)
	(gr_line
		(start 104.53243 -392.05281)
		(end 104.53243 -391.62609)
		(stroke
			(width 0.07112)
			(type default)
		)
		(layer "In6.Cu")
	)
	(gr_line
		(start 104.53243 -391.62609)
		(end 104.64038 -391.51814)
		(stroke
			(width 0.07112)
			(type default)
		)
		(layer "In6.Cu")
	)
	(gr_line
		(start 104.561132 -286.23641)
		(end 104.26319 -286.23641)
		(stroke
			(width 0.05715)
			(type default)
		)
		(layer "In6.Cu")
	)
	(gr_line
		(start 104.561132 -284.616398)
		(end 104.26319 -284.616398)
		(stroke
			(width 0.05715)
			(type default)
		)
		(layer "In6.Cu")
	)
	(gr_line
		(start 104.561132 -282.996386)
		(end 104.26319 -282.996386)
		(stroke
			(width 0.05715)
			(type default)
		)
		(layer "In6.Cu")
	)
	(gr_line
		(start 104.565196 -294.825674)
		(end 104.56545 -294.825928)
		(stroke
			(width 0.05715)
			(type default)
		)
		(layer "In6.Cu")
	)
	(gr_line
		(start 104.592628 -405.027638)
		(end 104.591104 -405.026114)
		(stroke
			(width 0.07112)
			(type default)
		)
		(layer "In6.Cu")
	)
	(gr_line
		(start 104.64038 -393.293346)
		(end 104.523794 -393.17676)
		(stroke
			(width 0.07112)
			(type default)
		)
		(layer "In6.Cu")
	)
	(gr_line
		(start 104.64038 -392.16076)
		(end 104.53243 -392.05281)
		(stroke
			(width 0.07112)
			(type default)
		)
		(layer "In6.Cu")
	)
	(gr_arc
		(start 104.701086 -292.365176)
		(mid 104.705011 -292.367987)
		(end 104.70896 -292.370764)
		(stroke
			(width 0.05715)
			(type default)
		)
		(layer "In6.Cu")
	)
	(gr_arc
		(start 104.701086 -290.745164)
		(mid 104.705011 -290.747975)
		(end 104.70896 -290.750752)
		(stroke
			(width 0.05715)
			(type default)
		)
		(layer "In6.Cu")
	)
	(gr_arc
		(start 104.701086 -289.125152)
		(mid 104.705011 -289.127963)
		(end 104.70896 -289.13074)
		(stroke
			(width 0.05715)
			(type default)
		)
		(layer "In6.Cu")
	)
	(gr_arc
		(start 104.701086 -287.50514)
		(mid 104.706272 -287.508853)
		(end 104.7115 -287.512506)
		(stroke
			(width 0.05715)
			(type default)
		)
		(layer "In6.Cu")
	)
	(gr_line
		(start 104.70896 -292.370764)
		(end 104.715818 -292.374828)
		(stroke
			(width 0.05715)
			(type default)
		)
		(layer "In6.Cu")
	)
	(gr_line
		(start 104.70896 -290.750752)
		(end 104.715818 -290.754816)
		(stroke
			(width 0.05715)
			(type default)
		)
		(layer "In6.Cu")
	)
	(gr_line
		(start 104.70896 -289.13074)
		(end 104.715818 -289.134804)
		(stroke
			(width 0.05715)
			(type default)
		)
		(layer "In6.Cu")
	)
	(gr_line
		(start 104.7115 -287.512506)
		(end 104.715818 -287.515046)
		(stroke
			(width 0.05715)
			(type default)
		)
		(layer "In6.Cu")
	)
	(gr_line
		(start 104.715818 -292.374828)
		(end 104.71658 -292.375336)
		(stroke
			(width 0.05715)
			(type default)
		)
		(layer "In6.Cu")
	)
	(gr_line
		(start 104.715818 -290.754816)
		(end 104.71658 -290.755324)
		(stroke
			(width 0.05715)
			(type default)
		)
		(layer "In6.Cu")
	)
	(gr_line
		(start 104.715818 -289.134804)
		(end 104.71658 -289.135312)
		(stroke
			(width 0.05715)
			(type default)
		)
		(layer "In6.Cu")
	)
	(gr_line
		(start 104.715818 -287.515046)
		(end 104.71658 -287.515554)
		(stroke
			(width 0.05715)
			(type default)
		)
		(layer "In6.Cu")
	)
	(gr_line
		(start 104.71658 -292.375336)
		(end 104.717342 -292.375844)
		(stroke
			(width 0.05715)
			(type default)
		)
		(layer "In6.Cu")
	)
	(gr_line
		(start 104.71658 -290.755324)
		(end 104.717342 -290.755832)
		(stroke
			(width 0.05715)
			(type default)
		)
		(layer "In6.Cu")
	)
	(gr_line
		(start 104.71658 -289.135312)
		(end 104.717342 -289.13582)
		(stroke
			(width 0.05715)
			(type default)
		)
		(layer "In6.Cu")
	)
	(gr_line
		(start 104.71658 -287.515554)
		(end 104.717596 -287.516062)
		(stroke
			(width 0.05715)
			(type default)
		)
		(layer "In6.Cu")
	)
	(gr_line
		(start 104.74706 -287.533334)
		(end 104.749854 -287.534858)
		(stroke
			(width 0.05715)
			(type default)
		)
		(layer "In6.Cu")
	)
	(gr_line
		(start 104.748076 -293.038784)
		(end 104.74706 -293.039292)
		(stroke
			(width 0.05715)
			(type default)
		)
		(layer "In6.Cu")
	)
	(gr_line
		(start 104.748076 -291.418772)
		(end 104.74706 -291.41928)
		(stroke
			(width 0.05715)
			(type default)
		)
		(layer "In6.Cu")
	)
	(gr_line
		(start 104.748076 -289.79876)
		(end 104.74706 -289.799268)
		(stroke
			(width 0.05715)
			(type default)
		)
		(layer "In6.Cu")
	)
	(gr_line
		(start 104.780588 -294.639746)
		(end 104.780588 -294.64)
		(stroke
			(width 0.05715)
			(type default)
		)
		(layer "In6.Cu")
	)
	(gr_line
		(start 104.780588 -294.032432)
		(end 104.780588 -294.032686)
		(stroke
			(width 0.05715)
			(type default)
		)
		(layer "In6.Cu")
	)
	(gr_line
		(start 104.843326 -293.204138)
		(end 104.842056 -293.2049)
		(stroke
			(width 0.05715)
			(type default)
		)
		(layer "In6.Cu")
	)
	(gr_line
		(start 104.843326 -291.584126)
		(end 104.842056 -291.584888)
		(stroke
			(width 0.05715)
			(type default)
		)
		(layer "In6.Cu")
	)
	(gr_line
		(start 104.843326 -289.964114)
		(end 104.842056 -289.964876)
		(stroke
			(width 0.05715)
			(type default)
		)
		(layer "In6.Cu")
	)
	(gr_line
		(start 104.843326 -287.368234)
		(end 104.844088 -287.368742)
		(stroke
			(width 0.05715)
			(type default)
		)
		(layer "In6.Cu")
	)
	(gr_line
		(start 104.843834 -293.203884)
		(end 104.843326 -293.204138)
		(stroke
			(width 0.05715)
			(type default)
		)
		(layer "In6.Cu")
	)
	(gr_line
		(start 104.843834 -291.583872)
		(end 104.843326 -291.584126)
		(stroke
			(width 0.05715)
			(type default)
		)
		(layer "In6.Cu")
	)
	(gr_line
		(start 104.843834 -289.96386)
		(end 104.843326 -289.964114)
		(stroke
			(width 0.05715)
			(type default)
		)
		(layer "In6.Cu")
	)
	(gr_line
		(start 104.843834 -287.368996)
		(end 104.844596 -287.369504)
		(stroke
			(width 0.05715)
			(type default)
		)
		(layer "In6.Cu")
	)
	(gr_line
		(start 104.844088 -287.368742)
		(end 104.843834 -287.368996)
		(stroke
			(width 0.05715)
			(type default)
		)
		(layer "In6.Cu")
	)
	(gr_line
		(start 104.886506 -293.873682)
		(end 104.892602 -293.878254)
		(stroke
			(width 0.05715)
			(type default)
		)
		(layer "In6.Cu")
	)
	(gr_line
		(start 104.92359 -393.294616)
		(end 104.92359 -392.632184)
		(stroke
			(width 0.07112)
			(type default)
		)
		(layer "In6.Cu")
	)
	(gr_line
		(start 104.92359 -392.16203)
		(end 104.92359 -391.51687)
		(stroke
			(width 0.07112)
			(type default)
		)
		(layer "In6.Cu")
	)
	(gr_line
		(start 104.97185 -296.26306)
		(end 104.97185 -296.291508)
		(stroke
			(width 0.05715)
			(type default)
		)
		(layer "In6.Cu")
	)
	(gr_line
		(start 105.002584 -405.027638)
		(end 104.592628 -405.027638)
		(stroke
			(width 0.07112)
			(type default)
		)
		(layer "In6.Cu")
	)
	(gr_line
		(start 105.01757 -296.21734)
		(end 104.97185 -296.26306)
		(stroke
			(width 0.05715)
			(type default)
		)
		(layer "In6.Cu")
	)
	(gr_line
		(start 105.126282 -284.62478)
		(end 105.126282 -284.625796)
		(stroke
			(width 0.05715)
			(type default)
		)
		(layer "In6.Cu")
	)
	(gr_arc
		(start 105.169462 -285.07436)
		(mid 105.170224 -285.074869)
		(end 105.170986 -285.075376)
		(stroke
			(width 0.05715)
			(type default)
		)
		(layer "In6.Cu")
	)
	(gr_arc
		(start 105.170986 -285.075376)
		(mid 105.174532 -285.07793)
		(end 105.178098 -285.080456)
		(stroke
			(width 0.05715)
			(type default)
		)
		(layer "In6.Cu")
	)
	(gr_line
		(start 105.182416 -285.082996)
		(end 105.188258 -285.086552)
		(stroke
			(width 0.05715)
			(type default)
		)
		(layer "In6.Cu")
	)
	(gr_line
		(start 105.197402 -285.760922)
		(end 105.19664 -285.76143)
		(stroke
			(width 0.05715)
			(type default)
		)
		(layer "In6.Cu")
	)
	(gr_line
		(start 105.207308 -285.75508)
		(end 105.197402 -285.760922)
		(stroke
			(width 0.05715)
			(type default)
		)
		(layer "In6.Cu")
	)
	(gr_line
		(start 105.207816 -285.754826)
		(end 105.207308 -285.75508)
		(stroke
			(width 0.05715)
			(type default)
		)
		(layer "In6.Cu")
	)
	(gr_line
		(start 105.20807 -296.21734)
		(end 105.25379 -296.26306)
		(stroke
			(width 0.05715)
			(type default)
		)
		(layer "In6.Cu")
	)
	(gr_line
		(start 105.25379 -296.26306)
		(end 105.25379 -296.291508)
		(stroke
			(width 0.05715)
			(type default)
		)
		(layer "In6.Cu")
	)
	(gr_line
		(start 105.292144 -286.546544)
		(end 105.292652 -286.546544)
		(stroke
			(width 0.05715)
			(type default)
		)
		(layer "In6.Cu")
	)
	(gr_line
		(start 105.303066 -285.92018)
		(end 105.302812 -285.92018)
		(stroke
			(width 0.05715)
			(type default)
		)
		(layer "In6.Cu")
	)
	(gr_line
		(start 105.342436 -399.4785)
		(end 105.342436 -399.05178)
		(stroke
			(width 0.07112)
			(type default)
		)
		(layer "In6.Cu")
	)
	(gr_line
		(start 105.342436 -399.05178)
		(end 105.478326 -398.91589)
		(stroke
			(width 0.07112)
			(type default)
		)
		(layer "In6.Cu")
	)
	(gr_line
		(start 105.342436 -398.35074)
		(end 105.342436 -397.92402)
		(stroke
			(width 0.07112)
			(type default)
		)
		(layer "In6.Cu")
	)
	(gr_line
		(start 105.342436 -397.92402)
		(end 105.478326 -397.78813)
		(stroke
			(width 0.07112)
			(type default)
		)
		(layer "In6.Cu")
	)
	(gr_line
		(start 105.478326 -399.61439)
		(end 105.342436 -399.4785)
		(stroke
			(width 0.07112)
			(type default)
		)
		(layer "In6.Cu")
	)
	(gr_line
		(start 105.478326 -398.48663)
		(end 105.342436 -398.35074)
		(stroke
			(width 0.07112)
			(type default)
		)
		(layer "In6.Cu")
	)
	(gr_line
		(start 105.68305 -289.153092)
		(end 105.691178 -289.158426)
		(stroke
			(width 0.05715)
			(type default)
		)
		(layer "In6.Cu")
	)
	(gr_line
		(start 105.761536 -399.61566)
		(end 105.761536 -398.91462)
		(stroke
			(width 0.07112)
			(type default)
		)
		(layer "In6.Cu")
	)
	(gr_line
		(start 105.761536 -398.4879)
		(end 105.761536 -397.78686)
		(stroke
			(width 0.07112)
			(type default)
		)
		(layer "In6.Cu")
	)
	(gr_line
		(start 105.924858 -296.26052)
		(end 105.916984 -296.281348)
		(stroke
			(width 0.05715)
			(type default)
		)
		(layer "In6.Cu")
	)
	(gr_arc
		(start 105.939336 -296.233088)
		(mid 105.931256 -296.24636)
		(end 105.924858 -296.26052)
		(stroke
			(width 0.05715)
			(type default)
		)
		(layer "In6.Cu")
	)
	(gr_arc
		(start 105.939336 -296.233088)
		(mid 105.953673 -296.206317)
		(end 105.961434 -296.176954)
		(stroke
			(width 0.05715)
			(type default)
		)
		(layer "In6.Cu")
	)
	(gr_line
		(start 106.131868 -307.664104)
		(end 106.131868 -307.664358)
		(stroke
			(width 0.07112)
			(type default)
		)
		(layer "In6.Cu")
	)
	(gr_line
		(start 106.146346 -285.755842)
		(end 106.14533 -285.75635)
		(stroke
			(width 0.05715)
			(type default)
		)
		(layer "In6.Cu")
	)
	(gr_line
		(start 106.148886 -285.754318)
		(end 106.148124 -285.754826)
		(stroke
			(width 0.05715)
			(type default)
		)
		(layer "In6.Cu")
	)
	(gr_line
		(start 106.153204 -296.22115)
		(end 106.198924 -296.26687)
		(stroke
			(width 0.05715)
			(type default)
		)
		(layer "In6.Cu")
	)
	(gr_line
		(start 106.153204 -296.187368)
		(end 106.153204 -296.22115)
		(stroke
			(width 0.05715)
			(type default)
		)
		(layer "In6.Cu")
	)
	(gr_line
		(start 106.153712 -285.751524)
		(end 106.150664 -285.753302)
		(stroke
			(width 0.05715)
			(type default)
		)
		(layer "In6.Cu")
	)
	(gr_line
		(start 106.157014 -285.749492)
		(end 106.15549 -285.750508)
		(stroke
			(width 0.05715)
			(type default)
		)
		(layer "In6.Cu")
	)
	(gr_line
		(start 106.160062 -285.747714)
		(end 106.158792 -285.748476)
		(stroke
			(width 0.05715)
			(type default)
		)
		(layer "In6.Cu")
	)
	(gr_line
		(start 106.198924 -296.26687)
		(end 106.198924 -296.281348)
		(stroke
			(width 0.05715)
			(type default)
		)
		(layer "In6.Cu")
	)
	(gr_line
		(start 106.25201 -285.9151)
		(end 106.250994 -285.915608)
		(stroke
			(width 0.05715)
			(type default)
		)
		(layer "In6.Cu")
	)
	(gr_line
		(start 106.25328 -285.914338)
		(end 106.25201 -285.9151)
		(stroke
			(width 0.05715)
			(type default)
		)
		(layer "In6.Cu")
	)
	(gr_line
		(start 106.254042 -285.91383)
		(end 106.25328 -285.914338)
		(stroke
			(width 0.05715)
			(type default)
		)
		(layer "In6.Cu")
	)
	(gr_line
		(start 106.255058 -285.913322)
		(end 106.254042 -285.91383)
		(stroke
			(width 0.05715)
			(type default)
		)
		(layer "In6.Cu")
	)
	(gr_line
		(start 106.30154 -413.1437)
		(end 106.01071 -413.43453)
		(stroke
			(width 0.07112)
			(type default)
		)
		(layer "In6.Cu")
	)
	(gr_line
		(start 106.440986 -286.23641)
		(end 106.738928 -286.23641)
		(stroke
			(width 0.05715)
			(type default)
		)
		(layer "In6.Cu")
	)
	(gr_line
		(start 106.440986 -284.616398)
		(end 106.738928 -284.616398)
		(stroke
			(width 0.05715)
			(type default)
		)
		(layer "In6.Cu")
	)
	(gr_line
		(start 106.440986 -282.996386)
		(end 106.738928 -282.996386)
		(stroke
			(width 0.05715)
			(type default)
		)
		(layer "In6.Cu")
	)
	(gr_line
		(start 106.487976 -372.839488)
		(end 106.568748 -373.014494)
		(stroke
			(width 0.07112)
			(type default)
		)
		(layer "In6.Cu")
	)
	(gr_line
		(start 106.58348 -413.1437)
		(end 106.87431 -413.43453)
		(stroke
			(width 0.07112)
			(type default)
		)
		(layer "In6.Cu")
	)
	(gr_line
		(start 106.606086 -372.517162)
		(end 106.487976 -372.839488)
		(stroke
			(width 0.07112)
			(type default)
		)
		(layer "In6.Cu")
	)
	(gr_line
		(start 106.738928 -286.23641)
		(end 106.763058 -286.26054)
		(stroke
			(width 0.05715)
			(type default)
		)
		(layer "In6.Cu")
	)
	(gr_line
		(start 106.738928 -284.616398)
		(end 106.80827 -284.68574)
		(stroke
			(width 0.05715)
			(type default)
		)
		(layer "In6.Cu")
	)
	(gr_line
		(start 106.738928 -282.996386)
		(end 106.821732 -283.07919)
		(stroke
			(width 0.05715)
			(type default)
		)
		(layer "In6.Cu")
	)
	(gr_line
		(start 106.781092 -372.43639)
		(end 106.606086 -372.517162)
		(stroke
			(width 0.07112)
			(type default)
		)
		(layer "In6.Cu")
	)
	(gr_line
		(start 106.819192 -371.938042)
		(end 106.899964 -372.113048)
		(stroke
			(width 0.07112)
			(type default)
		)
		(layer "In6.Cu")
	)
	(gr_arc
		(start 106.821732 -283.07919)
		(mid 106.823775 -283.090515)
		(end 106.82605 -283.101796)
		(stroke
			(width 0.05715)
			(type default)
		)
		(layer "In6.Cu")
	)
	(gr_arc
		(start 106.830114 -286.367474)
		(mid 106.802625 -286.310221)
		(end 106.763058 -286.26054)
		(stroke
			(width 0.05715)
			(type default)
		)
		(layer "In6.Cu")
	)
	(gr_arc
		(start 106.835702 -286.385508)
		(mid 106.835449 -286.384746)
		(end 106.835194 -286.383984)
		(stroke
			(width 0.05715)
			(type default)
		)
		(layer "In6.Cu")
	)
	(gr_line
		(start 106.937302 -371.615716)
		(end 106.819192 -371.938042)
		(stroke
			(width 0.07112)
			(type default)
		)
		(layer "In6.Cu")
	)
	(gr_arc
		(start 106.996484 -284.722062)
		(mid 106.998506 -284.710652)
		(end 107.000294 -284.699202)
		(stroke
			(width 0.05715)
			(type default)
		)
		(layer "In6.Cu")
	)
	(gr_arc
		(start 107.013248 -286.30626)
		(mid 107.012612 -286.306511)
		(end 107.011978 -286.306768)
		(stroke
			(width 0.05715)
			(type default)
		)
		(layer "In6.Cu")
	)
	(gr_line
		(start 107.014264 -296.584116)
		(end 107.014264 -296.612564)
		(stroke
			(width 0.05715)
			(type default)
		)
		(layer "In6.Cu")
	)
	(gr_line
		(start 107.047284 -372.533164)
		(end 106.834432 -373.112792)
		(stroke
			(width 0.07112)
			(type default)
		)
		(layer "In6.Cu")
	)
	(gr_line
		(start 107.059984 -296.538396)
		(end 107.014264 -296.584116)
		(stroke
			(width 0.05715)
			(type default)
		)
		(layer "In6.Cu")
	)
	(gr_line
		(start 107.083098 -286.23641)
		(end 107.013248 -286.30626)
		(stroke
			(width 0.05715)
			(type default)
		)
		(layer "In6.Cu")
	)
	(gr_line
		(start 107.083098 -284.616398)
		(end 107.000294 -284.699202)
		(stroke
			(width 0.05715)
			(type default)
		)
		(layer "In6.Cu")
	)
	(gr_line
		(start 107.083098 -282.996386)
		(end 107.013248 -283.066236)
		(stroke
			(width 0.05715)
			(type default)
		)
		(layer "In6.Cu")
	)
	(gr_line
		(start 107.08386 -295.477184)
		(end 107.079796 -295.47947)
		(stroke
			(width 0.05715)
			(type default)
		)
		(layer "In6.Cu")
	)
	(gr_line
		(start 107.112308 -371.534944)
		(end 106.937302 -371.615716)
		(stroke
			(width 0.07112)
			(type default)
		)
		(layer "In6.Cu")
	)
	(gr_line
		(start 107.150154 -371.036596)
		(end 107.23118 -371.211348)
		(stroke
			(width 0.07112)
			(type default)
		)
		(layer "In6.Cu")
	)
	(gr_line
		(start 107.205526 -405.239982)
		(end 107.496356 -405.530812)
		(stroke
			(width 0.07112)
			(type default)
		)
		(layer "In6.Cu")
	)
	(gr_line
		(start 107.221528 -374.085866)
		(end 107.3023 -374.260872)
		(stroke
			(width 0.07112)
			(type default)
		)
		(layer "In6.Cu")
	)
	(gr_line
		(start 107.22737 -286.578294)
		(end 107.228132 -286.578548)
		(stroke
			(width 0.05715)
			(type default)
		)
		(layer "In6.Cu")
	)
	(gr_arc
		(start 107.242102 -286.5882)
		(mid 107.235153 -286.583322)
		(end 107.228132 -286.578548)
		(stroke
			(width 0.05715)
			(type default)
		)
		(layer "In6.Cu")
	)
	(gr_line
		(start 107.250484 -296.538396)
		(end 107.296204 -296.584116)
		(stroke
			(width 0.05715)
			(type default)
		)
		(layer "In6.Cu")
	)
	(gr_line
		(start 107.268518 -370.71427)
		(end 107.150154 -371.036596)
		(stroke
			(width 0.07112)
			(type default)
		)
		(layer "In6.Cu")
	)
	(gr_line
		(start 107.296204 -296.584116)
		(end 107.296204 -296.612564)
		(stroke
			(width 0.05715)
			(type default)
		)
		(layer "In6.Cu")
	)
	(gr_line
		(start 107.339638 -373.76354)
		(end 107.221528 -374.085866)
		(stroke
			(width 0.07112)
			(type default)
		)
		(layer "In6.Cu")
	)
	(gr_line
		(start 107.3785 -371.631718)
		(end 107.165648 -372.211346)
		(stroke
			(width 0.07112)
			(type default)
		)
		(layer "In6.Cu")
	)
	(gr_line
		(start 107.38104 -286.23641)
		(end 107.083098 -286.23641)
		(stroke
			(width 0.05715)
			(type default)
		)
		(layer "In6.Cu")
	)
	(gr_line
		(start 107.38104 -284.616398)
		(end 107.083098 -284.616398)
		(stroke
			(width 0.05715)
			(type default)
		)
		(layer "In6.Cu")
	)
	(gr_line
		(start 107.38104 -282.996386)
		(end 107.083098 -282.996386)
		(stroke
			(width 0.05715)
			(type default)
		)
		(layer "In6.Cu")
	)
	(gr_line
		(start 107.44327 -370.633752)
		(end 107.268518 -370.71427)
		(stroke
			(width 0.07112)
			(type default)
		)
		(layer "In6.Cu")
	)
	(gr_line
		(start 107.443778 -306.693062)
		(end 107.443778 -306.693316)
		(stroke
			(width 0.07112)
			(type default)
		)
		(layer "In6.Cu")
	)
	(gr_line
		(start 107.47248 -283.770324)
		(end 107.472734 -283.771594)
		(stroke
			(width 0.05715)
			(type default)
		)
		(layer "In6.Cu")
	)
	(gr_line
		(start 107.47629 -283.814774)
		(end 107.47629 -283.816044)
		(stroke
			(width 0.05715)
			(type default)
		)
		(layer "In6.Cu")
	)
	(gr_line
		(start 107.48137 -370.13515)
		(end 107.562396 -370.309902)
		(stroke
			(width 0.07112)
			(type default)
		)
		(layer "In6.Cu")
	)
	(gr_line
		(start 107.514644 -373.682768)
		(end 107.339638 -373.76354)
		(stroke
			(width 0.07112)
			(type default)
		)
		(layer "In6.Cu")
	)
	(gr_line
		(start 107.552744 -373.18442)
		(end 107.633516 -373.359172)
		(stroke
			(width 0.07112)
			(type default)
		)
		(layer "In6.Cu")
	)
	(gr_line
		(start 107.55503 -294.666416)
		(end 107.554522 -294.66667)
		(stroke
			(width 0.05715)
			(type default)
		)
		(layer "In6.Cu")
	)
	(gr_line
		(start 107.55503 -289.14598)
		(end 107.555538 -289.146234)
		(stroke
			(width 0.05715)
			(type default)
		)
		(layer "In6.Cu")
	)
	(gr_arc
		(start 107.556554 -292.38702)
		(mid 107.558964 -292.388423)
		(end 107.56138 -292.389814)
		(stroke
			(width 0.05715)
			(type default)
		)
		(layer "In6.Cu")
	)
	(gr_arc
		(start 107.556554 -290.767008)
		(mid 107.558964 -290.768411)
		(end 107.56138 -290.769802)
		(stroke
			(width 0.05715)
			(type default)
		)
		(layer "In6.Cu")
	)
	(gr_line
		(start 107.557062 -288.185098)
		(end 107.55503 -288.186368)
		(stroke
			(width 0.05715)
			(type default)
		)
		(layer "In6.Cu")
	)
	(gr_line
		(start 107.56773 -292.393624)
		(end 107.567984 -292.393624)
		(stroke
			(width 0.05715)
			(type default)
		)
		(layer "In6.Cu")
	)
	(gr_line
		(start 107.56773 -290.773612)
		(end 107.567984 -290.773612)
		(stroke
			(width 0.05715)
			(type default)
		)
		(layer "In6.Cu")
	)
	(gr_line
		(start 107.567984 -291.418772)
		(end 107.56773 -291.419026)
		(stroke
			(width 0.05715)
			(type default)
		)
		(layer "In6.Cu")
	)
	(gr_line
		(start 107.567984 -289.79876)
		(end 107.56773 -289.799014)
		(stroke
			(width 0.05715)
			(type default)
		)
		(layer "In6.Cu")
	)
	(gr_line
		(start 107.599734 -369.812824)
		(end 107.48137 -370.13515)
		(stroke
			(width 0.07112)
			(type default)
		)
		(layer "In6.Cu")
	)
	(gr_line
		(start 107.650534 -294.831262)
		(end 107.65028 -294.831516)
		(stroke
			(width 0.05715)
			(type default)
		)
		(layer "In6.Cu")
	)
	(gr_line
		(start 107.663488 -292.228524)
		(end 107.668568 -292.231318)
		(stroke
			(width 0.05715)
			(type default)
		)
		(layer "In6.Cu")
	)
	(gr_line
		(start 107.663488 -290.608512)
		(end 107.668568 -290.611306)
		(stroke
			(width 0.05715)
			(type default)
		)
		(layer "In6.Cu")
	)
	(gr_line
		(start 107.668568 -292.231318)
		(end 107.66933 -292.231826)
		(stroke
			(width 0.05715)
			(type default)
		)
		(layer "In6.Cu")
	)
	(gr_line
		(start 107.668568 -290.611306)
		(end 107.66933 -290.611814)
		(stroke
			(width 0.05715)
			(type default)
		)
		(layer "In6.Cu")
	)
	(gr_line
		(start 107.66933 -292.231826)
		(end 107.670346 -292.232334)
		(stroke
			(width 0.05715)
			(type default)
		)
		(layer "In6.Cu")
	)
	(gr_line
		(start 107.66933 -290.611814)
		(end 107.670346 -290.612322)
		(stroke
			(width 0.05715)
			(type default)
		)
		(layer "In6.Cu")
	)
	(gr_line
		(start 107.670346 -292.232334)
		(end 107.671362 -292.232842)
		(stroke
			(width 0.05715)
			(type default)
		)
		(layer "In6.Cu")
	)
	(gr_line
		(start 107.670854 -372.862094)
		(end 107.552744 -373.18442)
		(stroke
			(width 0.07112)
			(type default)
		)
		(layer "In6.Cu")
	)
	(gr_line
		(start 107.685078 -291.571426)
		(end 107.684824 -291.571426)
		(stroke
			(width 0.05715)
			(type default)
		)
		(layer "In6.Cu")
	)
	(gr_line
		(start 107.685078 -289.951414)
		(end 107.684824 -289.951414)
		(stroke
			(width 0.05715)
			(type default)
		)
		(layer "In6.Cu")
	)
	(gr_line
		(start 107.694222 -292.246304)
		(end 107.70235 -292.25113)
		(stroke
			(width 0.05715)
			(type default)
		)
		(layer "In6.Cu")
	)
	(gr_line
		(start 107.694476 -290.626546)
		(end 107.70235 -290.631118)
		(stroke
			(width 0.05715)
			(type default)
		)
		(layer "In6.Cu")
	)
	(gr_line
		(start 107.69473 -287.38703)
		(end 107.70235 -287.391348)
		(stroke
			(width 0.05715)
			(type default)
		)
		(layer "In6.Cu")
	)
	(gr_line
		(start 107.694984 -291.565584)
		(end 107.69346 -291.5666)
		(stroke
			(width 0.05715)
			(type default)
		)
		(layer "In6.Cu")
	)
	(gr_line
		(start 107.694984 -289.945572)
		(end 107.69346 -289.946588)
		(stroke
			(width 0.05715)
			(type default)
		)
		(layer "In6.Cu")
	)
	(gr_line
		(start 107.695238 -289.007042)
		(end 107.70235 -289.011106)
		(stroke
			(width 0.05715)
			(type default)
		)
		(layer "In6.Cu")
	)
	(gr_line
		(start 107.700318 -293.182802)
		(end 107.694984 -293.18585)
		(stroke
			(width 0.05715)
			(type default)
		)
		(layer "In6.Cu")
	)
	(gr_arc
		(start 107.70235 -292.25113)
		(mid 107.702731 -292.251384)
		(end 107.703112 -292.251638)
		(stroke
			(width 0.05715)
			(type default)
		)
		(layer "In6.Cu")
	)
	(gr_arc
		(start 107.70235 -290.631118)
		(mid 107.702731 -290.631372)
		(end 107.703112 -290.631626)
		(stroke
			(width 0.05715)
			(type default)
		)
		(layer "In6.Cu")
	)
	(gr_arc
		(start 107.70235 -289.011106)
		(mid 107.702731 -289.01136)
		(end 107.703112 -289.011614)
		(stroke
			(width 0.05715)
			(type default)
		)
		(layer "In6.Cu")
	)
	(gr_line
		(start 107.70235 -287.391348)
		(end 107.70235 -287.391094)
		(stroke
			(width 0.05715)
			(type default)
		)
		(layer "In6.Cu")
	)
	(gr_line
		(start 107.703112 -293.18077)
		(end 107.700318 -293.182802)
		(stroke
			(width 0.05715)
			(type default)
		)
		(layer "In6.Cu")
	)
	(gr_arc
		(start 107.703112 -293.18077)
		(mid 107.707061 -293.177993)
		(end 107.710986 -293.175182)
		(stroke
			(width 0.05715)
			(type default)
		)
		(layer "In6.Cu")
	)
	(gr_line
		(start 107.709716 -370.730272)
		(end 107.49661 -371.3099)
		(stroke
			(width 0.07112)
			(type default)
		)
		(layer "In6.Cu")
	)
	(gr_arc
		(start 107.710986 -292.257226)
		(mid 107.707061 -292.254415)
		(end 107.703112 -292.251638)
		(stroke
			(width 0.05715)
			(type default)
		)
		(layer "In6.Cu")
	)
	(gr_arc
		(start 107.710986 -290.637214)
		(mid 107.707061 -290.634403)
		(end 107.703112 -290.631626)
		(stroke
			(width 0.05715)
			(type default)
		)
		(layer "In6.Cu")
	)
	(gr_arc
		(start 107.710986 -289.017202)
		(mid 107.707061 -289.014391)
		(end 107.703112 -289.011614)
		(stroke
			(width 0.05715)
			(type default)
		)
		(layer "In6.Cu")
	)
	(gr_arc
		(start 107.71124 -287.39719)
		(mid 107.70681 -287.39412)
		(end 107.70235 -287.391094)
		(stroke
			(width 0.05715)
			(type default)
		)
		(layer "In6.Cu")
	)
	(gr_line
		(start 107.774486 -369.732306)
		(end 107.599734 -369.812824)
		(stroke
			(width 0.07112)
			(type default)
		)
		(layer "In6.Cu")
	)
	(gr_line
		(start 107.780836 -373.779542)
		(end 107.567984 -374.35917)
		(stroke
			(width 0.07112)
			(type default)
		)
		(layer "In6.Cu")
	)
	(gr_line
		(start 107.830366 -370.401088)
		(end 107.827572 -370.409216)
		(stroke
			(width 0.07112)
			(type default)
		)
		(layer "In6.Cu")
	)
	(gr_line
		(start 107.84586 -372.781576)
		(end 107.670854 -372.862094)
		(stroke
			(width 0.07112)
			(type default)
		)
		(layer "In6.Cu")
	)
	(gr_line
		(start 107.883706 -372.282974)
		(end 107.964732 -372.457726)
		(stroke
			(width 0.07112)
			(type default)
		)
		(layer "In6.Cu")
	)
	(gr_line
		(start 108.00207 -371.960648)
		(end 107.883706 -372.282974)
		(stroke
			(width 0.07112)
			(type default)
		)
		(layer "In6.Cu")
	)
	(gr_line
		(start 108.040932 -369.828572)
		(end 107.830874 -370.40058)
		(stroke
			(width 0.07112)
			(type default)
		)
		(layer "In6.Cu")
	)
	(gr_line
		(start 108.069126 -405.239982)
		(end 107.778296 -405.530812)
		(stroke
			(width 0.07112)
			(type default)
		)
		(layer "In6.Cu")
	)
	(gr_line
		(start 108.112052 -372.878096)
		(end 107.898946 -373.457724)
		(stroke
			(width 0.07112)
			(type default)
		)
		(layer "In6.Cu")
	)
	(gr_line
		(start 108.176822 -371.88013)
		(end 108.00207 -371.960648)
		(stroke
			(width 0.07112)
			(type default)
		)
		(layer "In6.Cu")
	)
	(gr_line
		(start 108.17987 -295.53662)
		(end 108.17987 -295.565068)
		(stroke
			(width 0.05715)
			(type default)
		)
		(layer "In6.Cu")
	)
	(gr_line
		(start 108.214922 -371.381528)
		(end 108.295948 -371.55628)
		(stroke
			(width 0.07112)
			(type default)
		)
		(layer "In6.Cu")
	)
	(gr_line
		(start 108.22559 -295.4909)
		(end 108.17987 -295.53662)
		(stroke
			(width 0.05715)
			(type default)
		)
		(layer "In6.Cu")
	)
	(gr_line
		(start 108.333286 -371.059202)
		(end 108.214922 -371.381528)
		(stroke
			(width 0.07112)
			(type default)
		)
		(layer "In6.Cu")
	)
	(gr_line
		(start 108.41609 -295.4909)
		(end 108.46181 -295.53662)
		(stroke
			(width 0.05715)
			(type default)
		)
		(layer "In6.Cu")
	)
	(gr_line
		(start 108.443014 -371.97665)
		(end 108.230162 -372.556278)
		(stroke
			(width 0.07112)
			(type default)
		)
		(layer "In6.Cu")
	)
	(gr_arc
		(start 108.461048 -293.985188)
		(mid 108.464973 -293.987999)
		(end 108.468922 -293.990776)
		(stroke
			(width 0.05715)
			(type default)
		)
		(layer "In6.Cu")
	)
	(gr_arc
		(start 108.461048 -292.365176)
		(mid 108.464973 -292.367987)
		(end 108.468922 -292.370764)
		(stroke
			(width 0.05715)
			(type default)
		)
		(layer "In6.Cu")
	)
	(gr_arc
		(start 108.461048 -290.745164)
		(mid 108.464973 -290.747975)
		(end 108.468922 -290.750752)
		(stroke
			(width 0.05715)
			(type default)
		)
		(layer "In6.Cu")
	)
	(gr_arc
		(start 108.461048 -289.125152)
		(mid 108.464973 -289.127963)
		(end 108.468922 -289.13074)
		(stroke
			(width 0.05715)
			(type default)
		)
		(layer "In6.Cu")
	)
	(gr_arc
		(start 108.461048 -285.885382)
		(mid 108.464973 -285.888193)
		(end 108.468922 -285.89097)
		(stroke
			(width 0.05715)
			(type default)
		)
		(layer "In6.Cu")
	)
	(gr_line
		(start 108.46181 -295.53662)
		(end 108.46181 -295.565068)
		(stroke
			(width 0.05715)
			(type default)
		)
		(layer "In6.Cu")
	)
	(gr_line
		(start 108.468922 -293.990776)
		(end 108.47578 -293.99484)
		(stroke
			(width 0.05715)
			(type default)
		)
		(layer "In6.Cu")
	)
	(gr_line
		(start 108.468922 -292.370764)
		(end 108.47578 -292.374828)
		(stroke
			(width 0.05715)
			(type default)
		)
		(layer "In6.Cu")
	)
	(gr_line
		(start 108.468922 -290.750752)
		(end 108.47578 -290.754816)
		(stroke
			(width 0.05715)
			(type default)
		)
		(layer "In6.Cu")
	)
	(gr_line
		(start 108.468922 -289.13074)
		(end 108.47578 -289.134804)
		(stroke
			(width 0.05715)
			(type default)
		)
		(layer "In6.Cu")
	)
	(gr_line
		(start 108.468922 -285.89097)
		(end 108.47578 -285.895034)
		(stroke
			(width 0.05715)
			(type default)
		)
		(layer "In6.Cu")
	)
	(gr_line
		(start 108.47578 -293.99484)
		(end 108.476542 -293.995348)
		(stroke
			(width 0.05715)
			(type default)
		)
		(layer "In6.Cu")
	)
	(gr_line
		(start 108.47578 -292.374828)
		(end 108.476542 -292.375336)
		(stroke
			(width 0.05715)
			(type default)
		)
		(layer "In6.Cu")
	)
	(gr_line
		(start 108.47578 -290.754816)
		(end 108.476542 -290.755324)
		(stroke
			(width 0.05715)
			(type default)
		)
		(layer "In6.Cu")
	)
	(gr_line
		(start 108.47578 -289.134804)
		(end 108.476542 -289.135312)
		(stroke
			(width 0.05715)
			(type default)
		)
		(layer "In6.Cu")
	)
	(gr_line
		(start 108.47578 -285.895034)
		(end 108.476542 -285.895542)
		(stroke
			(width 0.05715)
			(type default)
		)
		(layer "In6.Cu")
	)
	(gr_line
		(start 108.476542 -293.995348)
		(end 108.477304 -293.995856)
		(stroke
			(width 0.05715)
			(type default)
		)
		(layer "In6.Cu")
	)
	(gr_line
		(start 108.476542 -292.375336)
		(end 108.477304 -292.375844)
		(stroke
			(width 0.05715)
			(type default)
		)
		(layer "In6.Cu")
	)
	(gr_line
		(start 108.476542 -290.755324)
		(end 108.477304 -290.755832)
		(stroke
			(width 0.05715)
			(type default)
		)
		(layer "In6.Cu")
	)
	(gr_line
		(start 108.476542 -289.135312)
		(end 108.477304 -289.13582)
		(stroke
			(width 0.05715)
			(type default)
		)
		(layer "In6.Cu")
	)
	(gr_line
		(start 108.476542 -285.895542)
		(end 108.477304 -285.89605)
		(stroke
			(width 0.05715)
			(type default)
		)
		(layer "In6.Cu")
	)
	(gr_line
		(start 108.503212 -293.041578)
		(end 108.502196 -293.042086)
		(stroke
			(width 0.05715)
			(type default)
		)
		(layer "In6.Cu")
	)
	(gr_line
		(start 108.503212 -291.421566)
		(end 108.502196 -291.422074)
		(stroke
			(width 0.05715)
			(type default)
		)
		(layer "In6.Cu")
	)
	(gr_line
		(start 108.503212 -289.801554)
		(end 108.502196 -289.802062)
		(stroke
			(width 0.05715)
			(type default)
		)
		(layer "In6.Cu")
	)
	(gr_line
		(start 108.50372 -294.661336)
		(end 108.501942 -294.662352)
		(stroke
			(width 0.05715)
			(type default)
		)
		(layer "In6.Cu")
	)
	(gr_line
		(start 108.50372 -293.041324)
		(end 108.503212 -293.041578)
		(stroke
			(width 0.05715)
			(type default)
		)
		(layer "In6.Cu")
	)
	(gr_line
		(start 108.50372 -291.421312)
		(end 108.503212 -291.421566)
		(stroke
			(width 0.05715)
			(type default)
		)
		(layer "In6.Cu")
	)
	(gr_line
		(start 108.50372 -289.8013)
		(end 108.503212 -289.801554)
		(stroke
			(width 0.05715)
			(type default)
		)
		(layer "In6.Cu")
	)
	(gr_line
		(start 108.507022 -294.659304)
		(end 108.505498 -294.66032)
		(stroke
			(width 0.05715)
			(type default)
		)
		(layer "In6.Cu")
	)
	(gr_line
		(start 108.507022 -293.039292)
		(end 108.505498 -293.040308)
		(stroke
			(width 0.05715)
			(type default)
		)
		(layer "In6.Cu")
	)
	(gr_line
		(start 108.507022 -291.41928)
		(end 108.505498 -291.420296)
		(stroke
			(width 0.05715)
			(type default)
		)
		(layer "In6.Cu")
	)
	(gr_line
		(start 108.507022 -289.799268)
		(end 108.505498 -289.800284)
		(stroke
			(width 0.05715)
			(type default)
		)
		(layer "In6.Cu")
	)
	(gr_line
		(start 108.508038 -370.978684)
		(end 108.333286 -371.059202)
		(stroke
			(width 0.07112)
			(type default)
		)
		(layer "In6.Cu")
	)
	(gr_line
		(start 108.508038 -294.658796)
		(end 108.507022 -294.659304)
		(stroke
			(width 0.05715)
			(type default)
		)
		(layer "In6.Cu")
	)
	(gr_line
		(start 108.508038 -293.038784)
		(end 108.507022 -293.039292)
		(stroke
			(width 0.05715)
			(type default)
		)
		(layer "In6.Cu")
	)
	(gr_line
		(start 108.508038 -291.418772)
		(end 108.507022 -291.41928)
		(stroke
			(width 0.05715)
			(type default)
		)
		(layer "In6.Cu")
	)
	(gr_line
		(start 108.508038 -289.79876)
		(end 108.507022 -289.799268)
		(stroke
			(width 0.05715)
			(type default)
		)
		(layer "In6.Cu")
	)
	(gr_line
		(start 108.508292 -294.01389)
		(end 108.5088 -294.014144)
		(stroke
			(width 0.05715)
			(type default)
		)
		(layer "In6.Cu")
	)
	(gr_line
		(start 108.508292 -292.393878)
		(end 108.5088 -292.394132)
		(stroke
			(width 0.05715)
			(type default)
		)
		(layer "In6.Cu")
	)
	(gr_line
		(start 108.508292 -290.773866)
		(end 108.5088 -290.77412)
		(stroke
			(width 0.05715)
			(type default)
		)
		(layer "In6.Cu")
	)
	(gr_line
		(start 108.508292 -289.153854)
		(end 108.5088 -289.154108)
		(stroke
			(width 0.05715)
			(type default)
		)
		(layer "In6.Cu")
	)
	(gr_line
		(start 108.508292 -285.914084)
		(end 108.5088 -285.914338)
		(stroke
			(width 0.05715)
			(type default)
		)
		(layer "In6.Cu")
	)
	(gr_line
		(start 108.508546 -294.658542)
		(end 108.508038 -294.658796)
		(stroke
			(width 0.05715)
			(type default)
		)
		(layer "In6.Cu")
	)
	(gr_line
		(start 108.508546 -293.03853)
		(end 108.508038 -293.038784)
		(stroke
			(width 0.05715)
			(type default)
		)
		(layer "In6.Cu")
	)
	(gr_line
		(start 108.508546 -291.418518)
		(end 108.508038 -291.418772)
		(stroke
			(width 0.05715)
			(type default)
		)
		(layer "In6.Cu")
	)
	(gr_line
		(start 108.508546 -289.798506)
		(end 108.508038 -289.79876)
		(stroke
			(width 0.05715)
			(type default)
		)
		(layer "In6.Cu")
	)
	(gr_line
		(start 108.5088 -294.014144)
		(end 108.511594 -294.015668)
		(stroke
			(width 0.05715)
			(type default)
		)
		(layer "In6.Cu")
	)
	(gr_line
		(start 108.5088 -292.394132)
		(end 108.511594 -292.395656)
		(stroke
			(width 0.05715)
			(type default)
		)
		(layer "In6.Cu")
	)
	(gr_line
		(start 108.5088 -290.77412)
		(end 108.511594 -290.775644)
		(stroke
			(width 0.05715)
			(type default)
		)
		(layer "In6.Cu")
	)
	(gr_line
		(start 108.5088 -289.154108)
		(end 108.511594 -289.155632)
		(stroke
			(width 0.05715)
			(type default)
		)
		(layer "In6.Cu")
	)
	(gr_line
		(start 108.5088 -285.914338)
		(end 108.511594 -285.915862)
		(stroke
			(width 0.05715)
			(type default)
		)
		(layer "In6.Cu")
	)
	(gr_line
		(start 108.546138 -370.480082)
		(end 108.62691 -370.65458)
		(stroke
			(width 0.07112)
			(type default)
		)
		(layer "In6.Cu")
	)
	(gr_line
		(start 108.600494 -294.825674)
		(end 108.597954 -294.827198)
		(stroke
			(width 0.05715)
			(type default)
		)
		(layer "In6.Cu")
	)
	(gr_line
		(start 108.602018 -294.824912)
		(end 108.600494 -294.825674)
		(stroke
			(width 0.05715)
			(type default)
		)
		(layer "In6.Cu")
	)
	(gr_line
		(start 108.603288 -294.82415)
		(end 108.602018 -294.824912)
		(stroke
			(width 0.05715)
			(type default)
		)
		(layer "In6.Cu")
	)
	(gr_line
		(start 108.603288 -293.204138)
		(end 108.60278 -293.204392)
		(stroke
			(width 0.05715)
			(type default)
		)
		(layer "In6.Cu")
	)
	(gr_line
		(start 108.603288 -291.584126)
		(end 108.60278 -291.58438)
		(stroke
			(width 0.05715)
			(type default)
		)
		(layer "In6.Cu")
	)
	(gr_line
		(start 108.603288 -289.964114)
		(end 108.60278 -289.964368)
		(stroke
			(width 0.05715)
			(type default)
		)
		(layer "In6.Cu")
	)
	(gr_line
		(start 108.603796 -293.203884)
		(end 108.603288 -293.204138)
		(stroke
			(width 0.05715)
			(type default)
		)
		(layer "In6.Cu")
	)
	(gr_line
		(start 108.603796 -291.583872)
		(end 108.603288 -291.584126)
		(stroke
			(width 0.05715)
			(type default)
		)
		(layer "In6.Cu")
	)
	(gr_line
		(start 108.603796 -289.96386)
		(end 108.603288 -289.964114)
		(stroke
			(width 0.05715)
			(type default)
		)
		(layer "In6.Cu")
	)
	(gr_line
		(start 108.60405 -293.84879)
		(end 108.605066 -293.849298)
		(stroke
			(width 0.05715)
			(type default)
		)
		(layer "In6.Cu")
	)
	(gr_line
		(start 108.60405 -292.228778)
		(end 108.605066 -292.229286)
		(stroke
			(width 0.05715)
			(type default)
		)
		(layer "In6.Cu")
	)
	(gr_line
		(start 108.60405 -290.608766)
		(end 108.605066 -290.609274)
		(stroke
			(width 0.05715)
			(type default)
		)
		(layer "In6.Cu")
	)
	(gr_line
		(start 108.60405 -288.988754)
		(end 108.605066 -288.989262)
		(stroke
			(width 0.05715)
			(type default)
		)
		(layer "In6.Cu")
	)
	(gr_line
		(start 108.60405 -285.748984)
		(end 108.605066 -285.749492)
		(stroke
			(width 0.05715)
			(type default)
		)
		(layer "In6.Cu")
	)
	(gr_line
		(start 108.605066 -293.849298)
		(end 108.60659 -293.850314)
		(stroke
			(width 0.05715)
			(type default)
		)
		(layer "In6.Cu")
	)
	(gr_line
		(start 108.605066 -292.229286)
		(end 108.60659 -292.230302)
		(stroke
			(width 0.05715)
			(type default)
		)
		(layer "In6.Cu")
	)
	(gr_line
		(start 108.605066 -290.609274)
		(end 108.60659 -290.61029)
		(stroke
			(width 0.05715)
			(type default)
		)
		(layer "In6.Cu")
	)
	(gr_line
		(start 108.605066 -288.989262)
		(end 108.60659 -288.990278)
		(stroke
			(width 0.05715)
			(type default)
		)
		(layer "In6.Cu")
	)
	(gr_line
		(start 108.605066 -285.749492)
		(end 108.60659 -285.750508)
		(stroke
			(width 0.05715)
			(type default)
		)
		(layer "In6.Cu")
	)
	(gr_line
		(start 108.60659 -293.850314)
		(end 108.607606 -293.850822)
		(stroke
			(width 0.05715)
			(type default)
		)
		(layer "In6.Cu")
	)
	(gr_line
		(start 108.60659 -292.230302)
		(end 108.607606 -292.23081)
		(stroke
			(width 0.05715)
			(type default)
		)
		(layer "In6.Cu")
	)
	(gr_line
		(start 108.60659 -290.61029)
		(end 108.607606 -290.610798)
		(stroke
			(width 0.05715)
			(type default)
		)
		(layer "In6.Cu")
	)
	(gr_line
		(start 108.60659 -288.990278)
		(end 108.607606 -288.990786)
		(stroke
			(width 0.05715)
			(type default)
		)
		(layer "In6.Cu")
	)
	(gr_line
		(start 108.60659 -285.750508)
		(end 108.607606 -285.751016)
		(stroke
			(width 0.05715)
			(type default)
		)
		(layer "In6.Cu")
	)
	(gr_line
		(start 108.607606 -293.850822)
		(end 108.612686 -293.85387)
		(stroke
			(width 0.05715)
			(type default)
		)
		(layer "In6.Cu")
	)
	(gr_line
		(start 108.607606 -292.23081)
		(end 108.612686 -292.233858)
		(stroke
			(width 0.05715)
			(type default)
		)
		(layer "In6.Cu")
	)
	(gr_line
		(start 108.607606 -290.610798)
		(end 108.612686 -290.613846)
		(stroke
			(width 0.05715)
			(type default)
		)
		(layer "In6.Cu")
	)
	(gr_line
		(start 108.607606 -288.990786)
		(end 108.612686 -288.993834)
		(stroke
			(width 0.05715)
			(type default)
		)
		(layer "In6.Cu")
	)
	(gr_line
		(start 108.607606 -285.751016)
		(end 108.612686 -285.754064)
		(stroke
			(width 0.05715)
			(type default)
		)
		(layer "In6.Cu")
	)
	(gr_line
		(start 108.627672 -370.656104)
		(end 108.627418 -370.656866)
		(stroke
			(width 0.07112)
			(type default)
		)
		(layer "In6.Cu")
	)
	(gr_line
		(start 108.664502 -370.157756)
		(end 108.546138 -370.480082)
		(stroke
			(width 0.07112)
			(type default)
		)
		(layer "In6.Cu")
	)
	(gr_line
		(start 108.673646 -387.498844)
		(end 108.382816 -387.789674)
		(stroke
			(width 0.07112)
			(type default)
		)
		(layer "In6.Cu")
	)
	(gr_line
		(start 108.673646 -387.216904)
		(end 108.382816 -386.926074)
		(stroke
			(width 0.07112)
			(type default)
		)
		(layer "In6.Cu")
	)
	(gr_line
		(start 108.77423 -371.075204)
		(end 108.561378 -371.654832)
		(stroke
			(width 0.07112)
			(type default)
		)
		(layer "In6.Cu")
	)
	(gr_line
		(start 108.790994 -285.426404)
		(end 109.088936 -285.426404)
		(stroke
			(width 0.05715)
			(type default)
		)
		(layer "In6.Cu")
	)
	(gr_line
		(start 108.790994 -283.806392)
		(end 109.088936 -283.806392)
		(stroke
			(width 0.05715)
			(type default)
		)
		(layer "In6.Cu")
	)
	(gr_line
		(start 108.790994 -282.18638)
		(end 109.088936 -282.18638)
		(stroke
			(width 0.05715)
			(type default)
		)
		(layer "In6.Cu")
	)
	(gr_line
		(start 108.839 -370.077238)
		(end 108.664502 -370.157756)
		(stroke
			(width 0.07112)
			(type default)
		)
		(layer "In6.Cu")
	)
	(gr_line
		(start 108.841286 -370.074952)
		(end 108.840778 -370.076476)
		(stroke
			(width 0.07112)
			(type default)
		)
		(layer "In6.Cu")
	)
	(gr_line
		(start 109.046264 -370.33454)
		(end 108.895388 -370.745258)
		(stroke
			(width 0.07112)
			(type default)
		)
		(layer "In6.Cu")
	)
	(gr_line
		(start 109.088936 -285.426404)
		(end 109.17174 -285.509208)
		(stroke
			(width 0.05715)
			(type default)
		)
		(layer "In6.Cu")
	)
	(gr_line
		(start 109.088936 -283.806392)
		(end 109.17174 -283.889196)
		(stroke
			(width 0.05715)
			(type default)
		)
		(layer "In6.Cu")
	)
	(gr_line
		(start 109.088936 -282.18638)
		(end 109.17174 -282.269184)
		(stroke
			(width 0.05715)
			(type default)
		)
		(layer "In6.Cu")
	)
	(gr_line
		(start 109.105446 -370.173504)
		(end 109.046264 -370.33454)
		(stroke
			(width 0.07112)
			(type default)
		)
		(layer "In6.Cu")
	)
	(gr_line
		(start 109.1057 -370.17325)
		(end 109.105446 -370.173504)
		(stroke
			(width 0.07112)
			(type default)
		)
		(layer "In6.Cu")
	)
	(gr_line
		(start 109.106208 -370.171726)
		(end 109.1057 -370.17325)
		(stroke
			(width 0.07112)
			(type default)
		)
		(layer "In6.Cu")
	)
	(gr_line
		(start 109.119924 -298.38396)
		(end 109.119924 -298.382944)
		(stroke
			(width 0.07112)
			(type default)
		)
		(layer "In6.Cu")
	)
	(gr_line
		(start 109.119924 -295.519856)
		(end 109.119924 -295.548304)
		(stroke
			(width 0.05715)
			(type default)
		)
		(layer "In6.Cu")
	)
	(gr_line
		(start 109.16539 -295.473882)
		(end 109.165644 -295.474136)
		(stroke
			(width 0.05715)
			(type default)
		)
		(layer "In6.Cu")
	)
	(gr_line
		(start 109.165644 -295.474136)
		(end 109.119924 -295.519856)
		(stroke
			(width 0.05715)
			(type default)
		)
		(layer "In6.Cu")
	)
	(gr_arc
		(start 109.17174 -285.509208)
		(mid 109.173533 -285.52053)
		(end 109.17555 -285.531814)
		(stroke
			(width 0.05715)
			(type default)
		)
		(layer "In6.Cu")
	)
	(gr_arc
		(start 109.17174 -283.889196)
		(mid 109.173533 -283.900518)
		(end 109.17555 -283.911802)
		(stroke
			(width 0.05715)
			(type default)
		)
		(layer "In6.Cu")
	)
	(gr_arc
		(start 109.17174 -282.269184)
		(mid 109.173532 -282.280506)
		(end 109.17555 -282.29179)
		(stroke
			(width 0.05715)
			(type default)
		)
		(layer "In6.Cu")
	)
	(gr_line
		(start 109.356144 -295.474136)
		(end 109.401864 -295.519856)
		(stroke
			(width 0.05715)
			(type default)
		)
		(layer "In6.Cu")
	)
	(gr_line
		(start 109.356398 -295.473882)
		(end 109.356144 -295.474136)
		(stroke
			(width 0.05715)
			(type default)
		)
		(layer "In6.Cu")
	)
	(gr_line
		(start 109.356398 -295.394634)
		(end 109.356398 -295.395142)
		(stroke
			(width 0.05715)
			(type default)
		)
		(layer "In6.Cu")
	)
	(gr_arc
		(start 109.400848 -285.885382)
		(mid 109.4049 -285.888194)
		(end 109.408976 -285.89097)
		(stroke
			(width 0.05715)
			(type default)
		)
		(layer "In6.Cu")
	)
	(gr_arc
		(start 109.400848 -282.645358)
		(mid 109.4049 -282.64817)
		(end 109.408976 -282.650946)
		(stroke
			(width 0.05715)
			(type default)
		)
		(layer "In6.Cu")
	)
	(gr_arc
		(start 109.401102 -289.125152)
		(mid 109.405027 -289.127963)
		(end 109.408976 -289.13074)
		(stroke
			(width 0.05715)
			(type default)
		)
		(layer "In6.Cu")
	)
	(gr_line
		(start 109.401864 -295.519856)
		(end 109.401864 -295.548304)
		(stroke
			(width 0.05715)
			(type default)
		)
		(layer "In6.Cu")
	)
	(gr_arc
		(start 109.40669 -286.58312)
		(mid 109.402486 -286.586022)
		(end 109.398308 -286.588962)
		(stroke
			(width 0.05715)
			(type default)
		)
		(layer "In6.Cu")
	)
	(gr_line
		(start 109.406944 -286.58312)
		(end 109.40669 -286.58312)
		(stroke
			(width 0.05715)
			(type default)
		)
		(layer "In6.Cu")
	)
	(gr_line
		(start 109.408976 -289.13074)
		(end 109.416596 -289.135312)
		(stroke
			(width 0.05715)
			(type default)
		)
		(layer "In6.Cu")
	)
	(gr_line
		(start 109.408976 -285.89097)
		(end 109.416596 -285.895542)
		(stroke
			(width 0.05715)
			(type default)
		)
		(layer "In6.Cu")
	)
	(gr_line
		(start 109.408976 -282.650946)
		(end 109.416596 -282.655518)
		(stroke
			(width 0.05715)
			(type default)
		)
		(layer "In6.Cu")
	)
	(gr_line
		(start 109.41177 -298.431458)
		(end 109.41177 -298.431712)
		(stroke
			(width 0.07112)
			(type default)
		)
		(layer "In6.Cu")
	)
	(gr_line
		(start 109.414564 -286.578802)
		(end 109.406944 -286.58312)
		(stroke
			(width 0.05715)
			(type default)
		)
		(layer "In6.Cu")
	)
	(gr_line
		(start 109.41558 -287.514792)
		(end 109.41812 -287.516316)
		(stroke
			(width 0.05715)
			(type default)
		)
		(layer "In6.Cu")
	)
	(gr_line
		(start 109.416596 -289.135312)
		(end 109.417358 -289.13582)
		(stroke
			(width 0.05715)
			(type default)
		)
		(layer "In6.Cu")
	)
	(gr_line
		(start 109.416596 -285.895542)
		(end 109.417358 -285.89605)
		(stroke
			(width 0.05715)
			(type default)
		)
		(layer "In6.Cu")
	)
	(gr_line
		(start 109.416596 -282.655518)
		(end 109.417358 -282.656026)
		(stroke
			(width 0.05715)
			(type default)
		)
		(layer "In6.Cu")
	)
	(gr_line
		(start 109.433106 -285.426404)
		(end 109.363764 -285.495746)
		(stroke
			(width 0.05715)
			(type default)
		)
		(layer "In6.Cu")
	)
	(gr_line
		(start 109.433106 -283.806392)
		(end 109.363764 -283.875734)
		(stroke
			(width 0.05715)
			(type default)
		)
		(layer "In6.Cu")
	)
	(gr_line
		(start 109.433106 -282.18638)
		(end 109.363764 -282.255722)
		(stroke
			(width 0.05715)
			(type default)
		)
		(layer "In6.Cu")
	)
	(gr_line
		(start 109.44479 -285.912052)
		(end 109.44606 -285.912814)
		(stroke
			(width 0.05715)
			(type default)
		)
		(layer "In6.Cu")
	)
	(gr_line
		(start 109.445044 -282.672028)
		(end 109.448346 -282.67406)
		(stroke
			(width 0.05715)
			(type default)
		)
		(layer "In6.Cu")
	)
	(gr_line
		(start 109.445552 -289.800284)
		(end 109.44225 -289.802316)
		(stroke
			(width 0.05715)
			(type default)
		)
		(layer "In6.Cu")
	)
	(gr_line
		(start 109.447584 -285.913576)
		(end 109.450632 -285.9151)
		(stroke
			(width 0.05715)
			(type default)
		)
		(layer "In6.Cu")
	)
	(gr_line
		(start 109.448092 -291.418772)
		(end 109.441996 -291.422328)
		(stroke
			(width 0.05715)
			(type default)
		)
		(layer "In6.Cu")
	)
	(gr_line
		(start 109.448854 -289.154108)
		(end 109.451648 -289.155632)
		(stroke
			(width 0.05715)
			(type default)
		)
		(layer "In6.Cu")
	)
	(gr_line
		(start 109.449108 -289.798252)
		(end 109.445552 -289.800284)
		(stroke
			(width 0.05715)
			(type default)
		)
		(layer "In6.Cu")
	)
	(gr_line
		(start 109.450632 -285.9151)
		(end 109.451394 -285.915608)
		(stroke
			(width 0.05715)
			(type default)
		)
		(layer "In6.Cu")
	)
	(gr_line
		(start 109.455712 -284.298136)
		(end 109.456982 -284.298898)
		(stroke
			(width 0.05715)
			(type default)
		)
		(layer "In6.Cu")
	)
	(gr_line
		(start 109.467142 -285.924752)
		(end 109.467904 -285.92526)
		(stroke
			(width 0.05715)
			(type default)
		)
		(layer "In6.Cu")
	)
	(gr_line
		(start 109.467904 -285.92526)
		(end 109.469428 -285.926276)
		(stroke
			(width 0.05715)
			(type default)
		)
		(layer "In6.Cu")
	)
	(gr_line
		(start 109.469428 -294.026082)
		(end 109.469682 -294.026082)
		(stroke
			(width 0.05715)
			(type default)
		)
		(layer "In6.Cu")
	)
	(gr_line
		(start 109.469428 -285.926276)
		(end 109.469682 -285.926276)
		(stroke
			(width 0.05715)
			(type default)
		)
		(layer "In6.Cu")
	)
	(gr_line
		(start 109.469936 -286.546544)
		(end 109.469428 -286.546544)
		(stroke
			(width 0.05715)
			(type default)
		)
		(layer "In6.Cu")
	)
	(gr_line
		(start 109.539786 -288.986214)
		(end 109.540548 -288.986722)
		(stroke
			(width 0.05715)
			(type default)
		)
		(layer "In6.Cu")
	)
	(gr_line
		(start 109.54258 -285.748222)
		(end 109.543088 -285.748476)
		(stroke
			(width 0.05715)
			(type default)
		)
		(layer "In6.Cu")
	)
	(gr_line
		(start 109.543088 -285.748476)
		(end 109.545882 -285.75)
		(stroke
			(width 0.05715)
			(type default)
		)
		(layer "In6.Cu")
	)
	(gr_line
		(start 109.543596 -290.608512)
		(end 109.544104 -290.608766)
		(stroke
			(width 0.05715)
			(type default)
		)
		(layer "In6.Cu")
	)
	(gr_line
		(start 109.54385 -293.20363)
		(end 109.540802 -293.205408)
		(stroke
			(width 0.05715)
			(type default)
		)
		(layer "In6.Cu")
	)
	(gr_line
		(start 109.545882 -285.75)
		(end 109.546644 -285.750508)
		(stroke
			(width 0.05715)
			(type default)
		)
		(layer "In6.Cu")
	)
	(gr_line
		(start 109.546644 -285.750508)
		(end 109.54766 -285.751016)
		(stroke
			(width 0.05715)
			(type default)
		)
		(layer "In6.Cu")
	)
	(gr_line
		(start 109.55528 -387.994398)
		(end 109.55528 -387.80212)
		(stroke
			(width 0.07112)
			(type default)
		)
		(layer "In6.Cu")
	)
	(gr_line
		(start 109.56417 -285.760668)
		(end 109.56544 -285.76143)
		(stroke
			(width 0.05715)
			(type default)
		)
		(layer "In6.Cu")
	)
	(gr_line
		(start 109.564678 -293.860728)
		(end 109.56544 -293.861236)
		(stroke
			(width 0.05715)
			(type default)
		)
		(layer "In6.Cu")
	)
	(gr_line
		(start 109.731048 -285.426404)
		(end 109.433106 -285.426404)
		(stroke
			(width 0.05715)
			(type default)
		)
		(layer "In6.Cu")
	)
	(gr_line
		(start 109.731048 -283.806392)
		(end 109.433106 -283.806392)
		(stroke
			(width 0.05715)
			(type default)
		)
		(layer "In6.Cu")
	)
	(gr_line
		(start 109.731048 -282.18638)
		(end 109.433106 -282.18638)
		(stroke
			(width 0.05715)
			(type default)
		)
		(layer "In6.Cu")
	)
	(gr_line
		(start 109.857286 -388.296404)
		(end 109.55528 -387.994398)
		(stroke
			(width 0.07112)
			(type default)
		)
		(layer "In6.Cu")
	)
	(gr_line
		(start 109.917992 -285.103824)
		(end 109.9185 -285.104078)
		(stroke
			(width 0.05715)
			(type default)
		)
		(layer "In6.Cu")
	)
	(gr_line
		(start 110.049564 -388.296404)
		(end 109.857286 -388.296404)
		(stroke
			(width 0.07112)
			(type default)
		)
		(layer "In6.Cu")
	)
	(gr_line
		(start 110.059978 -295.55313)
		(end 110.059978 -295.581578)
		(stroke
			(width 0.05715)
			(type default)
		)
		(layer "In6.Cu")
	)
	(gr_line
		(start 110.105698 -295.50741)
		(end 110.059978 -295.55313)
		(stroke
			(width 0.05715)
			(type default)
		)
		(layer "In6.Cu")
	)
	(gr_line
		(start 110.250732 -388.097014)
		(end 109.75467 -387.600952)
		(stroke
			(width 0.07112)
			(type default)
		)
		(layer "In6.Cu")
	)
	(gr_line
		(start 110.296198 -295.50741)
		(end 110.341918 -295.55313)
		(stroke
			(width 0.05715)
			(type default)
		)
		(layer "In6.Cu")
	)
	(gr_line
		(start 110.341918 -295.55313)
		(end 110.341918 -295.581578)
		(stroke
			(width 0.05715)
			(type default)
		)
		(layer "In6.Cu")
	)
	(gr_arc
		(start 110.342426 -285.886398)
		(mid 110.370104 -285.904876)
		(end 110.398814 -285.921704)
		(stroke
			(width 0.05715)
			(type default)
		)
		(layer "In6.Cu")
	)
	(gr_arc
		(start 110.34268 -290.74618)
		(mid 110.345088 -290.747965)
		(end 110.347506 -290.749736)
		(stroke
			(width 0.05715)
			(type default)
		)
		(layer "In6.Cu")
	)
	(gr_arc
		(start 110.34903 -286.581596)
		(mid 110.344314 -286.584873)
		(end 110.339632 -286.5882)
		(stroke
			(width 0.05715)
			(type default)
		)
		(layer "In6.Cu")
	)
	(gr_line
		(start 110.354364 -287.51403)
		(end 110.35919 -287.516824)
		(stroke
			(width 0.05715)
			(type default)
		)
		(layer "In6.Cu")
	)
	(gr_line
		(start 110.355888 -286.577786)
		(end 110.355888 -286.577532)
		(stroke
			(width 0.05715)
			(type default)
		)
		(layer "In6.Cu")
	)
	(gr_line
		(start 110.355888 -286.577532)
		(end 110.34903 -286.581596)
		(stroke
			(width 0.05715)
			(type default)
		)
		(layer "In6.Cu")
	)
	(gr_arc
		(start 110.375446 -294.00627)
		(mid 110.377476 -294.007417)
		(end 110.37951 -294.008556)
		(stroke
			(width 0.05715)
			(type default)
		)
		(layer "In6.Cu")
	)
	(gr_line
		(start 110.387892 -294.013636)
		(end 110.388146 -294.013636)
		(stroke
			(width 0.05715)
			(type default)
		)
		(layer "In6.Cu")
	)
	(gr_line
		(start 110.388146 -293.038784)
		(end 110.387892 -293.039038)
		(stroke
			(width 0.05715)
			(type default)
		)
		(layer "In6.Cu")
	)
	(gr_line
		(start 110.398814 -285.921704)
		(end 110.4011 -285.921704)
		(stroke
			(width 0.05715)
			(type default)
		)
		(layer "In6.Cu")
	)
	(gr_line
		(start 110.453424 -389.182864)
		(end 110.527084 -389.005064)
		(stroke
			(width 0.07112)
			(type default)
		)
		(layer "In6.Cu")
	)
	(gr_line
		(start 110.455202 -285.731204)
		(end 110.45571 -285.731204)
		(stroke
			(width 0.05715)
			(type default)
		)
		(layer "In6.Cu")
	)
	(gr_line
		(start 110.45571 -285.731204)
		(end 110.484412 -285.747968)
		(stroke
			(width 0.05715)
			(type default)
		)
		(layer "In6.Cu")
	)
	(gr_line
		(start 110.483904 -293.20363)
		(end 110.484158 -293.20363)
		(stroke
			(width 0.05715)
			(type default)
		)
		(layer "In6.Cu")
	)
	(gr_line
		(start 110.484412 -285.747968)
		(end 110.484666 -285.748222)
		(stroke
			(width 0.05715)
			(type default)
		)
		(layer "In6.Cu")
	)
	(gr_arc
		(start 110.506002 -285.761176)
		(mid 110.495405 -285.754582)
		(end 110.484666 -285.748222)
		(stroke
			(width 0.05715)
			(type default)
		)
		(layer "In6.Cu")
	)
	(gr_line
		(start 110.516162 -293.867586)
		(end 110.521496 -293.870634)
		(stroke
			(width 0.05715)
			(type default)
		)
		(layer "In6.Cu")
	)
	(gr_arc
		(start 110.52302 -293.87165)
		(mid 110.522258 -293.871141)
		(end 110.521496 -293.870634)
		(stroke
			(width 0.05715)
			(type default)
		)
		(layer "In6.Cu")
	)
	(gr_line
		(start 110.52302 -293.87165)
		(end 110.528608 -293.87546)
		(stroke
			(width 0.05715)
			(type default)
		)
		(layer "In6.Cu")
	)
	(gr_line
		(start 110.616746 -389.577326)
		(end 110.453424 -389.182864)
		(stroke
			(width 0.07112)
			(type default)
		)
		(layer "In6.Cu")
	)
	(gr_line
		(start 110.794546 -389.650986)
		(end 110.616746 -389.577326)
		(stroke
			(width 0.07112)
			(type default)
		)
		(layer "In6.Cu")
	)
	(gr_line
		(start 110.820708 -403.875494)
		(end 110.820708 -403.448774)
		(stroke
			(width 0.07112)
			(type default)
		)
		(layer "In6.Cu")
	)
	(gr_line
		(start 110.820708 -403.448774)
		(end 110.956598 -403.312884)
		(stroke
			(width 0.07112)
			(type default)
		)
		(layer "In6.Cu")
	)
	(gr_line
		(start 110.820708 -402.747734)
		(end 110.820708 -402.321014)
		(stroke
			(width 0.07112)
			(type default)
		)
		(layer "In6.Cu")
	)
	(gr_line
		(start 110.820708 -402.321014)
		(end 110.956598 -402.185124)
		(stroke
			(width 0.07112)
			(type default)
		)
		(layer "In6.Cu")
	)
	(gr_line
		(start 110.820708 -401.619974)
		(end 110.820708 -401.193254)
		(stroke
			(width 0.07112)
			(type default)
		)
		(layer "In6.Cu")
	)
	(gr_line
		(start 110.820708 -401.193254)
		(end 110.956598 -401.057364)
		(stroke
			(width 0.07112)
			(type default)
		)
		(layer "In6.Cu")
	)
	(gr_line
		(start 110.820708 -400.492214)
		(end 110.820708 -400.065494)
		(stroke
			(width 0.07112)
			(type default)
		)
		(layer "In6.Cu")
	)
	(gr_line
		(start 110.820708 -400.065494)
		(end 110.956598 -399.929604)
		(stroke
			(width 0.07112)
			(type default)
		)
		(layer "In6.Cu")
	)
	(gr_line
		(start 110.820708 -399.364454)
		(end 110.820708 -398.937734)
		(stroke
			(width 0.07112)
			(type default)
		)
		(layer "In6.Cu")
	)
	(gr_line
		(start 110.820708 -398.937734)
		(end 110.956598 -398.801844)
		(stroke
			(width 0.07112)
			(type default)
		)
		(layer "In6.Cu")
	)
	(gr_line
		(start 110.885224 -390.225026)
		(end 110.95863 -390.04748)
		(stroke
			(width 0.07112)
			(type default)
		)
		(layer "In6.Cu")
	)
	(gr_line
		(start 110.899194 -389.900668)
		(end 110.796324 -389.651748)
		(stroke
			(width 0.07112)
			(type default)
		)
		(layer "In6.Cu")
	)
	(gr_line
		(start 110.925864 -284.81401)
		(end 110.926372 -284.814518)
		(stroke
			(width 0.05715)
			(type default)
		)
		(layer "In6.Cu")
	)
	(gr_line
		(start 110.926372 -284.878526)
		(end 110.946438 -284.898592)
		(stroke
			(width 0.05715)
			(type default)
		)
		(layer "In6.Cu")
	)
	(gr_line
		(start 110.926372 -284.814518)
		(end 110.926372 -284.878526)
		(stroke
			(width 0.05715)
			(type default)
		)
		(layer "In6.Cu")
	)
	(gr_line
		(start 110.941104 -409.903676)
		(end 111.231934 -409.612846)
		(stroke
			(width 0.07112)
			(type default)
		)
		(layer "In6.Cu")
	)
	(gr_line
		(start 110.941104 -409.040076)
		(end 111.231934 -409.330906)
		(stroke
			(width 0.07112)
			(type default)
		)
		(layer "In6.Cu")
	)
	(gr_line
		(start 110.956598 -404.011384)
		(end 110.820708 -403.875494)
		(stroke
			(width 0.07112)
			(type default)
		)
		(layer "In6.Cu")
	)
	(gr_line
		(start 110.956598 -402.883624)
		(end 110.820708 -402.747734)
		(stroke
			(width 0.07112)
			(type default)
		)
		(layer "In6.Cu")
	)
	(gr_line
		(start 110.956598 -401.755864)
		(end 110.820708 -401.619974)
		(stroke
			(width 0.07112)
			(type default)
		)
		(layer "In6.Cu")
	)
	(gr_line
		(start 110.956598 -400.628104)
		(end 110.820708 -400.492214)
		(stroke
			(width 0.07112)
			(type default)
		)
		(layer "In6.Cu")
	)
	(gr_line
		(start 110.956598 -399.500344)
		(end 110.820708 -399.364454)
		(stroke
			(width 0.07112)
			(type default)
		)
		(layer "In6.Cu")
	)
	(gr_line
		(start 111.048546 -390.619488)
		(end 110.885224 -390.225026)
		(stroke
			(width 0.07112)
			(type default)
		)
		(layer "In6.Cu")
	)
	(gr_line
		(start 111.056674 -389.544052)
		(end 110.788196 -388.895844)
		(stroke
			(width 0.07112)
			(type default)
		)
		(layer "In6.Cu")
	)
	(gr_line
		(start 111.061754 -284.679136)
		(end 111.125762 -284.679136)
		(stroke
			(width 0.05715)
			(type default)
		)
		(layer "In6.Cu")
	)
	(gr_line
		(start 111.125762 -284.679136)
		(end 111.145828 -284.699202)
		(stroke
			(width 0.05715)
			(type default)
		)
		(layer "In6.Cu")
	)
	(gr_line
		(start 111.159798 -389.792718)
		(end 111.056674 -389.544052)
		(stroke
			(width 0.07112)
			(type default)
		)
		(layer "In6.Cu")
	)
	(gr_line
		(start 111.226092 -390.693148)
		(end 111.048546 -390.619488)
		(stroke
			(width 0.07112)
			(type default)
		)
		(layer "In6.Cu")
	)
	(gr_line
		(start 111.239808 -404.012654)
		(end 111.239808 -403.311614)
		(stroke
			(width 0.07112)
			(type default)
		)
		(layer "In6.Cu")
	)
	(gr_line
		(start 111.239808 -402.884894)
		(end 111.239808 -402.183854)
		(stroke
			(width 0.07112)
			(type default)
		)
		(layer "In6.Cu")
	)
	(gr_line
		(start 111.239808 -401.757134)
		(end 111.239808 -401.056094)
		(stroke
			(width 0.07112)
			(type default)
		)
		(layer "In6.Cu")
	)
	(gr_line
		(start 111.239808 -400.629374)
		(end 111.239808 -399.928334)
		(stroke
			(width 0.07112)
			(type default)
		)
		(layer "In6.Cu")
	)
	(gr_line
		(start 111.239808 -399.501614)
		(end 111.239808 -398.800574)
		(stroke
			(width 0.07112)
			(type default)
		)
		(layer "In6.Cu")
	)
	(gr_line
		(start 111.249968 -390.74725)
		(end 111.22787 -390.69391)
		(stroke
			(width 0.07112)
			(type default)
		)
		(layer "In6.Cu")
	)
	(gr_line
		(start 111.259366 -397.31061)
		(end 111.259366 -397.118332)
		(stroke
			(width 0.07112)
			(type default)
		)
		(layer "In6.Cu")
	)
	(gr_line
		(start 111.259366 -397.118332)
		(end 111.561372 -396.816326)
		(stroke
			(width 0.07112)
			(type default)
		)
		(layer "In6.Cu")
	)
	(gr_line
		(start 111.31677 -391.267188)
		(end 111.39043 -391.089642)
		(stroke
			(width 0.07112)
			(type default)
		)
		(layer "In6.Cu")
	)
	(gr_line
		(start 111.458756 -397.511778)
		(end 111.954818 -397.015716)
		(stroke
			(width 0.07112)
			(type default)
		)
		(layer "In6.Cu")
	)
	(gr_line
		(start 111.480092 -391.66165)
		(end 111.31677 -391.267188)
		(stroke
			(width 0.07112)
			(type default)
		)
		(layer "In6.Cu")
	)
	(gr_line
		(start 111.488474 -390.586214)
		(end 111.219996 -389.93826)
		(stroke
			(width 0.07112)
			(type default)
		)
		(layer "In6.Cu")
	)
	(gr_line
		(start 111.510318 -390.6393)
		(end 111.488474 -390.586214)
		(stroke
			(width 0.07112)
			(type default)
		)
		(layer "In6.Cu")
	)
	(gr_line
		(start 111.561372 -396.816326)
		(end 111.75365 -396.816326)
		(stroke
			(width 0.07112)
			(type default)
		)
		(layer "In6.Cu")
	)
	(gr_line
		(start 111.657892 -391.73531)
		(end 111.480092 -391.66165)
		(stroke
			(width 0.07112)
			(type default)
		)
		(layer "In6.Cu")
	)
	(gr_line
		(start 111.781844 -395.54277)
		(end 111.781844 -395.11605)
		(stroke
			(width 0.07112)
			(type default)
		)
		(layer "In6.Cu")
	)
	(gr_line
		(start 111.781844 -395.11605)
		(end 111.917734 -394.98016)
		(stroke
			(width 0.07112)
			(type default)
		)
		(layer "In6.Cu")
	)
	(gr_line
		(start 111.781844 -394.32103)
		(end 111.781844 -393.89431)
		(stroke
			(width 0.07112)
			(type default)
		)
		(layer "In6.Cu")
	)
	(gr_line
		(start 111.781844 -393.89431)
		(end 111.917734 -393.75842)
		(stroke
			(width 0.07112)
			(type default)
		)
		(layer "In6.Cu")
	)
	(gr_line
		(start 111.804704 -316.102492)
		(end 111.804958 -316.102492)
		(stroke
			(width 0.07112)
			(type default)
		)
		(layer "In6.Cu")
	)
	(gr_arc
		(start 111.81715 -304.803556)
		(mid 111.822321 -304.812594)
		(end 111.827564 -304.82159)
		(stroke
			(width 0.07112)
			(type default)
		)
		(layer "In6.Cu")
	)
	(gr_arc
		(start 111.827564 -304.82159)
		(mid 111.834487 -304.833311)
		(end 111.841534 -304.844958)
		(stroke
			(width 0.07112)
			(type default)
		)
		(layer "In6.Cu")
	)
	(gr_arc
		(start 111.841534 -304.844958)
		(mid 111.84696 -304.853743)
		(end 111.852456 -304.862484)
		(stroke
			(width 0.07112)
			(type default)
		)
		(layer "In6.Cu")
	)
	(gr_line
		(start 111.917734 -395.67866)
		(end 111.781844 -395.54277)
		(stroke
			(width 0.07112)
			(type default)
		)
		(layer "In6.Cu")
	)
	(gr_line
		(start 111.917734 -394.45692)
		(end 111.781844 -394.32103)
		(stroke
			(width 0.07112)
			(type default)
		)
		(layer "In6.Cu")
	)
	(gr_line
		(start 111.92002 -391.628122)
		(end 111.651542 -390.980168)
		(stroke
			(width 0.07112)
			(type default)
		)
		(layer "In6.Cu")
	)
	(gr_line
		(start 112.064038 -304.667666)
		(end 112.075468 -304.688748)
		(stroke
			(width 0.07112)
			(type default)
		)
		(layer "In6.Cu")
	)
	(gr_line
		(start 112.075468 -304.688748)
		(end 112.088676 -304.70856)
		(stroke
			(width 0.07112)
			(type default)
		)
		(layer "In6.Cu")
	)
	(gr_line
		(start 112.200944 -395.67993)
		(end 112.200944 -394.97889)
		(stroke
			(width 0.07112)
			(type default)
		)
		(layer "In6.Cu")
	)
	(gr_line
		(start 112.200944 -394.45819)
		(end 112.200944 -393.75715)
		(stroke
			(width 0.07112)
			(type default)
		)
		(layer "In6.Cu")
	)
	(gr_line
		(start 112.825784 -304.098198)
		(end 112.826038 -304.098198)
		(stroke
			(width 0.07112)
			(type default)
		)
		(layer "In6.Cu")
	)
	(gr_line
		(start 113.067338 -284.642814)
		(end 113.087404 -284.622748)
		(stroke
			(width 0.05715)
			(type default)
		)
		(layer "In6.Cu")
	)
	(gr_line
		(start 113.087404 -284.622748)
		(end 113.151412 -284.623002)
		(stroke
			(width 0.05715)
			(type default)
		)
		(layer "In6.Cu")
	)
	(gr_line
		(start 113.151412 -284.623002)
		(end 113.15192 -284.62224)
		(stroke
			(width 0.05715)
			(type default)
		)
		(layer "In6.Cu")
	)
	(gr_line
		(start 113.266728 -284.842204)
		(end 113.286794 -284.822138)
		(stroke
			(width 0.05715)
			(type default)
		)
		(layer "In6.Cu")
	)
	(gr_line
		(start 113.286794 -284.822138)
		(end 113.286794 -284.758384)
		(stroke
			(width 0.05715)
			(type default)
		)
		(layer "In6.Cu")
	)
	(gr_line
		(start 113.606326 -24.340566)
		(end 113.897156 -24.049736)
		(stroke
			(width 0.07112)
			(type default)
		)
		(layer "In6.Cu")
	)
	(gr_line
		(start 113.668302 -286.721804)
		(end 113.667794 -286.72155)
		(stroke
			(width 0.05715)
			(type default)
		)
		(layer "In6.Cu")
	)
	(gr_arc
		(start 113.669572 -285.750254)
		(mid 113.668428 -285.750888)
		(end 113.667286 -285.751524)
		(stroke
			(width 0.05715)
			(type default)
		)
		(layer "In6.Cu")
	)
	(gr_line
		(start 113.669572 -285.750254)
		(end 113.671858 -285.748984)
		(stroke
			(width 0.05715)
			(type default)
		)
		(layer "In6.Cu")
	)
	(gr_line
		(start 113.671604 -284.129226)
		(end 113.671858 -284.128972)
		(stroke
			(width 0.05715)
			(type default)
		)
		(layer "In6.Cu")
	)
	(gr_line
		(start 113.671858 -292.228524)
		(end 113.672366 -292.22827)
		(stroke
			(width 0.05715)
			(type default)
		)
		(layer "In6.Cu")
	)
	(gr_line
		(start 113.671858 -285.748984)
		(end 113.672366 -285.74873)
		(stroke
			(width 0.05715)
			(type default)
		)
		(layer "In6.Cu")
	)
	(gr_line
		(start 113.672366 -293.204138)
		(end 113.671604 -293.20363)
		(stroke
			(width 0.05715)
			(type default)
		)
		(layer "In6.Cu")
	)
	(gr_line
		(start 113.672366 -292.22827)
		(end 113.673636 -292.227508)
		(stroke
			(width 0.05715)
			(type default)
		)
		(layer "In6.Cu")
	)
	(gr_line
		(start 113.673636 -293.2049)
		(end 113.672366 -293.204138)
		(stroke
			(width 0.05715)
			(type default)
		)
		(layer "In6.Cu")
	)
	(gr_line
		(start 113.76533 -285.9151)
		(end 113.767108 -285.914084)
		(stroke
			(width 0.05715)
			(type default)
		)
		(layer "In6.Cu")
	)
	(gr_line
		(start 113.766854 -293.038276)
		(end 113.76279 -293.03599)
		(stroke
			(width 0.05715)
			(type default)
		)
		(layer "In6.Cu")
	)
	(gr_line
		(start 113.766854 -292.394132)
		(end 113.767616 -292.393624)
		(stroke
			(width 0.05715)
			(type default)
		)
		(layer "In6.Cu")
	)
	(gr_line
		(start 113.767108 -285.914084)
		(end 113.76787 -285.913576)
		(stroke
			(width 0.05715)
			(type default)
		)
		(layer "In6.Cu")
	)
	(gr_line
		(start 113.767362 -286.558736)
		(end 113.76533 -286.55772)
		(stroke
			(width 0.05715)
			(type default)
		)
		(layer "In6.Cu")
	)
	(gr_line
		(start 113.767616 -293.038784)
		(end 113.766854 -293.038276)
		(stroke
			(width 0.05715)
			(type default)
		)
		(layer "In6.Cu")
	)
	(gr_line
		(start 113.767616 -292.393624)
		(end 113.768632 -292.393116)
		(stroke
			(width 0.05715)
			(type default)
		)
		(layer "In6.Cu")
	)
	(gr_line
		(start 113.768632 -293.039292)
		(end 113.767616 -293.038784)
		(stroke
			(width 0.05715)
			(type default)
		)
		(layer "In6.Cu")
	)
	(gr_line
		(start 113.769394 -289.152584)
		(end 113.772188 -289.15106)
		(stroke
			(width 0.05715)
			(type default)
		)
		(layer "In6.Cu")
	)
	(gr_line
		(start 113.77168 -288.181034)
		(end 113.768378 -288.179256)
		(stroke
			(width 0.05715)
			(type default)
		)
		(layer "In6.Cu")
	)
	(gr_arc
		(start 113.772188 -289.15106)
		(mid 113.773332 -289.150426)
		(end 113.774474 -289.14979)
		(stroke
			(width 0.05715)
			(type default)
		)
		(layer "In6.Cu")
	)
	(gr_line
		(start 113.797334 -285.896558)
		(end 113.805208 -285.891986)
		(stroke
			(width 0.05715)
			(type default)
		)
		(layer "In6.Cu")
	)
	(gr_arc
		(start 113.805208 -285.891986)
		(mid 113.80597 -285.891479)
		(end 113.806732 -285.89097)
		(stroke
			(width 0.05715)
			(type default)
		)
		(layer "In6.Cu")
	)
	(gr_arc
		(start 113.807494 -285.890462)
		(mid 113.807113 -285.890716)
		(end 113.806732 -285.89097)
		(stroke
			(width 0.05715)
			(type default)
		)
		(layer "In6.Cu")
	)
	(gr_arc
		(start 113.808256 -285.889954)
		(mid 113.810674 -285.888182)
		(end 113.813082 -285.886398)
		(stroke
			(width 0.05715)
			(type default)
		)
		(layer "In6.Cu")
	)
	(gr_line
		(start 113.879376 -347.740986)
		(end 113.879122 -347.740986)
		(stroke
			(width 0.07112)
			(type default)
		)
		(layer "In6.Cu")
	)
	(gr_arc
		(start 113.891822 -347.732604)
		(mid 113.890806 -347.733239)
		(end 113.88979 -347.733874)
		(stroke
			(width 0.07112)
			(type default)
		)
		(layer "In6.Cu")
	)
	(gr_line
		(start 114.14125 -284.939232)
		(end 114.141758 -284.938978)
		(stroke
			(width 0.05715)
			(type default)
		)
		(layer "In6.Cu")
	)
	(gr_line
		(start 114.141758 -284.938978)
		(end 114.14252 -284.93847)
		(stroke
			(width 0.05715)
			(type default)
		)
		(layer "In6.Cu")
	)
	(gr_line
		(start 114.283744 -296.353738)
		(end 114.283744 -296.32529)
		(stroke
			(width 0.05715)
			(type default)
		)
		(layer "In6.Cu")
	)
	(gr_line
		(start 114.283744 -296.32529)
		(end 114.329464 -296.27957)
		(stroke
			(width 0.05715)
			(type default)
		)
		(layer "In6.Cu")
	)
	(gr_line
		(start 114.329464 -295.955974)
		(end 114.32921 -295.956228)
		(stroke
			(width 0.05715)
			(type default)
		)
		(layer "In6.Cu")
	)
	(gr_arc
		(start 114.329464 -287.852104)
		(mid 114.32946 -287.854263)
		(end 114.329464 -287.856422)
		(stroke
			(width 0.05715)
			(type default)
		)
		(layer "In6.Cu")
	)
	(gr_arc
		(start 114.329464 -286.229806)
		(mid 114.329454 -286.233108)
		(end 114.329464 -286.23641)
		(stroke
			(width 0.05715)
			(type default)
		)
		(layer "In6.Cu")
	)
	(gr_line
		(start 114.565684 -296.353738)
		(end 114.565684 -296.32529)
		(stroke
			(width 0.05715)
			(type default)
		)
		(layer "In6.Cu")
	)
	(gr_line
		(start 114.565684 -296.32529)
		(end 114.519964 -296.27957)
		(stroke
			(width 0.05715)
			(type default)
		)
		(layer "In6.Cu")
	)
	(gr_line
		(start 114.598196 -292.236652)
		(end 114.598704 -292.236398)
		(stroke
			(width 0.05715)
			(type default)
		)
		(layer "In6.Cu")
	)
	(gr_line
		(start 114.598704 -292.236398)
		(end 114.600228 -292.235382)
		(stroke
			(width 0.05715)
			(type default)
		)
		(layer "In6.Cu")
	)
	(gr_line
		(start 114.600228 -292.235382)
		(end 114.600736 -292.235128)
		(stroke
			(width 0.05715)
			(type default)
		)
		(layer "In6.Cu")
	)
	(gr_line
		(start 114.60607 -292.23208)
		(end 114.607594 -292.231064)
		(stroke
			(width 0.05715)
			(type default)
		)
		(layer "In6.Cu")
	)
	(gr_arc
		(start 114.607594 -294.821356)
		(mid 114.608482 -294.821865)
		(end 114.609372 -294.822372)
		(stroke
			(width 0.05715)
			(type default)
		)
		(layer "In6.Cu")
	)
	(gr_line
		(start 114.607594 -292.231064)
		(end 114.609372 -292.230048)
		(stroke
			(width 0.05715)
			(type default)
		)
		(layer "In6.Cu")
	)
	(gr_arc
		(start 114.607594 -289.96132)
		(mid 114.608482 -289.961829)
		(end 114.609372 -289.962336)
		(stroke
			(width 0.05715)
			(type default)
		)
		(layer "In6.Cu")
	)
	(gr_line
		(start 114.608102 -293.201598)
		(end 114.6048 -293.199566)
		(stroke
			(width 0.05715)
			(type default)
		)
		(layer "In6.Cu")
	)
	(gr_line
		(start 114.609118 -293.202106)
		(end 114.608102 -293.201598)
		(stroke
			(width 0.05715)
			(type default)
		)
		(layer "In6.Cu")
	)
	(gr_arc
		(start 114.609372 -293.85006)
		(mid 114.608228 -293.850694)
		(end 114.607086 -293.85133)
		(stroke
			(width 0.05715)
			(type default)
		)
		(layer "In6.Cu")
	)
	(gr_arc
		(start 114.609372 -288.990024)
		(mid 114.608228 -288.990658)
		(end 114.607086 -288.991294)
		(stroke
			(width 0.05715)
			(type default)
		)
		(layer "In6.Cu")
	)
	(gr_line
		(start 114.609372 -288.990024)
		(end 114.611658 -288.988754)
		(stroke
			(width 0.05715)
			(type default)
		)
		(layer "In6.Cu")
	)
	(gr_line
		(start 114.610388 -293.849552)
		(end 114.611658 -293.84879)
		(stroke
			(width 0.05715)
			(type default)
		)
		(layer "In6.Cu")
	)
	(gr_line
		(start 114.610388 -293.202868)
		(end 114.609118 -293.202106)
		(stroke
			(width 0.05715)
			(type default)
		)
		(layer "In6.Cu")
	)
	(gr_line
		(start 114.611404 -282.738576)
		(end 114.611912 -282.738068)
		(stroke
			(width 0.05715)
			(type default)
		)
		(layer "In6.Cu")
	)
	(gr_line
		(start 114.611658 -293.84879)
		(end 114.61242 -293.848282)
		(stroke
			(width 0.05715)
			(type default)
		)
		(layer "In6.Cu")
	)
	(gr_line
		(start 114.611658 -288.988754)
		(end 114.61242 -288.988246)
		(stroke
			(width 0.05715)
			(type default)
		)
		(layer "In6.Cu")
	)
	(gr_line
		(start 114.611912 -290.608512)
		(end 114.61242 -290.608258)
		(stroke
			(width 0.05715)
			(type default)
		)
		(layer "In6.Cu")
	)
	(gr_line
		(start 114.611912 -285.74873)
		(end 114.61242 -285.748476)
		(stroke
			(width 0.05715)
			(type default)
		)
		(layer "In6.Cu")
	)
	(gr_line
		(start 114.61242 -293.848282)
		(end 114.61369 -293.84752)
		(stroke
			(width 0.05715)
			(type default)
		)
		(layer "In6.Cu")
	)
	(gr_line
		(start 114.61369 -293.84752)
		(end 114.614706 -293.847012)
		(stroke
			(width 0.05715)
			(type default)
		)
		(layer "In6.Cu")
	)
	(gr_line
		(start 114.613944 -290.607242)
		(end 114.614706 -290.606988)
		(stroke
			(width 0.05715)
			(type default)
		)
		(layer "In6.Cu")
	)
	(gr_line
		(start 114.613944 -285.74746)
		(end 114.614706 -285.747206)
		(stroke
			(width 0.05715)
			(type default)
		)
		(layer "In6.Cu")
	)
	(gr_line
		(start 114.61623 -293.20617)
		(end 114.615214 -293.205662)
		(stroke
			(width 0.05715)
			(type default)
		)
		(layer "In6.Cu")
	)
	(gr_line
		(start 114.617246 -293.845488)
		(end 114.618008 -293.84498)
		(stroke
			(width 0.05715)
			(type default)
		)
		(layer "In6.Cu")
	)
	(gr_line
		(start 114.617246 -292.225476)
		(end 114.618008 -292.224968)
		(stroke
			(width 0.05715)
			(type default)
		)
		(layer "In6.Cu")
	)
	(gr_line
		(start 114.617246 -290.605464)
		(end 114.618008 -290.604956)
		(stroke
			(width 0.05715)
			(type default)
		)
		(layer "In6.Cu")
	)
	(gr_line
		(start 114.617246 -285.745682)
		(end 114.618008 -285.745174)
		(stroke
			(width 0.05715)
			(type default)
		)
		(layer "In6.Cu")
	)
	(gr_line
		(start 114.618008 -293.84498)
		(end 114.619532 -293.844218)
		(stroke
			(width 0.05715)
			(type default)
		)
		(layer "In6.Cu")
	)
	(gr_line
		(start 114.618008 -290.604956)
		(end 114.619532 -290.604194)
		(stroke
			(width 0.05715)
			(type default)
		)
		(layer "In6.Cu")
	)
	(gr_line
		(start 114.618008 -285.745174)
		(end 114.619532 -285.744412)
		(stroke
			(width 0.05715)
			(type default)
		)
		(layer "In6.Cu")
	)
	(gr_line
		(start 114.618516 -293.20744)
		(end 114.61623 -293.20617)
		(stroke
			(width 0.05715)
			(type default)
		)
		(layer "In6.Cu")
	)
	(gr_line
		(start 114.619532 -292.224206)
		(end 114.620294 -292.223698)
		(stroke
			(width 0.05715)
			(type default)
		)
		(layer "In6.Cu")
	)
	(gr_line
		(start 114.619532 -290.604194)
		(end 114.620294 -290.603686)
		(stroke
			(width 0.05715)
			(type default)
		)
		(layer "In6.Cu")
	)
	(gr_line
		(start 114.619532 -285.744412)
		(end 114.620294 -285.743904)
		(stroke
			(width 0.05715)
			(type default)
		)
		(layer "In6.Cu")
	)
	(gr_line
		(start 114.620294 -290.603686)
		(end 114.621564 -290.602924)
		(stroke
			(width 0.05715)
			(type default)
		)
		(layer "In6.Cu")
	)
	(gr_line
		(start 114.620294 -285.743904)
		(end 114.621564 -285.743142)
		(stroke
			(width 0.05715)
			(type default)
		)
		(layer "In6.Cu")
	)
	(gr_line
		(start 114.621564 -293.842948)
		(end 114.623596 -293.841932)
		(stroke
			(width 0.05715)
			(type default)
		)
		(layer "In6.Cu")
	)
	(gr_line
		(start 114.621564 -290.602924)
		(end 114.623596 -290.601908)
		(stroke
			(width 0.05715)
			(type default)
		)
		(layer "In6.Cu")
	)
	(gr_line
		(start 114.621564 -285.743142)
		(end 114.623596 -285.742126)
		(stroke
			(width 0.05715)
			(type default)
		)
		(layer "In6.Cu")
	)
	(gr_line
		(start 114.694208 -292.401244)
		(end 114.694716 -292.40099)
		(stroke
			(width 0.05715)
			(type default)
		)
		(layer "In6.Cu")
	)
	(gr_line
		(start 114.696494 -292.399974)
		(end 114.698272 -292.398958)
		(stroke
			(width 0.05715)
			(type default)
		)
		(layer "In6.Cu")
	)
	(gr_line
		(start 114.698272 -292.398958)
		(end 114.699034 -292.39845)
		(stroke
			(width 0.05715)
			(type default)
		)
		(layer "In6.Cu")
	)
	(gr_line
		(start 114.700558 -292.397688)
		(end 114.701066 -292.397434)
		(stroke
			(width 0.05715)
			(type default)
		)
		(layer "In6.Cu")
	)
	(gr_line
		(start 114.70513 -294.01516)
		(end 114.7064 -294.014398)
		(stroke
			(width 0.05715)
			(type default)
		)
		(layer "In6.Cu")
	)
	(gr_line
		(start 114.70513 -289.15487)
		(end 114.7064 -289.154108)
		(stroke
			(width 0.05715)
			(type default)
		)
		(layer "In6.Cu")
	)
	(gr_line
		(start 114.7064 -289.154108)
		(end 114.70767 -289.153346)
		(stroke
			(width 0.05715)
			(type default)
		)
		(layer "In6.Cu")
	)
	(gr_line
		(start 114.706908 -284.294326)
		(end 114.709194 -284.292802)
		(stroke
			(width 0.05715)
			(type default)
		)
		(layer "In6.Cu")
	)
	(gr_line
		(start 114.708686 -293.039546)
		(end 114.704622 -293.03726)
		(stroke
			(width 0.05715)
			(type default)
		)
		(layer "In6.Cu")
	)
	(gr_line
		(start 114.70894 -294.012874)
		(end 114.710464 -294.011858)
		(stroke
			(width 0.05715)
			(type default)
		)
		(layer "In6.Cu")
	)
	(gr_line
		(start 114.70894 -292.392862)
		(end 114.709448 -292.392608)
		(stroke
			(width 0.05715)
			(type default)
		)
		(layer "In6.Cu")
	)
	(gr_line
		(start 114.70894 -290.77285)
		(end 114.710464 -290.771834)
		(stroke
			(width 0.05715)
			(type default)
		)
		(layer "In6.Cu")
	)
	(gr_line
		(start 114.70894 -285.913068)
		(end 114.710464 -285.912052)
		(stroke
			(width 0.05715)
			(type default)
		)
		(layer "In6.Cu")
	)
	(gr_line
		(start 114.709956 -293.040054)
		(end 114.708686 -293.039546)
		(stroke
			(width 0.05715)
			(type default)
		)
		(layer "In6.Cu")
	)
	(gr_line
		(start 114.71021 -291.420296)
		(end 114.702844 -291.415978)
		(stroke
			(width 0.05715)
			(type default)
		)
		(layer "In6.Cu")
	)
	(gr_line
		(start 114.710718 -293.040562)
		(end 114.709956 -293.040054)
		(stroke
			(width 0.05715)
			(type default)
		)
		(layer "In6.Cu")
	)
	(gr_line
		(start 114.711734 -294.011096)
		(end 114.71275 -294.010588)
		(stroke
			(width 0.05715)
			(type default)
		)
		(layer "In6.Cu")
	)
	(gr_line
		(start 114.711734 -290.771072)
		(end 114.71275 -290.770564)
		(stroke
			(width 0.05715)
			(type default)
		)
		(layer "In6.Cu")
	)
	(gr_line
		(start 114.711734 -285.91129)
		(end 114.71275 -285.910782)
		(stroke
			(width 0.05715)
			(type default)
		)
		(layer "In6.Cu")
	)
	(gr_line
		(start 114.71275 -294.661844)
		(end 114.70513 -294.657526)
		(stroke
			(width 0.05715)
			(type default)
		)
		(layer "In6.Cu")
	)
	(gr_line
		(start 114.71275 -294.010588)
		(end 114.71529 -294.009064)
		(stroke
			(width 0.05715)
			(type default)
		)
		(layer "In6.Cu")
	)
	(gr_line
		(start 114.71275 -290.770564)
		(end 114.71529 -290.76904)
		(stroke
			(width 0.05715)
			(type default)
		)
		(layer "In6.Cu")
	)
	(gr_line
		(start 114.71275 -289.801808)
		(end 114.70513 -289.79749)
		(stroke
			(width 0.05715)
			(type default)
		)
		(layer "In6.Cu")
	)
	(gr_line
		(start 114.71275 -285.910782)
		(end 114.71529 -285.909258)
		(stroke
			(width 0.05715)
			(type default)
		)
		(layer "In6.Cu")
	)
	(gr_line
		(start 114.713512 -292.390068)
		(end 114.71529 -292.389052)
		(stroke
			(width 0.05715)
			(type default)
		)
		(layer "In6.Cu")
	)
	(gr_line
		(start 114.713766 -291.422328)
		(end 114.711988 -291.421312)
		(stroke
			(width 0.05715)
			(type default)
		)
		(layer "In6.Cu")
	)
	(gr_line
		(start 114.71402 -293.042594)
		(end 114.711988 -293.041324)
		(stroke
			(width 0.05715)
			(type default)
		)
		(layer "In6.Cu")
	)
	(gr_line
		(start 114.71529 -294.009064)
		(end 114.716052 -294.008556)
		(stroke
			(width 0.05715)
			(type default)
		)
		(layer "In6.Cu")
	)
	(gr_line
		(start 114.71529 -292.389052)
		(end 114.716052 -292.388544)
		(stroke
			(width 0.05715)
			(type default)
		)
		(layer "In6.Cu")
	)
	(gr_line
		(start 114.71529 -290.76904)
		(end 114.716052 -290.768532)
		(stroke
			(width 0.05715)
			(type default)
		)
		(layer "In6.Cu")
	)
	(gr_line
		(start 114.71529 -285.909258)
		(end 114.716052 -285.90875)
		(stroke
			(width 0.05715)
			(type default)
		)
		(layer "In6.Cu")
	)
	(gr_line
		(start 114.716052 -294.008556)
		(end 114.717068 -294.008048)
		(stroke
			(width 0.05715)
			(type default)
		)
		(layer "In6.Cu")
	)
	(gr_line
		(start 114.716052 -292.388544)
		(end 114.717068 -292.388036)
		(stroke
			(width 0.05715)
			(type default)
		)
		(layer "In6.Cu")
	)
	(gr_line
		(start 114.716052 -290.768532)
		(end 114.717068 -290.768024)
		(stroke
			(width 0.05715)
			(type default)
		)
		(layer "In6.Cu")
	)
	(gr_line
		(start 114.716052 -285.90875)
		(end 114.717068 -285.908242)
		(stroke
			(width 0.05715)
			(type default)
		)
		(layer "In6.Cu")
	)
	(gr_line
		(start 114.722656 -285.426404)
		(end 114.424714 -285.426404)
		(stroke
			(width 0.05715)
			(type default)
		)
		(layer "In6.Cu")
	)
	(gr_line
		(start 114.722656 -283.806392)
		(end 114.424714 -283.806392)
		(stroke
			(width 0.05715)
			(type default)
		)
		(layer "In6.Cu")
	)
	(gr_line
		(start 114.722656 -282.18638)
		(end 114.424714 -282.18638)
		(stroke
			(width 0.05715)
			(type default)
		)
		(layer "In6.Cu")
	)
	(gr_line
		(start 114.736372 -282.657042)
		(end 114.737134 -282.656534)
		(stroke
			(width 0.05715)
			(type default)
		)
		(layer "In6.Cu")
	)
	(gr_line
		(start 114.737896 -282.656026)
		(end 114.746786 -282.650946)
		(stroke
			(width 0.05715)
			(type default)
		)
		(layer "In6.Cu")
	)
	(gr_arc
		(start 114.738404 -288.197036)
		(mid 114.734477 -288.194607)
		(end 114.73053 -288.19221)
		(stroke
			(width 0.05715)
			(type default)
		)
		(layer "In6.Cu")
	)
	(gr_line
		(start 114.739166 -294.677084)
		(end 114.738658 -294.67683)
		(stroke
			(width 0.05715)
			(type default)
		)
		(layer "In6.Cu")
	)
	(gr_line
		(start 114.739928 -294.677592)
		(end 114.739166 -294.677084)
		(stroke
			(width 0.05715)
			(type default)
		)
		(layer "In6.Cu")
	)
	(gr_line
		(start 114.746786 -294.681656)
		(end 114.739928 -294.677592)
		(stroke
			(width 0.05715)
			(type default)
		)
		(layer "In6.Cu")
	)
	(gr_arc
		(start 114.74831 -282.64993)
		(mid 114.751493 -282.647655)
		(end 114.75466 -282.645358)
		(stroke
			(width 0.05715)
			(type default)
		)
		(layer "In6.Cu")
	)
	(gr_arc
		(start 114.75466 -294.687244)
		(mid 114.750735 -294.684433)
		(end 114.746786 -294.681656)
		(stroke
			(width 0.05715)
			(type default)
		)
		(layer "In6.Cu")
	)
	(gr_line
		(start 114.791998 -285.495746)
		(end 114.722656 -285.426404)
		(stroke
			(width 0.05715)
			(type default)
		)
		(layer "In6.Cu")
	)
	(gr_line
		(start 114.791998 -283.875734)
		(end 114.722656 -283.806392)
		(stroke
			(width 0.05715)
			(type default)
		)
		(layer "In6.Cu")
	)
	(gr_line
		(start 114.791998 -282.255722)
		(end 114.722656 -282.18638)
		(stroke
			(width 0.05715)
			(type default)
		)
		(layer "In6.Cu")
	)
	(gr_line
		(start 114.819938 -330.874116)
		(end 114.820192 -330.874116)
		(stroke
			(width 0.07112)
			(type default)
		)
		(layer "In6.Cu")
	)
	(gr_line
		(start 114.891312 -388.774432)
		(end 114.943636 -388.826756)
		(stroke
			(width 0.07112)
			(type default)
		)
		(layer "In6.Cu")
	)
	(gr_line
		(start 114.943636 -389.006588)
		(end 114.797078 -389.153146)
		(stroke
			(width 0.07112)
			(type default)
		)
		(layer "In6.Cu")
	)
	(gr_line
		(start 114.943636 -388.826756)
		(end 114.943636 -389.006588)
		(stroke
			(width 0.07112)
			(type default)
		)
		(layer "In6.Cu")
	)
	(gr_arc
		(start 114.980212 -285.532068)
		(mid 114.982235 -285.520658)
		(end 114.984022 -285.509208)
		(stroke
			(width 0.05715)
			(type default)
		)
		(layer "In6.Cu")
	)
	(gr_arc
		(start 114.980212 -283.912056)
		(mid 114.982234 -283.900646)
		(end 114.984022 -283.889196)
		(stroke
			(width 0.05715)
			(type default)
		)
		(layer "In6.Cu")
	)
	(gr_arc
		(start 114.980212 -282.292044)
		(mid 114.982234 -282.280634)
		(end 114.984022 -282.269184)
		(stroke
			(width 0.05715)
			(type default)
		)
		(layer "In6.Cu")
	)
	(gr_line
		(start 114.984022 -285.509208)
		(end 115.066826 -285.426404)
		(stroke
			(width 0.05715)
			(type default)
		)
		(layer "In6.Cu")
	)
	(gr_line
		(start 114.984022 -283.889196)
		(end 115.066826 -283.806392)
		(stroke
			(width 0.05715)
			(type default)
		)
		(layer "In6.Cu")
	)
	(gr_line
		(start 114.984022 -282.269184)
		(end 115.066826 -282.18638)
		(stroke
			(width 0.05715)
			(type default)
		)
		(layer "In6.Cu")
	)
	(gr_line
		(start 115.066826 -285.426404)
		(end 115.364768 -285.426404)
		(stroke
			(width 0.05715)
			(type default)
		)
		(layer "In6.Cu")
	)
	(gr_line
		(start 115.066826 -283.806392)
		(end 115.364768 -283.806392)
		(stroke
			(width 0.05715)
			(type default)
		)
		(layer "In6.Cu")
	)
	(gr_line
		(start 115.066826 -282.18638)
		(end 115.364768 -282.18638)
		(stroke
			(width 0.05715)
			(type default)
		)
		(layer "In6.Cu")
	)
	(gr_line
		(start 115.069874 -330.743052)
		(end 115.070128 -330.74356)
		(stroke
			(width 0.07112)
			(type default)
		)
		(layer "In6.Cu")
	)
	(gr_line
		(start 115.176554 -389.352536)
		(end 114.998246 -389.352536)
		(stroke
			(width 0.07112)
			(type default)
		)
		(layer "In6.Cu")
	)
	(gr_line
		(start 115.194588 -324.772528)
		(end 115.194842 -324.772528)
		(stroke
			(width 0.07112)
			(type default)
		)
		(layer "In6.Cu")
	)
	(gr_line
		(start 115.22329 -297.299888)
		(end 115.22329 -297.29938)
		(stroke
			(width 0.07112)
			(type default)
		)
		(layer "In6.Cu")
	)
	(gr_line
		(start 115.22329 -296.353738)
		(end 115.22329 -296.32529)
		(stroke
			(width 0.05715)
			(type default)
		)
		(layer "In6.Cu")
	)
	(gr_line
		(start 115.22329 -296.32529)
		(end 115.26901 -296.27957)
		(stroke
			(width 0.05715)
			(type default)
		)
		(layer "In6.Cu")
	)
	(gr_line
		(start 115.26393 -324.876668)
		(end 115.264438 -324.877938)
		(stroke
			(width 0.07112)
			(type default)
		)
		(layer "In6.Cu")
	)
	(gr_line
		(start 115.26901 -296.27957)
		(end 115.268756 -296.279316)
		(stroke
			(width 0.05715)
			(type default)
		)
		(layer "In6.Cu")
	)
	(gr_line
		(start 115.269518 -295.955974)
		(end 115.269264 -295.956228)
		(stroke
			(width 0.05715)
			(type default)
		)
		(layer "In6.Cu")
	)
	(gr_line
		(start 115.291362 -389.467344)
		(end 115.176554 -389.352536)
		(stroke
			(width 0.07112)
			(type default)
		)
		(layer "In6.Cu")
	)
	(gr_line
		(start 115.45951 -296.27957)
		(end 115.460018 -296.279062)
		(stroke
			(width 0.05715)
			(type default)
		)
		(layer "In6.Cu")
	)
	(gr_line
		(start 115.460018 -296.200576)
		(end 115.460018 -296.199814)
		(stroke
			(width 0.05715)
			(type default)
		)
		(layer "In6.Cu")
	)
	(gr_line
		(start 115.50523 -296.353738)
		(end 115.50523 -296.32529)
		(stroke
			(width 0.05715)
			(type default)
		)
		(layer "In6.Cu")
	)
	(gr_line
		(start 115.50523 -296.32529)
		(end 115.45951 -296.27957)
		(stroke
			(width 0.05715)
			(type default)
		)
		(layer "In6.Cu")
	)
	(gr_line
		(start 115.512342 -293.87165)
		(end 115.513104 -293.871142)
		(stroke
			(width 0.05715)
			(type default)
		)
		(layer "In6.Cu")
	)
	(gr_line
		(start 115.512342 -290.631626)
		(end 115.513104 -290.631118)
		(stroke
			(width 0.05715)
			(type default)
		)
		(layer "In6.Cu")
	)
	(gr_line
		(start 115.512342 -289.01136)
		(end 115.514374 -289.01009)
		(stroke
			(width 0.05715)
			(type default)
		)
		(layer "In6.Cu")
	)
	(gr_line
		(start 115.512342 -285.77159)
		(end 115.520216 -285.767018)
		(stroke
			(width 0.05715)
			(type default)
		)
		(layer "In6.Cu")
	)
	(gr_arc
		(start 115.512596 -293.87165)
		(mid 115.508647 -293.874427)
		(end 115.504722 -293.877238)
		(stroke
			(width 0.05715)
			(type default)
		)
		(layer "In6.Cu")
	)
	(gr_line
		(start 115.512596 -293.87165)
		(end 115.512342 -293.87165)
		(stroke
			(width 0.05715)
			(type default)
		)
		(layer "In6.Cu")
	)
	(gr_arc
		(start 115.512596 -292.251638)
		(mid 115.508647 -292.254415)
		(end 115.504722 -292.257226)
		(stroke
			(width 0.05715)
			(type default)
		)
		(layer "In6.Cu")
	)
	(gr_line
		(start 115.512596 -292.251638)
		(end 115.512342 -292.251638)
		(stroke
			(width 0.05715)
			(type default)
		)
		(layer "In6.Cu")
	)
	(gr_arc
		(start 115.512596 -290.631626)
		(mid 115.508647 -290.634403)
		(end 115.504722 -290.637214)
		(stroke
			(width 0.05715)
			(type default)
		)
		(layer "In6.Cu")
	)
	(gr_line
		(start 115.512596 -290.631626)
		(end 115.512342 -290.631626)
		(stroke
			(width 0.05715)
			(type default)
		)
		(layer "In6.Cu")
	)
	(gr_arc
		(start 115.512596 -289.011614)
		(mid 115.508647 -289.014391)
		(end 115.504722 -289.017202)
		(stroke
			(width 0.05715)
			(type default)
		)
		(layer "In6.Cu")
	)
	(gr_line
		(start 115.512596 -289.011614)
		(end 115.512342 -289.01136)
		(stroke
			(width 0.05715)
			(type default)
		)
		(layer "In6.Cu")
	)
	(gr_arc
		(start 115.512596 -285.771844)
		(mid 115.508647 -285.774621)
		(end 115.504722 -285.777432)
		(stroke
			(width 0.05715)
			(type default)
		)
		(layer "In6.Cu")
	)
	(gr_line
		(start 115.512596 -285.771844)
		(end 115.512342 -285.77159)
		(stroke
			(width 0.05715)
			(type default)
		)
		(layer "In6.Cu")
	)
	(gr_line
		(start 115.513104 -293.871142)
		(end 115.520724 -293.866824)
		(stroke
			(width 0.05715)
			(type default)
		)
		(layer "In6.Cu")
	)
	(gr_line
		(start 115.513104 -290.631118)
		(end 115.520216 -290.627054)
		(stroke
			(width 0.05715)
			(type default)
		)
		(layer "In6.Cu")
	)
	(gr_arc
		(start 115.513866 -292.250622)
		(mid 115.513104 -292.251129)
		(end 115.512342 -292.251638)
		(stroke
			(width 0.05715)
			(type default)
		)
		(layer "In6.Cu")
	)
	(gr_line
		(start 115.513866 -292.250622)
		(end 115.52174 -292.24605)
		(stroke
			(width 0.05715)
			(type default)
		)
		(layer "In6.Cu")
	)
	(gr_line
		(start 115.514374 -289.01009)
		(end 115.522756 -289.005518)
		(stroke
			(width 0.05715)
			(type default)
		)
		(layer "In6.Cu")
	)
	(gr_line
		(start 115.544346 -294.819324)
		(end 115.543584 -294.818816)
		(stroke
			(width 0.05715)
			(type default)
		)
		(layer "In6.Cu")
	)
	(gr_line
		(start 115.544346 -293.199312)
		(end 115.543584 -293.198804)
		(stroke
			(width 0.05715)
			(type default)
		)
		(layer "In6.Cu")
	)
	(gr_line
		(start 115.544346 -291.5793)
		(end 115.543584 -291.578792)
		(stroke
			(width 0.05715)
			(type default)
		)
		(layer "In6.Cu")
	)
	(gr_line
		(start 115.544346 -289.959288)
		(end 115.543584 -289.95878)
		(stroke
			(width 0.05715)
			(type default)
		)
		(layer "In6.Cu")
	)
	(gr_line
		(start 115.546886 -294.820848)
		(end 115.546378 -294.820594)
		(stroke
			(width 0.05715)
			(type default)
		)
		(layer "In6.Cu")
	)
	(gr_line
		(start 115.546886 -293.200836)
		(end 115.546378 -293.200582)
		(stroke
			(width 0.05715)
			(type default)
		)
		(layer "In6.Cu")
	)
	(gr_line
		(start 115.546886 -291.580824)
		(end 115.546378 -291.58057)
		(stroke
			(width 0.05715)
			(type default)
		)
		(layer "In6.Cu")
	)
	(gr_line
		(start 115.546886 -289.960812)
		(end 115.546378 -289.960558)
		(stroke
			(width 0.05715)
			(type default)
		)
		(layer "In6.Cu")
	)
	(gr_line
		(start 115.547648 -292.231318)
		(end 115.549172 -292.230302)
		(stroke
			(width 0.05715)
			(type default)
		)
		(layer "In6.Cu")
	)
	(gr_line
		(start 115.549172 -294.822118)
		(end 115.548664 -294.821864)
		(stroke
			(width 0.05715)
			(type default)
		)
		(layer "In6.Cu")
	)
	(gr_line
		(start 115.549172 -293.202106)
		(end 115.548664 -293.201852)
		(stroke
			(width 0.05715)
			(type default)
		)
		(layer "In6.Cu")
	)
	(gr_line
		(start 115.549172 -292.230302)
		(end 115.550696 -292.229286)
		(stroke
			(width 0.05715)
			(type default)
		)
		(layer "In6.Cu")
	)
	(gr_line
		(start 115.549172 -291.582094)
		(end 115.548664 -291.58184)
		(stroke
			(width 0.05715)
			(type default)
		)
		(layer "In6.Cu")
	)
	(gr_line
		(start 115.549172 -289.962082)
		(end 115.548664 -289.961828)
		(stroke
			(width 0.05715)
			(type default)
		)
		(layer "In6.Cu")
	)
	(gr_line
		(start 115.550696 -294.823134)
		(end 115.549172 -294.822118)
		(stroke
			(width 0.05715)
			(type default)
		)
		(layer "In6.Cu")
	)
	(gr_line
		(start 115.550696 -293.203122)
		(end 115.549172 -293.202106)
		(stroke
			(width 0.05715)
			(type default)
		)
		(layer "In6.Cu")
	)
	(gr_line
		(start 115.550696 -291.58311)
		(end 115.549172 -291.582094)
		(stroke
			(width 0.05715)
			(type default)
		)
		(layer "In6.Cu")
	)
	(gr_line
		(start 115.550696 -289.963098)
		(end 115.549172 -289.962082)
		(stroke
			(width 0.05715)
			(type default)
		)
		(layer "In6.Cu")
	)
	(gr_line
		(start 115.551712 -294.823642)
		(end 115.550696 -294.823134)
		(stroke
			(width 0.05715)
			(type default)
		)
		(layer "In6.Cu")
	)
	(gr_line
		(start 115.551712 -293.20363)
		(end 115.550696 -293.203122)
		(stroke
			(width 0.05715)
			(type default)
		)
		(layer "In6.Cu")
	)
	(gr_line
		(start 115.551712 -291.583618)
		(end 115.550696 -291.58311)
		(stroke
			(width 0.05715)
			(type default)
		)
		(layer "In6.Cu")
	)
	(gr_line
		(start 115.551712 -289.963606)
		(end 115.550696 -289.963098)
		(stroke
			(width 0.05715)
			(type default)
		)
		(layer "In6.Cu")
	)
	(gr_line
		(start 115.552474 -294.82415)
		(end 115.551712 -294.823642)
		(stroke
			(width 0.05715)
			(type default)
		)
		(layer "In6.Cu")
	)
	(gr_line
		(start 115.552474 -293.204138)
		(end 115.551712 -293.20363)
		(stroke
			(width 0.05715)
			(type default)
		)
		(layer "In6.Cu")
	)
	(gr_line
		(start 115.552474 -292.22827)
		(end 115.553744 -292.227508)
		(stroke
			(width 0.05715)
			(type default)
		)
		(layer "In6.Cu")
	)
	(gr_line
		(start 115.552474 -291.584126)
		(end 115.551712 -291.583618)
		(stroke
			(width 0.05715)
			(type default)
		)
		(layer "In6.Cu")
	)
	(gr_line
		(start 115.552474 -289.964114)
		(end 115.551712 -289.963606)
		(stroke
			(width 0.05715)
			(type default)
		)
		(layer "In6.Cu")
	)
	(gr_line
		(start 115.557046 -294.82669)
		(end 115.556284 -294.826182)
		(stroke
			(width 0.05715)
			(type default)
		)
		(layer "In6.Cu")
	)
	(gr_line
		(start 115.557046 -293.206678)
		(end 115.556284 -293.20617)
		(stroke
			(width 0.05715)
			(type default)
		)
		(layer "In6.Cu")
	)
	(gr_line
		(start 115.557046 -291.586666)
		(end 115.556284 -291.586158)
		(stroke
			(width 0.05715)
			(type default)
		)
		(layer "In6.Cu")
	)
	(gr_line
		(start 115.557046 -289.966654)
		(end 115.556284 -289.966146)
		(stroke
			(width 0.05715)
			(type default)
		)
		(layer "In6.Cu")
	)
	(gr_line
		(start 115.558824 -294.827706)
		(end 115.557808 -294.827198)
		(stroke
			(width 0.05715)
			(type default)
		)
		(layer "In6.Cu")
	)
	(gr_line
		(start 115.558824 -293.207694)
		(end 115.557808 -293.207186)
		(stroke
			(width 0.05715)
			(type default)
		)
		(layer "In6.Cu")
	)
	(gr_line
		(start 115.558824 -291.587682)
		(end 115.557808 -291.587174)
		(stroke
			(width 0.05715)
			(type default)
		)
		(layer "In6.Cu")
	)
	(gr_line
		(start 115.558824 -289.96767)
		(end 115.557808 -289.967162)
		(stroke
			(width 0.05715)
			(type default)
		)
		(layer "In6.Cu")
	)
	(gr_line
		(start 115.559332 -294.82796)
		(end 115.558824 -294.827706)
		(stroke
			(width 0.05715)
			(type default)
		)
		(layer "In6.Cu")
	)
	(gr_line
		(start 115.559332 -293.207948)
		(end 115.558824 -293.207694)
		(stroke
			(width 0.05715)
			(type default)
		)
		(layer "In6.Cu")
	)
	(gr_line
		(start 115.559332 -291.587936)
		(end 115.558824 -291.587682)
		(stroke
			(width 0.05715)
			(type default)
		)
		(layer "In6.Cu")
	)
	(gr_line
		(start 115.559332 -289.967924)
		(end 115.558824 -289.96767)
		(stroke
			(width 0.05715)
			(type default)
		)
		(layer "In6.Cu")
	)
	(gr_line
		(start 115.582954 -293.830756)
		(end 115.583208 -293.830502)
		(stroke
			(width 0.05715)
			(type default)
		)
		(layer "In6.Cu")
	)
	(gr_line
		(start 115.583208 -293.830502)
		(end 115.583462 -293.830502)
		(stroke
			(width 0.05715)
			(type default)
		)
		(layer "In6.Cu")
	)
	(gr_line
		(start 115.63731 -292.39972)
		(end 115.637818 -292.399466)
		(stroke
			(width 0.05715)
			(type default)
		)
		(layer "In6.Cu")
	)
	(gr_line
		(start 115.639596 -292.39845)
		(end 115.641882 -292.39718)
		(stroke
			(width 0.05715)
			(type default)
		)
		(layer "In6.Cu")
	)
	(gr_line
		(start 115.641882 -292.39718)
		(end 115.643152 -292.396418)
		(stroke
			(width 0.05715)
			(type default)
		)
		(layer "In6.Cu")
	)
	(gr_line
		(start 115.643152 -292.396418)
		(end 115.645184 -292.395148)
		(stroke
			(width 0.05715)
			(type default)
		)
		(layer "In6.Cu")
	)
	(gr_line
		(start 115.645184 -292.395148)
		(end 115.646962 -292.394132)
		(stroke
			(width 0.05715)
			(type default)
		)
		(layer "In6.Cu")
	)
	(gr_line
		(start 115.646962 -294.658288)
		(end 115.644168 -294.656764)
		(stroke
			(width 0.05715)
			(type default)
		)
		(layer "In6.Cu")
	)
	(gr_line
		(start 115.646962 -293.038276)
		(end 115.644168 -293.036752)
		(stroke
			(width 0.05715)
			(type default)
		)
		(layer "In6.Cu")
	)
	(gr_line
		(start 115.646962 -292.394132)
		(end 115.647724 -292.393624)
		(stroke
			(width 0.05715)
			(type default)
		)
		(layer "In6.Cu")
	)
	(gr_line
		(start 115.646962 -291.418264)
		(end 115.644168 -291.41674)
		(stroke
			(width 0.05715)
			(type default)
		)
		(layer "In6.Cu")
	)
	(gr_line
		(start 115.646962 -289.798252)
		(end 115.644168 -289.796728)
		(stroke
			(width 0.05715)
			(type default)
		)
		(layer "In6.Cu")
	)
	(gr_line
		(start 115.647724 -294.658796)
		(end 115.646962 -294.658288)
		(stroke
			(width 0.05715)
			(type default)
		)
		(layer "In6.Cu")
	)
	(gr_line
		(start 115.647724 -293.038784)
		(end 115.646962 -293.038276)
		(stroke
			(width 0.05715)
			(type default)
		)
		(layer "In6.Cu")
	)
	(gr_line
		(start 115.647724 -292.393624)
		(end 115.648232 -292.39337)
		(stroke
			(width 0.05715)
			(type default)
		)
		(layer "In6.Cu")
	)
	(gr_line
		(start 115.647724 -291.418772)
		(end 115.646962 -291.418264)
		(stroke
			(width 0.05715)
			(type default)
		)
		(layer "In6.Cu")
	)
	(gr_line
		(start 115.647724 -289.79876)
		(end 115.646962 -289.798252)
		(stroke
			(width 0.05715)
			(type default)
		)
		(layer "In6.Cu")
	)
	(gr_line
		(start 115.64874 -294.659304)
		(end 115.647724 -294.658796)
		(stroke
			(width 0.05715)
			(type default)
		)
		(layer "In6.Cu")
	)
	(gr_line
		(start 115.64874 -293.039292)
		(end 115.647724 -293.038784)
		(stroke
			(width 0.05715)
			(type default)
		)
		(layer "In6.Cu")
	)
	(gr_line
		(start 115.64874 -291.41928)
		(end 115.647724 -291.418772)
		(stroke
			(width 0.05715)
			(type default)
		)
		(layer "In6.Cu")
	)
	(gr_line
		(start 115.64874 -289.799268)
		(end 115.647724 -289.79876)
		(stroke
			(width 0.05715)
			(type default)
		)
		(layer "In6.Cu")
	)
	(gr_line
		(start 115.649502 -294.659812)
		(end 115.64874 -294.659304)
		(stroke
			(width 0.05715)
			(type default)
		)
		(layer "In6.Cu")
	)
	(gr_line
		(start 115.649502 -293.0398)
		(end 115.64874 -293.039292)
		(stroke
			(width 0.05715)
			(type default)
		)
		(layer "In6.Cu")
	)
	(gr_line
		(start 115.649502 -291.419788)
		(end 115.64874 -291.41928)
		(stroke
			(width 0.05715)
			(type default)
		)
		(layer "In6.Cu")
	)
	(gr_line
		(start 115.649502 -289.799776)
		(end 115.64874 -289.799268)
		(stroke
			(width 0.05715)
			(type default)
		)
		(layer "In6.Cu")
	)
	(gr_line
		(start 115.653058 -294.661844)
		(end 115.652042 -294.661336)
		(stroke
			(width 0.05715)
			(type default)
		)
		(layer "In6.Cu")
	)
	(gr_line
		(start 115.653058 -293.041832)
		(end 115.652042 -293.041324)
		(stroke
			(width 0.05715)
			(type default)
		)
		(layer "In6.Cu")
	)
	(gr_line
		(start 115.653058 -291.42182)
		(end 115.652042 -291.421312)
		(stroke
			(width 0.05715)
			(type default)
		)
		(layer "In6.Cu")
	)
	(gr_line
		(start 115.653058 -289.801808)
		(end 115.652042 -289.8013)
		(stroke
			(width 0.05715)
			(type default)
		)
		(layer "In6.Cu")
	)
	(gr_line
		(start 115.654074 -294.662606)
		(end 115.653058 -294.661844)
		(stroke
			(width 0.05715)
			(type default)
		)
		(layer "In6.Cu")
	)
	(gr_line
		(start 115.654074 -293.042594)
		(end 115.653058 -293.041832)
		(stroke
			(width 0.05715)
			(type default)
		)
		(layer "In6.Cu")
	)
	(gr_line
		(start 115.654074 -291.422582)
		(end 115.653058 -291.42182)
		(stroke
			(width 0.05715)
			(type default)
		)
		(layer "In6.Cu")
	)
	(gr_line
		(start 115.654074 -289.80257)
		(end 115.653058 -289.801808)
		(stroke
			(width 0.05715)
			(type default)
		)
		(layer "In6.Cu")
	)
	(gr_line
		(start 115.66779 -289.142932)
		(end 115.67541 -289.138868)
		(stroke
			(width 0.05715)
			(type default)
		)
		(layer "In6.Cu")
	)
	(gr_line
		(start 115.678458 -293.995856)
		(end 115.68176 -293.993824)
		(stroke
			(width 0.05715)
			(type default)
		)
		(layer "In6.Cu")
	)
	(gr_line
		(start 115.67922 -294.677084)
		(end 115.678712 -294.67683)
		(stroke
			(width 0.05715)
			(type default)
		)
		(layer "In6.Cu")
	)
	(gr_line
		(start 115.67922 -293.057072)
		(end 115.678712 -293.056818)
		(stroke
			(width 0.05715)
			(type default)
		)
		(layer "In6.Cu")
	)
	(gr_line
		(start 115.67922 -291.43706)
		(end 115.678712 -291.436806)
		(stroke
			(width 0.05715)
			(type default)
		)
		(layer "In6.Cu")
	)
	(gr_line
		(start 115.67922 -290.75507)
		(end 115.68557 -290.751514)
		(stroke
			(width 0.05715)
			(type default)
		)
		(layer "In6.Cu")
	)
	(gr_line
		(start 115.67922 -289.817048)
		(end 115.678712 -289.816794)
		(stroke
			(width 0.05715)
			(type default)
		)
		(layer "In6.Cu")
	)
	(gr_line
		(start 115.679982 -294.677592)
		(end 115.67922 -294.677084)
		(stroke
			(width 0.05715)
			(type default)
		)
		(layer "In6.Cu")
	)
	(gr_line
		(start 115.679982 -293.05758)
		(end 115.67922 -293.057072)
		(stroke
			(width 0.05715)
			(type default)
		)
		(layer "In6.Cu")
	)
	(gr_line
		(start 115.679982 -291.437568)
		(end 115.67922 -291.43706)
		(stroke
			(width 0.05715)
			(type default)
		)
		(layer "In6.Cu")
	)
	(gr_line
		(start 115.679982 -289.817556)
		(end 115.67922 -289.817048)
		(stroke
			(width 0.05715)
			(type default)
		)
		(layer "In6.Cu")
	)
	(gr_line
		(start 115.68176 -293.993824)
		(end 115.68684 -293.990776)
		(stroke
			(width 0.05715)
			(type default)
		)
		(layer "In6.Cu")
	)
	(gr_line
		(start 115.68557 -290.751514)
		(end 115.68684 -290.750752)
		(stroke
			(width 0.05715)
			(type default)
		)
		(layer "In6.Cu")
	)
	(gr_line
		(start 115.68684 -294.681656)
		(end 115.679982 -294.677592)
		(stroke
			(width 0.05715)
			(type default)
		)
		(layer "In6.Cu")
	)
	(gr_arc
		(start 115.68684 -293.990776)
		(mid 115.690789 -293.987999)
		(end 115.694714 -293.985188)
		(stroke
			(width 0.05715)
			(type default)
		)
		(layer "In6.Cu")
	)
	(gr_line
		(start 115.68684 -293.061644)
		(end 115.679982 -293.05758)
		(stroke
			(width 0.05715)
			(type default)
		)
		(layer "In6.Cu")
	)
	(gr_line
		(start 115.68684 -291.441632)
		(end 115.679982 -291.437568)
		(stroke
			(width 0.05715)
			(type default)
		)
		(layer "In6.Cu")
	)
	(gr_arc
		(start 115.68684 -290.750752)
		(mid 115.688111 -290.749865)
		(end 115.68938 -290.748974)
		(stroke
			(width 0.05715)
			(type default)
		)
		(layer "In6.Cu")
	)
	(gr_line
		(start 115.68684 -289.82162)
		(end 115.679982 -289.817556)
		(stroke
			(width 0.05715)
			(type default)
		)
		(layer "In6.Cu")
	)
	(gr_arc
		(start 115.690142 -290.748466)
		(mid 115.692687 -290.746695)
		(end 115.695222 -290.74491)
		(stroke
			(width 0.05715)
			(type default)
		)
		(layer "In6.Cu")
	)
	(gr_arc
		(start 115.694714 -294.687244)
		(mid 115.690789 -294.684433)
		(end 115.68684 -294.681656)
		(stroke
			(width 0.05715)
			(type default)
		)
		(layer "In6.Cu")
	)
	(gr_arc
		(start 115.694714 -293.067232)
		(mid 115.690789 -293.064421)
		(end 115.68684 -293.061644)
		(stroke
			(width 0.05715)
			(type default)
		)
		(layer "In6.Cu")
	)
	(gr_arc
		(start 115.694714 -291.44722)
		(mid 115.690789 -291.444409)
		(end 115.68684 -291.441632)
		(stroke
			(width 0.05715)
			(type default)
		)
		(layer "In6.Cu")
	)
	(gr_arc
		(start 115.694714 -289.827208)
		(mid 115.690789 -289.824397)
		(end 115.68684 -289.82162)
		(stroke
			(width 0.05715)
			(type default)
		)
		(layer "In6.Cu")
	)
	(gr_arc
		(start 115.697 -290.74364)
		(mid 115.69789 -290.742879)
		(end 115.698778 -290.742116)
		(stroke
			(width 0.05715)
			(type default)
		)
		(layer "In6.Cu")
	)
	(gr_line
		(start 115.913662 -399.58772)
		(end 116.05006 -400.275806)
		(stroke
			(width 0.07112)
			(type default)
		)
		(layer "In6.Cu")
	)
	(gr_line
		(start 116.043456 -331.11948)
		(end 116.043456 -331.119734)
		(stroke
			(width 0.07112)
			(type default)
		)
		(layer "In6.Cu")
	)
	(gr_line
		(start 116.091208 -388.774432)
		(end 116.143532 -388.826756)
		(stroke
			(width 0.07112)
			(type default)
		)
		(layer "In6.Cu")
	)
	(gr_line
		(start 116.132864 -400.694144)
		(end 116.269262 -401.38223)
		(stroke
			(width 0.07112)
			(type default)
		)
		(layer "In6.Cu")
	)
	(gr_line
		(start 116.143532 -389.006588)
		(end 115.996974 -389.153146)
		(stroke
			(width 0.07112)
			(type default)
		)
		(layer "In6.Cu")
	)
	(gr_line
		(start 116.143532 -388.826756)
		(end 116.143532 -389.006588)
		(stroke
			(width 0.07112)
			(type default)
		)
		(layer "In6.Cu")
	)
	(gr_line
		(start 116.164614 -296.353738)
		(end 116.164614 -296.32529)
		(stroke
			(width 0.05715)
			(type default)
		)
		(layer "In6.Cu")
	)
	(gr_line
		(start 116.164614 -296.32529)
		(end 116.210334 -296.27957)
		(stroke
			(width 0.05715)
			(type default)
		)
		(layer "In6.Cu")
	)
	(gr_line
		(start 116.190522 -399.532856)
		(end 116.190268 -399.532856)
		(stroke
			(width 0.07112)
			(type default)
		)
		(layer "In6.Cu")
	)
	(gr_line
		(start 116.191792 -399.533872)
		(end 116.351558 -399.640806)
		(stroke
			(width 0.07112)
			(type default)
		)
		(layer "In6.Cu")
	)
	(gr_line
		(start 116.209572 -296.200576)
		(end 116.209572 -296.19956)
		(stroke
			(width 0.05715)
			(type default)
		)
		(layer "In6.Cu")
	)
	(gr_line
		(start 116.321078 -331.069442)
		(end 116.321078 -331.070204)
		(stroke
			(width 0.07112)
			(type default)
		)
		(layer "In6.Cu")
	)
	(gr_line
		(start 116.351558 -399.640806)
		(end 116.434616 -400.059652)
		(stroke
			(width 0.07112)
			(type default)
		)
		(layer "In6.Cu")
	)
	(gr_line
		(start 116.352066 -401.800568)
		(end 116.488464 -402.4884)
		(stroke
			(width 0.07112)
			(type default)
		)
		(layer "In6.Cu")
	)
	(gr_line
		(start 116.37645 -389.352536)
		(end 116.198142 -389.352536)
		(stroke
			(width 0.07112)
			(type default)
		)
		(layer "In6.Cu")
	)
	(gr_line
		(start 116.400834 -296.27957)
		(end 116.401088 -296.279316)
		(stroke
			(width 0.05715)
			(type default)
		)
		(layer "In6.Cu")
	)
	(gr_line
		(start 116.401088 -296.279316)
		(end 116.401088 -296.278808)
		(stroke
			(width 0.05715)
			(type default)
		)
		(layer "In6.Cu")
	)
	(gr_line
		(start 116.410994 -400.640296)
		(end 116.57076 -400.74723)
		(stroke
			(width 0.07112)
			(type default)
		)
		(layer "In6.Cu")
	)
	(gr_line
		(start 116.425726 -410.030168)
		(end 116.716556 -410.320998)
		(stroke
			(width 0.07112)
			(type default)
		)
		(layer "In6.Cu")
	)
	(gr_line
		(start 116.434616 -400.059652)
		(end 116.327682 -400.219672)
		(stroke
			(width 0.07112)
			(type default)
		)
		(layer "In6.Cu")
	)
	(gr_line
		(start 116.446554 -296.353738)
		(end 116.446554 -296.32529)
		(stroke
			(width 0.05715)
			(type default)
		)
		(layer "In6.Cu")
	)
	(gr_line
		(start 116.446554 -296.32529)
		(end 116.400834 -296.27957)
		(stroke
			(width 0.05715)
			(type default)
		)
		(layer "In6.Cu")
	)
	(gr_line
		(start 116.469414 -68.242434)
		(end 116.478558 -68.24091)
		(stroke
			(width 0.07112)
			(type default)
		)
		(layer "In6.Cu")
	)
	(gr_line
		(start 116.478558 -68.24091)
		(end 116.487702 -68.239894)
		(stroke
			(width 0.07112)
			(type default)
		)
		(layer "In6.Cu")
	)
	(gr_line
		(start 116.488718 -287.37052)
		(end 116.490496 -287.369504)
		(stroke
			(width 0.05715)
			(type default)
		)
		(layer "In6.Cu")
	)
	(gr_line
		(start 116.491258 -389.467344)
		(end 116.37645 -389.352536)
		(stroke
			(width 0.07112)
			(type default)
		)
		(layer "In6.Cu")
	)
	(gr_line
		(start 116.491766 -287.368742)
		(end 116.493544 -287.367726)
		(stroke
			(width 0.05715)
			(type default)
		)
		(layer "In6.Cu")
	)
	(gr_line
		(start 116.494052 -287.367472)
		(end 116.493544 -287.367726)
		(stroke
			(width 0.05715)
			(type default)
		)
		(layer "In6.Cu")
	)
	(gr_line
		(start 116.518436 -68.520564)
		(end 116.518436 -68.52031)
		(stroke
			(width 0.07112)
			(type default)
		)
		(layer "In6.Cu")
	)
	(gr_line
		(start 116.535454 -339.21192)
		(end 116.535454 -339.212174)
		(stroke
			(width 0.07112)
			(type default)
		)
		(layer "In6.Cu")
	)
	(gr_line
		(start 116.57076 -400.74723)
		(end 116.653818 -401.166076)
		(stroke
			(width 0.07112)
			(type default)
		)
		(layer "In6.Cu")
	)
	(gr_line
		(start 116.588286 -287.533588)
		(end 116.588794 -287.533334)
		(stroke
			(width 0.05715)
			(type default)
		)
		(layer "In6.Cu")
	)
	(gr_line
		(start 116.590064 -287.532572)
		(end 116.58981 -287.532318)
		(stroke
			(width 0.05715)
			(type default)
		)
		(layer "In6.Cu")
	)
	(gr_line
		(start 116.630196 -401.74672)
		(end 116.789962 -401.853654)
		(stroke
			(width 0.07112)
			(type default)
		)
		(layer "In6.Cu")
	)
	(gr_line
		(start 116.653818 -401.166076)
		(end 116.546884 -401.326096)
		(stroke
			(width 0.07112)
			(type default)
		)
		(layer "In6.Cu")
	)
	(gr_line
		(start 116.679472 -295.146222)
		(end 116.679218 -295.146222)
		(stroke
			(width 0.05715)
			(type default)
		)
		(layer "In6.Cu")
	)
	(gr_line
		(start 116.716556 -411.183582)
		(end 116.716556 -411.884622)
		(stroke
			(width 0.07112)
			(type default)
		)
		(layer "In6.Cu")
	)
	(gr_line
		(start 116.716556 -406.71369)
		(end 116.425726 -407.00452)
		(stroke
			(width 0.07112)
			(type default)
		)
		(layer "In6.Cu")
	)
	(gr_line
		(start 116.789962 -401.853654)
		(end 116.87302 -402.2725)
		(stroke
			(width 0.07112)
			(type default)
		)
		(layer "In6.Cu")
	)
	(gr_line
		(start 116.866416 -283.84119)
		(end 116.866162 -283.84246)
		(stroke
			(width 0.05715)
			(type default)
		)
		(layer "In6.Cu")
	)
	(gr_line
		(start 116.869972 -283.79674)
		(end 116.869972 -283.79801)
		(stroke
			(width 0.05715)
			(type default)
		)
		(layer "In6.Cu")
	)
	(gr_line
		(start 116.87302 -402.2725)
		(end 116.765832 -402.432266)
		(stroke
			(width 0.07112)
			(type default)
		)
		(layer "In6.Cu")
	)
	(gr_line
		(start 116.959126 -286.56026)
		(end 116.960142 -286.559752)
		(stroke
			(width 0.05715)
			(type default)
		)
		(layer "In6.Cu")
	)
	(gr_line
		(start 116.96192 -283.318712)
		(end 116.962428 -283.318458)
		(stroke
			(width 0.05715)
			(type default)
		)
		(layer "In6.Cu")
	)
	(gr_line
		(start 116.962428 -283.318458)
		(end 116.963698 -283.317696)
		(stroke
			(width 0.05715)
			(type default)
		)
		(layer "In6.Cu")
	)
	(gr_line
		(start 116.97716 -330.863448)
		(end 116.97716 -330.863956)
		(stroke
			(width 0.07112)
			(type default)
		)
		(layer "In6.Cu")
	)
	(gr_line
		(start 116.998496 -406.71369)
		(end 117.289326 -407.00452)
		(stroke
			(width 0.07112)
			(type default)
		)
		(layer "In6.Cu")
	)
	(gr_line
		(start 116.999766 -411.184852)
		(end 117.135656 -411.320742)
		(stroke
			(width 0.07112)
			(type default)
		)
		(layer "In6.Cu")
	)
	(gr_line
		(start 117.054884 -286.725106)
		(end 117.056154 -286.724598)
		(stroke
			(width 0.05715)
			(type default)
		)
		(layer "In6.Cu")
	)
	(gr_line
		(start 117.057678 -283.483812)
		(end 117.058694 -283.483304)
		(stroke
			(width 0.05715)
			(type default)
		)
		(layer "In6.Cu")
	)
	(gr_line
		(start 117.072664 -286.23641)
		(end 116.774722 -286.23641)
		(stroke
			(width 0.05715)
			(type default)
		)
		(layer "In6.Cu")
	)
	(gr_line
		(start 117.072664 -284.616398)
		(end 116.774722 -284.616398)
		(stroke
			(width 0.05715)
			(type default)
		)
		(layer "In6.Cu")
	)
	(gr_line
		(start 117.072664 -282.996386)
		(end 116.774722 -282.996386)
		(stroke
			(width 0.05715)
			(type default)
		)
		(layer "In6.Cu")
	)
	(gr_line
		(start 117.090952 -286.704532)
		(end 117.096286 -286.70123)
		(stroke
			(width 0.05715)
			(type default)
		)
		(layer "In6.Cu")
	)
	(gr_line
		(start 117.096286 -286.70123)
		(end 117.096794 -286.700976)
		(stroke
			(width 0.05715)
			(type default)
		)
		(layer "In6.Cu")
	)
	(gr_arc
		(start 117.096794 -286.700976)
		(mid 117.098575 -286.69971)
		(end 117.10035 -286.698436)
		(stroke
			(width 0.05715)
			(type default)
		)
		(layer "In6.Cu")
	)
	(gr_line
		(start 117.099334 -296.353738)
		(end 117.099334 -296.32529)
		(stroke
			(width 0.05715)
			(type default)
		)
		(layer "In6.Cu")
	)
	(gr_line
		(start 117.099334 -296.32529)
		(end 117.145054 -296.27957)
		(stroke
			(width 0.05715)
			(type default)
		)
		(layer "In6.Cu")
	)
	(gr_arc
		(start 117.101112 -286.697928)
		(mid 117.104422 -286.695654)
		(end 117.107716 -286.693356)
		(stroke
			(width 0.05715)
			(type default)
		)
		(layer "In6.Cu")
	)
	(gr_line
		(start 117.135656 -411.747462)
		(end 116.999766 -411.883352)
		(stroke
			(width 0.07112)
			(type default)
		)
		(layer "In6.Cu")
	)
	(gr_line
		(start 117.135656 -411.320742)
		(end 117.135656 -411.747462)
		(stroke
			(width 0.07112)
			(type default)
		)
		(layer "In6.Cu")
	)
	(gr_line
		(start 117.142006 -286.305752)
		(end 117.072664 -286.23641)
		(stroke
			(width 0.05715)
			(type default)
		)
		(layer "In6.Cu")
	)
	(gr_line
		(start 117.142006 -283.065728)
		(end 117.072664 -282.996386)
		(stroke
			(width 0.05715)
			(type default)
		)
		(layer "In6.Cu")
	)
	(gr_line
		(start 117.155468 -284.699202)
		(end 117.072664 -284.616398)
		(stroke
			(width 0.05715)
			(type default)
		)
		(layer "In6.Cu")
	)
	(gr_arc
		(start 117.155468 -284.699202)
		(mid 117.157255 -284.710652)
		(end 117.159278 -284.722062)
		(stroke
			(width 0.05715)
			(type default)
		)
		(layer "In6.Cu")
	)
	(gr_line
		(start 117.289326 -410.030168)
		(end 116.998496 -410.320998)
		(stroke
			(width 0.07112)
			(type default)
		)
		(layer "In6.Cu")
	)
	(gr_line
		(start 117.291358 -388.774432)
		(end 117.343682 -388.826756)
		(stroke
			(width 0.07112)
			(type default)
		)
		(layer "In6.Cu")
	)
	(gr_arc
		(start 117.33022 -286.342074)
		(mid 117.332243 -286.330664)
		(end 117.33403 -286.319214)
		(stroke
			(width 0.05715)
			(type default)
		)
		(layer "In6.Cu")
	)
	(gr_arc
		(start 117.33022 -283.10205)
		(mid 117.332242 -283.09064)
		(end 117.33403 -283.07919)
		(stroke
			(width 0.05715)
			(type default)
		)
		(layer "In6.Cu")
	)
	(gr_line
		(start 117.33403 -286.319214)
		(end 117.416834 -286.23641)
		(stroke
			(width 0.05715)
			(type default)
		)
		(layer "In6.Cu")
	)
	(gr_line
		(start 117.33403 -283.07919)
		(end 117.416834 -282.996386)
		(stroke
			(width 0.05715)
			(type default)
		)
		(layer "In6.Cu")
	)
	(gr_line
		(start 117.343682 -389.030972)
		(end 117.221508 -389.153146)
		(stroke
			(width 0.07112)
			(type default)
		)
		(layer "In6.Cu")
	)
	(gr_line
		(start 117.343682 -388.826756)
		(end 117.343682 -389.030972)
		(stroke
			(width 0.07112)
			(type default)
		)
		(layer "In6.Cu")
	)
	(gr_line
		(start 117.347492 -284.68574)
		(end 117.416834 -284.616398)
		(stroke
			(width 0.05715)
			(type default)
		)
		(layer "In6.Cu")
	)
	(gr_line
		(start 117.381274 -296.353738)
		(end 117.381274 -296.32529)
		(stroke
			(width 0.05715)
			(type default)
		)
		(layer "In6.Cu")
	)
	(gr_line
		(start 117.381274 -296.32529)
		(end 117.335554 -296.27957)
		(stroke
			(width 0.05715)
			(type default)
		)
		(layer "In6.Cu")
	)
	(gr_line
		(start 117.416834 -286.23641)
		(end 117.714776 -286.23641)
		(stroke
			(width 0.05715)
			(type default)
		)
		(layer "In6.Cu")
	)
	(gr_line
		(start 117.416834 -284.616398)
		(end 117.714776 -284.616398)
		(stroke
			(width 0.05715)
			(type default)
		)
		(layer "In6.Cu")
	)
	(gr_line
		(start 117.416834 -282.996386)
		(end 117.714776 -282.996386)
		(stroke
			(width 0.05715)
			(type default)
		)
		(layer "In6.Cu")
	)
	(gr_line
		(start 117.561868 -339.564472)
		(end 117.561868 -339.564726)
		(stroke
			(width 0.07112)
			(type default)
		)
		(layer "In6.Cu")
	)
	(gr_line
		(start 117.576346 -389.352536)
		(end 117.422676 -389.352536)
		(stroke
			(width 0.07112)
			(type default)
		)
		(layer "In6.Cu")
	)
	(gr_line
		(start 117.683026 -414.965896)
		(end 118.100856 -415.529268)
		(stroke
			(width 0.07112)
			(type default)
		)
		(layer "In6.Cu")
	)
	(gr_line
		(start 117.691154 -389.467344)
		(end 117.576346 -389.352536)
		(stroke
			(width 0.07112)
			(type default)
		)
		(layer "In6.Cu")
	)
	(gr_line
		(start 117.771926 -395.455648)
		(end 117.771926 -396.156688)
		(stroke
			(width 0.07112)
			(type default)
		)
		(layer "In6.Cu")
	)
	(gr_line
		(start 117.771926 -394.327888)
		(end 117.771926 -395.028928)
		(stroke
			(width 0.07112)
			(type default)
		)
		(layer "In6.Cu")
	)
	(gr_line
		(start 117.798596 -399.46834)
		(end 118.098316 -400.102324)
		(stroke
			(width 0.07112)
			(type default)
		)
		(layer "In6.Cu")
	)
	(gr_line
		(start 117.903752 -295.634918)
		(end 117.902482 -295.634156)
		(stroke
			(width 0.05715)
			(type default)
		)
		(layer "In6.Cu")
	)
	(gr_line
		(start 117.907816 -295.637204)
		(end 117.906292 -295.636188)
		(stroke
			(width 0.05715)
			(type default)
		)
		(layer "In6.Cu")
	)
	(gr_line
		(start 117.90934 -295.637966)
		(end 117.907816 -295.637204)
		(stroke
			(width 0.05715)
			(type default)
		)
		(layer "In6.Cu")
	)
	(gr_line
		(start 117.911118 -414.798002)
		(end 118.101364 -414.826196)
		(stroke
			(width 0.07112)
			(type default)
		)
		(layer "In6.Cu")
	)
	(gr_line
		(start 117.997732 -295.468802)
		(end 117.997224 -295.468548)
		(stroke
			(width 0.05715)
			(type default)
		)
		(layer "In6.Cu")
	)
	(gr_line
		(start 117.998748 -295.46931)
		(end 117.997732 -295.468802)
		(stroke
			(width 0.05715)
			(type default)
		)
		(layer "In6.Cu")
	)
	(gr_line
		(start 118.000526 -295.470326)
		(end 117.998748 -295.46931)
		(stroke
			(width 0.05715)
			(type default)
		)
		(layer "In6.Cu")
	)
	(gr_line
		(start 118.002812 -295.47185)
		(end 118.00205 -295.471342)
		(stroke
			(width 0.05715)
			(type default)
		)
		(layer "In6.Cu")
	)
	(gr_line
		(start 118.029228 -295.48709)
		(end 118.028466 -295.486582)
		(stroke
			(width 0.05715)
			(type default)
		)
		(layer "In6.Cu")
	)
	(gr_line
		(start 118.02999 -295.487598)
		(end 118.029228 -295.48709)
		(stroke
			(width 0.05715)
			(type default)
		)
		(layer "In6.Cu")
	)
	(gr_line
		(start 118.036848 -295.491662)
		(end 118.02999 -295.487598)
		(stroke
			(width 0.05715)
			(type default)
		)
		(layer "In6.Cu")
	)
	(gr_line
		(start 118.04396 -296.353738)
		(end 118.04396 -296.32529)
		(stroke
			(width 0.05715)
			(type default)
		)
		(layer "In6.Cu")
	)
	(gr_line
		(start 118.04396 -296.32529)
		(end 118.08968 -296.27957)
		(stroke
			(width 0.05715)
			(type default)
		)
		(layer "In6.Cu")
	)
	(gr_arc
		(start 118.044722 -295.49725)
		(mid 118.040797 -295.494439)
		(end 118.036848 -295.491662)
		(stroke
			(width 0.05715)
			(type default)
		)
		(layer "In6.Cu")
	)
	(gr_line
		(start 118.055136 -399.348198)
		(end 118.236492 -399.412968)
		(stroke
			(width 0.07112)
			(type default)
		)
		(layer "In6.Cu")
	)
	(gr_line
		(start 118.055136 -395.456918)
		(end 118.191026 -395.592808)
		(stroke
			(width 0.07112)
			(type default)
		)
		(layer "In6.Cu")
	)
	(gr_line
		(start 118.055136 -394.329158)
		(end 118.191026 -394.465048)
		(stroke
			(width 0.07112)
			(type default)
		)
		(layer "In6.Cu")
	)
	(gr_line
		(start 118.101364 -414.826196)
		(end 118.355872 -415.169096)
		(stroke
			(width 0.07112)
			(type default)
		)
		(layer "In6.Cu")
	)
	(gr_line
		(start 118.191026 -396.019528)
		(end 118.055136 -396.155418)
		(stroke
			(width 0.07112)
			(type default)
		)
		(layer "In6.Cu")
	)
	(gr_line
		(start 118.191026 -395.592808)
		(end 118.191026 -396.019528)
		(stroke
			(width 0.07112)
			(type default)
		)
		(layer "In6.Cu")
	)
	(gr_line
		(start 118.191026 -394.891768)
		(end 118.055136 -395.027658)
		(stroke
			(width 0.07112)
			(type default)
		)
		(layer "In6.Cu")
	)
	(gr_line
		(start 118.191026 -394.465048)
		(end 118.191026 -394.891768)
		(stroke
			(width 0.07112)
			(type default)
		)
		(layer "In6.Cu")
	)
	(gr_line
		(start 118.236492 -399.412968)
		(end 118.418864 -399.799048)
		(stroke
			(width 0.07112)
			(type default)
		)
		(layer "In6.Cu")
	)
	(gr_line
		(start 118.3259 -296.353738)
		(end 118.3259 -296.32529)
		(stroke
			(width 0.05715)
			(type default)
		)
		(layer "In6.Cu")
	)
	(gr_line
		(start 118.3259 -296.32529)
		(end 118.28018 -296.27957)
		(stroke
			(width 0.05715)
			(type default)
		)
		(layer "In6.Cu")
	)
	(gr_line
		(start 118.341902 -400.617182)
		(end 118.641622 -401.251166)
		(stroke
			(width 0.07112)
			(type default)
		)
		(layer "In6.Cu")
	)
	(gr_line
		(start 118.349014 -322.613782)
		(end 118.349268 -322.61429)
		(stroke
			(width 0.07112)
			(type default)
		)
		(layer "In6.Cu")
	)
	(gr_line
		(start 118.355872 -415.169096)
		(end 118.327678 -415.359596)
		(stroke
			(width 0.07112)
			(type default)
		)
		(layer "In6.Cu")
	)
	(gr_line
		(start 118.418864 -399.799048)
		(end 118.354094 -399.980404)
		(stroke
			(width 0.07112)
			(type default)
		)
		(layer "In6.Cu")
	)
	(gr_line
		(start 118.491254 -388.774432)
		(end 118.543578 -388.826756)
		(stroke
			(width 0.07112)
			(type default)
		)
		(layer "In6.Cu")
	)
	(gr_line
		(start 118.535196 -339.514688)
		(end 118.535196 -339.514434)
		(stroke
			(width 0.07112)
			(type default)
		)
		(layer "In6.Cu")
	)
	(gr_line
		(start 118.543578 -389.006588)
		(end 118.39702 -389.153146)
		(stroke
			(width 0.07112)
			(type default)
		)
		(layer "In6.Cu")
	)
	(gr_line
		(start 118.543578 -388.826756)
		(end 118.543578 -389.006588)
		(stroke
			(width 0.07112)
			(type default)
		)
		(layer "In6.Cu")
	)
	(gr_line
		(start 118.598442 -400.49704)
		(end 118.779798 -400.56181)
		(stroke
			(width 0.07112)
			(type default)
		)
		(layer "In6.Cu")
	)
	(gr_line
		(start 118.641876 -416.258502)
		(end 119.059706 -416.821874)
		(stroke
			(width 0.07112)
			(type default)
		)
		(layer "In6.Cu")
	)
	(gr_line
		(start 118.776496 -389.352536)
		(end 118.598188 -389.352536)
		(stroke
			(width 0.07112)
			(type default)
		)
		(layer "In6.Cu")
	)
	(gr_line
		(start 118.779798 -400.56181)
		(end 118.962424 -400.94789)
		(stroke
			(width 0.07112)
			(type default)
		)
		(layer "In6.Cu")
	)
	(gr_line
		(start 118.835678 -401.661122)
		(end 119.135652 -402.29536)
		(stroke
			(width 0.07112)
			(type default)
		)
		(layer "In6.Cu")
	)
	(gr_line
		(start 118.84279 -285.912052)
		(end 118.842282 -285.911798)
		(stroke
			(width 0.05715)
			(type default)
		)
		(layer "In6.Cu")
	)
	(gr_line
		(start 118.843806 -295.634918)
		(end 118.842536 -295.634156)
		(stroke
			(width 0.05715)
			(type default)
		)
		(layer "In6.Cu")
	)
	(gr_line
		(start 118.84787 -295.637204)
		(end 118.846346 -295.636188)
		(stroke
			(width 0.05715)
			(type default)
		)
		(layer "In6.Cu")
	)
	(gr_line
		(start 118.849394 -295.637966)
		(end 118.84787 -295.637204)
		(stroke
			(width 0.05715)
			(type default)
		)
		(layer "In6.Cu")
	)
	(gr_line
		(start 118.854982 -284.931612)
		(end 118.854982 -284.931358)
		(stroke
			(width 0.05715)
			(type default)
		)
		(layer "In6.Cu")
	)
	(gr_line
		(start 118.854982 -284.931358)
		(end 118.860062 -284.92831)
		(stroke
			(width 0.05715)
			(type default)
		)
		(layer "In6.Cu")
	)
	(gr_line
		(start 118.860062 -284.92831)
		(end 118.860316 -284.92831)
		(stroke
			(width 0.05715)
			(type default)
		)
		(layer "In6.Cu")
	)
	(gr_line
		(start 118.869968 -416.090608)
		(end 119.060214 -416.118802)
		(stroke
			(width 0.07112)
			(type default)
		)
		(layer "In6.Cu")
	)
	(gr_line
		(start 118.891304 -389.467344)
		(end 118.776496 -389.352536)
		(stroke
			(width 0.07112)
			(type default)
		)
		(layer "In6.Cu")
	)
	(gr_arc
		(start 118.9355 -285.105856)
		(mid 118.936008 -285.105602)
		(end 118.936516 -285.105348)
		(stroke
			(width 0.05715)
			(type default)
		)
		(layer "In6.Cu")
	)
	(gr_line
		(start 118.936516 -285.105348)
		(end 118.937786 -285.104586)
		(stroke
			(width 0.05715)
			(type default)
		)
		(layer "In6.Cu")
	)
	(gr_line
		(start 118.937786 -295.468802)
		(end 118.937278 -295.468548)
		(stroke
			(width 0.05715)
			(type default)
		)
		(layer "In6.Cu")
	)
	(gr_line
		(start 118.937786 -285.104586)
		(end 118.940326 -285.103062)
		(stroke
			(width 0.05715)
			(type default)
		)
		(layer "In6.Cu")
	)
	(gr_line
		(start 118.938802 -295.46931)
		(end 118.937786 -295.468802)
		(stroke
			(width 0.05715)
			(type default)
		)
		(layer "In6.Cu")
	)
	(gr_line
		(start 118.94058 -295.470326)
		(end 118.938802 -295.46931)
		(stroke
			(width 0.05715)
			(type default)
		)
		(layer "In6.Cu")
	)
	(gr_line
		(start 118.942866 -295.47185)
		(end 118.942104 -295.471342)
		(stroke
			(width 0.05715)
			(type default)
		)
		(layer "In6.Cu")
	)
	(gr_arc
		(start 118.944644 -285.750762)
		(mid 118.942614 -285.749488)
		(end 118.94058 -285.748222)
		(stroke
			(width 0.05715)
			(type default)
		)
		(layer "In6.Cu")
	)
	(gr_line
		(start 118.962424 -400.94789)
		(end 118.8974 -401.129246)
		(stroke
			(width 0.07112)
			(type default)
		)
		(layer "In6.Cu")
	)
	(gr_line
		(start 118.969282 -295.48709)
		(end 118.96852 -295.486582)
		(stroke
			(width 0.05715)
			(type default)
		)
		(layer "In6.Cu")
	)
	(gr_line
		(start 118.970044 -295.487598)
		(end 118.969282 -295.48709)
		(stroke
			(width 0.05715)
			(type default)
		)
		(layer "In6.Cu")
	)
	(gr_line
		(start 118.971822 -395.429232)
		(end 118.971822 -396.130272)
		(stroke
			(width 0.07112)
			(type default)
		)
		(layer "In6.Cu")
	)
	(gr_line
		(start 118.971822 -394.301472)
		(end 118.971822 -395.002512)
		(stroke
			(width 0.07112)
			(type default)
		)
		(layer "In6.Cu")
	)
	(gr_line
		(start 118.976902 -295.491662)
		(end 118.970044 -295.487598)
		(stroke
			(width 0.05715)
			(type default)
		)
		(layer "In6.Cu")
	)
	(gr_line
		(start 118.98376 -296.353738)
		(end 118.98376 -296.32529)
		(stroke
			(width 0.05715)
			(type default)
		)
		(layer "In6.Cu")
	)
	(gr_line
		(start 118.98376 -296.32529)
		(end 119.02948 -296.27957)
		(stroke
			(width 0.05715)
			(type default)
		)
		(layer "In6.Cu")
	)
	(gr_arc
		(start 118.984776 -295.49725)
		(mid 118.980851 -295.494439)
		(end 118.976902 -295.491662)
		(stroke
			(width 0.05715)
			(type default)
		)
		(layer "In6.Cu")
	)
	(gr_line
		(start 119.02948 -296.007282)
		(end 119.029734 -296.007028)
		(stroke
			(width 0.05715)
			(type default)
		)
		(layer "In6.Cu")
	)
	(gr_arc
		(start 119.02948 -287.856422)
		(mid 119.02948 -287.855533)
		(end 119.02948 -287.854644)
		(stroke
			(width 0.05715)
			(type default)
		)
		(layer "In6.Cu")
	)
	(gr_line
		(start 119.029734 -295.955974)
		(end 119.02948 -295.956228)
		(stroke
			(width 0.05715)
			(type default)
		)
		(layer "In6.Cu")
	)
	(gr_line
		(start 119.060214 -416.118802)
		(end 119.314722 -416.461956)
		(stroke
			(width 0.07112)
			(type default)
		)
		(layer "In6.Cu")
	)
	(gr_line
		(start 119.092218 -401.541234)
		(end 119.273574 -401.606004)
		(stroke
			(width 0.07112)
			(type default)
		)
		(layer "In6.Cu")
	)
	(gr_line
		(start 119.21998 -296.086276)
		(end 119.220234 -296.086022)
		(stroke
			(width 0.05715)
			(type default)
		)
		(layer "In6.Cu")
	)
	(gr_line
		(start 119.255032 -395.430502)
		(end 119.390922 -395.566392)
		(stroke
			(width 0.07112)
			(type default)
		)
		(layer "In6.Cu")
	)
	(gr_line
		(start 119.255032 -394.302742)
		(end 119.390922 -394.438632)
		(stroke
			(width 0.07112)
			(type default)
		)
		(layer "In6.Cu")
	)
	(gr_line
		(start 119.2657 -296.353738)
		(end 119.2657 -296.32529)
		(stroke
			(width 0.05715)
			(type default)
		)
		(layer "In6.Cu")
	)
	(gr_line
		(start 119.2657 -296.32529)
		(end 119.21998 -296.27957)
		(stroke
			(width 0.05715)
			(type default)
		)
		(layer "In6.Cu")
	)
	(gr_arc
		(start 119.272558 -289.011614)
		(mid 119.269375 -289.013889)
		(end 119.266208 -289.016186)
		(stroke
			(width 0.05715)
			(type default)
		)
		(layer "In6.Cu")
	)
	(gr_line
		(start 119.273574 -401.606004)
		(end 119.4562 -401.992084)
		(stroke
			(width 0.07112)
			(type default)
		)
		(layer "In6.Cu")
	)
	(gr_line
		(start 119.277892 -289.008058)
		(end 119.279162 -289.007296)
		(stroke
			(width 0.05715)
			(type default)
		)
		(layer "In6.Cu")
	)
	(gr_arc
		(start 119.278146 -287.3883)
		(mid 119.270484 -287.393445)
		(end 119.262906 -287.398714)
		(stroke
			(width 0.05715)
			(type default)
		)
		(layer "In6.Cu")
	)
	(gr_line
		(start 119.278146 -287.3883)
		(end 119.279416 -287.387538)
		(stroke
			(width 0.05715)
			(type default)
		)
		(layer "In6.Cu")
	)
	(gr_line
		(start 119.279416 -287.387538)
		(end 119.280178 -287.38703)
		(stroke
			(width 0.05715)
			(type default)
		)
		(layer "In6.Cu")
	)
	(gr_line
		(start 119.281956 -289.005772)
		(end 119.282718 -289.005264)
		(stroke
			(width 0.05715)
			(type default)
		)
		(layer "In6.Cu")
	)
	(gr_line
		(start 119.282718 -289.005264)
		(end 119.283988 -289.004502)
		(stroke
			(width 0.05715)
			(type default)
		)
		(layer "In6.Cu")
	)
	(gr_line
		(start 119.283988 -289.004502)
		(end 119.285512 -289.00374)
		(stroke
			(width 0.05715)
			(type default)
		)
		(layer "In6.Cu")
	)
	(gr_line
		(start 119.287036 -289.002724)
		(end 119.287544 -289.00247)
		(stroke
			(width 0.05715)
			(type default)
		)
		(layer "In6.Cu")
	)
	(gr_line
		(start 119.287544 -289.00247)
		(end 119.290084 -289.0012)
		(stroke
			(width 0.05715)
			(type default)
		)
		(layer "In6.Cu")
	)
	(gr_line
		(start 119.290084 -289.0012)
		(end 119.290846 -289.000692)
		(stroke
			(width 0.05715)
			(type default)
		)
		(layer "In6.Cu")
	)
	(gr_line
		(start 119.290846 -289.000692)
		(end 119.291862 -289.000184)
		(stroke
			(width 0.05715)
			(type default)
		)
		(layer "In6.Cu")
	)
	(gr_line
		(start 119.306594 -287.371536)
		(end 119.307356 -287.371028)
		(stroke
			(width 0.05715)
			(type default)
		)
		(layer "In6.Cu")
	)
	(gr_line
		(start 119.308626 -287.370266)
		(end 119.310404 -287.369504)
		(stroke
			(width 0.05715)
			(type default)
		)
		(layer "In6.Cu")
	)
	(gr_line
		(start 119.311674 -287.368742)
		(end 119.312436 -287.368234)
		(stroke
			(width 0.05715)
			(type default)
		)
		(layer "In6.Cu")
	)
	(gr_line
		(start 119.311928 -284.128718)
		(end 119.312436 -284.128464)
		(stroke
			(width 0.05715)
			(type default)
		)
		(layer "In6.Cu")
	)
	(gr_line
		(start 119.312436 -284.128464)
		(end 119.313706 -284.127702)
		(stroke
			(width 0.05715)
			(type default)
		)
		(layer "In6.Cu")
	)
	(gr_line
		(start 119.313706 -284.127702)
		(end 119.315738 -284.126686)
		(stroke
			(width 0.05715)
			(type default)
		)
		(layer "In6.Cu")
	)
	(gr_line
		(start 119.314722 -416.461956)
		(end 119.286528 -416.652202)
		(stroke
			(width 0.07112)
			(type default)
		)
		(layer "In6.Cu")
	)
	(gr_line
		(start 119.315738 -284.126686)
		(end 119.315992 -284.126432)
		(stroke
			(width 0.05715)
			(type default)
		)
		(layer "In6.Cu")
	)
	(gr_line
		(start 119.38254 -289.168332)
		(end 119.384064 -289.167316)
		(stroke
			(width 0.05715)
			(type default)
		)
		(layer "In6.Cu")
	)
	(gr_line
		(start 119.384064 -289.167316)
		(end 119.384572 -289.167062)
		(stroke
			(width 0.05715)
			(type default)
		)
		(layer "In6.Cu")
	)
	(gr_line
		(start 119.390922 -395.993112)
		(end 119.255032 -396.129002)
		(stroke
			(width 0.07112)
			(type default)
		)
		(layer "In6.Cu")
	)
	(gr_line
		(start 119.390922 -395.566392)
		(end 119.390922 -395.993112)
		(stroke
			(width 0.07112)
			(type default)
		)
		(layer "In6.Cu")
	)
	(gr_line
		(start 119.390922 -394.865352)
		(end 119.255032 -395.001242)
		(stroke
			(width 0.07112)
			(type default)
		)
		(layer "In6.Cu")
	)
	(gr_line
		(start 119.390922 -394.438632)
		(end 119.390922 -394.865352)
		(stroke
			(width 0.07112)
			(type default)
		)
		(layer "In6.Cu")
	)
	(gr_line
		(start 119.401336 -284.297628)
		(end 119.40159 -284.297374)
		(stroke
			(width 0.05715)
			(type default)
		)
		(layer "In6.Cu")
	)
	(gr_line
		(start 119.406416 -287.534604)
		(end 119.406924 -287.53435)
		(stroke
			(width 0.05715)
			(type default)
		)
		(layer "In6.Cu")
	)
	(gr_line
		(start 119.406924 -287.53435)
		(end 119.407686 -287.533842)
		(stroke
			(width 0.05715)
			(type default)
		)
		(layer "In6.Cu")
	)
	(gr_line
		(start 119.407686 -287.533842)
		(end 119.408702 -287.533334)
		(stroke
			(width 0.05715)
			(type default)
		)
		(layer "In6.Cu")
	)
	(gr_line
		(start 119.408702 -287.533334)
		(end 119.409972 -287.532572)
		(stroke
			(width 0.05715)
			(type default)
		)
		(layer "In6.Cu")
	)
	(gr_line
		(start 119.409972 -287.532572)
		(end 119.410734 -287.532064)
		(stroke
			(width 0.05715)
			(type default)
		)
		(layer "In6.Cu")
	)
	(gr_line
		(start 119.410734 -287.532064)
		(end 119.412004 -287.531302)
		(stroke
			(width 0.05715)
			(type default)
		)
		(layer "In6.Cu")
	)
	(gr_line
		(start 119.412004 -287.531302)
		(end 119.412766 -287.530794)
		(stroke
			(width 0.05715)
			(type default)
		)
		(layer "In6.Cu")
	)
	(gr_line
		(start 119.412004 -284.291278)
		(end 119.412512 -284.291024)
		(stroke
			(width 0.05715)
			(type default)
		)
		(layer "In6.Cu")
	)
	(gr_line
		(start 119.4562 -401.992084)
		(end 119.391176 -402.173186)
		(stroke
			(width 0.07112)
			(type default)
		)
		(layer "In6.Cu")
	)
	(gr_arc
		(start 119.45747 -288.209228)
		(mid 119.454304 -288.20693)
		(end 119.45112 -288.204656)
		(stroke
			(width 0.05715)
			(type default)
		)
		(layer "In6.Cu")
	)
	(gr_line
		(start 119.488966 -410.030168)
		(end 119.779796 -410.320998)
		(stroke
			(width 0.07112)
			(type default)
		)
		(layer "In6.Cu")
	)
	(gr_line
		(start 119.489474 -417.401248)
		(end 119.907558 -417.964874)
		(stroke
			(width 0.07112)
			(type default)
		)
		(layer "In6.Cu")
	)
	(gr_line
		(start 119.49938 -295.146222)
		(end 119.499126 -295.146222)
		(stroke
			(width 0.05715)
			(type default)
		)
		(layer "In6.Cu")
	)
	(gr_line
		(start 119.690134 -295.146222)
		(end 119.68988 -295.146222)
		(stroke
			(width 0.05715)
			(type default)
		)
		(layer "In6.Cu")
	)
	(gr_line
		(start 119.69115 -388.774432)
		(end 119.743474 -388.826756)
		(stroke
			(width 0.07112)
			(type default)
		)
		(layer "In6.Cu")
	)
	(gr_line
		(start 119.71782 -417.233608)
		(end 119.908066 -417.261802)
		(stroke
			(width 0.07112)
			(type default)
		)
		(layer "In6.Cu")
	)
	(gr_line
		(start 119.743474 -389.006588)
		(end 119.596916 -389.153146)
		(stroke
			(width 0.07112)
			(type default)
		)
		(layer "In6.Cu")
	)
	(gr_line
		(start 119.743474 -388.826756)
		(end 119.743474 -389.006588)
		(stroke
			(width 0.07112)
			(type default)
		)
		(layer "In6.Cu")
	)
	(gr_line
		(start 119.779796 -406.71369)
		(end 119.488966 -407.00452)
		(stroke
			(width 0.07112)
			(type default)
		)
		(layer "In6.Cu")
	)
	(gr_line
		(start 119.783098 -295.63441)
		(end 119.781828 -295.633648)
		(stroke
			(width 0.05715)
			(type default)
		)
		(layer "In6.Cu")
	)
	(gr_line
		(start 119.892572 -286.23641)
		(end 119.59463 -286.23641)
		(stroke
			(width 0.05715)
			(type default)
		)
		(layer "In6.Cu")
	)
	(gr_line
		(start 119.892572 -284.616398)
		(end 119.59463 -284.616398)
		(stroke
			(width 0.05715)
			(type default)
		)
		(layer "In6.Cu")
	)
	(gr_line
		(start 119.892572 -282.996386)
		(end 119.59463 -282.996386)
		(stroke
			(width 0.05715)
			(type default)
		)
		(layer "In6.Cu")
	)
	(gr_line
		(start 119.907558 -417.964874)
		(end 119.907812 -417.96462)
		(stroke
			(width 0.07112)
			(type default)
		)
		(layer "In6.Cu")
	)
	(gr_line
		(start 119.908066 -417.261802)
		(end 120.162574 -417.604702)
		(stroke
			(width 0.07112)
			(type default)
		)
		(layer "In6.Cu")
	)
	(gr_line
		(start 119.934228 -296.353738)
		(end 119.934228 -296.32529)
		(stroke
			(width 0.05715)
			(type default)
		)
		(layer "In6.Cu")
	)
	(gr_line
		(start 119.934228 -296.32529)
		(end 119.979948 -296.27957)
		(stroke
			(width 0.05715)
			(type default)
		)
		(layer "In6.Cu")
	)
	(gr_line
		(start 119.961914 -286.305752)
		(end 119.892572 -286.23641)
		(stroke
			(width 0.05715)
			(type default)
		)
		(layer "In6.Cu")
	)
	(gr_line
		(start 119.961914 -283.065728)
		(end 119.892572 -282.996386)
		(stroke
			(width 0.05715)
			(type default)
		)
		(layer "In6.Cu")
	)
	(gr_line
		(start 119.975376 -284.699202)
		(end 119.892572 -284.616398)
		(stroke
			(width 0.05715)
			(type default)
		)
		(layer "In6.Cu")
	)
	(gr_arc
		(start 119.975376 -284.699202)
		(mid 119.977169 -284.710524)
		(end 119.979186 -284.721808)
		(stroke
			(width 0.05715)
			(type default)
		)
		(layer "In6.Cu")
	)
	(gr_line
		(start 119.976392 -389.352536)
		(end 119.798084 -389.352536)
		(stroke
			(width 0.07112)
			(type default)
		)
		(layer "In6.Cu")
	)
	(gr_line
		(start 119.97944 -296.007536)
		(end 119.97944 -296.007028)
		(stroke
			(width 0.05715)
			(type default)
		)
		(layer "In6.Cu")
	)
	(gr_line
		(start 120.059196 -352.435668)
		(end 120.05945 -352.435668)
		(stroke
			(width 0.07112)
			(type default)
		)
		(layer "In6.Cu")
	)
	(gr_line
		(start 120.061736 -406.71369)
		(end 120.352566 -407.00452)
		(stroke
			(width 0.07112)
			(type default)
		)
		(layer "In6.Cu")
	)
	(gr_line
		(start 120.0912 -389.467344)
		(end 119.976392 -389.352536)
		(stroke
			(width 0.07112)
			(type default)
		)
		(layer "In6.Cu")
	)
	(gr_arc
		(start 120.150128 -286.342074)
		(mid 120.152151 -286.330664)
		(end 120.153938 -286.319214)
		(stroke
			(width 0.05715)
			(type default)
		)
		(layer "In6.Cu")
	)
	(gr_arc
		(start 120.150128 -283.10205)
		(mid 120.15215 -283.09064)
		(end 120.153938 -283.07919)
		(stroke
			(width 0.05715)
			(type default)
		)
		(layer "In6.Cu")
	)
	(gr_line
		(start 120.153938 -286.319214)
		(end 120.236742 -286.23641)
		(stroke
			(width 0.05715)
			(type default)
		)
		(layer "In6.Cu")
	)
	(gr_line
		(start 120.153938 -283.07919)
		(end 120.236742 -282.996386)
		(stroke
			(width 0.05715)
			(type default)
		)
		(layer "In6.Cu")
	)
	(gr_line
		(start 120.162574 -417.604702)
		(end 120.13438 -417.795202)
		(stroke
			(width 0.07112)
			(type default)
		)
		(layer "In6.Cu")
	)
	(gr_line
		(start 120.1674 -284.68574)
		(end 120.236742 -284.616398)
		(stroke
			(width 0.05715)
			(type default)
		)
		(layer "In6.Cu")
	)
	(gr_line
		(start 120.170448 -296.08653)
		(end 120.170448 -296.086022)
		(stroke
			(width 0.05715)
			(type default)
		)
		(layer "In6.Cu")
	)
	(gr_line
		(start 120.171718 -394.539978)
		(end 120.171718 -395.241018)
		(stroke
			(width 0.07112)
			(type default)
		)
		(layer "In6.Cu")
	)
	(gr_line
		(start 120.216168 -296.353738)
		(end 120.216168 -296.32529)
		(stroke
			(width 0.05715)
			(type default)
		)
		(layer "In6.Cu")
	)
	(gr_line
		(start 120.216168 -296.32529)
		(end 120.170448 -296.27957)
		(stroke
			(width 0.05715)
			(type default)
		)
		(layer "In6.Cu")
	)
	(gr_line
		(start 120.236742 -286.23641)
		(end 120.534684 -286.23641)
		(stroke
			(width 0.05715)
			(type default)
		)
		(layer "In6.Cu")
	)
	(gr_line
		(start 120.236742 -284.616398)
		(end 120.534684 -284.616398)
		(stroke
			(width 0.05715)
			(type default)
		)
		(layer "In6.Cu")
	)
	(gr_line
		(start 120.236742 -282.996386)
		(end 120.534684 -282.996386)
		(stroke
			(width 0.05715)
			(type default)
		)
		(layer "In6.Cu")
	)
	(gr_line
		(start 120.244362 -285.099506)
		(end 120.243092 -285.098744)
		(stroke
			(width 0.05715)
			(type default)
		)
		(layer "In6.Cu")
	)
	(gr_line
		(start 120.246902 -285.10103)
		(end 120.24614 -285.100522)
		(stroke
			(width 0.05715)
			(type default)
		)
		(layer "In6.Cu")
	)
	(gr_line
		(start 120.24868 -287.37052)
		(end 120.250458 -287.369504)
		(stroke
			(width 0.05715)
			(type default)
		)
		(layer "In6.Cu")
	)
	(gr_line
		(start 120.249188 -285.1023)
		(end 120.248172 -285.101792)
		(stroke
			(width 0.05715)
			(type default)
		)
		(layer "In6.Cu")
	)
	(gr_line
		(start 120.250712 -285.103316)
		(end 120.249188 -285.1023)
		(stroke
			(width 0.05715)
			(type default)
		)
		(layer "In6.Cu")
	)
	(gr_line
		(start 120.251728 -287.368742)
		(end 120.25249 -287.368234)
		(stroke
			(width 0.05715)
			(type default)
		)
		(layer "In6.Cu")
	)
	(gr_line
		(start 120.251728 -285.103824)
		(end 120.250712 -285.103316)
		(stroke
			(width 0.05715)
			(type default)
		)
		(layer "In6.Cu")
	)
	(gr_line
		(start 120.25376 -287.367472)
		(end 120.257062 -287.365694)
		(stroke
			(width 0.05715)
			(type default)
		)
		(layer "In6.Cu")
	)
	(gr_line
		(start 120.25884 -285.107888)
		(end 120.258078 -285.10738)
		(stroke
			(width 0.05715)
			(type default)
		)
		(layer "In6.Cu")
	)
	(gr_line
		(start 120.259348 -285.108142)
		(end 120.25884 -285.107888)
		(stroke
			(width 0.05715)
			(type default)
		)
		(layer "In6.Cu")
	)
	(gr_line
		(start 120.346978 -284.93847)
		(end 120.344184 -284.936946)
		(stroke
			(width 0.05715)
			(type default)
		)
		(layer "In6.Cu")
	)
	(gr_line
		(start 120.34774 -284.938978)
		(end 120.346978 -284.93847)
		(stroke
			(width 0.05715)
			(type default)
		)
		(layer "In6.Cu")
	)
	(gr_line
		(start 120.348756 -284.939486)
		(end 120.34774 -284.938978)
		(stroke
			(width 0.05715)
			(type default)
		)
		(layer "In6.Cu")
	)
	(gr_line
		(start 120.350534 -284.940502)
		(end 120.348756 -284.939486)
		(stroke
			(width 0.05715)
			(type default)
		)
		(layer "In6.Cu")
	)
	(gr_line
		(start 120.352058 -287.531302)
		(end 120.35282 -287.530794)
		(stroke
			(width 0.05715)
			(type default)
		)
		(layer "In6.Cu")
	)
	(gr_line
		(start 120.352566 -410.030168)
		(end 120.061736 -410.320998)
		(stroke
			(width 0.07112)
			(type default)
		)
		(layer "In6.Cu")
	)
	(gr_line
		(start 120.353074 -284.942026)
		(end 120.352058 -284.941518)
		(stroke
			(width 0.05715)
			(type default)
		)
		(layer "In6.Cu")
	)
	(gr_line
		(start 120.35409 -284.942788)
		(end 120.353074 -284.942026)
		(stroke
			(width 0.05715)
			(type default)
		)
		(layer "In6.Cu")
	)
	(gr_line
		(start 120.363234 -304.154078)
		(end 120.36298 -304.154078)
		(stroke
			(width 0.07112)
			(type default)
		)
		(layer "In6.Cu")
	)
	(gr_line
		(start 120.379236 -284.957266)
		(end 120.378728 -284.957012)
		(stroke
			(width 0.05715)
			(type default)
		)
		(layer "In6.Cu")
	)
	(gr_line
		(start 120.379998 -284.957774)
		(end 120.379236 -284.957266)
		(stroke
			(width 0.05715)
			(type default)
		)
		(layer "In6.Cu")
	)
	(gr_line
		(start 120.386856 -284.961838)
		(end 120.379998 -284.957774)
		(stroke
			(width 0.05715)
			(type default)
		)
		(layer "In6.Cu")
	)
	(gr_arc
		(start 120.39473 -284.967426)
		(mid 120.390805 -284.964615)
		(end 120.386856 -284.961838)
		(stroke
			(width 0.05715)
			(type default)
		)
		(layer "In6.Cu")
	)
	(gr_line
		(start 120.439434 -295.146222)
		(end 120.43918 -295.146222)
		(stroke
			(width 0.05715)
			(type default)
		)
		(layer "In6.Cu")
	)
	(gr_line
		(start 120.454928 -394.541248)
		(end 120.590818 -394.677138)
		(stroke
			(width 0.07112)
			(type default)
		)
		(layer "In6.Cu")
	)
	(gr_line
		(start 120.533414 -350.064832)
		(end 120.533414 -350.065086)
		(stroke
			(width 0.07112)
			(type default)
		)
		(layer "In6.Cu")
	)
	(gr_line
		(start 120.590818 -395.103858)
		(end 120.454928 -395.239748)
		(stroke
			(width 0.07112)
			(type default)
		)
		(layer "In6.Cu")
	)
	(gr_line
		(start 120.590818 -394.677138)
		(end 120.590818 -395.103858)
		(stroke
			(width 0.07112)
			(type default)
		)
		(layer "In6.Cu")
	)
	(gr_line
		(start 120.613932 -414.393126)
		(end 120.678956 -414.490408)
		(stroke
			(width 0.07112)
			(type default)
		)
		(layer "In6.Cu")
	)
	(gr_line
		(start 120.630188 -295.146222)
		(end 120.629934 -295.146222)
		(stroke
			(width 0.05715)
			(type default)
		)
		(layer "In6.Cu")
	)
	(gr_line
		(start 120.678956 -414.490408)
		(end 120.679464 -414.490662)
		(stroke
			(width 0.07112)
			(type default)
		)
		(layer "In6.Cu")
	)
	(gr_line
		(start 120.679464 -414.490662)
		(end 121.004076 -414.97631)
		(stroke
			(width 0.07112)
			(type default)
		)
		(layer "In6.Cu")
	)
	(gr_line
		(start 120.794018 -350.172528)
		(end 120.794018 -350.172782)
		(stroke
			(width 0.07112)
			(type default)
		)
		(layer "In6.Cu")
	)
	(gr_line
		(start 120.84812 -286.70631)
		(end 120.848882 -286.705802)
		(stroke
			(width 0.05715)
			(type default)
		)
		(layer "In6.Cu")
	)
	(gr_line
		(start 120.848882 -286.705802)
		(end 120.854724 -286.7025)
		(stroke
			(width 0.05715)
			(type default)
		)
		(layer "In6.Cu")
	)
	(gr_line
		(start 120.850152 -414.236662)
		(end 121.038874 -414.274254)
		(stroke
			(width 0.07112)
			(type default)
		)
		(layer "In6.Cu")
	)
	(gr_line
		(start 120.854724 -286.7025)
		(end 120.856756 -286.700976)
		(stroke
			(width 0.05715)
			(type default)
		)
		(layer "In6.Cu")
	)
	(gr_arc
		(start 120.856756 -286.700976)
		(mid 120.858027 -286.700089)
		(end 120.859296 -286.699198)
		(stroke
			(width 0.05715)
			(type default)
		)
		(layer "In6.Cu")
	)
	(gr_arc
		(start 120.860058 -286.69869)
		(mid 120.863113 -286.696541)
		(end 120.866154 -286.694372)
		(stroke
			(width 0.05715)
			(type default)
		)
		(layer "In6.Cu")
	)
	(gr_line
		(start 120.866408 -296.353738)
		(end 120.866408 -296.32529)
		(stroke
			(width 0.05715)
			(type default)
		)
		(layer "In6.Cu")
	)
	(gr_line
		(start 120.866408 -296.32529)
		(end 120.912128 -296.27957)
		(stroke
			(width 0.05715)
			(type default)
		)
		(layer "In6.Cu")
	)
	(gr_line
		(start 120.8913 -388.774432)
		(end 120.943624 -388.826756)
		(stroke
			(width 0.07112)
			(type default)
		)
		(layer "In6.Cu")
	)
	(gr_line
		(start 120.943624 -389.006588)
		(end 120.797066 -389.153146)
		(stroke
			(width 0.07112)
			(type default)
		)
		(layer "In6.Cu")
	)
	(gr_line
		(start 120.943624 -388.826756)
		(end 120.943624 -389.006588)
		(stroke
			(width 0.07112)
			(type default)
		)
		(layer "In6.Cu")
	)
	(gr_line
		(start 120.955308 -320.097912)
		(end 120.955308 -320.098166)
		(stroke
			(width 0.07112)
			(type default)
		)
		(layer "In6.Cu")
	)
	(gr_line
		(start 120.956832 -303.865788)
		(end 120.956578 -303.865534)
		(stroke
			(width 0.07112)
			(type default)
		)
		(layer "In6.Cu")
	)
	(gr_line
		(start 121.038874 -414.274254)
		(end 121.276364 -414.629346)
		(stroke
			(width 0.07112)
			(type default)
		)
		(layer "In6.Cu")
	)
	(gr_arc
		(start 121.144792 -294.795194)
		(mid 121.148717 -294.798005)
		(end 121.152666 -294.800782)
		(stroke
			(width 0.05715)
			(type default)
		)
		(layer "In6.Cu")
	)
	(gr_arc
		(start 121.144792 -293.175182)
		(mid 121.14758 -293.177096)
		(end 121.15038 -293.178992)
		(stroke
			(width 0.05715)
			(type default)
		)
		(layer "In6.Cu")
	)
	(gr_arc
		(start 121.144792 -291.55517)
		(mid 121.148717 -291.557981)
		(end 121.152666 -291.560758)
		(stroke
			(width 0.05715)
			(type default)
		)
		(layer "In6.Cu")
	)
	(gr_arc
		(start 121.144792 -289.935158)
		(mid 121.148717 -289.937969)
		(end 121.152666 -289.940746)
		(stroke
			(width 0.05715)
			(type default)
		)
		(layer "In6.Cu")
	)
	(gr_arc
		(start 121.144792 -285.075376)
		(mid 121.148717 -285.078187)
		(end 121.152666 -285.080964)
		(stroke
			(width 0.05715)
			(type default)
		)
		(layer "In6.Cu")
	)
	(gr_line
		(start 121.148348 -296.353738)
		(end 121.148348 -296.32529)
		(stroke
			(width 0.05715)
			(type default)
		)
		(layer "In6.Cu")
	)
	(gr_line
		(start 121.148348 -296.32529)
		(end 121.102628 -296.27957)
		(stroke
			(width 0.05715)
			(type default)
		)
		(layer "In6.Cu")
	)
	(gr_arc
		(start 121.151142 -293.179754)
		(mid 121.151904 -293.180263)
		(end 121.152666 -293.18077)
		(stroke
			(width 0.05715)
			(type default)
		)
		(layer "In6.Cu")
	)
	(gr_line
		(start 121.152412 -294.800782)
		(end 121.152666 -294.800782)
		(stroke
			(width 0.05715)
			(type default)
		)
		(layer "In6.Cu")
	)
	(gr_arc
		(start 121.152412 -294.800782)
		(mid 121.155454 -294.802823)
		(end 121.158508 -294.804846)
		(stroke
			(width 0.05715)
			(type default)
		)
		(layer "In6.Cu")
	)
	(gr_arc
		(start 121.153428 -293.181278)
		(mid 121.153047 -293.181024)
		(end 121.152666 -293.18077)
		(stroke
			(width 0.05715)
			(type default)
		)
		(layer "In6.Cu")
	)
	(gr_arc
		(start 121.153428 -291.561266)
		(mid 121.153047 -291.561012)
		(end 121.152666 -291.560758)
		(stroke
			(width 0.05715)
			(type default)
		)
		(layer "In6.Cu")
	)
	(gr_arc
		(start 121.153428 -289.941254)
		(mid 121.153047 -289.941)
		(end 121.152666 -289.940746)
		(stroke
			(width 0.05715)
			(type default)
		)
		(layer "In6.Cu")
	)
	(gr_line
		(start 121.15546 -285.082996)
		(end 121.152666 -285.080964)
		(stroke
			(width 0.05715)
			(type default)
		)
		(layer "In6.Cu")
	)
	(gr_line
		(start 121.160286 -293.185342)
		(end 121.153428 -293.181278)
		(stroke
			(width 0.05715)
			(type default)
		)
		(layer "In6.Cu")
	)
	(gr_line
		(start 121.16054 -291.56533)
		(end 121.153428 -291.561266)
		(stroke
			(width 0.05715)
			(type default)
		)
		(layer "In6.Cu")
	)
	(gr_line
		(start 121.16054 -289.945318)
		(end 121.153428 -289.941254)
		(stroke
			(width 0.05715)
			(type default)
		)
		(layer "In6.Cu")
	)
	(gr_line
		(start 121.16054 -285.086044)
		(end 121.15546 -285.082996)
		(stroke
			(width 0.05715)
			(type default)
		)
		(layer "In6.Cu")
	)
	(gr_line
		(start 121.162572 -293.186612)
		(end 121.160286 -293.185342)
		(stroke
			(width 0.05715)
			(type default)
		)
		(layer "In6.Cu")
	)
	(gr_line
		(start 121.163588 -294.807386)
		(end 121.158508 -294.804846)
		(stroke
			(width 0.05715)
			(type default)
		)
		(layer "In6.Cu")
	)
	(gr_line
		(start 121.176542 -389.352536)
		(end 120.998234 -389.352536)
		(stroke
			(width 0.07112)
			(type default)
		)
		(layer "In6.Cu")
	)
	(gr_line
		(start 121.180352 -293.855648)
		(end 121.181114 -293.85514)
		(stroke
			(width 0.05715)
			(type default)
		)
		(layer "In6.Cu")
	)
	(gr_line
		(start 121.181114 -293.19728)
		(end 121.180098 -293.196772)
		(stroke
			(width 0.05715)
			(type default)
		)
		(layer "In6.Cu")
	)
	(gr_line
		(start 121.181876 -293.854632)
		(end 121.190766 -293.849552)
		(stroke
			(width 0.05715)
			(type default)
		)
		(layer "In6.Cu")
	)
	(gr_line
		(start 121.184162 -293.199312)
		(end 121.182384 -293.198042)
		(stroke
			(width 0.05715)
			(type default)
		)
		(layer "In6.Cu")
	)
	(gr_line
		(start 121.185178 -293.19982)
		(end 121.184162 -293.199312)
		(stroke
			(width 0.05715)
			(type default)
		)
		(layer "In6.Cu")
	)
	(gr_line
		(start 121.185686 -293.200074)
		(end 121.185178 -293.19982)
		(stroke
			(width 0.05715)
			(type default)
		)
		(layer "In6.Cu")
	)
	(gr_line
		(start 121.186956 -289.960812)
		(end 121.186194 -289.960304)
		(stroke
			(width 0.05715)
			(type default)
		)
		(layer "In6.Cu")
	)
	(gr_line
		(start 121.18975 -290.610036)
		(end 121.19356 -290.60775)
		(stroke
			(width 0.05715)
			(type default)
		)
		(layer "In6.Cu")
	)
	(gr_line
		(start 121.191274 -303.70907)
		(end 121.19102 -303.708816)
		(stroke
			(width 0.07112)
			(type default)
		)
		(layer "In6.Cu")
	)
	(gr_line
		(start 121.191274 -284.129226)
		(end 121.191782 -284.128972)
		(stroke
			(width 0.05715)
			(type default)
		)
		(layer "In6.Cu")
	)
	(gr_line
		(start 121.191782 -284.128972)
		(end 121.192544 -284.128464)
		(stroke
			(width 0.05715)
			(type default)
		)
		(layer "In6.Cu")
	)
	(gr_line
		(start 121.19229 -293.204138)
		(end 121.188988 -293.202106)
		(stroke
			(width 0.05715)
			(type default)
		)
		(layer "In6.Cu")
	)
	(gr_line
		(start 121.19356 -289.964622)
		(end 121.186956 -289.960812)
		(stroke
			(width 0.05715)
			(type default)
		)
		(layer "In6.Cu")
	)
	(gr_line
		(start 121.196354 -353.158298)
		(end 121.1961 -353.158298)
		(stroke
			(width 0.07112)
			(type default)
		)
		(layer "In6.Cu")
	)
	(gr_line
		(start 121.20499 -319.966848)
		(end 121.205244 -319.967356)
		(stroke
			(width 0.07112)
			(type default)
		)
		(layer "In6.Cu")
	)
	(gr_arc
		(start 121.21261 -353.147376)
		(mid 121.211975 -353.147757)
		(end 121.21134 -353.148138)
		(stroke
			(width 0.07112)
			(type default)
		)
		(layer "In6.Cu")
	)
	(gr_line
		(start 121.21261 -292.216586)
		(end 121.213118 -292.216332)
		(stroke
			(width 0.05715)
			(type default)
		)
		(layer "In6.Cu")
	)
	(gr_line
		(start 121.213118 -292.216332)
		(end 121.213372 -292.216332)
		(stroke
			(width 0.05715)
			(type default)
		)
		(layer "In6.Cu")
	)
	(gr_line
		(start 121.268998 -415.372804)
		(end 121.658634 -415.955988)
		(stroke
			(width 0.07112)
			(type default)
		)
		(layer "In6.Cu")
	)
	(gr_line
		(start 121.273316 -293.030402)
		(end 121.27103 -293.029132)
		(stroke
			(width 0.05715)
			(type default)
		)
		(layer "In6.Cu")
	)
	(gr_line
		(start 121.27484 -293.031164)
		(end 121.273316 -293.030402)
		(stroke
			(width 0.05715)
			(type default)
		)
		(layer "In6.Cu")
	)
	(gr_line
		(start 121.275602 -293.031672)
		(end 121.27484 -293.031164)
		(stroke
			(width 0.05715)
			(type default)
		)
		(layer "In6.Cu")
	)
	(gr_line
		(start 121.276364 -414.629346)
		(end 121.238772 -414.818068)
		(stroke
			(width 0.07112)
			(type default)
		)
		(layer "In6.Cu")
	)
	(gr_line
		(start 121.28119 -293.034974)
		(end 121.280428 -293.034466)
		(stroke
			(width 0.05715)
			(type default)
		)
		(layer "In6.Cu")
	)
	(gr_line
		(start 121.282206 -293.035482)
		(end 121.28119 -293.034974)
		(stroke
			(width 0.05715)
			(type default)
		)
		(layer "In6.Cu")
	)
	(gr_line
		(start 121.282714 -293.035736)
		(end 121.282206 -293.035482)
		(stroke
			(width 0.05715)
			(type default)
		)
		(layer "In6.Cu")
	)
	(gr_line
		(start 121.283222 -289.79622)
		(end 121.28246 -289.795712)
		(stroke
			(width 0.05715)
			(type default)
		)
		(layer "In6.Cu")
	)
	(gr_line
		(start 121.285 -290.775136)
		(end 121.286016 -290.774628)
		(stroke
			(width 0.05715)
			(type default)
		)
		(layer "In6.Cu")
	)
	(gr_line
		(start 121.286016 -290.774628)
		(end 121.286778 -290.77412)
		(stroke
			(width 0.05715)
			(type default)
		)
		(layer "In6.Cu")
	)
	(gr_line
		(start 121.286778 -290.77412)
		(end 121.287794 -290.773612)
		(stroke
			(width 0.05715)
			(type default)
		)
		(layer "In6.Cu")
	)
	(gr_line
		(start 121.29135 -389.467344)
		(end 121.176542 -389.352536)
		(stroke
			(width 0.07112)
			(type default)
		)
		(layer "In6.Cu")
	)
	(gr_line
		(start 121.296176 -290.768786)
		(end 121.295668 -290.76904)
		(stroke
			(width 0.05715)
			(type default)
		)
		(layer "In6.Cu")
	)
	(gr_arc
		(start 121.296176 -289.803586)
		(mid 121.295034 -289.802823)
		(end 121.29389 -289.802062)
		(stroke
			(width 0.05715)
			(type default)
		)
		(layer "In6.Cu")
	)
	(gr_arc
		(start 121.299224 -294.007032)
		(mid 121.301895 -294.005515)
		(end 121.304558 -294.003984)
		(stroke
			(width 0.05715)
			(type default)
		)
		(layer "In6.Cu")
	)
	(gr_arc
		(start 121.304558 -293.048436)
		(mid 121.301263 -293.046393)
		(end 121.297954 -293.044372)
		(stroke
			(width 0.05715)
			(type default)
		)
		(layer "In6.Cu")
	)
	(gr_line
		(start 121.308368 -292.381686)
		(end 121.30913 -292.381178)
		(stroke
			(width 0.05715)
			(type default)
		)
		(layer "In6.Cu")
	)
	(gr_line
		(start 121.321322 -288.198306)
		(end 121.31675 -288.195766)
		(stroke
			(width 0.05715)
			(type default)
		)
		(layer "In6.Cu")
	)
	(gr_line
		(start 121.324116 -288.19983)
		(end 121.321322 -288.198306)
		(stroke
			(width 0.05715)
			(type default)
		)
		(layer "In6.Cu")
	)
	(gr_line
		(start 121.327926 -294.680386)
		(end 121.310146 -294.67048)
		(stroke
			(width 0.05715)
			(type default)
		)
		(layer "In6.Cu")
	)
	(gr_line
		(start 121.328942 -294.682418)
		(end 121.327926 -294.680386)
		(stroke
			(width 0.05715)
			(type default)
		)
		(layer "In6.Cu")
	)
	(gr_arc
		(start 121.331228 -294.683942)
		(mid 121.330086 -294.683178)
		(end 121.328942 -294.682418)
		(stroke
			(width 0.05715)
			(type default)
		)
		(layer "In6.Cu")
	)
	(gr_arc
		(start 121.339356 -289.12058)
		(mid 121.340373 -289.119819)
		(end 121.341388 -289.119056)
		(stroke
			(width 0.05715)
			(type default)
		)
		(layer "In6.Cu")
	)
	(gr_arc
		(start 121.339864 -288.212022)
		(mid 121.332041 -288.20586)
		(end 121.324116 -288.19983)
		(stroke
			(width 0.05715)
			(type default)
		)
		(layer "In6.Cu")
	)
	(gr_line
		(start 121.371868 -394.805154)
		(end 121.371868 -395.506194)
		(stroke
			(width 0.07112)
			(type default)
		)
		(layer "In6.Cu")
	)
	(gr_line
		(start 121.404126 -401.539202)
		(end 121.849388 -402.081492)
		(stroke
			(width 0.07112)
			(type default)
		)
		(layer "In6.Cu")
	)
	(gr_line
		(start 121.504964 -415.21634)
		(end 121.693686 -415.253932)
		(stroke
			(width 0.07112)
			(type default)
		)
		(layer "In6.Cu")
	)
	(gr_line
		(start 121.520712 -419.330124)
		(end 122.103896 -419.720014)
		(stroke
			(width 0.07112)
			(type default)
		)
		(layer "In6.Cu")
	)
	(gr_line
		(start 121.566432 -287.081468)
		(end 121.566178 -287.082738)
		(stroke
			(width 0.05715)
			(type default)
		)
		(layer "In6.Cu")
	)
	(gr_line
		(start 121.569988 -287.036764)
		(end 121.569988 -287.038542)
		(stroke
			(width 0.05715)
			(type default)
		)
		(layer "In6.Cu")
	)
	(gr_arc
		(start 121.614946 -285.885636)
		(mid 121.61925 -285.888704)
		(end 121.623582 -285.891732)
		(stroke
			(width 0.05715)
			(type default)
		)
		(layer "In6.Cu")
	)
	(gr_line
		(start 121.622312 -401.360132)
		(end 121.622566 -401.360132)
		(stroke
			(width 0.07112)
			(type default)
		)
		(layer "In6.Cu")
	)
	(gr_line
		(start 121.623328 -285.891732)
		(end 121.623582 -285.891732)
		(stroke
			(width 0.05715)
			(type default)
		)
		(layer "In6.Cu")
	)
	(gr_line
		(start 121.623836 -401.360386)
		(end 121.815606 -401.379182)
		(stroke
			(width 0.07112)
			(type default)
		)
		(layer "In6.Cu")
	)
	(gr_arc
		(start 121.62536 -286.579818)
		(mid 121.618722 -286.584469)
		(end 121.612152 -286.589216)
		(stroke
			(width 0.05715)
			(type default)
		)
		(layer "In6.Cu")
	)
	(gr_line
		(start 121.62536 -286.579818)
		(end 121.628154 -286.578294)
		(stroke
			(width 0.05715)
			(type default)
		)
		(layer "In6.Cu")
	)
	(gr_line
		(start 121.630186 -285.895796)
		(end 121.623328 -285.891732)
		(stroke
			(width 0.05715)
			(type default)
		)
		(layer "In6.Cu")
	)
	(gr_line
		(start 121.655078 -394.806424)
		(end 121.790968 -394.942314)
		(stroke
			(width 0.07112)
			(type default)
		)
		(layer "In6.Cu")
	)
	(gr_line
		(start 121.66092 -283.319474)
		(end 121.661682 -283.318966)
		(stroke
			(width 0.05715)
			(type default)
		)
		(layer "In6.Cu")
	)
	(gr_line
		(start 121.661682 -283.318966)
		(end 121.662444 -283.318458)
		(stroke
			(width 0.05715)
			(type default)
		)
		(layer "In6.Cu")
	)
	(gr_line
		(start 121.662444 -283.318458)
		(end 121.663714 -283.317696)
		(stroke
			(width 0.05715)
			(type default)
		)
		(layer "In6.Cu")
	)
	(gr_line
		(start 121.663714 -283.317696)
		(end 121.66473 -283.317188)
		(stroke
			(width 0.05715)
			(type default)
		)
		(layer "In6.Cu")
	)
	(gr_line
		(start 121.66727 -283.315664)
		(end 121.668032 -283.315156)
		(stroke
			(width 0.05715)
			(type default)
		)
		(layer "In6.Cu")
	)
	(gr_line
		(start 121.668032 -283.315156)
		(end 121.669556 -283.314394)
		(stroke
			(width 0.05715)
			(type default)
		)
		(layer "In6.Cu")
	)
	(gr_line
		(start 121.678954 -419.095428)
		(end 121.867676 -419.057836)
		(stroke
			(width 0.07112)
			(type default)
		)
		(layer "In6.Cu")
	)
	(gr_line
		(start 121.693432 -285.932118)
		(end 121.693178 -285.932372)
		(stroke
			(width 0.05715)
			(type default)
		)
		(layer "In6.Cu")
	)
	(gr_line
		(start 121.693686 -415.253932)
		(end 121.930922 -415.609024)
		(stroke
			(width 0.07112)
			(type default)
		)
		(layer "In6.Cu")
	)
	(gr_line
		(start 121.759218 -283.48305)
		(end 121.760488 -283.482034)
		(stroke
			(width 0.05715)
			(type default)
		)
		(layer "In6.Cu")
	)
	(gr_line
		(start 121.761758 -283.481272)
		(end 121.762774 -283.480764)
		(stroke
			(width 0.05715)
			(type default)
		)
		(layer "In6.Cu")
	)
	(gr_line
		(start 121.762774 -283.480764)
		(end 121.765314 -283.47924)
		(stroke
			(width 0.05715)
			(type default)
		)
		(layer "In6.Cu")
	)
	(gr_line
		(start 121.765314 -283.47924)
		(end 121.766076 -283.478732)
		(stroke
			(width 0.05715)
			(type default)
		)
		(layer "In6.Cu")
	)
	(gr_line
		(start 121.766076 -283.478732)
		(end 121.76633 -283.478986)
		(stroke
			(width 0.05715)
			(type default)
		)
		(layer "In6.Cu")
	)
	(gr_line
		(start 121.76633 -283.478986)
		(end 121.767346 -283.478478)
		(stroke
			(width 0.05715)
			(type default)
		)
		(layer "In6.Cu")
	)
	(gr_line
		(start 121.77014 -283.4767)
		(end 121.772172 -283.475684)
		(stroke
			(width 0.05715)
			(type default)
		)
		(layer "In6.Cu")
	)
	(gr_line
		(start 121.78792 -283.466286)
		(end 121.796048 -283.46146)
		(stroke
			(width 0.05715)
			(type default)
		)
		(layer "In6.Cu")
	)
	(gr_line
		(start 121.790968 -395.369034)
		(end 121.655078 -395.504924)
		(stroke
			(width 0.07112)
			(type default)
		)
		(layer "In6.Cu")
	)
	(gr_line
		(start 121.790968 -394.942314)
		(end 121.790968 -395.369034)
		(stroke
			(width 0.07112)
			(type default)
		)
		(layer "In6.Cu")
	)
	(gr_arc
		(start 121.79681 -283.460952)
		(mid 121.796429 -283.461206)
		(end 121.796048 -283.46146)
		(stroke
			(width 0.05715)
			(type default)
		)
		(layer "In6.Cu")
	)
	(gr_arc
		(start 121.79681 -283.460952)
		(mid 121.800759 -283.458175)
		(end 121.804684 -283.455364)
		(stroke
			(width 0.05715)
			(type default)
		)
		(layer "In6.Cu")
	)
	(gr_line
		(start 121.80443 -296.353738)
		(end 121.80443 -296.32529)
		(stroke
			(width 0.05715)
			(type default)
		)
		(layer "In6.Cu")
	)
	(gr_line
		(start 121.80443 -296.32529)
		(end 121.85015 -296.27957)
		(stroke
			(width 0.05715)
			(type default)
		)
		(layer "In6.Cu")
	)
	(gr_line
		(start 121.815606 -401.379182)
		(end 122.08637 -401.709382)
		(stroke
			(width 0.07112)
			(type default)
		)
		(layer "In6.Cu")
	)
	(gr_line
		(start 121.849388 -402.081492)
		(end 121.849642 -402.081492)
		(stroke
			(width 0.07112)
			(type default)
		)
		(layer "In6.Cu")
	)
	(gr_line
		(start 121.849642 -296.007536)
		(end 121.849642 -296.007028)
		(stroke
			(width 0.05715)
			(type default)
		)
		(layer "In6.Cu")
	)
	(gr_line
		(start 121.867676 -419.057836)
		(end 122.222768 -419.295072)
		(stroke
			(width 0.07112)
			(type default)
		)
		(layer "In6.Cu")
	)
	(gr_line
		(start 121.896886 -398.516602)
		(end 122.392694 -399.01241)
		(stroke
			(width 0.07112)
			(type default)
		)
		(layer "In6.Cu")
	)
	(gr_line
		(start 121.930922 -415.609024)
		(end 121.89333 -415.797746)
		(stroke
			(width 0.07112)
			(type default)
		)
		(layer "In6.Cu")
	)
	(gr_line
		(start 122.04065 -296.08653)
		(end 122.04065 -296.086022)
		(stroke
			(width 0.05715)
			(type default)
		)
		(layer "In6.Cu")
	)
	(gr_line
		(start 122.08637 -401.709382)
		(end 122.067828 -401.901152)
		(stroke
			(width 0.07112)
			(type default)
		)
		(layer "In6.Cu")
	)
	(gr_line
		(start 122.08637 -296.353738)
		(end 122.08637 -296.32529)
		(stroke
			(width 0.05715)
			(type default)
		)
		(layer "In6.Cu")
	)
	(gr_line
		(start 122.08637 -296.32529)
		(end 122.04065 -296.27957)
		(stroke
			(width 0.05715)
			(type default)
		)
		(layer "In6.Cu")
	)
	(gr_line
		(start 122.091196 -388.774432)
		(end 122.14352 -388.826756)
		(stroke
			(width 0.07112)
			(type default)
		)
		(layer "In6.Cu")
	)
	(gr_line
		(start 122.091704 -313.158378)
		(end 122.091958 -313.158378)
		(stroke
			(width 0.07112)
			(type default)
		)
		(layer "In6.Cu")
	)
	(gr_line
		(start 122.098054 -398.317212)
		(end 122.290078 -398.317212)
		(stroke
			(width 0.07112)
			(type default)
		)
		(layer "In6.Cu")
	)
	(gr_arc
		(start 122.102118 -9.272016)
		(mid 123.157118 -8.83502)
		(end 123.594114 -7.78002)
		(stroke
			(width 0.2)
			(type default)
		)
		(layer "In6.Cu")
	)
	(gr_line
		(start 122.118628 -416.644582)
		(end 122.508264 -417.227766)
		(stroke
			(width 0.07112)
			(type default)
		)
		(layer "In6.Cu")
	)
	(gr_line
		(start 122.14352 -389.006588)
		(end 121.996962 -389.153146)
		(stroke
			(width 0.07112)
			(type default)
		)
		(layer "In6.Cu")
	)
	(gr_line
		(start 122.14352 -388.826756)
		(end 122.14352 -389.006588)
		(stroke
			(width 0.07112)
			(type default)
		)
		(layer "In6.Cu")
	)
	(gr_line
		(start 122.222768 -419.295072)
		(end 122.26036 -419.483794)
		(stroke
			(width 0.07112)
			(type default)
		)
		(layer "In6.Cu")
	)
	(gr_line
		(start 122.290078 -398.317212)
		(end 122.592084 -398.619218)
		(stroke
			(width 0.07112)
			(type default)
		)
		(layer "In6.Cu")
	)
	(gr_line
		(start 122.354848 -416.488118)
		(end 122.543316 -416.52571)
		(stroke
			(width 0.07112)
			(type default)
		)
		(layer "In6.Cu")
	)
	(gr_line
		(start 122.376438 -389.352536)
		(end 122.19813 -389.352536)
		(stroke
			(width 0.07112)
			(type default)
		)
		(layer "In6.Cu")
	)
	(gr_line
		(start 122.491246 -389.467344)
		(end 122.376438 -389.352536)
		(stroke
			(width 0.07112)
			(type default)
		)
		(layer "In6.Cu")
	)
	(gr_line
		(start 122.508264 -417.227766)
		(end 122.508518 -417.227766)
		(stroke
			(width 0.07112)
			(type default)
		)
		(layer "In6.Cu")
	)
	(gr_line
		(start 122.543316 -416.52571)
		(end 122.780806 -416.880802)
		(stroke
			(width 0.07112)
			(type default)
		)
		(layer "In6.Cu")
	)
	(gr_line
		(start 122.552206 -410.030168)
		(end 122.843036 -410.320998)
		(stroke
			(width 0.07112)
			(type default)
		)
		(layer "In6.Cu")
	)
	(gr_line
		(start 122.571764 -394.530834)
		(end 122.571764 -395.231874)
		(stroke
			(width 0.07112)
			(type default)
		)
		(layer "In6.Cu")
	)
	(gr_line
		(start 122.592084 -398.619218)
		(end 122.592084 -398.811242)
		(stroke
			(width 0.07112)
			(type default)
		)
		(layer "In6.Cu")
	)
	(gr_line
		(start 122.595894 -281.70251)
		(end 122.599196 -281.700478)
		(stroke
			(width 0.05715)
			(type default)
		)
		(layer "In6.Cu")
	)
	(gr_line
		(start 122.600212 -281.699716)
		(end 122.60072 -281.699462)
		(stroke
			(width 0.05715)
			(type default)
		)
		(layer "In6.Cu")
	)
	(gr_line
		(start 122.60072 -281.699462)
		(end 122.601736 -281.698954)
		(stroke
			(width 0.05715)
			(type default)
		)
		(layer "In6.Cu")
	)
	(gr_line
		(start 122.601736 -281.698954)
		(end 122.602498 -281.698446)
		(stroke
			(width 0.05715)
			(type default)
		)
		(layer "In6.Cu")
	)
	(gr_line
		(start 122.603768 -295.634918)
		(end 122.602498 -295.634156)
		(stroke
			(width 0.05715)
			(type default)
		)
		(layer "In6.Cu")
	)
	(gr_line
		(start 122.607832 -295.637204)
		(end 122.606308 -295.636188)
		(stroke
			(width 0.05715)
			(type default)
		)
		(layer "In6.Cu")
	)
	(gr_line
		(start 122.608086 -281.695144)
		(end 122.60961 -281.694382)
		(stroke
			(width 0.05715)
			(type default)
		)
		(layer "In6.Cu")
	)
	(gr_line
		(start 122.609356 -295.637966)
		(end 122.607832 -295.637204)
		(stroke
			(width 0.05715)
			(type default)
		)
		(layer "In6.Cu")
	)
	(gr_line
		(start 122.60961 -281.694382)
		(end 122.610372 -281.693874)
		(stroke
			(width 0.05715)
			(type default)
		)
		(layer "In6.Cu")
	)
	(gr_line
		(start 122.610372 -281.693874)
		(end 122.611642 -281.693112)
		(stroke
			(width 0.05715)
			(type default)
		)
		(layer "In6.Cu")
	)
	(gr_line
		(start 122.611642 -281.693112)
		(end 122.61215 -281.692858)
		(stroke
			(width 0.05715)
			(type default)
		)
		(layer "In6.Cu")
	)
	(gr_line
		(start 122.695208 -281.865324)
		(end 122.696986 -281.864308)
		(stroke
			(width 0.05715)
			(type default)
		)
		(layer "In6.Cu")
	)
	(gr_line
		(start 122.697748 -295.468802)
		(end 122.69724 -295.468548)
		(stroke
			(width 0.05715)
			(type default)
		)
		(layer "In6.Cu")
	)
	(gr_line
		(start 122.698764 -295.46931)
		(end 122.697748 -295.468802)
		(stroke
			(width 0.05715)
			(type default)
		)
		(layer "In6.Cu")
	)
	(gr_line
		(start 122.699272 -281.863038)
		(end 122.700542 -281.862022)
		(stroke
			(width 0.05715)
			(type default)
		)
		(layer "In6.Cu")
	)
	(gr_line
		(start 122.700542 -295.470326)
		(end 122.698764 -295.46931)
		(stroke
			(width 0.05715)
			(type default)
		)
		(layer "In6.Cu")
	)
	(gr_line
		(start 122.702828 -295.47185)
		(end 122.702066 -295.471342)
		(stroke
			(width 0.05715)
			(type default)
		)
		(layer "In6.Cu")
	)
	(gr_line
		(start 122.70486 -281.859482)
		(end 122.705368 -281.859228)
		(stroke
			(width 0.05715)
			(type default)
		)
		(layer "In6.Cu")
	)
	(gr_line
		(start 122.706638 -281.858466)
		(end 122.707654 -281.857958)
		(stroke
			(width 0.05715)
			(type default)
		)
		(layer "In6.Cu")
	)
	(gr_line
		(start 122.712734 -286.23641)
		(end 122.414792 -286.23641)
		(stroke
			(width 0.05715)
			(type default)
		)
		(layer "In6.Cu")
	)
	(gr_line
		(start 122.712734 -284.616398)
		(end 122.414792 -284.616398)
		(stroke
			(width 0.05715)
			(type default)
		)
		(layer "In6.Cu")
	)
	(gr_line
		(start 122.712734 -282.996386)
		(end 122.414792 -282.996386)
		(stroke
			(width 0.05715)
			(type default)
		)
		(layer "In6.Cu")
	)
	(gr_line
		(start 122.712734 -281.376374)
		(end 122.414792 -281.376374)
		(stroke
			(width 0.05715)
			(type default)
		)
		(layer "In6.Cu")
	)
	(gr_line
		(start 122.724672 -304.772822)
		(end 122.724672 -304.772568)
		(stroke
			(width 0.07112)
			(type default)
		)
		(layer "In6.Cu")
	)
	(gr_line
		(start 122.729244 -295.48709)
		(end 122.728482 -295.486582)
		(stroke
			(width 0.05715)
			(type default)
		)
		(layer "In6.Cu")
	)
	(gr_line
		(start 122.730006 -295.487598)
		(end 122.729244 -295.48709)
		(stroke
			(width 0.05715)
			(type default)
		)
		(layer "In6.Cu")
	)
	(gr_line
		(start 122.736864 -295.491662)
		(end 122.730006 -295.487598)
		(stroke
			(width 0.05715)
			(type default)
		)
		(layer "In6.Cu")
	)
	(gr_line
		(start 122.744484 -296.353738)
		(end 122.744484 -296.32529)
		(stroke
			(width 0.05715)
			(type default)
		)
		(layer "In6.Cu")
	)
	(gr_line
		(start 122.744484 -296.32529)
		(end 122.790204 -296.27957)
		(stroke
			(width 0.05715)
			(type default)
		)
		(layer "In6.Cu")
	)
	(gr_arc
		(start 122.744992 -295.49725)
		(mid 122.740941 -295.494437)
		(end 122.736864 -295.491662)
		(stroke
			(width 0.05715)
			(type default)
		)
		(layer "In6.Cu")
	)
	(gr_line
		(start 122.780806 -416.880802)
		(end 122.743214 -417.069778)
		(stroke
			(width 0.07112)
			(type default)
		)
		(layer "In6.Cu")
	)
	(gr_line
		(start 122.782076 -286.305752)
		(end 122.712734 -286.23641)
		(stroke
			(width 0.05715)
			(type default)
		)
		(layer "In6.Cu")
	)
	(gr_line
		(start 122.782076 -281.445716)
		(end 122.712734 -281.376374)
		(stroke
			(width 0.05715)
			(type default)
		)
		(layer "In6.Cu")
	)
	(gr_line
		(start 122.789696 -296.007536)
		(end 122.789696 -296.007028)
		(stroke
			(width 0.05715)
			(type default)
		)
		(layer "In6.Cu")
	)
	(gr_line
		(start 122.795538 -284.699202)
		(end 122.712734 -284.616398)
		(stroke
			(width 0.05715)
			(type default)
		)
		(layer "In6.Cu")
	)
	(gr_arc
		(start 122.795538 -284.699202)
		(mid 122.797325 -284.710652)
		(end 122.799348 -284.722062)
		(stroke
			(width 0.05715)
			(type default)
		)
		(layer "In6.Cu")
	)
	(gr_line
		(start 122.795538 -283.07919)
		(end 122.712734 -282.996386)
		(stroke
			(width 0.05715)
			(type default)
		)
		(layer "In6.Cu")
	)
	(gr_arc
		(start 122.795538 -283.07919)
		(mid 122.79733 -283.090512)
		(end 122.799348 -283.101796)
		(stroke
			(width 0.05715)
			(type default)
		)
		(layer "In6.Cu")
	)
	(gr_arc
		(start 122.843036 -413.020256)
		(mid 122.882496 -413.420665)
		(end 122.9995 -413.805624)
		(stroke
			(width 0.07112)
			(type default)
		)
		(layer "In6.Cu")
	)
	(gr_line
		(start 122.843036 -411.248606)
		(end 122.843036 -411.949646)
		(stroke
			(width 0.07112)
			(type default)
		)
		(layer "In6.Cu")
	)
	(gr_line
		(start 122.843036 -406.71369)
		(end 122.552206 -407.00452)
		(stroke
			(width 0.07112)
			(type default)
		)
		(layer "In6.Cu")
	)
	(gr_line
		(start 122.854974 -394.532104)
		(end 122.990864 -394.667994)
		(stroke
			(width 0.07112)
			(type default)
		)
		(layer "In6.Cu")
	)
	(gr_arc
		(start 122.97029 -286.342074)
		(mid 122.972313 -286.330664)
		(end 122.9741 -286.319214)
		(stroke
			(width 0.05715)
			(type default)
		)
		(layer "In6.Cu")
	)
	(gr_arc
		(start 122.97029 -281.482038)
		(mid 122.972312 -281.470628)
		(end 122.9741 -281.459178)
		(stroke
			(width 0.05715)
			(type default)
		)
		(layer "In6.Cu")
	)
	(gr_line
		(start 122.9741 -286.319214)
		(end 123.056904 -286.23641)
		(stroke
			(width 0.05715)
			(type default)
		)
		(layer "In6.Cu")
	)
	(gr_line
		(start 122.9741 -281.459178)
		(end 123.056904 -281.376374)
		(stroke
			(width 0.05715)
			(type default)
		)
		(layer "In6.Cu")
	)
	(gr_line
		(start 122.980704 -296.08653)
		(end 122.980704 -296.086022)
		(stroke
			(width 0.05715)
			(type default)
		)
		(layer "In6.Cu")
	)
	(gr_line
		(start 122.987562 -284.68574)
		(end 123.056904 -284.616398)
		(stroke
			(width 0.05715)
			(type default)
		)
		(layer "In6.Cu")
	)
	(gr_line
		(start 122.987562 -283.065728)
		(end 123.056904 -282.996386)
		(stroke
			(width 0.05715)
			(type default)
		)
		(layer "In6.Cu")
	)
	(gr_line
		(start 122.990864 -395.094714)
		(end 122.854974 -395.230604)
		(stroke
			(width 0.07112)
			(type default)
		)
		(layer "In6.Cu")
	)
	(gr_line
		(start 122.990864 -394.667994)
		(end 122.990864 -395.094714)
		(stroke
			(width 0.07112)
			(type default)
		)
		(layer "In6.Cu")
	)
	(gr_line
		(start 123.026424 -296.353738)
		(end 123.026424 -296.32529)
		(stroke
			(width 0.05715)
			(type default)
		)
		(layer "In6.Cu")
	)
	(gr_line
		(start 123.026424 -296.32529)
		(end 122.980704 -296.27957)
		(stroke
			(width 0.05715)
			(type default)
		)
		(layer "In6.Cu")
	)
	(gr_line
		(start 123.056904 -286.23641)
		(end 123.354846 -286.23641)
		(stroke
			(width 0.05715)
			(type default)
		)
		(layer "In6.Cu")
	)
	(gr_line
		(start 123.056904 -284.616398)
		(end 123.354846 -284.616398)
		(stroke
			(width 0.05715)
			(type default)
		)
		(layer "In6.Cu")
	)
	(gr_line
		(start 123.056904 -282.996386)
		(end 123.354846 -282.996386)
		(stroke
			(width 0.05715)
			(type default)
		)
		(layer "In6.Cu")
	)
	(gr_line
		(start 123.056904 -281.376374)
		(end 123.354846 -281.376374)
		(stroke
			(width 0.05715)
			(type default)
		)
		(layer "In6.Cu")
	)
	(gr_line
		(start 123.124976 -406.71369)
		(end 123.415806 -407.00452)
		(stroke
			(width 0.07112)
			(type default)
		)
		(layer "In6.Cu")
	)
	(gr_line
		(start 123.126246 -411.249876)
		(end 123.262136 -411.385766)
		(stroke
			(width 0.07112)
			(type default)
		)
		(layer "In6.Cu")
	)
	(gr_arc
		(start 123.164854 -414.123886)
		(mid 123.1646 -414.123632)
		(end 123.164346 -414.123378)
		(stroke
			(width 0.07112)
			(type default)
		)
		(layer "In6.Cu")
	)
	(gr_line
		(start 123.259088 -283.81579)
		(end 123.259088 -283.816298)
		(stroke
			(width 0.05715)
			(type default)
		)
		(layer "In6.Cu")
	)
	(gr_line
		(start 123.262136 -411.812486)
		(end 123.126246 -411.948376)
		(stroke
			(width 0.07112)
			(type default)
		)
		(layer "In6.Cu")
	)
	(gr_line
		(start 123.262136 -411.385766)
		(end 123.262136 -411.812486)
		(stroke
			(width 0.07112)
			(type default)
		)
		(layer "In6.Cu")
	)
	(gr_line
		(start 123.291346 -388.774432)
		(end 123.34367 -388.826756)
		(stroke
			(width 0.07112)
			(type default)
		)
		(layer "In6.Cu")
	)
	(gr_line
		(start 123.336812 -413.88284)
		(end 123.337066 -413.883348)
		(stroke
			(width 0.07112)
			(type default)
		)
		(layer "In6.Cu")
	)
	(gr_line
		(start 123.34367 -389.019796)
		(end 123.21032 -389.153146)
		(stroke
			(width 0.07112)
			(type default)
		)
		(layer "In6.Cu")
	)
	(gr_line
		(start 123.34367 -388.826756)
		(end 123.34367 -389.019796)
		(stroke
			(width 0.07112)
			(type default)
		)
		(layer "In6.Cu")
	)
	(gr_line
		(start 123.415806 -410.030168)
		(end 123.124976 -410.320998)
		(stroke
			(width 0.07112)
			(type default)
		)
		(layer "In6.Cu")
	)
	(gr_arc
		(start 123.44654 -283.772102)
		(mid 123.446287 -283.770705)
		(end 123.446032 -283.769308)
		(stroke
			(width 0.05715)
			(type default)
		)
		(layer "In6.Cu")
	)
	(gr_line
		(start 123.542552 -284.294326)
		(end 123.54179 -284.293818)
		(stroke
			(width 0.05715)
			(type default)
		)
		(layer "In6.Cu")
	)
	(gr_line
		(start 123.547886 -284.297374)
		(end 123.546362 -284.296358)
		(stroke
			(width 0.05715)
			(type default)
		)
		(layer "In6.Cu")
	)
	(gr_line
		(start 123.548902 -284.297882)
		(end 123.547886 -284.297374)
		(stroke
			(width 0.05715)
			(type default)
		)
		(layer "In6.Cu")
	)
	(gr_line
		(start 123.54941 -284.298136)
		(end 123.548902 -284.297882)
		(stroke
			(width 0.05715)
			(type default)
		)
		(layer "In6.Cu")
	)
	(gr_line
		(start 123.576334 -389.352536)
		(end 123.411488 -389.352536)
		(stroke
			(width 0.07112)
			(type default)
		)
		(layer "In6.Cu")
	)
	(gr_line
		(start 123.594114 -7.78002)
		(end 123.594114 -4.879848)
		(stroke
			(width 0.2)
			(type default)
		)
		(layer "In6.Cu")
	)
	(gr_line
		(start 123.637802 -295.468802)
		(end 123.637294 -295.468548)
		(stroke
			(width 0.05715)
			(type default)
		)
		(layer "In6.Cu")
	)
	(gr_line
		(start 123.640596 -284.130496)
		(end 123.637548 -284.128718)
		(stroke
			(width 0.05715)
			(type default)
		)
		(layer "In6.Cu")
	)
	(gr_line
		(start 123.643136 -284.13202)
		(end 123.64212 -284.131512)
		(stroke
			(width 0.05715)
			(type default)
		)
		(layer "In6.Cu")
	)
	(gr_line
		(start 123.644152 -284.132782)
		(end 123.643136 -284.13202)
		(stroke
			(width 0.05715)
			(type default)
		)
		(layer "In6.Cu")
	)
	(gr_line
		(start 123.64974 -342.3031)
		(end 123.64974 -342.303608)
		(stroke
			(width 0.07112)
			(type default)
		)
		(layer "In6.Cu")
	)
	(gr_line
		(start 123.669298 -284.14726)
		(end 123.66879 -284.147006)
		(stroke
			(width 0.05715)
			(type default)
		)
		(layer "In6.Cu")
	)
	(gr_line
		(start 123.67006 -284.147768)
		(end 123.669298 -284.14726)
		(stroke
			(width 0.05715)
			(type default)
		)
		(layer "In6.Cu")
	)
	(gr_line
		(start 123.676918 -284.151832)
		(end 123.67006 -284.147768)
		(stroke
			(width 0.05715)
			(type default)
		)
		(layer "In6.Cu")
	)
	(gr_line
		(start 123.684284 -296.353738)
		(end 123.684284 -296.32529)
		(stroke
			(width 0.05715)
			(type default)
		)
		(layer "In6.Cu")
	)
	(gr_line
		(start 123.684284 -296.32529)
		(end 123.730004 -296.27957)
		(stroke
			(width 0.05715)
			(type default)
		)
		(layer "In6.Cu")
	)
	(gr_arc
		(start 123.684792 -284.15742)
		(mid 123.680867 -284.154609)
		(end 123.676918 -284.151832)
		(stroke
			(width 0.05715)
			(type default)
		)
		(layer "In6.Cu")
	)
	(gr_line
		(start 123.691142 -389.467344)
		(end 123.576334 -389.352536)
		(stroke
			(width 0.07112)
			(type default)
		)
		(layer "In6.Cu")
	)
	(gr_line
		(start 123.729496 -296.007536)
		(end 123.729496 -296.007028)
		(stroke
			(width 0.05715)
			(type default)
		)
		(layer "In6.Cu")
	)
	(gr_line
		(start 123.771914 -394.504418)
		(end 123.771914 -395.205458)
		(stroke
			(width 0.07112)
			(type default)
		)
		(layer "In6.Cu")
	)
	(gr_line
		(start 123.919996 -286.229806)
		(end 123.919996 -286.23641)
		(stroke
			(width 0.05715)
			(type default)
		)
		(layer "In6.Cu")
	)
	(gr_line
		(start 123.920504 -296.08653)
		(end 123.920504 -296.086022)
		(stroke
			(width 0.05715)
			(type default)
		)
		(layer "In6.Cu")
	)
	(gr_line
		(start 123.966224 -296.353738)
		(end 123.966224 -296.32529)
		(stroke
			(width 0.05715)
			(type default)
		)
		(layer "In6.Cu")
	)
	(gr_line
		(start 123.966224 -296.32529)
		(end 123.920504 -296.27957)
		(stroke
			(width 0.05715)
			(type default)
		)
		(layer "In6.Cu")
	)
	(gr_line
		(start 124.055124 -394.505688)
		(end 124.191014 -394.641578)
		(stroke
			(width 0.07112)
			(type default)
		)
		(layer "In6.Cu")
	)
	(gr_line
		(start 124.102114 -12.288012)
		(end 83.70189 -12.288012)
		(stroke
			(width 0.2)
			(type default)
		)
		(layer "In6.Cu")
	)
	(gr_arc
		(start 124.102114 -12.288012)
		(mid 125.875532 -11.553433)
		(end 126.61011 -9.780016)
		(stroke
			(width 0.2)
			(type default)
		)
		(layer "In6.Cu")
	)
	(gr_line
		(start 124.191014 -395.068298)
		(end 124.055124 -395.204188)
		(stroke
			(width 0.07112)
			(type default)
		)
		(layer "In6.Cu")
	)
	(gr_line
		(start 124.191014 -394.641578)
		(end 124.191014 -395.068298)
		(stroke
			(width 0.07112)
			(type default)
		)
		(layer "In6.Cu")
	)
	(gr_line
		(start 124.468382 -311.611264)
		(end 124.468636 -311.611264)
		(stroke
			(width 0.07112)
			(type default)
		)
		(layer "In6.Cu")
	)
	(gr_line
		(start 124.477018 -285.910782)
		(end 124.476002 -285.910274)
		(stroke
			(width 0.05715)
			(type default)
		)
		(layer "In6.Cu")
	)
	(gr_line
		(start 124.478796 -285.912052)
		(end 124.477018 -285.910782)
		(stroke
			(width 0.05715)
			(type default)
		)
		(layer "In6.Cu")
	)
	(gr_line
		(start 124.48667 -285.91637)
		(end 124.485908 -285.916116)
		(stroke
			(width 0.05715)
			(type default)
		)
		(layer "In6.Cu")
	)
	(gr_line
		(start 124.491242 -388.774432)
		(end 124.536962 -388.820152)
		(stroke
			(width 0.07112)
			(type default)
		)
		(layer "In6.Cu")
	)
	(gr_line
		(start 124.536962 -388.999984)
		(end 124.3838 -389.153146)
		(stroke
			(width 0.07112)
			(type default)
		)
		(layer "In6.Cu")
	)
	(gr_line
		(start 124.536962 -388.820152)
		(end 124.536962 -388.999984)
		(stroke
			(width 0.07112)
			(type default)
		)
		(layer "In6.Cu")
	)
	(gr_line
		(start 124.571506 -285.745174)
		(end 124.57049 -285.744666)
		(stroke
			(width 0.05715)
			(type default)
		)
		(layer "In6.Cu")
	)
	(gr_line
		(start 124.577094 -285.748476)
		(end 124.573538 -285.746444)
		(stroke
			(width 0.05715)
			(type default)
		)
		(layer "In6.Cu")
	)
	(gr_line
		(start 124.621036 -414.974278)
		(end 125.269244 -415.242756)
		(stroke
			(width 0.07112)
			(type default)
		)
		(layer "In6.Cu")
	)
	(gr_line
		(start 124.624338 -296.37736)
		(end 124.624338 -296.348912)
		(stroke
			(width 0.05715)
			(type default)
		)
		(layer "In6.Cu")
	)
	(gr_line
		(start 124.624338 -296.348912)
		(end 124.670058 -296.303192)
		(stroke
			(width 0.05715)
			(type default)
		)
		(layer "In6.Cu")
	)
	(gr_line
		(start 124.66955 -295.956736)
		(end 124.66955 -295.956228)
		(stroke
			(width 0.05715)
			(type default)
		)
		(layer "In6.Cu")
	)
	(gr_line
		(start 124.730256 -414.712912)
		(end 124.90831 -414.639252)
		(stroke
			(width 0.07112)
			(type default)
		)
		(layer "In6.Cu")
	)
	(gr_line
		(start 124.776484 -389.352536)
		(end 124.584968 -389.352536)
		(stroke
			(width 0.07112)
			(type default)
		)
		(layer "In6.Cu")
	)
	(gr_line
		(start 124.860558 -296.03573)
		(end 124.860558 -296.035222)
		(stroke
			(width 0.05715)
			(type default)
		)
		(layer "In6.Cu")
	)
	(gr_line
		(start 124.891292 -389.467344)
		(end 124.776484 -389.352536)
		(stroke
			(width 0.07112)
			(type default)
		)
		(layer "In6.Cu")
	)
	(gr_line
		(start 124.906278 -296.37736)
		(end 124.906278 -296.348912)
		(stroke
			(width 0.05715)
			(type default)
		)
		(layer "In6.Cu")
	)
	(gr_line
		(start 124.906278 -296.348912)
		(end 124.860558 -296.303192)
		(stroke
			(width 0.05715)
			(type default)
		)
		(layer "In6.Cu")
	)
	(gr_line
		(start 124.90831 -414.639252)
		(end 125.302772 -414.802574)
		(stroke
			(width 0.07112)
			(type default)
		)
		(layer "In6.Cu")
	)
	(gr_line
		(start 124.939552 -394.52042)
		(end 124.939552 -395.22146)
		(stroke
			(width 0.07112)
			(type default)
		)
		(layer "In6.Cu")
	)
	(gr_line
		(start 124.948188 -294.82161)
		(end 124.944378 -294.819324)
		(stroke
			(width 0.05715)
			(type default)
		)
		(layer "In6.Cu")
	)
	(gr_line
		(start 124.948188 -291.581586)
		(end 124.944378 -291.5793)
		(stroke
			(width 0.05715)
			(type default)
		)
		(layer "In6.Cu")
	)
	(gr_line
		(start 124.948188 -285.101792)
		(end 124.944378 -285.099506)
		(stroke
			(width 0.05715)
			(type default)
		)
		(layer "In6.Cu")
	)
	(gr_line
		(start 124.948188 -283.48178)
		(end 124.944378 -283.479494)
		(stroke
			(width 0.05715)
			(type default)
		)
		(layer "In6.Cu")
	)
	(gr_line
		(start 124.949204 -294.822118)
		(end 124.948188 -294.82161)
		(stroke
			(width 0.05715)
			(type default)
		)
		(layer "In6.Cu")
	)
	(gr_line
		(start 124.949204 -291.582094)
		(end 124.948188 -291.581586)
		(stroke
			(width 0.05715)
			(type default)
		)
		(layer "In6.Cu")
	)
	(gr_line
		(start 124.949204 -285.1023)
		(end 124.948188 -285.101792)
		(stroke
			(width 0.05715)
			(type default)
		)
		(layer "In6.Cu")
	)
	(gr_line
		(start 124.949204 -283.482288)
		(end 124.948188 -283.48178)
		(stroke
			(width 0.05715)
			(type default)
		)
		(layer "In6.Cu")
	)
	(gr_line
		(start 124.950728 -294.823134)
		(end 124.949204 -294.822118)
		(stroke
			(width 0.05715)
			(type default)
		)
		(layer "In6.Cu")
	)
	(gr_line
		(start 124.950728 -293.849298)
		(end 124.951744 -293.84879)
		(stroke
			(width 0.05715)
			(type default)
		)
		(layer "In6.Cu")
	)
	(gr_line
		(start 124.950728 -292.229286)
		(end 124.951744 -292.228778)
		(stroke
			(width 0.05715)
			(type default)
		)
		(layer "In6.Cu")
	)
	(gr_line
		(start 124.950728 -291.58311)
		(end 124.949204 -291.582094)
		(stroke
			(width 0.05715)
			(type default)
		)
		(layer "In6.Cu")
	)
	(gr_line
		(start 124.950728 -290.609274)
		(end 124.951744 -290.608766)
		(stroke
			(width 0.05715)
			(type default)
		)
		(layer "In6.Cu")
	)
	(gr_line
		(start 124.950728 -288.989262)
		(end 124.951744 -288.988754)
		(stroke
			(width 0.05715)
			(type default)
		)
		(layer "In6.Cu")
	)
	(gr_line
		(start 124.950728 -285.103316)
		(end 124.949204 -285.1023)
		(stroke
			(width 0.05715)
			(type default)
		)
		(layer "In6.Cu")
	)
	(gr_line
		(start 124.950728 -284.12948)
		(end 124.951744 -284.128972)
		(stroke
			(width 0.05715)
			(type default)
		)
		(layer "In6.Cu")
	)
	(gr_line
		(start 124.950728 -283.483304)
		(end 124.949204 -283.482288)
		(stroke
			(width 0.05715)
			(type default)
		)
		(layer "In6.Cu")
	)
	(gr_line
		(start 124.950728 -282.509468)
		(end 124.951744 -282.50896)
		(stroke
			(width 0.05715)
			(type default)
		)
		(layer "In6.Cu")
	)
	(gr_line
		(start 124.951236 -294.823388)
		(end 124.950728 -294.823134)
		(stroke
			(width 0.05715)
			(type default)
		)
		(layer "In6.Cu")
	)
	(gr_line
		(start 124.951236 -291.583364)
		(end 124.950728 -291.58311)
		(stroke
			(width 0.05715)
			(type default)
		)
		(layer "In6.Cu")
	)
	(gr_line
		(start 124.951236 -285.10357)
		(end 124.950728 -285.103316)
		(stroke
			(width 0.05715)
			(type default)
		)
		(layer "In6.Cu")
	)
	(gr_line
		(start 124.951236 -283.483558)
		(end 124.950728 -283.483304)
		(stroke
			(width 0.05715)
			(type default)
		)
		(layer "In6.Cu")
	)
	(gr_line
		(start 124.951744 -293.84879)
		(end 124.952506 -293.848282)
		(stroke
			(width 0.05715)
			(type default)
		)
		(layer "In6.Cu")
	)
	(gr_line
		(start 124.951744 -292.228778)
		(end 124.952506 -292.22827)
		(stroke
			(width 0.05715)
			(type default)
		)
		(layer "In6.Cu")
	)
	(gr_line
		(start 124.951744 -290.608766)
		(end 124.952506 -290.608258)
		(stroke
			(width 0.05715)
			(type default)
		)
		(layer "In6.Cu")
	)
	(gr_line
		(start 124.951744 -288.988754)
		(end 124.952506 -288.988246)
		(stroke
			(width 0.05715)
			(type default)
		)
		(layer "In6.Cu")
	)
	(gr_line
		(start 124.951744 -284.128972)
		(end 124.952506 -284.128464)
		(stroke
			(width 0.05715)
			(type default)
		)
		(layer "In6.Cu")
	)
	(gr_line
		(start 124.951744 -282.50896)
		(end 124.952506 -282.508452)
		(stroke
			(width 0.05715)
			(type default)
		)
		(layer "In6.Cu")
	)
	(gr_line
		(start 124.952506 -293.848282)
		(end 124.953776 -293.84752)
		(stroke
			(width 0.05715)
			(type default)
		)
		(layer "In6.Cu")
	)
	(gr_line
		(start 124.952506 -292.22827)
		(end 124.953776 -292.227508)
		(stroke
			(width 0.05715)
			(type default)
		)
		(layer "In6.Cu")
	)
	(gr_line
		(start 124.952506 -290.608258)
		(end 124.953776 -290.607496)
		(stroke
			(width 0.05715)
			(type default)
		)
		(layer "In6.Cu")
	)
	(gr_line
		(start 124.952506 -288.988246)
		(end 124.953776 -288.987484)
		(stroke
			(width 0.05715)
			(type default)
		)
		(layer "In6.Cu")
	)
	(gr_line
		(start 124.952506 -284.128464)
		(end 124.953776 -284.127702)
		(stroke
			(width 0.05715)
			(type default)
		)
		(layer "In6.Cu")
	)
	(gr_line
		(start 124.952506 -282.508452)
		(end 124.953776 -282.50769)
		(stroke
			(width 0.05715)
			(type default)
		)
		(layer "In6.Cu")
	)
	(gr_line
		(start 124.953776 -293.2049)
		(end 124.952506 -293.204138)
		(stroke
			(width 0.05715)
			(type default)
		)
		(layer "In6.Cu")
	)
	(gr_line
		(start 124.953776 -289.964876)
		(end 124.952506 -289.964114)
		(stroke
			(width 0.05715)
			(type default)
		)
		(layer "In6.Cu")
	)
	(gr_line
		(start 125.03785 -294.652954)
		(end 125.036834 -294.652446)
		(stroke
			(width 0.05715)
			(type default)
		)
		(layer "In6.Cu")
	)
	(gr_line
		(start 125.03785 -291.41293)
		(end 125.036834 -291.412422)
		(stroke
			(width 0.05715)
			(type default)
		)
		(layer "In6.Cu")
	)
	(gr_line
		(start 125.03785 -284.933136)
		(end 125.036834 -284.932628)
		(stroke
			(width 0.05715)
			(type default)
		)
		(layer "In6.Cu")
	)
	(gr_line
		(start 125.03785 -283.313124)
		(end 125.036834 -283.312616)
		(stroke
			(width 0.05715)
			(type default)
		)
		(layer "In6.Cu")
	)
	(gr_line
		(start 125.038866 -294.653716)
		(end 125.03785 -294.652954)
		(stroke
			(width 0.05715)
			(type default)
		)
		(layer "In6.Cu")
	)
	(gr_line
		(start 125.038866 -291.413692)
		(end 125.03785 -291.41293)
		(stroke
			(width 0.05715)
			(type default)
		)
		(layer "In6.Cu")
	)
	(gr_line
		(start 125.038866 -284.933898)
		(end 125.03785 -284.933136)
		(stroke
			(width 0.05715)
			(type default)
		)
		(layer "In6.Cu")
	)
	(gr_line
		(start 125.038866 -283.313886)
		(end 125.03785 -283.313124)
		(stroke
			(width 0.05715)
			(type default)
		)
		(layer "In6.Cu")
	)
	(gr_line
		(start 125.0442 -294.656764)
		(end 125.043438 -294.656256)
		(stroke
			(width 0.05715)
			(type default)
		)
		(layer "In6.Cu")
	)
	(gr_line
		(start 125.0442 -291.41674)
		(end 125.043438 -291.416232)
		(stroke
			(width 0.05715)
			(type default)
		)
		(layer "In6.Cu")
	)
	(gr_line
		(start 125.0442 -284.936946)
		(end 125.043438 -284.936438)
		(stroke
			(width 0.05715)
			(type default)
		)
		(layer "In6.Cu")
	)
	(gr_line
		(start 125.0442 -283.316934)
		(end 125.043438 -283.316426)
		(stroke
			(width 0.05715)
			(type default)
		)
		(layer "In6.Cu")
	)
	(gr_line
		(start 125.045724 -294.014906)
		(end 125.046994 -294.014144)
		(stroke
			(width 0.05715)
			(type default)
		)
		(layer "In6.Cu")
	)
	(gr_line
		(start 125.045724 -292.394894)
		(end 125.046994 -292.394132)
		(stroke
			(width 0.05715)
			(type default)
		)
		(layer "In6.Cu")
	)
	(gr_line
		(start 125.045724 -290.774882)
		(end 125.046994 -290.77412)
		(stroke
			(width 0.05715)
			(type default)
		)
		(layer "In6.Cu")
	)
	(gr_line
		(start 125.045724 -289.15487)
		(end 125.046994 -289.154108)
		(stroke
			(width 0.05715)
			(type default)
		)
		(layer "In6.Cu")
	)
	(gr_line
		(start 125.045724 -284.295088)
		(end 125.046994 -284.294326)
		(stroke
			(width 0.05715)
			(type default)
		)
		(layer "In6.Cu")
	)
	(gr_line
		(start 125.045724 -282.675076)
		(end 125.046994 -282.674314)
		(stroke
			(width 0.05715)
			(type default)
		)
		(layer "In6.Cu")
	)
	(gr_line
		(start 125.046994 -294.658288)
		(end 125.0442 -294.656764)
		(stroke
			(width 0.05715)
			(type default)
		)
		(layer "In6.Cu")
	)
	(gr_line
		(start 125.046994 -294.014144)
		(end 125.047756 -294.013636)
		(stroke
			(width 0.05715)
			(type default)
		)
		(layer "In6.Cu")
	)
	(gr_line
		(start 125.046994 -292.394132)
		(end 125.047756 -292.393624)
		(stroke
			(width 0.05715)
			(type default)
		)
		(layer "In6.Cu")
	)
	(gr_line
		(start 125.046994 -291.418264)
		(end 125.0442 -291.41674)
		(stroke
			(width 0.05715)
			(type default)
		)
		(layer "In6.Cu")
	)
	(gr_line
		(start 125.046994 -290.77412)
		(end 125.047756 -290.773612)
		(stroke
			(width 0.05715)
			(type default)
		)
		(layer "In6.Cu")
	)
	(gr_line
		(start 125.046994 -289.154108)
		(end 125.047756 -289.1536)
		(stroke
			(width 0.05715)
			(type default)
		)
		(layer "In6.Cu")
	)
	(gr_line
		(start 125.046994 -284.93847)
		(end 125.0442 -284.936946)
		(stroke
			(width 0.05715)
			(type default)
		)
		(layer "In6.Cu")
	)
	(gr_line
		(start 125.046994 -284.294326)
		(end 125.047756 -284.293818)
		(stroke
			(width 0.05715)
			(type default)
		)
		(layer "In6.Cu")
	)
	(gr_line
		(start 125.046994 -283.318458)
		(end 125.0442 -283.316934)
		(stroke
			(width 0.05715)
			(type default)
		)
		(layer "In6.Cu")
	)
	(gr_line
		(start 125.046994 -282.674314)
		(end 125.047756 -282.673806)
		(stroke
			(width 0.05715)
			(type default)
		)
		(layer "In6.Cu")
	)
	(gr_line
		(start 125.047756 -294.658796)
		(end 125.046994 -294.658288)
		(stroke
			(width 0.05715)
			(type default)
		)
		(layer "In6.Cu")
	)
	(gr_line
		(start 125.047756 -294.013636)
		(end 125.048772 -294.013128)
		(stroke
			(width 0.05715)
			(type default)
		)
		(layer "In6.Cu")
	)
	(gr_line
		(start 125.047756 -293.038784)
		(end 125.047248 -293.03853)
		(stroke
			(width 0.05715)
			(type default)
		)
		(layer "In6.Cu")
	)
	(gr_line
		(start 125.047756 -292.393624)
		(end 125.048772 -292.393116)
		(stroke
			(width 0.05715)
			(type default)
		)
		(layer "In6.Cu")
	)
	(gr_line
		(start 125.047756 -291.418772)
		(end 125.046994 -291.418264)
		(stroke
			(width 0.05715)
			(type default)
		)
		(layer "In6.Cu")
	)
	(gr_line
		(start 125.047756 -290.773612)
		(end 125.048772 -290.773104)
		(stroke
			(width 0.05715)
			(type default)
		)
		(layer "In6.Cu")
	)
	(gr_line
		(start 125.047756 -289.79876)
		(end 125.047248 -289.798506)
		(stroke
			(width 0.05715)
			(type default)
		)
		(layer "In6.Cu")
	)
	(gr_line
		(start 125.047756 -289.1536)
		(end 125.048772 -289.153092)
		(stroke
			(width 0.05715)
			(type default)
		)
		(layer "In6.Cu")
	)
	(gr_line
		(start 125.047756 -284.938978)
		(end 125.046994 -284.93847)
		(stroke
			(width 0.05715)
			(type default)
		)
		(layer "In6.Cu")
	)
	(gr_line
		(start 125.047756 -284.293818)
		(end 125.048772 -284.29331)
		(stroke
			(width 0.05715)
			(type default)
		)
		(layer "In6.Cu")
	)
	(gr_line
		(start 125.047756 -283.318966)
		(end 125.046994 -283.318458)
		(stroke
			(width 0.05715)
			(type default)
		)
		(layer "In6.Cu")
	)
	(gr_line
		(start 125.047756 -282.673806)
		(end 125.048772 -282.673298)
		(stroke
			(width 0.05715)
			(type default)
		)
		(layer "In6.Cu")
	)
	(gr_line
		(start 125.048772 -293.039292)
		(end 125.047756 -293.038784)
		(stroke
			(width 0.05715)
			(type default)
		)
		(layer "In6.Cu")
	)
	(gr_line
		(start 125.048772 -289.799268)
		(end 125.047756 -289.79876)
		(stroke
			(width 0.05715)
			(type default)
		)
		(layer "In6.Cu")
	)
	(gr_line
		(start 125.222762 -394.52169)
		(end 125.358652 -394.65758)
		(stroke
			(width 0.07112)
			(type default)
		)
		(layer "In6.Cu")
	)
	(gr_line
		(start 125.269244 -415.242756)
		(end 125.323092 -415.265108)
		(stroke
			(width 0.07112)
			(type default)
		)
		(layer "In6.Cu")
	)
	(gr_line
		(start 125.302772 -414.802574)
		(end 125.376178 -414.980374)
		(stroke
			(width 0.07112)
			(type default)
		)
		(layer "In6.Cu")
	)
	(gr_line
		(start 125.358652 -395.0843)
		(end 125.222762 -395.22019)
		(stroke
			(width 0.07112)
			(type default)
		)
		(layer "In6.Cu")
	)
	(gr_line
		(start 125.358652 -394.65758)
		(end 125.358652 -395.0843)
		(stroke
			(width 0.07112)
			(type default)
		)
		(layer "In6.Cu")
	)
	(gr_line
		(start 125.421898 -295.633648)
		(end 125.421644 -295.633648)
		(stroke
			(width 0.05715)
			(type default)
		)
		(layer "In6.Cu")
	)
	(gr_line
		(start 125.42266 -381.84455)
		(end 126.1237 -381.84455)
		(stroke
			(width 0.07112)
			(type default)
		)
		(layer "In6.Cu")
	)
	(gr_line
		(start 125.42393 -382.12776)
		(end 125.55982 -382.26365)
		(stroke
			(width 0.07112)
			(type default)
		)
		(layer "In6.Cu")
	)
	(gr_line
		(start 125.532642 -284.616398)
		(end 125.2347 -284.616398)
		(stroke
			(width 0.05715)
			(type default)
		)
		(layer "In6.Cu")
	)
	(gr_line
		(start 125.532642 -282.996386)
		(end 125.2347 -282.996386)
		(stroke
			(width 0.05715)
			(type default)
		)
		(layer "In6.Cu")
	)
	(gr_line
		(start 125.532642 -281.376374)
		(end 125.2347 -281.376374)
		(stroke
			(width 0.05715)
			(type default)
		)
		(layer "In6.Cu")
	)
	(gr_line
		(start 125.55982 -382.26365)
		(end 125.98654 -382.26365)
		(stroke
			(width 0.07112)
			(type default)
		)
		(layer "In6.Cu")
	)
	(gr_line
		(start 125.563884 -296.372788)
		(end 125.563884 -296.34434)
		(stroke
			(width 0.05715)
			(type default)
		)
		(layer "In6.Cu")
	)
	(gr_line
		(start 125.563884 -296.34434)
		(end 125.609604 -296.29862)
		(stroke
			(width 0.05715)
			(type default)
		)
		(layer "In6.Cu")
	)
	(gr_line
		(start 125.601984 -281.445716)
		(end 125.532642 -281.376374)
		(stroke
			(width 0.05715)
			(type default)
		)
		(layer "In6.Cu")
	)
	(gr_line
		(start 125.615446 -410.030168)
		(end 125.906276 -410.320998)
		(stroke
			(width 0.07112)
			(type default)
		)
		(layer "In6.Cu")
	)
	(gr_line
		(start 125.615446 -284.699202)
		(end 125.532642 -284.616398)
		(stroke
			(width 0.05715)
			(type default)
		)
		(layer "In6.Cu")
	)
	(gr_arc
		(start 125.615446 -284.699202)
		(mid 125.617239 -284.710524)
		(end 125.619256 -284.721808)
		(stroke
			(width 0.05715)
			(type default)
		)
		(layer "In6.Cu")
	)
	(gr_line
		(start 125.615446 -283.07919)
		(end 125.532642 -282.996386)
		(stroke
			(width 0.05715)
			(type default)
		)
		(layer "In6.Cu")
	)
	(gr_line
		(start 125.6157 -283.07919)
		(end 125.615446 -283.07919)
		(stroke
			(width 0.05715)
			(type default)
		)
		(layer "In6.Cu")
	)
	(gr_arc
		(start 125.6157 -283.07919)
		(mid 125.617493 -283.090385)
		(end 125.61951 -283.101542)
		(stroke
			(width 0.05715)
			(type default)
		)
		(layer "In6.Cu")
	)
	(gr_line
		(start 125.622558 -426.830998)
		(end 125.749812 -426.958252)
		(stroke
			(width 0.07112)
			(type default)
		)
		(layer "In6.Cu")
	)
	(gr_line
		(start 125.622558 -426.548804)
		(end 125.749812 -426.42155)
		(stroke
			(width 0.07112)
			(type default)
		)
		(layer "In6.Cu")
	)
	(gr_line
		(start 125.663198 -415.405824)
		(end 126.311406 -415.674302)
		(stroke
			(width 0.07112)
			(type default)
		)
		(layer "In6.Cu")
	)
	(gr_line
		(start 125.691138 -388.774432)
		(end 125.743462 -388.826756)
		(stroke
			(width 0.07112)
			(type default)
		)
		(layer "In6.Cu")
	)
	(gr_line
		(start 125.743462 -389.006588)
		(end 125.596904 -389.153146)
		(stroke
			(width 0.07112)
			(type default)
		)
		(layer "In6.Cu")
	)
	(gr_line
		(start 125.743462 -388.826756)
		(end 125.743462 -389.006588)
		(stroke
			(width 0.07112)
			(type default)
		)
		(layer "In6.Cu")
	)
	(gr_line
		(start 125.749812 -426.958252)
		(end 125.749812 -427.289976)
		(stroke
			(width 0.07112)
			(type default)
		)
		(layer "In6.Cu")
	)
	(gr_line
		(start 125.749812 -426.42155)
		(end 125.749812 -426.089826)
		(stroke
			(width 0.07112)
			(type default)
		)
		(layer "In6.Cu")
	)
	(gr_line
		(start 125.772672 -415.144712)
		(end 125.950472 -415.070798)
		(stroke
			(width 0.07112)
			(type default)
		)
		(layer "In6.Cu")
	)
	(gr_arc
		(start 125.790198 -281.482038)
		(mid 125.79222 -281.470628)
		(end 125.794008 -281.459178)
		(stroke
			(width 0.05715)
			(type default)
		)
		(layer "In6.Cu")
	)
	(gr_line
		(start 125.794008 -281.459178)
		(end 125.876812 -281.376374)
		(stroke
			(width 0.05715)
			(type default)
		)
		(layer "In6.Cu")
	)
	(gr_line
		(start 125.80747 -284.68574)
		(end 125.876812 -284.616398)
		(stroke
			(width 0.05715)
			(type default)
		)
		(layer "In6.Cu")
	)
	(gr_line
		(start 125.807724 -283.065474)
		(end 125.876812 -282.996386)
		(stroke
			(width 0.05715)
			(type default)
		)
		(layer "In6.Cu")
	)
	(gr_arc
		(start 125.844808 -294.795194)
		(mid 125.848733 -294.798005)
		(end 125.852682 -294.800782)
		(stroke
			(width 0.05715)
			(type default)
		)
		(layer "In6.Cu")
	)
	(gr_arc
		(start 125.844808 -293.175182)
		(mid 125.848733 -293.177993)
		(end 125.852682 -293.18077)
		(stroke
			(width 0.05715)
			(type default)
		)
		(layer "In6.Cu")
	)
	(gr_line
		(start 125.845824 -296.372788)
		(end 125.845824 -296.34434)
		(stroke
			(width 0.05715)
			(type default)
		)
		(layer "In6.Cu")
	)
	(gr_line
		(start 125.845824 -296.34434)
		(end 125.800104 -296.29862)
		(stroke
			(width 0.05715)
			(type default)
		)
		(layer "In6.Cu")
	)
	(gr_arc
		(start 125.853444 -294.80129)
		(mid 125.853063 -294.801036)
		(end 125.852682 -294.800782)
		(stroke
			(width 0.05715)
			(type default)
		)
		(layer "In6.Cu")
	)
	(gr_arc
		(start 125.853444 -293.181278)
		(mid 125.853063 -293.181024)
		(end 125.852682 -293.18077)
		(stroke
			(width 0.05715)
			(type default)
		)
		(layer "In6.Cu")
	)
	(gr_line
		(start 125.86081 -293.185596)
		(end 125.853444 -293.181278)
		(stroke
			(width 0.05715)
			(type default)
		)
		(layer "In6.Cu")
	)
	(gr_line
		(start 125.861064 -294.805608)
		(end 125.853444 -294.80129)
		(stroke
			(width 0.05715)
			(type default)
		)
		(layer "In6.Cu")
	)
	(gr_line
		(start 125.875034 -290.618672)
		(end 125.876558 -290.617656)
		(stroke
			(width 0.05715)
			(type default)
		)
		(layer "In6.Cu")
	)
	(gr_line
		(start 125.876812 -284.616398)
		(end 126.174754 -284.616398)
		(stroke
			(width 0.05715)
			(type default)
		)
		(layer "In6.Cu")
	)
	(gr_line
		(start 125.876812 -282.996386)
		(end 126.174754 -282.996386)
		(stroke
			(width 0.05715)
			(type default)
		)
		(layer "In6.Cu")
	)
	(gr_line
		(start 125.876812 -281.376374)
		(end 126.174754 -281.376374)
		(stroke
			(width 0.05715)
			(type default)
		)
		(layer "In6.Cu")
	)
	(gr_line
		(start 125.885956 -293.852346)
		(end 125.89256 -293.848536)
		(stroke
			(width 0.05715)
			(type default)
		)
		(layer "In6.Cu")
	)
	(gr_line
		(start 125.889766 -291.587682)
		(end 125.889512 -291.587428)
		(stroke
			(width 0.05715)
			(type default)
		)
		(layer "In6.Cu")
	)
	(gr_line
		(start 125.890782 -293.203122)
		(end 125.889004 -293.201852)
		(stroke
			(width 0.05715)
			(type default)
		)
		(layer "In6.Cu")
	)
	(gr_line
		(start 125.892306 -293.204138)
		(end 125.890782 -293.203122)
		(stroke
			(width 0.05715)
			(type default)
		)
		(layer "In6.Cu")
	)
	(gr_line
		(start 125.906276 -406.71369)
		(end 125.615446 -407.00452)
		(stroke
			(width 0.07112)
			(type default)
		)
		(layer "In6.Cu")
	)
	(gr_line
		(start 125.906276 -405.022558)
		(end 125.906276 -405.723598)
		(stroke
			(width 0.07112)
			(type default)
		)
		(layer "In6.Cu")
	)
	(gr_line
		(start 125.908308 -288.353246)
		(end 125.908308 -288.3535)
		(stroke
			(width 0.05715)
			(type default)
		)
		(layer "In6.Cu")
	)
	(gr_line
		(start 125.950472 -415.070798)
		(end 126.344934 -415.23412)
		(stroke
			(width 0.07112)
			(type default)
		)
		(layer "In6.Cu")
	)
	(gr_line
		(start 125.959362 -413.525462)
		(end 125.959616 -413.526224)
		(stroke
			(width 0.07112)
			(type default)
		)
		(layer "In6.Cu")
	)
	(gr_line
		(start 125.97638 -389.352536)
		(end 125.798072 -389.352536)
		(stroke
			(width 0.07112)
			(type default)
		)
		(layer "In6.Cu")
	)
	(gr_line
		(start 125.98527 -293.03726)
		(end 125.984254 -293.036752)
		(stroke
			(width 0.05715)
			(type default)
		)
		(layer "In6.Cu")
	)
	(gr_line
		(start 125.98654 -382.26365)
		(end 126.12243 -382.12776)
		(stroke
			(width 0.07112)
			(type default)
		)
		(layer "In6.Cu")
	)
	(gr_line
		(start 125.987048 -291.423598)
		(end 125.985778 -291.422836)
		(stroke
			(width 0.05715)
			(type default)
		)
		(layer "In6.Cu")
	)
	(gr_arc
		(start 125.99035 -289.154362)
		(mid 125.992512 -289.153097)
		(end 125.994668 -289.151822)
		(stroke
			(width 0.05715)
			(type default)
		)
		(layer "In6.Cu")
	)
	(gr_line
		(start 125.991366 -294.660828)
		(end 125.991874 -294.661082)
		(stroke
			(width 0.05715)
			(type default)
		)
		(layer "In6.Cu")
	)
	(gr_arc
		(start 125.99924 -294.007032)
		(mid 126.001911 -294.005515)
		(end 126.004574 -294.003984)
		(stroke
			(width 0.05715)
			(type default)
		)
		(layer "In6.Cu")
	)
	(gr_arc
		(start 125.99924 -290.767008)
		(mid 126.001911 -290.765491)
		(end 126.004574 -290.76396)
		(stroke
			(width 0.05715)
			(type default)
		)
		(layer "In6.Cu")
	)
	(gr_arc
		(start 126.004574 -293.048436)
		(mid 126.001279 -293.046393)
		(end 125.99797 -293.044372)
		(stroke
			(width 0.05715)
			(type default)
		)
		(layer "In6.Cu")
	)
	(gr_arc
		(start 126.004574 -289.808412)
		(mid 126.001531 -289.806625)
		(end 125.998478 -289.804856)
		(stroke
			(width 0.05715)
			(type default)
		)
		(layer "In6.Cu")
	)
	(gr_line
		(start 126.021338 -288.198306)
		(end 126.01829 -288.196528)
		(stroke
			(width 0.05715)
			(type default)
		)
		(layer "In6.Cu")
	)
	(gr_line
		(start 126.024132 -288.19983)
		(end 126.021338 -288.198306)
		(stroke
			(width 0.05715)
			(type default)
		)
		(layer "In6.Cu")
	)
	(gr_arc
		(start 126.033022 -288.20618)
		(mid 126.028593 -288.202983)
		(end 126.024132 -288.19983)
		(stroke
			(width 0.05715)
			(type default)
		)
		(layer "In6.Cu")
	)
	(gr_line
		(start 126.079504 -283.816298)
		(end 126.079504 -283.815536)
		(stroke
			(width 0.05715)
			(type default)
		)
		(layer "In6.Cu")
	)
	(gr_line
		(start 126.091188 -389.467344)
		(end 125.97638 -389.352536)
		(stroke
			(width 0.07112)
			(type default)
		)
		(layer "In6.Cu")
	)
	(gr_arc
		(start 126.10211 -2.371852)
		(mid 124.3287 -3.106426)
		(end 123.594114 -4.879848)
		(stroke
			(width 0.2)
			(type default)
		)
		(layer "In6.Cu")
	)
	(gr_line
		(start 126.10211 -2.371852)
		(end 194.701922 -2.371852)
		(stroke
			(width 0.2)
			(type default)
		)
		(layer "In6.Cu")
	)
	(gr_line
		(start 126.188216 -406.71369)
		(end 126.479046 -407.00452)
		(stroke
			(width 0.07112)
			(type default)
		)
		(layer "In6.Cu")
	)
	(gr_line
		(start 126.189486 -405.023828)
		(end 126.325376 -405.159718)
		(stroke
			(width 0.07112)
			(type default)
		)
		(layer "In6.Cu")
	)
	(gr_arc
		(start 126.191264 -413.845756)
		(mid 126.190883 -413.845502)
		(end 126.190502 -413.845248)
		(stroke
			(width 0.07112)
			(type default)
		)
		(layer "In6.Cu")
	)
	(gr_line
		(start 126.24181 -23.72614)
		(end 125.54331 -23.72614)
		(stroke
			(width 0.07112)
			(type default)
		)
		(layer "In6.Cu")
	)
	(gr_line
		(start 126.26594 -283.769308)
		(end 126.26594 -283.77007)
		(stroke
			(width 0.05715)
			(type default)
		)
		(layer "In6.Cu")
	)
	(gr_line
		(start 126.266448 -287.081468)
		(end 126.266194 -287.082738)
		(stroke
			(width 0.05715)
			(type default)
		)
		(layer "In6.Cu")
	)
	(gr_line
		(start 126.269242 -283.796232)
		(end 126.269242 -283.79674)
		(stroke
			(width 0.05715)
			(type default)
		)
		(layer "In6.Cu")
	)
	(gr_line
		(start 126.270004 -287.036764)
		(end 126.270004 -287.038542)
		(stroke
			(width 0.05715)
			(type default)
		)
		(layer "In6.Cu")
	)
	(gr_arc
		(start 126.270004 -283.812996)
		(mid 126.269804 -283.80486)
		(end 126.269242 -283.79674)
		(stroke
			(width 0.05715)
			(type default)
		)
		(layer "In6.Cu")
	)
	(gr_line
		(start 126.297182 -327.690734)
		(end 126.297436 -327.691242)
		(stroke
			(width 0.07112)
			(type default)
		)
		(layer "In6.Cu")
	)
	(gr_line
		(start 126.325376 -405.586438)
		(end 126.189486 -405.722328)
		(stroke
			(width 0.07112)
			(type default)
		)
		(layer "In6.Cu")
	)
	(gr_line
		(start 126.325376 -405.159718)
		(end 126.325376 -405.586438)
		(stroke
			(width 0.07112)
			(type default)
		)
		(layer "In6.Cu")
	)
	(gr_arc
		(start 126.325376 -286.579818)
		(mid 126.318738 -286.584469)
		(end 126.312168 -286.589216)
		(stroke
			(width 0.05715)
			(type default)
		)
		(layer "In6.Cu")
	)
	(gr_line
		(start 126.325376 -286.579818)
		(end 126.32817 -286.578294)
		(stroke
			(width 0.05715)
			(type default)
		)
		(layer "In6.Cu")
	)
	(gr_line
		(start 126.344934 -415.23412)
		(end 126.418594 -415.412174)
		(stroke
			(width 0.07112)
			(type default)
		)
		(layer "In6.Cu")
	)
	(gr_line
		(start 126.357126 -284.291024)
		(end 126.355856 -284.290262)
		(stroke
			(width 0.05715)
			(type default)
		)
		(layer "In6.Cu")
	)
	(gr_line
		(start 126.362206 -284.294326)
		(end 126.361698 -284.294072)
		(stroke
			(width 0.05715)
			(type default)
		)
		(layer "In6.Cu")
	)
	(gr_line
		(start 126.36246 -285.914338)
		(end 126.361698 -285.91383)
		(stroke
			(width 0.05715)
			(type default)
		)
		(layer "In6.Cu")
	)
	(gr_line
		(start 126.36373 -285.9151)
		(end 126.36246 -285.914338)
		(stroke
			(width 0.05715)
			(type default)
		)
		(layer "In6.Cu")
	)
	(gr_line
		(start 126.369064 -284.29839)
		(end 126.366016 -284.296866)
		(stroke
			(width 0.05715)
			(type default)
		)
		(layer "In6.Cu")
	)
	(gr_line
		(start 126.393448 -284.312106)
		(end 126.393194 -284.312106)
		(stroke
			(width 0.05715)
			(type default)
		)
		(layer "In6.Cu")
	)
	(gr_line
		(start 126.451868 -284.125416)
		(end 126.450344 -284.124654)
		(stroke
			(width 0.05715)
			(type default)
		)
		(layer "In6.Cu")
	)
	(gr_line
		(start 126.458726 -285.749492)
		(end 126.45771 -285.748984)
		(stroke
			(width 0.05715)
			(type default)
		)
		(layer "In6.Cu")
	)
	(gr_line
		(start 126.460504 -284.130496)
		(end 126.459488 -284.129988)
		(stroke
			(width 0.05715)
			(type default)
		)
		(layer "In6.Cu")
	)
	(gr_line
		(start 126.461774 -295.471088)
		(end 126.459234 -295.469564)
		(stroke
			(width 0.05715)
			(type default)
		)
		(layer "In6.Cu")
	)
	(gr_line
		(start 126.462028 -284.131512)
		(end 126.460504 -284.130496)
		(stroke
			(width 0.05715)
			(type default)
		)
		(layer "In6.Cu")
	)
	(gr_line
		(start 126.463044 -284.13202)
		(end 126.462028 -284.131512)
		(stroke
			(width 0.05715)
			(type default)
		)
		(layer "In6.Cu")
	)
	(gr_line
		(start 126.46406 -284.132528)
		(end 126.463044 -284.13202)
		(stroke
			(width 0.05715)
			(type default)
		)
		(layer "In6.Cu")
	)
	(gr_line
		(start 126.479046 -410.030168)
		(end 126.188216 -410.320998)
		(stroke
			(width 0.07112)
			(type default)
		)
		(layer "In6.Cu")
	)
	(gr_line
		(start 126.489206 -284.14726)
		(end 126.481078 -284.142434)
		(stroke
			(width 0.05715)
			(type default)
		)
		(layer "In6.Cu")
	)
	(gr_line
		(start 126.489968 -284.147768)
		(end 126.489206 -284.14726)
		(stroke
			(width 0.05715)
			(type default)
		)
		(layer "In6.Cu")
	)
	(gr_line
		(start 126.496826 -284.151832)
		(end 126.494286 -284.150308)
		(stroke
			(width 0.05715)
			(type default)
		)
		(layer "In6.Cu")
	)
	(gr_arc
		(start 126.504446 -284.157166)
		(mid 126.500646 -284.154484)
		(end 126.496826 -284.151832)
		(stroke
			(width 0.05715)
			(type default)
		)
		(layer "In6.Cu")
	)
	(gr_line
		(start 126.55042 -381.84455)
		(end 127.25146 -381.84455)
		(stroke
			(width 0.07112)
			(type default)
		)
		(layer "In6.Cu")
	)
	(gr_line
		(start 126.55169 -382.12776)
		(end 126.68758 -382.26365)
		(stroke
			(width 0.07112)
			(type default)
		)
		(layer "In6.Cu")
	)
	(gr_line
		(start 126.594108 -296.55643)
		(end 126.594108 -296.52849)
		(stroke
			(width 0.05715)
			(type default)
		)
		(layer "In6.Cu")
	)
	(gr_line
		(start 126.594108 -296.52849)
		(end 126.639828 -296.48277)
		(stroke
			(width 0.05715)
			(type default)
		)
		(layer "In6.Cu")
	)
	(gr_line
		(start 126.594616 -296.556938)
		(end 126.594108 -296.55643)
		(stroke
			(width 0.05715)
			(type default)
		)
		(layer "In6.Cu")
	)
	(gr_line
		(start 126.61011 -5.787898)
		(end 126.61011 -9.780016)
		(stroke
			(width 0.2)
			(type default)
		)
		(layer "In6.Cu")
	)
	(gr_line
		(start 126.68758 -382.26365)
		(end 127.1143 -382.26365)
		(stroke
			(width 0.07112)
			(type default)
		)
		(layer "In6.Cu")
	)
	(gr_line
		(start 126.70536 -415.837624)
		(end 127.35306 -416.105848)
		(stroke
			(width 0.07112)
			(type default)
		)
		(layer "In6.Cu")
	)
	(gr_line
		(start 126.81458 -415.576258)
		(end 126.99238 -415.502598)
		(stroke
			(width 0.07112)
			(type default)
		)
		(layer "In6.Cu")
	)
	(gr_line
		(start 126.876048 -296.55643)
		(end 126.876048 -296.52849)
		(stroke
			(width 0.05715)
			(type default)
		)
		(layer "In6.Cu")
	)
	(gr_line
		(start 126.876048 -296.52849)
		(end 126.830328 -296.48277)
		(stroke
			(width 0.05715)
			(type default)
		)
		(layer "In6.Cu")
	)
	(gr_line
		(start 126.876556 -296.556938)
		(end 126.876048 -296.55643)
		(stroke
			(width 0.05715)
			(type default)
		)
		(layer "In6.Cu")
	)
	(gr_line
		(start 126.891288 -388.774432)
		(end 126.933452 -388.816596)
		(stroke
			(width 0.07112)
			(type default)
		)
		(layer "In6.Cu")
	)
	(gr_line
		(start 126.933452 -388.996428)
		(end 126.776734 -389.153146)
		(stroke
			(width 0.07112)
			(type default)
		)
		(layer "In6.Cu")
	)
	(gr_line
		(start 126.933452 -388.816596)
		(end 126.933452 -388.996428)
		(stroke
			(width 0.07112)
			(type default)
		)
		(layer "In6.Cu")
	)
	(gr_line
		(start 126.99238 -415.502598)
		(end 127.386842 -415.66592)
		(stroke
			(width 0.07112)
			(type default)
		)
		(layer "In6.Cu")
	)
	(gr_line
		(start 127.1143 -382.26365)
		(end 127.25019 -382.12776)
		(stroke
			(width 0.07112)
			(type default)
		)
		(layer "In6.Cu")
	)
	(gr_line
		(start 127.140716 -414.480248)
		(end 127.7239 -414.870138)
		(stroke
			(width 0.07112)
			(type default)
		)
		(layer "In6.Cu")
	)
	(gr_line
		(start 127.17653 -389.352536)
		(end 126.977902 -389.352536)
		(stroke
			(width 0.07112)
			(type default)
		)
		(layer "In6.Cu")
	)
	(gr_line
		(start 127.288798 -327.757536)
		(end 127.288798 -327.75779)
		(stroke
			(width 0.07112)
			(type default)
		)
		(layer "In6.Cu")
	)
	(gr_line
		(start 127.291338 -389.467344)
		(end 127.17653 -389.352536)
		(stroke
			(width 0.07112)
			(type default)
		)
		(layer "In6.Cu")
	)
	(gr_line
		(start 127.292862 -285.90875)
		(end 127.291592 -285.907988)
		(stroke
			(width 0.05715)
			(type default)
		)
		(layer "In6.Cu")
	)
	(gr_line
		(start 127.293116 -285.90875)
		(end 127.292862 -285.90875)
		(stroke
			(width 0.05715)
			(type default)
		)
		(layer "In6.Cu")
	)
	(gr_line
		(start 127.298958 -414.245552)
		(end 127.48768 -414.20796)
		(stroke
			(width 0.07112)
			(type default)
		)
		(layer "In6.Cu")
	)
	(gr_line
		(start 127.299466 -285.912306)
		(end 127.29464 -285.909512)
		(stroke
			(width 0.05715)
			(type default)
		)
		(layer "In6.Cu")
	)
	(gr_line
		(start 127.301752 -285.913576)
		(end 127.30099 -285.913068)
		(stroke
			(width 0.05715)
			(type default)
		)
		(layer "In6.Cu")
	)
	(gr_line
		(start 127.35306 -416.105848)
		(end 127.353314 -416.106102)
		(stroke
			(width 0.07112)
			(type default)
		)
		(layer "In6.Cu")
	)
	(gr_line
		(start 127.38481 -285.741618)
		(end 127.384048 -285.74111)
		(stroke
			(width 0.05715)
			(type default)
		)
		(layer "In6.Cu")
	)
	(gr_line
		(start 127.385826 -285.742126)
		(end 127.38481 -285.741618)
		(stroke
			(width 0.05715)
			(type default)
		)
		(layer "In6.Cu")
	)
	(gr_line
		(start 127.386842 -415.66592)
		(end 127.460248 -415.84372)
		(stroke
			(width 0.07112)
			(type default)
		)
		(layer "In6.Cu")
	)
	(gr_line
		(start 127.397764 -285.748984)
		(end 127.39624 -285.747968)
		(stroke
			(width 0.05715)
			(type default)
		)
		(layer "In6.Cu")
	)
	(gr_line
		(start 127.399034 -285.749746)
		(end 127.397764 -285.748984)
		(stroke
			(width 0.05715)
			(type default)
		)
		(layer "In6.Cu")
	)
	(gr_line
		(start 127.405892 -285.753556)
		(end 127.404114 -285.75254)
		(stroke
			(width 0.05715)
			(type default)
		)
		(layer "In6.Cu")
	)
	(gr_line
		(start 127.44704 -296.295318)
		(end 127.44704 -296.26687)
		(stroke
			(width 0.05715)
			(type default)
		)
		(layer "In6.Cu")
	)
	(gr_line
		(start 127.44704 -296.26687)
		(end 127.49276 -296.22115)
		(stroke
			(width 0.05715)
			(type default)
		)
		(layer "In6.Cu")
	)
	(gr_line
		(start 127.467868 -23.72614)
		(end 126.769368 -23.72614)
		(stroke
			(width 0.07112)
			(type default)
		)
		(layer "In6.Cu")
	)
	(gr_line
		(start 127.48768 -414.20796)
		(end 127.842772 -414.445196)
		(stroke
			(width 0.07112)
			(type default)
		)
		(layer "In6.Cu")
	)
	(gr_line
		(start 127.622554 -427.830742)
		(end 127.749808 -427.957996)
		(stroke
			(width 0.07112)
			(type default)
		)
		(layer "In6.Cu")
	)
	(gr_line
		(start 127.622554 -427.548802)
		(end 127.749808 -427.421548)
		(stroke
			(width 0.07112)
			(type default)
		)
		(layer "In6.Cu")
	)
	(gr_line
		(start 127.72898 -296.295318)
		(end 127.72898 -296.26687)
		(stroke
			(width 0.05715)
			(type default)
		)
		(layer "In6.Cu")
	)
	(gr_line
		(start 127.72898 -296.26687)
		(end 127.68326 -296.22115)
		(stroke
			(width 0.05715)
			(type default)
		)
		(layer "In6.Cu")
	)
	(gr_line
		(start 127.749808 -427.957996)
		(end 127.749808 -428.28972)
		(stroke
			(width 0.07112)
			(type default)
		)
		(layer "In6.Cu")
	)
	(gr_line
		(start 127.749808 -427.421548)
		(end 127.749808 -427.089824)
		(stroke
			(width 0.07112)
			(type default)
		)
		(layer "In6.Cu")
	)
	(gr_line
		(start 127.842772 -414.445196)
		(end 127.880364 -414.634172)
		(stroke
			(width 0.07112)
			(type default)
		)
		(layer "In6.Cu")
	)
	(gr_line
		(start 128.024382 -416.636454)
		(end 128.520444 -417.132516)
		(stroke
			(width 0.07112)
			(type default)
		)
		(layer "In6.Cu")
	)
	(gr_line
		(start 128.07823 -415.10712)
		(end 128.661668 -415.49701)
		(stroke
			(width 0.07112)
			(type default)
		)
		(layer "In6.Cu")
	)
	(gr_line
		(start 128.091184 -388.774432)
		(end 128.143508 -388.826756)
		(stroke
			(width 0.07112)
			(type default)
		)
		(layer "In6.Cu")
	)
	(gr_line
		(start 128.143508 -389.006588)
		(end 127.99695 -389.153146)
		(stroke
			(width 0.07112)
			(type default)
		)
		(layer "In6.Cu")
	)
	(gr_line
		(start 128.143508 -388.826756)
		(end 128.143508 -389.006588)
		(stroke
			(width 0.07112)
			(type default)
		)
		(layer "In6.Cu")
	)
	(gr_line
		(start 128.22555 -416.437064)
		(end 128.417828 -416.437064)
		(stroke
			(width 0.07112)
			(type default)
		)
		(layer "In6.Cu")
	)
	(gr_line
		(start 128.23444 -308.247288)
		(end 128.234186 -308.247288)
		(stroke
			(width 0.07112)
			(type default)
		)
		(layer "In6.Cu")
	)
	(gr_line
		(start 128.236472 -414.87217)
		(end 128.425448 -414.834578)
		(stroke
			(width 0.07112)
			(type default)
		)
		(layer "In6.Cu")
	)
	(gr_line
		(start 128.298194 -381.84455)
		(end 128.999234 -381.84455)
		(stroke
			(width 0.07112)
			(type default)
		)
		(layer "In6.Cu")
	)
	(gr_line
		(start 128.299464 -382.12776)
		(end 128.435354 -382.26365)
		(stroke
			(width 0.07112)
			(type default)
		)
		(layer "In6.Cu")
	)
	(gr_line
		(start 128.376426 -389.352536)
		(end 128.198118 -389.352536)
		(stroke
			(width 0.07112)
			(type default)
		)
		(layer "In6.Cu")
	)
	(gr_line
		(start 128.417828 -416.437064)
		(end 128.719834 -416.73907)
		(stroke
			(width 0.07112)
			(type default)
		)
		(layer "In6.Cu")
	)
	(gr_line
		(start 128.425448 -414.834578)
		(end 128.78054 -415.072068)
		(stroke
			(width 0.07112)
			(type default)
		)
		(layer "In6.Cu")
	)
	(gr_line
		(start 128.435354 -382.26365)
		(end 128.862074 -382.26365)
		(stroke
			(width 0.07112)
			(type default)
		)
		(layer "In6.Cu")
	)
	(gr_line
		(start 128.491234 -389.467344)
		(end 128.376426 -389.352536)
		(stroke
			(width 0.07112)
			(type default)
		)
		(layer "In6.Cu")
	)
	(gr_line
		(start 128.519428 -341.630508)
		(end 128.519428 -341.630254)
		(stroke
			(width 0.07112)
			(type default)
		)
		(layer "In6.Cu")
	)
	(gr_line
		(start 128.572768 -320.58102)
		(end 128.573022 -320.58102)
		(stroke
			(width 0.07112)
			(type default)
		)
		(layer "In6.Cu")
	)
	(gr_line
		(start 128.678686 -410.030168)
		(end 128.969516 -410.320998)
		(stroke
			(width 0.07112)
			(type default)
		)
		(layer "In6.Cu")
	)
	(gr_line
		(start 128.719834 -416.73907)
		(end 128.719834 -416.931348)
		(stroke
			(width 0.07112)
			(type default)
		)
		(layer "In6.Cu")
	)
	(gr_line
		(start 128.727962 -307.805836)
		(end 128.728216 -307.805836)
		(stroke
			(width 0.07112)
			(type default)
		)
		(layer "In6.Cu")
	)
	(gr_line
		(start 128.78054 -415.072068)
		(end 128.818132 -415.261044)
		(stroke
			(width 0.07112)
			(type default)
		)
		(layer "In6.Cu")
	)
	(gr_line
		(start 128.862074 -382.26365)
		(end 128.997964 -382.12776)
		(stroke
			(width 0.07112)
			(type default)
		)
		(layer "In6.Cu")
	)
	(gr_line
		(start 128.969516 -411.125924)
		(end 128.969516 -411.826964)
		(stroke
			(width 0.07112)
			(type default)
		)
		(layer "In6.Cu")
	)
	(gr_line
		(start 128.969516 -406.71369)
		(end 128.678686 -407.00452)
		(stroke
			(width 0.07112)
			(type default)
		)
		(layer "In6.Cu")
	)
	(gr_line
		(start 128.969516 -405.38019)
		(end 128.969516 -406.08123)
		(stroke
			(width 0.07112)
			(type default)
		)
		(layer "In6.Cu")
	)
	(gr_line
		(start 128.983486 -395.955012)
		(end 129.479548 -396.451074)
		(stroke
			(width 0.07112)
			(type default)
		)
		(layer "In6.Cu")
	)
	(gr_line
		(start 129.016252 -415.733992)
		(end 129.599436 -416.123882)
		(stroke
			(width 0.07112)
			(type default)
		)
		(layer "In6.Cu")
	)
	(gr_line
		(start 129.057654 -301.841916)
		(end 129.057654 -301.84217)
		(stroke
			(width 0.07112)
			(type default)
		)
		(layer "In6.Cu")
	)
	(gr_line
		(start 129.17424 -415.499042)
		(end 129.363216 -415.46145)
		(stroke
			(width 0.07112)
			(type default)
		)
		(layer "In6.Cu")
	)
	(gr_line
		(start 129.184654 -395.755622)
		(end 129.376932 -395.755622)
		(stroke
			(width 0.07112)
			(type default)
		)
		(layer "In6.Cu")
	)
	(gr_line
		(start 129.251456 -406.71369)
		(end 129.542286 -407.00452)
		(stroke
			(width 0.07112)
			(type default)
		)
		(layer "In6.Cu")
	)
	(gr_line
		(start 129.252726 -411.127194)
		(end 129.388616 -411.263084)
		(stroke
			(width 0.07112)
			(type default)
		)
		(layer "In6.Cu")
	)
	(gr_line
		(start 129.252726 -405.38146)
		(end 129.388616 -405.51735)
		(stroke
			(width 0.07112)
			(type default)
		)
		(layer "In6.Cu")
	)
	(gr_line
		(start 129.291334 -388.774432)
		(end 129.343658 -388.826756)
		(stroke
			(width 0.07112)
			(type default)
		)
		(layer "In6.Cu")
	)
	(gr_line
		(start 129.343658 -389.023352)
		(end 129.213864 -389.153146)
		(stroke
			(width 0.07112)
			(type default)
		)
		(layer "In6.Cu")
	)
	(gr_line
		(start 129.343658 -388.826756)
		(end 129.343658 -389.023352)
		(stroke
			(width 0.07112)
			(type default)
		)
		(layer "In6.Cu")
	)
	(gr_line
		(start 129.363216 -415.46145)
		(end 129.718308 -415.69894)
		(stroke
			(width 0.07112)
			(type default)
		)
		(layer "In6.Cu")
	)
	(gr_line
		(start 129.376932 -395.755622)
		(end 129.678938 -396.057628)
		(stroke
			(width 0.07112)
			(type default)
		)
		(layer "In6.Cu")
	)
	(gr_line
		(start 129.388616 -411.689804)
		(end 129.252726 -411.825694)
		(stroke
			(width 0.07112)
			(type default)
		)
		(layer "In6.Cu")
	)
	(gr_line
		(start 129.388616 -411.263084)
		(end 129.388616 -411.689804)
		(stroke
			(width 0.07112)
			(type default)
		)
		(layer "In6.Cu")
	)
	(gr_line
		(start 129.388616 -405.94407)
		(end 129.252726 -406.07996)
		(stroke
			(width 0.07112)
			(type default)
		)
		(layer "In6.Cu")
	)
	(gr_line
		(start 129.388616 -405.51735)
		(end 129.388616 -405.94407)
		(stroke
			(width 0.07112)
			(type default)
		)
		(layer "In6.Cu")
	)
	(gr_line
		(start 129.542286 -410.030168)
		(end 129.251456 -410.320998)
		(stroke
			(width 0.07112)
			(type default)
		)
		(layer "In6.Cu")
	)
	(gr_line
		(start 129.54381 -414.292542)
		(end 129.628392 -414.373314)
		(stroke
			(width 0.07112)
			(type default)
		)
		(layer "In6.Cu")
	)
	(gr_line
		(start 129.576322 -389.352536)
		(end 129.415032 -389.352536)
		(stroke
			(width 0.07112)
			(type default)
		)
		(layer "In6.Cu")
	)
	(gr_line
		(start 129.62255 -426.830998)
		(end 129.749804 -426.958252)
		(stroke
			(width 0.07112)
			(type default)
		)
		(layer "In6.Cu")
	)
	(gr_line
		(start 129.62255 -426.548804)
		(end 129.749804 -426.42155)
		(stroke
			(width 0.07112)
			(type default)
		)
		(layer "In6.Cu")
	)
	(gr_line
		(start 129.628392 -414.373314)
		(end 129.6289 -414.373314)
		(stroke
			(width 0.07112)
			(type default)
		)
		(layer "In6.Cu")
	)
	(gr_line
		(start 129.6289 -414.373314)
		(end 130.052064 -414.776158)
		(stroke
			(width 0.07112)
			(type default)
		)
		(layer "In6.Cu")
	)
	(gr_line
		(start 129.631694 -318.546226)
		(end 129.63144 -318.546226)
		(stroke
			(width 0.07112)
			(type default)
		)
		(layer "In6.Cu")
	)
	(gr_line
		(start 129.678938 -396.057628)
		(end 129.678938 -396.249906)
		(stroke
			(width 0.07112)
			(type default)
		)
		(layer "In6.Cu")
	)
	(gr_line
		(start 129.69113 -389.467344)
		(end 129.576322 -389.352536)
		(stroke
			(width 0.07112)
			(type default)
		)
		(layer "In6.Cu")
	)
	(gr_line
		(start 129.718308 -415.69894)
		(end 129.7559 -415.887662)
		(stroke
			(width 0.07112)
			(type default)
		)
		(layer "In6.Cu")
	)
	(gr_line
		(start 129.739898 -414.088326)
		(end 129.93243 -414.0835)
		(stroke
			(width 0.07112)
			(type default)
		)
		(layer "In6.Cu")
	)
	(gr_line
		(start 129.749804 -426.958252)
		(end 129.749804 -427.289976)
		(stroke
			(width 0.07112)
			(type default)
		)
		(layer "In6.Cu")
	)
	(gr_line
		(start 129.749804 -426.42155)
		(end 129.749804 -426.089826)
		(stroke
			(width 0.07112)
			(type default)
		)
		(layer "In6.Cu")
	)
	(gr_line
		(start 129.93243 -414.0835)
		(end 130.241548 -414.37814)
		(stroke
			(width 0.07112)
			(type default)
		)
		(layer "In6.Cu")
	)
	(gr_line
		(start 130.052064 -414.776158)
		(end 130.360928 -415.07029)
		(stroke
			(width 0.07112)
			(type default)
		)
		(layer "In6.Cu")
	)
	(gr_line
		(start 130.155696 -395.350492)
		(end 130.651758 -395.846554)
		(stroke
			(width 0.07112)
			(type default)
		)
		(layer "In6.Cu")
	)
	(gr_line
		(start 130.241548 -414.37814)
		(end 130.246374 -414.570164)
		(stroke
			(width 0.07112)
			(type default)
		)
		(layer "In6.Cu")
	)
	(gr_line
		(start 130.246374 -414.571942)
		(end 130.555238 -414.866074)
		(stroke
			(width 0.07112)
			(type default)
		)
		(layer "In6.Cu")
	)
	(gr_line
		(start 130.345434 -380.353824)
		(end 130.153156 -380.353824)
		(stroke
			(width 0.07112)
			(type default)
		)
		(layer "In6.Cu")
	)
	(gr_line
		(start 130.356864 -395.151102)
		(end 130.549142 -395.151102)
		(stroke
			(width 0.07112)
			(type default)
		)
		(layer "In6.Cu")
	)
	(gr_line
		(start 130.360928 -415.07029)
		(end 130.868928 -415.553906)
		(stroke
			(width 0.07112)
			(type default)
		)
		(layer "In6.Cu")
	)
	(gr_line
		(start 130.44805 -379.658372)
		(end 129.951988 -380.154434)
		(stroke
			(width 0.07112)
			(type default)
		)
		(layer "In6.Cu")
	)
	(gr_line
		(start 130.469132 -306.963318)
		(end 130.469386 -306.963318)
		(stroke
			(width 0.07112)
			(type default)
		)
		(layer "In6.Cu")
	)
	(gr_line
		(start 130.479292 -403.01545)
		(end 131.139946 -403.251924)
		(stroke
			(width 0.07112)
			(type default)
		)
		(layer "In6.Cu")
	)
	(gr_line
		(start 130.49123 -388.774432)
		(end 130.543554 -388.826756)
		(stroke
			(width 0.07112)
			(type default)
		)
		(layer "In6.Cu")
	)
	(gr_line
		(start 130.543554 -389.006588)
		(end 130.396996 -389.153146)
		(stroke
			(width 0.07112)
			(type default)
		)
		(layer "In6.Cu")
	)
	(gr_line
		(start 130.543554 -388.826756)
		(end 130.543554 -389.006588)
		(stroke
			(width 0.07112)
			(type default)
		)
		(layer "In6.Cu")
	)
	(gr_line
		(start 130.549142 -395.151102)
		(end 130.851148 -395.453108)
		(stroke
			(width 0.07112)
			(type default)
		)
		(layer "In6.Cu")
	)
	(gr_line
		(start 130.557016 -414.866074)
		(end 130.749294 -414.861248)
		(stroke
			(width 0.07112)
			(type default)
		)
		(layer "In6.Cu")
	)
	(gr_line
		(start 130.575558 -402.749258)
		(end 130.749548 -402.666708)
		(stroke
			(width 0.07112)
			(type default)
		)
		(layer "In6.Cu")
	)
	(gr_line
		(start 130.64744 -380.051818)
		(end 130.345434 -380.353824)
		(stroke
			(width 0.07112)
			(type default)
		)
		(layer "In6.Cu")
	)
	(gr_line
		(start 130.64744 -379.85954)
		(end 130.64744 -380.051818)
		(stroke
			(width 0.07112)
			(type default)
		)
		(layer "In6.Cu")
	)
	(gr_line
		(start 130.749294 -414.861248)
		(end 131.058412 -415.155888)
		(stroke
			(width 0.07112)
			(type default)
		)
		(layer "In6.Cu")
	)
	(gr_line
		(start 130.749548 -402.666708)
		(end 131.15163 -402.810472)
		(stroke
			(width 0.07112)
			(type default)
		)
		(layer "In6.Cu")
	)
	(gr_line
		(start 130.776472 -389.352536)
		(end 130.598164 -389.352536)
		(stroke
			(width 0.07112)
			(type default)
		)
		(layer "In6.Cu")
	)
	(gr_line
		(start 130.8481 -417.230052)
		(end 130.863594 -417.253166)
		(stroke
			(width 0.07112)
			(type default)
		)
		(layer "In6.Cu")
	)
	(gr_line
		(start 130.851148 -395.453108)
		(end 130.851148 -395.645386)
		(stroke
			(width 0.07112)
			(type default)
		)
		(layer "In6.Cu")
	)
	(gr_line
		(start 130.863594 -417.253166)
		(end 130.869182 -417.266628)
		(stroke
			(width 0.07112)
			(type default)
		)
		(layer "In6.Cu")
	)
	(gr_line
		(start 130.868928 -415.553906)
		(end 131.177792 -415.848038)
		(stroke
			(width 0.07112)
			(type default)
		)
		(layer "In6.Cu")
	)
	(gr_arc
		(start 130.87477 -417.28009)
		(mid 130.871985 -417.273355)
		(end 130.869182 -417.266628)
		(stroke
			(width 0.07112)
			(type default)
		)
		(layer "In6.Cu")
	)
	(gr_line
		(start 130.89128 -389.467344)
		(end 130.776472 -389.352536)
		(stroke
			(width 0.07112)
			(type default)
		)
		(layer "In6.Cu")
	)
	(gr_line
		(start 131.058412 -415.155888)
		(end 131.063238 -415.347912)
		(stroke
			(width 0.07112)
			(type default)
		)
		(layer "In6.Cu")
	)
	(gr_line
		(start 131.063238 -415.34969)
		(end 131.372102 -415.643822)
		(stroke
			(width 0.07112)
			(type default)
		)
		(layer "In6.Cu")
	)
	(gr_line
		(start 131.142994 -379.556264)
		(end 130.950716 -379.556264)
		(stroke
			(width 0.07112)
			(type default)
		)
		(layer "In6.Cu")
	)
	(gr_line
		(start 131.15163 -402.810472)
		(end 131.233926 -402.984716)
		(stroke
			(width 0.07112)
			(type default)
		)
		(layer "In6.Cu")
	)
	(gr_line
		(start 131.177792 -415.848038)
		(end 131.685792 -416.331654)
		(stroke
			(width 0.07112)
			(type default)
		)
		(layer "In6.Cu")
	)
	(gr_line
		(start 131.24561 -378.860812)
		(end 130.749548 -379.356874)
		(stroke
			(width 0.07112)
			(type default)
		)
		(layer "In6.Cu")
	)
	(gr_line
		(start 131.341114 -325.162926)
		(end 131.321302 -325.125842)
		(stroke
			(width 0.07112)
			(type default)
		)
		(layer "In6.Cu")
	)
	(gr_line
		(start 131.341622 -325.162926)
		(end 131.341114 -325.162926)
		(stroke
			(width 0.07112)
			(type default)
		)
		(layer "In6.Cu")
	)
	(gr_line
		(start 131.350004 -325.204582)
		(end 131.341622 -325.162926)
		(stroke
			(width 0.07112)
			(type default)
		)
		(layer "In6.Cu")
	)
	(gr_line
		(start 131.35102 -306.560728)
		(end 131.351274 -306.560728)
		(stroke
			(width 0.07112)
			(type default)
		)
		(layer "In6.Cu")
	)
	(gr_line
		(start 131.374134 -415.643822)
		(end 131.566158 -415.638996)
		(stroke
			(width 0.07112)
			(type default)
		)
		(layer "In6.Cu")
	)
	(gr_line
		(start 131.445 -379.254258)
		(end 131.142994 -379.556264)
		(stroke
			(width 0.07112)
			(type default)
		)
		(layer "In6.Cu")
	)
	(gr_line
		(start 131.445 -379.06198)
		(end 131.445 -379.254258)
		(stroke
			(width 0.07112)
			(type default)
		)
		(layer "In6.Cu")
	)
	(gr_line
		(start 131.566158 -415.638996)
		(end 131.875276 -415.933636)
		(stroke
			(width 0.07112)
			(type default)
		)
		(layer "In6.Cu")
	)
	(gr_line
		(start 131.622546 -427.830742)
		(end 131.7498 -427.957996)
		(stroke
			(width 0.07112)
			(type default)
		)
		(layer "In6.Cu")
	)
	(gr_line
		(start 131.622546 -427.548802)
		(end 131.7498 -427.421548)
		(stroke
			(width 0.07112)
			(type default)
		)
		(layer "In6.Cu")
	)
	(gr_line
		(start 131.685792 -416.331654)
		(end 131.994656 -416.625532)
		(stroke
			(width 0.07112)
			(type default)
		)
		(layer "In6.Cu")
	)
	(gr_line
		(start 131.69138 -388.774432)
		(end 131.736592 -388.819644)
		(stroke
			(width 0.07112)
			(type default)
		)
		(layer "In6.Cu")
	)
	(gr_line
		(start 131.736592 -388.999476)
		(end 131.582922 -389.153146)
		(stroke
			(width 0.07112)
			(type default)
		)
		(layer "In6.Cu")
	)
	(gr_line
		(start 131.736592 -388.819644)
		(end 131.736592 -388.999476)
		(stroke
			(width 0.07112)
			(type default)
		)
		(layer "In6.Cu")
	)
	(gr_line
		(start 131.741926 -410.030168)
		(end 132.032756 -410.320998)
		(stroke
			(width 0.07112)
			(type default)
		)
		(layer "In6.Cu")
	)
	(gr_line
		(start 131.7498 -427.957996)
		(end 131.7498 -428.28972)
		(stroke
			(width 0.07112)
			(type default)
		)
		(layer "In6.Cu")
	)
	(gr_line
		(start 131.7498 -427.421548)
		(end 131.7498 -427.089824)
		(stroke
			(width 0.07112)
			(type default)
		)
		(layer "In6.Cu")
	)
	(gr_line
		(start 131.875276 -415.933636)
		(end 131.880102 -416.12566)
		(stroke
			(width 0.07112)
			(type default)
		)
		(layer "In6.Cu")
	)
	(gr_line
		(start 131.880102 -416.127438)
		(end 132.188966 -416.42157)
		(stroke
			(width 0.07112)
			(type default)
		)
		(layer "In6.Cu")
	)
	(gr_line
		(start 131.940554 -378.758704)
		(end 131.748276 -378.758704)
		(stroke
			(width 0.07112)
			(type default)
		)
		(layer "In6.Cu")
	)
	(gr_line
		(start 131.976368 -389.352536)
		(end 131.78409 -389.352536)
		(stroke
			(width 0.07112)
			(type default)
		)
		(layer "In6.Cu")
	)
	(gr_line
		(start 131.994656 -416.625532)
		(end 132.502402 -417.109148)
		(stroke
			(width 0.07112)
			(type default)
		)
		(layer "In6.Cu")
	)
	(gr_line
		(start 132.00634 -21.9456)
		(end 131.30784 -21.9456)
		(stroke
			(width 0.07112)
			(type default)
		)
		(layer "In6.Cu")
	)
	(gr_line
		(start 132.032756 -410.994098)
		(end 132.032756 -411.695138)
		(stroke
			(width 0.07112)
			(type default)
		)
		(layer "In6.Cu")
	)
	(gr_line
		(start 132.032756 -406.71369)
		(end 131.741926 -407.00452)
		(stroke
			(width 0.07112)
			(type default)
		)
		(layer "In6.Cu")
	)
	(gr_line
		(start 132.032756 -405.366982)
		(end 132.032756 -406.068022)
		(stroke
			(width 0.07112)
			(type default)
		)
		(layer "In6.Cu")
	)
	(gr_line
		(start 132.04317 -378.063252)
		(end 131.547108 -378.559314)
		(stroke
			(width 0.07112)
			(type default)
		)
		(layer "In6.Cu")
	)
	(gr_line
		(start 132.091176 -389.467344)
		(end 131.976368 -389.352536)
		(stroke
			(width 0.07112)
			(type default)
		)
		(layer "In6.Cu")
	)
	(gr_line
		(start 132.110226 -311.484264)
		(end 132.105146 -311.476898)
		(stroke
			(width 0.07112)
			(type default)
		)
		(layer "In6.Cu")
	)
	(gr_line
		(start 132.190998 -416.42157)
		(end 132.383022 -416.416744)
		(stroke
			(width 0.07112)
			(type default)
		)
		(layer "In6.Cu")
	)
	(gr_line
		(start 132.24256 -378.456698)
		(end 131.940554 -378.758704)
		(stroke
			(width 0.07112)
			(type default)
		)
		(layer "In6.Cu")
	)
	(gr_line
		(start 132.24256 -378.26442)
		(end 132.24256 -378.456698)
		(stroke
			(width 0.07112)
			(type default)
		)
		(layer "In6.Cu")
	)
	(gr_line
		(start 132.314696 -406.71369)
		(end 132.605526 -407.00452)
		(stroke
			(width 0.07112)
			(type default)
		)
		(layer "In6.Cu")
	)
	(gr_line
		(start 132.315966 -410.995368)
		(end 132.451856 -411.131258)
		(stroke
			(width 0.07112)
			(type default)
		)
		(layer "In6.Cu")
	)
	(gr_line
		(start 132.315966 -405.368252)
		(end 132.451856 -405.504142)
		(stroke
			(width 0.07112)
			(type default)
		)
		(layer "In6.Cu")
	)
	(gr_line
		(start 132.383022 -416.416744)
		(end 132.692394 -416.71113)
		(stroke
			(width 0.07112)
			(type default)
		)
		(layer "In6.Cu")
	)
	(gr_line
		(start 132.451856 -411.557978)
		(end 132.315966 -411.693868)
		(stroke
			(width 0.07112)
			(type default)
		)
		(layer "In6.Cu")
	)
	(gr_line
		(start 132.451856 -411.131258)
		(end 132.451856 -411.557978)
		(stroke
			(width 0.07112)
			(type default)
		)
		(layer "In6.Cu")
	)
	(gr_line
		(start 132.451856 -405.930862)
		(end 132.315966 -406.066752)
		(stroke
			(width 0.07112)
			(type default)
		)
		(layer "In6.Cu")
	)
	(gr_line
		(start 132.451856 -405.504142)
		(end 132.451856 -405.930862)
		(stroke
			(width 0.07112)
			(type default)
		)
		(layer "In6.Cu")
	)
	(gr_line
		(start 132.597398 -414.167066)
		(end 132.662168 -414.264094)
		(stroke
			(width 0.07112)
			(type default)
		)
		(layer "In6.Cu")
	)
	(gr_line
		(start 132.605526 -410.030168)
		(end 132.314696 -410.320998)
		(stroke
			(width 0.07112)
			(type default)
		)
		(layer "In6.Cu")
	)
	(gr_line
		(start 132.662422 -414.264348)
		(end 132.662168 -414.264094)
		(stroke
			(width 0.07112)
			(type default)
		)
		(layer "In6.Cu")
	)
	(gr_line
		(start 132.662422 -414.264348)
		(end 132.987034 -414.75025)
		(stroke
			(width 0.07112)
			(type default)
		)
		(layer "In6.Cu")
	)
	(gr_line
		(start 132.692394 -416.71113)
		(end 132.696966 -416.903154)
		(stroke
			(width 0.07112)
			(type default)
		)
		(layer "In6.Cu")
	)
	(gr_line
		(start 132.738114 -377.961144)
		(end 132.545836 -377.961144)
		(stroke
			(width 0.07112)
			(type default)
		)
		(layer "In6.Cu")
	)
	(gr_line
		(start 132.833364 -414.010602)
		(end 133.022086 -414.048194)
		(stroke
			(width 0.07112)
			(type default)
		)
		(layer "In6.Cu")
	)
	(gr_line
		(start 132.84073 -377.265692)
		(end 132.344668 -377.761754)
		(stroke
			(width 0.07112)
			(type default)
		)
		(layer "In6.Cu")
	)
	(gr_line
		(start 132.891276 -388.774432)
		(end 132.9436 -388.826756)
		(stroke
			(width 0.07112)
			(type default)
		)
		(layer "In6.Cu")
	)
	(gr_line
		(start 132.9436 -389.006588)
		(end 132.797042 -389.153146)
		(stroke
			(width 0.07112)
			(type default)
		)
		(layer "In6.Cu")
	)
	(gr_line
		(start 132.9436 -388.826756)
		(end 132.9436 -389.006588)
		(stroke
			(width 0.07112)
			(type default)
		)
		(layer "In6.Cu")
	)
	(gr_line
		(start 133.022086 -414.048194)
		(end 133.259576 -414.403286)
		(stroke
			(width 0.07112)
			(type default)
		)
		(layer "In6.Cu")
	)
	(gr_line
		(start 133.04012 -377.659138)
		(end 132.738114 -377.961144)
		(stroke
			(width 0.07112)
			(type default)
		)
		(layer "In6.Cu")
	)
	(gr_line
		(start 133.04012 -377.46686)
		(end 133.04012 -377.659138)
		(stroke
			(width 0.07112)
			(type default)
		)
		(layer "In6.Cu")
	)
	(gr_line
		(start 133.176518 -389.352536)
		(end 132.99821 -389.352536)
		(stroke
			(width 0.07112)
			(type default)
		)
		(layer "In6.Cu")
	)
	(gr_line
		(start 133.224016 -415.104834)
		(end 133.613652 -415.688018)
		(stroke
			(width 0.07112)
			(type default)
		)
		(layer "In6.Cu")
	)
	(gr_line
		(start 133.259576 -414.403286)
		(end 133.221984 -414.592008)
		(stroke
			(width 0.07112)
			(type default)
		)
		(layer "In6.Cu")
	)
	(gr_line
		(start 133.291326 -389.467344)
		(end 133.176518 -389.352536)
		(stroke
			(width 0.07112)
			(type default)
		)
		(layer "In6.Cu")
	)
	(gr_line
		(start 133.459982 -414.94837)
		(end 133.648958 -414.985962)
		(stroke
			(width 0.07112)
			(type default)
		)
		(layer "In6.Cu")
	)
	(gr_line
		(start 133.511798 -402.85924)
		(end 134.159752 -403.127718)
		(stroke
			(width 0.07112)
			(type default)
		)
		(layer "In6.Cu")
	)
	(gr_line
		(start 133.619748 -402.598382)
		(end 133.619748 -402.598636)
		(stroke
			(width 0.07112)
			(type default)
		)
		(layer "In6.Cu")
	)
	(gr_line
		(start 133.621272 -402.598128)
		(end 133.799072 -402.524468)
		(stroke
			(width 0.07112)
			(type default)
		)
		(layer "In6.Cu")
	)
	(gr_line
		(start 133.622542 -426.830998)
		(end 133.749796 -426.958252)
		(stroke
			(width 0.07112)
			(type default)
		)
		(layer "In6.Cu")
	)
	(gr_line
		(start 133.622542 -426.548804)
		(end 133.749796 -426.42155)
		(stroke
			(width 0.07112)
			(type default)
		)
		(layer "In6.Cu")
	)
	(gr_line
		(start 133.648958 -414.985962)
		(end 133.886194 -415.341054)
		(stroke
			(width 0.07112)
			(type default)
		)
		(layer "In6.Cu")
	)
	(gr_line
		(start 133.654292 -391.977372)
		(end 133.654292 -391.978388)
		(stroke
			(width 0.07112)
			(type default)
		)
		(layer "In6.Cu")
	)
	(gr_line
		(start 133.72084 -25.62733)
		(end 133.78434 -25.62733)
		(stroke
			(width 0.07112)
			(type default)
		)
		(layer "In6.Cu")
	)
	(gr_line
		(start 133.749796 -426.958252)
		(end 133.749796 -427.289976)
		(stroke
			(width 0.07112)
			(type default)
		)
		(layer "In6.Cu")
	)
	(gr_line
		(start 133.749796 -426.42155)
		(end 133.749796 -426.089826)
		(stroke
			(width 0.07112)
			(type default)
		)
		(layer "In6.Cu")
	)
	(gr_line
		(start 133.770116 -320.315336)
		(end 133.77037 -320.315336)
		(stroke
			(width 0.07112)
			(type default)
		)
		(layer "In6.Cu")
	)
	(gr_line
		(start 133.78434 -25.62733)
		(end 134.07517 -25.3365)
		(stroke
			(width 0.07112)
			(type default)
		)
		(layer "In6.Cu")
	)
	(gr_line
		(start 133.799072 -402.524468)
		(end 134.193534 -402.68779)
		(stroke
			(width 0.07112)
			(type default)
		)
		(layer "In6.Cu")
	)
	(gr_line
		(start 133.850634 -416.042856)
		(end 133.971538 -416.223704)
		(stroke
			(width 0.07112)
			(type default)
		)
		(layer "In6.Cu")
	)
	(gr_line
		(start 133.886194 -415.341054)
		(end 133.848602 -415.53003)
		(stroke
			(width 0.07112)
			(type default)
		)
		(layer "In6.Cu")
	)
	(gr_line
		(start 133.971792 -416.223704)
		(end 133.971538 -416.223704)
		(stroke
			(width 0.07112)
			(type default)
		)
		(layer "In6.Cu")
	)
	(gr_line
		(start 133.971792 -416.223704)
		(end 134.24027 -416.625786)
		(stroke
			(width 0.07112)
			(type default)
		)
		(layer "In6.Cu")
	)
	(gr_line
		(start 134.019544 -23.417784)
		(end 133.541516 -22.939756)
		(stroke
			(width 0.07112)
			(type default)
		)
		(layer "In6.Cu")
	)
	(gr_line
		(start 134.0866 -415.886138)
		(end 134.275576 -415.92373)
		(stroke
			(width 0.07112)
			(type default)
		)
		(layer "In6.Cu")
	)
	(gr_line
		(start 134.14756 -324.438772)
		(end 134.14375 -324.428358)
		(stroke
			(width 0.07112)
			(type default)
		)
		(layer "In6.Cu")
	)
	(gr_line
		(start 134.15137 -324.449186)
		(end 134.14756 -324.438772)
		(stroke
			(width 0.07112)
			(type default)
		)
		(layer "In6.Cu")
	)
	(gr_line
		(start 134.155688 -324.470776)
		(end 134.15137 -324.449186)
		(stroke
			(width 0.07112)
			(type default)
		)
		(layer "In6.Cu")
	)
	(gr_line
		(start 134.159752 -403.127718)
		(end 134.160006 -403.127464)
		(stroke
			(width 0.07112)
			(type default)
		)
		(layer "In6.Cu")
	)
	(gr_line
		(start 134.193534 -402.68779)
		(end 134.267194 -402.86559)
		(stroke
			(width 0.07112)
			(type default)
		)
		(layer "In6.Cu")
	)
	(gr_line
		(start 134.240524 -416.625786)
		(end 134.24027 -416.625786)
		(stroke
			(width 0.07112)
			(type default)
		)
		(layer "In6.Cu")
	)
	(gr_line
		(start 134.267702 -402.867114)
		(end 134.267702 -402.86686)
		(stroke
			(width 0.07112)
			(type default)
		)
		(layer "In6.Cu")
	)
	(gr_line
		(start 134.275576 -415.92373)
		(end 134.512812 -416.278822)
		(stroke
			(width 0.07112)
			(type default)
		)
		(layer "In6.Cu")
	)
	(gr_line
		(start 134.36981 -305.774344)
		(end 134.370064 -305.774344)
		(stroke
			(width 0.07112)
			(type default)
		)
		(layer "In6.Cu")
	)
	(gr_line
		(start 134.512812 -416.278822)
		(end 134.47522 -416.467798)
		(stroke
			(width 0.07112)
			(type default)
		)
		(layer "In6.Cu")
	)
	(gr_line
		(start 134.805166 -410.030168)
		(end 135.095996 -410.320998)
		(stroke
			(width 0.07112)
			(type default)
		)
		(layer "In6.Cu")
	)
	(gr_line
		(start 134.821422 -310.346852)
		(end 134.816342 -310.339486)
		(stroke
			(width 0.07112)
			(type default)
		)
		(layer "In6.Cu")
	)
	(gr_line
		(start 135.095996 -411.08884)
		(end 135.095996 -411.78988)
		(stroke
			(width 0.07112)
			(type default)
		)
		(layer "In6.Cu")
	)
	(gr_line
		(start 135.095996 -406.71369)
		(end 134.805166 -407.00452)
		(stroke
			(width 0.07112)
			(type default)
		)
		(layer "In6.Cu")
	)
	(gr_line
		(start 135.095996 -405.234648)
		(end 135.095996 -405.935688)
		(stroke
			(width 0.07112)
			(type default)
		)
		(layer "In6.Cu")
	)
	(gr_line
		(start 135.2804 -413.978852)
		(end 135.325104 -414.087056)
		(stroke
			(width 0.07112)
			(type default)
		)
		(layer "In6.Cu")
	)
	(gr_line
		(start 135.325104 -414.087056)
		(end 135.325612 -414.08731)
		(stroke
			(width 0.07112)
			(type default)
		)
		(layer "In6.Cu")
	)
	(gr_line
		(start 135.325612 -414.08731)
		(end 135.549132 -414.626806)
		(stroke
			(width 0.07112)
			(type default)
		)
		(layer "In6.Cu")
	)
	(gr_line
		(start 135.377936 -406.71369)
		(end 135.668766 -407.00452)
		(stroke
			(width 0.07112)
			(type default)
		)
		(layer "In6.Cu")
	)
	(gr_line
		(start 135.379206 -411.09011)
		(end 135.515096 -411.226)
		(stroke
			(width 0.07112)
			(type default)
		)
		(layer "In6.Cu")
	)
	(gr_line
		(start 135.379206 -405.235918)
		(end 135.515096 -405.371808)
		(stroke
			(width 0.07112)
			(type default)
		)
		(layer "In6.Cu")
	)
	(gr_line
		(start 135.515096 -411.65272)
		(end 135.379206 -411.78861)
		(stroke
			(width 0.07112)
			(type default)
		)
		(layer "In6.Cu")
	)
	(gr_line
		(start 135.515096 -411.226)
		(end 135.515096 -411.65272)
		(stroke
			(width 0.07112)
			(type default)
		)
		(layer "In6.Cu")
	)
	(gr_line
		(start 135.515096 -405.798528)
		(end 135.379206 -405.934418)
		(stroke
			(width 0.07112)
			(type default)
		)
		(layer "In6.Cu")
	)
	(gr_line
		(start 135.515096 -405.371808)
		(end 135.515096 -405.798528)
		(stroke
			(width 0.07112)
			(type default)
		)
		(layer "In6.Cu")
	)
	(gr_line
		(start 135.516366 -402.447506)
		(end 136.16432 -402.715984)
		(stroke
			(width 0.07112)
			(type default)
		)
		(layer "In6.Cu")
	)
	(gr_line
		(start 135.542528 -413.871664)
		(end 135.720582 -413.945324)
		(stroke
			(width 0.07112)
			(type default)
		)
		(layer "In6.Cu")
	)
	(gr_line
		(start 135.616696 -427.54296)
		(end 135.622792 -427.54296)
		(stroke
			(width 0.07112)
			(type default)
		)
		(layer "In6.Cu")
	)
	(gr_line
		(start 135.617966 -427.82617)
		(end 135.749792 -427.957996)
		(stroke
			(width 0.07112)
			(type default)
		)
		(layer "In6.Cu")
	)
	(gr_line
		(start 135.622792 -427.54296)
		(end 135.749792 -427.41596)
		(stroke
			(width 0.07112)
			(type default)
		)
		(layer "In6.Cu")
	)
	(gr_line
		(start 135.625586 -402.186394)
		(end 135.803386 -402.112734)
		(stroke
			(width 0.07112)
			(type default)
		)
		(layer "In6.Cu")
	)
	(gr_line
		(start 135.630666 -414.823656)
		(end 135.712454 -415.021014)
		(stroke
			(width 0.07112)
			(type default)
		)
		(layer "In6.Cu")
	)
	(gr_line
		(start 135.668766 -410.030168)
		(end 135.377936 -410.320998)
		(stroke
			(width 0.07112)
			(type default)
		)
		(layer "In6.Cu")
	)
	(gr_line
		(start 135.712454 -415.021014)
		(end 135.980678 -415.668968)
		(stroke
			(width 0.07112)
			(type default)
		)
		(layer "In6.Cu")
	)
	(gr_line
		(start 135.720582 -413.945324)
		(end 135.883904 -414.339786)
		(stroke
			(width 0.07112)
			(type default)
		)
		(layer "In6.Cu")
	)
	(gr_line
		(start 135.749792 -427.957996)
		(end 135.749792 -428.28972)
		(stroke
			(width 0.07112)
			(type default)
		)
		(layer "In6.Cu")
	)
	(gr_line
		(start 135.749792 -427.41596)
		(end 135.749792 -427.089824)
		(stroke
			(width 0.07112)
			(type default)
		)
		(layer "In6.Cu")
	)
	(gr_line
		(start 135.803386 -402.112734)
		(end 136.197848 -402.276056)
		(stroke
			(width 0.07112)
			(type default)
		)
		(layer "In6.Cu")
	)
	(gr_line
		(start 135.883904 -414.339786)
		(end 135.810244 -414.517586)
		(stroke
			(width 0.07112)
			(type default)
		)
		(layer "In6.Cu")
	)
	(gr_line
		(start 135.891016 -414.715706)
		(end 135.972804 -414.913318)
		(stroke
			(width 0.07112)
			(type default)
		)
		(layer "In6.Cu")
	)
	(gr_line
		(start 135.974582 -414.91408)
		(end 136.152382 -414.987486)
		(stroke
			(width 0.07112)
			(type default)
		)
		(layer "In6.Cu")
	)
	(gr_line
		(start 135.980678 -415.668968)
		(end 136.144 -416.063176)
		(stroke
			(width 0.07112)
			(type default)
		)
		(layer "In6.Cu")
	)
	(gr_line
		(start 136.144 -416.063176)
		(end 136.412478 -416.71113)
		(stroke
			(width 0.07112)
			(type default)
		)
		(layer "In6.Cu")
	)
	(gr_line
		(start 136.152382 -414.987486)
		(end 136.315704 -415.381948)
		(stroke
			(width 0.07112)
			(type default)
		)
		(layer "In6.Cu")
	)
	(gr_line
		(start 136.197848 -402.276056)
		(end 136.271762 -402.453856)
		(stroke
			(width 0.07112)
			(type default)
		)
		(layer "In6.Cu")
	)
	(gr_line
		(start 136.241282 -415.561272)
		(end 136.40435 -415.95548)
		(stroke
			(width 0.07112)
			(type default)
		)
		(layer "In6.Cu")
	)
	(gr_line
		(start 136.315704 -415.381948)
		(end 136.242044 -415.559494)
		(stroke
			(width 0.07112)
			(type default)
		)
		(layer "In6.Cu")
	)
	(gr_line
		(start 136.406382 -415.956242)
		(end 136.583928 -416.029648)
		(stroke
			(width 0.07112)
			(type default)
		)
		(layer "In6.Cu")
	)
	(gr_line
		(start 136.445498 -387.582156)
		(end 137.146538 -387.582156)
		(stroke
			(width 0.07112)
			(type default)
		)
		(layer "In6.Cu")
	)
	(gr_line
		(start 136.446768 -387.865366)
		(end 136.582658 -388.001256)
		(stroke
			(width 0.07112)
			(type default)
		)
		(layer "In6.Cu")
	)
	(gr_line
		(start 136.558528 -402.879306)
		(end 137.206482 -403.147784)
		(stroke
			(width 0.07112)
			(type default)
		)
		(layer "In6.Cu")
	)
	(gr_line
		(start 136.582658 -388.001256)
		(end 137.009378 -388.001256)
		(stroke
			(width 0.07112)
			(type default)
		)
		(layer "In6.Cu")
	)
	(gr_line
		(start 136.583928 -416.029648)
		(end 136.74725 -416.42411)
		(stroke
			(width 0.07112)
			(type default)
		)
		(layer "In6.Cu")
	)
	(gr_line
		(start 136.667494 -402.61794)
		(end 136.845548 -402.54428)
		(stroke
			(width 0.07112)
			(type default)
		)
		(layer "In6.Cu")
	)
	(gr_line
		(start 136.74725 -416.42411)
		(end 136.67359 -416.60191)
		(stroke
			(width 0.07112)
			(type default)
		)
		(layer "In6.Cu")
	)
	(gr_line
		(start 136.845548 -402.54428)
		(end 137.24001 -402.707602)
		(stroke
			(width 0.07112)
			(type default)
		)
		(layer "In6.Cu")
	)
	(gr_line
		(start 137.009378 -388.001256)
		(end 137.145268 -387.865366)
		(stroke
			(width 0.07112)
			(type default)
		)
		(layer "In6.Cu")
	)
	(gr_line
		(start 137.24001 -402.707602)
		(end 137.313416 -402.885656)
		(stroke
			(width 0.07112)
			(type default)
		)
		(layer "In6.Cu")
	)
	(gr_line
		(start 137.59307 -426.860208)
		(end 137.622788 -426.860208)
		(stroke
			(width 0.07112)
			(type default)
		)
		(layer "In6.Cu")
	)
	(gr_line
		(start 137.59434 -426.576998)
		(end 137.749788 -426.42155)
		(stroke
			(width 0.07112)
			(type default)
		)
		(layer "In6.Cu")
	)
	(gr_line
		(start 137.622788 -426.860208)
		(end 137.749788 -426.987208)
		(stroke
			(width 0.07112)
			(type default)
		)
		(layer "In6.Cu")
	)
	(gr_line
		(start 137.749788 -426.987208)
		(end 137.749788 -427.289976)
		(stroke
			(width 0.07112)
			(type default)
		)
		(layer "In6.Cu")
	)
	(gr_line
		(start 137.749788 -426.42155)
		(end 137.749788 -426.089826)
		(stroke
			(width 0.07112)
			(type default)
		)
		(layer "In6.Cu")
	)
	(gr_line
		(start 137.860278 -402.18106)
		(end 138.508232 -402.449538)
		(stroke
			(width 0.07112)
			(type default)
		)
		(layer "In6.Cu")
	)
	(gr_line
		(start 137.868406 -410.030168)
		(end 138.159236 -410.320998)
		(stroke
			(width 0.07112)
			(type default)
		)
		(layer "In6.Cu")
	)
	(gr_line
		(start 137.969752 -401.919948)
		(end 138.147552 -401.846034)
		(stroke
			(width 0.07112)
			(type default)
		)
		(layer "In6.Cu")
	)
	(gr_line
		(start 138.147552 -401.846034)
		(end 138.542014 -402.009356)
		(stroke
			(width 0.07112)
			(type default)
		)
		(layer "In6.Cu")
	)
	(gr_line
		(start 138.159236 -406.71369)
		(end 137.868406 -407.00452)
		(stroke
			(width 0.07112)
			(type default)
		)
		(layer "In6.Cu")
	)
	(gr_line
		(start 138.202416 -413.52851)
		(end 138.27125 -414.226502)
		(stroke
			(width 0.07112)
			(type default)
		)
		(layer "In6.Cu")
	)
	(gr_line
		(start 138.312906 -414.650936)
		(end 138.38174 -415.349182)
		(stroke
			(width 0.07112)
			(type default)
		)
		(layer "In6.Cu")
	)
	(gr_line
		(start 138.42365 -415.773362)
		(end 138.492484 -416.471608)
		(stroke
			(width 0.07112)
			(type default)
		)
		(layer "In6.Cu")
	)
	(gr_line
		(start 138.441176 -406.71369)
		(end 138.732006 -407.00452)
		(stroke
			(width 0.07112)
			(type default)
		)
		(layer "In6.Cu")
	)
	(gr_line
		(start 138.484356 -413.502348)
		(end 138.6332 -413.624268)
		(stroke
			(width 0.07112)
			(type default)
		)
		(layer "In6.Cu")
	)
	(gr_line
		(start 138.542014 -402.009356)
		(end 138.61542 -402.18741)
		(stroke
			(width 0.07112)
			(type default)
		)
		(layer "In6.Cu")
	)
	(gr_line
		(start 138.5951 -414.624774)
		(end 138.743944 -414.746694)
		(stroke
			(width 0.07112)
			(type default)
		)
		(layer "In6.Cu")
	)
	(gr_line
		(start 138.6332 -413.624268)
		(end 138.674856 -414.04921)
		(stroke
			(width 0.07112)
			(type default)
		)
		(layer "In6.Cu")
	)
	(gr_line
		(start 138.674856 -414.04921)
		(end 138.552936 -414.1978)
		(stroke
			(width 0.07112)
			(type default)
		)
		(layer "In6.Cu")
	)
	(gr_line
		(start 138.70559 -415.746946)
		(end 138.854434 -415.86912)
		(stroke
			(width 0.07112)
			(type default)
		)
		(layer "In6.Cu")
	)
	(gr_line
		(start 138.732006 -410.030168)
		(end 138.441176 -410.320998)
		(stroke
			(width 0.07112)
			(type default)
		)
		(layer "In6.Cu")
	)
	(gr_line
		(start 138.743944 -414.746694)
		(end 138.7856 -415.171636)
		(stroke
			(width 0.07112)
			(type default)
		)
		(layer "In6.Cu")
	)
	(gr_line
		(start 138.748262 -370.206778)
		(end 138.457432 -369.915948)
		(stroke
			(width 0.07112)
			(type default)
		)
		(layer "In6.Cu")
	)
	(gr_line
		(start 138.748262 -369.343178)
		(end 138.457432 -369.634008)
		(stroke
			(width 0.07112)
			(type default)
		)
		(layer "In6.Cu")
	)
	(gr_line
		(start 138.7856 -415.171636)
		(end 138.663426 -415.32048)
		(stroke
			(width 0.07112)
			(type default)
		)
		(layer "In6.Cu")
	)
	(gr_line
		(start 138.854434 -415.86912)
		(end 138.896344 -416.294062)
		(stroke
			(width 0.07112)
			(type default)
		)
		(layer "In6.Cu")
	)
	(gr_line
		(start 138.896344 -416.294062)
		(end 138.77417 -416.442906)
		(stroke
			(width 0.07112)
			(type default)
		)
		(layer "In6.Cu")
	)
	(gr_line
		(start 139.307316 -341.726266)
		(end 139.30376 -341.707978)
		(stroke
			(width 0.07112)
			(type default)
		)
		(layer "In6.Cu")
	)
	(gr_line
		(start 139.313158 -341.743792)
		(end 139.307316 -341.726266)
		(stroke
			(width 0.07112)
			(type default)
		)
		(layer "In6.Cu")
	)
	(gr_line
		(start 139.313412 -341.743792)
		(end 139.313158 -341.743792)
		(stroke
			(width 0.07112)
			(type default)
		)
		(layer "In6.Cu")
	)
	(gr_line
		(start 139.62253 -427.830742)
		(end 139.749784 -427.957996)
		(stroke
			(width 0.07112)
			(type default)
		)
		(layer "In6.Cu")
	)
	(gr_line
		(start 139.62253 -427.548802)
		(end 139.749784 -427.421548)
		(stroke
			(width 0.07112)
			(type default)
		)
		(layer "In6.Cu")
	)
	(gr_line
		(start 139.671044 -395.294104)
		(end 139.783566 -395.325346)
		(stroke
			(width 0.07112)
			(type default)
		)
		(layer "In6.Cu")
	)
	(gr_line
		(start 139.674346 -402.932392)
		(end 140.3223 -403.20087)
		(stroke
			(width 0.07112)
			(type default)
		)
		(layer "In6.Cu")
	)
	(gr_line
		(start 139.747498 -395.021562)
		(end 139.915138 -394.92682)
		(stroke
			(width 0.07112)
			(type default)
		)
		(layer "In6.Cu")
	)
	(gr_line
		(start 139.749784 -427.957996)
		(end 139.749784 -428.28972)
		(stroke
			(width 0.07112)
			(type default)
		)
		(layer "In6.Cu")
	)
	(gr_line
		(start 139.749784 -427.421548)
		(end 139.749784 -427.089824)
		(stroke
			(width 0.07112)
			(type default)
		)
		(layer "In6.Cu")
	)
	(gr_line
		(start 139.783566 -402.67128)
		(end 139.961366 -402.59762)
		(stroke
			(width 0.07112)
			(type default)
		)
		(layer "In6.Cu")
	)
	(gr_line
		(start 139.783566 -395.3256)
		(end 140.346938 -395.481556)
		(stroke
			(width 0.07112)
			(type default)
		)
		(layer "In6.Cu")
	)
	(gr_line
		(start 139.783566 -395.325346)
		(end 139.783566 -395.3256)
		(stroke
			(width 0.07112)
			(type default)
		)
		(layer "In6.Cu")
	)
	(gr_line
		(start 139.915138 -394.92682)
		(end 140.326618 -395.040612)
		(stroke
			(width 0.07112)
			(type default)
		)
		(layer "In6.Cu")
	)
	(gr_line
		(start 139.961366 -402.59762)
		(end 140.355828 -402.760942)
		(stroke
			(width 0.07112)
			(type default)
		)
		(layer "In6.Cu")
	)
	(gr_line
		(start 140.104114 -330.248768)
		(end 140.104114 -330.248514)
		(stroke
			(width 0.07112)
			(type default)
		)
		(layer "In6.Cu")
	)
	(gr_line
		(start 140.104114 -330.248514)
		(end 140.104368 -330.248514)
		(stroke
			(width 0.07112)
			(type default)
		)
		(layer "In6.Cu")
	)
	(gr_line
		(start 140.104368 -330.248768)
		(end 140.104114 -330.248768)
		(stroke
			(width 0.07112)
			(type default)
		)
		(layer "In6.Cu")
	)
	(gr_line
		(start 140.3223 -403.20087)
		(end 140.322554 -403.20087)
		(stroke
			(width 0.07112)
			(type default)
		)
		(layer "In6.Cu")
	)
	(gr_line
		(start 140.326618 -395.040612)
		(end 140.42136 -395.208252)
		(stroke
			(width 0.07112)
			(type default)
		)
		(layer "In6.Cu")
	)
	(gr_line
		(start 140.355828 -402.760942)
		(end 140.429742 -402.938742)
		(stroke
			(width 0.07112)
			(type default)
		)
		(layer "In6.Cu")
	)
	(gr_line
		(start 140.526516 -373.385334)
		(end 140.526262 -373.384572)
		(stroke
			(width 0.07112)
			(type default)
		)
		(layer "In6.Cu")
	)
	(gr_line
		(start 140.619734 -387.498844)
		(end 140.910564 -387.789674)
		(stroke
			(width 0.07112)
			(type default)
		)
		(layer "In6.Cu")
	)
	(gr_line
		(start 140.619734 -387.216904)
		(end 140.910564 -386.926074)
		(stroke
			(width 0.07112)
			(type default)
		)
		(layer "In6.Cu")
	)
	(gr_line
		(start 140.63218 -402.027644)
		(end 141.280134 -402.296122)
		(stroke
			(width 0.07112)
			(type default)
		)
		(layer "In6.Cu")
	)
	(gr_line
		(start 140.741654 -401.766532)
		(end 140.9192 -401.692872)
		(stroke
			(width 0.07112)
			(type default)
		)
		(layer "In6.Cu")
	)
	(gr_line
		(start 140.9192 -401.692872)
		(end 141.313662 -401.856194)
		(stroke
			(width 0.07112)
			(type default)
		)
		(layer "In6.Cu")
	)
	(gr_line
		(start 140.931646 -410.030168)
		(end 141.222476 -410.320998)
		(stroke
			(width 0.07112)
			(type default)
		)
		(layer "In6.Cu")
	)
	(gr_line
		(start 141.222476 -411.217618)
		(end 141.222476 -411.918658)
		(stroke
			(width 0.07112)
			(type default)
		)
		(layer "In6.Cu")
	)
	(gr_line
		(start 141.222476 -406.71369)
		(end 140.931646 -407.00452)
		(stroke
			(width 0.07112)
			(type default)
		)
		(layer "In6.Cu")
	)
	(gr_line
		(start 141.243812 -413.671004)
		(end 141.278356 -414.371536)
		(stroke
			(width 0.07112)
			(type default)
		)
		(layer "In6.Cu")
	)
	(gr_line
		(start 141.280134 -402.296122)
		(end 141.284198 -402.297646)
		(stroke
			(width 0.07112)
			(type default)
		)
		(layer "In6.Cu")
	)
	(gr_line
		(start 141.299184 -414.797494)
		(end 141.333474 -415.498026)
		(stroke
			(width 0.07112)
			(type default)
		)
		(layer "In6.Cu")
	)
	(gr_line
		(start 141.313662 -401.856194)
		(end 141.387068 -402.03374)
		(stroke
			(width 0.07112)
			(type default)
		)
		(layer "In6.Cu")
	)
	(gr_line
		(start 141.354556 -415.923984)
		(end 141.388846 -416.624516)
		(stroke
			(width 0.07112)
			(type default)
		)
		(layer "In6.Cu")
	)
	(gr_line
		(start 141.38783 -402.035518)
		(end 141.392148 -402.037296)
		(stroke
			(width 0.07112)
			(type default)
		)
		(layer "In6.Cu")
	)
	(gr_line
		(start 141.409674 -417.050474)
		(end 141.444218 -417.751006)
		(stroke
			(width 0.07112)
			(type default)
		)
		(layer "In6.Cu")
	)
	(gr_line
		(start 141.504416 -406.71369)
		(end 141.795246 -407.00452)
		(stroke
			(width 0.07112)
			(type default)
		)
		(layer "In6.Cu")
	)
	(gr_line
		(start 141.50467 -413.23133)
		(end 141.504416 -413.23133)
		(stroke
			(width 0.07112)
			(type default)
		)
		(layer "In6.Cu")
	)
	(gr_line
		(start 141.505686 -411.218888)
		(end 141.641576 -411.354778)
		(stroke
			(width 0.07112)
			(type default)
		)
		(layer "In6.Cu")
	)
	(gr_line
		(start 141.524736 -413.642302)
		(end 141.525498 -413.657288)
		(stroke
			(width 0.07112)
			(type default)
		)
		(layer "In6.Cu")
	)
	(gr_line
		(start 141.526768 -413.658558)
		(end 141.669516 -413.78759)
		(stroke
			(width 0.07112)
			(type default)
		)
		(layer "In6.Cu")
	)
	(gr_line
		(start 141.527276 -372.093998)
		(end 141.525752 -372.090442)
		(stroke
			(width 0.07112)
			(type default)
		)
		(layer "In6.Cu")
	)
	(gr_line
		(start 141.58214 -414.784794)
		(end 141.724888 -414.91408)
		(stroke
			(width 0.07112)
			(type default)
		)
		(layer "In6.Cu")
	)
	(gr_line
		(start 141.637512 -415.911284)
		(end 141.78026 -416.04057)
		(stroke
			(width 0.07112)
			(type default)
		)
		(layer "In6.Cu")
	)
	(gr_line
		(start 141.641576 -411.781498)
		(end 141.505686 -411.917388)
		(stroke
			(width 0.07112)
			(type default)
		)
		(layer "In6.Cu")
	)
	(gr_line
		(start 141.641576 -411.354778)
		(end 141.641576 -411.781498)
		(stroke
			(width 0.07112)
			(type default)
		)
		(layer "In6.Cu")
	)
	(gr_line
		(start 141.669516 -413.78759)
		(end 141.690344 -414.214056)
		(stroke
			(width 0.07112)
			(type default)
		)
		(layer "In6.Cu")
	)
	(gr_line
		(start 141.674088 -402.45919)
		(end 142.322042 -402.727668)
		(stroke
			(width 0.07112)
			(type default)
		)
		(layer "In6.Cu")
	)
	(gr_line
		(start 141.690344 -414.214056)
		(end 141.561058 -414.35655)
		(stroke
			(width 0.07112)
			(type default)
		)
		(layer "In6.Cu")
	)
	(gr_line
		(start 141.69263 -417.037774)
		(end 141.835632 -417.16706)
		(stroke
			(width 0.07112)
			(type default)
		)
		(layer "In6.Cu")
	)
	(gr_line
		(start 141.724888 -414.91408)
		(end 141.745716 -415.340546)
		(stroke
			(width 0.07112)
			(type default)
		)
		(layer "In6.Cu")
	)
	(gr_line
		(start 141.745716 -415.340546)
		(end 141.61643 -415.483294)
		(stroke
			(width 0.07112)
			(type default)
		)
		(layer "In6.Cu")
	)
	(gr_line
		(start 141.78026 -416.04057)
		(end 141.801088 -416.467036)
		(stroke
			(width 0.07112)
			(type default)
		)
		(layer "In6.Cu")
	)
	(gr_line
		(start 141.783562 -402.198078)
		(end 141.961108 -402.124418)
		(stroke
			(width 0.07112)
			(type default)
		)
		(layer "In6.Cu")
	)
	(gr_line
		(start 141.795246 -410.030168)
		(end 141.504416 -410.320998)
		(stroke
			(width 0.07112)
			(type default)
		)
		(layer "In6.Cu")
	)
	(gr_line
		(start 141.801088 -416.467036)
		(end 141.671802 -416.609784)
		(stroke
			(width 0.07112)
			(type default)
		)
		(layer "In6.Cu")
	)
	(gr_line
		(start 141.808454 -337.369404)
		(end 141.808454 -337.369658)
		(stroke
			(width 0.07112)
			(type default)
		)
		(layer "In6.Cu")
	)
	(gr_line
		(start 141.835632 -417.16706)
		(end 141.85646 -417.593526)
		(stroke
			(width 0.07112)
			(type default)
		)
		(layer "In6.Cu")
	)
	(gr_line
		(start 141.85646 -417.593526)
		(end 141.72692 -417.736274)
		(stroke
			(width 0.07112)
			(type default)
		)
		(layer "In6.Cu")
	)
	(gr_line
		(start 141.92377 -329.695048)
		(end 141.924024 -329.695048)
		(stroke
			(width 0.07112)
			(type default)
		)
		(layer "In6.Cu")
	)
	(gr_line
		(start 141.961108 -402.124418)
		(end 142.35557 -402.28774)
		(stroke
			(width 0.07112)
			(type default)
		)
		(layer "In6.Cu")
	)
	(gr_line
		(start 142.074646 -335.248758)
		(end 142.0749 -335.248758)
		(stroke
			(width 0.07112)
			(type default)
		)
		(layer "In6.Cu")
	)
	(gr_line
		(start 142.0749 -335.249012)
		(end 142.074646 -335.248758)
		(stroke
			(width 0.07112)
			(type default)
		)
		(layer "In6.Cu")
	)
	(gr_line
		(start 142.267432 -329.976988)
		(end 142.267686 -329.976988)
		(stroke
			(width 0.07112)
			(type default)
		)
		(layer "In6.Cu")
	)
	(gr_line
		(start 142.351506 -335.194148)
		(end 142.35176 -335.194148)
		(stroke
			(width 0.07112)
			(type default)
		)
		(layer "In6.Cu")
	)
	(gr_line
		(start 142.35176 -335.194148)
		(end 142.351506 -335.193386)
		(stroke
			(width 0.07112)
			(type default)
		)
		(layer "In6.Cu")
	)
	(gr_line
		(start 142.35557 -402.28774)
		(end 142.428976 -402.465286)
		(stroke
			(width 0.07112)
			(type default)
		)
		(layer "In6.Cu")
	)
	(gr_line
		(start 142.429738 -402.467318)
		(end 142.429738 -402.467064)
		(stroke
			(width 0.07112)
			(type default)
		)
		(layer "In6.Cu")
	)
	(gr_line
		(start 142.429738 -402.467064)
		(end 142.429992 -402.467318)
		(stroke
			(width 0.07112)
			(type default)
		)
		(layer "In6.Cu")
	)
	(gr_line
		(start 142.429992 -402.467318)
		(end 142.429992 -402.467064)
		(stroke
			(width 0.07112)
			(type default)
		)
		(layer "In6.Cu")
	)
	(gr_line
		(start 142.622778 -426.830998)
		(end 142.750032 -426.958252)
		(stroke
			(width 0.07112)
			(type default)
		)
		(layer "In6.Cu")
	)
	(gr_line
		(start 142.622778 -426.548804)
		(end 142.750032 -426.42155)
		(stroke
			(width 0.07112)
			(type default)
		)
		(layer "In6.Cu")
	)
	(gr_line
		(start 142.71625 -402.89099)
		(end 143.36395 -403.159214)
		(stroke
			(width 0.07112)
			(type default)
		)
		(layer "In6.Cu")
	)
	(gr_line
		(start 142.73022 -374.453404)
		(end 142.749778 -374.261888)
		(stroke
			(width 0.07112)
			(type default)
		)
		(layer "In6.Cu")
	)
	(gr_line
		(start 142.750032 -426.958252)
		(end 142.750032 -427.289976)
		(stroke
			(width 0.07112)
			(type default)
		)
		(layer "In6.Cu")
	)
	(gr_line
		(start 142.750032 -426.42155)
		(end 142.750032 -426.089826)
		(stroke
			(width 0.07112)
			(type default)
		)
		(layer "In6.Cu")
	)
	(gr_line
		(start 142.825724 -402.629624)
		(end 143.00327 -402.555964)
		(stroke
			(width 0.07112)
			(type default)
		)
		(layer "In6.Cu")
	)
	(gr_line
		(start 143.000222 -374.784366)
		(end 142.73022 -374.453404)
		(stroke
			(width 0.07112)
			(type default)
		)
		(layer "In6.Cu")
	)
	(gr_line
		(start 143.00327 -402.555964)
		(end 143.397732 -402.71954)
		(stroke
			(width 0.07112)
			(type default)
		)
		(layer "In6.Cu")
	)
	(gr_line
		(start 143.191992 -374.803924)
		(end 143.000222 -374.784366)
		(stroke
			(width 0.07112)
			(type default)
		)
		(layer "In6.Cu")
	)
	(gr_line
		(start 143.36395 -403.159214)
		(end 143.364204 -403.159468)
		(stroke
			(width 0.07112)
			(type default)
		)
		(layer "In6.Cu")
	)
	(gr_line
		(start 143.397732 -402.71954)
		(end 143.471138 -402.897086)
		(stroke
			(width 0.07112)
			(type default)
		)
		(layer "In6.Cu")
	)
	(gr_line
		(start 143.411956 -374.62587)
		(end 142.968726 -374.08231)
		(stroke
			(width 0.07112)
			(type default)
		)
		(layer "In6.Cu")
	)
	(gr_line
		(start 143.443198 -375.327672)
		(end 143.462502 -375.135902)
		(stroke
			(width 0.07112)
			(type default)
		)
		(layer "In6.Cu")
	)
	(gr_line
		(start 143.7132 -375.658634)
		(end 143.443198 -375.327672)
		(stroke
			(width 0.07112)
			(type default)
		)
		(layer "In6.Cu")
	)
	(gr_line
		(start 143.734536 -402.091398)
		(end 144.389602 -402.341842)
		(stroke
			(width 0.07112)
			(type default)
		)
		(layer "In6.Cu")
	)
	(gr_line
		(start 143.80718 -370.068094)
		(end 143.806672 -370.06784)
		(stroke
			(width 0.07112)
			(type default)
		)
		(layer "In6.Cu")
	)
	(gr_line
		(start 143.836644 -401.827238)
		(end 144.012158 -401.748752)
		(stroke
			(width 0.07112)
			(type default)
		)
		(layer "In6.Cu")
	)
	(gr_line
		(start 143.904716 -375.677938)
		(end 143.7132 -375.658634)
		(stroke
			(width 0.07112)
			(type default)
		)
		(layer "In6.Cu")
	)
	(gr_line
		(start 143.994886 -410.030168)
		(end 144.285716 -410.320998)
		(stroke
			(width 0.07112)
			(type default)
		)
		(layer "In6.Cu")
	)
	(gr_line
		(start 144.012158 -401.748752)
		(end 144.411192 -401.900898)
		(stroke
			(width 0.07112)
			(type default)
		)
		(layer "In6.Cu")
	)
	(gr_line
		(start 144.107916 -416.634422)
		(end 144.107408 -416.634676)
		(stroke
			(width 0.07112)
			(type default)
		)
		(layer "In6.Cu")
	)
	(gr_line
		(start 144.107916 -416.63239)
		(end 144.107916 -416.634422)
		(stroke
			(width 0.07112)
			(type default)
		)
		(layer "In6.Cu")
	)
	(gr_line
		(start 144.124934 -375.499884)
		(end 143.68145 -374.956324)
		(stroke
			(width 0.07112)
			(type default)
		)
		(layer "In6.Cu")
	)
	(gr_line
		(start 144.14246 -415.931858)
		(end 144.107916 -416.63239)
		(stroke
			(width 0.07112)
			(type default)
		)
		(layer "In6.Cu")
	)
	(gr_line
		(start 144.156176 -376.201686)
		(end 144.17548 -376.01017)
		(stroke
			(width 0.07112)
			(type default)
		)
		(layer "In6.Cu")
	)
	(gr_line
		(start 144.163288 -415.5059)
		(end 144.14246 -415.931858)
		(stroke
			(width 0.07112)
			(type default)
		)
		(layer "In6.Cu")
	)
	(gr_line
		(start 144.197832 -414.805368)
		(end 144.163288 -415.5059)
		(stroke
			(width 0.07112)
			(type default)
		)
		(layer "In6.Cu")
	)
	(gr_line
		(start 144.21866 -414.37941)
		(end 144.197832 -414.805368)
		(stroke
			(width 0.07112)
			(type default)
		)
		(layer "In6.Cu")
	)
	(gr_line
		(start 144.253204 -413.678878)
		(end 144.21866 -414.37941)
		(stroke
			(width 0.07112)
			(type default)
		)
		(layer "In6.Cu")
	)
	(gr_line
		(start 144.285716 -411.19425)
		(end 144.285716 -411.89529)
		(stroke
			(width 0.07112)
			(type default)
		)
		(layer "In6.Cu")
	)
	(gr_line
		(start 144.285716 -406.71369)
		(end 143.994886 -407.00452)
		(stroke
			(width 0.07112)
			(type default)
		)
		(layer "In6.Cu")
	)
	(gr_line
		(start 144.389348 -416.646106)
		(end 144.389348 -416.648392)
		(stroke
			(width 0.07112)
			(type default)
		)
		(layer "In6.Cu")
	)
	(gr_line
		(start 144.411192 -401.900898)
		(end 144.489424 -402.07692)
		(stroke
			(width 0.07112)
			(type default)
		)
		(layer "In6.Cu")
	)
	(gr_line
		(start 144.425162 -415.947098)
		(end 144.554194 -416.089338)
		(stroke
			(width 0.07112)
			(type default)
		)
		(layer "In6.Cu")
	)
	(gr_line
		(start 144.426178 -376.532648)
		(end 144.156176 -376.201686)
		(stroke
			(width 0.07112)
			(type default)
		)
		(layer "In6.Cu")
	)
	(gr_line
		(start 144.437862 -332.442312)
		(end 144.438116 -332.442312)
		(stroke
			(width 0.07112)
			(type default)
		)
		(layer "In6.Cu")
	)
	(gr_line
		(start 144.44472 -415.519616)
		(end 144.423892 -415.945574)
		(stroke
			(width 0.07112)
			(type default)
		)
		(layer "In6.Cu")
	)
	(gr_line
		(start 144.480534 -414.820608)
		(end 144.609566 -414.962848)
		(stroke
			(width 0.07112)
			(type default)
		)
		(layer "In6.Cu")
	)
	(gr_line
		(start 144.500092 -414.393126)
		(end 144.479264 -414.819084)
		(stroke
			(width 0.07112)
			(type default)
		)
		(layer "In6.Cu")
	)
	(gr_line
		(start 144.533366 -416.515804)
		(end 144.390872 -416.644582)
		(stroke
			(width 0.07112)
			(type default)
		)
		(layer "In6.Cu")
	)
	(gr_line
		(start 144.535906 -413.693864)
		(end 144.665192 -413.836358)
		(stroke
			(width 0.07112)
			(type default)
		)
		(layer "In6.Cu")
	)
	(gr_line
		(start 144.554194 -416.089338)
		(end 144.533366 -416.515804)
		(stroke
			(width 0.07112)
			(type default)
		)
		(layer "In6.Cu")
	)
	(gr_line
		(start 144.567656 -406.71369)
		(end 144.858486 -407.00452)
		(stroke
			(width 0.07112)
			(type default)
		)
		(layer "In6.Cu")
	)
	(gr_line
		(start 144.568926 -411.19552)
		(end 144.704816 -411.33141)
		(stroke
			(width 0.07112)
			(type default)
		)
		(layer "In6.Cu")
	)
	(gr_line
		(start 144.588738 -415.389314)
		(end 144.446244 -415.518092)
		(stroke
			(width 0.07112)
			(type default)
		)
		(layer "In6.Cu")
	)
	(gr_line
		(start 144.609566 -414.962848)
		(end 144.588738 -415.389314)
		(stroke
			(width 0.07112)
			(type default)
		)
		(layer "In6.Cu")
	)
	(gr_line
		(start 144.616932 -427.54296)
		(end 144.623028 -427.54296)
		(stroke
			(width 0.07112)
			(type default)
		)
		(layer "In6.Cu")
	)
	(gr_line
		(start 144.61744 -376.551952)
		(end 144.426178 -376.532648)
		(stroke
			(width 0.07112)
			(type default)
		)
		(layer "In6.Cu")
	)
	(gr_line
		(start 144.618202 -427.82617)
		(end 144.750028 -427.957996)
		(stroke
			(width 0.07112)
			(type default)
		)
		(layer "In6.Cu")
	)
	(gr_line
		(start 144.623028 -427.54296)
		(end 144.750028 -427.41596)
		(stroke
			(width 0.07112)
			(type default)
		)
		(layer "In6.Cu")
	)
	(gr_line
		(start 144.635474 -371.211602)
		(end 144.63522 -371.211856)
		(stroke
			(width 0.07112)
			(type default)
		)
		(layer "In6.Cu")
	)
	(gr_line
		(start 144.64411 -414.262824)
		(end 144.501616 -414.391602)
		(stroke
			(width 0.07112)
			(type default)
		)
		(layer "In6.Cu")
	)
	(gr_line
		(start 144.665192 -413.836358)
		(end 144.64411 -414.262824)
		(stroke
			(width 0.07112)
			(type default)
		)
		(layer "In6.Cu")
	)
	(gr_line
		(start 144.704816 -411.75813)
		(end 144.568926 -411.89402)
		(stroke
			(width 0.07112)
			(type default)
		)
		(layer "In6.Cu")
	)
	(gr_line
		(start 144.704816 -411.33141)
		(end 144.704816 -411.75813)
		(stroke
			(width 0.07112)
			(type default)
		)
		(layer "In6.Cu")
	)
	(gr_line
		(start 144.750028 -427.957996)
		(end 144.750028 -428.28972)
		(stroke
			(width 0.07112)
			(type default)
		)
		(layer "In6.Cu")
	)
	(gr_line
		(start 144.750028 -427.41596)
		(end 144.750028 -427.089824)
		(stroke
			(width 0.07112)
			(type default)
		)
		(layer "In6.Cu")
	)
	(gr_line
		(start 144.788128 -402.494242)
		(end 145.443194 -402.744686)
		(stroke
			(width 0.07112)
			(type default)
		)
		(layer "In6.Cu")
	)
	(gr_line
		(start 144.837658 -376.373898)
		(end 144.394428 -375.830338)
		(stroke
			(width 0.07112)
			(type default)
		)
		(layer "In6.Cu")
	)
	(gr_line
		(start 144.858486 -410.030168)
		(end 144.567656 -410.320998)
		(stroke
			(width 0.07112)
			(type default)
		)
		(layer "In6.Cu")
	)
	(gr_line
		(start 144.889982 -402.230082)
		(end 145.06575 -402.151342)
		(stroke
			(width 0.07112)
			(type default)
		)
		(layer "In6.Cu")
	)
	(gr_line
		(start 145.06575 -402.151342)
		(end 145.464784 -402.303742)
		(stroke
			(width 0.07112)
			(type default)
		)
		(layer "In6.Cu")
	)
	(gr_line
		(start 145.464784 -402.303742)
		(end 145.543016 -402.479764)
		(stroke
			(width 0.07112)
			(type default)
		)
		(layer "In6.Cu")
	)
	(gr_line
		(start 145.534634 -399.303494)
		(end 146.195034 -399.539714)
		(stroke
			(width 0.07112)
			(type default)
		)
		(layer "In6.Cu")
	)
	(gr_line
		(start 145.630646 -399.037048)
		(end 145.805144 -398.954752)
		(stroke
			(width 0.07112)
			(type default)
		)
		(layer "In6.Cu")
	)
	(gr_line
		(start 145.805144 -398.954752)
		(end 146.206972 -399.098516)
		(stroke
			(width 0.07112)
			(type default)
		)
		(layer "In6.Cu")
	)
	(gr_line
		(start 145.84172 -402.897086)
		(end 146.496786 -403.14753)
		(stroke
			(width 0.07112)
			(type default)
		)
		(layer "In6.Cu")
	)
	(gr_line
		(start 145.943574 -402.632926)
		(end 146.119342 -402.55444)
		(stroke
			(width 0.07112)
			(type default)
		)
		(layer "In6.Cu")
	)
	(gr_line
		(start 146.007836 -397.048228)
		(end 146.683984 -397.235172)
		(stroke
			(width 0.07112)
			(type default)
		)
		(layer "In6.Cu")
	)
	(gr_line
		(start 146.055842 -373.059198)
		(end 146.073876 -372.632478)
		(stroke
			(width 0.07112)
			(type default)
		)
		(layer "In6.Cu")
	)
	(gr_line
		(start 146.073876 -372.632478)
		(end 146.215862 -372.502176)
		(stroke
			(width 0.07112)
			(type default)
		)
		(layer "In6.Cu")
	)
	(gr_line
		(start 146.08429 -396.775432)
		(end 146.251676 -396.680436)
		(stroke
			(width 0.07112)
			(type default)
		)
		(layer "In6.Cu")
	)
	(gr_line
		(start 146.103594 -371.9322)
		(end 146.121628 -371.50548)
		(stroke
			(width 0.07112)
			(type default)
		)
		(layer "In6.Cu")
	)
	(gr_line
		(start 146.119342 -402.55444)
		(end 146.518122 -402.70684)
		(stroke
			(width 0.07112)
			(type default)
		)
		(layer "In6.Cu")
	)
	(gr_line
		(start 146.121628 -371.50548)
		(end 146.26336 -371.375432)
		(stroke
			(width 0.07112)
			(type default)
		)
		(layer "In6.Cu")
	)
	(gr_line
		(start 146.1516 -370.805202)
		(end 146.169634 -370.378482)
		(stroke
			(width 0.07112)
			(type default)
		)
		(layer "In6.Cu")
	)
	(gr_line
		(start 146.169634 -370.378482)
		(end 146.311112 -370.248434)
		(stroke
			(width 0.07112)
			(type default)
		)
		(layer "In6.Cu")
	)
	(gr_line
		(start 146.186144 -373.20093)
		(end 146.055842 -373.059198)
		(stroke
			(width 0.07112)
			(type default)
		)
		(layer "In6.Cu")
	)
	(gr_line
		(start 146.195034 -399.539714)
		(end 146.19478 -399.540222)
		(stroke
			(width 0.07112)
			(type default)
		)
		(layer "In6.Cu")
	)
	(gr_line
		(start 146.206972 -399.098516)
		(end 146.289268 -399.27276)
		(stroke
			(width 0.07112)
			(type default)
		)
		(layer "In6.Cu")
	)
	(gr_line
		(start 146.233896 -372.073932)
		(end 146.103594 -371.9322)
		(stroke
			(width 0.07112)
			(type default)
		)
		(layer "In6.Cu")
	)
	(gr_line
		(start 146.251676 -396.680436)
		(end 146.66341 -396.794228)
		(stroke
			(width 0.07112)
			(type default)
		)
		(layer "In6.Cu")
	)
	(gr_line
		(start 146.264884 -371.374162)
		(end 146.264376 -371.374162)
		(stroke
			(width 0.07112)
			(type default)
		)
		(layer "In6.Cu")
	)
	(gr_line
		(start 146.281648 -370.94668)
		(end 146.1516 -370.805202)
		(stroke
			(width 0.07112)
			(type default)
		)
		(layer "In6.Cu")
	)
	(gr_line
		(start 146.28241 -370.94795)
		(end 146.282664 -370.94795)
		(stroke
			(width 0.07112)
			(type default)
		)
		(layer "In6.Cu")
	)
	(gr_line
		(start 146.301714 -380.538228)
		(end 146.318732 -380.346712)
		(stroke
			(width 0.07112)
			(type default)
		)
		(layer "In6.Cu")
	)
	(gr_line
		(start 146.312636 -370.247164)
		(end 146.312128 -370.24691)
		(stroke
			(width 0.07112)
			(type default)
		)
		(layer "In6.Cu")
	)
	(gr_line
		(start 146.4691 -373.213884)
		(end 146.498818 -372.513098)
		(stroke
			(width 0.07112)
			(type default)
		)
		(layer "In6.Cu")
	)
	(gr_line
		(start 146.484848 -419.048438)
		(end 146.484594 -419.048946)
		(stroke
			(width 0.07112)
			(type default)
		)
		(layer "In6.Cu")
	)
	(gr_line
		(start 146.516852 -372.086886)
		(end 146.546062 -371.39753)
		(stroke
			(width 0.07112)
			(type default)
		)
		(layer "In6.Cu")
	)
	(gr_line
		(start 146.518122 -402.70684)
		(end 146.596608 -402.882608)
		(stroke
			(width 0.07112)
			(type default)
		)
		(layer "In6.Cu")
	)
	(gr_line
		(start 146.546062 -371.394482)
		(end 146.54657 -371.383052)
		(stroke
			(width 0.07112)
			(type default)
		)
		(layer "In6.Cu")
	)
	(gr_line
		(start 146.564604 -370.959888)
		(end 146.594068 -370.259102)
		(stroke
			(width 0.07112)
			(type default)
		)
		(layer "In6.Cu")
	)
	(gr_line
		(start 146.575526 -380.865888)
		(end 146.301714 -380.538228)
		(stroke
			(width 0.07112)
			(type default)
		)
		(layer "In6.Cu")
	)
	(gr_line
		(start 146.62277 -426.830998)
		(end 146.750024 -426.958252)
		(stroke
			(width 0.07112)
			(type default)
		)
		(layer "In6.Cu")
	)
	(gr_line
		(start 146.62277 -426.548804)
		(end 146.750024 -426.42155)
		(stroke
			(width 0.07112)
			(type default)
		)
		(layer "In6.Cu")
	)
	(gr_line
		(start 146.650964 -417.933124)
		(end 146.650456 -417.933378)
		(stroke
			(width 0.07112)
			(type default)
		)
		(layer "In6.Cu")
	)
	(gr_line
		(start 146.66341 -396.794228)
		(end 146.758152 -396.961868)
		(stroke
			(width 0.07112)
			(type default)
		)
		(layer "In6.Cu")
	)
	(gr_line
		(start 146.750024 -426.958252)
		(end 146.750024 -427.289976)
		(stroke
			(width 0.07112)
			(type default)
		)
		(layer "In6.Cu")
	)
	(gr_line
		(start 146.750024 -426.42155)
		(end 146.750024 -426.089826)
		(stroke
			(width 0.07112)
			(type default)
		)
		(layer "In6.Cu")
	)
	(gr_line
		(start 146.753834 -417.239958)
		(end 146.650964 -417.933124)
		(stroke
			(width 0.07112)
			(type default)
		)
		(layer "In6.Cu")
	)
	(gr_line
		(start 146.758914 -396.963392)
		(end 146.759168 -396.963392)
		(stroke
			(width 0.07112)
			(type default)
		)
		(layer "In6.Cu")
	)
	(gr_line
		(start 146.767042 -380.882906)
		(end 146.575526 -380.865888)
		(stroke
			(width 0.07112)
			(type default)
		)
		(layer "In6.Cu")
	)
	(gr_line
		(start 146.777964 -418.997638)
		(end 146.77771 -418.998146)
		(stroke
			(width 0.07112)
			(type default)
		)
		(layer "In6.Cu")
	)
	(gr_line
		(start 146.795236 -377.35383)
		(end 146.826732 -377.163838)
		(stroke
			(width 0.07112)
			(type default)
		)
		(layer "In6.Cu")
	)
	(gr_line
		(start 146.816318 -416.818064)
		(end 146.753834 -417.239958)
		(stroke
			(width 0.07112)
			(type default)
		)
		(layer "In6.Cu")
	)
	(gr_line
		(start 146.919188 -416.124136)
		(end 146.816318 -416.818064)
		(stroke
			(width 0.07112)
			(type default)
		)
		(layer "In6.Cu")
	)
	(gr_line
		(start 146.929856 -417.974526)
		(end 146.929348 -417.97478)
		(stroke
			(width 0.07112)
			(type default)
		)
		(layer "In6.Cu")
	)
	(gr_line
		(start 146.985228 -380.702312)
		(end 146.535394 -380.16434)
		(stroke
			(width 0.07112)
			(type default)
		)
		(layer "In6.Cu")
	)
	(gr_line
		(start 147.012152 -415.49828)
		(end 146.919188 -416.124136)
		(stroke
			(width 0.07112)
			(type default)
		)
		(layer "In6.Cu")
	)
	(gr_line
		(start 147.025106 -381.403606)
		(end 147.042124 -381.21209)
		(stroke
			(width 0.07112)
			(type default)
		)
		(layer "In6.Cu")
	)
	(gr_line
		(start 147.033742 -417.282884)
		(end 147.148042 -417.437062)
		(stroke
			(width 0.07112)
			(type default)
		)
		(layer "In6.Cu")
	)
	(gr_line
		(start 147.043648 -377.701302)
		(end 146.795236 -377.35383)
		(stroke
			(width 0.07112)
			(type default)
		)
		(layer "In6.Cu")
	)
	(gr_line
		(start 147.058126 -410.030168)
		(end 147.348956 -410.320998)
		(stroke
			(width 0.07112)
			(type default)
		)
		(layer "In6.Cu")
	)
	(gr_line
		(start 147.085558 -417.859464)
		(end 146.93138 -417.973256)
		(stroke
			(width 0.07112)
			(type default)
		)
		(layer "In6.Cu")
	)
	(gr_line
		(start 147.094956 -416.859212)
		(end 147.032472 -417.281106)
		(stroke
			(width 0.07112)
			(type default)
		)
		(layer "In6.Cu")
	)
	(gr_line
		(start 147.115022 -414.804352)
		(end 147.012152 -415.49828)
		(stroke
			(width 0.07112)
			(type default)
		)
		(layer "In6.Cu")
	)
	(gr_line
		(start 147.148042 -417.437062)
		(end 147.085558 -417.859464)
		(stroke
			(width 0.07112)
			(type default)
		)
		(layer "In6.Cu")
	)
	(gr_line
		(start 147.182078 -398.68348)
		(end 147.8534 -398.887188)
		(stroke
			(width 0.07112)
			(type default)
		)
		(layer "In6.Cu")
	)
	(gr_line
		(start 147.184618 -414.334706)
		(end 147.115022 -414.804352)
		(stroke
			(width 0.07112)
			(type default)
		)
		(layer "In6.Cu")
	)
	(gr_line
		(start 147.19935 -416.167062)
		(end 147.31365 -416.32124)
		(stroke
			(width 0.07112)
			(type default)
		)
		(layer "In6.Cu")
	)
	(gr_line
		(start 147.23364 -377.732798)
		(end 147.043648 -377.701302)
		(stroke
			(width 0.07112)
			(type default)
		)
		(layer "In6.Cu")
	)
	(gr_line
		(start 147.250912 -416.743642)
		(end 147.096734 -416.857942)
		(stroke
			(width 0.07112)
			(type default)
		)
		(layer "In6.Cu")
	)
	(gr_line
		(start 147.265136 -398.412716)
		(end 147.435062 -398.322038)
		(stroke
			(width 0.07112)
			(type default)
		)
		(layer "In6.Cu")
	)
	(gr_line
		(start 147.287488 -413.641032)
		(end 147.184618 -414.334706)
		(stroke
			(width 0.07112)
			(type default)
		)
		(layer "In6.Cu")
	)
	(gr_line
		(start 147.29079 -415.539428)
		(end 147.19808 -416.165538)
		(stroke
			(width 0.07112)
			(type default)
		)
		(layer "In6.Cu")
	)
	(gr_line
		(start 147.298918 -381.731266)
		(end 147.025106 -381.403606)
		(stroke
			(width 0.07112)
			(type default)
		)
		(layer "In6.Cu")
	)
	(gr_line
		(start 147.31365 -416.32124)
		(end 147.250912 -416.743642)
		(stroke
			(width 0.07112)
			(type default)
		)
		(layer "In6.Cu")
	)
	(gr_line
		(start 147.348956 -411.123892)
		(end 147.348956 -411.824932)
		(stroke
			(width 0.07112)
			(type default)
		)
		(layer "In6.Cu")
	)
	(gr_line
		(start 147.348956 -406.71369)
		(end 147.058126 -407.00452)
		(stroke
			(width 0.07112)
			(type default)
		)
		(layer "In6.Cu")
	)
	(gr_line
		(start 147.39493 -414.847278)
		(end 147.509484 -415.001456)
		(stroke
			(width 0.07112)
			(type default)
		)
		(layer "In6.Cu")
	)
	(gr_line
		(start 147.41906 -385.31038)
		(end 147.772374 -385.405376)
		(stroke
			(width 0.07112)
			(type default)
		)
		(layer "In6.Cu")
	)
	(gr_line
		(start 147.435062 -398.322038)
		(end 147.843748 -398.445736)
		(stroke
			(width 0.07112)
			(type default)
		)
		(layer "In6.Cu")
	)
	(gr_line
		(start 147.447 -415.423858)
		(end 147.292568 -415.538158)
		(stroke
			(width 0.07112)
			(type default)
		)
		(layer "In6.Cu")
	)
	(gr_line
		(start 147.451318 -378.271278)
		(end 147.482814 -378.081286)
		(stroke
			(width 0.07112)
			(type default)
		)
		(layer "In6.Cu")
	)
	(gr_line
		(start 147.46351 -414.376108)
		(end 147.393914 -414.845754)
		(stroke
			(width 0.07112)
			(type default)
		)
		(layer "In6.Cu")
	)
	(gr_line
		(start 147.46478 -377.568968)
		(end 147.056602 -376.99823)
		(stroke
			(width 0.07112)
			(type default)
		)
		(layer "In6.Cu")
	)
	(gr_line
		(start 147.490434 -381.748284)
		(end 147.298918 -381.731266)
		(stroke
			(width 0.07112)
			(type default)
		)
		(layer "In6.Cu")
	)
	(gr_line
		(start 147.509484 -415.001456)
		(end 147.447 -415.423858)
		(stroke
			(width 0.07112)
			(type default)
		)
		(layer "In6.Cu")
	)
	(gr_line
		(start 147.56765 -413.683704)
		(end 147.682204 -413.83839)
		(stroke
			(width 0.07112)
			(type default)
		)
		(layer "In6.Cu")
	)
	(gr_line
		(start 147.619466 -414.260792)
		(end 147.465034 -414.374838)
		(stroke
			(width 0.07112)
			(type default)
		)
		(layer "In6.Cu")
	)
	(gr_line
		(start 147.630896 -406.71369)
		(end 147.921726 -407.00452)
		(stroke
			(width 0.07112)
			(type default)
		)
		(layer "In6.Cu")
	)
	(gr_line
		(start 147.632166 -411.125162)
		(end 147.768056 -411.261052)
		(stroke
			(width 0.07112)
			(type default)
		)
		(layer "In6.Cu")
	)
	(gr_line
		(start 147.633436 -402.347176)
		(end 148.281136 -402.616162)
		(stroke
			(width 0.07112)
			(type default)
		)
		(layer "In6.Cu")
	)
	(gr_line
		(start 147.682204 -413.83839)
		(end 147.619466 -414.260792)
		(stroke
			(width 0.07112)
			(type default)
		)
		(layer "In6.Cu")
	)
	(gr_line
		(start 147.69973 -378.61875)
		(end 147.451318 -378.271278)
		(stroke
			(width 0.07112)
			(type default)
		)
		(layer "In6.Cu")
	)
	(gr_line
		(start 147.70862 -381.56769)
		(end 147.258786 -381.029718)
		(stroke
			(width 0.07112)
			(type default)
		)
		(layer "In6.Cu")
	)
	(gr_line
		(start 147.74291 -402.086064)
		(end 147.920964 -402.012658)
		(stroke
			(width 0.07112)
			(type default)
		)
		(layer "In6.Cu")
	)
	(gr_line
		(start 147.7645 -352.263202)
		(end 147.7645 -352.263456)
		(stroke
			(width 0.07112)
			(type default)
		)
		(layer "In6.Cu")
	)
	(gr_line
		(start 147.768056 -411.687772)
		(end 147.632166 -411.823662)
		(stroke
			(width 0.07112)
			(type default)
		)
		(layer "In6.Cu")
	)
	(gr_line
		(start 147.768056 -411.261052)
		(end 147.768056 -411.687772)
		(stroke
			(width 0.07112)
			(type default)
		)
		(layer "In6.Cu")
	)
	(gr_line
		(start 147.772374 -385.405376)
		(end 147.772882 -385.404868)
		(stroke
			(width 0.07112)
			(type default)
		)
		(layer "In6.Cu")
	)
	(gr_line
		(start 147.81911 -386.003292)
		(end 147.913852 -385.649724)
		(stroke
			(width 0.07112)
			(type default)
		)
		(layer "In6.Cu")
	)
	(gr_line
		(start 147.843748 -398.445736)
		(end 147.934426 -398.615662)
		(stroke
			(width 0.07112)
			(type default)
		)
		(layer "In6.Cu")
	)
	(gr_line
		(start 147.889468 -378.650246)
		(end 147.69973 -378.61875)
		(stroke
			(width 0.07112)
			(type default)
		)
		(layer "In6.Cu")
	)
	(gr_line
		(start 147.920964 -402.012658)
		(end 148.315172 -402.176234)
		(stroke
			(width 0.07112)
			(type default)
		)
		(layer "In6.Cu")
	)
	(gr_line
		(start 147.921726 -410.030168)
		(end 147.630896 -410.320998)
		(stroke
			(width 0.07112)
			(type default)
		)
		(layer "In6.Cu")
	)
	(gr_line
		(start 148.035518 -385.579112)
		(end 148.08835 -385.548632)
		(stroke
			(width 0.07112)
			(type default)
		)
		(layer "In6.Cu")
	)
	(gr_line
		(start 148.08835 -385.548632)
		(end 148.176488 -385.460494)
		(stroke
			(width 0.07112)
			(type default)
		)
		(layer "In6.Cu")
	)
	(gr_line
		(start 148.1074 -379.188726)
		(end 148.138896 -378.998988)
		(stroke
			(width 0.07112)
			(type default)
		)
		(layer "In6.Cu")
	)
	(gr_line
		(start 148.120608 -378.486416)
		(end 147.712684 -377.915932)
		(stroke
			(width 0.07112)
			(type default)
		)
		(layer "In6.Cu")
	)
	(gr_line
		(start 148.176488 -385.460494)
		(end 148.176488 -385.334764)
		(stroke
			(width 0.07112)
			(type default)
		)
		(layer "In6.Cu")
	)
	(gr_line
		(start 148.315172 -402.176234)
		(end 148.388578 -402.354034)
		(stroke
			(width 0.07112)
			(type default)
		)
		(layer "In6.Cu")
	)
	(gr_line
		(start 148.355812 -379.536198)
		(end 148.1074 -379.188726)
		(stroke
			(width 0.07112)
			(type default)
		)
		(layer "In6.Cu")
	)
	(gr_line
		(start 148.489416 -372.099332)
		(end 148.488908 -372.098824)
		(stroke
			(width 0.07112)
			(type default)
		)
		(layer "In6.Cu")
	)
	(gr_line
		(start 148.54555 -379.567694)
		(end 148.355812 -379.536198)
		(stroke
			(width 0.07112)
			(type default)
		)
		(layer "In6.Cu")
	)
	(gr_line
		(start 148.618956 -385.31038)
		(end 148.97227 -385.405376)
		(stroke
			(width 0.07112)
			(type default)
		)
		(layer "In6.Cu")
	)
	(gr_line
		(start 148.622766 -427.830742)
		(end 148.75002 -427.957996)
		(stroke
			(width 0.07112)
			(type default)
		)
		(layer "In6.Cu")
	)
	(gr_line
		(start 148.622766 -427.548802)
		(end 148.75002 -427.421548)
		(stroke
			(width 0.07112)
			(type default)
		)
		(layer "In6.Cu")
	)
	(gr_line
		(start 148.743416 -397.805148)
		(end 149.41931 -397.992092)
		(stroke
			(width 0.07112)
			(type default)
		)
		(layer "In6.Cu")
	)
	(gr_line
		(start 148.75002 -427.957996)
		(end 148.75002 -428.28972)
		(stroke
			(width 0.07112)
			(type default)
		)
		(layer "In6.Cu")
	)
	(gr_line
		(start 148.75002 -427.421548)
		(end 148.75002 -427.089824)
		(stroke
			(width 0.07112)
			(type default)
		)
		(layer "In6.Cu")
	)
	(gr_line
		(start 148.776436 -379.403864)
		(end 148.368512 -378.83338)
		(stroke
			(width 0.07112)
			(type default)
		)
		(layer "In6.Cu")
	)
	(gr_line
		(start 148.820124 -397.532606)
		(end 148.987256 -397.43761)
		(stroke
			(width 0.07112)
			(type default)
		)
		(layer "In6.Cu")
	)
	(gr_line
		(start 148.97227 -385.405376)
		(end 148.972778 -385.404868)
		(stroke
			(width 0.07112)
			(type default)
		)
		(layer "In6.Cu")
	)
	(gr_line
		(start 148.987256 -397.43761)
		(end 149.398736 -397.551402)
		(stroke
			(width 0.07112)
			(type default)
		)
		(layer "In6.Cu")
	)
	(gr_line
		(start 149.019006 -386.003292)
		(end 149.113748 -385.649724)
		(stroke
			(width 0.07112)
			(type default)
		)
		(layer "In6.Cu")
	)
	(gr_line
		(start 149.086316 -382.075182)
		(end 149.086062 -382.075436)
		(stroke
			(width 0.07112)
			(type default)
		)
		(layer "In6.Cu")
	)
	(gr_line
		(start 149.235414 -385.579112)
		(end 149.288246 -385.548632)
		(stroke
			(width 0.07112)
			(type default)
		)
		(layer "In6.Cu")
	)
	(gr_line
		(start 149.276308 -381.817118)
		(end 149.276054 -381.816864)
		(stroke
			(width 0.07112)
			(type default)
		)
		(layer "In6.Cu")
	)
	(gr_line
		(start 149.288246 -385.548632)
		(end 149.376384 -385.460494)
		(stroke
			(width 0.07112)
			(type default)
		)
		(layer "In6.Cu")
	)
	(gr_line
		(start 149.324568 -417.678616)
		(end 149.324314 -417.678616)
		(stroke
			(width 0.07112)
			(type default)
		)
		(layer "In6.Cu")
	)
	(gr_line
		(start 149.376384 -385.460494)
		(end 149.376384 -385.334764)
		(stroke
			(width 0.07112)
			(type default)
		)
		(layer "In6.Cu")
	)
	(gr_line
		(start 149.398736 -397.551402)
		(end 149.493478 -397.719042)
		(stroke
			(width 0.07112)
			(type default)
		)
		(layer "In6.Cu")
	)
	(gr_line
		(start 149.494494 -397.720566)
		(end 149.494494 -397.720312)
		(stroke
			(width 0.07112)
			(type default)
		)
		(layer "In6.Cu")
	)
	(gr_line
		(start 149.495002 -416.99815)
		(end 149.324568 -417.678616)
		(stroke
			(width 0.07112)
			(type default)
		)
		(layer "In6.Cu")
	)
	(gr_line
		(start 149.53107 -401.913598)
		(end 150.179278 -402.182076)
		(stroke
			(width 0.07112)
			(type default)
		)
		(layer "In6.Cu")
	)
	(gr_line
		(start 149.598634 -416.584384)
		(end 149.495002 -416.99815)
		(stroke
			(width 0.07112)
			(type default)
		)
		(layer "In6.Cu")
	)
	(gr_line
		(start 149.612096 -400.76247)
		(end 150.27275 -400.99869)
		(stroke
			(width 0.07112)
			(type default)
		)
		(layer "In6.Cu")
	)
	(gr_line
		(start 149.63902 -401.65274)
		(end 149.63902 -401.652994)
		(stroke
			(width 0.07112)
			(type default)
		)
		(layer "In6.Cu")
	)
	(gr_line
		(start 149.640544 -401.652486)
		(end 149.81809 -401.578572)
		(stroke
			(width 0.07112)
			(type default)
		)
		(layer "In6.Cu")
	)
	(gr_line
		(start 149.708362 -400.496024)
		(end 149.882606 -400.413728)
		(stroke
			(width 0.07112)
			(type default)
		)
		(layer "In6.Cu")
	)
	(gr_line
		(start 149.764496 -417.647374)
		(end 149.59965 -417.745926)
		(stroke
			(width 0.07112)
			(type default)
		)
		(layer "In6.Cu")
	)
	(gr_line
		(start 149.768814 -415.904172)
		(end 149.598634 -416.584384)
		(stroke
			(width 0.07112)
			(type default)
		)
		(layer "In6.Cu")
	)
	(gr_line
		(start 149.769322 -417.068508)
		(end 149.868128 -417.2331)
		(stroke
			(width 0.07112)
			(type default)
		)
		(layer "In6.Cu")
	)
	(gr_line
		(start 149.81809 -401.578572)
		(end 150.212552 -401.741894)
		(stroke
			(width 0.07112)
			(type default)
		)
		(layer "In6.Cu")
	)
	(gr_line
		(start 149.819106 -385.31038)
		(end 150.172166 -385.405376)
		(stroke
			(width 0.07112)
			(type default)
		)
		(layer "In6.Cu")
	)
	(gr_line
		(start 149.868128 -417.2331)
		(end 149.764496 -417.647374)
		(stroke
			(width 0.07112)
			(type default)
		)
		(layer "In6.Cu")
	)
	(gr_line
		(start 149.871938 -416.652964)
		(end 149.768306 -417.06673)
		(stroke
			(width 0.07112)
			(type default)
		)
		(layer "In6.Cu")
	)
	(gr_line
		(start 149.872446 -415.490406)
		(end 149.768814 -415.904172)
		(stroke
			(width 0.07112)
			(type default)
		)
		(layer "In6.Cu")
	)
	(gr_line
		(start 149.882606 -400.413728)
		(end 150.284688 -400.557492)
		(stroke
			(width 0.07112)
			(type default)
		)
		(layer "In6.Cu")
	)
	(gr_line
		(start 150.038562 -416.553396)
		(end 149.873716 -416.651948)
		(stroke
			(width 0.07112)
			(type default)
		)
		(layer "In6.Cu")
	)
	(gr_line
		(start 150.04288 -414.810194)
		(end 149.872446 -415.490406)
		(stroke
			(width 0.07112)
			(type default)
		)
		(layer "In6.Cu")
	)
	(gr_line
		(start 150.043388 -415.974276)
		(end 150.142194 -416.139122)
		(stroke
			(width 0.07112)
			(type default)
		)
		(layer "In6.Cu")
	)
	(gr_line
		(start 150.121366 -410.030168)
		(end 150.412196 -410.320998)
		(stroke
			(width 0.07112)
			(type default)
		)
		(layer "In6.Cu")
	)
	(gr_line
		(start 150.142194 -416.139122)
		(end 150.038562 -416.553396)
		(stroke
			(width 0.07112)
			(type default)
		)
		(layer "In6.Cu")
	)
	(gr_line
		(start 150.146004 -415.558986)
		(end 150.042372 -415.972752)
		(stroke
			(width 0.07112)
			(type default)
		)
		(layer "In6.Cu")
	)
	(gr_line
		(start 150.172166 -385.405376)
		(end 150.172674 -385.404868)
		(stroke
			(width 0.07112)
			(type default)
		)
		(layer "In6.Cu")
	)
	(gr_line
		(start 150.212552 -401.741894)
		(end 150.286212 -401.919948)
		(stroke
			(width 0.07112)
			(type default)
		)
		(layer "In6.Cu")
	)
	(gr_line
		(start 150.218902 -386.003292)
		(end 150.313644 -385.649724)
		(stroke
			(width 0.07112)
			(type default)
		)
		(layer "In6.Cu")
	)
	(gr_line
		(start 150.284688 -400.557492)
		(end 150.367238 -400.731736)
		(stroke
			(width 0.07112)
			(type default)
		)
		(layer "In6.Cu")
	)
	(gr_line
		(start 150.286212 -382.0414)
		(end 150.285958 -382.0414)
		(stroke
			(width 0.07112)
			(type default)
		)
		(layer "In6.Cu")
	)
	(gr_line
		(start 150.312628 -415.459418)
		(end 150.147528 -415.55797)
		(stroke
			(width 0.07112)
			(type default)
		)
		(layer "In6.Cu")
	)
	(gr_line
		(start 150.316946 -413.716216)
		(end 150.146512 -414.396428)
		(stroke
			(width 0.07112)
			(type default)
		)
		(layer "In6.Cu")
	)
	(gr_line
		(start 150.317454 -414.880298)
		(end 150.41626 -415.045144)
		(stroke
			(width 0.07112)
			(type default)
		)
		(layer "In6.Cu")
	)
	(gr_line
		(start 150.412196 -406.71369)
		(end 150.121366 -407.00452)
		(stroke
			(width 0.07112)
			(type default)
		)
		(layer "In6.Cu")
	)
	(gr_line
		(start 150.412196 -404.995888)
		(end 150.412196 -405.696928)
		(stroke
			(width 0.07112)
			(type default)
		)
		(layer "In6.Cu")
	)
	(gr_line
		(start 150.41626 -415.045144)
		(end 150.312628 -415.459418)
		(stroke
			(width 0.07112)
			(type default)
		)
		(layer "In6.Cu")
	)
	(gr_line
		(start 150.43531 -385.579112)
		(end 150.488142 -385.548632)
		(stroke
			(width 0.07112)
			(type default)
		)
		(layer "In6.Cu")
	)
	(gr_line
		(start 150.488142 -385.548632)
		(end 150.57628 -385.460494)
		(stroke
			(width 0.07112)
			(type default)
		)
		(layer "In6.Cu")
	)
	(gr_arc
		(start 150.492206 -381.803656)
		(mid 150.49246 -381.804037)
		(end 150.492714 -381.804418)
		(stroke
			(width 0.07112)
			(type default)
		)
		(layer "In6.Cu")
	)
	(gr_line
		(start 150.573232 -402.345398)
		(end 151.220932 -402.613622)
		(stroke
			(width 0.07112)
			(type default)
		)
		(layer "In6.Cu")
	)
	(gr_line
		(start 150.57628 -385.460494)
		(end 150.57628 -385.334764)
		(stroke
			(width 0.07112)
			(type default)
		)
		(layer "In6.Cu")
	)
	(gr_line
		(start 150.586694 -414.36544)
		(end 150.421594 -414.463992)
		(stroke
			(width 0.07112)
			(type default)
		)
		(layer "In6.Cu")
	)
	(gr_line
		(start 150.591266 -413.78632)
		(end 150.690326 -413.951166)
		(stroke
			(width 0.07112)
			(type default)
		)
		(layer "In6.Cu")
	)
	(gr_line
		(start 150.622762 -426.830998)
		(end 150.750016 -426.958252)
		(stroke
			(width 0.07112)
			(type default)
		)
		(layer "In6.Cu")
	)
	(gr_line
		(start 150.622762 -426.548804)
		(end 150.750016 -426.42155)
		(stroke
			(width 0.07112)
			(type default)
		)
		(layer "In6.Cu")
	)
	(gr_line
		(start 150.682452 -402.084032)
		(end 150.860252 -402.010372)
		(stroke
			(width 0.07112)
			(type default)
		)
		(layer "In6.Cu")
	)
	(gr_line
		(start 150.690326 -413.951166)
		(end 150.586694 -414.36544)
		(stroke
			(width 0.07112)
			(type default)
		)
		(layer "In6.Cu")
	)
	(gr_line
		(start 150.694136 -406.71369)
		(end 150.984966 -407.00452)
		(stroke
			(width 0.07112)
			(type default)
		)
		(layer "In6.Cu")
	)
	(gr_line
		(start 150.695406 -404.997158)
		(end 150.831296 -405.133048)
		(stroke
			(width 0.07112)
			(type default)
		)
		(layer "In6.Cu")
	)
	(gr_line
		(start 150.750016 -426.958252)
		(end 150.750016 -427.289976)
		(stroke
			(width 0.07112)
			(type default)
		)
		(layer "In6.Cu")
	)
	(gr_line
		(start 150.750016 -426.42155)
		(end 150.750016 -426.089826)
		(stroke
			(width 0.07112)
			(type default)
		)
		(layer "In6.Cu")
	)
	(gr_line
		(start 150.831296 -405.559768)
		(end 150.695406 -405.695658)
		(stroke
			(width 0.07112)
			(type default)
		)
		(layer "In6.Cu")
	)
	(gr_line
		(start 150.831296 -405.133048)
		(end 150.831296 -405.559768)
		(stroke
			(width 0.07112)
			(type default)
		)
		(layer "In6.Cu")
	)
	(gr_line
		(start 150.860252 -402.010372)
		(end 151.254714 -402.173694)
		(stroke
			(width 0.07112)
			(type default)
		)
		(layer "In6.Cu")
	)
	(gr_line
		(start 150.984966 -410.030168)
		(end 150.694136 -410.320998)
		(stroke
			(width 0.07112)
			(type default)
		)
		(layer "In6.Cu")
	)
	(gr_line
		(start 151.019002 -385.31038)
		(end 151.372316 -385.405376)
		(stroke
			(width 0.07112)
			(type default)
		)
		(layer "In6.Cu")
	)
	(gr_line
		(start 151.220932 -402.613622)
		(end 151.221186 -402.613622)
		(stroke
			(width 0.07112)
			(type default)
		)
		(layer "In6.Cu")
	)
	(gr_line
		(start 151.254714 -402.173694)
		(end 151.32812 -402.351494)
		(stroke
			(width 0.07112)
			(type default)
		)
		(layer "In6.Cu")
	)
	(gr_line
		(start 151.258016 -377.962922)
		(end 151.348186 -377.792996)
		(stroke
			(width 0.07112)
			(type default)
		)
		(layer "In6.Cu")
	)
	(gr_line
		(start 151.328882 -402.353272)
		(end 151.328882 -402.353018)
		(stroke
			(width 0.07112)
			(type default)
		)
		(layer "In6.Cu")
	)
	(gr_line
		(start 151.372316 -385.405376)
		(end 151.372824 -385.404868)
		(stroke
			(width 0.07112)
			(type default)
		)
		(layer "In6.Cu")
	)
	(gr_line
		(start 151.38273 -378.371354)
		(end 151.258016 -377.962922)
		(stroke
			(width 0.07112)
			(type default)
		)
		(layer "In6.Cu")
	)
	(gr_line
		(start 151.419052 -386.003292)
		(end 151.513794 -385.649724)
		(stroke
			(width 0.07112)
			(type default)
		)
		(layer "In6.Cu")
	)
	(gr_line
		(start 151.55291 -378.461524)
		(end 151.38273 -378.371354)
		(stroke
			(width 0.07112)
			(type default)
		)
		(layer "In6.Cu")
	)
	(gr_line
		(start 151.588216 -379.041406)
		(end 151.678386 -378.87148)
		(stroke
			(width 0.07112)
			(type default)
		)
		(layer "In6.Cu")
	)
	(gr_line
		(start 151.63546 -385.579112)
		(end 151.688292 -385.548632)
		(stroke
			(width 0.07112)
			(type default)
		)
		(layer "In6.Cu")
	)
	(gr_line
		(start 151.688292 -385.548632)
		(end 151.77643 -385.460494)
		(stroke
			(width 0.07112)
			(type default)
		)
		(layer "In6.Cu")
	)
	(gr_line
		(start 151.69642 -381.808482)
		(end 151.696166 -381.808228)
		(stroke
			(width 0.07112)
			(type default)
		)
		(layer "In6.Cu")
	)
	(gr_line
		(start 151.71293 -379.449838)
		(end 151.588216 -379.041406)
		(stroke
			(width 0.07112)
			(type default)
		)
		(layer "In6.Cu")
	)
	(gr_line
		(start 151.77643 -385.460494)
		(end 151.77643 -385.334764)
		(stroke
			(width 0.07112)
			(type default)
		)
		(layer "In6.Cu")
	)
	(gr_line
		(start 151.824182 -378.379736)
		(end 151.618696 -377.709176)
		(stroke
			(width 0.07112)
			(type default)
		)
		(layer "In6.Cu")
	)
	(gr_line
		(start 151.88311 -379.540008)
		(end 151.71293 -379.449838)
		(stroke
			(width 0.07112)
			(type default)
		)
		(layer "In6.Cu")
	)
	(gr_line
		(start 151.918162 -380.11989)
		(end 152.008586 -379.949964)
		(stroke
			(width 0.07112)
			(type default)
		)
		(layer "In6.Cu")
	)
	(gr_line
		(start 152.04313 -380.528322)
		(end 151.918162 -380.11989)
		(stroke
			(width 0.07112)
			(type default)
		)
		(layer "In6.Cu")
	)
	(gr_line
		(start 152.053544 -417.770564)
		(end 151.403558 -419.913054)
		(stroke
			(width 0.07112)
			(type default)
		)
		(layer "In6.Cu")
	)
	(gr_line
		(start 152.154382 -379.45822)
		(end 151.948896 -378.78766)
		(stroke
			(width 0.07112)
			(type default)
		)
		(layer "In6.Cu")
	)
	(gr_line
		(start 152.21331 -380.618492)
		(end 152.04313 -380.528322)
		(stroke
			(width 0.07112)
			(type default)
		)
		(layer "In6.Cu")
	)
	(gr_line
		(start 152.218898 -385.31038)
		(end 152.572212 -385.405376)
		(stroke
			(width 0.07112)
			(type default)
		)
		(layer "In6.Cu")
	)
	(gr_line
		(start 152.257252 -417.099496)
		(end 152.053544 -417.770564)
		(stroke
			(width 0.07112)
			(type default)
		)
		(layer "In6.Cu")
	)
	(gr_line
		(start 152.323292 -417.852352)
		(end 151.67356 -419.994842)
		(stroke
			(width 0.07112)
			(type default)
		)
		(layer "In6.Cu")
	)
	(gr_line
		(start 152.38095 -416.691318)
		(end 152.257252 -417.099496)
		(stroke
			(width 0.07112)
			(type default)
		)
		(layer "In6.Cu")
	)
	(gr_line
		(start 152.484328 -380.536704)
		(end 152.279096 -379.866144)
		(stroke
			(width 0.07112)
			(type default)
		)
		(layer "In6.Cu")
	)
	(gr_line
		(start 152.494488 -417.760912)
		(end 152.32507 -417.851336)
		(stroke
			(width 0.07112)
			(type default)
		)
		(layer "In6.Cu")
	)
	(gr_line
		(start 152.527762 -417.182808)
		(end 152.61844 -417.35248)
		(stroke
			(width 0.07112)
			(type default)
		)
		(layer "In6.Cu")
	)
	(gr_line
		(start 152.572212 -385.405376)
		(end 152.57272 -385.404868)
		(stroke
			(width 0.07112)
			(type default)
		)
		(layer "In6.Cu")
	)
	(gr_line
		(start 152.584658 -416.02025)
		(end 152.38095 -416.691318)
		(stroke
			(width 0.07112)
			(type default)
		)
		(layer "In6.Cu")
	)
	(gr_line
		(start 152.61844 -417.35248)
		(end 152.494488 -417.760912)
		(stroke
			(width 0.07112)
			(type default)
		)
		(layer "In6.Cu")
	)
	(gr_line
		(start 152.618948 -386.003292)
		(end 152.71369 -385.649724)
		(stroke
			(width 0.07112)
			(type default)
		)
		(layer "In6.Cu")
	)
	(gr_line
		(start 152.622758 -427.830742)
		(end 152.750012 -427.957996)
		(stroke
			(width 0.07112)
			(type default)
		)
		(layer "In6.Cu")
	)
	(gr_line
		(start 152.622758 -427.548802)
		(end 152.750012 -427.421548)
		(stroke
			(width 0.07112)
			(type default)
		)
		(layer "In6.Cu")
	)
	(gr_line
		(start 152.650698 -416.773106)
		(end 152.527 -417.181284)
		(stroke
			(width 0.07112)
			(type default)
		)
		(layer "In6.Cu")
	)
	(gr_line
		(start 152.686258 -382.384046)
		(end 152.686004 -382.3843)
		(stroke
			(width 0.07112)
			(type default)
		)
		(layer "In6.Cu")
	)
	(gr_line
		(start 152.750012 -427.957996)
		(end 152.750012 -428.28972)
		(stroke
			(width 0.07112)
			(type default)
		)
		(layer "In6.Cu")
	)
	(gr_line
		(start 152.750012 -427.421548)
		(end 152.750012 -427.089824)
		(stroke
			(width 0.07112)
			(type default)
		)
		(layer "In6.Cu")
	)
	(gr_line
		(start 152.770332 -378.637546)
		(end 152.863296 -378.468636)
		(stroke
			(width 0.07112)
			(type default)
		)
		(layer "In6.Cu")
	)
	(gr_line
		(start 152.776682 -415.387282)
		(end 152.584658 -416.02025)
		(stroke
			(width 0.07112)
			(type default)
		)
		(layer "In6.Cu")
	)
	(gr_line
		(start 152.822148 -416.681666)
		(end 152.652476 -416.77209)
		(stroke
			(width 0.07112)
			(type default)
		)
		(layer "In6.Cu")
	)
	(gr_line
		(start 152.835356 -385.579112)
		(end 152.888188 -385.548632)
		(stroke
			(width 0.07112)
			(type default)
		)
		(layer "In6.Cu")
	)
	(gr_line
		(start 152.855168 -416.103562)
		(end 152.945846 -416.273234)
		(stroke
			(width 0.07112)
			(type default)
		)
		(layer "In6.Cu")
	)
	(gr_line
		(start 152.888188 -385.548632)
		(end 152.976326 -385.460494)
		(stroke
			(width 0.07112)
			(type default)
		)
		(layer "In6.Cu")
	)
	(gr_line
		(start 152.88895 -379.047756)
		(end 152.770332 -378.637546)
		(stroke
			(width 0.07112)
			(type default)
		)
		(layer "In6.Cu")
	)
	(gr_line
		(start 152.945846 -416.273234)
		(end 152.822148 -416.681666)
		(stroke
			(width 0.07112)
			(type default)
		)
		(layer "In6.Cu")
	)
	(gr_line
		(start 152.976326 -385.460494)
		(end 152.976326 -385.334764)
		(stroke
			(width 0.07112)
			(type default)
		)
		(layer "In6.Cu")
	)
	(gr_line
		(start 152.980136 -414.716214)
		(end 152.776682 -415.387282)
		(stroke
			(width 0.07112)
			(type default)
		)
		(layer "In6.Cu")
	)
	(gr_line
		(start 153.04643 -415.46907)
		(end 152.854406 -416.102038)
		(stroke
			(width 0.07112)
			(type default)
		)
		(layer "In6.Cu")
	)
	(gr_line
		(start 153.057606 -379.14072)
		(end 152.88895 -379.047756)
		(stroke
			(width 0.07112)
			(type default)
		)
		(layer "In6.Cu")
	)
	(gr_line
		(start 153.083768 -379.72111)
		(end 153.176732 -379.552454)
		(stroke
			(width 0.07112)
			(type default)
		)
		(layer "In6.Cu")
	)
	(gr_line
		(start 153.102564 -400.770598)
		(end 153.750518 -401.039076)
		(stroke
			(width 0.07112)
			(type default)
		)
		(layer "In6.Cu")
	)
	(gr_line
		(start 153.104088 -414.308036)
		(end 153.054304 -414.471866)
		(stroke
			(width 0.07112)
			(type default)
		)
		(layer "In6.Cu")
	)
	(gr_line
		(start 153.184606 -410.030168)
		(end 153.475436 -410.320998)
		(stroke
			(width 0.07112)
			(type default)
		)
		(layer "In6.Cu")
	)
	(gr_line
		(start 153.202386 -380.13132)
		(end 153.083768 -379.72111)
		(stroke
			(width 0.07112)
			(type default)
		)
		(layer "In6.Cu")
	)
	(gr_line
		(start 153.212038 -400.509486)
		(end 153.389584 -400.435572)
		(stroke
			(width 0.07112)
			(type default)
		)
		(layer "In6.Cu")
	)
	(gr_line
		(start 153.217626 -415.37763)
		(end 153.047954 -415.468308)
		(stroke
			(width 0.07112)
			(type default)
		)
		(layer "In6.Cu")
	)
	(gr_line
		(start 153.2509 -414.799526)
		(end 153.341578 -414.969198)
		(stroke
			(width 0.07112)
			(type default)
		)
		(layer "In6.Cu")
	)
	(gr_line
		(start 153.25598 -368.318288)
		(end 153.255726 -368.318542)
		(stroke
			(width 0.07112)
			(type default)
		)
		(layer "In6.Cu")
	)
	(gr_line
		(start 153.307796 -413.63646)
		(end 153.104088 -414.308036)
		(stroke
			(width 0.07112)
			(type default)
		)
		(layer "In6.Cu")
	)
	(gr_line
		(start 153.313638 -413.617664)
		(end 153.307796 -413.63646)
		(stroke
			(width 0.07112)
			(type default)
		)
		(layer "In6.Cu")
	)
	(gr_line
		(start 153.3144 -358.52354)
		(end 153.314146 -358.52354)
		(stroke
			(width 0.07112)
			(type default)
		)
		(layer "In6.Cu")
	)
	(gr_line
		(start 153.330148 -379.06325)
		(end 153.135076 -378.389134)
		(stroke
			(width 0.07112)
			(type default)
		)
		(layer "In6.Cu")
	)
	(gr_line
		(start 153.341578 -414.969198)
		(end 153.217626 -415.37763)
		(stroke
			(width 0.07112)
			(type default)
		)
		(layer "In6.Cu")
	)
	(gr_line
		(start 153.371296 -380.224284)
		(end 153.202386 -380.13132)
		(stroke
			(width 0.07112)
			(type default)
		)
		(layer "In6.Cu")
	)
	(gr_line
		(start 153.389584 -400.435572)
		(end 153.7843 -400.598894)
		(stroke
			(width 0.07112)
			(type default)
		)
		(layer "In6.Cu")
	)
	(gr_line
		(start 153.397458 -380.804674)
		(end 153.490422 -380.635764)
		(stroke
			(width 0.07112)
			(type default)
		)
		(layer "In6.Cu")
	)
	(gr_line
		(start 153.419048 -385.31038)
		(end 153.772362 -385.405376)
		(stroke
			(width 0.07112)
			(type default)
		)
		(layer "In6.Cu")
	)
	(gr_line
		(start 153.475436 -413.028384)
		(end 153.475182 -413.028384)
		(stroke
			(width 0.07112)
			(type default)
		)
		(layer "In6.Cu")
	)
	(gr_line
		(start 153.475436 -411.24124)
		(end 153.475436 -411.94228)
		(stroke
			(width 0.07112)
			(type default)
		)
		(layer "In6.Cu")
	)
	(gr_line
		(start 153.475436 -406.71369)
		(end 153.184606 -407.00452)
		(stroke
			(width 0.07112)
			(type default)
		)
		(layer "In6.Cu")
	)
	(gr_line
		(start 153.516076 -381.214884)
		(end 153.397458 -380.804674)
		(stroke
			(width 0.07112)
			(type default)
		)
		(layer "In6.Cu")
	)
	(gr_line
		(start 153.545286 -414.298384)
		(end 153.37536 -414.389062)
		(stroke
			(width 0.07112)
			(type default)
		)
		(layer "In6.Cu")
	)
	(gr_line
		(start 153.578306 -413.720026)
		(end 153.668984 -413.889698)
		(stroke
			(width 0.07112)
			(type default)
		)
		(layer "In6.Cu")
	)
	(gr_line
		(start 153.583386 -413.699452)
		(end 153.577544 -413.718502)
		(stroke
			(width 0.07112)
			(type default)
		)
		(layer "In6.Cu")
	)
	(gr_line
		(start 153.643584 -380.146814)
		(end 153.448512 -379.472952)
		(stroke
			(width 0.07112)
			(type default)
		)
		(layer "In6.Cu")
	)
	(gr_line
		(start 153.668984 -413.889698)
		(end 153.545286 -414.298384)
		(stroke
			(width 0.07112)
			(type default)
		)
		(layer "In6.Cu")
	)
	(gr_line
		(start 153.684732 -381.307594)
		(end 153.516076 -381.214884)
		(stroke
			(width 0.07112)
			(type default)
		)
		(layer "In6.Cu")
	)
	(gr_line
		(start 153.757376 -406.71369)
		(end 154.048206 -407.00452)
		(stroke
			(width 0.07112)
			(type default)
		)
		(layer "In6.Cu")
	)
	(gr_line
		(start 153.758646 -411.24251)
		(end 153.894536 -411.3784)
		(stroke
			(width 0.07112)
			(type default)
		)
		(layer "In6.Cu")
	)
	(gr_line
		(start 153.772362 -385.405376)
		(end 153.77287 -385.404868)
		(stroke
			(width 0.07112)
			(type default)
		)
		(layer "In6.Cu")
	)
	(gr_line
		(start 153.7843 -400.598894)
		(end 153.85796 -400.776948)
		(stroke
			(width 0.07112)
			(type default)
		)
		(layer "In6.Cu")
	)
	(gr_line
		(start 153.819098 -386.003292)
		(end 153.91384 -385.649724)
		(stroke
			(width 0.07112)
			(type default)
		)
		(layer "In6.Cu")
	)
	(gr_line
		(start 153.894536 -411.80512)
		(end 153.758646 -411.94101)
		(stroke
			(width 0.07112)
			(type default)
		)
		(layer "In6.Cu")
	)
	(gr_line
		(start 153.894536 -411.3784)
		(end 153.894536 -411.80512)
		(stroke
			(width 0.07112)
			(type default)
		)
		(layer "In6.Cu")
	)
	(gr_line
		(start 153.95702 -381.230124)
		(end 153.762202 -380.556262)
		(stroke
			(width 0.07112)
			(type default)
		)
		(layer "In6.Cu")
	)
	(gr_line
		(start 154.035506 -385.579112)
		(end 154.088338 -385.548632)
		(stroke
			(width 0.07112)
			(type default)
		)
		(layer "In6.Cu")
	)
	(gr_line
		(start 154.048206 -410.030168)
		(end 153.757376 -410.320998)
		(stroke
			(width 0.07112)
			(type default)
		)
		(layer "In6.Cu")
	)
	(gr_line
		(start 154.077416 -378.577094)
		(end 154.177746 -378.412502)
		(stroke
			(width 0.07112)
			(type default)
		)
		(layer "In6.Cu")
	)
	(gr_line
		(start 154.088338 -385.548632)
		(end 154.176476 -385.460494)
		(stroke
			(width 0.07112)
			(type default)
		)
		(layer "In6.Cu")
	)
	(gr_line
		(start 154.176476 -385.460494)
		(end 154.176476 -385.334764)
		(stroke
			(width 0.07112)
			(type default)
		)
		(layer "In6.Cu")
	)
	(gr_line
		(start 154.178 -378.991876)
		(end 154.077416 -378.577094)
		(stroke
			(width 0.07112)
			(type default)
		)
		(layer "In6.Cu")
	)
	(gr_line
		(start 154.342592 -379.092206)
		(end 154.178 -378.991876)
		(stroke
			(width 0.07112)
			(type default)
		)
		(layer "In6.Cu")
	)
	(gr_line
		(start 154.343608 -379.673104)
		(end 154.443684 -379.508766)
		(stroke
			(width 0.07112)
			(type default)
		)
		(layer "In6.Cu")
	)
	(gr_line
		(start 154.362912 -402.579332)
		(end 155.010866 -402.84781)
		(stroke
			(width 0.07112)
			(type default)
		)
		(layer "In6.Cu")
	)
	(gr_line
		(start 154.444192 -380.087886)
		(end 154.343608 -379.673104)
		(stroke
			(width 0.07112)
			(type default)
		)
		(layer "In6.Cu")
	)
	(gr_line
		(start 154.472386 -402.31822)
		(end 154.650186 -402.24456)
		(stroke
			(width 0.07112)
			(type default)
		)
		(layer "In6.Cu")
	)
	(gr_line
		(start 154.506422 -367.683288)
		(end 154.506168 -367.683542)
		(stroke
			(width 0.07112)
			(type default)
		)
		(layer "In6.Cu")
	)
	(gr_line
		(start 154.60853 -380.187962)
		(end 154.444192 -380.087886)
		(stroke
			(width 0.07112)
			(type default)
		)
		(layer "In6.Cu")
	)
	(gr_line
		(start 154.609546 -380.769114)
		(end 154.709622 -380.60503)
		(stroke
			(width 0.07112)
			(type default)
		)
		(layer "In6.Cu")
	)
	(gr_line
		(start 154.617928 -379.02642)
		(end 154.452574 -378.344938)
		(stroke
			(width 0.07112)
			(type default)
		)
		(layer "In6.Cu")
	)
	(gr_line
		(start 154.618944 -385.31038)
		(end 154.972258 -385.405376)
		(stroke
			(width 0.07112)
			(type default)
		)
		(layer "In6.Cu")
	)
	(gr_line
		(start 154.622754 -426.830998)
		(end 154.750008 -426.958252)
		(stroke
			(width 0.07112)
			(type default)
		)
		(layer "In6.Cu")
	)
	(gr_line
		(start 154.622754 -426.548804)
		(end 154.750008 -426.42155)
		(stroke
			(width 0.07112)
			(type default)
		)
		(layer "In6.Cu")
	)
	(gr_line
		(start 154.650186 -402.24456)
		(end 155.044648 -402.407882)
		(stroke
			(width 0.07112)
			(type default)
		)
		(layer "In6.Cu")
	)
	(gr_line
		(start 154.71013 -381.183896)
		(end 154.609546 -380.769114)
		(stroke
			(width 0.07112)
			(type default)
		)
		(layer "In6.Cu")
	)
	(gr_line
		(start 154.750008 -426.958252)
		(end 154.750008 -427.289976)
		(stroke
			(width 0.07112)
			(type default)
		)
		(layer "In6.Cu")
	)
	(gr_line
		(start 154.750008 -426.42155)
		(end 154.750008 -426.089826)
		(stroke
			(width 0.07112)
			(type default)
		)
		(layer "In6.Cu")
	)
	(gr_line
		(start 154.784552 -401.46732)
		(end 155.432506 -401.735798)
		(stroke
			(width 0.07112)
			(type default)
		)
		(layer "In6.Cu")
	)
	(gr_line
		(start 154.874468 -381.283972)
		(end 154.71013 -381.183896)
		(stroke
			(width 0.07112)
			(type default)
		)
		(layer "In6.Cu")
	)
	(gr_line
		(start 154.875992 -381.284988)
		(end 154.876246 -381.284988)
		(stroke
			(width 0.07112)
			(type default)
		)
		(layer "In6.Cu")
	)
	(gr_line
		(start 154.88412 -380.12243)
		(end 154.718766 -379.440948)
		(stroke
			(width 0.07112)
			(type default)
		)
		(layer "In6.Cu")
	)
	(gr_line
		(start 154.893772 -401.206208)
		(end 155.071826 -401.132548)
		(stroke
			(width 0.07112)
			(type default)
		)
		(layer "In6.Cu")
	)
	(gr_line
		(start 154.945588 -416.608768)
		(end 154.67711 -417.256722)
		(stroke
			(width 0.07112)
			(type default)
		)
		(layer "In6.Cu")
	)
	(gr_line
		(start 154.972258 -385.405376)
		(end 154.972766 -385.404868)
		(stroke
			(width 0.07112)
			(type default)
		)
		(layer "In6.Cu")
	)
	(gr_line
		(start 155.010866 -402.84781)
		(end 155.01112 -402.84781)
		(stroke
			(width 0.07112)
			(type default)
		)
		(layer "In6.Cu")
	)
	(gr_line
		(start 155.018994 -386.003292)
		(end 155.113736 -385.649724)
		(stroke
			(width 0.07112)
			(type default)
		)
		(layer "In6.Cu")
	)
	(gr_line
		(start 155.044648 -402.407882)
		(end 155.118308 -402.585682)
		(stroke
			(width 0.07112)
			(type default)
		)
		(layer "In6.Cu")
	)
	(gr_line
		(start 155.071826 -401.132548)
		(end 155.466288 -401.29587)
		(stroke
			(width 0.07112)
			(type default)
		)
		(layer "In6.Cu")
	)
	(gr_line
		(start 155.086304 -382.166368)
		(end 155.08605 -382.166368)
		(stroke
			(width 0.07112)
			(type default)
		)
		(layer "In6.Cu")
	)
	(gr_line
		(start 155.117292 -417.290504)
		(end 154.939238 -417.36391)
		(stroke
			(width 0.07112)
			(type default)
		)
		(layer "In6.Cu")
	)
	(gr_line
		(start 155.150058 -381.21844)
		(end 154.984704 -380.536958)
		(stroke
			(width 0.07112)
			(type default)
		)
		(layer "In6.Cu")
	)
	(gr_line
		(start 155.206954 -416.717988)
		(end 155.280614 -416.895788)
		(stroke
			(width 0.07112)
			(type default)
		)
		(layer "In6.Cu")
	)
	(gr_line
		(start 155.235402 -385.579112)
		(end 155.288234 -385.548632)
		(stroke
			(width 0.07112)
			(type default)
		)
		(layer "In6.Cu")
	)
	(gr_line
		(start 155.280614 -416.895788)
		(end 155.117292 -417.290504)
		(stroke
			(width 0.07112)
			(type default)
		)
		(layer "In6.Cu")
	)
	(gr_line
		(start 155.288234 -385.548632)
		(end 155.376372 -385.460494)
		(stroke
			(width 0.07112)
			(type default)
		)
		(layer "In6.Cu")
	)
	(gr_arc
		(start 155.357322 -382.072642)
		(mid 155.35707 -382.071499)
		(end 155.356814 -382.070356)
		(stroke
			(width 0.07112)
			(type default)
		)
		(layer "In6.Cu")
	)
	(gr_line
		(start 155.376372 -385.460494)
		(end 155.376372 -385.334764)
		(stroke
			(width 0.07112)
			(type default)
		)
		(layer "In6.Cu")
	)
	(gr_line
		(start 155.377388 -415.566606)
		(end 155.10891 -416.214814)
		(stroke
			(width 0.07112)
			(type default)
		)
		(layer "In6.Cu")
	)
	(gr_line
		(start 155.432506 -401.735798)
		(end 155.43276 -401.735798)
		(stroke
			(width 0.07112)
			(type default)
		)
		(layer "In6.Cu")
	)
	(gr_line
		(start 155.466288 -401.29587)
		(end 155.539948 -401.47367)
		(stroke
			(width 0.07112)
			(type default)
		)
		(layer "In6.Cu")
	)
	(gr_line
		(start 155.549092 -416.248342)
		(end 155.371038 -416.322002)
		(stroke
			(width 0.07112)
			(type default)
		)
		(layer "In6.Cu")
	)
	(gr_line
		(start 155.6385 -415.675826)
		(end 155.71216 -415.85388)
		(stroke
			(width 0.07112)
			(type default)
		)
		(layer "In6.Cu")
	)
	(gr_line
		(start 155.71216 -415.85388)
		(end 155.549092 -416.248342)
		(stroke
			(width 0.07112)
			(type default)
		)
		(layer "In6.Cu")
	)
	(gr_line
		(start 155.819094 -385.31038)
		(end 156.172154 -385.405376)
		(stroke
			(width 0.07112)
			(type default)
		)
		(layer "In6.Cu")
	)
	(gr_line
		(start 156.172154 -385.405376)
		(end 156.172662 -385.404868)
		(stroke
			(width 0.07112)
			(type default)
		)
		(layer "In6.Cu")
	)
	(gr_line
		(start 156.182314 -380.98857)
		(end 156.200856 -380.562104)
		(stroke
			(width 0.07112)
			(type default)
		)
		(layer "In6.Cu")
	)
	(gr_line
		(start 156.200856 -380.562104)
		(end 156.342588 -380.43231)
		(stroke
			(width 0.07112)
			(type default)
		)
		(layer "In6.Cu")
	)
	(gr_line
		(start 156.21889 -386.003292)
		(end 156.313632 -385.649724)
		(stroke
			(width 0.07112)
			(type default)
		)
		(layer "In6.Cu")
	)
	(gr_line
		(start 156.231082 -379.861572)
		(end 156.249624 -379.435106)
		(stroke
			(width 0.07112)
			(type default)
		)
		(layer "In6.Cu")
	)
	(gr_line
		(start 156.247846 -410.030168)
		(end 156.538676 -410.320998)
		(stroke
			(width 0.07112)
			(type default)
		)
		(layer "In6.Cu")
	)
	(gr_line
		(start 156.249624 -379.435106)
		(end 156.391102 -379.305566)
		(stroke
			(width 0.07112)
			(type default)
		)
		(layer "In6.Cu")
	)
	(gr_line
		(start 156.279596 -378.734828)
		(end 156.298138 -378.308362)
		(stroke
			(width 0.07112)
			(type default)
		)
		(layer "In6.Cu")
	)
	(gr_line
		(start 156.298138 -378.308362)
		(end 156.439616 -378.178568)
		(stroke
			(width 0.07112)
			(type default)
		)
		(layer "In6.Cu")
	)
	(gr_line
		(start 156.312362 -381.130302)
		(end 156.182314 -380.98857)
		(stroke
			(width 0.07112)
			(type default)
		)
		(layer "In6.Cu")
	)
	(gr_line
		(start 156.344112 -380.430786)
		(end 156.343858 -380.430786)
		(stroke
			(width 0.07112)
			(type default)
		)
		(layer "In6.Cu")
	)
	(gr_line
		(start 156.36113 -380.00305)
		(end 156.231082 -379.861572)
		(stroke
			(width 0.07112)
			(type default)
		)
		(layer "In6.Cu")
	)
	(gr_line
		(start 156.362146 -380.004574)
		(end 156.3624 -380.004574)
		(stroke
			(width 0.07112)
			(type default)
		)
		(layer "In6.Cu")
	)
	(gr_line
		(start 156.392626 -379.304042)
		(end 156.392372 -379.304042)
		(stroke
			(width 0.07112)
			(type default)
		)
		(layer "In6.Cu")
	)
	(gr_line
		(start 156.409644 -378.876306)
		(end 156.279596 -378.734828)
		(stroke
			(width 0.07112)
			(type default)
		)
		(layer "In6.Cu")
	)
	(gr_line
		(start 156.41066 -378.87783)
		(end 156.410914 -378.87783)
		(stroke
			(width 0.07112)
			(type default)
		)
		(layer "In6.Cu")
	)
	(gr_line
		(start 156.435298 -385.579112)
		(end 156.48813 -385.548632)
		(stroke
			(width 0.07112)
			(type default)
		)
		(layer "In6.Cu")
	)
	(gr_line
		(start 156.44114 -378.177298)
		(end 156.440886 -378.177298)
		(stroke
			(width 0.07112)
			(type default)
		)
		(layer "In6.Cu")
	)
	(gr_line
		(start 156.48813 -385.548632)
		(end 156.576268 -385.460494)
		(stroke
			(width 0.07112)
			(type default)
		)
		(layer "In6.Cu")
	)
	(gr_line
		(start 156.52877 -413.083502)
		(end 156.52877 -413.083756)
		(stroke
			(width 0.07112)
			(type default)
		)
		(layer "In6.Cu")
	)
	(gr_line
		(start 156.538676 -411.178756)
		(end 156.538676 -411.879796)
		(stroke
			(width 0.07112)
			(type default)
		)
		(layer "In6.Cu")
	)
	(gr_line
		(start 156.538676 -406.71369)
		(end 156.247846 -407.00452)
		(stroke
			(width 0.07112)
			(type default)
		)
		(layer "In6.Cu")
	)
	(gr_line
		(start 156.576268 -385.460494)
		(end 156.576268 -385.334764)
		(stroke
			(width 0.07112)
			(type default)
		)
		(layer "In6.Cu")
	)
	(gr_line
		(start 156.595318 -381.143764)
		(end 156.625544 -380.442978)
		(stroke
			(width 0.07112)
			(type default)
		)
		(layer "In6.Cu")
	)
	(gr_line
		(start 156.62275 -427.830742)
		(end 156.750004 -427.957996)
		(stroke
			(width 0.07112)
			(type default)
		)
		(layer "In6.Cu")
	)
	(gr_line
		(start 156.62275 -427.548802)
		(end 156.750004 -427.421548)
		(stroke
			(width 0.07112)
			(type default)
		)
		(layer "In6.Cu")
	)
	(gr_line
		(start 156.643832 -380.016766)
		(end 156.674058 -379.316234)
		(stroke
			(width 0.07112)
			(type default)
		)
		(layer "In6.Cu")
	)
	(gr_line
		(start 156.692346 -378.890022)
		(end 156.722572 -378.18949)
		(stroke
			(width 0.07112)
			(type default)
		)
		(layer "In6.Cu")
	)
	(gr_line
		(start 156.750004 -427.957996)
		(end 156.750004 -428.28972)
		(stroke
			(width 0.07112)
			(type default)
		)
		(layer "In6.Cu")
	)
	(gr_line
		(start 156.750004 -427.421548)
		(end 156.750004 -427.089824)
		(stroke
			(width 0.07112)
			(type default)
		)
		(layer "In6.Cu")
	)
	(gr_arc
		(start 156.798518 -369.991132)
		(mid 156.798137 -369.990751)
		(end 156.797756 -369.99037)
		(stroke
			(width 0.07112)
			(type default)
		)
		(layer "In6.Cu")
	)
	(gr_line
		(start 156.820616 -413.034988)
		(end 156.820616 -413.03575)
		(stroke
			(width 0.07112)
			(type default)
		)
		(layer "In6.Cu")
	)
	(gr_line
		(start 156.820616 -406.71369)
		(end 157.111446 -407.00452)
		(stroke
			(width 0.07112)
			(type default)
		)
		(layer "In6.Cu")
	)
	(gr_line
		(start 156.821886 -411.180026)
		(end 156.957776 -411.315916)
		(stroke
			(width 0.07112)
			(type default)
		)
		(layer "In6.Cu")
	)
	(gr_line
		(start 156.957776 -411.742636)
		(end 156.821886 -411.878526)
		(stroke
			(width 0.07112)
			(type default)
		)
		(layer "In6.Cu")
	)
	(gr_line
		(start 156.957776 -411.315916)
		(end 156.957776 -411.742636)
		(stroke
			(width 0.07112)
			(type default)
		)
		(layer "In6.Cu")
	)
	(gr_line
		(start 157.01899 -385.31038)
		(end 157.372304 -385.405376)
		(stroke
			(width 0.07112)
			(type default)
		)
		(layer "In6.Cu")
	)
	(gr_line
		(start 157.111446 -410.030168)
		(end 156.820616 -410.320998)
		(stroke
			(width 0.07112)
			(type default)
		)
		(layer "In6.Cu")
	)
	(gr_line
		(start 157.372304 -385.405376)
		(end 157.372812 -385.404868)
		(stroke
			(width 0.07112)
			(type default)
		)
		(layer "In6.Cu")
	)
	(gr_line
		(start 157.37332 -379.741938)
		(end 157.391354 -379.315472)
		(stroke
			(width 0.07112)
			(type default)
		)
		(layer "In6.Cu")
	)
	(gr_line
		(start 157.391354 -379.315472)
		(end 157.533086 -379.185424)
		(stroke
			(width 0.07112)
			(type default)
		)
		(layer "In6.Cu")
	)
	(gr_line
		(start 157.41904 -386.003292)
		(end 157.513782 -385.649724)
		(stroke
			(width 0.07112)
			(type default)
		)
		(layer "In6.Cu")
	)
	(gr_line
		(start 157.421072 -378.61494)
		(end 157.439106 -378.188474)
		(stroke
			(width 0.07112)
			(type default)
		)
		(layer "In6.Cu")
	)
	(gr_line
		(start 157.439106 -378.188474)
		(end 157.580838 -378.058426)
		(stroke
			(width 0.07112)
			(type default)
		)
		(layer "In6.Cu")
	)
	(gr_line
		(start 157.45333 -417.437062)
		(end 157.122876 -418.055552)
		(stroke
			(width 0.07112)
			(type default)
		)
		(layer "In6.Cu")
	)
	(gr_line
		(start 157.47492 -377.347988)
		(end 157.492954 -376.921522)
		(stroke
			(width 0.07112)
			(type default)
		)
		(layer "In6.Cu")
	)
	(gr_line
		(start 157.492954 -376.921522)
		(end 157.634686 -376.791728)
		(stroke
			(width 0.07112)
			(type default)
		)
		(layer "In6.Cu")
	)
	(gr_line
		(start 157.503368 -379.88367)
		(end 157.37332 -379.741938)
		(stroke
			(width 0.07112)
			(type default)
		)
		(layer "In6.Cu")
	)
	(gr_line
		(start 157.551374 -378.756672)
		(end 157.421072 -378.61494)
		(stroke
			(width 0.07112)
			(type default)
		)
		(layer "In6.Cu")
	)
	(gr_line
		(start 157.557216 -418.13226)
		(end 157.373066 -418.187886)
		(stroke
			(width 0.07112)
			(type default)
		)
		(layer "In6.Cu")
	)
	(gr_line
		(start 157.582362 -378.057156)
		(end 157.581854 -378.056902)
		(stroke
			(width 0.07112)
			(type default)
		)
		(layer "In6.Cu")
	)
	(gr_line
		(start 157.604968 -377.48972)
		(end 157.47492 -377.347988)
		(stroke
			(width 0.07112)
			(type default)
		)
		(layer "In6.Cu")
	)
	(gr_line
		(start 157.605984 -377.49099)
		(end 157.606238 -377.49099)
		(stroke
			(width 0.07112)
			(type default)
		)
		(layer "In6.Cu")
	)
	(gr_line
		(start 157.635448 -385.579112)
		(end 157.68828 -385.548632)
		(stroke
			(width 0.07112)
			(type default)
		)
		(layer "In6.Cu")
	)
	(gr_line
		(start 157.63621 -376.790204)
		(end 157.635702 -376.78995)
		(stroke
			(width 0.07112)
			(type default)
		)
		(layer "In6.Cu")
	)
	(gr_line
		(start 157.68828 -385.548632)
		(end 157.776418 -385.460494)
		(stroke
			(width 0.07112)
			(type default)
		)
		(layer "In6.Cu")
	)
	(gr_line
		(start 157.702758 -417.571428)
		(end 157.758384 -417.755578)
		(stroke
			(width 0.07112)
			(type default)
		)
		(layer "In6.Cu")
	)
	(gr_line
		(start 157.758384 -417.755578)
		(end 157.557216 -418.13226)
		(stroke
			(width 0.07112)
			(type default)
		)
		(layer "In6.Cu")
	)
	(gr_line
		(start 157.776418 -385.460494)
		(end 157.776418 -385.334764)
		(stroke
			(width 0.07112)
			(type default)
		)
		(layer "In6.Cu")
	)
	(gr_line
		(start 157.786324 -379.896878)
		(end 157.816042 -379.196092)
		(stroke
			(width 0.07112)
			(type default)
		)
		(layer "In6.Cu")
	)
	(gr_line
		(start 157.834076 -378.76988)
		(end 157.863794 -378.06884)
		(stroke
			(width 0.07112)
			(type default)
		)
		(layer "In6.Cu")
	)
	(gr_line
		(start 157.887924 -377.502928)
		(end 157.917642 -376.801888)
		(stroke
			(width 0.07112)
			(type default)
		)
		(layer "In6.Cu")
	)
	(gr_line
		(start 157.984952 -416.442398)
		(end 157.654498 -417.060888)
		(stroke
			(width 0.07112)
			(type default)
		)
		(layer "In6.Cu")
	)
	(gr_line
		(start 158.088838 -417.137596)
		(end 157.904688 -417.193222)
		(stroke
			(width 0.07112)
			(type default)
		)
		(layer "In6.Cu")
	)
	(gr_line
		(start 158.218886 -385.31038)
		(end 158.5722 -385.405376)
		(stroke
			(width 0.07112)
			(type default)
		)
		(layer "In6.Cu")
	)
	(gr_line
		(start 158.23438 -416.576764)
		(end 158.290006 -416.760914)
		(stroke
			(width 0.07112)
			(type default)
		)
		(layer "In6.Cu")
	)
	(gr_line
		(start 158.290006 -416.760914)
		(end 158.088838 -417.137596)
		(stroke
			(width 0.07112)
			(type default)
		)
		(layer "In6.Cu")
	)
	(gr_line
		(start 158.516574 -415.44748)
		(end 158.18612 -416.066224)
		(stroke
			(width 0.07112)
			(type default)
		)
		(layer "In6.Cu")
	)
	(gr_line
		(start 158.560262 -381.206756)
		(end 158.566358 -380.779782)
		(stroke
			(width 0.07112)
			(type default)
		)
		(layer "In6.Cu")
	)
	(gr_line
		(start 158.566358 -380.779782)
		(end 158.70428 -380.645924)
		(stroke
			(width 0.07112)
			(type default)
		)
		(layer "In6.Cu")
	)
	(gr_line
		(start 158.5722 -385.405376)
		(end 158.572708 -385.404868)
		(stroke
			(width 0.07112)
			(type default)
		)
		(layer "In6.Cu")
	)
	(gr_line
		(start 158.576264 -380.078996)
		(end 158.58236 -379.652022)
		(stroke
			(width 0.07112)
			(type default)
		)
		(layer "In6.Cu")
	)
	(gr_line
		(start 158.58236 -379.652022)
		(end 158.720028 -379.518164)
		(stroke
			(width 0.07112)
			(type default)
		)
		(layer "In6.Cu")
	)
	(gr_line
		(start 158.592266 -378.951236)
		(end 158.598362 -378.524262)
		(stroke
			(width 0.07112)
			(type default)
		)
		(layer "In6.Cu")
	)
	(gr_line
		(start 158.598362 -378.524262)
		(end 158.73603 -378.390658)
		(stroke
			(width 0.07112)
			(type default)
		)
		(layer "In6.Cu")
	)
	(gr_line
		(start 158.618936 -386.003292)
		(end 158.713678 -385.649724)
		(stroke
			(width 0.07112)
			(type default)
		)
		(layer "In6.Cu")
	)
	(gr_line
		(start 158.620714 -416.142678)
		(end 158.436564 -416.198558)
		(stroke
			(width 0.07112)
			(type default)
		)
		(layer "In6.Cu")
	)
	(gr_line
		(start 158.694374 -381.344678)
		(end 158.560262 -381.206756)
		(stroke
			(width 0.07112)
			(type default)
		)
		(layer "In6.Cu")
	)
	(gr_line
		(start 158.70555 -380.644654)
		(end 158.705296 -380.644654)
		(stroke
			(width 0.07112)
			(type default)
		)
		(layer "In6.Cu")
	)
	(gr_line
		(start 158.710122 -380.216918)
		(end 158.576264 -380.078996)
		(stroke
			(width 0.07112)
			(type default)
		)
		(layer "In6.Cu")
	)
	(gr_line
		(start 158.721552 -379.516894)
		(end 158.721298 -379.516894)
		(stroke
			(width 0.07112)
			(type default)
		)
		(layer "In6.Cu")
	)
	(gr_line
		(start 158.726124 -379.089158)
		(end 158.592266 -378.951236)
		(stroke
			(width 0.07112)
			(type default)
		)
		(layer "In6.Cu")
	)
	(gr_line
		(start 158.737554 -378.389134)
		(end 158.7373 -378.389134)
		(stroke
			(width 0.07112)
			(type default)
		)
		(layer "In6.Cu")
	)
	(gr_line
		(start 158.766002 -415.5821)
		(end 158.821882 -415.76625)
		(stroke
			(width 0.07112)
			(type default)
		)
		(layer "In6.Cu")
	)
	(gr_line
		(start 158.821882 -415.76625)
		(end 158.620714 -416.142678)
		(stroke
			(width 0.07112)
			(type default)
		)
		(layer "In6.Cu")
	)
	(gr_line
		(start 158.835344 -385.579112)
		(end 158.888176 -385.548632)
		(stroke
			(width 0.07112)
			(type default)
		)
		(layer "In6.Cu")
	)
	(gr_line
		(start 158.888176 -385.548632)
		(end 158.976314 -385.460494)
		(stroke
			(width 0.07112)
			(type default)
		)
		(layer "In6.Cu")
	)
	(gr_line
		(start 158.976314 -385.460494)
		(end 158.976314 -385.334764)
		(stroke
			(width 0.07112)
			(type default)
		)
		(layer "In6.Cu")
	)
	(gr_line
		(start 158.97733 -381.350012)
		(end 158.98749 -380.648718)
		(stroke
			(width 0.07112)
			(type default)
		)
		(layer "In6.Cu")
	)
	(gr_line
		(start 158.993332 -380.222252)
		(end 159.003238 -379.520958)
		(stroke
			(width 0.07112)
			(type default)
		)
		(layer "In6.Cu")
	)
	(gr_line
		(start 159.009334 -379.094492)
		(end 159.01924 -378.393198)
		(stroke
			(width 0.07112)
			(type default)
		)
		(layer "In6.Cu")
	)
	(gr_line
		(start 159.311086 -410.030168)
		(end 159.601916 -410.320998)
		(stroke
			(width 0.07112)
			(type default)
		)
		(layer "In6.Cu")
	)
	(gr_line
		(start 159.419036 -385.31038)
		(end 159.77235 -385.405376)
		(stroke
			(width 0.07112)
			(type default)
		)
		(layer "In6.Cu")
	)
	(gr_line
		(start 159.434022 -413.731456)
		(end 159.103568 -414.349946)
		(stroke
			(width 0.07112)
			(type default)
		)
		(layer "In6.Cu")
	)
	(gr_line
		(start 159.537908 -414.426654)
		(end 159.353758 -414.48228)
		(stroke
			(width 0.07112)
			(type default)
		)
		(layer "In6.Cu")
	)
	(gr_line
		(start 159.601916 -411.100524)
		(end 159.601916 -411.801564)
		(stroke
			(width 0.07112)
			(type default)
		)
		(layer "In6.Cu")
	)
	(gr_line
		(start 159.601916 -406.71369)
		(end 159.311086 -407.00452)
		(stroke
			(width 0.07112)
			(type default)
		)
		(layer "In6.Cu")
	)
	(gr_line
		(start 159.68345 -413.865568)
		(end 159.739076 -414.049972)
		(stroke
			(width 0.07112)
			(type default)
		)
		(layer "In6.Cu")
	)
	(gr_line
		(start 159.739076 -414.049972)
		(end 159.537908 -414.426654)
		(stroke
			(width 0.07112)
			(type default)
		)
		(layer "In6.Cu")
	)
	(gr_line
		(start 159.749236 -381.34798)
		(end 159.749236 -380.92126)
		(stroke
			(width 0.07112)
			(type default)
		)
		(layer "In6.Cu")
	)
	(gr_line
		(start 159.749236 -380.92126)
		(end 159.885126 -380.78537)
		(stroke
			(width 0.07112)
			(type default)
		)
		(layer "In6.Cu")
	)
	(gr_line
		(start 159.749236 -380.22022)
		(end 159.749236 -379.7935)
		(stroke
			(width 0.07112)
			(type default)
		)
		(layer "In6.Cu")
	)
	(gr_line
		(start 159.749236 -379.7935)
		(end 159.885126 -379.65761)
		(stroke
			(width 0.07112)
			(type default)
		)
		(layer "In6.Cu")
	)
	(gr_line
		(start 159.749236 -379.09246)
		(end 159.749236 -378.66574)
		(stroke
			(width 0.07112)
			(type default)
		)
		(layer "In6.Cu")
	)
	(gr_line
		(start 159.749236 -378.66574)
		(end 159.885126 -378.52985)
		(stroke
			(width 0.07112)
			(type default)
		)
		(layer "In6.Cu")
	)
	(gr_line
		(start 159.77235 -385.405376)
		(end 159.772858 -385.404868)
		(stroke
			(width 0.07112)
			(type default)
		)
		(layer "In6.Cu")
	)
	(gr_line
		(start 159.819086 -386.003292)
		(end 159.913828 -385.649724)
		(stroke
			(width 0.07112)
			(type default)
		)
		(layer "In6.Cu")
	)
	(gr_line
		(start 159.883856 -406.71369)
		(end 160.174686 -407.00452)
		(stroke
			(width 0.07112)
			(type default)
		)
		(layer "In6.Cu")
	)
	(gr_line
		(start 159.885126 -411.101794)
		(end 160.021016 -411.237684)
		(stroke
			(width 0.07112)
			(type default)
		)
		(layer "In6.Cu")
	)
	(gr_line
		(start 159.885126 -381.48387)
		(end 159.749236 -381.34798)
		(stroke
			(width 0.07112)
			(type default)
		)
		(layer "In6.Cu")
	)
	(gr_line
		(start 159.885126 -380.35611)
		(end 159.749236 -380.22022)
		(stroke
			(width 0.07112)
			(type default)
		)
		(layer "In6.Cu")
	)
	(gr_line
		(start 159.885126 -379.22835)
		(end 159.749236 -379.09246)
		(stroke
			(width 0.07112)
			(type default)
		)
		(layer "In6.Cu")
	)
	(gr_line
		(start 160.021016 -411.664404)
		(end 159.885126 -411.800294)
		(stroke
			(width 0.07112)
			(type default)
		)
		(layer "In6.Cu")
	)
	(gr_line
		(start 160.021016 -411.237684)
		(end 160.021016 -411.664404)
		(stroke
			(width 0.07112)
			(type default)
		)
		(layer "In6.Cu")
	)
	(gr_line
		(start 160.035494 -385.579112)
		(end 160.088326 -385.548632)
		(stroke
			(width 0.07112)
			(type default)
		)
		(layer "In6.Cu")
	)
	(gr_line
		(start 160.088326 -385.548632)
		(end 160.176464 -385.460494)
		(stroke
			(width 0.07112)
			(type default)
		)
		(layer "In6.Cu")
	)
	(gr_line
		(start 160.168336 -381.48514)
		(end 160.168336 -380.7841)
		(stroke
			(width 0.07112)
			(type default)
		)
		(layer "In6.Cu")
	)
	(gr_line
		(start 160.168336 -380.35738)
		(end 160.168336 -379.65634)
		(stroke
			(width 0.07112)
			(type default)
		)
		(layer "In6.Cu")
	)
	(gr_line
		(start 160.168336 -379.22962)
		(end 160.168336 -378.52858)
		(stroke
			(width 0.07112)
			(type default)
		)
		(layer "In6.Cu")
	)
	(gr_line
		(start 160.174686 -410.030168)
		(end 159.883856 -410.320998)
		(stroke
			(width 0.07112)
			(type default)
		)
		(layer "In6.Cu")
	)
	(gr_line
		(start 160.176464 -385.460494)
		(end 160.176464 -385.334764)
		(stroke
			(width 0.07112)
			(type default)
		)
		(layer "In6.Cu")
	)
	(gr_line
		(start 160.235646 -371.06479)
		(end 160.235646 -371.066314)
		(stroke
			(width 0.07112)
			(type default)
		)
		(layer "In6.Cu")
	)
	(gr_line
		(start 160.333182 -416.94608)
		(end 159.943546 -417.529264)
		(stroke
			(width 0.07112)
			(type default)
		)
		(layer "In6.Cu")
	)
	(gr_line
		(start 160.368234 -417.648136)
		(end 160.179512 -417.685728)
		(stroke
			(width 0.07112)
			(type default)
		)
		(layer "In6.Cu")
	)
	(gr_line
		(start 160.567878 -417.104322)
		(end 160.60547 -417.293044)
		(stroke
			(width 0.07112)
			(type default)
		)
		(layer "In6.Cu")
	)
	(gr_line
		(start 160.60547 -417.293044)
		(end 160.368234 -417.648136)
		(stroke
			(width 0.07112)
			(type default)
		)
		(layer "In6.Cu")
	)
	(gr_line
		(start 160.618932 -385.31038)
		(end 160.972246 -385.405376)
		(stroke
			(width 0.07112)
			(type default)
		)
		(layer "In6.Cu")
	)
	(gr_line
		(start 160.972246 -385.405376)
		(end 160.972754 -385.404868)
		(stroke
			(width 0.07112)
			(type default)
		)
		(layer "In6.Cu")
	)
	(gr_line
		(start 161.018982 -386.003292)
		(end 161.113724 -385.649724)
		(stroke
			(width 0.07112)
			(type default)
		)
		(layer "In6.Cu")
	)
	(gr_arc
		(start 161.052256 -383.963418)
		(mid 161.073944 -383.926255)
		(end 161.085022 -383.884678)
		(stroke
			(width 0.07112)
			(type default)
		)
		(layer "In6.Cu")
	)
	(gr_line
		(start 161.062416 -415.854642)
		(end 160.67278 -416.437826)
		(stroke
			(width 0.07112)
			(type default)
		)
		(layer "In6.Cu")
	)
	(gr_line
		(start 161.097468 -416.556698)
		(end 160.908746 -416.59429)
		(stroke
			(width 0.07112)
			(type default)
		)
		(layer "In6.Cu")
	)
	(gr_line
		(start 161.12871 -381.895604)
		(end 161.128964 -381.89535)
		(stroke
			(width 0.07112)
			(type default)
		)
		(layer "In6.Cu")
	)
	(gr_line
		(start 161.23539 -385.579112)
		(end 161.288222 -385.548632)
		(stroke
			(width 0.07112)
			(type default)
		)
		(layer "In6.Cu")
	)
	(gr_line
		(start 161.261806 -384.154426)
		(end 161.368232 -384.048)
		(stroke
			(width 0.07112)
			(type default)
		)
		(layer "In6.Cu")
	)
	(gr_line
		(start 161.288222 -385.548632)
		(end 161.37636 -385.460494)
		(stroke
			(width 0.07112)
			(type default)
		)
		(layer "In6.Cu")
	)
	(gr_line
		(start 161.297112 -416.013138)
		(end 161.334704 -416.201606)
		(stroke
			(width 0.07112)
			(type default)
		)
		(layer "In6.Cu")
	)
	(gr_line
		(start 161.334704 -416.201606)
		(end 161.097468 -416.556698)
		(stroke
			(width 0.07112)
			(type default)
		)
		(layer "In6.Cu")
	)
	(gr_line
		(start 161.368232 -384.048)
		(end 161.368232 -383.897886)
		(stroke
			(width 0.07112)
			(type default)
		)
		(layer "In6.Cu")
	)
	(gr_line
		(start 161.37636 -385.460494)
		(end 161.37636 -385.334764)
		(stroke
			(width 0.07112)
			(type default)
		)
		(layer "In6.Cu")
	)
	(gr_line
		(start 161.819082 -385.31038)
		(end 162.172142 -385.405376)
		(stroke
			(width 0.07112)
			(type default)
		)
		(layer "In6.Cu")
	)
	(gr_line
		(start 161.864548 -379.63348)
		(end 162.019742 -379.235716)
		(stroke
			(width 0.07112)
			(type default)
		)
		(layer "In6.Cu")
	)
	(gr_line
		(start 161.941764 -379.809502)
		(end 161.864548 -379.63348)
		(stroke
			(width 0.07112)
			(type default)
		)
		(layer "In6.Cu")
	)
	(gr_line
		(start 161.942272 -379.81128)
		(end 161.942526 -379.81128)
		(stroke
			(width 0.07112)
			(type default)
		)
		(layer "In6.Cu")
	)
	(gr_line
		(start 162.019742 -379.235716)
		(end 162.196018 -379.1585)
		(stroke
			(width 0.07112)
			(type default)
		)
		(layer "In6.Cu")
	)
	(gr_line
		(start 162.172142 -385.405376)
		(end 162.17265 -385.404868)
		(stroke
			(width 0.07112)
			(type default)
		)
		(layer "In6.Cu")
	)
	(gr_line
		(start 162.205162 -379.913896)
		(end 162.460178 -379.2601)
		(stroke
			(width 0.07112)
			(type default)
		)
		(layer "In6.Cu")
	)
	(gr_line
		(start 162.218878 -386.003292)
		(end 162.31362 -385.649724)
		(stroke
			(width 0.07112)
			(type default)
		)
		(layer "In6.Cu")
	)
	(gr_line
		(start 162.274758 -378.582682)
		(end 162.429952 -378.184918)
		(stroke
			(width 0.07112)
			(type default)
		)
		(layer "In6.Cu")
	)
	(gr_line
		(start 162.27933 -414.033462)
		(end 161.889694 -414.616646)
		(stroke
			(width 0.07112)
			(type default)
		)
		(layer "In6.Cu")
	)
	(gr_line
		(start 162.314382 -414.735518)
		(end 162.12566 -414.77311)
		(stroke
			(width 0.07112)
			(type default)
		)
		(layer "In6.Cu")
	)
	(gr_line
		(start 162.351974 -378.758958)
		(end 162.274758 -378.582682)
		(stroke
			(width 0.07112)
			(type default)
		)
		(layer "In6.Cu")
	)
	(gr_line
		(start 162.374326 -410.030168)
		(end 162.665156 -410.320998)
		(stroke
			(width 0.07112)
			(type default)
		)
		(layer "In6.Cu")
	)
	(gr_line
		(start 162.429952 -378.184918)
		(end 162.605974 -378.107702)
		(stroke
			(width 0.07112)
			(type default)
		)
		(layer "In6.Cu")
	)
	(gr_line
		(start 162.435286 -385.579112)
		(end 162.488118 -385.548632)
		(stroke
			(width 0.07112)
			(type default)
		)
		(layer "In6.Cu")
	)
	(gr_line
		(start 162.488118 -385.548632)
		(end 162.576256 -385.460494)
		(stroke
			(width 0.07112)
			(type default)
		)
		(layer "In6.Cu")
	)
	(gr_line
		(start 162.514026 -414.191704)
		(end 162.551618 -414.380426)
		(stroke
			(width 0.07112)
			(type default)
		)
		(layer "In6.Cu")
	)
	(gr_line
		(start 162.551618 -414.380426)
		(end 162.314382 -414.735518)
		(stroke
			(width 0.07112)
			(type default)
		)
		(layer "In6.Cu")
	)
	(gr_line
		(start 162.576256 -385.460494)
		(end 162.576256 -385.334764)
		(stroke
			(width 0.07112)
			(type default)
		)
		(layer "In6.Cu")
	)
	(gr_line
		(start 162.607752 -378.10694)
		(end 162.61207 -378.096018)
		(stroke
			(width 0.07112)
			(type default)
		)
		(layer "In6.Cu")
	)
	(gr_line
		(start 162.615372 -378.86259)
		(end 162.870388 -378.209302)
		(stroke
			(width 0.07112)
			(type default)
		)
		(layer "In6.Cu")
	)
	(gr_line
		(start 162.665156 -411.069536)
		(end 162.665156 -411.770576)
		(stroke
			(width 0.07112)
			(type default)
		)
		(layer "In6.Cu")
	)
	(gr_line
		(start 162.684968 -377.531884)
		(end 162.840162 -377.13412)
		(stroke
			(width 0.07112)
			(type default)
		)
		(layer "In6.Cu")
	)
	(gr_line
		(start 162.69208 -406.686766)
		(end 162.374326 -407.00452)
		(stroke
			(width 0.07112)
			(type default)
		)
		(layer "In6.Cu")
	)
	(gr_line
		(start 162.701224 -363.255814)
		(end 162.701224 -363.25556)
		(stroke
			(width 0.07112)
			(type default)
		)
		(layer "In6.Cu")
	)
	(gr_line
		(start 162.762184 -377.70816)
		(end 162.684968 -377.531884)
		(stroke
			(width 0.07112)
			(type default)
		)
		(layer "In6.Cu")
	)
	(gr_line
		(start 162.840162 -377.13412)
		(end 163.016184 -377.056904)
		(stroke
			(width 0.07112)
			(type default)
		)
		(layer "In6.Cu")
	)
	(gr_line
		(start 162.867594 -380.137924)
		(end 163.03371 -379.744732)
		(stroke
			(width 0.07112)
			(type default)
		)
		(layer "In6.Cu")
	)
	(gr_line
		(start 162.870388 -378.209302)
		(end 162.874706 -378.19838)
		(stroke
			(width 0.07112)
			(type default)
		)
		(layer "In6.Cu")
	)
	(gr_line
		(start 162.940238 -380.316232)
		(end 162.867594 -380.137924)
		(stroke
			(width 0.07112)
			(type default)
		)
		(layer "In6.Cu")
	)
	(gr_line
		(start 162.948366 -411.070806)
		(end 163.084256 -411.206696)
		(stroke
			(width 0.07112)
			(type default)
		)
		(layer "In6.Cu")
	)
	(gr_line
		(start 162.97529 -406.741884)
		(end 163.237926 -407.00452)
		(stroke
			(width 0.07112)
			(type default)
		)
		(layer "In6.Cu")
	)
	(gr_line
		(start 162.97529 -406.685496)
		(end 162.97529 -406.741884)
		(stroke
			(width 0.07112)
			(type default)
		)
		(layer "In6.Cu")
	)
	(gr_line
		(start 163.017962 -377.056142)
		(end 163.017962 -377.055888)
		(stroke
			(width 0.07112)
			(type default)
		)
		(layer "In6.Cu")
	)
	(gr_line
		(start 163.018978 -385.31038)
		(end 163.372292 -385.405376)
		(stroke
			(width 0.07112)
			(type default)
		)
		(layer "In6.Cu")
	)
	(gr_line
		(start 163.025582 -377.811792)
		(end 163.280598 -377.158504)
		(stroke
			(width 0.07112)
			(type default)
		)
		(layer "In6.Cu")
	)
	(gr_line
		(start 163.03371 -379.744732)
		(end 163.212018 -379.672342)
		(stroke
			(width 0.07112)
			(type default)
		)
		(layer "In6.Cu")
	)
	(gr_line
		(start 163.084256 -411.633416)
		(end 162.948366 -411.769306)
		(stroke
			(width 0.07112)
			(type default)
		)
		(layer "In6.Cu")
	)
	(gr_line
		(start 163.084256 -411.206696)
		(end 163.084256 -411.633416)
		(stroke
			(width 0.07112)
			(type default)
		)
		(layer "In6.Cu")
	)
	(gr_line
		(start 163.200588 -380.427484)
		(end 163.473384 -379.781308)
		(stroke
			(width 0.07112)
			(type default)
		)
		(layer "In6.Cu")
	)
	(gr_line
		(start 163.237926 -410.030168)
		(end 162.947096 -410.320998)
		(stroke
			(width 0.07112)
			(type default)
		)
		(layer "In6.Cu")
	)
	(gr_line
		(start 163.306252 -379.09881)
		(end 163.472114 -378.705364)
		(stroke
			(width 0.07112)
			(type default)
		)
		(layer "In6.Cu")
	)
	(gr_line
		(start 163.372292 -385.405376)
		(end 163.3728 -385.404868)
		(stroke
			(width 0.07112)
			(type default)
		)
		(layer "In6.Cu")
	)
	(gr_line
		(start 163.378642 -379.277118)
		(end 163.306252 -379.09881)
		(stroke
			(width 0.07112)
			(type default)
		)
		(layer "In6.Cu")
	)
	(gr_line
		(start 163.419028 -386.003292)
		(end 163.51377 -385.649724)
		(stroke
			(width 0.07112)
			(type default)
		)
		(layer "In6.Cu")
	)
	(gr_line
		(start 163.472114 -378.705364)
		(end 163.650422 -378.633228)
		(stroke
			(width 0.07112)
			(type default)
		)
		(layer "In6.Cu")
	)
	(gr_arc
		(start 163.605718 -369.991132)
		(mid 163.605337 -369.990751)
		(end 163.604956 -369.99037)
		(stroke
			(width 0.07112)
			(type default)
		)
		(layer "In6.Cu")
	)
	(gr_line
		(start 163.635436 -385.579112)
		(end 163.688268 -385.548632)
		(stroke
			(width 0.07112)
			(type default)
		)
		(layer "In6.Cu")
	)
	(gr_line
		(start 163.639246 -379.38837)
		(end 163.911788 -378.742194)
		(stroke
			(width 0.07112)
			(type default)
		)
		(layer "In6.Cu")
	)
	(gr_line
		(start 163.6522 -378.632466)
		(end 163.651946 -378.632466)
		(stroke
			(width 0.07112)
			(type default)
		)
		(layer "In6.Cu")
	)
	(gr_line
		(start 163.688268 -385.548632)
		(end 163.776406 -385.460494)
		(stroke
			(width 0.07112)
			(type default)
		)
		(layer "In6.Cu")
	)
	(gr_line
		(start 163.74491 -378.059696)
		(end 163.910772 -377.66625)
		(stroke
			(width 0.07112)
			(type default)
		)
		(layer "In6.Cu")
	)
	(gr_line
		(start 163.776406 -385.460494)
		(end 163.776406 -385.334764)
		(stroke
			(width 0.07112)
			(type default)
		)
		(layer "In6.Cu")
	)
	(gr_line
		(start 163.8173 -378.23775)
		(end 163.74491 -378.059696)
		(stroke
			(width 0.07112)
			(type default)
		)
		(layer "In6.Cu")
	)
	(gr_line
		(start 163.817808 -378.239528)
		(end 163.818062 -378.239528)
		(stroke
			(width 0.07112)
			(type default)
		)
		(layer "In6.Cu")
	)
	(gr_line
		(start 163.910772 -377.66625)
		(end 164.08908 -377.594114)
		(stroke
			(width 0.07112)
			(type default)
		)
		(layer "In6.Cu")
	)
	(gr_line
		(start 164.07765 -378.349256)
		(end 164.350446 -377.702826)
		(stroke
			(width 0.07112)
			(type default)
		)
		(layer "In6.Cu")
	)
	(gr_line
		(start 164.090858 -377.593352)
		(end 164.090604 -377.593098)
		(stroke
			(width 0.07112)
			(type default)
		)
		(layer "In6.Cu")
	)
	(gr_line
		(start 164.219128 -385.31038)
		(end 164.572188 -385.405376)
		(stroke
			(width 0.07112)
			(type default)
		)
		(layer "In6.Cu")
	)
	(gr_line
		(start 164.330126 -380.248668)
		(end 164.537644 -379.875542)
		(stroke
			(width 0.07112)
			(type default)
		)
		(layer "In6.Cu")
	)
	(gr_line
		(start 164.382704 -380.433326)
		(end 164.330126 -380.248668)
		(stroke
			(width 0.07112)
			(type default)
		)
		(layer "In6.Cu")
	)
	(gr_line
		(start 164.537644 -379.875542)
		(end 164.72281 -379.822964)
		(stroke
			(width 0.07112)
			(type default)
		)
		(layer "In6.Cu")
	)
	(gr_line
		(start 164.572188 -385.405376)
		(end 164.572696 -385.404868)
		(stroke
			(width 0.07112)
			(type default)
		)
		(layer "In6.Cu")
	)
	(gr_line
		(start 164.618924 -386.003292)
		(end 164.713666 -385.649724)
		(stroke
			(width 0.07112)
			(type default)
		)
		(layer "In6.Cu")
	)
	(gr_line
		(start 164.629592 -380.572264)
		(end 164.970968 -379.959616)
		(stroke
			(width 0.07112)
			(type default)
		)
		(layer "In6.Cu")
	)
	(gr_line
		(start 164.835332 -385.579112)
		(end 164.888164 -385.548632)
		(stroke
			(width 0.07112)
			(type default)
		)
		(layer "In6.Cu")
	)
	(gr_line
		(start 164.87902 -379.263148)
		(end 165.086792 -378.890276)
		(stroke
			(width 0.07112)
			(type default)
		)
		(layer "In6.Cu")
	)
	(gr_line
		(start 164.888164 -385.548632)
		(end 164.976302 -385.460494)
		(stroke
			(width 0.07112)
			(type default)
		)
		(layer "In6.Cu")
	)
	(gr_line
		(start 164.931598 -379.44806)
		(end 164.87902 -379.263148)
		(stroke
			(width 0.07112)
			(type default)
		)
		(layer "In6.Cu")
	)
	(gr_line
		(start 164.970968 -379.959616)
		(end 165.07714 -379.768862)
		(stroke
			(width 0.07112)
			(type default)
		)
		(layer "In6.Cu")
	)
	(gr_line
		(start 164.976302 -385.460494)
		(end 164.976302 -385.334764)
		(stroke
			(width 0.07112)
			(type default)
		)
		(layer "In6.Cu")
	)
	(gr_line
		(start 165.0619 -371.223286)
		(end 165.061646 -371.22354)
		(stroke
			(width 0.07112)
			(type default)
		)
		(layer "In6.Cu")
	)
	(gr_line
		(start 165.086792 -378.890276)
		(end 165.271704 -378.837698)
		(stroke
			(width 0.07112)
			(type default)
		)
		(layer "In6.Cu")
	)
	(gr_line
		(start 165.09492 -364.405418)
		(end 165.047422 -364.231936)
		(stroke
			(width 0.07112)
			(type default)
		)
		(layer "In6.Cu")
	)
	(gr_line
		(start 165.178486 -379.586998)
		(end 165.519862 -378.97435)
		(stroke
			(width 0.07112)
			(type default)
		)
		(layer "In6.Cu")
	)
	(gr_line
		(start 165.419024 -385.31038)
		(end 165.772338 -385.405376)
		(stroke
			(width 0.07112)
			(type default)
		)
		(layer "In6.Cu")
	)
	(gr_line
		(start 165.427914 -378.277882)
		(end 165.635686 -377.90501)
		(stroke
			(width 0.07112)
			(type default)
		)
		(layer "In6.Cu")
	)
	(gr_line
		(start 165.480492 -378.462794)
		(end 165.427914 -378.277882)
		(stroke
			(width 0.07112)
			(type default)
		)
		(layer "In6.Cu")
	)
	(gr_line
		(start 165.481508 -364.625128)
		(end 165.09492 -364.405418)
		(stroke
			(width 0.07112)
			(type default)
		)
		(layer "In6.Cu")
	)
	(gr_line
		(start 165.519862 -378.97435)
		(end 165.631368 -378.773944)
		(stroke
			(width 0.07112)
			(type default)
		)
		(layer "In6.Cu")
	)
	(gr_line
		(start 165.635686 -377.90501)
		(end 165.820598 -377.852432)
		(stroke
			(width 0.07112)
			(type default)
		)
		(layer "In6.Cu")
	)
	(gr_line
		(start 165.65499 -364.577376)
		(end 165.481508 -364.625128)
		(stroke
			(width 0.07112)
			(type default)
		)
		(layer "In6.Cu")
	)
	(gr_line
		(start 165.72738 -378.601732)
		(end 166.068756 -377.98883)
		(stroke
			(width 0.07112)
			(type default)
		)
		(layer "In6.Cu")
	)
	(gr_line
		(start 165.772338 -385.405376)
		(end 165.772846 -385.404868)
		(stroke
			(width 0.07112)
			(type default)
		)
		(layer "In6.Cu")
	)
	(gr_line
		(start 165.79596 -364.331758)
		(end 165.18636 -363.985048)
		(stroke
			(width 0.07112)
			(type default)
		)
		(layer "In6.Cu")
	)
	(gr_line
		(start 165.819074 -386.003292)
		(end 165.913816 -385.649724)
		(stroke
			(width 0.07112)
			(type default)
		)
		(layer "In6.Cu")
	)
	(gr_line
		(start 165.822122 -377.851924)
		(end 165.822376 -377.85167)
		(stroke
			(width 0.07112)
			(type default)
		)
		(layer "In6.Cu")
	)
	(gr_line
		(start 165.822376 -377.851924)
		(end 165.822122 -377.851924)
		(stroke
			(width 0.07112)
			(type default)
		)
		(layer "In6.Cu")
	)
	(gr_line
		(start 166.035482 -385.579112)
		(end 166.088314 -385.548632)
		(stroke
			(width 0.07112)
			(type default)
		)
		(layer "In6.Cu")
	)
	(gr_line
		(start 166.07536 -364.962948)
		(end 166.027862 -364.789212)
		(stroke
			(width 0.07112)
			(type default)
		)
		(layer "In6.Cu")
	)
	(gr_line
		(start 166.088314 -385.548632)
		(end 166.176452 -385.460494)
		(stroke
			(width 0.07112)
			(type default)
		)
		(layer "In6.Cu")
	)
	(gr_line
		(start 166.176452 -385.460494)
		(end 166.176452 -385.334764)
		(stroke
			(width 0.07112)
			(type default)
		)
		(layer "In6.Cu")
	)
	(gr_line
		(start 166.461948 -365.182658)
		(end 166.07536 -364.962948)
		(stroke
			(width 0.07112)
			(type default)
		)
		(layer "In6.Cu")
	)
	(gr_line
		(start 166.63543 -365.134906)
		(end 166.461948 -365.182658)
		(stroke
			(width 0.07112)
			(type default)
		)
		(layer "In6.Cu")
	)
	(gr_line
		(start 166.7764 -364.889034)
		(end 166.1668 -364.542578)
		(stroke
			(width 0.07112)
			(type default)
		)
		(layer "In6.Cu")
	)
	(gr_line
		(start 167.0558 -365.520478)
		(end 167.008302 -365.346742)
		(stroke
			(width 0.07112)
			(type default)
		)
		(layer "In6.Cu")
	)
	(gr_arc
		(start 167.37965 -383.413762)
		(mid 167.380032 -383.413382)
		(end 167.380412 -383.413)
		(stroke
			(width 0.07112)
			(type default)
		)
		(layer "In6.Cu")
	)
	(gr_line
		(start 167.442388 -365.740188)
		(end 167.0558 -365.520478)
		(stroke
			(width 0.07112)
			(type default)
		)
		(layer "In6.Cu")
	)
	(gr_line
		(start 167.616124 -365.692182)
		(end 167.442388 -365.740188)
		(stroke
			(width 0.07112)
			(type default)
		)
		(layer "In6.Cu")
	)
	(gr_line
		(start 167.75684 -365.446564)
		(end 167.14724 -365.099854)
		(stroke
			(width 0.07112)
			(type default)
		)
		(layer "In6.Cu")
	)
	(gr_line
		(start 168.000934 -63.623952)
		(end 168.001188 -63.623952)
		(stroke
			(width 0.07112)
			(type default)
		)
		(layer "In6.Cu")
	)
	(gr_line
		(start 168.134284 -381.668528)
		(end 168.205404 -381.247396)
		(stroke
			(width 0.07112)
			(type default)
		)
		(layer "In6.Cu")
	)
	(gr_line
		(start 168.205404 -381.247396)
		(end 168.362376 -381.136144)
		(stroke
			(width 0.07112)
			(type default)
		)
		(layer "In6.Cu")
	)
	(gr_line
		(start 168.24579 -381.825246)
		(end 168.134284 -381.668528)
		(stroke
			(width 0.07112)
			(type default)
		)
		(layer "In6.Cu")
	)
	(gr_line
		(start 168.322244 -380.556516)
		(end 168.393618 -380.135384)
		(stroke
			(width 0.07112)
			(type default)
		)
		(layer "In6.Cu")
	)
	(gr_line
		(start 168.393618 -380.135384)
		(end 168.55059 -380.024132)
		(stroke
			(width 0.07112)
			(type default)
		)
		(layer "In6.Cu")
	)
	(gr_line
		(start 168.43375 -380.713234)
		(end 168.322244 -380.556516)
		(stroke
			(width 0.07112)
			(type default)
		)
		(layer "In6.Cu")
	)
	(gr_line
		(start 168.524682 -381.873506)
		(end 168.641776 -381.182118)
		(stroke
			(width 0.07112)
			(type default)
		)
		(layer "In6.Cu")
	)
	(gr_line
		(start 168.547034 -365.89589)
		(end 168.54678 -365.895636)
		(stroke
			(width 0.07112)
			(type default)
		)
		(layer "In6.Cu")
	)
	(gr_line
		(start 168.712896 -380.761494)
		(end 168.82999 -380.070106)
		(stroke
			(width 0.07112)
			(type default)
		)
		(layer "In6.Cu")
	)
	(gr_line
		(start 170.240198 -368.412268)
		(end 170.240198 -368.412014)
		(stroke
			(width 0.07112)
			(type default)
		)
		(layer "In6.Cu")
	)
	(gr_line
		(start 170.369738 -369.555776)
		(end 170.369738 -369.555522)
		(stroke
			(width 0.07112)
			(type default)
		)
		(layer "In6.Cu")
	)
	(gr_line
		(start 170.563032 -368.471704)
		(end 170.563032 -368.472212)
		(stroke
			(width 0.07112)
			(type default)
		)
		(layer "In6.Cu")
	)
	(gr_line
		(start 170.650916 -369.532916)
		(end 170.650916 -369.532154)
		(stroke
			(width 0.07112)
			(type default)
		)
		(layer "In6.Cu")
	)
	(gr_line
		(start 171.180252 -367.890806)
		(end 171.180252 -367.890552)
		(stroke
			(width 0.07112)
			(type default)
		)
		(layer "In6.Cu")
	)
	(gr_line
		(start 172.143928 -372.18747)
		(end 172.143674 -372.187978)
		(stroke
			(width 0.07112)
			(type default)
		)
		(layer "In6.Cu")
	)
	(gr_line
		(start 181.750716 -53.664104)
		(end 182.041546 -53.954934)
		(stroke
			(width 0.07112)
			(type default)
		)
		(layer "In6.Cu")
	)
	(gr_line
		(start 181.750716 -53.382164)
		(end 182.041546 -53.091334)
		(stroke
			(width 0.07112)
			(type default)
		)
		(layer "In6.Cu")
	)
	(gr_line
		(start 181.750716 -50.658268)
		(end 182.041546 -50.949098)
		(stroke
			(width 0.07112)
			(type default)
		)
		(layer "In6.Cu")
	)
	(gr_line
		(start 181.750716 -50.376328)
		(end 182.041546 -50.085498)
		(stroke
			(width 0.07112)
			(type default)
		)
		(layer "In6.Cu")
	)
	(gr_line
		(start 181.750716 -47.737268)
		(end 182.041546 -48.028098)
		(stroke
			(width 0.07112)
			(type default)
		)
		(layer "In6.Cu")
	)
	(gr_line
		(start 181.750716 -47.455328)
		(end 182.041546 -47.164498)
		(stroke
			(width 0.07112)
			(type default)
		)
		(layer "In6.Cu")
	)
	(gr_line
		(start 181.750716 -44.689268)
		(end 182.041546 -44.980098)
		(stroke
			(width 0.07112)
			(type default)
		)
		(layer "In6.Cu")
	)
	(gr_line
		(start 181.750716 -44.407328)
		(end 182.041546 -44.116498)
		(stroke
			(width 0.07112)
			(type default)
		)
		(layer "In6.Cu")
	)
	(gr_line
		(start 194.193922 -9.780016)
		(end 194.193922 -5.787898)
		(stroke
			(width 0.2)
			(type default)
		)
		(layer "In6.Cu")
	)
	(gr_arc
		(start 194.193922 -9.780016)
		(mid 194.928504 -11.55342)
		(end 196.701918 -12.288012)
		(stroke
			(width 0.2)
			(type default)
		)
		(layer "In6.Cu")
	)
	(gr_line
		(start 194.193922 -5.787898)
		(end 126.61011 -5.787898)
		(stroke
			(width 0.2)
			(type default)
		)
		(layer "In6.Cu")
	)
	(gr_line
		(start 194.496944 -441.481972)
		(end 194.496944 -441.17006)
		(stroke
			(width 0.2)
			(type default)
		)
		(layer "In6.Cu")
	)
	(gr_arc
		(start 195.50507 -440.161934)
		(mid 194.792223 -440.457215)
		(end 194.496944 -441.17006)
		(stroke
			(width 0.2)
			(type default)
		)
		(layer "In6.Cu")
	)
	(gr_line
		(start 195.50507 -440.161934)
		(end 276.314916 -440.161934)
		(stroke
			(width 0.2)
			(type default)
		)
		(layer "In6.Cu")
	)
	(gr_arc
		(start 197.209918 -7.78002)
		(mid 197.646914 -8.83502)
		(end 198.701914 -9.272016)
		(stroke
			(width 0.2)
			(type default)
		)
		(layer "In6.Cu")
	)
	(gr_arc
		(start 197.209918 -4.879848)
		(mid 196.475361 -3.106388)
		(end 194.701922 -2.371852)
		(stroke
			(width 0.2)
			(type default)
		)
		(layer "In6.Cu")
	)
	(gr_line
		(start 197.209918 -4.879848)
		(end 197.209918 -7.78002)
		(stroke
			(width 0.2)
			(type default)
		)
		(layer "In6.Cu")
	)
	(gr_line
		(start 198.701914 -9.272016)
		(end 223.300036 -9.272016)
		(stroke
			(width 0.2)
			(type default)
		)
		(layer "In6.Cu")
	)
	(gr_line
		(start 214.24011 4.941824)
		(end 213.94928 4.650994)
		(stroke
			(width 0.07112)
			(type default)
		)
		(layer "In6.Cu")
	)
	(gr_line
		(start 214.24011 5.223764)
		(end 213.94928 5.514594)
		(stroke
			(width 0.07112)
			(type default)
		)
		(layer "In6.Cu")
	)
	(gr_line
		(start 221.30004 -12.288012)
		(end 196.701918 -12.288012)
		(stroke
			(width 0.2)
			(type default)
		)
		(layer "In6.Cu")
	)
	(gr_line
		(start 222.792036 -34.120074)
		(end 222.792036 -13.780008)
		(stroke
			(width 0.2)
			(type default)
		)
		(layer "In6.Cu")
	)
	(gr_arc
		(start 222.792036 -34.120074)
		(mid 223.526604 -35.8935)
		(end 225.300032 -36.62807)
		(stroke
			(width 0.2)
			(type default)
		)
		(layer "In6.Cu")
	)
	(gr_arc
		(start 222.792036 -13.780008)
		(mid 222.35504 -12.725008)
		(end 221.30004 -12.288012)
		(stroke
			(width 0.2)
			(type default)
		)
		(layer "In6.Cu")
	)
	(gr_arc
		(start 225.808032 -33.120076)
		(mid 225.952135 -33.467971)
		(end 226.30003 -33.612074)
		(stroke
			(width 0.2)
			(type default)
		)
		(layer "In6.Cu")
	)
	(gr_arc
		(start 225.808032 -11.780012)
		(mid 225.073463 -10.006571)
		(end 223.300036 -9.272016)
		(stroke
			(width 0.2)
			(type default)
		)
		(layer "In6.Cu")
	)
	(gr_line
		(start 225.808032 -11.780012)
		(end 225.808032 -33.120076)
		(stroke
			(width 0.2)
			(type default)
		)
		(layer "In6.Cu")
	)
	(gr_line
		(start 226.30003 -33.612074)
		(end 255.800098 -33.612074)
		(stroke
			(width 0.2)
			(type default)
		)
		(layer "In6.Cu")
	)
	(gr_arc
		(start 255.800098 -33.612074)
		(mid 256.147993 -33.467971)
		(end 256.292096 -33.120076)
		(stroke
			(width 0.2)
			(type default)
		)
		(layer "In6.Cu")
	)
	(gr_line
		(start 256.292096 -33.120076)
		(end 256.292096 -11.780012)
		(stroke
			(width 0.2)
			(type default)
		)
		(layer "In6.Cu")
	)
	(gr_line
		(start 256.800096 -36.62807)
		(end 225.300032 -36.62807)
		(stroke
			(width 0.2)
			(type default)
		)
		(layer "In6.Cu")
	)
	(gr_arc
		(start 256.800096 -36.62807)
		(mid 258.57351 -35.893495)
		(end 259.308092 -34.120074)
		(stroke
			(width 0.2)
			(type default)
		)
		(layer "In6.Cu")
	)
	(gr_arc
		(start 258.800092 -9.272016)
		(mid 257.02668 -10.006595)
		(end 256.292096 -11.780012)
		(stroke
			(width 0.2)
			(type default)
		)
		(layer "In6.Cu")
	)
	(gr_line
		(start 258.800092 -9.272016)
		(end 383.601976 -9.272016)
		(stroke
			(width 0.2)
			(type default)
		)
		(layer "In6.Cu")
	)
	(gr_line
		(start 259.308092 -13.780008)
		(end 259.308092 -34.120074)
		(stroke
			(width 0.2)
			(type default)
		)
		(layer "In6.Cu")
	)
	(gr_arc
		(start 260.800088 -12.288012)
		(mid 259.745088 -12.725008)
		(end 259.308092 -13.780008)
		(stroke
			(width 0.2)
			(type default)
		)
		(layer "In6.Cu")
	)
	(gr_line
		(start 277.323042 -441.481972)
		(end 463.300064 -441.481972)
		(stroke
			(width 0.2)
			(type default)
		)
		(layer "In6.Cu")
	)
	(gr_arc
		(start 277.323042 -441.17006)
		(mid 277.027756 -440.457227)
		(end 276.314916 -440.161934)
		(stroke
			(width 0.2)
			(type default)
		)
		(layer "In6.Cu")
	)
	(gr_line
		(start 277.323042 -441.17006)
		(end 277.323042 -441.481972)
		(stroke
			(width 0.2)
			(type default)
		)
		(layer "In6.Cu")
	)
	(gr_line
		(start 295.952926 -386.280914)
		(end 295.952926 -386.981954)
		(stroke
			(width 0.07112)
			(type default)
		)
		(layer "In6.Cu")
	)
	(gr_line
		(start 295.952926 -383.201926)
		(end 295.952926 -383.902966)
		(stroke
			(width 0.07112)
			(type default)
		)
		(layer "In6.Cu")
	)
	(gr_line
		(start 295.952926 -382.074166)
		(end 295.952926 -382.775206)
		(stroke
			(width 0.07112)
			(type default)
		)
		(layer "In6.Cu")
	)
	(gr_line
		(start 295.952926 -380.514098)
		(end 295.952926 -381.215138)
		(stroke
			(width 0.07112)
			(type default)
		)
		(layer "In6.Cu")
	)
	(gr_line
		(start 296.236136 -386.282184)
		(end 296.372026 -386.418074)
		(stroke
			(width 0.07112)
			(type default)
		)
		(layer "In6.Cu")
	)
	(gr_line
		(start 296.236136 -383.203196)
		(end 296.372026 -383.339086)
		(stroke
			(width 0.07112)
			(type default)
		)
		(layer "In6.Cu")
	)
	(gr_line
		(start 296.236136 -382.075436)
		(end 296.372026 -382.211326)
		(stroke
			(width 0.07112)
			(type default)
		)
		(layer "In6.Cu")
	)
	(gr_line
		(start 296.236136 -380.515368)
		(end 296.372026 -380.651258)
		(stroke
			(width 0.07112)
			(type default)
		)
		(layer "In6.Cu")
	)
	(gr_line
		(start 296.372026 -386.844794)
		(end 296.236136 -386.980684)
		(stroke
			(width 0.07112)
			(type default)
		)
		(layer "In6.Cu")
	)
	(gr_line
		(start 296.372026 -386.418074)
		(end 296.372026 -386.844794)
		(stroke
			(width 0.07112)
			(type default)
		)
		(layer "In6.Cu")
	)
	(gr_line
		(start 296.372026 -383.765806)
		(end 296.236136 -383.901696)
		(stroke
			(width 0.07112)
			(type default)
		)
		(layer "In6.Cu")
	)
	(gr_line
		(start 296.372026 -383.339086)
		(end 296.372026 -383.765806)
		(stroke
			(width 0.07112)
			(type default)
		)
		(layer "In6.Cu")
	)
	(gr_line
		(start 296.372026 -382.638046)
		(end 296.236136 -382.773936)
		(stroke
			(width 0.07112)
			(type default)
		)
		(layer "In6.Cu")
	)
	(gr_line
		(start 296.372026 -382.211326)
		(end 296.372026 -382.638046)
		(stroke
			(width 0.07112)
			(type default)
		)
		(layer "In6.Cu")
	)
	(gr_line
		(start 296.372026 -381.077978)
		(end 296.236136 -381.213868)
		(stroke
			(width 0.07112)
			(type default)
		)
		(layer "In6.Cu")
	)
	(gr_line
		(start 296.372026 -380.651258)
		(end 296.372026 -381.077978)
		(stroke
			(width 0.07112)
			(type default)
		)
		(layer "In6.Cu")
	)
	(gr_line
		(start 297.139614 -390.46023)
		(end 297.430444 -390.75106)
		(stroke
			(width 0.07112)
			(type default)
		)
		(layer "In6.Cu")
	)
	(gr_line
		(start 297.139614 -390.17829)
		(end 297.430444 -389.88746)
		(stroke
			(width 0.07112)
			(type default)
		)
		(layer "In6.Cu")
	)
	(gr_line
		(start 297.367706 -380.288038)
		(end 297.503596 -380.423928)
		(stroke
			(width 0.07112)
			(type default)
		)
		(layer "In6.Cu")
	)
	(gr_line
		(start 297.367706 -379.861318)
		(end 297.367706 -380.288038)
		(stroke
			(width 0.07112)
			(type default)
		)
		(layer "In6.Cu")
	)
	(gr_line
		(start 297.367706 -379.160278)
		(end 297.503596 -379.296168)
		(stroke
			(width 0.07112)
			(type default)
		)
		(layer "In6.Cu")
	)
	(gr_line
		(start 297.367706 -378.733558)
		(end 297.367706 -379.160278)
		(stroke
			(width 0.07112)
			(type default)
		)
		(layer "In6.Cu")
	)
	(gr_line
		(start 297.367706 -378.032518)
		(end 297.503596 -378.168408)
		(stroke
			(width 0.07112)
			(type default)
		)
		(layer "In6.Cu")
	)
	(gr_line
		(start 297.367706 -377.605798)
		(end 297.367706 -378.032518)
		(stroke
			(width 0.07112)
			(type default)
		)
		(layer "In6.Cu")
	)
	(gr_line
		(start 297.503596 -379.725428)
		(end 297.367706 -379.861318)
		(stroke
			(width 0.07112)
			(type default)
		)
		(layer "In6.Cu")
	)
	(gr_line
		(start 297.503596 -378.597668)
		(end 297.367706 -378.733558)
		(stroke
			(width 0.07112)
			(type default)
		)
		(layer "In6.Cu")
	)
	(gr_line
		(start 297.503596 -377.469908)
		(end 297.367706 -377.605798)
		(stroke
			(width 0.07112)
			(type default)
		)
		(layer "In6.Cu")
	)
	(gr_line
		(start 297.717972 -384.637788)
		(end 297.430444 -384.35026)
		(stroke
			(width 0.07112)
			(type default)
		)
		(layer "In6.Cu")
	)
	(gr_line
		(start 297.723306 -384.920998)
		(end 297.430444 -385.21386)
		(stroke
			(width 0.07112)
			(type default)
		)
		(layer "In6.Cu")
	)
	(gr_line
		(start 297.724576 -384.637788)
		(end 297.717972 -384.637788)
		(stroke
			(width 0.07112)
			(type default)
		)
		(layer "In6.Cu")
	)
	(gr_line
		(start 297.786806 -379.724158)
		(end 297.786806 -380.425198)
		(stroke
			(width 0.07112)
			(type default)
		)
		(layer "In6.Cu")
	)
	(gr_line
		(start 297.786806 -378.596398)
		(end 297.786806 -379.297438)
		(stroke
			(width 0.07112)
			(type default)
		)
		(layer "In6.Cu")
	)
	(gr_line
		(start 297.786806 -377.468638)
		(end 297.786806 -378.169678)
		(stroke
			(width 0.07112)
			(type default)
		)
		(layer "In6.Cu")
	)
	(gr_line
		(start 298.432474 -383.65557)
		(end 298.568364 -383.79146)
		(stroke
			(width 0.07112)
			(type default)
		)
		(layer "In6.Cu")
	)
	(gr_line
		(start 298.432474 -383.22885)
		(end 298.432474 -383.65557)
		(stroke
			(width 0.07112)
			(type default)
		)
		(layer "In6.Cu")
	)
	(gr_line
		(start 298.568364 -383.09296)
		(end 298.432474 -383.22885)
		(stroke
			(width 0.07112)
			(type default)
		)
		(layer "In6.Cu")
	)
	(gr_line
		(start 298.851574 -383.09169)
		(end 298.851574 -383.79273)
		(stroke
			(width 0.07112)
			(type default)
		)
		(layer "In6.Cu")
	)
	(gr_line
		(start 299.060616 4.650994)
		(end 298.769786 4.941824)
		(stroke
			(width 0.07112)
			(type default)
		)
		(layer "In6.Cu")
	)
	(gr_line
		(start 299.060616 5.514594)
		(end 298.769786 5.223764)
		(stroke
			(width 0.07112)
			(type default)
		)
		(layer "In6.Cu")
	)
	(gr_line
		(start 299.305726 -379.5903)
		(end 299.014896 -379.88113)
		(stroke
			(width 0.07112)
			(type default)
		)
		(layer "In6.Cu")
	)
	(gr_line
		(start 299.587666 -379.5903)
		(end 299.878496 -379.88113)
		(stroke
			(width 0.07112)
			(type default)
		)
		(layer "In6.Cu")
	)
	(gr_line
		(start 301.007526 -377.1265)
		(end 300.716696 -377.41733)
		(stroke
			(width 0.07112)
			(type default)
		)
		(layer "In6.Cu")
	)
	(gr_line
		(start 301.289466 -377.1265)
		(end 301.580296 -377.41733)
		(stroke
			(width 0.07112)
			(type default)
		)
		(layer "In6.Cu")
	)
	(gr_line
		(start 304.363882 -382.101344)
		(end 304.120296 -382.34493)
		(stroke
			(width 0.07112)
			(type default)
		)
		(layer "In6.Cu")
	)
	(gr_arc
		(start 304.363882 -382.101344)
		(mid 304.395315 -382.05693)
		(end 304.41011 -382.00457)
		(stroke
			(width 0.07112)
			(type default)
		)
		(layer "In6.Cu")
	)
	(gr_arc
		(start 304.694082 -382.00457)
		(mid 304.708936 -382.056904)
		(end 304.74031 -382.101344)
		(stroke
			(width 0.07112)
			(type default)
		)
		(layer "In6.Cu")
	)
	(gr_line
		(start 304.74031 -382.101344)
		(end 304.983896 -382.34493)
		(stroke
			(width 0.07112)
			(type default)
		)
		(layer "In6.Cu")
	)
	(gr_line
		(start 305.084734 -374.647968)
		(end 305.084734 -374.647714)
		(stroke
			(width 0.07112)
			(type default)
		)
		(layer "In6.Cu")
	)
	(gr_line
		(start 305.325526 -418.412168)
		(end 305.616356 -418.702998)
		(stroke
			(width 0.07112)
			(type default)
		)
		(layer "In6.Cu")
	)
	(gr_line
		(start 305.616356 -415.09569)
		(end 305.325526 -415.38652)
		(stroke
			(width 0.07112)
			(type default)
		)
		(layer "In6.Cu")
	)
	(gr_line
		(start 305.898296 -415.09569)
		(end 306.189126 -415.38652)
		(stroke
			(width 0.07112)
			(type default)
		)
		(layer "In6.Cu")
	)
	(gr_line
		(start 306.112926 -379.5903)
		(end 305.822096 -379.88113)
		(stroke
			(width 0.07112)
			(type default)
		)
		(layer "In6.Cu")
	)
	(gr_line
		(start 306.189126 -418.412168)
		(end 305.898296 -418.702998)
		(stroke
			(width 0.07112)
			(type default)
		)
		(layer "In6.Cu")
	)
	(gr_line
		(start 306.394866 -379.5903)
		(end 306.685696 -379.88113)
		(stroke
			(width 0.07112)
			(type default)
		)
		(layer "In6.Cu")
	)
	(gr_line
		(start 307.551836 -423.116502)
		(end 308.153562 -423.477182)
		(stroke
			(width 0.07112)
			(type default)
		)
		(layer "In6.Cu")
	)
	(gr_line
		(start 307.698648 -422.874186)
		(end 307.885084 -422.82745)
		(stroke
			(width 0.07112)
			(type default)
		)
		(layer "In6.Cu")
	)
	(gr_line
		(start 307.814726 -377.1265)
		(end 307.523896 -377.41733)
		(stroke
			(width 0.07112)
			(type default)
		)
		(layer "In6.Cu")
	)
	(gr_line
		(start 307.885084 -422.82745)
		(end 308.251352 -423.046906)
		(stroke
			(width 0.07112)
			(type default)
		)
		(layer "In6.Cu")
	)
	(gr_line
		(start 308.096666 -377.1265)
		(end 308.387496 -377.41733)
		(stroke
			(width 0.07112)
			(type default)
		)
		(layer "In6.Cu")
	)
	(gr_line
		(start 308.251352 -423.046906)
		(end 308.298088 -423.233596)
		(stroke
			(width 0.07112)
			(type default)
		)
		(layer "In6.Cu")
	)
	(gr_line
		(start 308.388766 -418.412168)
		(end 308.679596 -418.702998)
		(stroke
			(width 0.07112)
			(type default)
		)
		(layer "In6.Cu")
	)
	(gr_line
		(start 308.519322 -423.696384)
		(end 309.121048 -424.057064)
		(stroke
			(width 0.07112)
			(type default)
		)
		(layer "In6.Cu")
	)
	(gr_line
		(start 308.66588 -423.454068)
		(end 308.85257 -423.407332)
		(stroke
			(width 0.07112)
			(type default)
		)
		(layer "In6.Cu")
	)
	(gr_line
		(start 308.679596 -420.04361)
		(end 308.679596 -420.72433)
		(stroke
			(width 0.07112)
			(type default)
		)
		(layer "In6.Cu")
	)
	(gr_line
		(start 308.679596 -415.09569)
		(end 308.388766 -415.38652)
		(stroke
			(width 0.07112)
			(type default)
		)
		(layer "In6.Cu")
	)
	(gr_line
		(start 308.85257 -423.407332)
		(end 309.218838 -423.626788)
		(stroke
			(width 0.07112)
			(type default)
		)
		(layer "In6.Cu")
	)
	(gr_line
		(start 308.961536 -415.09569)
		(end 309.252366 -415.38652)
		(stroke
			(width 0.07112)
			(type default)
		)
		(layer "In6.Cu")
	)
	(gr_line
		(start 308.962806 -420.04488)
		(end 309.088536 -420.17061)
		(stroke
			(width 0.07112)
			(type default)
		)
		(layer "In6.Cu")
	)
	(gr_line
		(start 309.088536 -420.59733)
		(end 308.962806 -420.72306)
		(stroke
			(width 0.07112)
			(type default)
		)
		(layer "In6.Cu")
	)
	(gr_line
		(start 309.088536 -420.17061)
		(end 309.088536 -420.59733)
		(stroke
			(width 0.07112)
			(type default)
		)
		(layer "In6.Cu")
	)
	(gr_line
		(start 309.218838 -423.626788)
		(end 309.265574 -423.813732)
		(stroke
			(width 0.07112)
			(type default)
		)
		(layer "In6.Cu")
	)
	(gr_line
		(start 309.252366 -418.412168)
		(end 308.961536 -418.702998)
		(stroke
			(width 0.07112)
			(type default)
		)
		(layer "In6.Cu")
	)
	(gr_line
		(start 309.486808 -424.27652)
		(end 310.088534 -424.6372)
		(stroke
			(width 0.07112)
			(type default)
		)
		(layer "In6.Cu")
	)
	(gr_line
		(start 309.633366 -424.03395)
		(end 309.820056 -423.987214)
		(stroke
			(width 0.07112)
			(type default)
		)
		(layer "In6.Cu")
	)
	(gr_line
		(start 309.820056 -423.987214)
		(end 310.186324 -424.20667)
		(stroke
			(width 0.07112)
			(type default)
		)
		(layer "In6.Cu")
	)
	(gr_line
		(start 310.012842 -422.53408)
		(end 310.654192 -422.763442)
		(stroke
			(width 0.07112)
			(type default)
		)
		(layer "In6.Cu")
	)
	(gr_line
		(start 310.013096 -422.533826)
		(end 310.012842 -422.53408)
		(stroke
			(width 0.07112)
			(type default)
		)
		(layer "In6.Cu")
	)
	(gr_line
		(start 310.040274 -409.304236)
		(end 310.040528 -409.304744)
		(stroke
			(width 0.07112)
			(type default)
		)
		(layer "In6.Cu")
	)
	(gr_line
		(start 310.108854 -422.267634)
		(end 310.270144 -422.191434)
		(stroke
			(width 0.07112)
			(type default)
		)
		(layer "In6.Cu")
	)
	(gr_line
		(start 310.186324 -424.20667)
		(end 310.23306 -424.393614)
		(stroke
			(width 0.07112)
			(type default)
		)
		(layer "In6.Cu")
	)
	(gr_line
		(start 310.270144 -422.191434)
		(end 310.672226 -422.335198)
		(stroke
			(width 0.07112)
			(type default)
		)
		(layer "In6.Cu")
	)
	(gr_line
		(start 310.287924 -409.669742)
		(end 310.119014 -409.57627)
		(stroke
			(width 0.07112)
			(type default)
		)
		(layer "In6.Cu")
	)
	(gr_line
		(start 310.454294 -424.856402)
		(end 311.05602 -425.217082)
		(stroke
			(width 0.07112)
			(type default)
		)
		(layer "In6.Cu")
	)
	(gr_line
		(start 310.600852 -424.614086)
		(end 310.787542 -424.567096)
		(stroke
			(width 0.07112)
			(type default)
		)
		(layer "In6.Cu")
	)
	(gr_line
		(start 310.672226 -422.335198)
		(end 310.748426 -422.496488)
		(stroke
			(width 0.07112)
			(type default)
		)
		(layer "In6.Cu")
	)
	(gr_line
		(start 310.698388 -409.55214)
		(end 310.287924 -409.669742)
		(stroke
			(width 0.07112)
			(type default)
		)
		(layer "In6.Cu")
	)
	(gr_line
		(start 310.71439 -409.110688)
		(end 310.040274 -409.304236)
		(stroke
			(width 0.07112)
			(type default)
		)
		(layer "In6.Cu")
	)
	(gr_line
		(start 310.787542 -424.567096)
		(end 311.15381 -424.786552)
		(stroke
			(width 0.07112)
			(type default)
		)
		(layer "In6.Cu")
	)
	(gr_line
		(start 310.79186 -409.38323)
		(end 310.698388 -409.55214)
		(stroke
			(width 0.07112)
			(type default)
		)
		(layer "In6.Cu")
	)
	(gr_line
		(start 311.055766 -422.906952)
		(end 311.697116 -423.136314)
		(stroke
			(width 0.07112)
			(type default)
		)
		(layer "In6.Cu")
	)
	(gr_line
		(start 311.152032 -422.64076)
		(end 311.313322 -422.56456)
		(stroke
			(width 0.07112)
			(type default)
		)
		(layer "In6.Cu")
	)
	(gr_line
		(start 311.15381 -424.786552)
		(end 311.2008 -424.973496)
		(stroke
			(width 0.07112)
			(type default)
		)
		(layer "In6.Cu")
	)
	(gr_line
		(start 311.171082 -382.101344)
		(end 310.927496 -382.34493)
		(stroke
			(width 0.07112)
			(type default)
		)
		(layer "In6.Cu")
	)
	(gr_arc
		(start 311.171082 -382.101344)
		(mid 311.202515 -382.05693)
		(end 311.21731 -382.00457)
		(stroke
			(width 0.07112)
			(type default)
		)
		(layer "In6.Cu")
	)
	(gr_line
		(start 311.313322 -422.56456)
		(end 311.71515 -422.70807)
		(stroke
			(width 0.07112)
			(type default)
		)
		(layer "In6.Cu")
	)
	(gr_line
		(start 311.371996 -409.358592)
		(end 311.203086 -409.26512)
		(stroke
			(width 0.07112)
			(type default)
		)
		(layer "In6.Cu")
	)
	(gr_line
		(start 311.42178 -425.436284)
		(end 312.023506 -425.796964)
		(stroke
			(width 0.07112)
			(type default)
		)
		(layer "In6.Cu")
	)
	(gr_line
		(start 311.452006 -418.412168)
		(end 311.742836 -418.702998)
		(stroke
			(width 0.07112)
			(type default)
		)
		(layer "In6.Cu")
	)
	(gr_arc
		(start 311.501282 -382.00457)
		(mid 311.516136 -382.056904)
		(end 311.54751 -382.101344)
		(stroke
			(width 0.07112)
			(type default)
		)
		(layer "In6.Cu")
	)
	(gr_line
		(start 311.54751 -382.101344)
		(end 311.791096 -382.34493)
		(stroke
			(width 0.07112)
			(type default)
		)
		(layer "In6.Cu")
	)
	(gr_line
		(start 311.568338 -425.193968)
		(end 311.755028 -425.146978)
		(stroke
			(width 0.07112)
			(type default)
		)
		(layer "In6.Cu")
	)
	(gr_line
		(start 311.579006 -410.474922)
		(end 311.409334 -410.38399)
		(stroke
			(width 0.07112)
			(type default)
		)
		(layer "In6.Cu")
	)
	(gr_line
		(start 311.71515 -422.70807)
		(end 311.79135 -422.86936)
		(stroke
			(width 0.07112)
			(type default)
		)
		(layer "In6.Cu")
	)
	(gr_line
		(start 311.742836 -419.477698)
		(end 311.742836 -420.178738)
		(stroke
			(width 0.07112)
			(type default)
		)
		(layer "In6.Cu")
	)
	(gr_line
		(start 311.742836 -415.09569)
		(end 311.452006 -415.38652)
		(stroke
			(width 0.07112)
			(type default)
		)
		(layer "In6.Cu")
	)
	(gr_line
		(start 311.755028 -425.146978)
		(end 312.121296 -425.366434)
		(stroke
			(width 0.07112)
			(type default)
		)
		(layer "In6.Cu")
	)
	(gr_line
		(start 311.78246 -409.240736)
		(end 311.371996 -409.358592)
		(stroke
			(width 0.07112)
			(type default)
		)
		(layer "In6.Cu")
	)
	(gr_line
		(start 311.798716 -408.799538)
		(end 311.124346 -408.993086)
		(stroke
			(width 0.07112)
			(type default)
		)
		(layer "In6.Cu")
	)
	(gr_line
		(start 311.875932 -409.071826)
		(end 311.78246 -409.240736)
		(stroke
			(width 0.07112)
			(type default)
		)
		(layer "In6.Cu")
	)
	(gr_line
		(start 311.987692 -410.351478)
		(end 311.579006 -410.474922)
		(stroke
			(width 0.07112)
			(type default)
		)
		(layer "In6.Cu")
	)
	(gr_line
		(start 311.997598 -409.91028)
		(end 311.326276 -410.113226)
		(stroke
			(width 0.07112)
			(type default)
		)
		(layer "In6.Cu")
	)
	(gr_line
		(start 312.024776 -415.09569)
		(end 312.315606 -415.38652)
		(stroke
			(width 0.07112)
			(type default)
		)
		(layer "In6.Cu")
	)
	(gr_line
		(start 312.026046 -419.478968)
		(end 312.161936 -419.614858)
		(stroke
			(width 0.07112)
			(type default)
		)
		(layer "In6.Cu")
	)
	(gr_line
		(start 312.07837 -410.181806)
		(end 311.987692 -410.351478)
		(stroke
			(width 0.07112)
			(type default)
		)
		(layer "In6.Cu")
	)
	(gr_line
		(start 312.121296 -425.366434)
		(end 312.168286 -425.553632)
		(stroke
			(width 0.07112)
			(type default)
		)
		(layer "In6.Cu")
	)
	(gr_line
		(start 312.161936 -420.041578)
		(end 312.026046 -420.177468)
		(stroke
			(width 0.07112)
			(type default)
		)
		(layer "In6.Cu")
	)
	(gr_line
		(start 312.161936 -419.614858)
		(end 312.161936 -420.041578)
		(stroke
			(width 0.07112)
			(type default)
		)
		(layer "In6.Cu")
	)
	(gr_line
		(start 312.315606 -418.412168)
		(end 312.024776 -418.702998)
		(stroke
			(width 0.07112)
			(type default)
		)
		(layer "In6.Cu")
	)
	(gr_line
		(start 312.456068 -409.047188)
		(end 312.287412 -408.953716)
		(stroke
			(width 0.07112)
			(type default)
		)
		(layer "In6.Cu")
	)
	(gr_line
		(start 312.65876 -410.148532)
		(end 312.489088 -410.0576)
		(stroke
			(width 0.07112)
			(type default)
		)
		(layer "In6.Cu")
	)
	(gr_line
		(start 312.736992 -422.364408)
		(end 312.858658 -422.4147)
		(stroke
			(width 0.07112)
			(type default)
		)
		(layer "In6.Cu")
	)
	(gr_line
		(start 312.846466 -422.103042)
		(end 313.024012 -422.029636)
		(stroke
			(width 0.07112)
			(type default)
		)
		(layer "In6.Cu")
	)
	(gr_line
		(start 312.858658 -422.4147)
		(end 313.3852 -422.632632)
		(stroke
			(width 0.07112)
			(type default)
		)
		(layer "In6.Cu")
	)
	(gr_line
		(start 312.866532 -408.929332)
		(end 312.456068 -409.047188)
		(stroke
			(width 0.07112)
			(type default)
		)
		(layer "In6.Cu")
	)
	(gr_line
		(start 312.882788 -408.488134)
		(end 312.208418 -408.681682)
		(stroke
			(width 0.07112)
			(type default)
		)
		(layer "In6.Cu")
	)
	(gr_line
		(start 312.920126 -379.5903)
		(end 312.629296 -379.88113)
		(stroke
			(width 0.07112)
			(type default)
		)
		(layer "In6.Cu")
	)
	(gr_line
		(start 312.95975 -408.760676)
		(end 312.866532 -408.929332)
		(stroke
			(width 0.07112)
			(type default)
		)
		(layer "In6.Cu")
	)
	(gr_line
		(start 313.024012 -422.029636)
		(end 313.418728 -422.192704)
		(stroke
			(width 0.07112)
			(type default)
		)
		(layer "In6.Cu")
	)
	(gr_line
		(start 313.067446 -410.025088)
		(end 312.65876 -410.148532)
		(stroke
			(width 0.07112)
			(type default)
		)
		(layer "In6.Cu")
	)
	(gr_line
		(start 313.077352 -409.58389)
		(end 312.40603 -409.786836)
		(stroke
			(width 0.07112)
			(type default)
		)
		(layer "In6.Cu")
	)
	(gr_line
		(start 313.158124 -409.855416)
		(end 313.067446 -410.025088)
		(stroke
			(width 0.07112)
			(type default)
		)
		(layer "In6.Cu")
	)
	(gr_line
		(start 313.202066 -379.5903)
		(end 313.492896 -379.88113)
		(stroke
			(width 0.07112)
			(type default)
		)
		(layer "In6.Cu")
	)
	(gr_line
		(start 313.3852 -422.632632)
		(end 313.532774 -422.693846)
		(stroke
			(width 0.07112)
			(type default)
		)
		(layer "In6.Cu")
	)
	(gr_line
		(start 313.418728 -422.192704)
		(end 313.492134 -422.370504)
		(stroke
			(width 0.07112)
			(type default)
		)
		(layer "In6.Cu")
	)
	(gr_line
		(start 313.492896 -422.372282)
		(end 313.64047 -422.433242)
		(stroke
			(width 0.07112)
			(type default)
		)
		(layer "In6.Cu")
	)
	(gr_line
		(start 313.51982 -410.604208)
		(end 313.520074 -410.604462)
		(stroke
			(width 0.07112)
			(type default)
		)
		(layer "In6.Cu")
	)
	(gr_line
		(start 313.73826 -409.822142)
		(end 313.568842 -409.73121)
		(stroke
			(width 0.07112)
			(type default)
		)
		(layer "In6.Cu")
	)
	(gr_line
		(start 313.779408 -422.795954)
		(end 314.427362 -423.064432)
		(stroke
			(width 0.07112)
			(type default)
		)
		(layer "In6.Cu")
	)
	(gr_line
		(start 313.784996 -410.957014)
		(end 313.612022 -410.871924)
		(stroke
			(width 0.07112)
			(type default)
		)
		(layer "In6.Cu")
	)
	(gr_line
		(start 313.888628 -422.534842)
		(end 314.066174 -422.461182)
		(stroke
			(width 0.07112)
			(type default)
		)
		(layer "In6.Cu")
	)
	(gr_line
		(start 314.066174 -422.461182)
		(end 314.460636 -422.624504)
		(stroke
			(width 0.07112)
			(type default)
		)
		(layer "In6.Cu")
	)
	(gr_line
		(start 314.146946 -409.698698)
		(end 313.73826 -409.822142)
		(stroke
			(width 0.07112)
			(type default)
		)
		(layer "In6.Cu")
	)
	(gr_line
		(start 314.157106 -409.2575)
		(end 313.485784 -409.460446)
		(stroke
			(width 0.07112)
			(type default)
		)
		(layer "In6.Cu")
	)
	(gr_line
		(start 314.183522 -410.37764)
		(end 313.51982 -410.604208)
		(stroke
			(width 0.07112)
			(type default)
		)
		(layer "In6.Cu")
	)
	(gr_line
		(start 314.18911 -410.819092)
		(end 313.784996 -410.957014)
		(stroke
			(width 0.07112)
			(type default)
		)
		(layer "In6.Cu")
	)
	(gr_line
		(start 314.237878 -409.529026)
		(end 314.146946 -409.698698)
		(stroke
			(width 0.07112)
			(type default)
		)
		(layer "In6.Cu")
	)
	(gr_line
		(start 314.273946 -410.645864)
		(end 314.18911 -410.819092)
		(stroke
			(width 0.07112)
			(type default)
		)
		(layer "In6.Cu")
	)
	(gr_line
		(start 314.427362 -423.064432)
		(end 314.433712 -423.066972)
		(stroke
			(width 0.07112)
			(type default)
		)
		(layer "In6.Cu")
	)
	(gr_line
		(start 314.460636 -422.624504)
		(end 314.534296 -422.80205)
		(stroke
			(width 0.07112)
			(type default)
		)
		(layer "In6.Cu")
	)
	(gr_line
		(start 314.507372 -426.830744)
		(end 314.649612 -426.972984)
		(stroke
			(width 0.07112)
			(type default)
		)
		(layer "In6.Cu")
	)
	(gr_line
		(start 314.507372 -426.548804)
		(end 314.649612 -426.406564)
		(stroke
			(width 0.07112)
			(type default)
		)
		(layer "In6.Cu")
	)
	(gr_line
		(start 314.515246 -418.412168)
		(end 314.806076 -418.702998)
		(stroke
			(width 0.07112)
			(type default)
		)
		(layer "In6.Cu")
	)
	(gr_line
		(start 314.535058 -422.803828)
		(end 314.541662 -422.806622)
		(stroke
			(width 0.07112)
			(type default)
		)
		(layer "In6.Cu")
	)
	(gr_line
		(start 314.621926 -377.1265)
		(end 314.331096 -377.41733)
		(stroke
			(width 0.07112)
			(type default)
		)
		(layer "In6.Cu")
	)
	(gr_line
		(start 314.649612 -426.972984)
		(end 314.649612 -427.289976)
		(stroke
			(width 0.07112)
			(type default)
		)
		(layer "In6.Cu")
	)
	(gr_line
		(start 314.649612 -426.406564)
		(end 314.649612 -426.089826)
		(stroke
			(width 0.07112)
			(type default)
		)
		(layer "In6.Cu")
	)
	(gr_line
		(start 314.806076 -419.587426)
		(end 314.806076 -420.288466)
		(stroke
			(width 0.07112)
			(type default)
		)
		(layer "In6.Cu")
	)
	(gr_line
		(start 314.806076 -415.09569)
		(end 314.515246 -415.38652)
		(stroke
			(width 0.07112)
			(type default)
		)
		(layer "In6.Cu")
	)
	(gr_line
		(start 314.821316 -423.2275)
		(end 315.469524 -423.495978)
		(stroke
			(width 0.07112)
			(type default)
		)
		(layer "In6.Cu")
	)
	(gr_line
		(start 314.852304 -410.592524)
		(end 314.679584 -410.507434)
		(stroke
			(width 0.07112)
			(type default)
		)
		(layer "In6.Cu")
	)
	(gr_line
		(start 314.903866 -377.1265)
		(end 315.194696 -377.41733)
		(stroke
			(width 0.07112)
			(type default)
		)
		(layer "In6.Cu")
	)
	(gr_line
		(start 314.93079 -422.966388)
		(end 315.108336 -422.892728)
		(stroke
			(width 0.07112)
			(type default)
		)
		(layer "In6.Cu")
	)
	(gr_line
		(start 315.088016 -415.09569)
		(end 315.378846 -415.38652)
		(stroke
			(width 0.07112)
			(type default)
		)
		(layer "In6.Cu")
	)
	(gr_line
		(start 315.089286 -419.588696)
		(end 315.225176 -419.724586)
		(stroke
			(width 0.07112)
			(type default)
		)
		(layer "In6.Cu")
	)
	(gr_line
		(start 315.108336 -422.892728)
		(end 315.502798 -423.05605)
		(stroke
			(width 0.07112)
			(type default)
		)
		(layer "In6.Cu")
	)
	(gr_line
		(start 315.225176 -420.151306)
		(end 315.089286 -420.287196)
		(stroke
			(width 0.07112)
			(type default)
		)
		(layer "In6.Cu")
	)
	(gr_line
		(start 315.225176 -419.724586)
		(end 315.225176 -420.151306)
		(stroke
			(width 0.07112)
			(type default)
		)
		(layer "In6.Cu")
	)
	(gr_line
		(start 315.25083 -410.01315)
		(end 314.587128 -410.239718)
		(stroke
			(width 0.07112)
			(type default)
		)
		(layer "In6.Cu")
	)
	(gr_line
		(start 315.256418 -410.454602)
		(end 314.852304 -410.592524)
		(stroke
			(width 0.07112)
			(type default)
		)
		(layer "In6.Cu")
	)
	(gr_line
		(start 315.341254 -410.281628)
		(end 315.256418 -410.454602)
		(stroke
			(width 0.07112)
			(type default)
		)
		(layer "In6.Cu")
	)
	(gr_line
		(start 315.378846 -418.412168)
		(end 315.088016 -418.702998)
		(stroke
			(width 0.07112)
			(type default)
		)
		(layer "In6.Cu")
	)
	(gr_line
		(start 315.502798 -423.05605)
		(end 315.576458 -423.23385)
		(stroke
			(width 0.07112)
			(type default)
		)
		(layer "In6.Cu")
	)
	(gr_line
		(start 315.863478 -423.6593)
		(end 316.51194 -423.927778)
		(stroke
			(width 0.07112)
			(type default)
		)
		(layer "In6.Cu")
	)
	(gr_line
		(start 315.919866 -410.22778)
		(end 315.746892 -410.142944)
		(stroke
			(width 0.07112)
			(type default)
		)
		(layer "In6.Cu")
	)
	(gr_line
		(start 315.972698 -423.397934)
		(end 316.150498 -423.324274)
		(stroke
			(width 0.07112)
			(type default)
		)
		(layer "In6.Cu")
	)
	(gr_line
		(start 316.150498 -423.324274)
		(end 316.54496 -423.487596)
		(stroke
			(width 0.07112)
			(type default)
		)
		(layer "In6.Cu")
	)
	(gr_line
		(start 316.300866 -411.313376)
		(end 316.130432 -411.26283)
		(stroke
			(width 0.07112)
			(type default)
		)
		(layer "In6.Cu")
	)
	(gr_line
		(start 316.318138 -409.64866)
		(end 315.654436 -409.875228)
		(stroke
			(width 0.07112)
			(type default)
		)
		(layer "In6.Cu")
	)
	(gr_line
		(start 316.32398 -410.089858)
		(end 315.919866 -410.22778)
		(stroke
			(width 0.07112)
			(type default)
		)
		(layer "In6.Cu")
	)
	(gr_line
		(start 316.408562 -409.917138)
		(end 316.32398 -410.089858)
		(stroke
			(width 0.07112)
			(type default)
		)
		(layer "In6.Cu")
	)
	(gr_line
		(start 316.512702 -427.548802)
		(end 316.522354 -427.548802)
		(stroke
			(width 0.07112)
			(type default)
		)
		(layer "In6.Cu")
	)
	(gr_line
		(start 316.513972 -427.832012)
		(end 316.649608 -427.967648)
		(stroke
			(width 0.07112)
			(type default)
		)
		(layer "In6.Cu")
	)
	(gr_line
		(start 316.522354 -427.548802)
		(end 316.649608 -427.421548)
		(stroke
			(width 0.07112)
			(type default)
		)
		(layer "In6.Cu")
	)
	(gr_line
		(start 316.54496 -423.487596)
		(end 316.618874 -423.665396)
		(stroke
			(width 0.07112)
			(type default)
		)
		(layer "In6.Cu")
	)
	(gr_line
		(start 316.611 -410.6799)
		(end 315.994542 -411.014164)
		(stroke
			(width 0.07112)
			(type default)
		)
		(layer "In6.Cu")
	)
	(gr_line
		(start 316.649608 -427.967648)
		(end 316.649608 -428.28972)
		(stroke
			(width 0.07112)
			(type default)
		)
		(layer "In6.Cu")
	)
	(gr_line
		(start 316.649608 -427.421548)
		(end 316.649608 -427.089824)
		(stroke
			(width 0.07112)
			(type default)
		)
		(layer "In6.Cu")
	)
	(gr_line
		(start 316.694312 -411.100016)
		(end 316.300866 -411.313376)
		(stroke
			(width 0.07112)
			(type default)
		)
		(layer "In6.Cu")
	)
	(gr_line
		(start 316.73419 -0.138176)
		(end 316.44336 -0.429006)
		(stroke
			(width 0.07112)
			(type default)
		)
		(layer "In6.Cu")
	)
	(gr_line
		(start 316.73419 0.143764)
		(end 316.44336 0.434594)
		(stroke
			(width 0.07112)
			(type default)
		)
		(layer "In6.Cu")
	)
	(gr_line
		(start 316.744858 -410.929328)
		(end 316.694312 -411.100016)
		(stroke
			(width 0.07112)
			(type default)
		)
		(layer "In6.Cu")
	)
	(gr_line
		(start 316.799976 -423.741342)
		(end 316.799976 -423.74185)
		(stroke
			(width 0.07112)
			(type default)
		)
		(layer "In6.Cu")
	)
	(gr_line
		(start 316.82182 -422.86936)
		(end 317.405004 -423.258996)
		(stroke
			(width 0.07112)
			(type default)
		)
		(layer "In6.Cu")
	)
	(gr_line
		(start 316.980316 -422.634664)
		(end 317.168784 -422.597072)
		(stroke
			(width 0.07112)
			(type default)
		)
		(layer "In6.Cu")
	)
	(gr_line
		(start 317.168784 -422.597072)
		(end 317.523876 -422.834308)
		(stroke
			(width 0.07112)
			(type default)
		)
		(layer "In6.Cu")
	)
	(gr_line
		(start 317.523876 -422.834308)
		(end 317.561468 -423.02303)
		(stroke
			(width 0.07112)
			(type default)
		)
		(layer "In6.Cu")
	)
	(gr_line
		(start 317.578486 -418.412168)
		(end 317.869316 -418.702998)
		(stroke
			(width 0.07112)
			(type default)
		)
		(layer "In6.Cu")
	)
	(gr_line
		(start 317.759588 -423.495978)
		(end 318.342772 -423.885614)
		(stroke
			(width 0.07112)
			(type default)
		)
		(layer "In6.Cu")
	)
	(gr_line
		(start 317.869316 -419.552882)
		(end 317.869316 -420.253922)
		(stroke
			(width 0.07112)
			(type default)
		)
		(layer "In6.Cu")
	)
	(gr_line
		(start 317.869316 -415.09569)
		(end 317.578486 -415.38652)
		(stroke
			(width 0.07112)
			(type default)
		)
		(layer "In6.Cu")
	)
	(gr_line
		(start 317.91783 -423.261282)
		(end 318.106552 -423.22369)
		(stroke
			(width 0.07112)
			(type default)
		)
		(layer "In6.Cu")
	)
	(gr_line
		(start 317.978282 -382.101344)
		(end 317.734696 -382.34493)
		(stroke
			(width 0.07112)
			(type default)
		)
		(layer "In6.Cu")
	)
	(gr_arc
		(start 317.978282 -382.101344)
		(mid 318.009715 -382.05693)
		(end 318.02451 -382.00457)
		(stroke
			(width 0.07112)
			(type default)
		)
		(layer "In6.Cu")
	)
	(gr_line
		(start 318.106552 -423.22369)
		(end 318.461644 -423.460926)
		(stroke
			(width 0.07112)
			(type default)
		)
		(layer "In6.Cu")
	)
	(gr_line
		(start 318.151256 -415.09569)
		(end 318.442086 -415.38652)
		(stroke
			(width 0.07112)
			(type default)
		)
		(layer "In6.Cu")
	)
	(gr_line
		(start 318.152526 -419.554152)
		(end 318.288416 -419.690042)
		(stroke
			(width 0.07112)
			(type default)
		)
		(layer "In6.Cu")
	)
	(gr_line
		(start 318.288416 -420.116762)
		(end 318.152526 -420.252652)
		(stroke
			(width 0.07112)
			(type default)
		)
		(layer "In6.Cu")
	)
	(gr_line
		(start 318.288416 -419.690042)
		(end 318.288416 -420.116762)
		(stroke
			(width 0.07112)
			(type default)
		)
		(layer "In6.Cu")
	)
	(gr_arc
		(start 318.308482 -382.00457)
		(mid 318.323336 -382.056904)
		(end 318.35471 -382.101344)
		(stroke
			(width 0.07112)
			(type default)
		)
		(layer "In6.Cu")
	)
	(gr_line
		(start 318.35471 -382.101344)
		(end 318.598296 -382.34493)
		(stroke
			(width 0.07112)
			(type default)
		)
		(layer "In6.Cu")
	)
	(gr_line
		(start 318.442086 -418.412168)
		(end 318.151256 -418.702998)
		(stroke
			(width 0.07112)
			(type default)
		)
		(layer "In6.Cu")
	)
	(gr_line
		(start 318.461644 -423.460926)
		(end 318.499236 -423.649648)
		(stroke
			(width 0.07112)
			(type default)
		)
		(layer "In6.Cu")
	)
	(gr_line
		(start 318.507364 -426.830744)
		(end 318.649604 -426.972984)
		(stroke
			(width 0.07112)
			(type default)
		)
		(layer "In6.Cu")
	)
	(gr_line
		(start 318.507364 -426.548804)
		(end 318.649604 -426.406564)
		(stroke
			(width 0.07112)
			(type default)
		)
		(layer "In6.Cu")
	)
	(gr_line
		(start 318.649604 -426.972984)
		(end 318.649604 -427.289976)
		(stroke
			(width 0.07112)
			(type default)
		)
		(layer "In6.Cu")
	)
	(gr_line
		(start 318.649604 -426.406564)
		(end 318.649604 -426.089826)
		(stroke
			(width 0.07112)
			(type default)
		)
		(layer "In6.Cu")
	)
	(gr_line
		(start 318.71031 -422.514014)
		(end 319.273682 -422.932098)
		(stroke
			(width 0.07112)
			(type default)
		)
		(layer "In6.Cu")
	)
	(gr_line
		(start 318.71031 -422.51376)
		(end 318.71031 -422.514014)
		(stroke
			(width 0.07112)
			(type default)
		)
		(layer "In6.Cu")
	)
	(gr_line
		(start 318.79032 -410.239972)
		(end 318.630046 -410.154374)
		(stroke
			(width 0.07112)
			(type default)
		)
		(layer "In6.Cu")
	)
	(gr_line
		(start 318.81191 -410.99232)
		(end 318.812164 -410.992574)
		(stroke
			(width 0.07112)
			(type default)
		)
		(layer "In6.Cu")
	)
	(gr_line
		(start 318.879982 -422.287192)
		(end 319.070228 -422.258998)
		(stroke
			(width 0.07112)
			(type default)
		)
		(layer "In6.Cu")
	)
	(gr_line
		(start 319.070228 -422.258998)
		(end 319.413128 -422.513506)
		(stroke
			(width 0.07112)
			(type default)
		)
		(layer "In6.Cu")
	)
	(gr_line
		(start 319.07226 -411.348682)
		(end 318.900302 -411.261306)
		(stroke
			(width 0.07112)
			(type default)
		)
		(layer "In6.Cu")
	)
	(gr_line
		(start 319.213484 -410.11221)
		(end 318.79032 -410.239972)
		(stroke
			(width 0.07112)
			(type default)
		)
		(layer "In6.Cu")
	)
	(gr_line
		(start 319.21831 -409.680156)
		(end 318.546988 -409.88361)
		(stroke
			(width 0.07112)
			(type default)
		)
		(layer "In6.Cu")
	)
	(gr_line
		(start 319.273682 -422.932098)
		(end 319.417192 -423.038524)
		(stroke
			(width 0.07112)
			(type default)
		)
		(layer "In6.Cu")
	)
	(gr_line
		(start 319.299336 -409.951428)
		(end 319.213484 -410.11221)
		(stroke
			(width 0.07112)
			(type default)
		)
		(layer "In6.Cu")
	)
	(gr_line
		(start 319.413128 -422.513506)
		(end 319.441322 -422.703752)
		(stroke
			(width 0.07112)
			(type default)
		)
		(layer "In6.Cu")
	)
	(gr_line
		(start 319.441576 -422.70553)
		(end 319.585086 -422.811956)
		(stroke
			(width 0.07112)
			(type default)
		)
		(layer "In6.Cu")
	)
	(gr_line
		(start 319.478152 -411.216856)
		(end 319.07226 -411.348682)
		(stroke
			(width 0.07112)
			(type default)
		)
		(layer "In6.Cu")
	)
	(gr_line
		(start 319.479168 -410.775404)
		(end 318.81191 -410.99232)
		(stroke
			(width 0.07112)
			(type default)
		)
		(layer "In6.Cu")
	)
	(gr_line
		(start 319.565528 -411.044898)
		(end 319.478152 -411.216856)
		(stroke
			(width 0.07112)
			(type default)
		)
		(layer "In6.Cu")
	)
	(gr_line
		(start 319.616328 -423.186098)
		(end 320.1797 -423.604182)
		(stroke
			(width 0.07112)
			(type default)
		)
		(layer "In6.Cu")
	)
	(gr_line
		(start 319.727326 -379.5903)
		(end 319.436496 -379.88113)
		(stroke
			(width 0.07112)
			(type default)
		)
		(layer "In6.Cu")
	)
	(gr_line
		(start 319.786 -422.959276)
		(end 319.975992 -422.931082)
		(stroke
			(width 0.07112)
			(type default)
		)
		(layer "In6.Cu")
	)
	(gr_line
		(start 319.87109 -409.913836)
		(end 319.709292 -409.827222)
		(stroke
			(width 0.07112)
			(type default)
		)
		(layer "In6.Cu")
	)
	(gr_line
		(start 319.975992 -422.931082)
		(end 320.319146 -423.18559)
		(stroke
			(width 0.07112)
			(type default)
		)
		(layer "In6.Cu")
	)
	(gr_line
		(start 320.009266 -379.5903)
		(end 320.300096 -379.88113)
		(stroke
			(width 0.07112)
			(type default)
		)
		(layer "In6.Cu")
	)
	(gr_line
		(start 320.144902 -410.999686)
		(end 319.973198 -410.912564)
		(stroke
			(width 0.07112)
			(type default)
		)
		(layer "In6.Cu")
	)
	(gr_line
		(start 320.1797 -423.604182)
		(end 320.24828 -423.654982)
		(stroke
			(width 0.07112)
			(type default)
		)
		(layer "In6.Cu")
	)
	(gr_line
		(start 320.235326 -376.03938)
		(end 320.235326 -376.039634)
		(stroke
			(width 0.07112)
			(type default)
		)
		(layer "In6.Cu")
	)
	(gr_line
		(start 320.292222 -409.786328)
		(end 319.87109 -409.913836)
		(stroke
			(width 0.07112)
			(type default)
		)
		(layer "In6.Cu")
	)
	(gr_line
		(start 320.298064 -409.353004)
		(end 319.626488 -409.556458)
		(stroke
			(width 0.07112)
			(type default)
		)
		(layer "In6.Cu")
	)
	(gr_line
		(start 320.319146 -423.18559)
		(end 320.34734 -423.375836)
		(stroke
			(width 0.07112)
			(type default)
		)
		(layer "In6.Cu")
	)
	(gr_line
		(start 320.347594 -423.377614)
		(end 320.416174 -423.428414)
		(stroke
			(width 0.07112)
			(type default)
		)
		(layer "In6.Cu")
	)
	(gr_line
		(start 320.378836 -409.62453)
		(end 320.292222 -409.786328)
		(stroke
			(width 0.07112)
			(type default)
		)
		(layer "In6.Cu")
	)
	(gr_line
		(start 320.50736 -427.830742)
		(end 320.6496 -427.972982)
		(stroke
			(width 0.07112)
			(type default)
		)
		(layer "In6.Cu")
	)
	(gr_line
		(start 320.50736 -427.548802)
		(end 320.6496 -427.406562)
		(stroke
			(width 0.07112)
			(type default)
		)
		(layer "In6.Cu")
	)
	(gr_line
		(start 320.522346 -423.858182)
		(end 321.085464 -424.276012)
		(stroke
			(width 0.07112)
			(type default)
		)
		(layer "In6.Cu")
	)
	(gr_line
		(start 320.550794 -410.86786)
		(end 320.144902 -410.999686)
		(stroke
			(width 0.07112)
			(type default)
		)
		(layer "In6.Cu")
	)
	(gr_line
		(start 320.55181 -410.426408)
		(end 319.884806 -410.643324)
		(stroke
			(width 0.07112)
			(type default)
		)
		(layer "In6.Cu")
	)
	(gr_line
		(start 320.63817 -410.696156)
		(end 320.550794 -410.86786)
		(stroke
			(width 0.07112)
			(type default)
		)
		(layer "In6.Cu")
	)
	(gr_line
		(start 320.641726 -418.412168)
		(end 320.932556 -418.702998)
		(stroke
			(width 0.07112)
			(type default)
		)
		(layer "In6.Cu")
	)
	(gr_line
		(start 320.6496 -427.972982)
		(end 320.6496 -428.28972)
		(stroke
			(width 0.07112)
			(type default)
		)
		(layer "In6.Cu")
	)
	(gr_line
		(start 320.6496 -427.406562)
		(end 320.6496 -427.089824)
		(stroke
			(width 0.07112)
			(type default)
		)
		(layer "In6.Cu")
	)
	(gr_line
		(start 320.691764 -423.63136)
		(end 320.88201 -423.603166)
		(stroke
			(width 0.07112)
			(type default)
		)
		(layer "In6.Cu")
	)
	(gr_line
		(start 320.88201 -423.603166)
		(end 321.225164 -423.857674)
		(stroke
			(width 0.07112)
			(type default)
		)
		(layer "In6.Cu")
	)
	(gr_line
		(start 320.932556 -419.578028)
		(end 320.932556 -420.279068)
		(stroke
			(width 0.07112)
			(type default)
		)
		(layer "In6.Cu")
	)
	(gr_line
		(start 320.932556 -415.09569)
		(end 320.641726 -415.38652)
		(stroke
			(width 0.07112)
			(type default)
		)
		(layer "In6.Cu")
	)
	(gr_line
		(start 320.946272 -409.584398)
		(end 320.789046 -409.500324)
		(stroke
			(width 0.07112)
			(type default)
		)
		(layer "In6.Cu")
	)
	(gr_line
		(start 321.085464 -424.276012)
		(end 321.085464 -424.275758)
		(stroke
			(width 0.07112)
			(type default)
		)
		(layer "In6.Cu")
	)
	(gr_line
		(start 321.214496 -415.09569)
		(end 321.505326 -415.38652)
		(stroke
			(width 0.07112)
			(type default)
		)
		(layer "In6.Cu")
	)
	(gr_line
		(start 321.215766 -419.579298)
		(end 321.351656 -419.715188)
		(stroke
			(width 0.07112)
			(type default)
		)
		(layer "In6.Cu")
	)
	(gr_line
		(start 321.217544 -410.650944)
		(end 321.046094 -410.563568)
		(stroke
			(width 0.07112)
			(type default)
		)
		(layer "In6.Cu")
	)
	(gr_line
		(start 321.225164 -423.857674)
		(end 321.253358 -424.04792)
		(stroke
			(width 0.07112)
			(type default)
		)
		(layer "In6.Cu")
	)
	(gr_line
		(start 321.351656 -420.141908)
		(end 321.215766 -420.277798)
		(stroke
			(width 0.07112)
			(type default)
		)
		(layer "In6.Cu")
	)
	(gr_line
		(start 321.351656 -419.715188)
		(end 321.351656 -420.141908)
		(stroke
			(width 0.07112)
			(type default)
		)
		(layer "In6.Cu")
	)
	(gr_line
		(start 321.374008 -409.454858)
		(end 320.946272 -409.584398)
		(stroke
			(width 0.07112)
			(type default)
		)
		(layer "In6.Cu")
	)
	(gr_line
		(start 321.37731 -409.026106)
		(end 320.705988 -409.22956)
		(stroke
			(width 0.07112)
			(type default)
		)
		(layer "In6.Cu")
	)
	(gr_line
		(start 321.429126 -377.1265)
		(end 321.138296 -377.41733)
		(stroke
			(width 0.07112)
			(type default)
		)
		(layer "In6.Cu")
	)
	(gr_line
		(start 321.458336 -409.297378)
		(end 321.374008 -409.454858)
		(stroke
			(width 0.07112)
			(type default)
		)
		(layer "In6.Cu")
	)
	(gr_line
		(start 321.505326 -418.412168)
		(end 321.214496 -418.702998)
		(stroke
			(width 0.07112)
			(type default)
		)
		(layer "In6.Cu")
	)
	(gr_line
		(start 321.512438 -410.113988)
		(end 320.957448 -410.294582)
		(stroke
			(width 0.07112)
			(type default)
		)
		(layer "In6.Cu")
	)
	(gr_line
		(start 321.512692 -410.114496)
		(end 321.512438 -410.113988)
		(stroke
			(width 0.07112)
			(type default)
		)
		(layer "In6.Cu")
	)
	(gr_line
		(start 321.623436 -410.518864)
		(end 321.217544 -410.650944)
		(stroke
			(width 0.07112)
			(type default)
		)
		(layer "In6.Cu")
	)
	(gr_line
		(start 321.623944 -410.078428)
		(end 321.512692 -410.114496)
		(stroke
			(width 0.07112)
			(type default)
		)
		(layer "In6.Cu")
	)
	(gr_line
		(start 321.710304 -410.347922)
		(end 321.623436 -410.518864)
		(stroke
			(width 0.07112)
			(type default)
		)
		(layer "In6.Cu")
	)
	(gr_line
		(start 321.711066 -377.1265)
		(end 322.001896 -377.41733)
		(stroke
			(width 0.07112)
			(type default)
		)
		(layer "In6.Cu")
	)
	(gr_line
		(start 322.009008 -423.06367)
		(end 322.454016 -423.605706)
		(stroke
			(width 0.07112)
			(type default)
		)
		(layer "In6.Cu")
	)
	(gr_line
		(start 322.228718 -422.884854)
		(end 322.420234 -422.90365)
		(stroke
			(width 0.07112)
			(type default)
		)
		(layer "In6.Cu")
	)
	(gr_line
		(start 322.420234 -422.90365)
		(end 322.691252 -423.23385)
		(stroke
			(width 0.07112)
			(type default)
		)
		(layer "In6.Cu")
	)
	(gr_line
		(start 322.488052 -426.569886)
		(end 322.522342 -426.569886)
		(stroke
			(width 0.07112)
			(type default)
		)
		(layer "In6.Cu")
	)
	(gr_line
		(start 322.489322 -426.853096)
		(end 322.649596 -427.01337)
		(stroke
			(width 0.07112)
			(type default)
		)
		(layer "In6.Cu")
	)
	(gr_line
		(start 322.522342 -426.569886)
		(end 322.649596 -426.442632)
		(stroke
			(width 0.07112)
			(type default)
		)
		(layer "In6.Cu")
	)
	(gr_line
		(start 322.574412 -411.296358)
		(end 322.402708 -411.207458)
		(stroke
			(width 0.07112)
			(type default)
		)
		(layer "In6.Cu")
	)
	(gr_line
		(start 322.649596 -427.01337)
		(end 322.649596 -427.289976)
		(stroke
			(width 0.07112)
			(type default)
		)
		(layer "In6.Cu")
	)
	(gr_line
		(start 322.649596 -426.442632)
		(end 322.649596 -426.089826)
		(stroke
			(width 0.07112)
			(type default)
		)
		(layer "In6.Cu")
	)
	(gr_line
		(start 322.691252 -423.23385)
		(end 322.672456 -423.425366)
		(stroke
			(width 0.07112)
			(type default)
		)
		(layer "In6.Cu")
	)
	(gr_line
		(start 322.72478 -423.935398)
		(end 323.169534 -424.477434)
		(stroke
			(width 0.07112)
			(type default)
		)
		(layer "In6.Cu")
	)
	(gr_line
		(start 322.944236 -423.756836)
		(end 323.135752 -423.775632)
		(stroke
			(width 0.07112)
			(type default)
		)
		(layer "In6.Cu")
	)
	(gr_line
		(start 322.98132 -411.16758)
		(end 322.574412 -411.296358)
		(stroke
			(width 0.07112)
			(type default)
		)
		(layer "In6.Cu")
	)
	(gr_line
		(start 322.985384 -410.72562)
		(end 322.315586 -410.937964)
		(stroke
			(width 0.07112)
			(type default)
		)
		(layer "In6.Cu")
	)
	(gr_line
		(start 323.070474 -410.995876)
		(end 322.98132 -411.16758)
		(stroke
			(width 0.07112)
			(type default)
		)
		(layer "In6.Cu")
	)
	(gr_line
		(start 323.135752 -423.775632)
		(end 323.40677 -424.105832)
		(stroke
			(width 0.07112)
			(type default)
		)
		(layer "In6.Cu")
	)
	(gr_line
		(start 323.40677 -424.105832)
		(end 323.38772 -424.297094)
		(stroke
			(width 0.07112)
			(type default)
		)
		(layer "In6.Cu")
	)
	(gr_line
		(start 323.66839 -410.95549)
		(end 323.489574 -410.86278)
		(stroke
			(width 0.07112)
			(type default)
		)
		(layer "In6.Cu")
	)
	(gr_line
		(start 323.704966 -418.412168)
		(end 323.995796 -418.702998)
		(stroke
			(width 0.07112)
			(type default)
		)
		(layer "In6.Cu")
	)
	(gr_line
		(start 323.971666 -410.412946)
		(end 323.403722 -410.593032)
		(stroke
			(width 0.07112)
			(type default)
		)
		(layer "In6.Cu")
	)
	(gr_line
		(start 323.97192 -410.4132)
		(end 323.971666 -410.412946)
		(stroke
			(width 0.07112)
			(type default)
		)
		(layer "In6.Cu")
	)
	(gr_line
		(start 323.995796 -419.61562)
		(end 323.995796 -420.31666)
		(stroke
			(width 0.07112)
			(type default)
		)
		(layer "In6.Cu")
	)
	(gr_line
		(start 323.995796 -415.09569)
		(end 323.704966 -415.38652)
		(stroke
			(width 0.07112)
			(type default)
		)
		(layer "In6.Cu")
	)
	(gr_line
		(start 324.075298 -410.826712)
		(end 323.66839 -410.95549)
		(stroke
			(width 0.07112)
			(type default)
		)
		(layer "In6.Cu")
	)
	(gr_line
		(start 324.083426 -410.377894)
		(end 323.97192 -410.4132)
		(stroke
			(width 0.07112)
			(type default)
		)
		(layer "In6.Cu")
	)
	(gr_line
		(start 324.167754 -410.64815)
		(end 324.075298 -410.826712)
		(stroke
			(width 0.07112)
			(type default)
		)
		(layer "In6.Cu")
	)
	(gr_line
		(start 324.180454 -421.879268)
		(end 324.448932 -422.527222)
		(stroke
			(width 0.07112)
			(type default)
		)
		(layer "In6.Cu")
	)
	(gr_line
		(start 324.277736 -415.09569)
		(end 324.568566 -415.38652)
		(stroke
			(width 0.07112)
			(type default)
		)
		(layer "In6.Cu")
	)
	(gr_line
		(start 324.279006 -419.61689)
		(end 324.414896 -419.75278)
		(stroke
			(width 0.07112)
			(type default)
		)
		(layer "In6.Cu")
	)
	(gr_line
		(start 324.296786 -421.423338)
		(end 324.440804 -421.771572)
		(stroke
			(width 0.07112)
			(type default)
		)
		(layer "In6.Cu")
	)
	(gr_line
		(start 324.414896 -420.1795)
		(end 324.279006 -420.31539)
		(stroke
			(width 0.07112)
			(type default)
		)
		(layer "In6.Cu")
	)
	(gr_line
		(start 324.414896 -419.75278)
		(end 324.414896 -420.1795)
		(stroke
			(width 0.07112)
			(type default)
		)
		(layer "In6.Cu")
	)
	(gr_line
		(start 324.442582 -421.772334)
		(end 324.620382 -421.84574)
		(stroke
			(width 0.07112)
			(type default)
		)
		(layer "In6.Cu")
	)
	(gr_line
		(start 324.448932 -422.527222)
		(end 324.612 -422.92143)
		(stroke
			(width 0.07112)
			(type default)
		)
		(layer "In6.Cu")
	)
	(gr_line
		(start 324.507352 -427.830742)
		(end 324.649592 -427.972982)
		(stroke
			(width 0.07112)
			(type default)
		)
		(layer "In6.Cu")
	)
	(gr_line
		(start 324.507352 -427.548802)
		(end 324.649592 -427.406562)
		(stroke
			(width 0.07112)
			(type default)
		)
		(layer "In6.Cu")
	)
	(gr_line
		(start 324.508876 -410.24302)
		(end 324.503288 -410.244798)
		(stroke
			(width 0.07112)
			(type default)
		)
		(layer "In6.Cu")
	)
	(gr_line
		(start 324.508876 -410.242766)
		(end 324.508876 -410.24302)
		(stroke
			(width 0.07112)
			(type default)
		)
		(layer "In6.Cu")
	)
	(gr_line
		(start 324.568566 -418.412168)
		(end 324.277736 -418.702998)
		(stroke
			(width 0.07112)
			(type default)
		)
		(layer "In6.Cu")
	)
	(gr_line
		(start 324.597522 -411.653228)
		(end 324.597014 -411.653482)
		(stroke
			(width 0.07112)
			(type default)
		)
		(layer "In6.Cu")
	)
	(gr_line
		(start 324.612 -422.92143)
		(end 324.880478 -423.569384)
		(stroke
			(width 0.07112)
			(type default)
		)
		(layer "In6.Cu")
	)
	(gr_line
		(start 324.620382 -421.84574)
		(end 324.783704 -422.240202)
		(stroke
			(width 0.07112)
			(type default)
		)
		(layer "In6.Cu")
	)
	(gr_line
		(start 324.649592 -427.972982)
		(end 324.649592 -428.28972)
		(stroke
			(width 0.07112)
			(type default)
		)
		(layer "In6.Cu")
	)
	(gr_line
		(start 324.649592 -427.406562)
		(end 324.649592 -427.089824)
		(stroke
			(width 0.07112)
			(type default)
		)
		(layer "In6.Cu")
	)
	(gr_line
		(start 324.709282 -422.419526)
		(end 324.87235 -422.813734)
		(stroke
			(width 0.07112)
			(type default)
		)
		(layer "In6.Cu")
	)
	(gr_line
		(start 324.75297 -410.598874)
		(end 324.589902 -410.514546)
		(stroke
			(width 0.07112)
			(type default)
		)
		(layer "In6.Cu")
	)
	(gr_line
		(start 324.783704 -422.240202)
		(end 324.710044 -422.417748)
		(stroke
			(width 0.07112)
			(type default)
		)
		(layer "In6.Cu")
	)
	(gr_line
		(start 324.832726 -377.70816)
		(end 324.541896 -377.41733)
		(stroke
			(width 0.07112)
			(type default)
		)
		(layer "In6.Cu")
	)
	(gr_line
		(start 324.874382 -422.814496)
		(end 325.051928 -422.887902)
		(stroke
			(width 0.07112)
			(type default)
		)
		(layer "In6.Cu")
	)
	(gr_line
		(start 324.880478 -423.569384)
		(end 325.0438 -423.963592)
		(stroke
			(width 0.07112)
			(type default)
		)
		(layer "In6.Cu")
	)
	(gr_line
		(start 325.039736 -410.07411)
		(end 324.508876 -410.242766)
		(stroke
			(width 0.07112)
			(type default)
		)
		(layer "In6.Cu")
	)
	(gr_line
		(start 325.0438 -423.963592)
		(end 325.312278 -424.6118)
		(stroke
			(width 0.07112)
			(type default)
		)
		(layer "In6.Cu")
	)
	(gr_line
		(start 325.045832 -410.077666)
		(end 325.039736 -410.07411)
		(stroke
			(width 0.07112)
			(type default)
		)
		(layer "In6.Cu")
	)
	(gr_line
		(start 325.051928 -422.887902)
		(end 325.21525 -423.282364)
		(stroke
			(width 0.07112)
			(type default)
		)
		(layer "In6.Cu")
	)
	(gr_line
		(start 325.10857 -411.624526)
		(end 324.93585 -411.53969)
		(stroke
			(width 0.07112)
			(type default)
		)
		(layer "In6.Cu")
	)
	(gr_line
		(start 325.114666 -377.70816)
		(end 325.405496 -377.41733)
		(stroke
			(width 0.07112)
			(type default)
		)
		(layer "In6.Cu")
	)
	(gr_line
		(start 325.140828 -423.461688)
		(end 325.303896 -423.855896)
		(stroke
			(width 0.07112)
			(type default)
		)
		(layer "In6.Cu")
	)
	(gr_line
		(start 325.157084 -410.04236)
		(end 325.045832 -410.077666)
		(stroke
			(width 0.07112)
			(type default)
		)
		(layer "In6.Cu")
	)
	(gr_line
		(start 325.159878 -410.470096)
		(end 324.75297 -410.598874)
		(stroke
			(width 0.07112)
			(type default)
		)
		(layer "In6.Cu")
	)
	(gr_line
		(start 325.21525 -423.282364)
		(end 325.14159 -423.45991)
		(stroke
			(width 0.07112)
			(type default)
		)
		(layer "In6.Cu")
	)
	(gr_line
		(start 325.241666 -410.312616)
		(end 325.159878 -410.470096)
		(stroke
			(width 0.07112)
			(type default)
		)
		(layer "In6.Cu")
	)
	(gr_line
		(start 325.305928 -423.856658)
		(end 325.483474 -423.930064)
		(stroke
			(width 0.07112)
			(type default)
		)
		(layer "In6.Cu")
	)
	(gr_line
		(start 325.483474 -423.930064)
		(end 325.646796 -424.324526)
		(stroke
			(width 0.07112)
			(type default)
		)
		(layer "In6.Cu")
	)
	(gr_line
		(start 325.507858 -411.046168)
		(end 324.843902 -411.27172)
		(stroke
			(width 0.07112)
			(type default)
		)
		(layer "In6.Cu")
	)
	(gr_line
		(start 325.512938 -411.487366)
		(end 325.10857 -411.624526)
		(stroke
			(width 0.07112)
			(type default)
		)
		(layer "In6.Cu")
	)
	(gr_line
		(start 325.597774 -411.314646)
		(end 325.512938 -411.487366)
		(stroke
			(width 0.07112)
			(type default)
		)
		(layer "In6.Cu")
	)
	(gr_line
		(start 325.646796 -424.324526)
		(end 325.57339 -424.502072)
		(stroke
			(width 0.07112)
			(type default)
		)
		(layer "In6.Cu")
	)
	(gr_line
		(start 325.903336 -426.68825)
		(end 325.904352 -426.689266)
		(stroke
			(width 0.07112)
			(type default)
		)
		(layer "In6.Cu")
	)
	(gr_line
		(start 326.176386 -411.26156)
		(end 326.003666 -411.176724)
		(stroke
			(width 0.07112)
			(type default)
		)
		(layer "In6.Cu")
	)
	(gr_line
		(start 326.48652 -426.849794)
		(end 326.487028 -426.849794)
		(stroke
			(width 0.07112)
			(type default)
		)
		(layer "In6.Cu")
	)
	(gr_line
		(start 326.487028 -426.849794)
		(end 326.518524 -426.849794)
		(stroke
			(width 0.07112)
			(type default)
		)
		(layer "In6.Cu")
	)
	(gr_line
		(start 326.488044 -426.567854)
		(end 326.488298 -426.567854)
		(stroke
			(width 0.07112)
			(type default)
		)
		(layer "In6.Cu")
	)
	(gr_line
		(start 326.489568 -426.566584)
		(end 326.649588 -426.406564)
		(stroke
			(width 0.07112)
			(type default)
		)
		(layer "In6.Cu")
	)
	(gr_line
		(start 326.518524 -426.849794)
		(end 326.649588 -426.980858)
		(stroke
			(width 0.07112)
			(type default)
		)
		(layer "In6.Cu")
	)
	(gr_line
		(start 326.575674 -410.683202)
		(end 325.911718 -410.908754)
		(stroke
			(width 0.07112)
			(type default)
		)
		(layer "In6.Cu")
	)
	(gr_line
		(start 326.580754 -411.1244)
		(end 326.176386 -411.26156)
		(stroke
			(width 0.07112)
			(type default)
		)
		(layer "In6.Cu")
	)
	(gr_line
		(start 326.649588 -426.980858)
		(end 326.649588 -427.289976)
		(stroke
			(width 0.07112)
			(type default)
		)
		(layer "In6.Cu")
	)
	(gr_line
		(start 326.649588 -426.406564)
		(end 326.649588 -426.089826)
		(stroke
			(width 0.07112)
			(type default)
		)
		(layer "In6.Cu")
	)
	(gr_line
		(start 326.66559 -410.95168)
		(end 326.580754 -411.1244)
		(stroke
			(width 0.07112)
			(type default)
		)
		(layer "In6.Cu")
	)
	(gr_line
		(start 326.750934 -378.63399)
		(end 326.737218 -378.633228)
		(stroke
			(width 0.07112)
			(type default)
		)
		(layer "In6.Cu")
	)
	(gr_arc
		(start 326.750934 -378.35205)
		(mid 326.744086 -378.35149)
		(end 326.737218 -378.351288)
		(stroke
			(width 0.07112)
			(type default)
		)
		(layer "In6.Cu")
	)
	(gr_line
		(start 326.758808 -378.63399)
		(end 326.750934 -378.63399)
		(stroke
			(width 0.07112)
			(type default)
		)
		(layer "In6.Cu")
	)
	(gr_line
		(start 326.768206 -418.412168)
		(end 327.059036 -418.702998)
		(stroke
			(width 0.07112)
			(type default)
		)
		(layer "In6.Cu")
	)
	(gr_line
		(start 327.059036 -419.72865)
		(end 327.059036 -420.42969)
		(stroke
			(width 0.07112)
			(type default)
		)
		(layer "In6.Cu")
	)
	(gr_line
		(start 327.059036 -415.09569)
		(end 326.768206 -415.38652)
		(stroke
			(width 0.07112)
			(type default)
		)
		(layer "In6.Cu")
	)
	(gr_line
		(start 327.095358 -421.532812)
		(end 327.147428 -421.79494)
		(stroke
			(width 0.07112)
			(type default)
		)
		(layer "In6.Cu")
	)
	(gr_line
		(start 327.147428 -421.79494)
		(end 327.284334 -422.482772)
		(stroke
			(width 0.07112)
			(type default)
		)
		(layer "In6.Cu")
	)
	(gr_line
		(start 327.244202 -410.898594)
		(end 327.071482 -410.813758)
		(stroke
			(width 0.07112)
			(type default)
		)
		(layer "In6.Cu")
	)
	(gr_line
		(start 327.340976 -415.09569)
		(end 327.631806 -415.38652)
		(stroke
			(width 0.07112)
			(type default)
		)
		(layer "In6.Cu")
	)
	(gr_line
		(start 327.342246 -419.72992)
		(end 327.478136 -419.86581)
		(stroke
			(width 0.07112)
			(type default)
		)
		(layer "In6.Cu")
	)
	(gr_line
		(start 327.367392 -422.90111)
		(end 327.504298 -423.589196)
		(stroke
			(width 0.07112)
			(type default)
		)
		(layer "In6.Cu")
	)
	(gr_line
		(start 327.425558 -421.741092)
		(end 327.585578 -421.848026)
		(stroke
			(width 0.07112)
			(type default)
		)
		(layer "In6.Cu")
	)
	(gr_line
		(start 327.478136 -420.29253)
		(end 327.342246 -420.42842)
		(stroke
			(width 0.07112)
			(type default)
		)
		(layer "In6.Cu")
	)
	(gr_line
		(start 327.478136 -419.86581)
		(end 327.478136 -420.29253)
		(stroke
			(width 0.07112)
			(type default)
		)
		(layer "In6.Cu")
	)
	(gr_line
		(start 327.556876 -388.463028)
		(end 327.277476 -388.742428)
		(stroke
			(width 0.07112)
			(type default)
		)
		(layer "In6.Cu")
	)
	(gr_line
		(start 327.568306 -385.047998)
		(end 327.277476 -385.338828)
		(stroke
			(width 0.07112)
			(type default)
		)
		(layer "In6.Cu")
	)
	(gr_line
		(start 327.568306 -384.766058)
		(end 327.277476 -384.475228)
		(stroke
			(width 0.07112)
			(type default)
		)
		(layer "In6.Cu")
	)
	(gr_line
		(start 327.578466 -388.179818)
		(end 327.277476 -387.878828)
		(stroke
			(width 0.07112)
			(type default)
		)
		(layer "In6.Cu")
	)
	(gr_line
		(start 327.579736 -388.463028)
		(end 327.556876 -388.463028)
		(stroke
			(width 0.07112)
			(type default)
		)
		(layer "In6.Cu")
	)
	(gr_line
		(start 327.585578 -421.848026)
		(end 327.66889 -422.266618)
		(stroke
			(width 0.07112)
			(type default)
		)
		(layer "In6.Cu")
	)
	(gr_line
		(start 327.606914 -424.105832)
		(end 327.607168 -424.105832)
		(stroke
			(width 0.07112)
			(type default)
		)
		(layer "In6.Cu")
	)
	(gr_line
		(start 327.631806 -418.412168)
		(end 327.340976 -418.702998)
		(stroke
			(width 0.07112)
			(type default)
		)
		(layer "In6.Cu")
	)
	(gr_line
		(start 327.64349 -410.320236)
		(end 326.979534 -410.545788)
		(stroke
			(width 0.07112)
			(type default)
		)
		(layer "In6.Cu")
	)
	(gr_line
		(start 327.645522 -422.847008)
		(end 327.805796 -422.954196)
		(stroke
			(width 0.07112)
			(type default)
		)
		(layer "In6.Cu")
	)
	(gr_line
		(start 327.64857 -410.761434)
		(end 327.244202 -410.898594)
		(stroke
			(width 0.07112)
			(type default)
		)
		(layer "In6.Cu")
	)
	(gr_line
		(start 327.66889 -422.266618)
		(end 327.561956 -422.426892)
		(stroke
			(width 0.07112)
			(type default)
		)
		(layer "In6.Cu")
	)
	(gr_line
		(start 327.733406 -410.588714)
		(end 327.64857 -410.761434)
		(stroke
			(width 0.07112)
			(type default)
		)
		(layer "In6.Cu")
	)
	(gr_line
		(start 327.805796 -422.954196)
		(end 327.889108 -423.372788)
		(stroke
			(width 0.07112)
			(type default)
		)
		(layer "In6.Cu")
	)
	(gr_line
		(start 327.889108 -423.372788)
		(end 327.78192 -423.533062)
		(stroke
			(width 0.07112)
			(type default)
		)
		(layer "In6.Cu")
	)
	(gr_line
		(start 328.37247 -378.869448)
		(end 328.180192 -378.869448)
		(stroke
			(width 0.07112)
			(type default)
		)
		(layer "In6.Cu")
	)
	(gr_line
		(start 328.475086 -379.5649)
		(end 327.979024 -379.068838)
		(stroke
			(width 0.07112)
			(type default)
		)
		(layer "In6.Cu")
	)
	(gr_line
		(start 328.507344 -427.830742)
		(end 328.649584 -427.972982)
		(stroke
			(width 0.07112)
			(type default)
		)
		(layer "In6.Cu")
	)
	(gr_line
		(start 328.507344 -427.548802)
		(end 328.649584 -427.406562)
		(stroke
			(width 0.07112)
			(type default)
		)
		(layer "In6.Cu")
	)
	(gr_line
		(start 328.579734 -411.57144)
		(end 328.40422 -411.492192)
		(stroke
			(width 0.07112)
			(type default)
		)
		(layer "In6.Cu")
	)
	(gr_line
		(start 328.649584 -427.972982)
		(end 328.649584 -428.28972)
		(stroke
			(width 0.07112)
			(type default)
		)
		(layer "In6.Cu")
	)
	(gr_line
		(start 328.649584 -427.406562)
		(end 328.649584 -427.089824)
		(stroke
			(width 0.07112)
			(type default)
		)
		(layer "In6.Cu")
	)
	(gr_line
		(start 328.674476 -379.363732)
		(end 328.674476 -379.171454)
		(stroke
			(width 0.07112)
			(type default)
		)
		(layer "In6.Cu")
	)
	(gr_line
		(start 328.674476 -379.171454)
		(end 328.37247 -378.869448)
		(stroke
			(width 0.07112)
			(type default)
		)
		(layer "In6.Cu")
	)
	(gr_line
		(start 328.959464 -410.979874)
		(end 328.303382 -411.227524)
		(stroke
			(width 0.07112)
			(type default)
		)
		(layer "In6.Cu")
	)
	(gr_line
		(start 328.979276 -411.420564)
		(end 328.579734 -411.57144)
		(stroke
			(width 0.07112)
			(type default)
		)
		(layer "In6.Cu")
	)
	(gr_line
		(start 329.05827 -411.24505)
		(end 328.979276 -411.420564)
		(stroke
			(width 0.07112)
			(type default)
		)
		(layer "In6.Cu")
	)
	(gr_line
		(start 329.17003 -379.667008)
		(end 328.977752 -379.667008)
		(stroke
			(width 0.07112)
			(type default)
		)
		(layer "In6.Cu")
	)
	(gr_line
		(start 329.272646 -380.36246)
		(end 328.776584 -379.866398)
		(stroke
			(width 0.07112)
			(type default)
		)
		(layer "In6.Cu")
	)
	(gr_line
		(start 329.472036 -380.161292)
		(end 329.472036 -379.969014)
		(stroke
			(width 0.07112)
			(type default)
		)
		(layer "In6.Cu")
	)
	(gr_line
		(start 329.472036 -379.969014)
		(end 329.17003 -379.667008)
		(stroke
			(width 0.07112)
			(type default)
		)
		(layer "In6.Cu")
	)
	(gr_line
		(start 329.63485 -411.17266)
		(end 329.45959 -411.093666)
		(stroke
			(width 0.07112)
			(type default)
		)
		(layer "In6.Cu")
	)
	(gr_line
		(start 329.831446 -418.412168)
		(end 330.122276 -418.702998)
		(stroke
			(width 0.07112)
			(type default)
		)
		(layer "In6.Cu")
	)
	(gr_line
		(start 329.96759 -380.464568)
		(end 329.775312 -380.464568)
		(stroke
			(width 0.07112)
			(type default)
		)
		(layer "In6.Cu")
	)
	(gr_line
		(start 330.01458 -410.581094)
		(end 329.358498 -410.828998)
		(stroke
			(width 0.07112)
			(type default)
		)
		(layer "In6.Cu")
	)
	(gr_line
		(start 330.034392 -411.022038)
		(end 329.63485 -411.17266)
		(stroke
			(width 0.07112)
			(type default)
		)
		(layer "In6.Cu")
	)
	(gr_line
		(start 330.070206 -381.16002)
		(end 329.574144 -380.663958)
		(stroke
			(width 0.07112)
			(type default)
		)
		(layer "In6.Cu")
	)
	(gr_line
		(start 330.113386 -410.846524)
		(end 330.034392 -411.022038)
		(stroke
			(width 0.07112)
			(type default)
		)
		(layer "In6.Cu")
	)
	(gr_line
		(start 330.122276 -424.593766)
		(end 330.122276 -425.294806)
		(stroke
			(width 0.07112)
			(type default)
		)
		(layer "In6.Cu")
	)
	(gr_line
		(start 330.122276 -423.466006)
		(end 330.122276 -424.167046)
		(stroke
			(width 0.07112)
			(type default)
		)
		(layer "In6.Cu")
	)
	(gr_line
		(start 330.122276 -422.338246)
		(end 330.122276 -423.039286)
		(stroke
			(width 0.07112)
			(type default)
		)
		(layer "In6.Cu")
	)
	(gr_line
		(start 330.122276 -421.210486)
		(end 330.122276 -421.911526)
		(stroke
			(width 0.07112)
			(type default)
		)
		(layer "In6.Cu")
	)
	(gr_line
		(start 330.122276 -419.541452)
		(end 330.122276 -420.242492)
		(stroke
			(width 0.07112)
			(type default)
		)
		(layer "In6.Cu")
	)
	(gr_line
		(start 330.122276 -415.09569)
		(end 329.831446 -415.38652)
		(stroke
			(width 0.07112)
			(type default)
		)
		(layer "In6.Cu")
	)
	(gr_line
		(start 330.269596 -380.958852)
		(end 330.269596 -380.766574)
		(stroke
			(width 0.07112)
			(type default)
		)
		(layer "In6.Cu")
	)
	(gr_line
		(start 330.269596 -380.766574)
		(end 329.96759 -380.464568)
		(stroke
			(width 0.07112)
			(type default)
		)
		(layer "In6.Cu")
	)
	(gr_line
		(start 330.404216 -415.09569)
		(end 330.695046 -415.38652)
		(stroke
			(width 0.07112)
			(type default)
		)
		(layer "In6.Cu")
	)
	(gr_line
		(start 330.405486 -424.595036)
		(end 330.541376 -424.730926)
		(stroke
			(width 0.07112)
			(type default)
		)
		(layer "In6.Cu")
	)
	(gr_line
		(start 330.405486 -423.467276)
		(end 330.541376 -423.603166)
		(stroke
			(width 0.07112)
			(type default)
		)
		(layer "In6.Cu")
	)
	(gr_line
		(start 330.405486 -422.339516)
		(end 330.541376 -422.475406)
		(stroke
			(width 0.07112)
			(type default)
		)
		(layer "In6.Cu")
	)
	(gr_line
		(start 330.405486 -421.211756)
		(end 330.541376 -421.347646)
		(stroke
			(width 0.07112)
			(type default)
		)
		(layer "In6.Cu")
	)
	(gr_line
		(start 330.405486 -419.542722)
		(end 330.541376 -419.678612)
		(stroke
			(width 0.07112)
			(type default)
		)
		(layer "In6.Cu")
	)
	(gr_line
		(start 330.541376 -425.157646)
		(end 330.405486 -425.293536)
		(stroke
			(width 0.07112)
			(type default)
		)
		(layer "In6.Cu")
	)
	(gr_line
		(start 330.541376 -424.730926)
		(end 330.541376 -425.157646)
		(stroke
			(width 0.07112)
			(type default)
		)
		(layer "In6.Cu")
	)
	(gr_line
		(start 330.541376 -424.029886)
		(end 330.405486 -424.165776)
		(stroke
			(width 0.07112)
			(type default)
		)
		(layer "In6.Cu")
	)
	(gr_line
		(start 330.541376 -423.603166)
		(end 330.541376 -424.029886)
		(stroke
			(width 0.07112)
			(type default)
		)
		(layer "In6.Cu")
	)
	(gr_line
		(start 330.541376 -422.902126)
		(end 330.405486 -423.038016)
		(stroke
			(width 0.07112)
			(type default)
		)
		(layer "In6.Cu")
	)
	(gr_line
		(start 330.541376 -422.475406)
		(end 330.541376 -422.902126)
		(stroke
			(width 0.07112)
			(type default)
		)
		(layer "In6.Cu")
	)
	(gr_line
		(start 330.541376 -421.774366)
		(end 330.405486 -421.910256)
		(stroke
			(width 0.07112)
			(type default)
		)
		(layer "In6.Cu")
	)
	(gr_line
		(start 330.541376 -421.347646)
		(end 330.541376 -421.774366)
		(stroke
			(width 0.07112)
			(type default)
		)
		(layer "In6.Cu")
	)
	(gr_line
		(start 330.541376 -420.105332)
		(end 330.405486 -420.241222)
		(stroke
			(width 0.07112)
			(type default)
		)
		(layer "In6.Cu")
	)
	(gr_line
		(start 330.541376 -419.678612)
		(end 330.541376 -420.105332)
		(stroke
			(width 0.07112)
			(type default)
		)
		(layer "In6.Cu")
	)
	(gr_line
		(start 330.689966 -410.774134)
		(end 330.514452 -410.694886)
		(stroke
			(width 0.07112)
			(type default)
		)
		(layer "In6.Cu")
	)
	(gr_line
		(start 330.695046 -418.412168)
		(end 330.404216 -418.702998)
		(stroke
			(width 0.07112)
			(type default)
		)
		(layer "In6.Cu")
	)
	(gr_line
		(start 330.76515 -381.262128)
		(end 330.572872 -381.262128)
		(stroke
			(width 0.07112)
			(type default)
		)
		(layer "In6.Cu")
	)
	(gr_line
		(start 330.867766 -381.95758)
		(end 330.371704 -381.461518)
		(stroke
			(width 0.07112)
			(type default)
		)
		(layer "In6.Cu")
	)
	(gr_line
		(start 331.052678 -411.345634)
		(end 331.052678 -411.345888)
		(stroke
			(width 0.07112)
			(type default)
		)
		(layer "In6.Cu")
	)
	(gr_line
		(start 331.067156 -381.756412)
		(end 331.067156 -381.564134)
		(stroke
			(width 0.07112)
			(type default)
		)
		(layer "In6.Cu")
	)
	(gr_line
		(start 331.067156 -381.564134)
		(end 330.76515 -381.262128)
		(stroke
			(width 0.07112)
			(type default)
		)
		(layer "In6.Cu")
	)
	(gr_line
		(start 331.069696 -410.182568)
		(end 330.413614 -410.430472)
		(stroke
			(width 0.07112)
			(type default)
		)
		(layer "In6.Cu")
	)
	(gr_line
		(start 331.089508 -410.623512)
		(end 330.689966 -410.774134)
		(stroke
			(width 0.07112)
			(type default)
		)
		(layer "In6.Cu")
	)
	(gr_line
		(start 331.168502 -410.447998)
		(end 331.089508 -410.623512)
		(stroke
			(width 0.07112)
			(type default)
		)
		(layer "In6.Cu")
	)
	(gr_line
		(start 331.339698 -411.68066)
		(end 331.161898 -411.607)
		(stroke
			(width 0.07112)
			(type default)
		)
		(layer "In6.Cu")
	)
	(gr_line
		(start 331.507592 -426.830744)
		(end 331.649832 -426.972984)
		(stroke
			(width 0.07112)
			(type default)
		)
		(layer "In6.Cu")
	)
	(gr_line
		(start 331.507592 -426.548804)
		(end 331.649832 -426.406564)
		(stroke
			(width 0.07112)
			(type default)
		)
		(layer "In6.Cu")
	)
	(gr_line
		(start 331.56271 -382.059688)
		(end 331.370432 -382.059688)
		(stroke
			(width 0.07112)
			(type default)
		)
		(layer "In6.Cu")
	)
	(gr_line
		(start 331.649832 -426.972984)
		(end 331.649832 -427.289976)
		(stroke
			(width 0.07112)
			(type default)
		)
		(layer "In6.Cu")
	)
	(gr_line
		(start 331.649832 -426.406564)
		(end 331.649832 -426.089826)
		(stroke
			(width 0.07112)
			(type default)
		)
		(layer "In6.Cu")
	)
	(gr_line
		(start 331.665326 -382.75514)
		(end 331.169264 -382.259078)
		(stroke
			(width 0.07112)
			(type default)
		)
		(layer "In6.Cu")
	)
	(gr_line
		(start 331.700886 -411.077156)
		(end 331.052678 -411.345634)
		(stroke
			(width 0.07112)
			(type default)
		)
		(layer "In6.Cu")
	)
	(gr_line
		(start 331.705712 -408.939492)
		(end 331.705458 -408.939492)
		(stroke
			(width 0.07112)
			(type default)
		)
		(layer "In6.Cu")
	)
	(gr_line
		(start 331.73416 -411.517338)
		(end 331.339698 -411.68066)
		(stroke
			(width 0.07112)
			(type default)
		)
		(layer "In6.Cu")
	)
	(gr_line
		(start 331.800708 -409.205176)
		(end 331.79639 -409.2067)
		(stroke
			(width 0.07112)
			(type default)
		)
		(layer "In6.Cu")
	)
	(gr_line
		(start 331.805026 -409.203652)
		(end 331.800708 -409.205176)
		(stroke
			(width 0.07112)
			(type default)
		)
		(layer "In6.Cu")
	)
	(gr_line
		(start 331.80782 -411.339284)
		(end 331.73416 -411.517338)
		(stroke
			(width 0.07112)
			(type default)
		)
		(layer "In6.Cu")
	)
	(gr_line
		(start 331.864716 -382.553972)
		(end 331.864716 -382.361694)
		(stroke
			(width 0.07112)
			(type default)
		)
		(layer "In6.Cu")
	)
	(gr_line
		(start 331.864716 -382.361694)
		(end 331.56271 -382.059688)
		(stroke
			(width 0.07112)
			(type default)
		)
		(layer "In6.Cu")
	)
	(gr_line
		(start 332.38186 -411.24886)
		(end 332.204314 -411.1752)
		(stroke
			(width 0.07112)
			(type default)
		)
		(layer "In6.Cu")
	)
	(gr_line
		(start 332.743048 -410.64561)
		(end 332.09484 -410.914088)
		(stroke
			(width 0.07112)
			(type default)
		)
		(layer "In6.Cu")
	)
	(gr_line
		(start 332.776322 -411.085538)
		(end 332.38186 -411.24886)
		(stroke
			(width 0.07112)
			(type default)
		)
		(layer "In6.Cu")
	)
	(gr_line
		(start 332.849982 -410.907738)
		(end 332.776322 -411.085538)
		(stroke
			(width 0.07112)
			(type default)
		)
		(layer "In6.Cu")
	)
	(gr_line
		(start 332.852522 -423.574718)
		(end 332.783942 -424.272964)
		(stroke
			(width 0.07112)
			(type default)
		)
		(layer "In6.Cu")
	)
	(gr_line
		(start 332.894686 -418.412168)
		(end 333.185516 -418.702998)
		(stroke
			(width 0.07112)
			(type default)
		)
		(layer "In6.Cu")
	)
	(gr_line
		(start 332.962758 -422.452546)
		(end 332.894178 -423.150284)
		(stroke
			(width 0.07112)
			(type default)
		)
		(layer "In6.Cu")
	)
	(gr_line
		(start 333.064358 -424.300396)
		(end 332.99019 -425.057316)
		(stroke
			(width 0.07112)
			(type default)
		)
		(layer "In6.Cu")
	)
	(gr_line
		(start 333.134208 -423.60342)
		(end 333.256382 -423.752264)
		(stroke
			(width 0.07112)
			(type default)
		)
		(layer "In6.Cu")
	)
	(gr_line
		(start 333.185516 -419.690042)
		(end 333.185516 -420.391082)
		(stroke
			(width 0.07112)
			(type default)
		)
		(layer "In6.Cu")
	)
	(gr_line
		(start 333.185516 -415.09569)
		(end 332.894686 -415.38652)
		(stroke
			(width 0.07112)
			(type default)
		)
		(layer "In6.Cu")
	)
	(gr_line
		(start 333.214726 -424.177206)
		(end 333.065882 -424.299126)
		(stroke
			(width 0.07112)
			(type default)
		)
		(layer "In6.Cu")
	)
	(gr_line
		(start 333.244698 -422.480994)
		(end 333.366872 -422.629838)
		(stroke
			(width 0.07112)
			(type default)
		)
		(layer "In6.Cu")
	)
	(gr_line
		(start 333.256382 -423.752264)
		(end 333.214726 -424.177206)
		(stroke
			(width 0.07112)
			(type default)
		)
		(layer "In6.Cu")
	)
	(gr_line
		(start 333.325216 -423.05478)
		(end 333.176118 -423.176954)
		(stroke
			(width 0.07112)
			(type default)
		)
		(layer "In6.Cu")
	)
	(gr_line
		(start 333.366872 -422.629838)
		(end 333.325216 -423.05478)
		(stroke
			(width 0.07112)
			(type default)
		)
		(layer "In6.Cu")
	)
	(gr_line
		(start 333.424022 -410.817314)
		(end 333.246222 -410.743654)
		(stroke
			(width 0.07112)
			(type default)
		)
		(layer "In6.Cu")
	)
	(gr_line
		(start 333.467456 -415.09569)
		(end 333.758286 -415.38652)
		(stroke
			(width 0.07112)
			(type default)
		)
		(layer "In6.Cu")
	)
	(gr_line
		(start 333.468726 -419.691312)
		(end 333.604616 -419.827202)
		(stroke
			(width 0.07112)
			(type default)
		)
		(layer "In6.Cu")
	)
	(gr_line
		(start 333.507588 -427.830742)
		(end 333.649828 -427.972982)
		(stroke
			(width 0.07112)
			(type default)
		)
		(layer "In6.Cu")
	)
	(gr_line
		(start 333.507588 -427.548802)
		(end 333.649828 -427.406562)
		(stroke
			(width 0.07112)
			(type default)
		)
		(layer "In6.Cu")
	)
	(gr_line
		(start 333.604616 -420.253922)
		(end 333.468726 -420.389812)
		(stroke
			(width 0.07112)
			(type default)
		)
		(layer "In6.Cu")
	)
	(gr_line
		(start 333.604616 -419.827202)
		(end 333.604616 -420.253922)
		(stroke
			(width 0.07112)
			(type default)
		)
		(layer "In6.Cu")
	)
	(gr_line
		(start 333.649828 -427.972982)
		(end 333.649828 -428.28972)
		(stroke
			(width 0.07112)
			(type default)
		)
		(layer "In6.Cu")
	)
	(gr_line
		(start 333.649828 -427.406562)
		(end 333.649828 -427.089824)
		(stroke
			(width 0.07112)
			(type default)
		)
		(layer "In6.Cu")
	)
	(gr_line
		(start 333.758286 -418.412168)
		(end 333.467456 -418.702998)
		(stroke
			(width 0.07112)
			(type default)
		)
		(layer "In6.Cu")
	)
	(gr_line
		(start 333.784956 -410.214064)
		(end 333.137002 -410.482288)
		(stroke
			(width 0.07112)
			(type default)
		)
		(layer "In6.Cu")
	)
	(gr_line
		(start 333.78521 -410.214064)
		(end 333.78521 -410.21381)
		(stroke
			(width 0.07112)
			(type default)
		)
		(layer "In6.Cu")
	)
	(gr_line
		(start 333.78521 -410.21381)
		(end 333.784956 -410.214064)
		(stroke
			(width 0.07112)
			(type default)
		)
		(layer "In6.Cu")
	)
	(gr_line
		(start 333.818484 -410.653992)
		(end 333.424022 -410.817314)
		(stroke
			(width 0.07112)
			(type default)
		)
		(layer "In6.Cu")
	)
	(gr_line
		(start 333.892398 -410.476192)
		(end 333.818484 -410.653992)
		(stroke
			(width 0.07112)
			(type default)
		)
		(layer "In6.Cu")
	)
	(gr_line
		(start 334.532732 -383.476754)
		(end 334.396842 -383.612644)
		(stroke
			(width 0.07112)
			(type default)
		)
		(layer "In6.Cu")
	)
	(gr_line
		(start 334.898746 -426.097954)
		(end 334.899 -426.0977)
		(stroke
			(width 0.07112)
			(type default)
		)
		(layer "In6.Cu")
	)
	(gr_line
		(start 334.959452 -383.476754)
		(end 334.532732 -383.476754)
		(stroke
			(width 0.07112)
			(type default)
		)
		(layer "In6.Cu")
	)
	(gr_line
		(start 334.963008 -411.330394)
		(end 334.778858 -411.274768)
		(stroke
			(width 0.07112)
			(type default)
		)
		(layer "In6.Cu")
	)
	(gr_line
		(start 335.095342 -383.612644)
		(end 334.959452 -383.476754)
		(stroke
			(width 0.07112)
			(type default)
		)
		(layer "In6.Cu")
	)
	(gr_line
		(start 335.096612 -383.895854)
		(end 334.395572 -383.895854)
		(stroke
			(width 0.07112)
			(type default)
		)
		(layer "In6.Cu")
	)
	(gr_line
		(start 335.12887 -423.575988)
		(end 334.828896 -424.209972)
		(stroke
			(width 0.07112)
			(type default)
		)
		(layer "In6.Cu")
	)
	(gr_line
		(start 335.262728 -410.694886)
		(end 334.644238 -411.025594)
		(stroke
			(width 0.07112)
			(type default)
		)
		(layer "In6.Cu")
	)
	(gr_line
		(start 335.266792 -424.265344)
		(end 335.085436 -424.330114)
		(stroke
			(width 0.07112)
			(type default)
		)
		(layer "In6.Cu")
	)
	(gr_arc
		(start 335.305654 -426.847762)
		(mid 335.3054 -426.847762)
		(end 335.305146 -426.847762)
		(stroke
			(width 0.07112)
			(type default)
		)
		(layer "In6.Cu")
	)
	(gr_line
		(start 335.339436 -411.129226)
		(end 334.963008 -411.330394)
		(stroke
			(width 0.07112)
			(type default)
		)
		(layer "In6.Cu")
	)
	(gr_line
		(start 335.384394 -423.698162)
		(end 335.449164 -423.879264)
		(stroke
			(width 0.07112)
			(type default)
		)
		(layer "In6.Cu")
	)
	(gr_line
		(start 335.395316 -410.945076)
		(end 335.339436 -411.129226)
		(stroke
			(width 0.07112)
			(type default)
		)
		(layer "In6.Cu")
	)
	(gr_line
		(start 335.449164 -423.879264)
		(end 335.266792 -424.265344)
		(stroke
			(width 0.07112)
			(type default)
		)
		(layer "In6.Cu")
	)
	(gr_line
		(start 335.490566 -426.847762)
		(end 335.514696 -426.847762)
		(stroke
			(width 0.07112)
			(type default)
		)
		(layer "In6.Cu")
	)
	(gr_line
		(start 335.491836 -426.564552)
		(end 335.649824 -426.406564)
		(stroke
			(width 0.07112)
			(type default)
		)
		(layer "In6.Cu")
	)
	(gr_line
		(start 335.514696 -426.847762)
		(end 335.649824 -426.98289)
		(stroke
			(width 0.07112)
			(type default)
		)
		(layer "In6.Cu")
	)
	(gr_line
		(start 335.611216 -422.556432)
		(end 335.311242 -423.190416)
		(stroke
			(width 0.07112)
			(type default)
		)
		(layer "In6.Cu")
	)
	(gr_line
		(start 335.649824 -426.98289)
		(end 335.649824 -427.289976)
		(stroke
			(width 0.07112)
			(type default)
		)
		(layer "In6.Cu")
	)
	(gr_line
		(start 335.649824 -426.406564)
		(end 335.649824 -426.089826)
		(stroke
			(width 0.07112)
			(type default)
		)
		(layer "In6.Cu")
	)
	(gr_line
		(start 335.660492 -383.476754)
		(end 335.524602 -383.612644)
		(stroke
			(width 0.07112)
			(type default)
		)
		(layer "In6.Cu")
	)
	(gr_line
		(start 335.748884 -423.245788)
		(end 335.567782 -423.310558)
		(stroke
			(width 0.07112)
			(type default)
		)
		(layer "In6.Cu")
	)
	(gr_line
		(start 335.866486 -422.67886)
		(end 335.931256 -422.859708)
		(stroke
			(width 0.07112)
			(type default)
		)
		(layer "In6.Cu")
	)
	(gr_line
		(start 335.931256 -422.859708)
		(end 335.748884 -423.245788)
		(stroke
			(width 0.07112)
			(type default)
		)
		(layer "In6.Cu")
	)
	(gr_line
		(start 335.957926 -418.412168)
		(end 336.248756 -418.702998)
		(stroke
			(width 0.07112)
			(type default)
		)
		(layer "In6.Cu")
	)
	(gr_line
		(start 336.087212 -383.476754)
		(end 335.660492 -383.476754)
		(stroke
			(width 0.07112)
			(type default)
		)
		(layer "In6.Cu")
	)
	(gr_line
		(start 336.093308 -421.536876)
		(end 335.793588 -422.17086)
		(stroke
			(width 0.07112)
			(type default)
		)
		(layer "In6.Cu")
	)
	(gr_line
		(start 336.223102 -383.612644)
		(end 336.087212 -383.476754)
		(stroke
			(width 0.07112)
			(type default)
		)
		(layer "In6.Cu")
	)
	(gr_line
		(start 336.224372 -383.895854)
		(end 335.523332 -383.895854)
		(stroke
			(width 0.07112)
			(type default)
		)
		(layer "In6.Cu")
	)
	(gr_line
		(start 336.23123 -422.226232)
		(end 336.050128 -422.291002)
		(stroke
			(width 0.07112)
			(type default)
		)
		(layer "In6.Cu")
	)
	(gr_line
		(start 336.248756 -419.502082)
		(end 336.248756 -420.203122)
		(stroke
			(width 0.07112)
			(type default)
		)
		(layer "In6.Cu")
	)
	(gr_line
		(start 336.248756 -415.09569)
		(end 335.957926 -415.38652)
		(stroke
			(width 0.07112)
			(type default)
		)
		(layer "In6.Cu")
	)
	(gr_line
		(start 336.31886 -397.156432)
		(end 336.364326 -397.201898)
		(stroke
			(width 0.07112)
			(type default)
		)
		(layer "In6.Cu")
	)
	(gr_line
		(start 336.348832 -421.65905)
		(end 336.413602 -421.840152)
		(stroke
			(width 0.07112)
			(type default)
		)
		(layer "In6.Cu")
	)
	(gr_line
		(start 336.364326 -397.381984)
		(end 336.219038 -397.527272)
		(stroke
			(width 0.07112)
			(type default)
		)
		(layer "In6.Cu")
	)
	(gr_line
		(start 336.364326 -397.201898)
		(end 336.364326 -397.381984)
		(stroke
			(width 0.07112)
			(type default)
		)
		(layer "In6.Cu")
	)
	(gr_line
		(start 336.413602 -421.840152)
		(end 336.23123 -422.226232)
		(stroke
			(width 0.07112)
			(type default)
		)
		(layer "In6.Cu")
	)
	(gr_line
		(start 336.530696 -415.09569)
		(end 336.821526 -415.38652)
		(stroke
			(width 0.07112)
			(type default)
		)
		(layer "In6.Cu")
	)
	(gr_line
		(start 336.531966 -419.503352)
		(end 336.667856 -419.639242)
		(stroke
			(width 0.07112)
			(type default)
		)
		(layer "In6.Cu")
	)
	(gr_line
		(start 336.596228 -397.726662)
		(end 336.420206 -397.726662)
		(stroke
			(width 0.07112)
			(type default)
		)
		(layer "In6.Cu")
	)
	(gr_line
		(start 336.667856 -420.065962)
		(end 336.531966 -420.201852)
		(stroke
			(width 0.07112)
			(type default)
		)
		(layer "In6.Cu")
	)
	(gr_line
		(start 336.667856 -419.639242)
		(end 336.667856 -420.065962)
		(stroke
			(width 0.07112)
			(type default)
		)
		(layer "In6.Cu")
	)
	(gr_line
		(start 336.71891 -397.849344)
		(end 336.596228 -397.726662)
		(stroke
			(width 0.07112)
			(type default)
		)
		(layer "In6.Cu")
	)
	(gr_line
		(start 336.821526 -418.412168)
		(end 336.530696 -418.702998)
		(stroke
			(width 0.07112)
			(type default)
		)
		(layer "In6.Cu")
	)
	(gr_line
		(start 337.480656 -410.258006)
		(end 337.307174 -410.175202)
		(stroke
			(width 0.07112)
			(type default)
		)
		(layer "In6.Cu")
	)
	(gr_line
		(start 337.50758 -427.830742)
		(end 337.64982 -427.972982)
		(stroke
			(width 0.07112)
			(type default)
		)
		(layer "In6.Cu")
	)
	(gr_line
		(start 337.50758 -427.548802)
		(end 337.64982 -427.406562)
		(stroke
			(width 0.07112)
			(type default)
		)
		(layer "In6.Cu")
	)
	(gr_line
		(start 337.518756 -397.156432)
		(end 337.57108 -397.208756)
		(stroke
			(width 0.07112)
			(type default)
		)
		(layer "In6.Cu")
	)
	(gr_line
		(start 337.562444 -423.855642)
		(end 337.37042 -423.855642)
		(stroke
			(width 0.07112)
			(type default)
		)
		(layer "In6.Cu")
	)
	(gr_line
		(start 337.57108 -397.388588)
		(end 337.424522 -397.535146)
		(stroke
			(width 0.07112)
			(type default)
		)
		(layer "In6.Cu")
	)
	(gr_line
		(start 337.57108 -397.208756)
		(end 337.57108 -397.388588)
		(stroke
			(width 0.07112)
			(type default)
		)
		(layer "In6.Cu")
	)
	(gr_line
		(start 337.573112 -406.069546)
		(end 337.569302 -406.070816)
		(stroke
			(width 0.07112)
			(type default)
		)
		(layer "In6.Cu")
	)
	(gr_line
		(start 337.58886 -406.06472)
		(end 337.573874 -406.069292)
		(stroke
			(width 0.07112)
			(type default)
		)
		(layer "In6.Cu")
	)
	(gr_line
		(start 337.599782 -406.060402)
		(end 337.590892 -406.063958)
		(stroke
			(width 0.07112)
			(type default)
		)
		(layer "In6.Cu")
	)
	(gr_line
		(start 337.64982 -427.972982)
		(end 337.64982 -428.28972)
		(stroke
			(width 0.07112)
			(type default)
		)
		(layer "In6.Cu")
	)
	(gr_line
		(start 337.64982 -427.406562)
		(end 337.64982 -427.089824)
		(stroke
			(width 0.07112)
			(type default)
		)
		(layer "In6.Cu")
	)
	(gr_line
		(start 337.66506 -423.160444)
		(end 337.169252 -423.656252)
		(stroke
			(width 0.07112)
			(type default)
		)
		(layer "In6.Cu")
	)
	(gr_line
		(start 337.803998 -397.734536)
		(end 337.62569 -397.734536)
		(stroke
			(width 0.07112)
			(type default)
		)
		(layer "In6.Cu")
	)
	(gr_line
		(start 337.86445 -423.553636)
		(end 337.562444 -423.855642)
		(stroke
			(width 0.07112)
			(type default)
		)
		(layer "In6.Cu")
	)
	(gr_line
		(start 337.86445 -423.361612)
		(end 337.86445 -423.553636)
		(stroke
			(width 0.07112)
			(type default)
		)
		(layer "In6.Cu")
	)
	(gr_line
		(start 337.872832 -409.674568)
		(end 337.21167 -409.908502)
		(stroke
			(width 0.07112)
			(type default)
		)
		(layer "In6.Cu")
	)
	(gr_line
		(start 337.883246 -410.115766)
		(end 337.480656 -410.258006)
		(stroke
			(width 0.07112)
			(type default)
		)
		(layer "In6.Cu")
	)
	(gr_line
		(start 337.918806 -397.849344)
		(end 337.803998 -397.734536)
		(stroke
			(width 0.07112)
			(type default)
		)
		(layer "In6.Cu")
	)
	(gr_line
		(start 337.952334 -411.53461)
		(end 337.769708 -411.473142)
		(stroke
			(width 0.07112)
			(type default)
		)
		(layer "In6.Cu")
	)
	(gr_line
		(start 337.96605 -409.94203)
		(end 337.883246 -410.115766)
		(stroke
			(width 0.07112)
			(type default)
		)
		(layer "In6.Cu")
	)
	(gr_line
		(start 338.216494 -383.476754)
		(end 338.080604 -383.612644)
		(stroke
			(width 0.07112)
			(type default)
		)
		(layer "In6.Cu")
	)
	(gr_line
		(start 338.271358 -410.907992)
		(end 337.642962 -411.219904)
		(stroke
			(width 0.07112)
			(type default)
		)
		(layer "In6.Cu")
	)
	(gr_line
		(start 338.334858 -411.344872)
		(end 337.952334 -411.53461)
		(stroke
			(width 0.07112)
			(type default)
		)
		(layer "In6.Cu")
	)
	(gr_line
		(start 338.360004 -423.058336)
		(end 338.167726 -423.058336)
		(stroke
			(width 0.07112)
			(type default)
		)
		(layer "In6.Cu")
	)
	(gr_line
		(start 338.396326 -411.162246)
		(end 338.334858 -411.344872)
		(stroke
			(width 0.07112)
			(type default)
		)
		(layer "In6.Cu")
	)
	(gr_line
		(start 338.46262 -422.362884)
		(end 337.966558 -422.858946)
		(stroke
			(width 0.07112)
			(type default)
		)
		(layer "In6.Cu")
	)
	(gr_line
		(start 338.643214 -383.476754)
		(end 338.216494 -383.476754)
		(stroke
			(width 0.07112)
			(type default)
		)
		(layer "In6.Cu")
	)
	(gr_line
		(start 338.66201 -422.75633)
		(end 338.360004 -423.058336)
		(stroke
			(width 0.07112)
			(type default)
		)
		(layer "In6.Cu")
	)
	(gr_line
		(start 338.66201 -422.564052)
		(end 338.66201 -422.75633)
		(stroke
			(width 0.07112)
			(type default)
		)
		(layer "In6.Cu")
	)
	(gr_line
		(start 338.718906 -397.156432)
		(end 338.770214 -397.20774)
		(stroke
			(width 0.07112)
			(type default)
		)
		(layer "In6.Cu")
	)
	(gr_line
		(start 338.770214 -397.417544)
		(end 338.653628 -397.53413)
		(stroke
			(width 0.07112)
			(type default)
		)
		(layer "In6.Cu")
	)
	(gr_line
		(start 338.770214 -397.20774)
		(end 338.770214 -397.417544)
		(stroke
			(width 0.07112)
			(type default)
		)
		(layer "In6.Cu")
	)
	(gr_line
		(start 338.779104 -383.612644)
		(end 338.643214 -383.476754)
		(stroke
			(width 0.07112)
			(type default)
		)
		(layer "In6.Cu")
	)
	(gr_line
		(start 338.780374 -383.895854)
		(end 338.079334 -383.895854)
		(stroke
			(width 0.07112)
			(type default)
		)
		(layer "In6.Cu")
	)
	(gr_line
		(start 338.962746 -411.03296)
		(end 338.78012 -410.971746)
		(stroke
			(width 0.07112)
			(type default)
		)
		(layer "In6.Cu")
	)
	(gr_line
		(start 339.002878 -397.73352)
		(end 338.854796 -397.73352)
		(stroke
			(width 0.07112)
			(type default)
		)
		(layer "In6.Cu")
	)
	(gr_line
		(start 339.021166 -418.412168)
		(end 339.311996 -418.702998)
		(stroke
			(width 0.07112)
			(type default)
		)
		(layer "In6.Cu")
	)
	(gr_line
		(start 339.056472 -426.776642)
		(end 339.056726 -426.776642)
		(stroke
			(width 0.07112)
			(type default)
		)
		(layer "In6.Cu")
	)
	(gr_line
		(start 339.118702 -397.849344)
		(end 339.002878 -397.73352)
		(stroke
			(width 0.07112)
			(type default)
		)
		(layer "In6.Cu")
	)
	(gr_line
		(start 339.28177 -410.406596)
		(end 338.653374 -410.718508)
		(stroke
			(width 0.07112)
			(type default)
		)
		(layer "In6.Cu")
	)
	(gr_line
		(start 339.311996 -419.566344)
		(end 339.311996 -420.267384)
		(stroke
			(width 0.07112)
			(type default)
		)
		(layer "In6.Cu")
	)
	(gr_line
		(start 339.311996 -415.09569)
		(end 339.021166 -415.38652)
		(stroke
			(width 0.07112)
			(type default)
		)
		(layer "In6.Cu")
	)
	(gr_line
		(start 339.34527 -410.843476)
		(end 338.962746 -411.03296)
		(stroke
			(width 0.07112)
			(type default)
		)
		(layer "In6.Cu")
	)
	(gr_line
		(start 339.406738 -410.660596)
		(end 339.34527 -410.843476)
		(stroke
			(width 0.07112)
			(type default)
		)
		(layer "In6.Cu")
	)
	(gr_line
		(start 339.495384 -426.548804)
		(end 339.522816 -426.548804)
		(stroke
			(width 0.07112)
			(type default)
		)
		(layer "In6.Cu")
	)
	(gr_line
		(start 339.496654 -426.832014)
		(end 339.649816 -426.985176)
		(stroke
			(width 0.07112)
			(type default)
		)
		(layer "In6.Cu")
	)
	(gr_line
		(start 339.522816 -426.548804)
		(end 339.649816 -426.421804)
		(stroke
			(width 0.07112)
			(type default)
		)
		(layer "In6.Cu")
	)
	(gr_line
		(start 339.593936 -415.09569)
		(end 339.884766 -415.38652)
		(stroke
			(width 0.07112)
			(type default)
		)
		(layer "In6.Cu")
	)
	(gr_line
		(start 339.595206 -419.567614)
		(end 339.731096 -419.703504)
		(stroke
			(width 0.07112)
			(type default)
		)
		(layer "In6.Cu")
	)
	(gr_line
		(start 339.649816 -426.985176)
		(end 339.649816 -427.289976)
		(stroke
			(width 0.07112)
			(type default)
		)
		(layer "In6.Cu")
	)
	(gr_line
		(start 339.649816 -426.421804)
		(end 339.649816 -426.089826)
		(stroke
			(width 0.07112)
			(type default)
		)
		(layer "In6.Cu")
	)
	(gr_line
		(start 339.731096 -420.130224)
		(end 339.595206 -420.266114)
		(stroke
			(width 0.07112)
			(type default)
		)
		(layer "In6.Cu")
	)
	(gr_line
		(start 339.731096 -419.703504)
		(end 339.731096 -420.130224)
		(stroke
			(width 0.07112)
			(type default)
		)
		(layer "In6.Cu")
	)
	(gr_line
		(start 339.75294 -424.097196)
		(end 339.56244 -424.071288)
		(stroke
			(width 0.07112)
			(type default)
		)
		(layer "In6.Cu")
	)
	(gr_line
		(start 339.884766 -418.412168)
		(end 339.593936 -418.702998)
		(stroke
			(width 0.07112)
			(type default)
		)
		(layer "In6.Cu")
	)
	(gr_line
		(start 339.918802 -397.156432)
		(end 339.971126 -397.208756)
		(stroke
			(width 0.07112)
			(type default)
		)
		(layer "In6.Cu")
	)
	(gr_line
		(start 339.948012 -423.42181)
		(end 339.389974 -423.846498)
		(stroke
			(width 0.07112)
			(type default)
		)
		(layer "In6.Cu")
	)
	(gr_line
		(start 339.971126 -397.388588)
		(end 339.824568 -397.535146)
		(stroke
			(width 0.07112)
			(type default)
		)
		(layer "In6.Cu")
	)
	(gr_line
		(start 339.971126 -397.208756)
		(end 339.971126 -397.388588)
		(stroke
			(width 0.07112)
			(type default)
		)
		(layer "In6.Cu")
	)
	(gr_line
		(start 340.092792 -423.838624)
		(end 339.75294 -424.097196)
		(stroke
			(width 0.07112)
			(type default)
		)
		(layer "In6.Cu")
	)
	(gr_line
		(start 340.1187 -423.64787)
		(end 340.092792 -423.838624)
		(stroke
			(width 0.07112)
			(type default)
		)
		(layer "In6.Cu")
	)
	(gr_line
		(start 340.204044 -397.734536)
		(end 340.025736 -397.734536)
		(stroke
			(width 0.07112)
			(type default)
		)
		(layer "In6.Cu")
	)
	(gr_line
		(start 340.318852 -397.849344)
		(end 340.204044 -397.734536)
		(stroke
			(width 0.07112)
			(type default)
		)
		(layer "In6.Cu")
	)
	(gr_line
		(start 340.650576 -423.41419)
		(end 340.460076 -423.388282)
		(stroke
			(width 0.07112)
			(type default)
		)
		(layer "In6.Cu")
	)
	(gr_line
		(start 340.845648 -422.738804)
		(end 340.28761 -423.163746)
		(stroke
			(width 0.07112)
			(type default)
		)
		(layer "In6.Cu")
	)
	(gr_line
		(start 340.989412 -424.87215)
		(end 340.989158 -424.871896)
		(stroke
			(width 0.07112)
			(type default)
		)
		(layer "In6.Cu")
	)
	(gr_line
		(start 340.990428 -423.155618)
		(end 340.650576 -423.41419)
		(stroke
			(width 0.07112)
			(type default)
		)
		(layer "In6.Cu")
	)
	(gr_line
		(start 341.016336 -422.964864)
		(end 340.990428 -423.155618)
		(stroke
			(width 0.07112)
			(type default)
		)
		(layer "In6.Cu")
	)
	(gr_line
		(start 341.118698 -397.156432)
		(end 341.171022 -397.208756)
		(stroke
			(width 0.07112)
			(type default)
		)
		(layer "In6.Cu")
	)
	(gr_line
		(start 341.171022 -397.388588)
		(end 341.024464 -397.535146)
		(stroke
			(width 0.07112)
			(type default)
		)
		(layer "In6.Cu")
	)
	(gr_line
		(start 341.171022 -397.208756)
		(end 341.171022 -397.388588)
		(stroke
			(width 0.07112)
			(type default)
		)
		(layer "In6.Cu")
	)
	(gr_line
		(start 341.40394 -397.734536)
		(end 341.225632 -397.734536)
		(stroke
			(width 0.07112)
			(type default)
		)
		(layer "In6.Cu")
	)
	(gr_line
		(start 341.507572 -427.830742)
		(end 341.649812 -427.972982)
		(stroke
			(width 0.07112)
			(type default)
		)
		(layer "In6.Cu")
	)
	(gr_line
		(start 341.507572 -427.548802)
		(end 341.649812 -427.406562)
		(stroke
			(width 0.07112)
			(type default)
		)
		(layer "In6.Cu")
	)
	(gr_line
		(start 341.518748 -397.849344)
		(end 341.40394 -397.734536)
		(stroke
			(width 0.07112)
			(type default)
		)
		(layer "In6.Cu")
	)
	(gr_line
		(start 341.548212 -422.731184)
		(end 341.357712 -422.705276)
		(stroke
			(width 0.07112)
			(type default)
		)
		(layer "In6.Cu")
	)
	(gr_line
		(start 341.649812 -427.972982)
		(end 341.649812 -428.28972)
		(stroke
			(width 0.07112)
			(type default)
		)
		(layer "In6.Cu")
	)
	(gr_line
		(start 341.649812 -427.406562)
		(end 341.649812 -427.089824)
		(stroke
			(width 0.07112)
			(type default)
		)
		(layer "In6.Cu")
	)
	(gr_line
		(start 341.743284 -422.055798)
		(end 341.185246 -422.48074)
		(stroke
			(width 0.07112)
			(type default)
		)
		(layer "In6.Cu")
	)
	(gr_line
		(start 341.888064 -422.472612)
		(end 341.548212 -422.731184)
		(stroke
			(width 0.07112)
			(type default)
		)
		(layer "In6.Cu")
	)
	(gr_line
		(start 341.913972 -422.281858)
		(end 341.888064 -422.472612)
		(stroke
			(width 0.07112)
			(type default)
		)
		(layer "In6.Cu")
	)
	(gr_line
		(start 342.011508 -423.810938)
		(end 341.819992 -423.792142)
		(stroke
			(width 0.07112)
			(type default)
		)
		(layer "In6.Cu")
	)
	(gr_line
		(start 342.084406 -418.412168)
		(end 342.375236 -418.702998)
		(stroke
			(width 0.07112)
			(type default)
		)
		(layer "In6.Cu")
	)
	(gr_line
		(start 342.181688 -423.128694)
		(end 341.639398 -423.573702)
		(stroke
			(width 0.07112)
			(type default)
		)
		(layer "In6.Cu")
	)
	(gr_line
		(start 342.318848 -397.156432)
		(end 342.365584 -397.203168)
		(stroke
			(width 0.07112)
			(type default)
		)
		(layer "In6.Cu")
	)
	(gr_line
		(start 342.341454 -423.53992)
		(end 342.011508 -423.810938)
		(stroke
			(width 0.07112)
			(type default)
		)
		(layer "In6.Cu")
	)
	(gr_line
		(start 342.36025 -423.348404)
		(end 342.341454 -423.53992)
		(stroke
			(width 0.07112)
			(type default)
		)
		(layer "In6.Cu")
	)
	(gr_line
		(start 342.365584 -397.44015)
		(end 342.270588 -397.535146)
		(stroke
			(width 0.07112)
			(type default)
		)
		(layer "In6.Cu")
	)
	(gr_line
		(start 342.365584 -397.203168)
		(end 342.365584 -397.44015)
		(stroke
			(width 0.07112)
			(type default)
		)
		(layer "In6.Cu")
	)
	(gr_line
		(start 342.375236 -419.50386)
		(end 342.375236 -420.2049)
		(stroke
			(width 0.07112)
			(type default)
		)
		(layer "In6.Cu")
	)
	(gr_line
		(start 342.375236 -415.09569)
		(end 342.084406 -415.38652)
		(stroke
			(width 0.07112)
			(type default)
		)
		(layer "In6.Cu")
	)
	(gr_line
		(start 342.60409 -397.734536)
		(end 342.471756 -397.734536)
		(stroke
			(width 0.07112)
			(type default)
		)
		(layer "In6.Cu")
	)
	(gr_line
		(start 342.657176 -415.09569)
		(end 342.948006 -415.38652)
		(stroke
			(width 0.07112)
			(type default)
		)
		(layer "In6.Cu")
	)
	(gr_line
		(start 342.658446 -419.50513)
		(end 342.794336 -419.64102)
		(stroke
			(width 0.07112)
			(type default)
		)
		(layer "In6.Cu")
	)
	(gr_line
		(start 342.718898 -397.849344)
		(end 342.60409 -397.734536)
		(stroke
			(width 0.07112)
			(type default)
		)
		(layer "In6.Cu")
	)
	(gr_line
		(start 342.794336 -420.06774)
		(end 342.658446 -420.20363)
		(stroke
			(width 0.07112)
			(type default)
		)
		(layer "In6.Cu")
	)
	(gr_line
		(start 342.794336 -419.64102)
		(end 342.794336 -420.06774)
		(stroke
			(width 0.07112)
			(type default)
		)
		(layer "In6.Cu")
	)
	(gr_line
		(start 342.883236 -423.09542)
		(end 342.69172 -423.076624)
		(stroke
			(width 0.07112)
			(type default)
		)
		(layer "In6.Cu")
	)
	(gr_line
		(start 342.948006 -418.412168)
		(end 342.657176 -418.702998)
		(stroke
			(width 0.07112)
			(type default)
		)
		(layer "In6.Cu")
	)
	(gr_line
		(start 343.053416 -422.41343)
		(end 342.511126 -422.858184)
		(stroke
			(width 0.07112)
			(type default)
		)
		(layer "In6.Cu")
	)
	(gr_line
		(start 343.213182 -422.824402)
		(end 342.883236 -423.09542)
		(stroke
			(width 0.07112)
			(type default)
		)
		(layer "In6.Cu")
	)
	(gr_line
		(start 343.231978 -422.63314)
		(end 343.213182 -422.824402)
		(stroke
			(width 0.07112)
			(type default)
		)
		(layer "In6.Cu")
	)
	(gr_line
		(start 343.383108 -422.142666)
		(end 343.382854 -422.14292)
		(stroke
			(width 0.07112)
			(type default)
		)
		(layer "In6.Cu")
	)
	(gr_line
		(start 343.493344 -426.865796)
		(end 343.522808 -426.865796)
		(stroke
			(width 0.07112)
			(type default)
		)
		(layer "In6.Cu")
	)
	(gr_line
		(start 343.494614 -426.582586)
		(end 343.649808 -426.427392)
		(stroke
			(width 0.07112)
			(type default)
		)
		(layer "In6.Cu")
	)
	(gr_line
		(start 343.518744 -397.156432)
		(end 343.571068 -397.208756)
		(stroke
			(width 0.07112)
			(type default)
		)
		(layer "In6.Cu")
	)
	(gr_line
		(start 343.522808 -426.865796)
		(end 343.649808 -426.992796)
		(stroke
			(width 0.07112)
			(type default)
		)
		(layer "In6.Cu")
	)
	(gr_line
		(start 343.571068 -397.388588)
		(end 343.42451 -397.535146)
		(stroke
			(width 0.07112)
			(type default)
		)
		(layer "In6.Cu")
	)
	(gr_line
		(start 343.571068 -397.208756)
		(end 343.571068 -397.388588)
		(stroke
			(width 0.07112)
			(type default)
		)
		(layer "In6.Cu")
	)
	(gr_line
		(start 343.649808 -426.992796)
		(end 343.649808 -427.289976)
		(stroke
			(width 0.07112)
			(type default)
		)
		(layer "In6.Cu")
	)
	(gr_line
		(start 343.649808 -426.427392)
		(end 343.649808 -426.089826)
		(stroke
			(width 0.07112)
			(type default)
		)
		(layer "In6.Cu")
	)
	(gr_line
		(start 343.687654 -411.617668)
		(end 343.497154 -411.589474)
		(stroke
			(width 0.07112)
			(type default)
		)
		(layer "In6.Cu")
	)
	(gr_line
		(start 343.803986 -397.734536)
		(end 343.625678 -397.734536)
		(stroke
			(width 0.07112)
			(type default)
		)
		(layer "In6.Cu")
	)
	(gr_line
		(start 343.891108 -410.944822)
		(end 343.327482 -411.362652)
		(stroke
			(width 0.07112)
			(type default)
		)
		(layer "In6.Cu")
	)
	(gr_line
		(start 343.918794 -397.849344)
		(end 343.803986 -397.734536)
		(stroke
			(width 0.07112)
			(type default)
		)
		(layer "In6.Cu")
	)
	(gr_line
		(start 344.030554 -411.36316)
		(end 343.687654 -411.617668)
		(stroke
			(width 0.07112)
			(type default)
		)
		(layer "In6.Cu")
	)
	(gr_line
		(start 344.058748 -411.172914)
		(end 344.030554 -411.36316)
		(stroke
			(width 0.07112)
			(type default)
		)
		(layer "In6.Cu")
	)
	(gr_line
		(start 344.284046 -423.610024)
		(end 344.12682 -423.526204)
		(stroke
			(width 0.07112)
			(type default)
		)
		(layer "In6.Cu")
	)
	(gr_line
		(start 344.370152 -296.252646)
		(end 344.370152 -296.281094)
		(stroke
			(width 0.05715)
			(type default)
		)
		(layer "In6.Cu")
	)
	(gr_line
		(start 344.415872 -296.206926)
		(end 344.370152 -296.252646)
		(stroke
			(width 0.05715)
			(type default)
		)
		(layer "In6.Cu")
	)
	(gr_line
		(start 344.593418 -410.945838)
		(end 344.403172 -410.917644)
		(stroke
			(width 0.07112)
			(type default)
		)
		(layer "In6.Cu")
	)
	(gr_line
		(start 344.606372 -296.206926)
		(end 344.652092 -296.252646)
		(stroke
			(width 0.05715)
			(type default)
		)
		(layer "In6.Cu")
	)
	(gr_arc
		(start 344.648282 -286.692848)
		(mid 344.654978 -286.697723)
		(end 344.661744 -286.7025)
		(stroke
			(width 0.05715)
			(type default)
		)
		(layer "In6.Cu")
	)
	(gr_line
		(start 344.652092 -296.252646)
		(end 344.652092 -296.281094)
		(stroke
			(width 0.05715)
			(type default)
		)
		(layer "In6.Cu")
	)
	(gr_line
		(start 344.661744 -286.7025)
		(end 344.664284 -286.704024)
		(stroke
			(width 0.05715)
			(type default)
		)
		(layer "In6.Cu")
	)
	(gr_arc
		(start 344.678254 -422.044622)
		(mid 344.678 -422.044622)
		(end 344.677746 -422.044622)
		(stroke
			(width 0.07112)
			(type default)
		)
		(layer "In6.Cu")
	)
	(gr_line
		(start 344.692478 -423.486072)
		(end 344.284046 -423.610024)
		(stroke
			(width 0.07112)
			(type default)
		)
		(layer "In6.Cu")
	)
	(gr_line
		(start 344.695526 -423.057574)
		(end 344.043762 -423.25544)
		(stroke
			(width 0.07112)
			(type default)
		)
		(layer "In6.Cu")
	)
	(gr_line
		(start 344.698066 -285.74873)
		(end 344.697558 -285.749238)
		(stroke
			(width 0.05715)
			(type default)
		)
		(layer "In6.Cu")
	)
	(gr_line
		(start 344.698574 -285.748476)
		(end 344.698066 -285.74873)
		(stroke
			(width 0.05715)
			(type default)
		)
		(layer "In6.Cu")
	)
	(gr_line
		(start 344.718894 -397.156432)
		(end 344.771218 -397.208756)
		(stroke
			(width 0.07112)
			(type default)
		)
		(layer "In6.Cu")
	)
	(gr_line
		(start 344.771218 -397.388588)
		(end 344.62466 -397.535146)
		(stroke
			(width 0.07112)
			(type default)
		)
		(layer "In6.Cu")
	)
	(gr_line
		(start 344.771218 -397.208756)
		(end 344.771218 -397.388588)
		(stroke
			(width 0.07112)
			(type default)
		)
		(layer "In6.Cu")
	)
	(gr_line
		(start 344.776552 -423.3291)
		(end 344.692478 -423.486072)
		(stroke
			(width 0.07112)
			(type default)
		)
		(layer "In6.Cu")
	)
	(gr_line
		(start 344.793824 -285.91383)
		(end 344.7923 -285.914592)
		(stroke
			(width 0.05715)
			(type default)
		)
		(layer "In6.Cu")
	)
	(gr_line
		(start 344.797126 -410.272992)
		(end 344.233754 -410.690822)
		(stroke
			(width 0.07112)
			(type default)
		)
		(layer "In6.Cu")
	)
	(gr_line
		(start 344.83294 -422.014904)
		(end 344.831924 -422.015158)
		(stroke
			(width 0.07112)
			(type default)
		)
		(layer "In6.Cu")
	)
	(gr_line
		(start 344.936572 -410.69133)
		(end 344.593418 -410.945838)
		(stroke
			(width 0.07112)
			(type default)
		)
		(layer "In6.Cu")
	)
	(gr_line
		(start 344.964766 -410.501338)
		(end 344.936572 -410.69133)
		(stroke
			(width 0.07112)
			(type default)
		)
		(layer "In6.Cu")
	)
	(gr_line
		(start 345.003882 -397.734536)
		(end 344.825828 -397.734536)
		(stroke
			(width 0.07112)
			(type default)
		)
		(layer "In6.Cu")
	)
	(gr_line
		(start 345.11869 -397.849344)
		(end 345.003882 -397.734536)
		(stroke
			(width 0.07112)
			(type default)
		)
		(layer "In6.Cu")
	)
	(gr_line
		(start 345.147646 -418.412168)
		(end 345.438476 -418.702998)
		(stroke
			(width 0.07112)
			(type default)
		)
		(layer "In6.Cu")
	)
	(gr_line
		(start 345.310206 -296.252646)
		(end 345.310206 -296.281094)
		(stroke
			(width 0.05715)
			(type default)
		)
		(layer "In6.Cu")
	)
	(gr_line
		(start 345.355926 -296.206926)
		(end 345.310206 -296.252646)
		(stroke
			(width 0.05715)
			(type default)
		)
		(layer "In6.Cu")
	)
	(gr_line
		(start 345.438476 -419.495478)
		(end 345.438476 -420.196518)
		(stroke
			(width 0.07112)
			(type default)
		)
		(layer "In6.Cu")
	)
	(gr_line
		(start 345.438476 -415.09569)
		(end 345.147646 -415.38652)
		(stroke
			(width 0.07112)
			(type default)
		)
		(layer "In6.Cu")
	)
	(gr_line
		(start 345.507564 -427.830742)
		(end 345.649804 -427.972982)
		(stroke
			(width 0.07112)
			(type default)
		)
		(layer "In6.Cu")
	)
	(gr_line
		(start 345.507564 -427.548802)
		(end 345.649804 -427.406562)
		(stroke
			(width 0.07112)
			(type default)
		)
		(layer "In6.Cu")
	)
	(gr_line
		(start 345.546426 -296.206926)
		(end 345.592146 -296.252646)
		(stroke
			(width 0.05715)
			(type default)
		)
		(layer "In6.Cu")
	)
	(gr_line
		(start 345.592146 -296.252646)
		(end 345.592146 -296.281094)
		(stroke
			(width 0.05715)
			(type default)
		)
		(layer "In6.Cu")
	)
	(gr_arc
		(start 345.599004 -285.77159)
		(mid 345.595055 -285.774367)
		(end 345.59113 -285.777178)
		(stroke
			(width 0.05715)
			(type default)
		)
		(layer "In6.Cu")
	)
	(gr_line
		(start 345.60764 -285.76651)
		(end 345.599004 -285.77159)
		(stroke
			(width 0.05715)
			(type default)
		)
		(layer "In6.Cu")
	)
	(gr_line
		(start 345.612212 -285.763716)
		(end 345.609418 -285.765494)
		(stroke
			(width 0.05715)
			(type default)
		)
		(layer "In6.Cu")
	)
	(gr_line
		(start 345.62161 -285.758128)
		(end 345.620594 -285.75889)
		(stroke
			(width 0.05715)
			(type default)
		)
		(layer "In6.Cu")
	)
	(gr_line
		(start 345.624404 -285.756604)
		(end 345.623134 -285.757366)
		(stroke
			(width 0.05715)
			(type default)
		)
		(layer "In6.Cu")
	)
	(gr_line
		(start 345.625166 -285.756096)
		(end 345.624404 -285.756604)
		(stroke
			(width 0.05715)
			(type default)
		)
		(layer "In6.Cu")
	)
	(gr_line
		(start 345.626436 -285.755334)
		(end 345.625166 -285.756096)
		(stroke
			(width 0.05715)
			(type default)
		)
		(layer "In6.Cu")
	)
	(gr_line
		(start 345.627198 -285.754826)
		(end 345.626436 -285.755334)
		(stroke
			(width 0.05715)
			(type default)
		)
		(layer "In6.Cu")
	)
	(gr_line
		(start 345.628976 -285.754064)
		(end 345.62796 -285.754572)
		(stroke
			(width 0.05715)
			(type default)
		)
		(layer "In6.Cu")
	)
	(gr_line
		(start 345.633294 -285.751524)
		(end 345.632278 -285.752032)
		(stroke
			(width 0.05715)
			(type default)
		)
		(layer "In6.Cu")
	)
	(gr_line
		(start 345.633802 -285.75127)
		(end 345.633294 -285.751524)
		(stroke
			(width 0.05715)
			(type default)
		)
		(layer "In6.Cu")
	)
	(gr_line
		(start 345.633802 -284.131258)
		(end 345.630754 -284.133036)
		(stroke
			(width 0.05715)
			(type default)
		)
		(layer "In6.Cu")
	)
	(gr_line
		(start 345.637104 -285.749238)
		(end 345.63558 -285.750254)
		(stroke
			(width 0.05715)
			(type default)
		)
		(layer "In6.Cu")
	)
	(gr_line
		(start 345.637104 -284.129226)
		(end 345.63558 -284.130242)
		(stroke
			(width 0.05715)
			(type default)
		)
		(layer "In6.Cu")
	)
	(gr_line
		(start 345.637866 -285.74873)
		(end 345.637104 -285.749238)
		(stroke
			(width 0.05715)
			(type default)
		)
		(layer "In6.Cu")
	)
	(gr_line
		(start 345.63812 -284.128718)
		(end 345.637104 -284.129226)
		(stroke
			(width 0.05715)
			(type default)
		)
		(layer "In6.Cu")
	)
	(gr_line
		(start 345.649804 -427.972982)
		(end 345.649804 -428.28972)
		(stroke
			(width 0.07112)
			(type default)
		)
		(layer "In6.Cu")
	)
	(gr_line
		(start 345.649804 -427.406562)
		(end 345.649804 -427.089824)
		(stroke
			(width 0.07112)
			(type default)
		)
		(layer "In6.Cu")
	)
	(gr_line
		(start 345.720416 -415.09569)
		(end 346.011246 -415.38652)
		(stroke
			(width 0.07112)
			(type default)
		)
		(layer "In6.Cu")
	)
	(gr_line
		(start 345.721686 -419.496748)
		(end 345.857576 -419.632638)
		(stroke
			(width 0.07112)
			(type default)
		)
		(layer "In6.Cu")
	)
	(gr_line
		(start 345.722702 -285.920434)
		(end 345.721178 -285.921196)
		(stroke
			(width 0.05715)
			(type default)
		)
		(layer "In6.Cu")
	)
	(gr_line
		(start 345.725242 -285.91891)
		(end 345.724734 -285.919164)
		(stroke
			(width 0.05715)
			(type default)
		)
		(layer "In6.Cu")
	)
	(gr_line
		(start 345.725242 -284.298644)
		(end 345.723718 -284.299406)
		(stroke
			(width 0.05715)
			(type default)
		)
		(layer "In6.Cu")
	)
	(gr_line
		(start 345.727782 -285.917386)
		(end 345.726766 -285.917894)
		(stroke
			(width 0.05715)
			(type default)
		)
		(layer "In6.Cu")
	)
	(gr_line
		(start 345.729306 -285.91637)
		(end 345.727782 -285.917386)
		(stroke
			(width 0.05715)
			(type default)
		)
		(layer "In6.Cu")
	)
	(gr_line
		(start 345.730576 -285.915608)
		(end 345.729306 -285.91637)
		(stroke
			(width 0.05715)
			(type default)
		)
		(layer "In6.Cu")
	)
	(gr_line
		(start 345.730576 -284.295596)
		(end 345.729814 -284.296104)
		(stroke
			(width 0.05715)
			(type default)
		)
		(layer "In6.Cu")
	)
	(gr_line
		(start 345.73337 -285.914084)
		(end 345.732862 -285.914338)
		(stroke
			(width 0.05715)
			(type default)
		)
		(layer "In6.Cu")
	)
	(gr_line
		(start 345.733878 -285.91383)
		(end 345.73337 -285.914084)
		(stroke
			(width 0.05715)
			(type default)
		)
		(layer "In6.Cu")
	)
	(gr_line
		(start 345.734132 -284.293564)
		(end 345.73337 -284.294072)
		(stroke
			(width 0.05715)
			(type default)
		)
		(layer "In6.Cu")
	)
	(gr_line
		(start 345.736672 -284.29204)
		(end 345.73591 -284.292548)
		(stroke
			(width 0.05715)
			(type default)
		)
		(layer "In6.Cu")
	)
	(gr_line
		(start 345.737434 -284.291532)
		(end 345.736672 -284.29204)
		(stroke
			(width 0.05715)
			(type default)
		)
		(layer "In6.Cu")
	)
	(gr_line
		(start 345.857576 -420.059358)
		(end 345.721686 -420.195248)
		(stroke
			(width 0.07112)
			(type default)
		)
		(layer "In6.Cu")
	)
	(gr_line
		(start 345.857576 -419.632638)
		(end 345.857576 -420.059358)
		(stroke
			(width 0.07112)
			(type default)
		)
		(layer "In6.Cu")
	)
	(gr_line
		(start 345.91879 -397.156432)
		(end 345.971114 -397.208756)
		(stroke
			(width 0.07112)
			(type default)
		)
		(layer "In6.Cu")
	)
	(gr_line
		(start 345.921076 -284.616144)
		(end 346.219018 -284.616144)
		(stroke
			(width 0.05715)
			(type default)
		)
		(layer "In6.Cu")
	)
	(gr_line
		(start 345.921076 -282.996132)
		(end 346.219018 -282.996132)
		(stroke
			(width 0.05715)
			(type default)
		)
		(layer "In6.Cu")
	)
	(gr_line
		(start 345.921076 -281.37612)
		(end 346.219018 -281.37612)
		(stroke
			(width 0.05715)
			(type default)
		)
		(layer "In6.Cu")
	)
	(gr_line
		(start 345.971114 -397.388588)
		(end 345.824556 -397.535146)
		(stroke
			(width 0.07112)
			(type default)
		)
		(layer "In6.Cu")
	)
	(gr_line
		(start 345.971114 -397.208756)
		(end 345.971114 -397.388588)
		(stroke
			(width 0.07112)
			(type default)
		)
		(layer "In6.Cu")
	)
	(gr_line
		(start 346.011246 -418.412168)
		(end 345.720416 -418.702998)
		(stroke
			(width 0.07112)
			(type default)
		)
		(layer "In6.Cu")
	)
	(gr_line
		(start 346.041472 -407.408126)
		(end 345.849194 -407.408126)
		(stroke
			(width 0.07112)
			(type default)
		)
		(layer "In6.Cu")
	)
	(gr_line
		(start 346.144342 -406.712674)
		(end 345.64828 -407.208736)
		(stroke
			(width 0.07112)
			(type default)
		)
		(layer "In6.Cu")
	)
	(gr_line
		(start 346.168472 -409.509468)
		(end 345.976956 -409.528264)
		(stroke
			(width 0.07112)
			(type default)
		)
		(layer "In6.Cu")
	)
	(gr_line
		(start 346.202254 -408.807412)
		(end 345.7575 -409.349448)
		(stroke
			(width 0.07112)
			(type default)
		)
		(layer "In6.Cu")
	)
	(gr_line
		(start 346.204032 -397.734536)
		(end 346.025724 -397.734536)
		(stroke
			(width 0.07112)
			(type default)
		)
		(layer "In6.Cu")
	)
	(gr_line
		(start 346.219018 -284.616144)
		(end 346.28836 -284.685486)
		(stroke
			(width 0.05715)
			(type default)
		)
		(layer "In6.Cu")
	)
	(gr_line
		(start 346.219018 -282.996132)
		(end 346.28836 -283.065474)
		(stroke
			(width 0.05715)
			(type default)
		)
		(layer "In6.Cu")
	)
	(gr_line
		(start 346.219018 -281.37612)
		(end 346.301822 -281.458924)
		(stroke
			(width 0.05715)
			(type default)
		)
		(layer "In6.Cu")
	)
	(gr_line
		(start 346.25026 -296.252646)
		(end 346.25026 -296.281094)
		(stroke
			(width 0.05715)
			(type default)
		)
		(layer "In6.Cu")
	)
	(gr_line
		(start 346.29598 -296.206926)
		(end 346.25026 -296.252646)
		(stroke
			(width 0.05715)
			(type default)
		)
		(layer "In6.Cu")
	)
	(gr_arc
		(start 346.301822 -281.458924)
		(mid 346.303613 -281.470246)
		(end 346.305632 -281.48153)
		(stroke
			(width 0.05715)
			(type default)
		)
		(layer "In6.Cu")
	)
	(gr_line
		(start 346.31884 -397.849344)
		(end 346.204032 -397.734536)
		(stroke
			(width 0.07112)
			(type default)
		)
		(layer "In6.Cu")
	)
	(gr_line
		(start 346.343478 -407.10612)
		(end 346.041472 -407.408126)
		(stroke
			(width 0.07112)
			(type default)
		)
		(layer "In6.Cu")
	)
	(gr_line
		(start 346.343732 -406.913588)
		(end 346.343478 -407.10612)
		(stroke
			(width 0.07112)
			(type default)
		)
		(layer "In6.Cu")
	)
	(gr_line
		(start 346.420694 -408.988006)
		(end 346.43949 -409.179522)
		(stroke
			(width 0.07112)
			(type default)
		)
		(layer "In6.Cu")
	)
	(gr_line
		(start 346.43949 -409.179522)
		(end 346.168472 -409.509468)
		(stroke
			(width 0.07112)
			(type default)
		)
		(layer "In6.Cu")
	)
	(gr_line
		(start 346.441522 -402.696426)
		(end 346.441522 -403.397466)
		(stroke
			(width 0.07112)
			(type default)
		)
		(layer "In6.Cu")
	)
	(gr_arc
		(start 346.476574 -284.721554)
		(mid 346.478595 -284.710271)
		(end 346.480384 -284.698948)
		(stroke
			(width 0.05715)
			(type default)
		)
		(layer "In6.Cu")
	)
	(gr_arc
		(start 346.476574 -283.101796)
		(mid 346.478595 -283.090385)
		(end 346.480384 -283.078936)
		(stroke
			(width 0.05715)
			(type default)
		)
		(layer "In6.Cu")
	)
	(gr_line
		(start 346.48648 -296.206926)
		(end 346.5322 -296.252646)
		(stroke
			(width 0.05715)
			(type default)
		)
		(layer "In6.Cu")
	)
	(gr_arc
		(start 346.52839 -286.693102)
		(mid 346.533702 -286.696943)
		(end 346.539058 -286.700722)
		(stroke
			(width 0.05715)
			(type default)
		)
		(layer "In6.Cu")
	)
	(gr_line
		(start 346.5322 -296.252646)
		(end 346.5322 -296.281094)
		(stroke
			(width 0.05715)
			(type default)
		)
		(layer "In6.Cu")
	)
	(gr_line
		(start 346.539058 -286.700722)
		(end 346.541852 -286.702246)
		(stroke
			(width 0.05715)
			(type default)
		)
		(layer "In6.Cu")
	)
	(gr_line
		(start 346.541852 -286.702246)
		(end 346.546932 -286.705294)
		(stroke
			(width 0.05715)
			(type default)
		)
		(layer "In6.Cu")
	)
	(gr_line
		(start 346.546932 -286.705294)
		(end 346.547948 -286.705548)
		(stroke
			(width 0.05715)
			(type default)
		)
		(layer "In6.Cu")
	)
	(gr_line
		(start 346.563188 -284.616144)
		(end 346.480384 -284.698948)
		(stroke
			(width 0.05715)
			(type default)
		)
		(layer "In6.Cu")
	)
	(gr_line
		(start 346.563188 -282.996132)
		(end 346.480384 -283.078936)
		(stroke
			(width 0.05715)
			(type default)
		)
		(layer "In6.Cu")
	)
	(gr_line
		(start 346.563188 -281.37612)
		(end 346.493846 -281.445462)
		(stroke
			(width 0.05715)
			(type default)
		)
		(layer "In6.Cu")
	)
	(gr_line
		(start 346.578936 -281.864054)
		(end 346.578936 -281.8638)
		(stroke
			(width 0.05715)
			(type default)
		)
		(layer "In6.Cu")
	)
	(gr_line
		(start 346.580968 -281.864816)
		(end 346.581222 -281.864816)
		(stroke
			(width 0.05715)
			(type default)
		)
		(layer "In6.Cu")
	)
	(gr_line
		(start 346.674186 -285.913576)
		(end 346.673678 -285.91383)
		(stroke
			(width 0.05715)
			(type default)
		)
		(layer "In6.Cu")
	)
	(gr_arc
		(start 346.677234 -281.69997)
		(mid 346.675965 -281.699206)
		(end 346.674694 -281.698446)
		(stroke
			(width 0.05715)
			(type default)
		)
		(layer "In6.Cu")
	)
	(gr_line
		(start 346.724732 -402.697696)
		(end 346.860622 -402.833586)
		(stroke
			(width 0.07112)
			(type default)
		)
		(layer "In6.Cu")
	)
	(gr_arc
		(start 346.76588 -295.139364)
		(mid 346.76587 -295.142666)
		(end 346.76588 -295.145968)
		(stroke
			(width 0.05715)
			(type default)
		)
		(layer "In6.Cu")
	)
	(gr_line
		(start 346.76588 -288.672524)
		(end 346.76588 -288.66592)
		(stroke
			(width 0.05715)
			(type default)
		)
		(layer "In6.Cu")
	)
	(gr_line
		(start 346.773754 -285.36265)
		(end 346.774008 -285.361634)
		(stroke
			(width 0.05715)
			(type default)
		)
		(layer "In6.Cu")
	)
	(gr_line
		(start 346.839286 -406.610566)
		(end 346.646754 -406.610566)
		(stroke
			(width 0.07112)
			(type default)
		)
		(layer "In6.Cu")
	)
	(gr_line
		(start 346.84843 -422.404286)
		(end 346.84843 -422.40454)
		(stroke
			(width 0.07112)
			(type default)
		)
		(layer "In6.Cu")
	)
	(gr_line
		(start 346.860622 -403.260306)
		(end 346.724732 -403.396196)
		(stroke
			(width 0.07112)
			(type default)
		)
		(layer "In6.Cu")
	)
	(gr_line
		(start 346.860622 -402.833586)
		(end 346.860622 -403.260306)
		(stroke
			(width 0.07112)
			(type default)
		)
		(layer "In6.Cu")
	)
	(gr_line
		(start 346.86113 -284.616144)
		(end 346.563188 -284.616144)
		(stroke
			(width 0.05715)
			(type default)
		)
		(layer "In6.Cu")
	)
	(gr_line
		(start 346.86113 -282.996132)
		(end 346.563188 -282.996132)
		(stroke
			(width 0.05715)
			(type default)
		)
		(layer "In6.Cu")
	)
	(gr_line
		(start 346.86113 -281.37612)
		(end 346.563188 -281.37612)
		(stroke
			(width 0.05715)
			(type default)
		)
		(layer "In6.Cu")
	)
	(gr_line
		(start 346.941902 -405.915114)
		(end 346.44584 -406.411176)
		(stroke
			(width 0.07112)
			(type default)
		)
		(layer "In6.Cu")
	)
	(gr_line
		(start 346.95638 -285.442406)
		(end 346.95638 -285.443168)
		(stroke
			(width 0.05715)
			(type default)
		)
		(layer "In6.Cu")
	)
	(gr_line
		(start 346.95638 -285.442152)
		(end 346.95638 -285.442406)
		(stroke
			(width 0.05715)
			(type default)
		)
		(layer "In6.Cu")
	)
	(gr_arc
		(start 346.95638 -285.442152)
		(mid 346.95638 -285.441898)
		(end 346.95638 -285.441644)
		(stroke
			(width 0.05715)
			(type default)
		)
		(layer "In6.Cu")
	)
	(gr_arc
		(start 346.980256 -284.984444)
		(mid 346.977199 -284.987483)
		(end 346.97416 -284.99054)
		(stroke
			(width 0.05715)
			(type default)
		)
		(layer "In6.Cu")
	)
	(gr_arc
		(start 346.988384 -284.97784)
		(mid 346.984304 -284.981122)
		(end 346.980256 -284.984444)
		(stroke
			(width 0.05715)
			(type default)
		)
		(layer "In6.Cu")
	)
	(gr_arc
		(start 347.01099 -284.960314)
		(mid 347.006529 -284.963594)
		(end 347.0021 -284.966918)
		(stroke
			(width 0.05715)
			(type default)
		)
		(layer "In6.Cu")
	)
	(gr_arc
		(start 347.011752 -283.339794)
		(mid 347.003574 -283.345438)
		(end 346.995496 -283.351224)
		(stroke
			(width 0.05715)
			(type default)
		)
		(layer "In6.Cu")
	)
	(gr_line
		(start 347.016832 -283.336746)
		(end 347.011752 -283.339794)
		(stroke
			(width 0.05715)
			(type default)
		)
		(layer "In6.Cu")
	)
	(gr_line
		(start 347.017848 -283.336238)
		(end 347.016832 -283.336746)
		(stroke
			(width 0.05715)
			(type default)
		)
		(layer "In6.Cu")
	)
	(gr_line
		(start 347.020896 -284.954472)
		(end 347.011752 -284.959806)
		(stroke
			(width 0.05715)
			(type default)
		)
		(layer "In6.Cu")
	)
	(gr_line
		(start 347.048074 -284.938724)
		(end 347.04655 -284.939486)
		(stroke
			(width 0.05715)
			(type default)
		)
		(layer "In6.Cu")
	)
	(gr_line
		(start 347.048582 -294.658288)
		(end 347.048074 -294.658542)
		(stroke
			(width 0.05715)
			(type default)
		)
		(layer "In6.Cu")
	)
	(gr_line
		(start 347.060012 -283.311854)
		(end 347.058996 -283.312362)
		(stroke
			(width 0.05715)
			(type default)
		)
		(layer "In6.Cu")
	)
	(gr_line
		(start 347.060774 -283.311346)
		(end 347.060012 -283.311854)
		(stroke
			(width 0.05715)
			(type default)
		)
		(layer "In6.Cu")
	)
	(gr_line
		(start 347.06306 -283.310076)
		(end 347.060774 -283.311346)
		(stroke
			(width 0.05715)
			(type default)
		)
		(layer "In6.Cu")
	)
	(gr_line
		(start 347.101414 -422.765728)
		(end 346.931742 -422.67505)
		(stroke
			(width 0.07112)
			(type default)
		)
		(layer "In6.Cu")
	)
	(gr_line
		(start 347.118686 -397.156432)
		(end 347.17101 -397.208756)
		(stroke
			(width 0.07112)
			(type default)
		)
		(layer "In6.Cu")
	)
	(gr_line
		(start 347.141038 -406.30856)
		(end 346.839286 -406.610566)
		(stroke
			(width 0.07112)
			(type default)
		)
		(layer "In6.Cu")
	)
	(gr_line
		(start 347.141292 -406.116282)
		(end 347.141038 -406.30856)
		(stroke
			(width 0.07112)
			(type default)
		)
		(layer "In6.Cu")
	)
	(gr_line
		(start 347.143578 -285.10357)
		(end 347.142562 -285.104078)
		(stroke
			(width 0.05715)
			(type default)
		)
		(layer "In6.Cu")
	)
	(gr_line
		(start 347.144086 -285.10357)
		(end 347.143578 -285.10357)
		(stroke
			(width 0.05715)
			(type default)
		)
		(layer "In6.Cu")
	)
	(gr_line
		(start 347.17101 -397.388588)
		(end 347.024452 -397.535146)
		(stroke
			(width 0.07112)
			(type default)
		)
		(layer "In6.Cu")
	)
	(gr_line
		(start 347.17101 -397.208756)
		(end 347.17101 -397.388588)
		(stroke
			(width 0.07112)
			(type default)
		)
		(layer "In6.Cu")
	)
	(gr_line
		(start 347.190568 -296.252646)
		(end 347.190568 -296.281094)
		(stroke
			(width 0.05715)
			(type default)
		)
		(layer "In6.Cu")
	)
	(gr_line
		(start 347.236288 -296.206926)
		(end 347.190568 -296.252646)
		(stroke
			(width 0.05715)
			(type default)
		)
		(layer "In6.Cu")
	)
	(gr_line
		(start 347.272864 -409.869894)
		(end 347.273118 -409.87091)
		(stroke
			(width 0.07112)
			(type default)
		)
		(layer "In6.Cu")
	)
	(gr_line
		(start 347.273118 -409.87091)
		(end 346.92463 -410.340048)
		(stroke
			(width 0.07112)
			(type default)
		)
		(layer "In6.Cu")
	)
	(gr_line
		(start 347.342714 -409.775914)
		(end 347.272864 -409.869894)
		(stroke
			(width 0.07112)
			(type default)
		)
		(layer "In6.Cu")
	)
	(gr_line
		(start 347.342968 -410.480002)
		(end 347.152722 -410.507942)
		(stroke
			(width 0.07112)
			(type default)
		)
		(layer "In6.Cu")
	)
	(gr_line
		(start 347.403928 -397.734536)
		(end 347.22562 -397.734536)
		(stroke
			(width 0.07112)
			(type default)
		)
		(layer "In6.Cu")
	)
	(gr_line
		(start 347.407484 -422.234614)
		(end 346.84843 -422.404286)
		(stroke
			(width 0.07112)
			(type default)
		)
		(layer "In6.Cu")
	)
	(gr_line
		(start 347.407738 -422.23436)
		(end 347.407484 -422.234614)
		(stroke
			(width 0.07112)
			(type default)
		)
		(layer "In6.Cu")
	)
	(gr_line
		(start 347.426788 -296.206926)
		(end 347.472508 -296.252646)
		(stroke
			(width 0.05715)
			(type default)
		)
		(layer "In6.Cu")
	)
	(gr_line
		(start 347.472508 -296.252646)
		(end 347.472508 -296.281094)
		(stroke
			(width 0.05715)
			(type default)
		)
		(layer "In6.Cu")
	)
	(gr_line
		(start 347.486224 -423.824654)
		(end 347.326204 -423.717466)
		(stroke
			(width 0.07112)
			(type default)
		)
		(layer "In6.Cu")
	)
	(gr_line
		(start 347.5101 -422.641776)
		(end 347.101414 -422.765728)
		(stroke
			(width 0.07112)
			(type default)
		)
		(layer "In6.Cu")
	)
	(gr_line
		(start 347.518736 -397.849344)
		(end 347.403928 -397.734536)
		(stroke
			(width 0.07112)
			(type default)
		)
		(layer "In6.Cu")
	)
	(gr_line
		(start 347.519752 -422.200324)
		(end 347.407738 -422.23436)
		(stroke
			(width 0.07112)
			(type default)
		)
		(layer "In6.Cu")
	)
	(gr_line
		(start 347.569282 -409.94584)
		(end 347.59773 -410.137102)
		(stroke
			(width 0.07112)
			(type default)
		)
		(layer "In6.Cu")
	)
	(gr_line
		(start 347.582236 -402.567648)
		(end 347.582236 -403.268688)
		(stroke
			(width 0.07112)
			(type default)
		)
		(layer "In6.Cu")
	)
	(gr_line
		(start 347.59773 -410.137102)
		(end 347.342968 -410.480002)
		(stroke
			(width 0.07112)
			(type default)
		)
		(layer "In6.Cu")
	)
	(gr_line
		(start 347.600778 -422.47185)
		(end 347.5101 -422.641776)
		(stroke
			(width 0.07112)
			(type default)
		)
		(layer "In6.Cu")
	)
	(gr_line
		(start 347.636592 -405.813006)
		(end 347.444568 -405.813006)
		(stroke
			(width 0.07112)
			(type default)
		)
		(layer "In6.Cu")
	)
	(gr_line
		(start 347.665548 -409.341066)
		(end 347.595952 -409.434538)
		(stroke
			(width 0.07112)
			(type default)
		)
		(layer "In6.Cu")
	)
	(gr_line
		(start 347.665802 -409.340812)
		(end 347.665548 -409.341066)
		(stroke
			(width 0.07112)
			(type default)
		)
		(layer "In6.Cu")
	)
	(gr_line
		(start 347.666818 -409.340812)
		(end 347.665802 -409.340812)
		(stroke
			(width 0.07112)
			(type default)
		)
		(layer "In6.Cu")
	)
	(gr_line
		(start 347.705934 -295.066974)
		(end 347.70568 -295.067228)
		(stroke
			(width 0.05715)
			(type default)
		)
		(layer "In6.Cu")
	)
	(gr_line
		(start 347.739208 -405.117808)
		(end 347.2434 -405.613616)
		(stroke
			(width 0.07112)
			(type default)
		)
		(layer "In6.Cu")
	)
	(gr_line
		(start 347.865446 -402.568918)
		(end 348.001336 -402.704808)
		(stroke
			(width 0.07112)
			(type default)
		)
		(layer "In6.Cu")
	)
	(gr_line
		(start 347.896434 -295.145968)
		(end 347.89618 -295.146222)
		(stroke
			(width 0.05715)
			(type default)
		)
		(layer "In6.Cu")
	)
	(gr_line
		(start 347.90507 -423.741342)
		(end 347.486224 -423.824654)
		(stroke
			(width 0.07112)
			(type default)
		)
		(layer "In6.Cu")
	)
	(gr_line
		(start 347.938598 -405.511)
		(end 347.636592 -405.813006)
		(stroke
			(width 0.07112)
			(type default)
		)
		(layer "In6.Cu")
	)
	(gr_line
		(start 347.938598 -405.318976)
		(end 347.938598 -405.511)
		(stroke
			(width 0.07112)
			(type default)
		)
		(layer "In6.Cu")
	)
	(gr_line
		(start 347.957902 -423.303446)
		(end 347.27007 -423.440098)
		(stroke
			(width 0.07112)
			(type default)
		)
		(layer "In6.Cu")
	)
	(gr_line
		(start 347.98254 -293.041832)
		(end 347.980254 -293.043102)
		(stroke
			(width 0.05715)
			(type default)
		)
		(layer "In6.Cu")
	)
	(gr_line
		(start 347.98254 -291.42182)
		(end 347.980254 -291.42309)
		(stroke
			(width 0.05715)
			(type default)
		)
		(layer "In6.Cu")
	)
	(gr_line
		(start 347.98254 -289.801808)
		(end 347.980254 -289.803078)
		(stroke
			(width 0.05715)
			(type default)
		)
		(layer "In6.Cu")
	)
	(gr_line
		(start 347.98254 -284.942026)
		(end 347.980254 -284.943296)
		(stroke
			(width 0.05715)
			(type default)
		)
		(layer "In6.Cu")
	)
	(gr_line
		(start 347.983302 -293.041324)
		(end 347.98254 -293.041832)
		(stroke
			(width 0.05715)
			(type default)
		)
		(layer "In6.Cu")
	)
	(gr_line
		(start 347.983302 -291.421312)
		(end 347.98254 -291.42182)
		(stroke
			(width 0.05715)
			(type default)
		)
		(layer "In6.Cu")
	)
	(gr_line
		(start 347.983302 -289.8013)
		(end 347.98254 -289.801808)
		(stroke
			(width 0.05715)
			(type default)
		)
		(layer "In6.Cu")
	)
	(gr_line
		(start 347.983302 -284.941518)
		(end 347.98254 -284.942026)
		(stroke
			(width 0.05715)
			(type default)
		)
		(layer "In6.Cu")
	)
	(gr_line
		(start 347.98381 -294.661082)
		(end 347.981778 -294.662352)
		(stroke
			(width 0.05715)
			(type default)
		)
		(layer "In6.Cu")
	)
	(gr_line
		(start 347.98381 -293.04107)
		(end 347.983302 -293.041324)
		(stroke
			(width 0.05715)
			(type default)
		)
		(layer "In6.Cu")
	)
	(gr_line
		(start 347.98381 -291.421058)
		(end 347.983302 -291.421312)
		(stroke
			(width 0.05715)
			(type default)
		)
		(layer "In6.Cu")
	)
	(gr_line
		(start 347.98381 -289.801046)
		(end 347.983302 -289.8013)
		(stroke
			(width 0.05715)
			(type default)
		)
		(layer "In6.Cu")
	)
	(gr_line
		(start 347.98381 -284.941264)
		(end 347.983302 -284.941518)
		(stroke
			(width 0.05715)
			(type default)
		)
		(layer "In6.Cu")
	)
	(gr_line
		(start 347.987112 -293.039038)
		(end 347.98508 -293.040308)
		(stroke
			(width 0.05715)
			(type default)
		)
		(layer "In6.Cu")
	)
	(gr_line
		(start 347.987112 -291.419026)
		(end 347.98508 -291.420296)
		(stroke
			(width 0.05715)
			(type default)
		)
		(layer "In6.Cu")
	)
	(gr_line
		(start 347.987112 -289.799014)
		(end 347.98508 -289.800284)
		(stroke
			(width 0.05715)
			(type default)
		)
		(layer "In6.Cu")
	)
	(gr_line
		(start 347.987112 -284.939232)
		(end 347.98508 -284.940502)
		(stroke
			(width 0.05715)
			(type default)
		)
		(layer "In6.Cu")
	)
	(gr_line
		(start 347.987874 -293.03853)
		(end 347.987112 -293.039038)
		(stroke
			(width 0.05715)
			(type default)
		)
		(layer "In6.Cu")
	)
	(gr_line
		(start 347.987874 -291.418518)
		(end 347.987112 -291.419026)
		(stroke
			(width 0.05715)
			(type default)
		)
		(layer "In6.Cu")
	)
	(gr_line
		(start 347.987874 -289.798506)
		(end 347.987112 -289.799014)
		(stroke
			(width 0.05715)
			(type default)
		)
		(layer "In6.Cu")
	)
	(gr_line
		(start 347.987874 -284.938724)
		(end 347.987112 -284.939232)
		(stroke
			(width 0.05715)
			(type default)
		)
		(layer "In6.Cu")
	)
	(gr_line
		(start 347.994986 -294.017192)
		(end 347.995748 -294.0177)
		(stroke
			(width 0.05715)
			(type default)
		)
		(layer "In6.Cu")
	)
	(gr_line
		(start 347.994986 -292.39718)
		(end 347.995748 -292.397688)
		(stroke
			(width 0.05715)
			(type default)
		)
		(layer "In6.Cu")
	)
	(gr_line
		(start 347.994986 -290.777168)
		(end 347.995748 -290.777676)
		(stroke
			(width 0.05715)
			(type default)
		)
		(layer "In6.Cu")
	)
	(gr_line
		(start 348.001336 -403.131528)
		(end 347.865446 -403.267418)
		(stroke
			(width 0.07112)
			(type default)
		)
		(layer "In6.Cu")
	)
	(gr_line
		(start 348.001336 -402.704808)
		(end 348.001336 -403.131528)
		(stroke
			(width 0.07112)
			(type default)
		)
		(layer "In6.Cu")
	)
	(gr_line
		(start 348.01175 -423.581322)
		(end 347.90507 -423.741342)
		(stroke
			(width 0.07112)
			(type default)
		)
		(layer "In6.Cu")
	)
	(gr_line
		(start 348.01556 -409.574238)
		(end 347.824044 -409.602686)
		(stroke
			(width 0.07112)
			(type default)
		)
		(layer "In6.Cu")
	)
	(gr_line
		(start 348.01556 -408.87142)
		(end 347.666818 -409.340812)
		(stroke
			(width 0.07112)
			(type default)
		)
		(layer "In6.Cu")
	)
	(gr_line
		(start 348.07779 -294.826944)
		(end 348.07652 -294.827706)
		(stroke
			(width 0.05715)
			(type default)
		)
		(layer "In6.Cu")
	)
	(gr_line
		(start 348.078044 -293.206932)
		(end 348.075758 -293.208456)
		(stroke
			(width 0.05715)
			(type default)
		)
		(layer "In6.Cu")
	)
	(gr_line
		(start 348.078044 -291.58692)
		(end 348.075758 -291.588444)
		(stroke
			(width 0.05715)
			(type default)
		)
		(layer "In6.Cu")
	)
	(gr_line
		(start 348.078044 -289.966908)
		(end 348.075758 -289.968432)
		(stroke
			(width 0.05715)
			(type default)
		)
		(layer "In6.Cu")
	)
	(gr_line
		(start 348.078044 -285.107126)
		(end 348.075758 -285.10865)
		(stroke
			(width 0.05715)
			(type default)
		)
		(layer "In6.Cu")
	)
	(gr_line
		(start 348.079822 -294.825928)
		(end 348.07779 -294.826944)
		(stroke
			(width 0.05715)
			(type default)
		)
		(layer "In6.Cu")
	)
	(gr_line
		(start 348.080584 -293.205408)
		(end 348.079822 -293.205916)
		(stroke
			(width 0.05715)
			(type default)
		)
		(layer "In6.Cu")
	)
	(gr_line
		(start 348.080584 -291.585396)
		(end 348.079822 -291.585904)
		(stroke
			(width 0.05715)
			(type default)
		)
		(layer "In6.Cu")
	)
	(gr_line
		(start 348.080584 -289.965384)
		(end 348.079822 -289.965892)
		(stroke
			(width 0.05715)
			(type default)
		)
		(layer "In6.Cu")
	)
	(gr_line
		(start 348.080584 -285.105602)
		(end 348.079822 -285.10611)
		(stroke
			(width 0.05715)
			(type default)
		)
		(layer "In6.Cu")
	)
	(gr_line
		(start 348.081092 -294.825166)
		(end 348.079822 -294.825928)
		(stroke
			(width 0.05715)
			(type default)
		)
		(layer "In6.Cu")
	)
	(gr_line
		(start 348.082108 -293.204646)
		(end 348.080584 -293.205408)
		(stroke
			(width 0.05715)
			(type default)
		)
		(layer "In6.Cu")
	)
	(gr_line
		(start 348.082108 -291.584634)
		(end 348.080584 -291.585396)
		(stroke
			(width 0.05715)
			(type default)
		)
		(layer "In6.Cu")
	)
	(gr_line
		(start 348.082108 -289.964622)
		(end 348.080584 -289.965384)
		(stroke
			(width 0.05715)
			(type default)
		)
		(layer "In6.Cu")
	)
	(gr_line
		(start 348.082108 -285.10484)
		(end 348.080584 -285.105602)
		(stroke
			(width 0.05715)
			(type default)
		)
		(layer "In6.Cu")
	)
	(gr_line
		(start 348.082616 -293.847774)
		(end 348.08541 -293.849298)
		(stroke
			(width 0.05715)
			(type default)
		)
		(layer "In6.Cu")
	)
	(gr_line
		(start 348.082616 -292.227762)
		(end 348.08541 -292.229286)
		(stroke
			(width 0.05715)
			(type default)
		)
		(layer "In6.Cu")
	)
	(gr_line
		(start 348.082616 -290.60775)
		(end 348.08541 -290.609274)
		(stroke
			(width 0.05715)
			(type default)
		)
		(layer "In6.Cu")
	)
	(gr_line
		(start 348.083378 -293.203884)
		(end 348.082108 -293.204646)
		(stroke
			(width 0.05715)
			(type default)
		)
		(layer "In6.Cu")
	)
	(gr_line
		(start 348.083378 -291.583872)
		(end 348.082108 -291.584634)
		(stroke
			(width 0.05715)
			(type default)
		)
		(layer "In6.Cu")
	)
	(gr_line
		(start 348.083378 -289.96386)
		(end 348.082108 -289.964622)
		(stroke
			(width 0.05715)
			(type default)
		)
		(layer "In6.Cu")
	)
	(gr_line
		(start 348.083378 -285.104078)
		(end 348.082108 -285.10484)
		(stroke
			(width 0.05715)
			(type default)
		)
		(layer "In6.Cu")
	)
	(gr_line
		(start 348.083886 -293.20363)
		(end 348.083378 -293.203884)
		(stroke
			(width 0.05715)
			(type default)
		)
		(layer "In6.Cu")
	)
	(gr_line
		(start 348.083886 -291.583618)
		(end 348.083378 -291.583872)
		(stroke
			(width 0.05715)
			(type default)
		)
		(layer "In6.Cu")
	)
	(gr_line
		(start 348.083886 -289.963606)
		(end 348.083378 -289.96386)
		(stroke
			(width 0.05715)
			(type default)
		)
		(layer "In6.Cu")
	)
	(gr_line
		(start 348.083886 -285.103824)
		(end 348.083378 -285.104078)
		(stroke
			(width 0.05715)
			(type default)
		)
		(layer "In6.Cu")
	)
	(gr_line
		(start 348.08668 -293.85006)
		(end 348.087442 -293.850568)
		(stroke
			(width 0.05715)
			(type default)
		)
		(layer "In6.Cu")
	)
	(gr_line
		(start 348.08668 -292.230048)
		(end 348.087442 -292.230556)
		(stroke
			(width 0.05715)
			(type default)
		)
		(layer "In6.Cu")
	)
	(gr_line
		(start 348.08668 -290.610036)
		(end 348.087442 -290.610544)
		(stroke
			(width 0.05715)
			(type default)
		)
		(layer "In6.Cu")
	)
	(gr_line
		(start 348.090236 -293.852092)
		(end 348.091252 -293.852854)
		(stroke
			(width 0.05715)
			(type default)
		)
		(layer "In6.Cu")
	)
	(gr_line
		(start 348.090236 -292.23208)
		(end 348.091252 -292.232842)
		(stroke
			(width 0.05715)
			(type default)
		)
		(layer "In6.Cu")
	)
	(gr_line
		(start 348.090236 -290.612068)
		(end 348.091252 -290.61283)
		(stroke
			(width 0.05715)
			(type default)
		)
		(layer "In6.Cu")
	)
	(gr_line
		(start 348.125288 -296.252646)
		(end 348.125288 -296.281094)
		(stroke
			(width 0.05715)
			(type default)
		)
		(layer "In6.Cu")
	)
	(gr_line
		(start 348.171008 -296.206926)
		(end 348.125288 -296.252646)
		(stroke
			(width 0.05715)
			(type default)
		)
		(layer "In6.Cu")
	)
	(gr_line
		(start 348.210886 -418.412168)
		(end 348.501716 -418.702998)
		(stroke
			(width 0.07112)
			(type default)
		)
		(layer "In6.Cu")
	)
	(gr_line
		(start 348.242128 -409.041346)
		(end 348.270068 -409.231592)
		(stroke
			(width 0.07112)
			(type default)
		)
		(layer "In6.Cu")
	)
	(gr_line
		(start 348.270068 -409.231592)
		(end 348.01556 -409.574238)
		(stroke
			(width 0.07112)
			(type default)
		)
		(layer "In6.Cu")
	)
	(gr_line
		(start 348.318836 -397.156432)
		(end 348.37116 -397.208756)
		(stroke
			(width 0.07112)
			(type default)
		)
		(layer "In6.Cu")
	)
	(gr_line
		(start 348.361508 -296.206926)
		(end 348.407228 -296.252646)
		(stroke
			(width 0.05715)
			(type default)
		)
		(layer "In6.Cu")
	)
	(gr_line
		(start 348.37116 -397.388588)
		(end 348.224602 -397.535146)
		(stroke
			(width 0.07112)
			(type default)
		)
		(layer "In6.Cu")
	)
	(gr_line
		(start 348.37116 -397.208756)
		(end 348.37116 -397.388588)
		(stroke
			(width 0.07112)
			(type default)
		)
		(layer "In6.Cu")
	)
	(gr_line
		(start 348.407228 -296.252646)
		(end 348.407228 -296.281094)
		(stroke
			(width 0.05715)
			(type default)
		)
		(layer "In6.Cu")
	)
	(gr_line
		(start 348.501716 -420.146988)
		(end 348.501716 -420.709852)
		(stroke
			(width 0.07112)
			(type default)
		)
		(layer "In6.Cu")
	)
	(gr_line
		(start 348.501716 -419.299644)
		(end 348.501716 -419.862508)
		(stroke
			(width 0.07112)
			(type default)
		)
		(layer "In6.Cu")
	)
	(gr_line
		(start 348.501716 -415.09569)
		(end 348.210886 -415.38652)
		(stroke
			(width 0.07112)
			(type default)
		)
		(layer "In6.Cu")
	)
	(gr_line
		(start 348.556072 -285.91256)
		(end 348.554548 -285.913322)
		(stroke
			(width 0.05715)
			(type default)
		)
		(layer "In6.Cu")
	)
	(gr_line
		(start 348.604078 -397.734536)
		(end 348.42577 -397.734536)
		(stroke
			(width 0.07112)
			(type default)
		)
		(layer "In6.Cu")
	)
	(gr_line
		(start 348.688152 -408.668728)
		(end 348.497906 -408.696922)
		(stroke
			(width 0.07112)
			(type default)
		)
		(layer "In6.Cu")
	)
	(gr_line
		(start 348.688152 -407.96591)
		(end 348.269814 -408.529028)
		(stroke
			(width 0.07112)
			(type default)
		)
		(layer "In6.Cu")
	)
	(gr_line
		(start 348.718886 -397.849344)
		(end 348.604078 -397.734536)
		(stroke
			(width 0.07112)
			(type default)
		)
		(layer "In6.Cu")
	)
	(gr_line
		(start 348.741238 -286.236156)
		(end 349.03918 -286.236156)
		(stroke
			(width 0.05715)
			(type default)
		)
		(layer "In6.Cu")
	)
	(gr_line
		(start 348.741238 -284.616144)
		(end 349.03918 -284.616144)
		(stroke
			(width 0.05715)
			(type default)
		)
		(layer "In6.Cu")
	)
	(gr_line
		(start 348.741238 -282.996132)
		(end 349.03918 -282.996132)
		(stroke
			(width 0.05715)
			(type default)
		)
		(layer "In6.Cu")
	)
	(gr_line
		(start 348.741238 -281.37612)
		(end 349.03918 -281.37612)
		(stroke
			(width 0.05715)
			(type default)
		)
		(layer "In6.Cu")
	)
	(gr_line
		(start 348.783656 -415.09569)
		(end 349.074486 -415.38652)
		(stroke
			(width 0.07112)
			(type default)
		)
		(layer "In6.Cu")
	)
	(gr_line
		(start 348.784926 -420.148258)
		(end 348.922848 -420.28618)
		(stroke
			(width 0.07112)
			(type default)
		)
		(layer "In6.Cu")
	)
	(gr_line
		(start 348.784926 -419.300914)
		(end 348.922848 -419.438836)
		(stroke
			(width 0.07112)
			(type default)
		)
		(layer "In6.Cu")
	)
	(gr_arc
		(start 348.881192 -293.984934)
		(mid 348.885117 -293.987745)
		(end 348.889066 -293.990522)
		(stroke
			(width 0.05715)
			(type default)
		)
		(layer "In6.Cu")
	)
	(gr_arc
		(start 348.881192 -292.364922)
		(mid 348.885117 -292.367733)
		(end 348.889066 -292.37051)
		(stroke
			(width 0.05715)
			(type default)
		)
		(layer "In6.Cu")
	)
	(gr_arc
		(start 348.881192 -290.74491)
		(mid 348.885117 -290.747721)
		(end 348.889066 -290.750498)
		(stroke
			(width 0.05715)
			(type default)
		)
		(layer "In6.Cu")
	)
	(gr_arc
		(start 348.881192 -289.124898)
		(mid 348.885117 -289.127709)
		(end 348.889066 -289.130486)
		(stroke
			(width 0.05715)
			(type default)
		)
		(layer "In6.Cu")
	)
	(gr_arc
		(start 348.881192 -287.504886)
		(mid 348.886378 -287.508599)
		(end 348.891606 -287.512252)
		(stroke
			(width 0.05715)
			(type default)
		)
		(layer "In6.Cu")
	)
	(gr_line
		(start 348.889066 -293.990522)
		(end 348.895924 -293.994586)
		(stroke
			(width 0.05715)
			(type default)
		)
		(layer "In6.Cu")
	)
	(gr_line
		(start 348.889066 -292.37051)
		(end 348.895924 -292.374574)
		(stroke
			(width 0.05715)
			(type default)
		)
		(layer "In6.Cu")
	)
	(gr_line
		(start 348.889066 -290.750498)
		(end 348.895924 -290.754562)
		(stroke
			(width 0.05715)
			(type default)
		)
		(layer "In6.Cu")
	)
	(gr_line
		(start 348.889066 -289.130486)
		(end 348.895924 -289.13455)
		(stroke
			(width 0.05715)
			(type default)
		)
		(layer "In6.Cu")
	)
	(gr_line
		(start 348.891606 -287.512252)
		(end 348.895924 -287.514792)
		(stroke
			(width 0.05715)
			(type default)
		)
		(layer "In6.Cu")
	)
	(gr_line
		(start 348.895924 -293.994586)
		(end 348.896686 -293.995094)
		(stroke
			(width 0.05715)
			(type default)
		)
		(layer "In6.Cu")
	)
	(gr_line
		(start 348.895924 -292.374574)
		(end 348.896686 -292.375082)
		(stroke
			(width 0.05715)
			(type default)
		)
		(layer "In6.Cu")
	)
	(gr_line
		(start 348.895924 -290.754562)
		(end 348.896686 -290.75507)
		(stroke
			(width 0.05715)
			(type default)
		)
		(layer "In6.Cu")
	)
	(gr_line
		(start 348.895924 -289.13455)
		(end 348.896686 -289.135058)
		(stroke
			(width 0.05715)
			(type default)
		)
		(layer "In6.Cu")
	)
	(gr_line
		(start 348.895924 -287.514792)
		(end 348.896686 -287.5153)
		(stroke
			(width 0.05715)
			(type default)
		)
		(layer "In6.Cu")
	)
	(gr_line
		(start 348.896686 -293.995094)
		(end 348.897448 -293.995602)
		(stroke
			(width 0.05715)
			(type default)
		)
		(layer "In6.Cu")
	)
	(gr_line
		(start 348.896686 -292.375082)
		(end 348.897448 -292.37559)
		(stroke
			(width 0.05715)
			(type default)
		)
		(layer "In6.Cu")
	)
	(gr_line
		(start 348.896686 -290.75507)
		(end 348.897448 -290.755578)
		(stroke
			(width 0.05715)
			(type default)
		)
		(layer "In6.Cu")
	)
	(gr_line
		(start 348.896686 -289.135058)
		(end 348.897448 -289.135566)
		(stroke
			(width 0.05715)
			(type default)
		)
		(layer "In6.Cu")
	)
	(gr_line
		(start 348.896686 -287.5153)
		(end 348.897448 -287.515808)
		(stroke
			(width 0.05715)
			(type default)
		)
		(layer "In6.Cu")
	)
	(gr_line
		(start 348.91472 -408.135836)
		(end 348.94266 -408.326082)
		(stroke
			(width 0.07112)
			(type default)
		)
		(layer "In6.Cu")
	)
	(gr_line
		(start 348.922848 -420.57066)
		(end 348.784926 -420.708582)
		(stroke
			(width 0.07112)
			(type default)
		)
		(layer "In6.Cu")
	)
	(gr_line
		(start 348.922848 -420.28618)
		(end 348.922848 -420.57066)
		(stroke
			(width 0.07112)
			(type default)
		)
		(layer "In6.Cu")
	)
	(gr_line
		(start 348.922848 -419.723316)
		(end 348.784926 -419.861238)
		(stroke
			(width 0.07112)
			(type default)
		)
		(layer "In6.Cu")
	)
	(gr_line
		(start 348.922848 -419.438836)
		(end 348.922848 -419.723316)
		(stroke
			(width 0.07112)
			(type default)
		)
		(layer "In6.Cu")
	)
	(gr_line
		(start 348.928182 -293.03853)
		(end 348.927166 -293.039038)
		(stroke
			(width 0.05715)
			(type default)
		)
		(layer "In6.Cu")
	)
	(gr_line
		(start 348.928182 -291.418518)
		(end 348.927166 -291.419026)
		(stroke
			(width 0.05715)
			(type default)
		)
		(layer "In6.Cu")
	)
	(gr_line
		(start 348.928182 -289.798506)
		(end 348.927166 -289.799014)
		(stroke
			(width 0.05715)
			(type default)
		)
		(layer "In6.Cu")
	)
	(gr_line
		(start 348.928436 -294.013636)
		(end 348.928944 -294.01389)
		(stroke
			(width 0.05715)
			(type default)
		)
		(layer "In6.Cu")
	)
	(gr_line
		(start 348.928436 -287.533842)
		(end 348.92996 -287.534604)
		(stroke
			(width 0.05715)
			(type default)
		)
		(layer "In6.Cu")
	)
	(gr_line
		(start 348.928944 -294.01389)
		(end 348.931738 -294.015414)
		(stroke
			(width 0.05715)
			(type default)
		)
		(layer "In6.Cu")
	)
	(gr_line
		(start 348.930468 -284.936946)
		(end 348.927674 -284.93847)
		(stroke
			(width 0.05715)
			(type default)
		)
		(layer "In6.Cu")
	)
	(gr_line
		(start 348.930468 -283.316934)
		(end 348.927674 -283.318458)
		(stroke
			(width 0.05715)
			(type default)
		)
		(layer "In6.Cu")
	)
	(gr_line
		(start 348.94266 -408.326082)
		(end 348.688152 -408.668728)
		(stroke
			(width 0.07112)
			(type default)
		)
		(layer "In6.Cu")
	)
	(gr_line
		(start 349.022416 -285.103824)
		(end 349.022924 -285.10357)
		(stroke
			(width 0.05715)
			(type default)
		)
		(layer "In6.Cu")
	)
	(gr_line
		(start 349.022416 -283.483812)
		(end 349.022924 -283.483558)
		(stroke
			(width 0.05715)
			(type default)
		)
		(layer "In6.Cu")
	)
	(gr_line
		(start 349.023432 -293.203884)
		(end 349.022162 -293.204646)
		(stroke
			(width 0.05715)
			(type default)
		)
		(layer "In6.Cu")
	)
	(gr_line
		(start 349.023432 -291.583872)
		(end 349.022162 -291.584634)
		(stroke
			(width 0.05715)
			(type default)
		)
		(layer "In6.Cu")
	)
	(gr_line
		(start 349.023432 -289.96386)
		(end 349.022162 -289.964622)
		(stroke
			(width 0.05715)
			(type default)
		)
		(layer "In6.Cu")
	)
	(gr_line
		(start 349.023432 -287.36798)
		(end 349.024194 -287.368488)
		(stroke
			(width 0.05715)
			(type default)
		)
		(layer "In6.Cu")
	)
	(gr_line
		(start 349.02394 -293.20363)
		(end 349.023432 -293.203884)
		(stroke
			(width 0.05715)
			(type default)
		)
		(layer "In6.Cu")
	)
	(gr_line
		(start 349.02394 -291.583618)
		(end 349.023432 -291.583872)
		(stroke
			(width 0.05715)
			(type default)
		)
		(layer "In6.Cu")
	)
	(gr_line
		(start 349.02394 -289.963606)
		(end 349.023432 -289.96386)
		(stroke
			(width 0.05715)
			(type default)
		)
		(layer "In6.Cu")
	)
	(gr_line
		(start 349.02394 -287.368742)
		(end 349.024702 -287.36925)
		(stroke
			(width 0.05715)
			(type default)
		)
		(layer "In6.Cu")
	)
	(gr_line
		(start 349.02394 -285.103062)
		(end 349.022924 -285.10357)
		(stroke
			(width 0.05715)
			(type default)
		)
		(layer "In6.Cu")
	)
	(gr_line
		(start 349.02394 -283.48305)
		(end 349.022924 -283.483558)
		(stroke
			(width 0.05715)
			(type default)
		)
		(layer "In6.Cu")
	)
	(gr_line
		(start 349.024194 -287.368488)
		(end 349.02394 -287.368742)
		(stroke
			(width 0.05715)
			(type default)
		)
		(layer "In6.Cu")
	)
	(gr_line
		(start 349.028004 -285.100776)
		(end 349.02394 -285.103062)
		(stroke
			(width 0.05715)
			(type default)
		)
		(layer "In6.Cu")
	)
	(gr_arc
		(start 349.028004 -285.100776)
		(mid 349.028766 -285.100396)
		(end 349.029528 -285.100014)
		(stroke
			(width 0.05715)
			(type default)
		)
		(layer "In6.Cu")
	)
	(gr_line
		(start 349.028004 -283.480764)
		(end 349.02394 -283.48305)
		(stroke
			(width 0.05715)
			(type default)
		)
		(layer "In6.Cu")
	)
	(gr_arc
		(start 349.028004 -283.480764)
		(mid 349.028766 -283.480384)
		(end 349.029528 -283.480002)
		(stroke
			(width 0.05715)
			(type default)
		)
		(layer "In6.Cu")
	)
	(gr_line
		(start 349.03918 -286.236156)
		(end 349.121984 -286.31896)
		(stroke
			(width 0.05715)
			(type default)
		)
		(layer "In6.Cu")
	)
	(gr_line
		(start 349.03918 -284.616144)
		(end 349.108268 -284.685232)
		(stroke
			(width 0.05715)
			(type default)
		)
		(layer "In6.Cu")
	)
	(gr_line
		(start 349.03918 -282.996132)
		(end 349.108268 -283.06522)
		(stroke
			(width 0.05715)
			(type default)
		)
		(layer "In6.Cu")
	)
	(gr_line
		(start 349.03918 -281.37612)
		(end 349.121984 -281.458924)
		(stroke
			(width 0.05715)
			(type default)
		)
		(layer "In6.Cu")
	)
	(gr_line
		(start 349.050864 -294.808148)
		(end 349.046292 -294.810688)
		(stroke
			(width 0.05715)
			(type default)
		)
		(layer "In6.Cu")
	)
	(gr_line
		(start 349.070422 -296.252646)
		(end 349.070422 -296.281094)
		(stroke
			(width 0.05715)
			(type default)
		)
		(layer "In6.Cu")
	)
	(gr_line
		(start 349.074486 -418.412168)
		(end 348.783656 -418.702998)
		(stroke
			(width 0.07112)
			(type default)
		)
		(layer "In6.Cu")
	)
	(gr_line
		(start 349.078042 -294.790114)
		(end 349.061786 -294.801798)
		(stroke
			(width 0.05715)
			(type default)
		)
		(layer "In6.Cu")
	)
	(gr_line
		(start 349.10903 -284.685994)
		(end 349.109284 -284.685994)
		(stroke
			(width 0.05715)
			(type default)
		)
		(layer "In6.Cu")
	)
	(gr_line
		(start 349.10903 -283.065982)
		(end 349.109284 -283.065982)
		(stroke
			(width 0.05715)
			(type default)
		)
		(layer "In6.Cu")
	)
	(gr_line
		(start 349.116142 -296.206926)
		(end 349.070422 -296.252646)
		(stroke
			(width 0.05715)
			(type default)
		)
		(layer "In6.Cu")
	)
	(gr_arc
		(start 349.121984 -286.31896)
		(mid 349.123775 -286.330282)
		(end 349.125794 -286.341566)
		(stroke
			(width 0.05715)
			(type default)
		)
		(layer "In6.Cu")
	)
	(gr_line
		(start 349.121984 -281.477466)
		(end 349.126048 -281.48153)
		(stroke
			(width 0.05715)
			(type default)
		)
		(layer "In6.Cu")
	)
	(gr_arc
		(start 349.121984 -281.458924)
		(mid 349.121909 -281.468195)
		(end 349.121984 -281.477466)
		(stroke
			(width 0.05715)
			(type default)
		)
		(layer "In6.Cu")
	)
	(gr_arc
		(start 349.296482 -284.721554)
		(mid 349.298502 -284.71027)
		(end 349.300292 -284.698948)
		(stroke
			(width 0.05715)
			(type default)
		)
		(layer "In6.Cu")
	)
	(gr_arc
		(start 349.296482 -283.101542)
		(mid 349.298502 -283.090258)
		(end 349.300292 -283.078936)
		(stroke
			(width 0.05715)
			(type default)
		)
		(layer "In6.Cu")
	)
	(gr_line
		(start 349.306642 -296.206926)
		(end 349.352362 -296.252646)
		(stroke
			(width 0.05715)
			(type default)
		)
		(layer "In6.Cu")
	)
	(gr_line
		(start 349.352362 -296.252646)
		(end 349.352362 -296.281094)
		(stroke
			(width 0.05715)
			(type default)
		)
		(layer "In6.Cu")
	)
	(gr_line
		(start 349.383096 -286.236156)
		(end 349.314008 -286.305244)
		(stroke
			(width 0.05715)
			(type default)
		)
		(layer "In6.Cu")
	)
	(gr_line
		(start 349.383096 -284.616144)
		(end 349.300292 -284.698948)
		(stroke
			(width 0.05715)
			(type default)
		)
		(layer "In6.Cu")
	)
	(gr_line
		(start 349.383096 -282.996132)
		(end 349.300292 -283.078936)
		(stroke
			(width 0.05715)
			(type default)
		)
		(layer "In6.Cu")
	)
	(gr_line
		(start 349.383096 -281.37612)
		(end 349.313246 -281.44597)
		(stroke
			(width 0.05715)
			(type default)
		)
		(layer "In6.Cu")
	)
	(gr_line
		(start 349.427546 -406.969976)
		(end 349.4278 -406.969976)
		(stroke
			(width 0.07112)
			(type default)
		)
		(layer "In6.Cu")
	)
	(gr_line
		(start 349.493586 -281.69997)
		(end 349.498412 -281.702764)
		(stroke
			(width 0.05715)
			(type default)
		)
		(layer "In6.Cu")
	)
	(gr_line
		(start 349.518732 -397.156432)
		(end 349.571056 -397.208756)
		(stroke
			(width 0.07112)
			(type default)
		)
		(layer "In6.Cu")
	)
	(gr_line
		(start 349.571056 -397.388588)
		(end 349.424498 -397.535146)
		(stroke
			(width 0.07112)
			(type default)
		)
		(layer "In6.Cu")
	)
	(gr_line
		(start 349.571056 -397.208756)
		(end 349.571056 -397.388588)
		(stroke
			(width 0.07112)
			(type default)
		)
		(layer "In6.Cu")
	)
	(gr_line
		(start 349.676212 -423.18813)
		(end 349.498412 -423.11447)
		(stroke
			(width 0.07112)
			(type default)
		)
		(layer "In6.Cu")
	)
	(gr_line
		(start 349.681038 -286.236156)
		(end 349.383096 -286.236156)
		(stroke
			(width 0.05715)
			(type default)
		)
		(layer "In6.Cu")
	)
	(gr_line
		(start 349.681038 -284.616144)
		(end 349.383096 -284.616144)
		(stroke
			(width 0.05715)
			(type default)
		)
		(layer "In6.Cu")
	)
	(gr_line
		(start 349.681038 -282.996132)
		(end 349.383096 -282.996132)
		(stroke
			(width 0.05715)
			(type default)
		)
		(layer "In6.Cu")
	)
	(gr_line
		(start 349.681038 -281.37612)
		(end 349.383096 -281.37612)
		(stroke
			(width 0.05715)
			(type default)
		)
		(layer "In6.Cu")
	)
	(gr_line
		(start 349.803974 -397.734536)
		(end 349.625666 -397.734536)
		(stroke
			(width 0.07112)
			(type default)
		)
		(layer "In6.Cu")
	)
	(gr_line
		(start 349.918782 -397.849344)
		(end 349.803974 -397.734536)
		(stroke
			(width 0.07112)
			(type default)
		)
		(layer "In6.Cu")
	)
	(gr_line
		(start 350.015302 -296.252646)
		(end 350.015302 -296.281094)
		(stroke
			(width 0.05715)
			(type default)
		)
		(layer "In6.Cu")
	)
	(gr_line
		(start 350.037146 -422.58488)
		(end 349.389192 -422.853358)
		(stroke
			(width 0.07112)
			(type default)
		)
		(layer "In6.Cu")
	)
	(gr_line
		(start 350.061022 -296.206926)
		(end 350.015302 -296.252646)
		(stroke
			(width 0.05715)
			(type default)
		)
		(layer "In6.Cu")
	)
	(gr_line
		(start 350.070928 -423.024808)
		(end 349.676212 -423.18813)
		(stroke
			(width 0.07112)
			(type default)
		)
		(layer "In6.Cu")
	)
	(gr_line
		(start 350.144588 -422.847008)
		(end 350.070928 -423.024808)
		(stroke
			(width 0.07112)
			(type default)
		)
		(layer "In6.Cu")
	)
	(gr_line
		(start 350.251522 -296.206926)
		(end 350.297242 -296.252646)
		(stroke
			(width 0.05715)
			(type default)
		)
		(layer "In6.Cu")
	)
	(gr_arc
		(start 350.291146 -283.45511)
		(mid 350.295071 -283.457921)
		(end 350.29902 -283.460698)
		(stroke
			(width 0.05715)
			(type default)
		)
		(layer "In6.Cu")
	)
	(gr_line
		(start 350.297242 -296.252646)
		(end 350.297242 -296.281094)
		(stroke
			(width 0.05715)
			(type default)
		)
		(layer "In6.Cu")
	)
	(gr_line
		(start 350.29902 -283.460698)
		(end 350.305878 -283.464762)
		(stroke
			(width 0.05715)
			(type default)
		)
		(layer "In6.Cu")
	)
	(gr_line
		(start 350.305878 -283.464762)
		(end 350.30664 -283.46527)
		(stroke
			(width 0.05715)
			(type default)
		)
		(layer "In6.Cu")
	)
	(gr_line
		(start 350.30664 -283.46527)
		(end 350.307402 -283.465778)
		(stroke
			(width 0.05715)
			(type default)
		)
		(layer "In6.Cu")
	)
	(gr_line
		(start 350.331024 -285.752794)
		(end 350.330516 -285.753048)
		(stroke
			(width 0.05715)
			(type default)
		)
		(layer "In6.Cu")
	)
	(gr_line
		(start 350.331024 -284.132782)
		(end 350.330516 -284.133036)
		(stroke
			(width 0.05715)
			(type default)
		)
		(layer "In6.Cu")
	)
	(gr_line
		(start 350.33712 -285.749238)
		(end 350.335596 -285.750254)
		(stroke
			(width 0.05715)
			(type default)
		)
		(layer "In6.Cu")
	)
	(gr_line
		(start 350.33712 -284.129226)
		(end 350.335596 -284.130242)
		(stroke
			(width 0.05715)
			(type default)
		)
		(layer "In6.Cu")
	)
	(gr_line
		(start 350.337882 -285.74873)
		(end 350.33712 -285.749238)
		(stroke
			(width 0.05715)
			(type default)
		)
		(layer "In6.Cu")
	)
	(gr_line
		(start 350.337882 -284.128718)
		(end 350.33712 -284.129226)
		(stroke
			(width 0.05715)
			(type default)
		)
		(layer "In6.Cu")
	)
	(gr_line
		(start 350.33839 -283.483812)
		(end 350.338898 -283.484066)
		(stroke
			(width 0.05715)
			(type default)
		)
		(layer "In6.Cu")
	)
	(gr_line
		(start 350.338898 -285.104078)
		(end 350.340168 -285.10484)
		(stroke
			(width 0.05715)
			(type default)
		)
		(layer "In6.Cu")
	)
	(gr_line
		(start 350.338898 -283.484066)
		(end 350.341692 -283.48559)
		(stroke
			(width 0.05715)
			(type default)
		)
		(layer "In6.Cu")
	)
	(gr_line
		(start 350.414844 -408.551126)
		(end 350.36506 -408.656536)
		(stroke
			(width 0.07112)
			(type default)
		)
		(layer "In6.Cu")
	)
	(gr_line
		(start 350.417638 -408.55011)
		(end 350.414844 -408.551126)
		(stroke
			(width 0.07112)
			(type default)
		)
		(layer "In6.Cu")
	)
	(gr_line
		(start 350.425258 -285.91891)
		(end 350.423734 -285.919926)
		(stroke
			(width 0.05715)
			(type default)
		)
		(layer "In6.Cu")
	)
	(gr_line
		(start 350.425258 -284.298898)
		(end 350.423734 -284.299914)
		(stroke
			(width 0.05715)
			(type default)
		)
		(layer "In6.Cu")
	)
	(gr_line
		(start 350.433386 -285.914084)
		(end 350.432878 -285.914338)
		(stroke
			(width 0.05715)
			(type default)
		)
		(layer "In6.Cu")
	)
	(gr_line
		(start 350.433386 -284.294072)
		(end 350.432878 -284.294326)
		(stroke
			(width 0.05715)
			(type default)
		)
		(layer "In6.Cu")
	)
	(gr_line
		(start 350.43364 -284.93847)
		(end 350.434148 -284.938724)
		(stroke
			(width 0.05715)
			(type default)
		)
		(layer "In6.Cu")
	)
	(gr_line
		(start 350.433894 -285.91383)
		(end 350.433386 -285.914084)
		(stroke
			(width 0.05715)
			(type default)
		)
		(layer "In6.Cu")
	)
	(gr_line
		(start 350.433894 -284.293818)
		(end 350.433386 -284.294072)
		(stroke
			(width 0.05715)
			(type default)
		)
		(layer "In6.Cu")
	)
	(gr_line
		(start 350.434148 -284.938724)
		(end 350.435164 -284.939232)
		(stroke
			(width 0.05715)
			(type default)
		)
		(layer "In6.Cu")
	)
	(gr_line
		(start 350.434148 -283.318712)
		(end 350.435164 -283.31922)
		(stroke
			(width 0.05715)
			(type default)
		)
		(layer "In6.Cu")
	)
	(gr_line
		(start 350.435164 -283.31922)
		(end 350.436688 -283.320236)
		(stroke
			(width 0.05715)
			(type default)
		)
		(layer "In6.Cu")
	)
	(gr_line
		(start 350.436688 -283.320236)
		(end 350.437704 -283.320744)
		(stroke
			(width 0.05715)
			(type default)
		)
		(layer "In6.Cu")
	)
	(gr_line
		(start 350.437704 -283.320744)
		(end 350.442784 -283.323792)
		(stroke
			(width 0.05715)
			(type default)
		)
		(layer "In6.Cu")
	)
	(gr_line
		(start 350.667574 -408.021536)
		(end 350.417638 -408.55011)
		(stroke
			(width 0.07112)
			(type default)
		)
		(layer "In6.Cu")
	)
	(gr_line
		(start 350.718882 -397.156432)
		(end 350.771206 -397.208756)
		(stroke
			(width 0.07112)
			(type default)
		)
		(layer "In6.Cu")
	)
	(gr_line
		(start 350.771206 -397.388588)
		(end 350.624648 -397.535146)
		(stroke
			(width 0.07112)
			(type default)
		)
		(layer "In6.Cu")
	)
	(gr_line
		(start 350.771206 -397.208756)
		(end 350.771206 -397.388588)
		(stroke
			(width 0.07112)
			(type default)
		)
		(layer "In6.Cu")
	)
	(gr_line
		(start 350.805496 -408.710638)
		(end 350.6216 -408.776678)
		(stroke
			(width 0.07112)
			(type default)
		)
		(layer "In6.Cu")
	)
	(gr_line
		(start 350.923098 -408.143456)
		(end 350.987868 -408.324558)
		(stroke
			(width 0.07112)
			(type default)
		)
		(layer "In6.Cu")
	)
	(gr_line
		(start 350.960182 -296.252646)
		(end 350.960182 -296.281094)
		(stroke
			(width 0.05715)
			(type default)
		)
		(layer "In6.Cu")
	)
	(gr_line
		(start 350.987868 -408.324558)
		(end 350.805496 -408.710638)
		(stroke
			(width 0.07112)
			(type default)
		)
		(layer "In6.Cu")
	)
	(gr_line
		(start 351.00387 -397.734536)
		(end 350.825816 -397.734536)
		(stroke
			(width 0.07112)
			(type default)
		)
		(layer "In6.Cu")
	)
	(gr_line
		(start 351.005902 -296.206926)
		(end 350.960182 -296.252646)
		(stroke
			(width 0.05715)
			(type default)
		)
		(layer "In6.Cu")
	)
	(gr_line
		(start 351.118678 -397.849344)
		(end 351.00387 -397.734536)
		(stroke
			(width 0.07112)
			(type default)
		)
		(layer "In6.Cu")
	)
	(gr_line
		(start 351.149666 -407.001726)
		(end 350.849692 -407.635964)
		(stroke
			(width 0.07112)
			(type default)
		)
		(layer "In6.Cu")
	)
	(gr_line
		(start 351.196402 -296.206926)
		(end 351.242122 -296.252646)
		(stroke
			(width 0.05715)
			(type default)
		)
		(layer "In6.Cu")
	)
	(gr_line
		(start 351.242122 -296.252646)
		(end 351.242122 -296.281094)
		(stroke
			(width 0.05715)
			(type default)
		)
		(layer "In6.Cu")
	)
	(gr_line
		(start 351.274126 -418.412168)
		(end 351.564956 -418.702998)
		(stroke
			(width 0.07112)
			(type default)
		)
		(layer "In6.Cu")
	)
	(gr_line
		(start 351.27819 -285.74873)
		(end 351.277174 -285.749238)
		(stroke
			(width 0.05715)
			(type default)
		)
		(layer "In6.Cu")
	)
	(gr_line
		(start 351.287588 -407.690828)
		(end 351.106486 -407.755852)
		(stroke
			(width 0.07112)
			(type default)
		)
		(layer "In6.Cu")
	)
	(gr_line
		(start 351.37344 -285.914084)
		(end 351.37217 -285.914846)
		(stroke
			(width 0.05715)
			(type default)
		)
		(layer "In6.Cu")
	)
	(gr_line
		(start 351.373948 -285.91383)
		(end 351.37344 -285.914084)
		(stroke
			(width 0.05715)
			(type default)
		)
		(layer "In6.Cu")
	)
	(gr_line
		(start 351.40519 -407.123646)
		(end 351.46996 -407.304748)
		(stroke
			(width 0.07112)
			(type default)
		)
		(layer "In6.Cu")
	)
	(gr_arc
		(start 351.465896 -287.045908)
		(mid 351.465892 -287.048067)
		(end 351.465896 -287.050226)
		(stroke
			(width 0.05715)
			(type default)
		)
		(layer "In6.Cu")
	)
	(gr_line
		(start 351.46996 -407.304748)
		(end 351.287588 -407.690828)
		(stroke
			(width 0.07112)
			(type default)
		)
		(layer "In6.Cu")
	)
	(gr_line
		(start 351.561146 -286.236156)
		(end 351.859088 -286.236156)
		(stroke
			(width 0.05715)
			(type default)
		)
		(layer "In6.Cu")
	)
	(gr_line
		(start 351.561146 -284.616144)
		(end 351.859088 -284.616144)
		(stroke
			(width 0.05715)
			(type default)
		)
		(layer "In6.Cu")
	)
	(gr_line
		(start 351.561146 -282.996132)
		(end 351.859088 -282.996132)
		(stroke
			(width 0.05715)
			(type default)
		)
		(layer "In6.Cu")
	)
	(gr_line
		(start 351.563178 -415.097468)
		(end 351.274126 -415.38652)
		(stroke
			(width 0.07112)
			(type default)
		)
		(layer "In6.Cu")
	)
	(gr_line
		(start 351.563178 -415.093912)
		(end 351.563178 -415.097468)
		(stroke
			(width 0.07112)
			(type default)
		)
		(layer "In6.Cu")
	)
	(gr_line
		(start 351.564956 -419.478714)
		(end 351.564956 -420.179754)
		(stroke
			(width 0.07112)
			(type default)
		)
		(layer "In6.Cu")
	)
	(gr_line
		(start 351.631758 -405.981916)
		(end 351.331784 -406.616154)
		(stroke
			(width 0.07112)
			(type default)
		)
		(layer "In6.Cu")
	)
	(gr_arc
		(start 351.656142 -285.436564)
		(mid 351.656272 -285.434659)
		(end 351.656396 -285.432754)
		(stroke
			(width 0.05715)
			(type default)
		)
		(layer "In6.Cu")
	)
	(gr_line
		(start 351.656396 -285.427166)
		(end 351.656396 -285.432754)
		(stroke
			(width 0.05715)
			(type default)
		)
		(layer "In6.Cu")
	)
	(gr_line
		(start 351.748598 -294.658288)
		(end 351.74809 -294.658542)
		(stroke
			(width 0.05715)
			(type default)
		)
		(layer "In6.Cu")
	)
	(gr_line
		(start 351.76968 -406.671018)
		(end 351.588578 -406.736042)
		(stroke
			(width 0.07112)
			(type default)
		)
		(layer "In6.Cu")
	)
	(gr_line
		(start 351.846388 -415.095182)
		(end 352.137726 -415.38652)
		(stroke
			(width 0.07112)
			(type default)
		)
		(layer "In6.Cu")
	)
	(gr_line
		(start 351.848166 -419.479984)
		(end 351.984056 -419.615874)
		(stroke
			(width 0.07112)
			(type default)
		)
		(layer "In6.Cu")
	)
	(gr_line
		(start 351.859088 -286.236156)
		(end 351.941892 -286.31896)
		(stroke
			(width 0.05715)
			(type default)
		)
		(layer "In6.Cu")
	)
	(gr_line
		(start 351.859088 -284.616144)
		(end 351.92843 -284.685486)
		(stroke
			(width 0.05715)
			(type default)
		)
		(layer "In6.Cu")
	)
	(gr_line
		(start 351.859088 -282.996132)
		(end 351.941892 -283.078936)
		(stroke
			(width 0.05715)
			(type default)
		)
		(layer "In6.Cu")
	)
	(gr_line
		(start 351.875344 -289.006788)
		(end 351.882456 -289.010852)
		(stroke
			(width 0.05715)
			(type default)
		)
		(layer "In6.Cu")
	)
	(gr_arc
		(start 351.882456 -289.010852)
		(mid 351.882837 -289.011106)
		(end 351.883218 -289.01136)
		(stroke
			(width 0.05715)
			(type default)
		)
		(layer "In6.Cu")
	)
	(gr_line
		(start 351.887282 -406.103836)
		(end 351.952052 -406.284938)
		(stroke
			(width 0.07112)
			(type default)
		)
		(layer "In6.Cu")
	)
	(gr_arc
		(start 351.891092 -289.016948)
		(mid 351.887167 -289.014137)
		(end 351.883218 -289.01136)
		(stroke
			(width 0.05715)
			(type default)
		)
		(layer "In6.Cu")
	)
	(gr_line
		(start 351.918778 -397.156432)
		(end 351.971102 -397.208756)
		(stroke
			(width 0.07112)
			(type default)
		)
		(layer "In6.Cu")
	)
	(gr_arc
		(start 351.941892 -286.31896)
		(mid 351.943684 -286.330282)
		(end 351.945702 -286.341566)
		(stroke
			(width 0.05715)
			(type default)
		)
		(layer "In6.Cu")
	)
	(gr_arc
		(start 351.941892 -283.078936)
		(mid 351.943678 -283.090386)
		(end 351.945702 -283.101796)
		(stroke
			(width 0.05715)
			(type default)
		)
		(layer "In6.Cu")
	)
	(gr_line
		(start 351.952052 -406.284938)
		(end 351.76968 -406.671018)
		(stroke
			(width 0.07112)
			(type default)
		)
		(layer "In6.Cu")
	)
	(gr_line
		(start 351.966784 -296.252646)
		(end 351.966784 -296.281094)
		(stroke
			(width 0.05715)
			(type default)
		)
		(layer "In6.Cu")
	)
	(gr_line
		(start 351.971102 -397.388588)
		(end 351.824544 -397.535146)
		(stroke
			(width 0.07112)
			(type default)
		)
		(layer "In6.Cu")
	)
	(gr_line
		(start 351.971102 -397.208756)
		(end 351.971102 -397.388588)
		(stroke
			(width 0.07112)
			(type default)
		)
		(layer "In6.Cu")
	)
	(gr_line
		(start 351.984056 -420.042594)
		(end 351.848166 -420.178484)
		(stroke
			(width 0.07112)
			(type default)
		)
		(layer "In6.Cu")
	)
	(gr_line
		(start 351.984056 -419.615874)
		(end 351.984056 -420.042594)
		(stroke
			(width 0.07112)
			(type default)
		)
		(layer "In6.Cu")
	)
	(gr_line
		(start 352.012504 -296.206926)
		(end 351.966784 -296.252646)
		(stroke
			(width 0.05715)
			(type default)
		)
		(layer "In6.Cu")
	)
	(gr_arc
		(start 352.116644 -284.721808)
		(mid 352.118665 -284.710397)
		(end 352.120454 -284.698948)
		(stroke
			(width 0.05715)
			(type default)
		)
		(layer "In6.Cu")
	)
	(gr_line
		(start 352.137726 -418.412168)
		(end 351.846896 -418.702998)
		(stroke
			(width 0.07112)
			(type default)
		)
		(layer "In6.Cu")
	)
	(gr_line
		(start 352.203004 -296.206926)
		(end 352.248724 -296.252646)
		(stroke
			(width 0.05715)
			(type default)
		)
		(layer "In6.Cu")
	)
	(gr_line
		(start 352.203258 -286.236156)
		(end 352.133916 -286.305498)
		(stroke
			(width 0.05715)
			(type default)
		)
		(layer "In6.Cu")
	)
	(gr_line
		(start 352.203258 -284.616144)
		(end 352.120454 -284.698948)
		(stroke
			(width 0.05715)
			(type default)
		)
		(layer "In6.Cu")
	)
	(gr_line
		(start 352.203258 -282.996132)
		(end 352.133916 -283.065474)
		(stroke
			(width 0.05715)
			(type default)
		)
		(layer "In6.Cu")
	)
	(gr_line
		(start 352.20402 -397.734536)
		(end 352.025712 -397.734536)
		(stroke
			(width 0.07112)
			(type default)
		)
		(layer "In6.Cu")
	)
	(gr_line
		(start 352.248724 -296.252646)
		(end 352.248724 -296.281094)
		(stroke
			(width 0.05715)
			(type default)
		)
		(layer "In6.Cu")
	)
	(gr_line
		(start 352.318828 -397.849344)
		(end 352.20402 -397.734536)
		(stroke
			(width 0.07112)
			(type default)
		)
		(layer "In6.Cu")
	)
	(gr_line
		(start 352.5012 -286.236156)
		(end 352.203258 -286.236156)
		(stroke
			(width 0.05715)
			(type default)
		)
		(layer "In6.Cu")
	)
	(gr_line
		(start 352.5012 -284.616144)
		(end 352.203258 -284.616144)
		(stroke
			(width 0.05715)
			(type default)
		)
		(layer "In6.Cu")
	)
	(gr_line
		(start 352.5012 -282.996132)
		(end 352.203258 -282.996132)
		(stroke
			(width 0.05715)
			(type default)
		)
		(layer "In6.Cu")
	)
	(gr_line
		(start 352.505264 -294.82542)
		(end 352.505518 -294.825674)
		(stroke
			(width 0.05715)
			(type default)
		)
		(layer "In6.Cu")
	)
	(gr_line
		(start 352.513392 -409.359354)
		(end 352.484944 -409.473146)
		(stroke
			(width 0.07112)
			(type default)
		)
		(layer "In6.Cu")
	)
	(gr_line
		(start 352.51517 -409.358338)
		(end 352.513392 -409.359354)
		(stroke
			(width 0.07112)
			(type default)
		)
		(layer "In6.Cu")
	)
	(gr_arc
		(start 352.641154 -292.364922)
		(mid 352.645079 -292.367733)
		(end 352.649028 -292.37051)
		(stroke
			(width 0.05715)
			(type default)
		)
		(layer "In6.Cu")
	)
	(gr_arc
		(start 352.641154 -290.74491)
		(mid 352.645079 -290.747721)
		(end 352.649028 -290.750498)
		(stroke
			(width 0.05715)
			(type default)
		)
		(layer "In6.Cu")
	)
	(gr_arc
		(start 352.641154 -289.124898)
		(mid 352.645079 -289.127709)
		(end 352.649028 -289.130486)
		(stroke
			(width 0.05715)
			(type default)
		)
		(layer "In6.Cu")
	)
	(gr_arc
		(start 352.641154 -287.504886)
		(mid 352.64634 -287.508599)
		(end 352.651568 -287.512252)
		(stroke
			(width 0.05715)
			(type default)
		)
		(layer "In6.Cu")
	)
	(gr_line
		(start 352.649028 -292.37051)
		(end 352.655886 -292.374574)
		(stroke
			(width 0.05715)
			(type default)
		)
		(layer "In6.Cu")
	)
	(gr_line
		(start 352.649028 -290.750498)
		(end 352.655886 -290.754562)
		(stroke
			(width 0.05715)
			(type default)
		)
		(layer "In6.Cu")
	)
	(gr_line
		(start 352.649028 -289.130486)
		(end 352.655886 -289.13455)
		(stroke
			(width 0.05715)
			(type default)
		)
		(layer "In6.Cu")
	)
	(gr_line
		(start 352.651568 -287.512252)
		(end 352.655886 -287.514792)
		(stroke
			(width 0.05715)
			(type default)
		)
		(layer "In6.Cu")
	)
	(gr_line
		(start 352.655886 -292.374574)
		(end 352.656648 -292.375082)
		(stroke
			(width 0.05715)
			(type default)
		)
		(layer "In6.Cu")
	)
	(gr_line
		(start 352.655886 -290.754562)
		(end 352.656648 -290.75507)
		(stroke
			(width 0.05715)
			(type default)
		)
		(layer "In6.Cu")
	)
	(gr_line
		(start 352.655886 -289.13455)
		(end 352.656648 -289.135058)
		(stroke
			(width 0.05715)
			(type default)
		)
		(layer "In6.Cu")
	)
	(gr_line
		(start 352.655886 -287.514792)
		(end 352.656648 -287.5153)
		(stroke
			(width 0.05715)
			(type default)
		)
		(layer "In6.Cu")
	)
	(gr_line
		(start 352.656394 -408.79522)
		(end 352.51517 -409.358338)
		(stroke
			(width 0.07112)
			(type default)
		)
		(layer "In6.Cu")
	)
	(gr_line
		(start 352.656648 -292.375082)
		(end 352.65741 -292.37559)
		(stroke
			(width 0.05715)
			(type default)
		)
		(layer "In6.Cu")
	)
	(gr_line
		(start 352.656648 -290.75507)
		(end 352.65741 -290.755578)
		(stroke
			(width 0.05715)
			(type default)
		)
		(layer "In6.Cu")
	)
	(gr_line
		(start 352.656648 -289.135058)
		(end 352.65741 -289.135566)
		(stroke
			(width 0.05715)
			(type default)
		)
		(layer "In6.Cu")
	)
	(gr_line
		(start 352.656648 -287.5153)
		(end 352.65741 -287.515808)
		(stroke
			(width 0.05715)
			(type default)
		)
		(layer "In6.Cu")
	)
	(gr_line
		(start 352.65868 -408.79395)
		(end 352.656394 -408.79522)
		(stroke
			(width 0.07112)
			(type default)
		)
		(layer "In6.Cu")
	)
	(gr_line
		(start 352.688144 -293.03853)
		(end 352.687128 -293.039038)
		(stroke
			(width 0.05715)
			(type default)
		)
		(layer "In6.Cu")
	)
	(gr_line
		(start 352.688144 -291.418518)
		(end 352.687128 -291.419026)
		(stroke
			(width 0.05715)
			(type default)
		)
		(layer "In6.Cu")
	)
	(gr_line
		(start 352.688144 -289.798506)
		(end 352.687128 -289.799014)
		(stroke
			(width 0.05715)
			(type default)
		)
		(layer "In6.Cu")
	)
	(gr_line
		(start 352.688398 -287.533842)
		(end 352.689922 -287.534604)
		(stroke
			(width 0.05715)
			(type default)
		)
		(layer "In6.Cu")
	)
	(gr_line
		(start 352.720656 -294.639492)
		(end 352.720656 -294.639746)
		(stroke
			(width 0.05715)
			(type default)
		)
		(layer "In6.Cu")
	)
	(gr_line
		(start 352.720656 -294.032178)
		(end 352.720656 -294.032432)
		(stroke
			(width 0.05715)
			(type default)
		)
		(layer "In6.Cu")
	)
	(gr_line
		(start 352.75901 -409.541472)
		(end 352.758756 -409.541726)
		(stroke
			(width 0.07112)
			(type default)
		)
		(layer "In6.Cu")
	)
	(gr_line
		(start 352.783394 -293.203884)
		(end 352.782124 -293.204646)
		(stroke
			(width 0.05715)
			(type default)
		)
		(layer "In6.Cu")
	)
	(gr_line
		(start 352.783394 -291.583872)
		(end 352.782124 -291.584634)
		(stroke
			(width 0.05715)
			(type default)
		)
		(layer "In6.Cu")
	)
	(gr_line
		(start 352.783394 -289.96386)
		(end 352.782124 -289.964622)
		(stroke
			(width 0.05715)
			(type default)
		)
		(layer "In6.Cu")
	)
	(gr_line
		(start 352.783394 -287.36798)
		(end 352.784156 -287.368488)
		(stroke
			(width 0.05715)
			(type default)
		)
		(layer "In6.Cu")
	)
	(gr_line
		(start 352.783902 -293.20363)
		(end 352.783394 -293.203884)
		(stroke
			(width 0.05715)
			(type default)
		)
		(layer "In6.Cu")
	)
	(gr_line
		(start 352.783902 -291.583618)
		(end 352.783394 -291.583872)
		(stroke
			(width 0.05715)
			(type default)
		)
		(layer "In6.Cu")
	)
	(gr_line
		(start 352.783902 -289.963606)
		(end 352.783394 -289.96386)
		(stroke
			(width 0.05715)
			(type default)
		)
		(layer "In6.Cu")
	)
	(gr_line
		(start 352.783902 -287.368742)
		(end 352.784664 -287.36925)
		(stroke
			(width 0.05715)
			(type default)
		)
		(layer "In6.Cu")
	)
	(gr_line
		(start 352.784156 -287.368488)
		(end 352.783902 -287.368742)
		(stroke
			(width 0.05715)
			(type default)
		)
		(layer "In6.Cu")
	)
	(gr_line
		(start 352.790506 -408.258264)
		(end 352.793046 -408.262074)
		(stroke
			(width 0.07112)
			(type default)
		)
		(layer "In6.Cu")
	)
	(gr_line
		(start 352.793046 -408.262074)
		(end 352.764598 -408.375866)
		(stroke
			(width 0.07112)
			(type default)
		)
		(layer "In6.Cu")
	)
	(gr_line
		(start 352.826574 -293.873428)
		(end 352.83267 -293.878)
		(stroke
			(width 0.05715)
			(type default)
		)
		(layer "In6.Cu")
	)
	(gr_line
		(start 352.911918 -296.252646)
		(end 352.911918 -296.281094)
		(stroke
			(width 0.05715)
			(type default)
		)
		(layer "In6.Cu")
	)
	(gr_line
		(start 352.92665 -409.441142)
		(end 352.759772 -409.540964)
		(stroke
			(width 0.07112)
			(type default)
		)
		(layer "In6.Cu")
	)
	(gr_line
		(start 352.930968 -407.69794)
		(end 352.790506 -408.258264)
		(stroke
			(width 0.07112)
			(type default)
		)
		(layer "In6.Cu")
	)
	(gr_line
		(start 352.933 -408.864562)
		(end 353.030282 -409.026868)
		(stroke
			(width 0.07112)
			(type default)
		)
		(layer "In6.Cu")
	)
	(gr_line
		(start 352.933762 -408.861768)
		(end 352.933 -408.864562)
		(stroke
			(width 0.07112)
			(type default)
		)
		(layer "In6.Cu")
	)
	(gr_line
		(start 352.957638 -296.206926)
		(end 352.911918 -296.252646)
		(stroke
			(width 0.05715)
			(type default)
		)
		(layer "In6.Cu")
	)
	(gr_line
		(start 353.030282 -409.026868)
		(end 352.92665 -409.441142)
		(stroke
			(width 0.07112)
			(type default)
		)
		(layer "In6.Cu")
	)
	(gr_line
		(start 353.06254 -284.580076)
		(end 353.062794 -284.581346)
		(stroke
			(width 0.05715)
			(type default)
		)
		(layer "In6.Cu")
	)
	(gr_line
		(start 353.06635 -284.624526)
		(end 353.06635 -284.625796)
		(stroke
			(width 0.05715)
			(type default)
		)
		(layer "In6.Cu")
	)
	(gr_line
		(start 353.118928 -397.156432)
		(end 353.171252 -397.208756)
		(stroke
			(width 0.07112)
			(type default)
		)
		(layer "In6.Cu")
	)
	(gr_line
		(start 353.13747 -285.760668)
		(end 353.136708 -285.761176)
		(stroke
			(width 0.05715)
			(type default)
		)
		(layer "In6.Cu")
	)
	(gr_line
		(start 353.148138 -296.206926)
		(end 353.193858 -296.252646)
		(stroke
			(width 0.05715)
			(type default)
		)
		(layer "In6.Cu")
	)
	(gr_line
		(start 353.171252 -397.388588)
		(end 353.024694 -397.535146)
		(stroke
			(width 0.07112)
			(type default)
		)
		(layer "In6.Cu")
	)
	(gr_line
		(start 353.171252 -397.208756)
		(end 353.171252 -397.388588)
		(stroke
			(width 0.07112)
			(type default)
		)
		(layer "In6.Cu")
	)
	(gr_line
		(start 353.193858 -296.252646)
		(end 353.193858 -296.281094)
		(stroke
			(width 0.05715)
			(type default)
		)
		(layer "In6.Cu")
	)
	(gr_line
		(start 353.200716 -408.347164)
		(end 353.03968 -408.44343)
		(stroke
			(width 0.07112)
			(type default)
		)
		(layer "In6.Cu")
	)
	(gr_line
		(start 353.205034 -406.603962)
		(end 353.0346 -407.284174)
		(stroke
			(width 0.07112)
			(type default)
		)
		(layer "In6.Cu")
	)
	(gr_line
		(start 353.205288 -407.76779)
		(end 353.304348 -407.93289)
		(stroke
			(width 0.07112)
			(type default)
		)
		(layer "In6.Cu")
	)
	(gr_line
		(start 353.232212 -286.54629)
		(end 353.23272 -286.54629)
		(stroke
			(width 0.05715)
			(type default)
		)
		(layer "In6.Cu")
	)
	(gr_line
		(start 353.23272 -285.926022)
		(end 353.232466 -285.926022)
		(stroke
			(width 0.05715)
			(type default)
		)
		(layer "In6.Cu")
	)
	(gr_line
		(start 353.233228 -285.925768)
		(end 353.23272 -285.926022)
		(stroke
			(width 0.05715)
			(type default)
		)
		(layer "In6.Cu")
	)
	(gr_line
		(start 353.287584 -286.578548)
		(end 353.295204 -286.582866)
		(stroke
			(width 0.05715)
			(type default)
		)
		(layer "In6.Cu")
	)
	(gr_line
		(start 353.295204 -286.582866)
		(end 353.295204 -286.582612)
		(stroke
			(width 0.05715)
			(type default)
		)
		(layer "In6.Cu")
	)
	(gr_arc
		(start 353.30384 -286.588708)
		(mid 353.299536 -286.58564)
		(end 353.295204 -286.582612)
		(stroke
			(width 0.05715)
			(type default)
		)
		(layer "In6.Cu")
	)
	(gr_line
		(start 353.304348 -407.93289)
		(end 353.200716 -408.347164)
		(stroke
			(width 0.07112)
			(type default)
		)
		(layer "In6.Cu")
	)
	(gr_line
		(start 353.403916 -397.734536)
		(end 353.225862 -397.734536)
		(stroke
			(width 0.07112)
			(type default)
		)
		(layer "In6.Cu")
	)
	(gr_line
		(start 353.474782 -407.253186)
		(end 353.309428 -407.351992)
		(stroke
			(width 0.07112)
			(type default)
		)
		(layer "In6.Cu")
	)
	(gr_line
		(start 353.479354 -406.673812)
		(end 353.578414 -406.838912)
		(stroke
			(width 0.07112)
			(type default)
		)
		(layer "In6.Cu")
	)
	(gr_line
		(start 353.518724 -397.849344)
		(end 353.403916 -397.734536)
		(stroke
			(width 0.07112)
			(type default)
		)
		(layer "In6.Cu")
	)
	(gr_line
		(start 353.578414 -406.838912)
		(end 353.474782 -407.253186)
		(stroke
			(width 0.07112)
			(type default)
		)
		(layer "In6.Cu")
	)
	(gr_line
		(start 353.857052 -296.252646)
		(end 353.857052 -296.281094)
		(stroke
			(width 0.05715)
			(type default)
		)
		(layer "In6.Cu")
	)
	(gr_line
		(start 353.902772 -296.206926)
		(end 353.857052 -296.252646)
		(stroke
			(width 0.05715)
			(type default)
		)
		(layer "In6.Cu")
	)
	(gr_line
		(start 354.086414 -285.755588)
		(end 354.085906 -285.755842)
		(stroke
			(width 0.05715)
			(type default)
		)
		(layer "In6.Cu")
	)
	(gr_line
		(start 354.093272 -296.206926)
		(end 354.138992 -296.252646)
		(stroke
			(width 0.05715)
			(type default)
		)
		(layer "In6.Cu")
	)
	(gr_line
		(start 354.09378 -285.75127)
		(end 354.088192 -285.754572)
		(stroke
			(width 0.05715)
			(type default)
		)
		(layer "In6.Cu")
	)
	(gr_line
		(start 354.097082 -285.749238)
		(end 354.095558 -285.750254)
		(stroke
			(width 0.05715)
			(type default)
		)
		(layer "In6.Cu")
	)
	(gr_line
		(start 354.138992 -296.252646)
		(end 354.138992 -296.281094)
		(stroke
			(width 0.05715)
			(type default)
		)
		(layer "In6.Cu")
	)
	(gr_line
		(start 354.192078 -285.914846)
		(end 354.191062 -285.915354)
		(stroke
			(width 0.05715)
			(type default)
		)
		(layer "In6.Cu")
	)
	(gr_line
		(start 354.193348 -285.914084)
		(end 354.192078 -285.914846)
		(stroke
			(width 0.05715)
			(type default)
		)
		(layer "In6.Cu")
	)
	(gr_line
		(start 354.193856 -285.91383)
		(end 354.193348 -285.914084)
		(stroke
			(width 0.05715)
			(type default)
		)
		(layer "In6.Cu")
	)
	(gr_line
		(start 354.318824 -397.156432)
		(end 354.371148 -397.208756)
		(stroke
			(width 0.07112)
			(type default)
		)
		(layer "In6.Cu")
	)
	(gr_line
		(start 354.371148 -397.388588)
		(end 354.22459 -397.535146)
		(stroke
			(width 0.07112)
			(type default)
		)
		(layer "In6.Cu")
	)
	(gr_line
		(start 354.371148 -397.208756)
		(end 354.371148 -397.388588)
		(stroke
			(width 0.07112)
			(type default)
		)
		(layer "In6.Cu")
	)
	(gr_line
		(start 354.381054 -286.236156)
		(end 354.678996 -286.236156)
		(stroke
			(width 0.05715)
			(type default)
		)
		(layer "In6.Cu")
	)
	(gr_line
		(start 354.381054 -284.616144)
		(end 354.678996 -284.616144)
		(stroke
			(width 0.05715)
			(type default)
		)
		(layer "In6.Cu")
	)
	(gr_line
		(start 354.381054 -282.996132)
		(end 354.678996 -282.996132)
		(stroke
			(width 0.05715)
			(type default)
		)
		(layer "In6.Cu")
	)
	(gr_line
		(start 354.476558 -295.145968)
		(end 354.476304 -295.146222)
		(stroke
			(width 0.05715)
			(type default)
		)
		(layer "In6.Cu")
	)
	(gr_line
		(start 354.604066 -397.734536)
		(end 354.425758 -397.734536)
		(stroke
			(width 0.07112)
			(type default)
		)
		(layer "In6.Cu")
	)
	(gr_line
		(start 354.678996 -286.236156)
		(end 354.703126 -286.260286)
		(stroke
			(width 0.05715)
			(type default)
		)
		(layer "In6.Cu")
	)
	(gr_line
		(start 354.678996 -284.616144)
		(end 354.748338 -284.685486)
		(stroke
			(width 0.05715)
			(type default)
		)
		(layer "In6.Cu")
	)
	(gr_line
		(start 354.678996 -282.996132)
		(end 354.7618 -283.078936)
		(stroke
			(width 0.05715)
			(type default)
		)
		(layer "In6.Cu")
	)
	(gr_line
		(start 354.718874 -397.849344)
		(end 354.604066 -397.734536)
		(stroke
			(width 0.07112)
			(type default)
		)
		(layer "In6.Cu")
	)
	(gr_arc
		(start 354.7618 -283.078936)
		(mid 354.763844 -283.090261)
		(end 354.766118 -283.101542)
		(stroke
			(width 0.05715)
			(type default)
		)
		(layer "In6.Cu")
	)
	(gr_arc
		(start 354.770182 -286.36722)
		(mid 354.742706 -286.309957)
		(end 354.703126 -286.260286)
		(stroke
			(width 0.05715)
			(type default)
		)
		(layer "In6.Cu")
	)
	(gr_arc
		(start 354.77577 -286.385254)
		(mid 354.775517 -286.384492)
		(end 354.775262 -286.38373)
		(stroke
			(width 0.05715)
			(type default)
		)
		(layer "In6.Cu")
	)
	(gr_line
		(start 354.887784 -296.583862)
		(end 354.887784 -296.61231)
		(stroke
			(width 0.05715)
			(type default)
		)
		(layer "In6.Cu")
	)
	(gr_line
		(start 354.933504 -296.538142)
		(end 354.887784 -296.583862)
		(stroke
			(width 0.05715)
			(type default)
		)
		(layer "In6.Cu")
	)
	(gr_arc
		(start 354.936552 -284.721808)
		(mid 354.938573 -284.710397)
		(end 354.940362 -284.698948)
		(stroke
			(width 0.05715)
			(type default)
		)
		(layer "In6.Cu")
	)
	(gr_arc
		(start 354.953316 -286.306006)
		(mid 354.95268 -286.306257)
		(end 354.952046 -286.306514)
		(stroke
			(width 0.05715)
			(type default)
		)
		(layer "In6.Cu")
	)
	(gr_line
		(start 355.023166 -286.236156)
		(end 354.953316 -286.306006)
		(stroke
			(width 0.05715)
			(type default)
		)
		(layer "In6.Cu")
	)
	(gr_line
		(start 355.023166 -284.616144)
		(end 354.940362 -284.698948)
		(stroke
			(width 0.05715)
			(type default)
		)
		(layer "In6.Cu")
	)
	(gr_line
		(start 355.023166 -282.996132)
		(end 354.953316 -283.065982)
		(stroke
			(width 0.05715)
			(type default)
		)
		(layer "In6.Cu")
	)
	(gr_line
		(start 355.023928 -295.47693)
		(end 355.019864 -295.479216)
		(stroke
			(width 0.05715)
			(type default)
		)
		(layer "In6.Cu")
	)
	(gr_line
		(start 355.124004 -296.538142)
		(end 355.169724 -296.583862)
		(stroke
			(width 0.05715)
			(type default)
		)
		(layer "In6.Cu")
	)
	(gr_line
		(start 355.167438 -286.57804)
		(end 355.1682 -286.578294)
		(stroke
			(width 0.05715)
			(type default)
		)
		(layer "In6.Cu")
	)
	(gr_line
		(start 355.169724 -296.583862)
		(end 355.169724 -296.61231)
		(stroke
			(width 0.05715)
			(type default)
		)
		(layer "In6.Cu")
	)
	(gr_arc
		(start 355.18217 -286.587946)
		(mid 355.175221 -286.583068)
		(end 355.1682 -286.578294)
		(stroke
			(width 0.05715)
			(type default)
		)
		(layer "In6.Cu")
	)
	(gr_line
		(start 355.22916 -287.078674)
		(end 355.228906 -287.077404)
		(stroke
			(width 0.05715)
			(type default)
		)
		(layer "In6.Cu")
	)
	(gr_line
		(start 355.229414 -287.080198)
		(end 355.22916 -287.078674)
		(stroke
			(width 0.05715)
			(type default)
		)
		(layer "In6.Cu")
	)
	(gr_line
		(start 355.321108 -286.236156)
		(end 355.023166 -286.236156)
		(stroke
			(width 0.05715)
			(type default)
		)
		(layer "In6.Cu")
	)
	(gr_line
		(start 355.321108 -284.616144)
		(end 355.023166 -284.616144)
		(stroke
			(width 0.05715)
			(type default)
		)
		(layer "In6.Cu")
	)
	(gr_line
		(start 355.321108 -282.996132)
		(end 355.023166 -282.996132)
		(stroke
			(width 0.05715)
			(type default)
		)
		(layer "In6.Cu")
	)
	(gr_line
		(start 355.412548 -283.77007)
		(end 355.412802 -283.77134)
		(stroke
			(width 0.05715)
			(type default)
		)
		(layer "In6.Cu")
	)
	(gr_line
		(start 355.416358 -283.81452)
		(end 355.416358 -283.81579)
		(stroke
			(width 0.05715)
			(type default)
		)
		(layer "In6.Cu")
	)
	(gr_line
		(start 355.495098 -294.666162)
		(end 355.49459 -294.666416)
		(stroke
			(width 0.05715)
			(type default)
		)
		(layer "In6.Cu")
	)
	(gr_line
		(start 355.495098 -289.145726)
		(end 355.495606 -289.14598)
		(stroke
			(width 0.05715)
			(type default)
		)
		(layer "In6.Cu")
	)
	(gr_arc
		(start 355.496622 -292.386766)
		(mid 355.499032 -292.388169)
		(end 355.501448 -292.38956)
		(stroke
			(width 0.05715)
			(type default)
		)
		(layer "In6.Cu")
	)
	(gr_arc
		(start 355.496622 -290.766754)
		(mid 355.499032 -290.768157)
		(end 355.501448 -290.769548)
		(stroke
			(width 0.05715)
			(type default)
		)
		(layer "In6.Cu")
	)
	(gr_line
		(start 355.49713 -288.184844)
		(end 355.495098 -288.186114)
		(stroke
			(width 0.05715)
			(type default)
		)
		(layer "In6.Cu")
	)
	(gr_line
		(start 355.507798 -292.39337)
		(end 355.508052 -292.39337)
		(stroke
			(width 0.05715)
			(type default)
		)
		(layer "In6.Cu")
	)
	(gr_line
		(start 355.507798 -290.773358)
		(end 355.508052 -290.773358)
		(stroke
			(width 0.05715)
			(type default)
		)
		(layer "In6.Cu")
	)
	(gr_line
		(start 355.508052 -291.418518)
		(end 355.507798 -291.418772)
		(stroke
			(width 0.05715)
			(type default)
		)
		(layer "In6.Cu")
	)
	(gr_line
		(start 355.508052 -289.798506)
		(end 355.507798 -289.79876)
		(stroke
			(width 0.05715)
			(type default)
		)
		(layer "In6.Cu")
	)
	(gr_line
		(start 355.590602 -294.831008)
		(end 355.590348 -294.831262)
		(stroke
			(width 0.05715)
			(type default)
		)
		(layer "In6.Cu")
	)
	(gr_line
		(start 355.603556 -292.22827)
		(end 355.608636 -292.231064)
		(stroke
			(width 0.05715)
			(type default)
		)
		(layer "In6.Cu")
	)
	(gr_line
		(start 355.603556 -290.608258)
		(end 355.608636 -290.611052)
		(stroke
			(width 0.05715)
			(type default)
		)
		(layer "In6.Cu")
	)
	(gr_line
		(start 355.608636 -292.231064)
		(end 355.609398 -292.231572)
		(stroke
			(width 0.05715)
			(type default)
		)
		(layer "In6.Cu")
	)
	(gr_line
		(start 355.608636 -290.611052)
		(end 355.609398 -290.61156)
		(stroke
			(width 0.05715)
			(type default)
		)
		(layer "In6.Cu")
	)
	(gr_line
		(start 355.609398 -292.231572)
		(end 355.610414 -292.23208)
		(stroke
			(width 0.05715)
			(type default)
		)
		(layer "In6.Cu")
	)
	(gr_line
		(start 355.609398 -290.61156)
		(end 355.610414 -290.612068)
		(stroke
			(width 0.05715)
			(type default)
		)
		(layer "In6.Cu")
	)
	(gr_line
		(start 355.610414 -292.23208)
		(end 355.61143 -292.232588)
		(stroke
			(width 0.05715)
			(type default)
		)
		(layer "In6.Cu")
	)
	(gr_line
		(start 355.625146 -291.571172)
		(end 355.624892 -291.571172)
		(stroke
			(width 0.05715)
			(type default)
		)
		(layer "In6.Cu")
	)
	(gr_line
		(start 355.625146 -289.95116)
		(end 355.624892 -289.95116)
		(stroke
			(width 0.05715)
			(type default)
		)
		(layer "In6.Cu")
	)
	(gr_line
		(start 355.63429 -292.24605)
		(end 355.642418 -292.250876)
		(stroke
			(width 0.05715)
			(type default)
		)
		(layer "In6.Cu")
	)
	(gr_line
		(start 355.634544 -290.626292)
		(end 355.642418 -290.630864)
		(stroke
			(width 0.05715)
			(type default)
		)
		(layer "In6.Cu")
	)
	(gr_line
		(start 355.634798 -287.386776)
		(end 355.642418 -287.391094)
		(stroke
			(width 0.05715)
			(type default)
		)
		(layer "In6.Cu")
	)
	(gr_line
		(start 355.635052 -291.56533)
		(end 355.633528 -291.566346)
		(stroke
			(width 0.05715)
			(type default)
		)
		(layer "In6.Cu")
	)
	(gr_line
		(start 355.635052 -289.945318)
		(end 355.633528 -289.946334)
		(stroke
			(width 0.05715)
			(type default)
		)
		(layer "In6.Cu")
	)
	(gr_line
		(start 355.635306 -289.006788)
		(end 355.642418 -289.010852)
		(stroke
			(width 0.05715)
			(type default)
		)
		(layer "In6.Cu")
	)
	(gr_line
		(start 355.640386 -293.182548)
		(end 355.635052 -293.185596)
		(stroke
			(width 0.05715)
			(type default)
		)
		(layer "In6.Cu")
	)
	(gr_arc
		(start 355.642418 -292.250876)
		(mid 355.642799 -292.25113)
		(end 355.64318 -292.251384)
		(stroke
			(width 0.05715)
			(type default)
		)
		(layer "In6.Cu")
	)
	(gr_arc
		(start 355.642418 -290.630864)
		(mid 355.642799 -290.631118)
		(end 355.64318 -290.631372)
		(stroke
			(width 0.05715)
			(type default)
		)
		(layer "In6.Cu")
	)
	(gr_arc
		(start 355.642418 -289.010852)
		(mid 355.642799 -289.011106)
		(end 355.64318 -289.01136)
		(stroke
			(width 0.05715)
			(type default)
		)
		(layer "In6.Cu")
	)
	(gr_line
		(start 355.642418 -287.391094)
		(end 355.642418 -287.39084)
		(stroke
			(width 0.05715)
			(type default)
		)
		(layer "In6.Cu")
	)
	(gr_line
		(start 355.64318 -293.180516)
		(end 355.640386 -293.182548)
		(stroke
			(width 0.05715)
			(type default)
		)
		(layer "In6.Cu")
	)
	(gr_arc
		(start 355.64318 -293.180516)
		(mid 355.647129 -293.177739)
		(end 355.651054 -293.174928)
		(stroke
			(width 0.05715)
			(type default)
		)
		(layer "In6.Cu")
	)
	(gr_arc
		(start 355.651054 -292.256972)
		(mid 355.647129 -292.254161)
		(end 355.64318 -292.251384)
		(stroke
			(width 0.05715)
			(type default)
		)
		(layer "In6.Cu")
	)
	(gr_arc
		(start 355.651054 -290.63696)
		(mid 355.647129 -290.634149)
		(end 355.64318 -290.631372)
		(stroke
			(width 0.05715)
			(type default)
		)
		(layer "In6.Cu")
	)
	(gr_arc
		(start 355.651054 -289.016948)
		(mid 355.647129 -289.014137)
		(end 355.64318 -289.01136)
		(stroke
			(width 0.05715)
			(type default)
		)
		(layer "In6.Cu")
	)
	(gr_arc
		(start 355.651308 -287.396936)
		(mid 355.646878 -287.393866)
		(end 355.642418 -287.39084)
		(stroke
			(width 0.05715)
			(type default)
		)
		(layer "In6.Cu")
	)
	(gr_line
		(start 356.119938 -295.536366)
		(end 356.119938 -295.564814)
		(stroke
			(width 0.05715)
			(type default)
		)
		(layer "In6.Cu")
	)
	(gr_line
		(start 356.165404 -295.490392)
		(end 356.165658 -295.490646)
		(stroke
			(width 0.05715)
			(type default)
		)
		(layer "In6.Cu")
	)
	(gr_line
		(start 356.165658 -295.490646)
		(end 356.119938 -295.536366)
		(stroke
			(width 0.05715)
			(type default)
		)
		(layer "In6.Cu")
	)
	(gr_line
		(start 356.356158 -295.490646)
		(end 356.401878 -295.536366)
		(stroke
			(width 0.05715)
			(type default)
		)
		(layer "In6.Cu")
	)
	(gr_line
		(start 356.356412 -295.490392)
		(end 356.356158 -295.490646)
		(stroke
			(width 0.05715)
			(type default)
		)
		(layer "In6.Cu")
	)
	(gr_line
		(start 356.356412 -295.411144)
		(end 356.356412 -295.411652)
		(stroke
			(width 0.05715)
			(type default)
		)
		(layer "In6.Cu")
	)
	(gr_arc
		(start 356.401116 -293.984934)
		(mid 356.405041 -293.987745)
		(end 356.40899 -293.990522)
		(stroke
			(width 0.05715)
			(type default)
		)
		(layer "In6.Cu")
	)
	(gr_arc
		(start 356.401116 -292.364922)
		(mid 356.405041 -292.367733)
		(end 356.40899 -292.37051)
		(stroke
			(width 0.05715)
			(type default)
		)
		(layer "In6.Cu")
	)
	(gr_arc
		(start 356.401116 -290.74491)
		(mid 356.405041 -290.747721)
		(end 356.40899 -290.750498)
		(stroke
			(width 0.05715)
			(type default)
		)
		(layer "In6.Cu")
	)
	(gr_arc
		(start 356.401116 -289.124898)
		(mid 356.405041 -289.127709)
		(end 356.40899 -289.130486)
		(stroke
			(width 0.05715)
			(type default)
		)
		(layer "In6.Cu")
	)
	(gr_arc
		(start 356.401116 -285.885128)
		(mid 356.405041 -285.887939)
		(end 356.40899 -285.890716)
		(stroke
			(width 0.05715)
			(type default)
		)
		(layer "In6.Cu")
	)
	(gr_line
		(start 356.401878 -295.536366)
		(end 356.401878 -295.564814)
		(stroke
			(width 0.05715)
			(type default)
		)
		(layer "In6.Cu")
	)
	(gr_line
		(start 356.40899 -293.990522)
		(end 356.415848 -293.994586)
		(stroke
			(width 0.05715)
			(type default)
		)
		(layer "In6.Cu")
	)
	(gr_line
		(start 356.40899 -292.37051)
		(end 356.415848 -292.374574)
		(stroke
			(width 0.05715)
			(type default)
		)
		(layer "In6.Cu")
	)
	(gr_line
		(start 356.40899 -290.750498)
		(end 356.415848 -290.754562)
		(stroke
			(width 0.05715)
			(type default)
		)
		(layer "In6.Cu")
	)
	(gr_line
		(start 356.40899 -289.130486)
		(end 356.415848 -289.13455)
		(stroke
			(width 0.05715)
			(type default)
		)
		(layer "In6.Cu")
	)
	(gr_line
		(start 356.40899 -285.890716)
		(end 356.415848 -285.89478)
		(stroke
			(width 0.05715)
			(type default)
		)
		(layer "In6.Cu")
	)
	(gr_line
		(start 356.415848 -293.994586)
		(end 356.41661 -293.995094)
		(stroke
			(width 0.05715)
			(type default)
		)
		(layer "In6.Cu")
	)
	(gr_line
		(start 356.415848 -292.374574)
		(end 356.41661 -292.375082)
		(stroke
			(width 0.05715)
			(type default)
		)
		(layer "In6.Cu")
	)
	(gr_line
		(start 356.415848 -290.754562)
		(end 356.41661 -290.75507)
		(stroke
			(width 0.05715)
			(type default)
		)
		(layer "In6.Cu")
	)
	(gr_line
		(start 356.415848 -289.13455)
		(end 356.41661 -289.135058)
		(stroke
			(width 0.05715)
			(type default)
		)
		(layer "In6.Cu")
	)
	(gr_line
		(start 356.415848 -285.89478)
		(end 356.41661 -285.895288)
		(stroke
			(width 0.05715)
			(type default)
		)
		(layer "In6.Cu")
	)
	(gr_line
		(start 356.41661 -293.995094)
		(end 356.417372 -293.995602)
		(stroke
			(width 0.05715)
			(type default)
		)
		(layer "In6.Cu")
	)
	(gr_line
		(start 356.41661 -292.375082)
		(end 356.417372 -292.37559)
		(stroke
			(width 0.05715)
			(type default)
		)
		(layer "In6.Cu")
	)
	(gr_line
		(start 356.41661 -290.75507)
		(end 356.417372 -290.755578)
		(stroke
			(width 0.05715)
			(type default)
		)
		(layer "In6.Cu")
	)
	(gr_line
		(start 356.41661 -289.135058)
		(end 356.417372 -289.135566)
		(stroke
			(width 0.05715)
			(type default)
		)
		(layer "In6.Cu")
	)
	(gr_line
		(start 356.41661 -285.895288)
		(end 356.417372 -285.895796)
		(stroke
			(width 0.05715)
			(type default)
		)
		(layer "In6.Cu")
	)
	(gr_line
		(start 356.44328 -293.041324)
		(end 356.442264 -293.041832)
		(stroke
			(width 0.05715)
			(type default)
		)
		(layer "In6.Cu")
	)
	(gr_line
		(start 356.44328 -291.421312)
		(end 356.442264 -291.42182)
		(stroke
			(width 0.05715)
			(type default)
		)
		(layer "In6.Cu")
	)
	(gr_line
		(start 356.44328 -289.8013)
		(end 356.442264 -289.801808)
		(stroke
			(width 0.05715)
			(type default)
		)
		(layer "In6.Cu")
	)
	(gr_line
		(start 356.443788 -294.661082)
		(end 356.44201 -294.662098)
		(stroke
			(width 0.05715)
			(type default)
		)
		(layer "In6.Cu")
	)
	(gr_line
		(start 356.443788 -293.04107)
		(end 356.44328 -293.041324)
		(stroke
			(width 0.05715)
			(type default)
		)
		(layer "In6.Cu")
	)
	(gr_line
		(start 356.443788 -291.421058)
		(end 356.44328 -291.421312)
		(stroke
			(width 0.05715)
			(type default)
		)
		(layer "In6.Cu")
	)
	(gr_line
		(start 356.443788 -289.801046)
		(end 356.44328 -289.8013)
		(stroke
			(width 0.05715)
			(type default)
		)
		(layer "In6.Cu")
	)
	(gr_line
		(start 356.44709 -294.65905)
		(end 356.445566 -294.660066)
		(stroke
			(width 0.05715)
			(type default)
		)
		(layer "In6.Cu")
	)
	(gr_line
		(start 356.44709 -293.039038)
		(end 356.445566 -293.040054)
		(stroke
			(width 0.05715)
			(type default)
		)
		(layer "In6.Cu")
	)
	(gr_line
		(start 356.44709 -291.419026)
		(end 356.445566 -291.420042)
		(stroke
			(width 0.05715)
			(type default)
		)
		(layer "In6.Cu")
	)
	(gr_line
		(start 356.44709 -289.799014)
		(end 356.445566 -289.80003)
		(stroke
			(width 0.05715)
			(type default)
		)
		(layer "In6.Cu")
	)
	(gr_line
		(start 356.447852 -293.03853)
		(end 356.44709 -293.039038)
		(stroke
			(width 0.05715)
			(type default)
		)
		(layer "In6.Cu")
	)
	(gr_line
		(start 356.447852 -291.418518)
		(end 356.44709 -291.419026)
		(stroke
			(width 0.05715)
			(type default)
		)
		(layer "In6.Cu")
	)
	(gr_line
		(start 356.447852 -289.798506)
		(end 356.44709 -289.799014)
		(stroke
			(width 0.05715)
			(type default)
		)
		(layer "In6.Cu")
	)
	(gr_line
		(start 356.448106 -294.658542)
		(end 356.44709 -294.65905)
		(stroke
			(width 0.05715)
			(type default)
		)
		(layer "In6.Cu")
	)
	(gr_line
		(start 356.44836 -294.013636)
		(end 356.448868 -294.01389)
		(stroke
			(width 0.05715)
			(type default)
		)
		(layer "In6.Cu")
	)
	(gr_line
		(start 356.44836 -292.393624)
		(end 356.448868 -292.393878)
		(stroke
			(width 0.05715)
			(type default)
		)
		(layer "In6.Cu")
	)
	(gr_line
		(start 356.44836 -290.773612)
		(end 356.448868 -290.773866)
		(stroke
			(width 0.05715)
			(type default)
		)
		(layer "In6.Cu")
	)
	(gr_line
		(start 356.44836 -289.1536)
		(end 356.448868 -289.153854)
		(stroke
			(width 0.05715)
			(type default)
		)
		(layer "In6.Cu")
	)
	(gr_line
		(start 356.44836 -285.91383)
		(end 356.448868 -285.914084)
		(stroke
			(width 0.05715)
			(type default)
		)
		(layer "In6.Cu")
	)
	(gr_line
		(start 356.448614 -294.658288)
		(end 356.448106 -294.658542)
		(stroke
			(width 0.05715)
			(type default)
		)
		(layer "In6.Cu")
	)
	(gr_line
		(start 356.448868 -294.01389)
		(end 356.451662 -294.015414)
		(stroke
			(width 0.05715)
			(type default)
		)
		(layer "In6.Cu")
	)
	(gr_line
		(start 356.448868 -292.393878)
		(end 356.451662 -292.395402)
		(stroke
			(width 0.05715)
			(type default)
		)
		(layer "In6.Cu")
	)
	(gr_line
		(start 356.448868 -290.773866)
		(end 356.451662 -290.77539)
		(stroke
			(width 0.05715)
			(type default)
		)
		(layer "In6.Cu")
	)
	(gr_line
		(start 356.448868 -289.153854)
		(end 356.451662 -289.155378)
		(stroke
			(width 0.05715)
			(type default)
		)
		(layer "In6.Cu")
	)
	(gr_line
		(start 356.448868 -285.914084)
		(end 356.451662 -285.915608)
		(stroke
			(width 0.05715)
			(type default)
		)
		(layer "In6.Cu")
	)
	(gr_line
		(start 356.540562 -294.82542)
		(end 356.538022 -294.826944)
		(stroke
			(width 0.05715)
			(type default)
		)
		(layer "In6.Cu")
	)
	(gr_line
		(start 356.542086 -294.824658)
		(end 356.540562 -294.82542)
		(stroke
			(width 0.05715)
			(type default)
		)
		(layer "In6.Cu")
	)
	(gr_line
		(start 356.543356 -294.823896)
		(end 356.542086 -294.824658)
		(stroke
			(width 0.05715)
			(type default)
		)
		(layer "In6.Cu")
	)
	(gr_line
		(start 356.543356 -293.203884)
		(end 356.542848 -293.204138)
		(stroke
			(width 0.05715)
			(type default)
		)
		(layer "In6.Cu")
	)
	(gr_line
		(start 356.543356 -291.583872)
		(end 356.542848 -291.584126)
		(stroke
			(width 0.05715)
			(type default)
		)
		(layer "In6.Cu")
	)
	(gr_line
		(start 356.543356 -289.96386)
		(end 356.542848 -289.964114)
		(stroke
			(width 0.05715)
			(type default)
		)
		(layer "In6.Cu")
	)
	(gr_line
		(start 356.543864 -293.20363)
		(end 356.543356 -293.203884)
		(stroke
			(width 0.05715)
			(type default)
		)
		(layer "In6.Cu")
	)
	(gr_line
		(start 356.543864 -291.583618)
		(end 356.543356 -291.583872)
		(stroke
			(width 0.05715)
			(type default)
		)
		(layer "In6.Cu")
	)
	(gr_line
		(start 356.543864 -289.963606)
		(end 356.543356 -289.96386)
		(stroke
			(width 0.05715)
			(type default)
		)
		(layer "In6.Cu")
	)
	(gr_line
		(start 356.544118 -293.848536)
		(end 356.545134 -293.849044)
		(stroke
			(width 0.05715)
			(type default)
		)
		(layer "In6.Cu")
	)
	(gr_line
		(start 356.544118 -292.228524)
		(end 356.545134 -292.229032)
		(stroke
			(width 0.05715)
			(type default)
		)
		(layer "In6.Cu")
	)
	(gr_line
		(start 356.544118 -290.608512)
		(end 356.545134 -290.60902)
		(stroke
			(width 0.05715)
			(type default)
		)
		(layer "In6.Cu")
	)
	(gr_line
		(start 356.544118 -288.9885)
		(end 356.545134 -288.989008)
		(stroke
			(width 0.05715)
			(type default)
		)
		(layer "In6.Cu")
	)
	(gr_line
		(start 356.544118 -285.74873)
		(end 356.545134 -285.749238)
		(stroke
			(width 0.05715)
			(type default)
		)
		(layer "In6.Cu")
	)
	(gr_line
		(start 356.545134 -293.849044)
		(end 356.546658 -293.85006)
		(stroke
			(width 0.05715)
			(type default)
		)
		(layer "In6.Cu")
	)
	(gr_line
		(start 356.545134 -292.229032)
		(end 356.546658 -292.230048)
		(stroke
			(width 0.05715)
			(type default)
		)
		(layer "In6.Cu")
	)
	(gr_line
		(start 356.545134 -290.60902)
		(end 356.546658 -290.610036)
		(stroke
			(width 0.05715)
			(type default)
		)
		(layer "In6.Cu")
	)
	(gr_line
		(start 356.545134 -288.989008)
		(end 356.546658 -288.990024)
		(stroke
			(width 0.05715)
			(type default)
		)
		(layer "In6.Cu")
	)
	(gr_line
		(start 356.545134 -285.749238)
		(end 356.546658 -285.750254)
		(stroke
			(width 0.05715)
			(type default)
		)
		(layer "In6.Cu")
	)
	(gr_line
		(start 356.546658 -293.85006)
		(end 356.547674 -293.850568)
		(stroke
			(width 0.05715)
			(type default)
		)
		(layer "In6.Cu")
	)
	(gr_line
		(start 356.546658 -292.230048)
		(end 356.547674 -292.230556)
		(stroke
			(width 0.05715)
			(type default)
		)
		(layer "In6.Cu")
	)
	(gr_line
		(start 356.546658 -290.610036)
		(end 356.547674 -290.610544)
		(stroke
			(width 0.05715)
			(type default)
		)
		(layer "In6.Cu")
	)
	(gr_line
		(start 356.546658 -288.990024)
		(end 356.547674 -288.990532)
		(stroke
			(width 0.05715)
			(type default)
		)
		(layer "In6.Cu")
	)
	(gr_line
		(start 356.546658 -285.750254)
		(end 356.547674 -285.750762)
		(stroke
			(width 0.05715)
			(type default)
		)
		(layer "In6.Cu")
	)
	(gr_line
		(start 356.547674 -293.850568)
		(end 356.552754 -293.853616)
		(stroke
			(width 0.05715)
			(type default)
		)
		(layer "In6.Cu")
	)
	(gr_line
		(start 356.547674 -292.230556)
		(end 356.552754 -292.233604)
		(stroke
			(width 0.05715)
			(type default)
		)
		(layer "In6.Cu")
	)
	(gr_line
		(start 356.547674 -290.610544)
		(end 356.552754 -290.613592)
		(stroke
			(width 0.05715)
			(type default)
		)
		(layer "In6.Cu")
	)
	(gr_line
		(start 356.547674 -288.990532)
		(end 356.552754 -288.99358)
		(stroke
			(width 0.05715)
			(type default)
		)
		(layer "In6.Cu")
	)
	(gr_line
		(start 356.547674 -285.750762)
		(end 356.552754 -285.75381)
		(stroke
			(width 0.05715)
			(type default)
		)
		(layer "In6.Cu")
	)
	(gr_line
		(start 356.731062 -285.42615)
		(end 357.029004 -285.42615)
		(stroke
			(width 0.05715)
			(type default)
		)
		(layer "In6.Cu")
	)
	(gr_line
		(start 356.731062 -283.806138)
		(end 357.029004 -283.806138)
		(stroke
			(width 0.05715)
			(type default)
		)
		(layer "In6.Cu")
	)
	(gr_line
		(start 356.731062 -282.186126)
		(end 357.029004 -282.186126)
		(stroke
			(width 0.05715)
			(type default)
		)
		(layer "In6.Cu")
	)
	(gr_line
		(start 357.029004 -285.42615)
		(end 357.111808 -285.508954)
		(stroke
			(width 0.05715)
			(type default)
		)
		(layer "In6.Cu")
	)
	(gr_line
		(start 357.029004 -283.806138)
		(end 357.111808 -283.888942)
		(stroke
			(width 0.05715)
			(type default)
		)
		(layer "In6.Cu")
	)
	(gr_line
		(start 357.029004 -282.186126)
		(end 357.111808 -282.26893)
		(stroke
			(width 0.05715)
			(type default)
		)
		(layer "In6.Cu")
	)
	(gr_line
		(start 357.059992 -295.519602)
		(end 357.059992 -295.54805)
		(stroke
			(width 0.05715)
			(type default)
		)
		(layer "In6.Cu")
	)
	(gr_line
		(start 357.105712 -295.473882)
		(end 357.059992 -295.519602)
		(stroke
			(width 0.05715)
			(type default)
		)
		(layer "In6.Cu")
	)
	(gr_line
		(start 357.105712 -295.473882)
		(end 357.105458 -295.473628)
		(stroke
			(width 0.05715)
			(type default)
		)
		(layer "In6.Cu")
	)
	(gr_arc
		(start 357.111808 -285.508954)
		(mid 357.1136 -285.520276)
		(end 357.115618 -285.53156)
		(stroke
			(width 0.05715)
			(type default)
		)
		(layer "In6.Cu")
	)
	(gr_arc
		(start 357.111808 -283.888942)
		(mid 357.113599 -283.900264)
		(end 357.115618 -283.911548)
		(stroke
			(width 0.05715)
			(type default)
		)
		(layer "In6.Cu")
	)
	(gr_arc
		(start 357.111808 -282.26893)
		(mid 357.113599 -282.280252)
		(end 357.115618 -282.291536)
		(stroke
			(width 0.05715)
			(type default)
		)
		(layer "In6.Cu")
	)
	(gr_line
		(start 357.296212 -295.473882)
		(end 357.296466 -295.473628)
		(stroke
			(width 0.05715)
			(type default)
		)
		(layer "In6.Cu")
	)
	(gr_line
		(start 357.296212 -295.473882)
		(end 357.341932 -295.519602)
		(stroke
			(width 0.05715)
			(type default)
		)
		(layer "In6.Cu")
	)
	(gr_line
		(start 357.296466 -295.39438)
		(end 357.296466 -295.394888)
		(stroke
			(width 0.05715)
			(type default)
		)
		(layer "In6.Cu")
	)
	(gr_arc
		(start 357.340916 -285.885128)
		(mid 357.344968 -285.88794)
		(end 357.349044 -285.890716)
		(stroke
			(width 0.05715)
			(type default)
		)
		(layer "In6.Cu")
	)
	(gr_arc
		(start 357.340916 -282.645104)
		(mid 357.344968 -282.647916)
		(end 357.349044 -282.650692)
		(stroke
			(width 0.05715)
			(type default)
		)
		(layer "In6.Cu")
	)
	(gr_arc
		(start 357.34117 -289.124898)
		(mid 357.345095 -289.127709)
		(end 357.349044 -289.130486)
		(stroke
			(width 0.05715)
			(type default)
		)
		(layer "In6.Cu")
	)
	(gr_line
		(start 357.341678 -287.505394)
		(end 357.34117 -287.504886)
		(stroke
			(width 0.05715)
			(type default)
		)
		(layer "In6.Cu")
	)
	(gr_line
		(start 357.341932 -295.519602)
		(end 357.341932 -295.54805)
		(stroke
			(width 0.05715)
			(type default)
		)
		(layer "In6.Cu")
	)
	(gr_arc
		(start 357.346758 -286.582866)
		(mid 357.342554 -286.585768)
		(end 357.338376 -286.588708)
		(stroke
			(width 0.05715)
			(type default)
		)
		(layer "In6.Cu")
	)
	(gr_line
		(start 357.346758 -286.582866)
		(end 357.347012 -286.582866)
		(stroke
			(width 0.05715)
			(type default)
		)
		(layer "In6.Cu")
	)
	(gr_line
		(start 357.349044 -289.130486)
		(end 357.355902 -289.13455)
		(stroke
			(width 0.05715)
			(type default)
		)
		(layer "In6.Cu")
	)
	(gr_line
		(start 357.349044 -285.890716)
		(end 357.355902 -285.89478)
		(stroke
			(width 0.05715)
			(type default)
		)
		(layer "In6.Cu")
	)
	(gr_line
		(start 357.349044 -282.650692)
		(end 357.355902 -282.654756)
		(stroke
			(width 0.05715)
			(type default)
		)
		(layer "In6.Cu")
	)
	(gr_line
		(start 357.354632 -286.578548)
		(end 357.347012 -286.582866)
		(stroke
			(width 0.05715)
			(type default)
		)
		(layer "In6.Cu")
	)
	(gr_line
		(start 357.355902 -289.13455)
		(end 357.356664 -289.135058)
		(stroke
			(width 0.05715)
			(type default)
		)
		(layer "In6.Cu")
	)
	(gr_line
		(start 357.355902 -285.89478)
		(end 357.356664 -285.895288)
		(stroke
			(width 0.05715)
			(type default)
		)
		(layer "In6.Cu")
	)
	(gr_line
		(start 357.355902 -282.654756)
		(end 357.356664 -282.655264)
		(stroke
			(width 0.05715)
			(type default)
		)
		(layer "In6.Cu")
	)
	(gr_line
		(start 357.356664 -289.135058)
		(end 357.357426 -289.135566)
		(stroke
			(width 0.05715)
			(type default)
		)
		(layer "In6.Cu")
	)
	(gr_line
		(start 357.356664 -285.895288)
		(end 357.357426 -285.895796)
		(stroke
			(width 0.05715)
			(type default)
		)
		(layer "In6.Cu")
	)
	(gr_line
		(start 357.356664 -282.655264)
		(end 357.357426 -282.655772)
		(stroke
			(width 0.05715)
			(type default)
		)
		(layer "In6.Cu")
	)
	(gr_line
		(start 357.373174 -285.42615)
		(end 357.303832 -285.495492)
		(stroke
			(width 0.05715)
			(type default)
		)
		(layer "In6.Cu")
	)
	(gr_line
		(start 357.373174 -283.806138)
		(end 357.303832 -283.87548)
		(stroke
			(width 0.05715)
			(type default)
		)
		(layer "In6.Cu")
	)
	(gr_line
		(start 357.373174 -282.186126)
		(end 357.303832 -282.255468)
		(stroke
			(width 0.05715)
			(type default)
		)
		(layer "In6.Cu")
	)
	(gr_line
		(start 357.384604 -292.391338)
		(end 357.387144 -292.392862)
		(stroke
			(width 0.05715)
			(type default)
		)
		(layer "In6.Cu")
	)
	(gr_line
		(start 357.38816 -291.418518)
		(end 357.387144 -291.419026)
		(stroke
			(width 0.05715)
			(type default)
		)
		(layer "In6.Cu")
	)
	(gr_line
		(start 357.38816 -289.798506)
		(end 357.387144 -289.799014)
		(stroke
			(width 0.05715)
			(type default)
		)
		(layer "In6.Cu")
	)
	(gr_line
		(start 357.388414 -289.1536)
		(end 357.388922 -289.153854)
		(stroke
			(width 0.05715)
			(type default)
		)
		(layer "In6.Cu")
	)
	(gr_line
		(start 357.388922 -289.797998)
		(end 357.38816 -289.798506)
		(stroke
			(width 0.05715)
			(type default)
		)
		(layer "In6.Cu")
	)
	(gr_line
		(start 357.388922 -289.153854)
		(end 357.391716 -289.155378)
		(stroke
			(width 0.05715)
			(type default)
		)
		(layer "In6.Cu")
	)
	(gr_line
		(start 357.390192 -289.797236)
		(end 357.388922 -289.797998)
		(stroke
			(width 0.05715)
			(type default)
		)
		(layer "In6.Cu")
	)
	(gr_line
		(start 357.39324 -293.035482)
		(end 357.392224 -293.036244)
		(stroke
			(width 0.05715)
			(type default)
		)
		(layer "In6.Cu")
	)
	(gr_line
		(start 357.39578 -284.297882)
		(end 357.39705 -284.298644)
		(stroke
			(width 0.05715)
			(type default)
		)
		(layer "In6.Cu")
	)
	(gr_line
		(start 357.40721 -285.924498)
		(end 357.409496 -285.926022)
		(stroke
			(width 0.05715)
			(type default)
		)
		(layer "In6.Cu")
	)
	(gr_line
		(start 357.40975 -294.025828)
		(end 357.409496 -294.025828)
		(stroke
			(width 0.05715)
			(type default)
		)
		(layer "In6.Cu")
	)
	(gr_line
		(start 357.40975 -285.926022)
		(end 357.409496 -285.926022)
		(stroke
			(width 0.05715)
			(type default)
		)
		(layer "In6.Cu")
	)
	(gr_line
		(start 357.410004 -286.54629)
		(end 357.409496 -286.54629)
		(stroke
			(width 0.05715)
			(type default)
		)
		(layer "In6.Cu")
	)
	(gr_line
		(start 357.469186 -293.8399)
		(end 357.470964 -293.840916)
		(stroke
			(width 0.05715)
			(type default)
		)
		(layer "In6.Cu")
	)
	(gr_line
		(start 357.479854 -282.506166)
		(end 357.480616 -282.506674)
		(stroke
			(width 0.05715)
			(type default)
		)
		(layer "In6.Cu")
	)
	(gr_line
		(start 357.480616 -282.506674)
		(end 357.48214 -282.507436)
		(stroke
			(width 0.05715)
			(type default)
		)
		(layer "In6.Cu")
	)
	(gr_line
		(start 357.48214 -282.507436)
		(end 357.482902 -282.507944)
		(stroke
			(width 0.05715)
			(type default)
		)
		(layer "In6.Cu")
	)
	(gr_line
		(start 357.48341 -291.583872)
		(end 357.48214 -291.584634)
		(stroke
			(width 0.05715)
			(type default)
		)
		(layer "In6.Cu")
	)
	(gr_line
		(start 357.48341 -289.96386)
		(end 357.48214 -289.964622)
		(stroke
			(width 0.05715)
			(type default)
		)
		(layer "In6.Cu")
	)
	(gr_line
		(start 357.48341 -288.987992)
		(end 357.484172 -288.9885)
		(stroke
			(width 0.05715)
			(type default)
		)
		(layer "In6.Cu")
	)
	(gr_line
		(start 357.483664 -290.608258)
		(end 357.484172 -290.608512)
		(stroke
			(width 0.05715)
			(type default)
		)
		(layer "In6.Cu")
	)
	(gr_line
		(start 357.483918 -293.203376)
		(end 357.48087 -293.2049)
		(stroke
			(width 0.05715)
			(type default)
		)
		(layer "In6.Cu")
	)
	(gr_line
		(start 357.483918 -291.583618)
		(end 357.48341 -291.583872)
		(stroke
			(width 0.05715)
			(type default)
		)
		(layer "In6.Cu")
	)
	(gr_line
		(start 357.483918 -289.963606)
		(end 357.48341 -289.96386)
		(stroke
			(width 0.05715)
			(type default)
		)
		(layer "In6.Cu")
	)
	(gr_line
		(start 357.484172 -288.343594)
		(end 357.483918 -288.34334)
		(stroke
			(width 0.05715)
			(type default)
		)
		(layer "In6.Cu")
	)
	(gr_line
		(start 357.50373 -293.859966)
		(end 357.504746 -293.860474)
		(stroke
			(width 0.05715)
			(type default)
		)
		(layer "In6.Cu")
	)
	(gr_line
		(start 357.504746 -293.860474)
		(end 357.505508 -293.860982)
		(stroke
			(width 0.05715)
			(type default)
		)
		(layer "In6.Cu")
	)
	(gr_arc
		(start 357.579676 -283.030168)
		(mid 357.579802 -283.031057)
		(end 357.57993 -283.031946)
		(stroke
			(width 0.05715)
			(type default)
		)
		(layer "In6.Cu")
	)
	(gr_line
		(start 357.580184 -283.033216)
		(end 357.57993 -283.031946)
		(stroke
			(width 0.05715)
			(type default)
		)
		(layer "In6.Cu")
	)
	(gr_line
		(start 357.671116 -285.42615)
		(end 357.373174 -285.42615)
		(stroke
			(width 0.05715)
			(type default)
		)
		(layer "In6.Cu")
	)
	(gr_line
		(start 357.671116 -283.806138)
		(end 357.373174 -283.806138)
		(stroke
			(width 0.05715)
			(type default)
		)
		(layer "In6.Cu")
	)
	(gr_line
		(start 357.671116 -282.186126)
		(end 357.373174 -282.186126)
		(stroke
			(width 0.05715)
			(type default)
		)
		(layer "In6.Cu")
	)
	(gr_line
		(start 357.85806 -285.10357)
		(end 357.858568 -285.103824)
		(stroke
			(width 0.05715)
			(type default)
		)
		(layer "In6.Cu")
	)
	(gr_line
		(start 358.000046 -295.552876)
		(end 358.000046 -295.581324)
		(stroke
			(width 0.05715)
			(type default)
		)
		(layer "In6.Cu")
	)
	(gr_line
		(start 358.045766 -295.507156)
		(end 358.000046 -295.552876)
		(stroke
			(width 0.05715)
			(type default)
		)
		(layer "In6.Cu")
	)
	(gr_line
		(start 358.236266 -295.507156)
		(end 358.281986 -295.552876)
		(stroke
			(width 0.05715)
			(type default)
		)
		(layer "In6.Cu")
	)
	(gr_line
		(start 358.281986 -295.552876)
		(end 358.281986 -295.581324)
		(stroke
			(width 0.05715)
			(type default)
		)
		(layer "In6.Cu")
	)
	(gr_arc
		(start 358.282494 -285.886144)
		(mid 358.31017 -285.904625)
		(end 358.338882 -285.92145)
		(stroke
			(width 0.05715)
			(type default)
		)
		(layer "In6.Cu")
	)
	(gr_arc
		(start 358.282748 -290.745926)
		(mid 358.285156 -290.747711)
		(end 358.287574 -290.749482)
		(stroke
			(width 0.05715)
			(type default)
		)
		(layer "In6.Cu")
	)
	(gr_arc
		(start 358.289098 -286.581342)
		(mid 358.284382 -286.58462)
		(end 358.2797 -286.587946)
		(stroke
			(width 0.05715)
			(type default)
		)
		(layer "In6.Cu")
	)
	(gr_line
		(start 358.294432 -287.513776)
		(end 358.299258 -287.51657)
		(stroke
			(width 0.05715)
			(type default)
		)
		(layer "In6.Cu")
	)
	(gr_line
		(start 358.295956 -286.577532)
		(end 358.295956 -286.577278)
		(stroke
			(width 0.05715)
			(type default)
		)
		(layer "In6.Cu")
	)
	(gr_line
		(start 358.295956 -286.577278)
		(end 358.289098 -286.581342)
		(stroke
			(width 0.05715)
			(type default)
		)
		(layer "In6.Cu")
	)
	(gr_arc
		(start 358.315514 -294.006016)
		(mid 358.317544 -294.007163)
		(end 358.319578 -294.008302)
		(stroke
			(width 0.05715)
			(type default)
		)
		(layer "In6.Cu")
	)
	(gr_line
		(start 358.32796 -294.013382)
		(end 358.328214 -294.013382)
		(stroke
			(width 0.05715)
			(type default)
		)
		(layer "In6.Cu")
	)
	(gr_line
		(start 358.328214 -293.03853)
		(end 358.32796 -293.038784)
		(stroke
			(width 0.05715)
			(type default)
		)
		(layer "In6.Cu")
	)
	(gr_line
		(start 358.338882 -285.92145)
		(end 358.341168 -285.92145)
		(stroke
			(width 0.05715)
			(type default)
		)
		(layer "In6.Cu")
	)
	(gr_line
		(start 358.39527 -285.73095)
		(end 358.395778 -285.73095)
		(stroke
			(width 0.05715)
			(type default)
		)
		(layer "In6.Cu")
	)
	(gr_line
		(start 358.395778 -285.73095)
		(end 358.42448 -285.747714)
		(stroke
			(width 0.05715)
			(type default)
		)
		(layer "In6.Cu")
	)
	(gr_line
		(start 358.423972 -293.203376)
		(end 358.424226 -293.203376)
		(stroke
			(width 0.05715)
			(type default)
		)
		(layer "In6.Cu")
	)
	(gr_line
		(start 358.42448 -285.747714)
		(end 358.424734 -285.747968)
		(stroke
			(width 0.05715)
			(type default)
		)
		(layer "In6.Cu")
	)
	(gr_arc
		(start 358.44607 -285.760922)
		(mid 358.435473 -285.754328)
		(end 358.424734 -285.747968)
		(stroke
			(width 0.05715)
			(type default)
		)
		(layer "In6.Cu")
	)
	(gr_line
		(start 358.45623 -293.867332)
		(end 358.461564 -293.87038)
		(stroke
			(width 0.05715)
			(type default)
		)
		(layer "In6.Cu")
	)
	(gr_arc
		(start 358.463088 -293.871396)
		(mid 358.462326 -293.870887)
		(end 358.461564 -293.87038)
		(stroke
			(width 0.05715)
			(type default)
		)
		(layer "In6.Cu")
	)
	(gr_line
		(start 358.463088 -293.871396)
		(end 358.468676 -293.875206)
		(stroke
			(width 0.05715)
			(type default)
		)
		(layer "In6.Cu")
	)
	(gr_line
		(start 358.865932 -284.813756)
		(end 358.86644 -284.814264)
		(stroke
			(width 0.05715)
			(type default)
		)
		(layer "In6.Cu")
	)
	(gr_line
		(start 358.86644 -284.878272)
		(end 358.886506 -284.898338)
		(stroke
			(width 0.05715)
			(type default)
		)
		(layer "In6.Cu")
	)
	(gr_line
		(start 358.86644 -284.814264)
		(end 358.86644 -284.878272)
		(stroke
			(width 0.05715)
			(type default)
		)
		(layer "In6.Cu")
	)
	(gr_line
		(start 359.001822 -284.678882)
		(end 359.06583 -284.678882)
		(stroke
			(width 0.05715)
			(type default)
		)
		(layer "In6.Cu")
	)
	(gr_line
		(start 359.06583 -284.678882)
		(end 359.085896 -284.698948)
		(stroke
			(width 0.05715)
			(type default)
		)
		(layer "In6.Cu")
	)
	(gr_line
		(start 361.007406 -284.64256)
		(end 361.027472 -284.622494)
		(stroke
			(width 0.05715)
			(type default)
		)
		(layer "In6.Cu")
	)
	(gr_line
		(start 361.027472 -284.622494)
		(end 361.09148 -284.622748)
		(stroke
			(width 0.05715)
			(type default)
		)
		(layer "In6.Cu")
	)
	(gr_line
		(start 361.09148 -284.622748)
		(end 361.091988 -284.621986)
		(stroke
			(width 0.05715)
			(type default)
		)
		(layer "In6.Cu")
	)
	(gr_line
		(start 361.206796 -284.84195)
		(end 361.226862 -284.821884)
		(stroke
			(width 0.05715)
			(type default)
		)
		(layer "In6.Cu")
	)
	(gr_line
		(start 361.226862 -284.821884)
		(end 361.226862 -284.75813)
		(stroke
			(width 0.05715)
			(type default)
		)
		(layer "In6.Cu")
	)
	(gr_line
		(start 361.304586 -320.922904)
		(end 361.304586 -320.923158)
		(stroke
			(width 0.07112)
			(type default)
		)
		(layer "In6.Cu")
	)
	(gr_arc
		(start 361.413044 -378.96927)
		(mid 361.412148 -378.97168)
		(end 361.411266 -378.974096)
		(stroke
			(width 0.07112)
			(type default)
		)
		(layer "In6.Cu")
	)
	(gr_arc
		(start 361.416092 -378.96165)
		(mid 361.414809 -378.96482)
		(end 361.413552 -378.968)
		(stroke
			(width 0.07112)
			(type default)
		)
		(layer "In6.Cu")
	)
	(gr_line
		(start 361.416092 -378.96165)
		(end 361.415838 -378.96165)
		(stroke
			(width 0.07112)
			(type default)
		)
		(layer "In6.Cu")
	)
	(gr_line
		(start 361.416854 -378.959618)
		(end 361.415838 -378.96165)
		(stroke
			(width 0.07112)
			(type default)
		)
		(layer "In6.Cu")
	)
	(gr_line
		(start 361.60837 -286.72155)
		(end 361.607862 -286.721296)
		(stroke
			(width 0.05715)
			(type default)
		)
		(layer "In6.Cu")
	)
	(gr_arc
		(start 361.60964 -285.75)
		(mid 361.608496 -285.750634)
		(end 361.607354 -285.75127)
		(stroke
			(width 0.05715)
			(type default)
		)
		(layer "In6.Cu")
	)
	(gr_line
		(start 361.60964 -285.75)
		(end 361.611926 -285.74873)
		(stroke
			(width 0.05715)
			(type default)
		)
		(layer "In6.Cu")
	)
	(gr_line
		(start 361.611672 -284.128972)
		(end 361.611926 -284.128718)
		(stroke
			(width 0.05715)
			(type default)
		)
		(layer "In6.Cu")
	)
	(gr_line
		(start 361.611926 -292.22827)
		(end 361.612434 -292.228016)
		(stroke
			(width 0.05715)
			(type default)
		)
		(layer "In6.Cu")
	)
	(gr_line
		(start 361.611926 -285.74873)
		(end 361.612434 -285.748476)
		(stroke
			(width 0.05715)
			(type default)
		)
		(layer "In6.Cu")
	)
	(gr_line
		(start 361.612434 -293.203884)
		(end 361.611672 -293.203376)
		(stroke
			(width 0.05715)
			(type default)
		)
		(layer "In6.Cu")
	)
	(gr_line
		(start 361.612434 -292.228016)
		(end 361.613704 -292.227254)
		(stroke
			(width 0.05715)
			(type default)
		)
		(layer "In6.Cu")
	)
	(gr_line
		(start 361.613704 -293.204646)
		(end 361.612434 -293.203884)
		(stroke
			(width 0.05715)
			(type default)
		)
		(layer "In6.Cu")
	)
	(gr_line
		(start 361.705398 -285.914846)
		(end 361.707176 -285.91383)
		(stroke
			(width 0.05715)
			(type default)
		)
		(layer "In6.Cu")
	)
	(gr_line
		(start 361.706922 -293.038022)
		(end 361.702858 -293.035736)
		(stroke
			(width 0.05715)
			(type default)
		)
		(layer "In6.Cu")
	)
	(gr_line
		(start 361.706922 -292.393878)
		(end 361.707684 -292.39337)
		(stroke
			(width 0.05715)
			(type default)
		)
		(layer "In6.Cu")
	)
	(gr_line
		(start 361.707176 -285.91383)
		(end 361.707938 -285.913322)
		(stroke
			(width 0.05715)
			(type default)
		)
		(layer "In6.Cu")
	)
	(gr_line
		(start 361.70743 -286.558482)
		(end 361.705398 -286.557466)
		(stroke
			(width 0.05715)
			(type default)
		)
		(layer "In6.Cu")
	)
	(gr_line
		(start 361.707684 -293.03853)
		(end 361.706922 -293.038022)
		(stroke
			(width 0.05715)
			(type default)
		)
		(layer "In6.Cu")
	)
	(gr_line
		(start 361.707684 -292.39337)
		(end 361.7087 -292.392862)
		(stroke
			(width 0.05715)
			(type default)
		)
		(layer "In6.Cu")
	)
	(gr_line
		(start 361.7087 -293.039038)
		(end 361.707684 -293.03853)
		(stroke
			(width 0.05715)
			(type default)
		)
		(layer "In6.Cu")
	)
	(gr_line
		(start 361.709462 -289.15233)
		(end 361.712256 -289.150806)
		(stroke
			(width 0.05715)
			(type default)
		)
		(layer "In6.Cu")
	)
	(gr_line
		(start 361.711748 -288.18078)
		(end 361.708446 -288.179002)
		(stroke
			(width 0.05715)
			(type default)
		)
		(layer "In6.Cu")
	)
	(gr_arc
		(start 361.712256 -289.150806)
		(mid 361.7134 -289.150172)
		(end 361.714542 -289.149536)
		(stroke
			(width 0.05715)
			(type default)
		)
		(layer "In6.Cu")
	)
	(gr_line
		(start 361.737402 -285.896304)
		(end 361.745276 -285.891732)
		(stroke
			(width 0.05715)
			(type default)
		)
		(layer "In6.Cu")
	)
	(gr_arc
		(start 361.745276 -285.891732)
		(mid 361.746038 -285.891225)
		(end 361.7468 -285.890716)
		(stroke
			(width 0.05715)
			(type default)
		)
		(layer "In6.Cu")
	)
	(gr_arc
		(start 361.747562 -285.890208)
		(mid 361.747181 -285.890462)
		(end 361.7468 -285.890716)
		(stroke
			(width 0.05715)
			(type default)
		)
		(layer "In6.Cu")
	)
	(gr_arc
		(start 361.748324 -285.8897)
		(mid 361.750742 -285.887928)
		(end 361.75315 -285.886144)
		(stroke
			(width 0.05715)
			(type default)
		)
		(layer "In6.Cu")
	)
	(gr_line
		(start 362.081318 -284.938978)
		(end 362.081826 -284.938724)
		(stroke
			(width 0.05715)
			(type default)
		)
		(layer "In6.Cu")
	)
	(gr_line
		(start 362.081826 -284.938724)
		(end 362.082588 -284.938216)
		(stroke
			(width 0.05715)
			(type default)
		)
		(layer "In6.Cu")
	)
	(gr_line
		(start 362.223812 -296.353484)
		(end 362.223812 -296.325036)
		(stroke
			(width 0.05715)
			(type default)
		)
		(layer "In6.Cu")
	)
	(gr_line
		(start 362.223812 -296.325036)
		(end 362.269532 -296.279316)
		(stroke
			(width 0.05715)
			(type default)
		)
		(layer "In6.Cu")
	)
	(gr_line
		(start 362.269532 -295.95572)
		(end 362.269278 -295.955974)
		(stroke
			(width 0.05715)
			(type default)
		)
		(layer "In6.Cu")
	)
	(gr_arc
		(start 362.269532 -287.85185)
		(mid 362.269528 -287.854009)
		(end 362.269532 -287.856168)
		(stroke
			(width 0.05715)
			(type default)
		)
		(layer "In6.Cu")
	)
	(gr_arc
		(start 362.269532 -286.229552)
		(mid 362.269522 -286.232854)
		(end 362.269532 -286.236156)
		(stroke
			(width 0.05715)
			(type default)
		)
		(layer "In6.Cu")
	)
	(gr_line
		(start 362.272326 -284.584648)
		(end 362.27258 -284.583124)
		(stroke
			(width 0.05715)
			(type default)
		)
		(layer "In6.Cu")
	)
	(gr_arc
		(start 362.272834 -284.581092)
		(mid 362.272706 -284.582108)
		(end 362.27258 -284.583124)
		(stroke
			(width 0.05715)
			(type default)
		)
		(layer "In6.Cu")
	)
	(gr_line
		(start 362.487718 -381.221488)
		(end 362.56849 -381.39624)
		(stroke
			(width 0.07112)
			(type default)
		)
		(layer "In6.Cu")
	)
	(gr_line
		(start 362.505752 -296.353484)
		(end 362.505752 -296.325036)
		(stroke
			(width 0.05715)
			(type default)
		)
		(layer "In6.Cu")
	)
	(gr_line
		(start 362.505752 -296.325036)
		(end 362.460032 -296.279316)
		(stroke
			(width 0.05715)
			(type default)
		)
		(layer "In6.Cu")
	)
	(gr_line
		(start 362.54436 -293.199058)
		(end 362.54309 -293.198296)
		(stroke
			(width 0.05715)
			(type default)
		)
		(layer "In6.Cu")
	)
	(gr_line
		(start 362.5469 -293.200582)
		(end 362.546138 -293.200074)
		(stroke
			(width 0.05715)
			(type default)
		)
		(layer "In6.Cu")
	)
	(gr_line
		(start 362.549186 -293.201852)
		(end 362.54817 -293.201344)
		(stroke
			(width 0.05715)
			(type default)
		)
		(layer "In6.Cu")
	)
	(gr_arc
		(start 362.54944 -294.822118)
		(mid 362.549059 -294.821864)
		(end 362.548678 -294.82161)
		(stroke
			(width 0.05715)
			(type default)
		)
		(layer "In6.Cu")
	)
	(gr_arc
		(start 362.54944 -293.849806)
		(mid 362.548296 -293.85044)
		(end 362.547154 -293.851076)
		(stroke
			(width 0.05715)
			(type default)
		)
		(layer "In6.Cu")
	)
	(gr_line
		(start 362.54944 -293.849806)
		(end 362.551726 -293.848536)
		(stroke
			(width 0.05715)
			(type default)
		)
		(layer "In6.Cu")
	)
	(gr_arc
		(start 362.54944 -289.962082)
		(mid 362.549059 -289.961828)
		(end 362.548678 -289.961574)
		(stroke
			(width 0.05715)
			(type default)
		)
		(layer "In6.Cu")
	)
	(gr_arc
		(start 362.54944 -288.98977)
		(mid 362.548296 -288.990404)
		(end 362.547154 -288.99104)
		(stroke
			(width 0.05715)
			(type default)
		)
		(layer "In6.Cu")
	)
	(gr_line
		(start 362.54944 -288.98977)
		(end 362.551726 -288.9885)
		(stroke
			(width 0.05715)
			(type default)
		)
		(layer "In6.Cu")
	)
	(gr_line
		(start 362.55071 -293.202868)
		(end 362.549186 -293.201852)
		(stroke
			(width 0.05715)
			(type default)
		)
		(layer "In6.Cu")
	)
	(gr_line
		(start 362.55071 -292.229032)
		(end 362.551726 -292.228524)
		(stroke
			(width 0.05715)
			(type default)
		)
		(layer "In6.Cu")
	)
	(gr_line
		(start 362.551472 -282.738322)
		(end 362.55198 -282.737814)
		(stroke
			(width 0.05715)
			(type default)
		)
		(layer "In6.Cu")
	)
	(gr_line
		(start 362.551726 -294.823388)
		(end 362.54944 -294.822118)
		(stroke
			(width 0.05715)
			(type default)
		)
		(layer "In6.Cu")
	)
	(gr_line
		(start 362.551726 -293.848536)
		(end 362.552488 -293.848028)
		(stroke
			(width 0.05715)
			(type default)
		)
		(layer "In6.Cu")
	)
	(gr_line
		(start 362.551726 -293.203376)
		(end 362.55071 -293.202868)
		(stroke
			(width 0.05715)
			(type default)
		)
		(layer "In6.Cu")
	)
	(gr_line
		(start 362.551726 -292.228524)
		(end 362.552488 -292.228016)
		(stroke
			(width 0.05715)
			(type default)
		)
		(layer "In6.Cu")
	)
	(gr_line
		(start 362.551726 -289.963352)
		(end 362.54944 -289.962082)
		(stroke
			(width 0.05715)
			(type default)
		)
		(layer "In6.Cu")
	)
	(gr_line
		(start 362.551726 -288.9885)
		(end 362.552488 -288.987992)
		(stroke
			(width 0.05715)
			(type default)
		)
		(layer "In6.Cu")
	)
	(gr_line
		(start 362.55198 -290.608258)
		(end 362.552488 -290.608004)
		(stroke
			(width 0.05715)
			(type default)
		)
		(layer "In6.Cu")
	)
	(gr_line
		(start 362.55198 -285.748476)
		(end 362.552488 -285.748222)
		(stroke
			(width 0.05715)
			(type default)
		)
		(layer "In6.Cu")
	)
	(gr_line
		(start 362.552488 -294.823896)
		(end 362.551726 -294.823388)
		(stroke
			(width 0.05715)
			(type default)
		)
		(layer "In6.Cu")
	)
	(gr_line
		(start 362.552488 -293.848028)
		(end 362.553758 -293.847266)
		(stroke
			(width 0.05715)
			(type default)
		)
		(layer "In6.Cu")
	)
	(gr_line
		(start 362.552488 -292.228016)
		(end 362.553758 -292.227254)
		(stroke
			(width 0.05715)
			(type default)
		)
		(layer "In6.Cu")
	)
	(gr_line
		(start 362.552488 -291.583872)
		(end 362.551726 -291.583364)
		(stroke
			(width 0.05715)
			(type default)
		)
		(layer "In6.Cu")
	)
	(gr_line
		(start 362.552488 -290.608004)
		(end 362.553758 -290.607242)
		(stroke
			(width 0.05715)
			(type default)
		)
		(layer "In6.Cu")
	)
	(gr_line
		(start 362.552488 -289.96386)
		(end 362.551726 -289.963352)
		(stroke
			(width 0.05715)
			(type default)
		)
		(layer "In6.Cu")
	)
	(gr_line
		(start 362.552488 -285.748222)
		(end 362.553758 -285.74746)
		(stroke
			(width 0.05715)
			(type default)
		)
		(layer "In6.Cu")
	)
	(gr_line
		(start 362.553758 -294.824658)
		(end 362.552488 -294.823896)
		(stroke
			(width 0.05715)
			(type default)
		)
		(layer "In6.Cu")
	)
	(gr_line
		(start 362.553758 -291.584634)
		(end 362.552488 -291.583872)
		(stroke
			(width 0.05715)
			(type default)
		)
		(layer "In6.Cu")
	)
	(gr_line
		(start 362.553758 -289.964622)
		(end 362.552488 -289.96386)
		(stroke
			(width 0.05715)
			(type default)
		)
		(layer "In6.Cu")
	)
	(gr_line
		(start 362.557822 -294.826944)
		(end 362.556298 -294.825928)
		(stroke
			(width 0.05715)
			(type default)
		)
		(layer "In6.Cu")
	)
	(gr_line
		(start 362.557822 -291.58692)
		(end 362.556298 -291.585904)
		(stroke
			(width 0.05715)
			(type default)
		)
		(layer "In6.Cu")
	)
	(gr_line
		(start 362.557822 -289.966908)
		(end 362.556298 -289.965892)
		(stroke
			(width 0.05715)
			(type default)
		)
		(layer "In6.Cu")
	)
	(gr_line
		(start 362.558584 -294.827198)
		(end 362.557822 -294.826944)
		(stroke
			(width 0.05715)
			(type default)
		)
		(layer "In6.Cu")
	)
	(gr_line
		(start 362.558584 -289.967162)
		(end 362.557822 -289.966908)
		(stroke
			(width 0.05715)
			(type default)
		)
		(layer "In6.Cu")
	)
	(gr_line
		(start 362.558838 -293.20744)
		(end 362.557822 -293.206932)
		(stroke
			(width 0.05715)
			(type default)
		)
		(layer "In6.Cu")
	)
	(gr_line
		(start 362.558838 -291.587428)
		(end 362.557822 -291.58692)
		(stroke
			(width 0.05715)
			(type default)
		)
		(layer "In6.Cu")
	)
	(gr_line
		(start 362.559346 -293.207694)
		(end 362.558838 -293.20744)
		(stroke
			(width 0.05715)
			(type default)
		)
		(layer "In6.Cu")
	)
	(gr_line
		(start 362.559346 -291.587682)
		(end 362.558838 -291.587428)
		(stroke
			(width 0.05715)
			(type default)
		)
		(layer "In6.Cu")
	)
	(gr_line
		(start 362.605828 -380.899162)
		(end 362.487718 -381.221488)
		(stroke
			(width 0.07112)
			(type default)
		)
		(layer "In6.Cu")
	)
	(gr_line
		(start 362.645198 -294.014652)
		(end 362.648754 -294.012874)
		(stroke
			(width 0.05715)
			(type default)
		)
		(layer "In6.Cu")
	)
	(gr_line
		(start 362.645198 -289.154616)
		(end 362.646468 -289.153854)
		(stroke
			(width 0.05715)
			(type default)
		)
		(layer "In6.Cu")
	)
	(gr_line
		(start 362.645706 -292.39464)
		(end 362.646976 -292.393878)
		(stroke
			(width 0.05715)
			(type default)
		)
		(layer "In6.Cu")
	)
	(gr_line
		(start 362.646214 -282.674568)
		(end 362.647738 -282.673552)
		(stroke
			(width 0.05715)
			(type default)
		)
		(layer "In6.Cu")
	)
	(gr_line
		(start 362.646468 -289.153854)
		(end 362.647738 -289.153092)
		(stroke
			(width 0.05715)
			(type default)
		)
		(layer "In6.Cu")
	)
	(gr_line
		(start 362.646976 -294.658034)
		(end 362.645198 -294.657018)
		(stroke
			(width 0.05715)
			(type default)
		)
		(layer "In6.Cu")
	)
	(gr_line
		(start 362.646976 -293.038022)
		(end 362.644182 -293.036498)
		(stroke
			(width 0.05715)
			(type default)
		)
		(layer "In6.Cu")
	)
	(gr_line
		(start 362.646976 -292.393878)
		(end 362.647738 -292.39337)
		(stroke
			(width 0.05715)
			(type default)
		)
		(layer "In6.Cu")
	)
	(gr_line
		(start 362.646976 -291.41801)
		(end 362.644436 -291.416486)
		(stroke
			(width 0.05715)
			(type default)
		)
		(layer "In6.Cu")
	)
	(gr_line
		(start 362.646976 -290.773866)
		(end 362.647738 -290.773358)
		(stroke
			(width 0.05715)
			(type default)
		)
		(layer "In6.Cu")
	)
	(gr_line
		(start 362.646976 -289.797998)
		(end 362.645198 -289.796982)
		(stroke
			(width 0.05715)
			(type default)
		)
		(layer "In6.Cu")
	)
	(gr_line
		(start 362.646976 -284.294072)
		(end 362.649262 -284.292548)
		(stroke
			(width 0.05715)
			(type default)
		)
		(layer "In6.Cu")
	)
	(gr_line
		(start 362.647738 -294.658542)
		(end 362.646976 -294.658034)
		(stroke
			(width 0.05715)
			(type default)
		)
		(layer "In6.Cu")
	)
	(gr_line
		(start 362.647738 -293.03853)
		(end 362.646976 -293.038022)
		(stroke
			(width 0.05715)
			(type default)
		)
		(layer "In6.Cu")
	)
	(gr_line
		(start 362.647738 -292.39337)
		(end 362.648754 -292.392862)
		(stroke
			(width 0.05715)
			(type default)
		)
		(layer "In6.Cu")
	)
	(gr_line
		(start 362.647738 -291.418518)
		(end 362.646976 -291.41801)
		(stroke
			(width 0.05715)
			(type default)
		)
		(layer "In6.Cu")
	)
	(gr_line
		(start 362.647738 -290.773358)
		(end 362.648754 -290.77285)
		(stroke
			(width 0.05715)
			(type default)
		)
		(layer "In6.Cu")
	)
	(gr_line
		(start 362.647738 -289.798506)
		(end 362.646976 -289.797998)
		(stroke
			(width 0.05715)
			(type default)
		)
		(layer "In6.Cu")
	)
	(gr_line
		(start 362.647738 -285.913576)
		(end 362.648754 -285.913068)
		(stroke
			(width 0.05715)
			(type default)
		)
		(layer "In6.Cu")
	)
	(gr_line
		(start 362.647738 -282.673552)
		(end 362.64977 -282.672282)
		(stroke
			(width 0.05715)
			(type default)
		)
		(layer "In6.Cu")
	)
	(gr_line
		(start 362.648754 -294.65905)
		(end 362.647738 -294.658542)
		(stroke
			(width 0.05715)
			(type default)
		)
		(layer "In6.Cu")
	)
	(gr_line
		(start 362.648754 -293.039038)
		(end 362.647738 -293.03853)
		(stroke
			(width 0.05715)
			(type default)
		)
		(layer "In6.Cu")
	)
	(gr_line
		(start 362.648754 -291.419026)
		(end 362.647738 -291.418518)
		(stroke
			(width 0.05715)
			(type default)
		)
		(layer "In6.Cu")
	)
	(gr_line
		(start 362.648754 -289.799014)
		(end 362.647738 -289.798506)
		(stroke
			(width 0.05715)
			(type default)
		)
		(layer "In6.Cu")
	)
	(gr_line
		(start 362.650532 -294.660066)
		(end 362.648754 -294.65905)
		(stroke
			(width 0.05715)
			(type default)
		)
		(layer "In6.Cu")
	)
	(gr_line
		(start 362.650532 -293.040054)
		(end 362.648754 -293.039038)
		(stroke
			(width 0.05715)
			(type default)
		)
		(layer "In6.Cu")
	)
	(gr_line
		(start 362.650532 -291.420042)
		(end 362.648754 -291.419026)
		(stroke
			(width 0.05715)
			(type default)
		)
		(layer "In6.Cu")
	)
	(gr_line
		(start 362.650532 -289.80003)
		(end 362.648754 -289.799014)
		(stroke
			(width 0.05715)
			(type default)
		)
		(layer "In6.Cu")
	)
	(gr_line
		(start 362.653072 -294.66159)
		(end 362.652056 -294.661082)
		(stroke
			(width 0.05715)
			(type default)
		)
		(layer "In6.Cu")
	)
	(gr_line
		(start 362.653072 -293.041578)
		(end 362.652056 -293.04107)
		(stroke
			(width 0.05715)
			(type default)
		)
		(layer "In6.Cu")
	)
	(gr_line
		(start 362.653072 -291.421566)
		(end 362.652056 -291.421058)
		(stroke
			(width 0.05715)
			(type default)
		)
		(layer "In6.Cu")
	)
	(gr_line
		(start 362.653072 -289.801554)
		(end 362.652056 -289.801046)
		(stroke
			(width 0.05715)
			(type default)
		)
		(layer "In6.Cu")
	)
	(gr_line
		(start 362.654088 -294.662352)
		(end 362.653072 -294.66159)
		(stroke
			(width 0.05715)
			(type default)
		)
		(layer "In6.Cu")
	)
	(gr_line
		(start 362.654088 -293.04234)
		(end 362.653072 -293.041578)
		(stroke
			(width 0.05715)
			(type default)
		)
		(layer "In6.Cu")
	)
	(gr_line
		(start 362.654088 -291.422328)
		(end 362.653072 -291.421566)
		(stroke
			(width 0.05715)
			(type default)
		)
		(layer "In6.Cu")
	)
	(gr_line
		(start 362.654088 -289.802316)
		(end 362.653072 -289.801554)
		(stroke
			(width 0.05715)
			(type default)
		)
		(layer "In6.Cu")
	)
	(gr_line
		(start 362.662724 -285.42615)
		(end 362.364782 -285.42615)
		(stroke
			(width 0.05715)
			(type default)
		)
		(layer "In6.Cu")
	)
	(gr_line
		(start 362.662724 -283.806138)
		(end 362.364782 -283.806138)
		(stroke
			(width 0.05715)
			(type default)
		)
		(layer "In6.Cu")
	)
	(gr_line
		(start 362.662724 -282.186126)
		(end 362.364782 -282.186126)
		(stroke
			(width 0.05715)
			(type default)
		)
		(layer "In6.Cu")
	)
	(gr_line
		(start 362.67644 -282.656788)
		(end 362.677202 -282.65628)
		(stroke
			(width 0.05715)
			(type default)
		)
		(layer "In6.Cu")
	)
	(gr_line
		(start 362.677964 -282.655772)
		(end 362.686854 -282.650692)
		(stroke
			(width 0.05715)
			(type default)
		)
		(layer "In6.Cu")
	)
	(gr_arc
		(start 362.678472 -288.196782)
		(mid 362.674545 -288.194353)
		(end 362.670598 -288.191956)
		(stroke
			(width 0.05715)
			(type default)
		)
		(layer "In6.Cu")
	)
	(gr_line
		(start 362.679234 -294.67683)
		(end 362.678726 -294.676576)
		(stroke
			(width 0.05715)
			(type default)
		)
		(layer "In6.Cu")
	)
	(gr_line
		(start 362.679234 -293.056818)
		(end 362.678726 -293.056564)
		(stroke
			(width 0.05715)
			(type default)
		)
		(layer "In6.Cu")
	)
	(gr_line
		(start 362.679234 -291.436806)
		(end 362.678726 -291.436552)
		(stroke
			(width 0.05715)
			(type default)
		)
		(layer "In6.Cu")
	)
	(gr_line
		(start 362.679234 -289.816794)
		(end 362.678726 -289.81654)
		(stroke
			(width 0.05715)
			(type default)
		)
		(layer "In6.Cu")
	)
	(gr_line
		(start 362.679996 -293.057326)
		(end 362.679234 -293.056818)
		(stroke
			(width 0.05715)
			(type default)
		)
		(layer "In6.Cu")
	)
	(gr_line
		(start 362.679996 -291.437314)
		(end 362.679234 -291.436806)
		(stroke
			(width 0.05715)
			(type default)
		)
		(layer "In6.Cu")
	)
	(gr_line
		(start 362.679996 -289.817302)
		(end 362.679234 -289.816794)
		(stroke
			(width 0.05715)
			(type default)
		)
		(layer "In6.Cu")
	)
	(gr_line
		(start 362.681774 -294.678354)
		(end 362.679234 -294.67683)
		(stroke
			(width 0.05715)
			(type default)
		)
		(layer "In6.Cu")
	)
	(gr_line
		(start 362.686092 -294.680894)
		(end 362.681774 -294.678354)
		(stroke
			(width 0.05715)
			(type default)
		)
		(layer "In6.Cu")
	)
	(gr_line
		(start 362.686854 -293.06139)
		(end 362.679996 -293.057326)
		(stroke
			(width 0.05715)
			(type default)
		)
		(layer "In6.Cu")
	)
	(gr_line
		(start 362.686854 -291.441378)
		(end 362.679996 -291.437314)
		(stroke
			(width 0.05715)
			(type default)
		)
		(layer "In6.Cu")
	)
	(gr_line
		(start 362.686854 -289.821366)
		(end 362.679996 -289.817302)
		(stroke
			(width 0.05715)
			(type default)
		)
		(layer "In6.Cu")
	)
	(gr_arc
		(start 362.688378 -282.649676)
		(mid 362.691561 -282.647401)
		(end 362.694728 -282.645104)
		(stroke
			(width 0.05715)
			(type default)
		)
		(layer "In6.Cu")
	)
	(gr_arc
		(start 362.694728 -294.68699)
		(mid 362.690424 -294.683922)
		(end 362.686092 -294.680894)
		(stroke
			(width 0.05715)
			(type default)
		)
		(layer "In6.Cu")
	)
	(gr_arc
		(start 362.694728 -293.066978)
		(mid 362.690803 -293.064167)
		(end 362.686854 -293.06139)
		(stroke
			(width 0.05715)
			(type default)
		)
		(layer "In6.Cu")
	)
	(gr_arc
		(start 362.694728 -291.446966)
		(mid 362.690803 -291.444155)
		(end 362.686854 -291.441378)
		(stroke
			(width 0.05715)
			(type default)
		)
		(layer "In6.Cu")
	)
	(gr_arc
		(start 362.694728 -289.826954)
		(mid 362.690803 -289.824143)
		(end 362.686854 -289.821366)
		(stroke
			(width 0.05715)
			(type default)
		)
		(layer "In6.Cu")
	)
	(gr_line
		(start 362.732066 -285.495492)
		(end 362.662724 -285.42615)
		(stroke
			(width 0.05715)
			(type default)
		)
		(layer "In6.Cu")
	)
	(gr_line
		(start 362.732066 -283.87548)
		(end 362.662724 -283.806138)
		(stroke
			(width 0.05715)
			(type default)
		)
		(layer "In6.Cu")
	)
	(gr_line
		(start 362.732066 -282.255468)
		(end 362.662724 -282.186126)
		(stroke
			(width 0.05715)
			(type default)
		)
		(layer "In6.Cu")
	)
	(gr_line
		(start 362.78058 -380.818644)
		(end 362.605828 -380.899162)
		(stroke
			(width 0.07112)
			(type default)
		)
		(layer "In6.Cu")
	)
	(gr_line
		(start 362.818934 -380.320042)
		(end 362.899706 -380.494794)
		(stroke
			(width 0.07112)
			(type default)
		)
		(layer "In6.Cu")
	)
	(gr_line
		(start 362.835698 -319.84823)
		(end 362.835698 -319.848484)
		(stroke
			(width 0.07112)
			(type default)
		)
		(layer "In6.Cu")
	)
	(gr_arc
		(start 362.92028 -285.531814)
		(mid 362.922301 -285.520403)
		(end 362.92409 -285.508954)
		(stroke
			(width 0.05715)
			(type default)
		)
		(layer "In6.Cu")
	)
	(gr_arc
		(start 362.92028 -283.911802)
		(mid 362.922301 -283.900391)
		(end 362.92409 -283.888942)
		(stroke
			(width 0.05715)
			(type default)
		)
		(layer "In6.Cu")
	)
	(gr_arc
		(start 362.92028 -282.29179)
		(mid 362.922301 -282.280379)
		(end 362.92409 -282.26893)
		(stroke
			(width 0.05715)
			(type default)
		)
		(layer "In6.Cu")
	)
	(gr_line
		(start 362.92409 -285.508954)
		(end 363.006894 -285.42615)
		(stroke
			(width 0.05715)
			(type default)
		)
		(layer "In6.Cu")
	)
	(gr_line
		(start 362.92409 -283.888942)
		(end 363.006894 -283.806138)
		(stroke
			(width 0.05715)
			(type default)
		)
		(layer "In6.Cu")
	)
	(gr_line
		(start 362.92409 -282.26893)
		(end 363.006894 -282.186126)
		(stroke
			(width 0.05715)
			(type default)
		)
		(layer "In6.Cu")
	)
	(gr_line
		(start 362.937044 -379.997716)
		(end 362.818934 -380.320042)
		(stroke
			(width 0.07112)
			(type default)
		)
		(layer "In6.Cu")
	)
	(gr_line
		(start 363.006894 -285.42615)
		(end 363.304836 -285.42615)
		(stroke
			(width 0.05715)
			(type default)
		)
		(layer "In6.Cu")
	)
	(gr_line
		(start 363.006894 -283.806138)
		(end 363.304836 -283.806138)
		(stroke
			(width 0.05715)
			(type default)
		)
		(layer "In6.Cu")
	)
	(gr_line
		(start 363.006894 -282.186126)
		(end 363.304836 -282.186126)
		(stroke
			(width 0.05715)
			(type default)
		)
		(layer "In6.Cu")
	)
	(gr_line
		(start 363.047026 -380.915164)
		(end 362.83392 -381.494792)
		(stroke
			(width 0.07112)
			(type default)
		)
		(layer "In6.Cu")
	)
	(gr_line
		(start 363.111796 -379.917198)
		(end 362.937044 -379.997716)
		(stroke
			(width 0.07112)
			(type default)
		)
		(layer "In6.Cu")
	)
	(gr_line
		(start 363.149896 -379.418596)
		(end 363.230668 -379.593094)
		(stroke
			(width 0.07112)
			(type default)
		)
		(layer "In6.Cu")
	)
	(gr_line
		(start 363.163358 -297.299634)
		(end 363.163358 -297.299126)
		(stroke
			(width 0.07112)
			(type default)
		)
		(layer "In6.Cu")
	)
	(gr_line
		(start 363.163358 -296.353484)
		(end 363.163358 -296.325036)
		(stroke
			(width 0.05715)
			(type default)
		)
		(layer "In6.Cu")
	)
	(gr_line
		(start 363.163358 -296.325036)
		(end 363.209078 -296.279316)
		(stroke
			(width 0.05715)
			(type default)
		)
		(layer "In6.Cu")
	)
	(gr_line
		(start 363.22127 -382.467866)
		(end 363.302042 -382.642872)
		(stroke
			(width 0.07112)
			(type default)
		)
		(layer "In6.Cu")
	)
	(gr_line
		(start 363.23143 -379.594872)
		(end 363.231176 -379.59538)
		(stroke
			(width 0.07112)
			(type default)
		)
		(layer "In6.Cu")
	)
	(gr_line
		(start 363.26826 -379.09627)
		(end 363.149896 -379.418596)
		(stroke
			(width 0.07112)
			(type default)
		)
		(layer "In6.Cu")
	)
	(gr_line
		(start 363.33938 -382.14554)
		(end 363.22127 -382.467866)
		(stroke
			(width 0.07112)
			(type default)
		)
		(layer "In6.Cu")
	)
	(gr_line
		(start 363.377988 -380.013718)
		(end 363.165136 -380.593346)
		(stroke
			(width 0.07112)
			(type default)
		)
		(layer "In6.Cu")
	)
	(gr_line
		(start 363.442758 -379.015752)
		(end 363.26826 -379.09627)
		(stroke
			(width 0.07112)
			(type default)
		)
		(layer "In6.Cu")
	)
	(gr_line
		(start 363.445298 -296.353484)
		(end 363.445298 -296.325036)
		(stroke
			(width 0.05715)
			(type default)
		)
		(layer "In6.Cu")
	)
	(gr_line
		(start 363.445298 -296.325036)
		(end 363.399578 -296.279316)
		(stroke
			(width 0.05715)
			(type default)
		)
		(layer "In6.Cu")
	)
	(gr_line
		(start 363.481112 -378.51715)
		(end 363.561884 -378.691648)
		(stroke
			(width 0.07112)
			(type default)
		)
		(layer "In6.Cu")
	)
	(gr_line
		(start 363.484414 -294.81907)
		(end 363.483652 -294.818562)
		(stroke
			(width 0.05715)
			(type default)
		)
		(layer "In6.Cu")
	)
	(gr_line
		(start 363.484414 -293.199058)
		(end 363.483652 -293.19855)
		(stroke
			(width 0.05715)
			(type default)
		)
		(layer "In6.Cu")
	)
	(gr_line
		(start 363.484414 -291.579046)
		(end 363.483652 -291.578538)
		(stroke
			(width 0.05715)
			(type default)
		)
		(layer "In6.Cu")
	)
	(gr_line
		(start 363.484414 -289.959034)
		(end 363.483652 -289.958526)
		(stroke
			(width 0.05715)
			(type default)
		)
		(layer "In6.Cu")
	)
	(gr_line
		(start 363.486954 -294.820594)
		(end 363.486446 -294.82034)
		(stroke
			(width 0.05715)
			(type default)
		)
		(layer "In6.Cu")
	)
	(gr_line
		(start 363.486954 -293.200582)
		(end 363.486446 -293.200328)
		(stroke
			(width 0.05715)
			(type default)
		)
		(layer "In6.Cu")
	)
	(gr_line
		(start 363.486954 -291.58057)
		(end 363.486446 -291.580316)
		(stroke
			(width 0.05715)
			(type default)
		)
		(layer "In6.Cu")
	)
	(gr_line
		(start 363.486954 -289.960558)
		(end 363.486446 -289.960304)
		(stroke
			(width 0.05715)
			(type default)
		)
		(layer "In6.Cu")
	)
	(gr_line
		(start 363.48924 -294.821864)
		(end 363.488732 -294.82161)
		(stroke
			(width 0.05715)
			(type default)
		)
		(layer "In6.Cu")
	)
	(gr_line
		(start 363.48924 -293.201852)
		(end 363.488732 -293.201598)
		(stroke
			(width 0.05715)
			(type default)
		)
		(layer "In6.Cu")
	)
	(gr_line
		(start 363.48924 -291.58184)
		(end 363.488732 -291.581586)
		(stroke
			(width 0.05715)
			(type default)
		)
		(layer "In6.Cu")
	)
	(gr_line
		(start 363.48924 -289.961828)
		(end 363.488732 -289.961574)
		(stroke
			(width 0.05715)
			(type default)
		)
		(layer "In6.Cu")
	)
	(gr_line
		(start 363.490764 -294.82288)
		(end 363.48924 -294.821864)
		(stroke
			(width 0.05715)
			(type default)
		)
		(layer "In6.Cu")
	)
	(gr_line
		(start 363.490764 -293.849044)
		(end 363.49178 -293.848536)
		(stroke
			(width 0.05715)
			(type default)
		)
		(layer "In6.Cu")
	)
	(gr_line
		(start 363.490764 -293.202868)
		(end 363.48924 -293.201852)
		(stroke
			(width 0.05715)
			(type default)
		)
		(layer "In6.Cu")
	)
	(gr_line
		(start 363.490764 -292.229032)
		(end 363.49178 -292.228524)
		(stroke
			(width 0.05715)
			(type default)
		)
		(layer "In6.Cu")
	)
	(gr_line
		(start 363.490764 -291.582856)
		(end 363.48924 -291.58184)
		(stroke
			(width 0.05715)
			(type default)
		)
		(layer "In6.Cu")
	)
	(gr_line
		(start 363.490764 -290.60902)
		(end 363.49178 -290.608512)
		(stroke
			(width 0.05715)
			(type default)
		)
		(layer "In6.Cu")
	)
	(gr_line
		(start 363.490764 -289.962844)
		(end 363.48924 -289.961828)
		(stroke
			(width 0.05715)
			(type default)
		)
		(layer "In6.Cu")
	)
	(gr_line
		(start 363.490764 -288.989008)
		(end 363.49178 -288.9885)
		(stroke
			(width 0.05715)
			(type default)
		)
		(layer "In6.Cu")
	)
	(gr_line
		(start 363.490764 -285.749238)
		(end 363.49178 -285.74873)
		(stroke
			(width 0.05715)
			(type default)
		)
		(layer "In6.Cu")
	)
	(gr_line
		(start 363.49178 -294.823388)
		(end 363.490764 -294.82288)
		(stroke
			(width 0.05715)
			(type default)
		)
		(layer "In6.Cu")
	)
	(gr_line
		(start 363.49178 -293.848536)
		(end 363.492542 -293.848028)
		(stroke
			(width 0.05715)
			(type default)
		)
		(layer "In6.Cu")
	)
	(gr_line
		(start 363.49178 -293.203376)
		(end 363.490764 -293.202868)
		(stroke
			(width 0.05715)
			(type default)
		)
		(layer "In6.Cu")
	)
	(gr_line
		(start 363.49178 -292.228524)
		(end 363.492542 -292.228016)
		(stroke
			(width 0.05715)
			(type default)
		)
		(layer "In6.Cu")
	)
	(gr_line
		(start 363.49178 -291.583364)
		(end 363.490764 -291.582856)
		(stroke
			(width 0.05715)
			(type default)
		)
		(layer "In6.Cu")
	)
	(gr_line
		(start 363.49178 -290.608512)
		(end 363.492542 -290.608004)
		(stroke
			(width 0.05715)
			(type default)
		)
		(layer "In6.Cu")
	)
	(gr_line
		(start 363.49178 -289.963352)
		(end 363.490764 -289.962844)
		(stroke
			(width 0.05715)
			(type default)
		)
		(layer "In6.Cu")
	)
	(gr_line
		(start 363.49178 -288.9885)
		(end 363.492542 -288.987992)
		(stroke
			(width 0.05715)
			(type default)
		)
		(layer "In6.Cu")
	)
	(gr_line
		(start 363.49178 -285.74873)
		(end 363.492542 -285.748222)
		(stroke
			(width 0.05715)
			(type default)
		)
		(layer "In6.Cu")
	)
	(gr_line
		(start 363.492542 -294.823896)
		(end 363.49178 -294.823388)
		(stroke
			(width 0.05715)
			(type default)
		)
		(layer "In6.Cu")
	)
	(gr_line
		(start 363.492542 -293.848028)
		(end 363.493812 -293.847266)
		(stroke
			(width 0.05715)
			(type default)
		)
		(layer "In6.Cu")
	)
	(gr_line
		(start 363.492542 -293.203884)
		(end 363.49178 -293.203376)
		(stroke
			(width 0.05715)
			(type default)
		)
		(layer "In6.Cu")
	)
	(gr_line
		(start 363.492542 -292.228016)
		(end 363.493812 -292.227254)
		(stroke
			(width 0.05715)
			(type default)
		)
		(layer "In6.Cu")
	)
	(gr_line
		(start 363.492542 -291.583872)
		(end 363.49178 -291.583364)
		(stroke
			(width 0.05715)
			(type default)
		)
		(layer "In6.Cu")
	)
	(gr_line
		(start 363.492542 -290.608004)
		(end 363.493812 -290.607242)
		(stroke
			(width 0.05715)
			(type default)
		)
		(layer "In6.Cu")
	)
	(gr_line
		(start 363.492542 -289.96386)
		(end 363.49178 -289.963352)
		(stroke
			(width 0.05715)
			(type default)
		)
		(layer "In6.Cu")
	)
	(gr_line
		(start 363.492542 -288.987992)
		(end 363.493812 -288.98723)
		(stroke
			(width 0.05715)
			(type default)
		)
		(layer "In6.Cu")
	)
	(gr_line
		(start 363.492542 -285.748222)
		(end 363.493812 -285.74746)
		(stroke
			(width 0.05715)
			(type default)
		)
		(layer "In6.Cu")
	)
	(gr_line
		(start 363.497114 -294.826436)
		(end 363.496352 -294.825928)
		(stroke
			(width 0.05715)
			(type default)
		)
		(layer "In6.Cu")
	)
	(gr_line
		(start 363.497114 -293.206424)
		(end 363.496352 -293.205916)
		(stroke
			(width 0.05715)
			(type default)
		)
		(layer "In6.Cu")
	)
	(gr_line
		(start 363.497114 -291.586412)
		(end 363.496352 -291.585904)
		(stroke
			(width 0.05715)
			(type default)
		)
		(layer "In6.Cu")
	)
	(gr_line
		(start 363.497114 -289.9664)
		(end 363.496352 -289.965892)
		(stroke
			(width 0.05715)
			(type default)
		)
		(layer "In6.Cu")
	)
	(gr_line
		(start 363.498892 -294.827452)
		(end 363.497876 -294.826944)
		(stroke
			(width 0.05715)
			(type default)
		)
		(layer "In6.Cu")
	)
	(gr_line
		(start 363.498892 -293.20744)
		(end 363.497876 -293.206932)
		(stroke
			(width 0.05715)
			(type default)
		)
		(layer "In6.Cu")
	)
	(gr_line
		(start 363.498892 -291.587428)
		(end 363.497876 -291.58692)
		(stroke
			(width 0.05715)
			(type default)
		)
		(layer "In6.Cu")
	)
	(gr_line
		(start 363.498892 -289.967416)
		(end 363.497876 -289.966908)
		(stroke
			(width 0.05715)
			(type default)
		)
		(layer "In6.Cu")
	)
	(gr_line
		(start 363.4994 -294.827706)
		(end 363.498892 -294.827452)
		(stroke
			(width 0.05715)
			(type default)
		)
		(layer "In6.Cu")
	)
	(gr_line
		(start 363.4994 -293.207694)
		(end 363.498892 -293.20744)
		(stroke
			(width 0.05715)
			(type default)
		)
		(layer "In6.Cu")
	)
	(gr_line
		(start 363.4994 -291.587682)
		(end 363.498892 -291.587428)
		(stroke
			(width 0.05715)
			(type default)
		)
		(layer "In6.Cu")
	)
	(gr_line
		(start 363.4994 -289.96767)
		(end 363.498892 -289.967416)
		(stroke
			(width 0.05715)
			(type default)
		)
		(layer "In6.Cu")
	)
	(gr_line
		(start 363.514386 -382.064768)
		(end 363.33938 -382.14554)
		(stroke
			(width 0.07112)
			(type default)
		)
		(layer "In6.Cu")
	)
	(gr_line
		(start 363.552486 -381.56642)
		(end 363.633258 -381.741172)
		(stroke
			(width 0.07112)
			(type default)
		)
		(layer "In6.Cu")
	)
	(gr_line
		(start 363.58576 -294.014652)
		(end 363.58703 -294.01389)
		(stroke
			(width 0.05715)
			(type default)
		)
		(layer "In6.Cu")
	)
	(gr_line
		(start 363.58576 -292.39464)
		(end 363.58703 -292.393878)
		(stroke
			(width 0.05715)
			(type default)
		)
		(layer "In6.Cu")
	)
	(gr_line
		(start 363.58576 -290.774628)
		(end 363.58703 -290.773866)
		(stroke
			(width 0.05715)
			(type default)
		)
		(layer "In6.Cu")
	)
	(gr_line
		(start 363.58576 -289.154616)
		(end 363.58703 -289.153854)
		(stroke
			(width 0.05715)
			(type default)
		)
		(layer "In6.Cu")
	)
	(gr_line
		(start 363.58576 -285.914846)
		(end 363.58703 -285.914084)
		(stroke
			(width 0.05715)
			(type default)
		)
		(layer "In6.Cu")
	)
	(gr_line
		(start 363.58703 -294.658034)
		(end 363.584236 -294.65651)
		(stroke
			(width 0.05715)
			(type default)
		)
		(layer "In6.Cu")
	)
	(gr_line
		(start 363.58703 -294.01389)
		(end 363.587792 -294.013382)
		(stroke
			(width 0.05715)
			(type default)
		)
		(layer "In6.Cu")
	)
	(gr_line
		(start 363.58703 -293.038022)
		(end 363.584236 -293.036498)
		(stroke
			(width 0.05715)
			(type default)
		)
		(layer "In6.Cu")
	)
	(gr_line
		(start 363.58703 -292.393878)
		(end 363.587792 -292.39337)
		(stroke
			(width 0.05715)
			(type default)
		)
		(layer "In6.Cu")
	)
	(gr_line
		(start 363.58703 -291.41801)
		(end 363.584236 -291.416486)
		(stroke
			(width 0.05715)
			(type default)
		)
		(layer "In6.Cu")
	)
	(gr_line
		(start 363.58703 -290.773866)
		(end 363.587792 -290.773358)
		(stroke
			(width 0.05715)
			(type default)
		)
		(layer "In6.Cu")
	)
	(gr_line
		(start 363.58703 -289.797998)
		(end 363.584236 -289.796474)
		(stroke
			(width 0.05715)
			(type default)
		)
		(layer "In6.Cu")
	)
	(gr_line
		(start 363.58703 -289.153854)
		(end 363.587792 -289.153346)
		(stroke
			(width 0.05715)
			(type default)
		)
		(layer "In6.Cu")
	)
	(gr_line
		(start 363.58703 -285.914084)
		(end 363.587792 -285.913576)
		(stroke
			(width 0.05715)
			(type default)
		)
		(layer "In6.Cu")
	)
	(gr_line
		(start 363.587792 -294.658542)
		(end 363.58703 -294.658034)
		(stroke
			(width 0.05715)
			(type default)
		)
		(layer "In6.Cu")
	)
	(gr_line
		(start 363.587792 -294.013382)
		(end 363.588808 -294.012874)
		(stroke
			(width 0.05715)
			(type default)
		)
		(layer "In6.Cu")
	)
	(gr_line
		(start 363.587792 -293.03853)
		(end 363.58703 -293.038022)
		(stroke
			(width 0.05715)
			(type default)
		)
		(layer "In6.Cu")
	)
	(gr_line
		(start 363.587792 -292.39337)
		(end 363.588808 -292.392862)
		(stroke
			(width 0.05715)
			(type default)
		)
		(layer "In6.Cu")
	)
	(gr_line
		(start 363.587792 -291.418518)
		(end 363.58703 -291.41801)
		(stroke
			(width 0.05715)
			(type default)
		)
		(layer "In6.Cu")
	)
	(gr_line
		(start 363.587792 -290.773358)
		(end 363.588808 -290.77285)
		(stroke
			(width 0.05715)
			(type default)
		)
		(layer "In6.Cu")
	)
	(gr_line
		(start 363.587792 -289.798506)
		(end 363.58703 -289.797998)
		(stroke
			(width 0.05715)
			(type default)
		)
		(layer "In6.Cu")
	)
	(gr_line
		(start 363.587792 -289.153346)
		(end 363.588808 -289.152838)
		(stroke
			(width 0.05715)
			(type default)
		)
		(layer "In6.Cu")
	)
	(gr_line
		(start 363.587792 -285.913576)
		(end 363.588808 -285.913068)
		(stroke
			(width 0.05715)
			(type default)
		)
		(layer "In6.Cu")
	)
	(gr_line
		(start 363.588808 -294.65905)
		(end 363.587792 -294.658542)
		(stroke
			(width 0.05715)
			(type default)
		)
		(layer "In6.Cu")
	)
	(gr_line
		(start 363.588808 -293.039038)
		(end 363.587792 -293.03853)
		(stroke
			(width 0.05715)
			(type default)
		)
		(layer "In6.Cu")
	)
	(gr_line
		(start 363.588808 -291.419026)
		(end 363.587792 -291.418518)
		(stroke
			(width 0.05715)
			(type default)
		)
		(layer "In6.Cu")
	)
	(gr_line
		(start 363.588808 -289.799014)
		(end 363.587792 -289.798506)
		(stroke
			(width 0.05715)
			(type default)
		)
		(layer "In6.Cu")
	)
	(gr_line
		(start 363.58957 -294.659558)
		(end 363.588808 -294.65905)
		(stroke
			(width 0.05715)
			(type default)
		)
		(layer "In6.Cu")
	)
	(gr_line
		(start 363.58957 -293.039546)
		(end 363.588808 -293.039038)
		(stroke
			(width 0.05715)
			(type default)
		)
		(layer "In6.Cu")
	)
	(gr_line
		(start 363.58957 -291.419534)
		(end 363.588808 -291.419026)
		(stroke
			(width 0.05715)
			(type default)
		)
		(layer "In6.Cu")
	)
	(gr_line
		(start 363.58957 -289.799522)
		(end 363.588808 -289.799014)
		(stroke
			(width 0.05715)
			(type default)
		)
		(layer "In6.Cu")
	)
	(gr_line
		(start 363.593126 -294.66159)
		(end 363.59211 -294.661082)
		(stroke
			(width 0.05715)
			(type default)
		)
		(layer "In6.Cu")
	)
	(gr_line
		(start 363.593126 -293.041578)
		(end 363.59211 -293.04107)
		(stroke
			(width 0.05715)
			(type default)
		)
		(layer "In6.Cu")
	)
	(gr_line
		(start 363.593126 -291.421566)
		(end 363.59211 -291.421058)
		(stroke
			(width 0.05715)
			(type default)
		)
		(layer "In6.Cu")
	)
	(gr_line
		(start 363.593126 -289.801554)
		(end 363.59211 -289.801046)
		(stroke
			(width 0.05715)
			(type default)
		)
		(layer "In6.Cu")
	)
	(gr_line
		(start 363.594142 -294.662352)
		(end 363.593126 -294.66159)
		(stroke
			(width 0.05715)
			(type default)
		)
		(layer "In6.Cu")
	)
	(gr_line
		(start 363.594142 -293.04234)
		(end 363.593126 -293.041578)
		(stroke
			(width 0.05715)
			(type default)
		)
		(layer "In6.Cu")
	)
	(gr_line
		(start 363.594142 -291.422328)
		(end 363.593126 -291.421566)
		(stroke
			(width 0.05715)
			(type default)
		)
		(layer "In6.Cu")
	)
	(gr_line
		(start 363.594142 -289.802316)
		(end 363.593126 -289.801554)
		(stroke
			(width 0.05715)
			(type default)
		)
		(layer "In6.Cu")
	)
	(gr_line
		(start 363.599476 -378.194824)
		(end 363.481112 -378.51715)
		(stroke
			(width 0.07112)
			(type default)
		)
		(layer "In6.Cu")
	)
	(gr_line
		(start 363.619288 -294.67683)
		(end 363.61878 -294.676576)
		(stroke
			(width 0.05715)
			(type default)
		)
		(layer "In6.Cu")
	)
	(gr_line
		(start 363.619288 -293.056818)
		(end 363.61878 -293.056564)
		(stroke
			(width 0.05715)
			(type default)
		)
		(layer "In6.Cu")
	)
	(gr_line
		(start 363.619288 -291.436806)
		(end 363.61878 -291.436552)
		(stroke
			(width 0.05715)
			(type default)
		)
		(layer "In6.Cu")
	)
	(gr_line
		(start 363.619288 -289.816794)
		(end 363.61878 -289.81654)
		(stroke
			(width 0.05715)
			(type default)
		)
		(layer "In6.Cu")
	)
	(gr_line
		(start 363.62005 -294.677338)
		(end 363.619288 -294.67683)
		(stroke
			(width 0.05715)
			(type default)
		)
		(layer "In6.Cu")
	)
	(gr_line
		(start 363.62005 -293.057326)
		(end 363.619288 -293.056818)
		(stroke
			(width 0.05715)
			(type default)
		)
		(layer "In6.Cu")
	)
	(gr_line
		(start 363.62005 -291.437314)
		(end 363.619288 -291.436806)
		(stroke
			(width 0.05715)
			(type default)
		)
		(layer "In6.Cu")
	)
	(gr_line
		(start 363.62005 -289.817302)
		(end 363.619288 -289.816794)
		(stroke
			(width 0.05715)
			(type default)
		)
		(layer "In6.Cu")
	)
	(gr_line
		(start 363.626908 -294.681402)
		(end 363.62005 -294.677338)
		(stroke
			(width 0.05715)
			(type default)
		)
		(layer "In6.Cu")
	)
	(gr_line
		(start 363.626908 -293.06139)
		(end 363.62005 -293.057326)
		(stroke
			(width 0.05715)
			(type default)
		)
		(layer "In6.Cu")
	)
	(gr_line
		(start 363.626908 -291.441378)
		(end 363.62005 -291.437314)
		(stroke
			(width 0.05715)
			(type default)
		)
		(layer "In6.Cu")
	)
	(gr_line
		(start 363.626908 -289.821366)
		(end 363.62005 -289.817302)
		(stroke
			(width 0.05715)
			(type default)
		)
		(layer "In6.Cu")
	)
	(gr_arc
		(start 363.634782 -294.68699)
		(mid 363.630857 -294.684179)
		(end 363.626908 -294.681402)
		(stroke
			(width 0.05715)
			(type default)
		)
		(layer "In6.Cu")
	)
	(gr_arc
		(start 363.634782 -293.066978)
		(mid 363.630857 -293.064167)
		(end 363.626908 -293.06139)
		(stroke
			(width 0.05715)
			(type default)
		)
		(layer "In6.Cu")
	)
	(gr_arc
		(start 363.634782 -291.446966)
		(mid 363.630857 -291.444155)
		(end 363.626908 -291.441378)
		(stroke
			(width 0.05715)
			(type default)
		)
		(layer "In6.Cu")
	)
	(gr_arc
		(start 363.634782 -289.826954)
		(mid 363.630857 -289.824143)
		(end 363.626908 -289.821366)
		(stroke
			(width 0.05715)
			(type default)
		)
		(layer "In6.Cu")
	)
	(gr_line
		(start 363.670596 -381.244094)
		(end 363.552486 -381.56642)
		(stroke
			(width 0.07112)
			(type default)
		)
		(layer "In6.Cu")
	)
	(gr_line
		(start 363.709204 -379.112018)
		(end 363.499146 -379.683772)
		(stroke
			(width 0.07112)
			(type default)
		)
		(layer "In6.Cu")
	)
	(gr_line
		(start 363.74959 -379.002036)
		(end 363.709204 -379.112018)
		(stroke
			(width 0.07112)
			(type default)
		)
		(layer "In6.Cu")
	)
	(gr_line
		(start 363.774482 -378.114052)
		(end 363.599476 -378.194824)
		(stroke
			(width 0.07112)
			(type default)
		)
		(layer "In6.Cu")
	)
	(gr_line
		(start 363.776006 -378.11329)
		(end 363.775752 -378.113544)
		(stroke
			(width 0.07112)
			(type default)
		)
		(layer "In6.Cu")
	)
	(gr_line
		(start 363.780578 -382.161542)
		(end 363.567726 -382.74117)
		(stroke
			(width 0.07112)
			(type default)
		)
		(layer "In6.Cu")
	)
	(gr_line
		(start 363.845602 -381.163576)
		(end 363.670596 -381.244094)
		(stroke
			(width 0.07112)
			(type default)
		)
		(layer "In6.Cu")
	)
	(gr_line
		(start 363.883448 -380.664974)
		(end 363.964474 -380.839726)
		(stroke
			(width 0.07112)
			(type default)
		)
		(layer "In6.Cu")
	)
	(gr_line
		(start 363.99978 -378.321062)
		(end 363.827314 -378.790454)
		(stroke
			(width 0.07112)
			(type default)
		)
		(layer "In6.Cu")
	)
	(gr_line
		(start 364.000288 -378.320808)
		(end 363.99978 -378.321062)
		(stroke
			(width 0.07112)
			(type default)
		)
		(layer "In6.Cu")
	)
	(gr_line
		(start 364.001812 -380.342648)
		(end 363.883448 -380.664974)
		(stroke
			(width 0.07112)
			(type default)
		)
		(layer "In6.Cu")
	)
	(gr_line
		(start 364.040674 -378.210826)
		(end 364.000288 -378.320808)
		(stroke
			(width 0.07112)
			(type default)
		)
		(layer "In6.Cu")
	)
	(gr_line
		(start 364.040928 -378.210064)
		(end 364.040674 -378.210826)
		(stroke
			(width 0.07112)
			(type default)
		)
		(layer "In6.Cu")
	)
	(gr_line
		(start 364.104682 -296.353484)
		(end 364.104682 -296.325036)
		(stroke
			(width 0.05715)
			(type default)
		)
		(layer "In6.Cu")
	)
	(gr_line
		(start 364.104682 -296.325036)
		(end 364.150402 -296.279316)
		(stroke
			(width 0.05715)
			(type default)
		)
		(layer "In6.Cu")
	)
	(gr_line
		(start 364.111794 -381.260096)
		(end 363.898688 -381.839724)
		(stroke
			(width 0.07112)
			(type default)
		)
		(layer "In6.Cu")
	)
	(gr_line
		(start 364.14964 -296.200322)
		(end 364.14964 -296.199306)
		(stroke
			(width 0.05715)
			(type default)
		)
		(layer "In6.Cu")
	)
	(gr_line
		(start 364.176564 -380.26213)
		(end 364.001812 -380.342648)
		(stroke
			(width 0.07112)
			(type default)
		)
		(layer "In6.Cu")
	)
	(gr_line
		(start 364.214664 -379.763528)
		(end 364.29569 -379.93828)
		(stroke
			(width 0.07112)
			(type default)
		)
		(layer "In6.Cu")
	)
	(gr_line
		(start 364.333028 -379.441202)
		(end 364.214664 -379.763528)
		(stroke
			(width 0.07112)
			(type default)
		)
		(layer "In6.Cu")
	)
	(gr_line
		(start 364.340902 -296.279316)
		(end 364.341156 -296.279062)
		(stroke
			(width 0.05715)
			(type default)
		)
		(layer "In6.Cu")
	)
	(gr_line
		(start 364.341156 -296.279062)
		(end 364.341156 -296.278554)
		(stroke
			(width 0.05715)
			(type default)
		)
		(layer "In6.Cu")
	)
	(gr_line
		(start 364.386622 -296.353484)
		(end 364.386622 -296.325036)
		(stroke
			(width 0.05715)
			(type default)
		)
		(layer "In6.Cu")
	)
	(gr_line
		(start 364.386622 -296.325036)
		(end 364.340902 -296.279316)
		(stroke
			(width 0.05715)
			(type default)
		)
		(layer "In6.Cu")
	)
	(gr_line
		(start 364.429294 -287.370012)
		(end 364.430818 -287.368996)
		(stroke
			(width 0.05715)
			(type default)
		)
		(layer "In6.Cu")
	)
	(gr_line
		(start 364.431834 -287.368488)
		(end 364.433612 -287.367472)
		(stroke
			(width 0.05715)
			(type default)
		)
		(layer "In6.Cu")
	)
	(gr_line
		(start 364.43412 -287.367218)
		(end 364.433612 -287.367472)
		(stroke
			(width 0.05715)
			(type default)
		)
		(layer "In6.Cu")
	)
	(gr_line
		(start 364.442756 -380.35865)
		(end 364.229904 -380.938278)
		(stroke
			(width 0.07112)
			(type default)
		)
		(layer "In6.Cu")
	)
	(gr_line
		(start 364.50778 -379.360684)
		(end 364.333028 -379.441202)
		(stroke
			(width 0.07112)
			(type default)
		)
		(layer "In6.Cu")
	)
	(gr_line
		(start 364.524798 -287.535366)
		(end 364.525814 -287.534858)
		(stroke
			(width 0.05715)
			(type default)
		)
		(layer "In6.Cu")
	)
	(gr_line
		(start 364.525814 -287.534858)
		(end 364.526576 -287.53435)
		(stroke
			(width 0.05715)
			(type default)
		)
		(layer "In6.Cu")
	)
	(gr_line
		(start 364.528354 -287.533334)
		(end 364.528862 -287.53308)
		(stroke
			(width 0.05715)
			(type default)
		)
		(layer "In6.Cu")
	)
	(gr_line
		(start 364.530132 -287.532318)
		(end 364.529878 -287.532064)
		(stroke
			(width 0.05715)
			(type default)
		)
		(layer "In6.Cu")
	)
	(gr_line
		(start 364.54588 -378.862082)
		(end 364.626652 -379.03658)
		(stroke
			(width 0.07112)
			(type default)
		)
		(layer "In6.Cu")
	)
	(gr_line
		(start 364.61954 -295.145968)
		(end 364.619286 -295.145968)
		(stroke
			(width 0.05715)
			(type default)
		)
		(layer "In6.Cu")
	)
	(gr_line
		(start 364.627414 -379.038104)
		(end 364.62716 -379.038866)
		(stroke
			(width 0.07112)
			(type default)
		)
		(layer "In6.Cu")
	)
	(gr_line
		(start 364.662466 -334.721962)
		(end 364.67161 -334.77327)
		(stroke
			(width 0.07112)
			(type default)
		)
		(layer "In6.Cu")
	)
	(gr_line
		(start 364.664244 -378.539756)
		(end 364.54588 -378.862082)
		(stroke
			(width 0.07112)
			(type default)
		)
		(layer "In6.Cu")
	)
	(gr_line
		(start 364.67161 -334.77327)
		(end 364.67161 -334.773778)
		(stroke
			(width 0.07112)
			(type default)
		)
		(layer "In6.Cu")
	)
	(gr_line
		(start 364.673642 -334.785208)
		(end 364.673896 -334.786224)
		(stroke
			(width 0.07112)
			(type default)
		)
		(layer "In6.Cu")
	)
	(gr_line
		(start 364.773972 -379.457204)
		(end 364.56112 -380.036832)
		(stroke
			(width 0.07112)
			(type default)
		)
		(layer "In6.Cu")
	)
	(gr_line
		(start 364.806484 -283.840936)
		(end 364.80623 -283.842206)
		(stroke
			(width 0.05715)
			(type default)
		)
		(layer "In6.Cu")
	)
	(gr_line
		(start 364.81004 -283.796486)
		(end 364.81004 -283.797756)
		(stroke
			(width 0.05715)
			(type default)
		)
		(layer "In6.Cu")
	)
	(gr_line
		(start 364.810802 -0.429006)
		(end 364.519972 -0.138176)
		(stroke
			(width 0.07112)
			(type default)
		)
		(layer "In6.Cu")
	)
	(gr_line
		(start 364.810802 0.434594)
		(end 364.519972 0.143764)
		(stroke
			(width 0.07112)
			(type default)
		)
		(layer "In6.Cu")
	)
	(gr_line
		(start 364.83925 -378.458984)
		(end 364.664244 -378.539756)
		(stroke
			(width 0.07112)
			(type default)
		)
		(layer "In6.Cu")
	)
	(gr_line
		(start 364.840774 -378.458222)
		(end 364.84052 -378.458476)
		(stroke
			(width 0.07112)
			(type default)
		)
		(layer "In6.Cu")
	)
	(gr_line
		(start 364.899194 -286.560006)
		(end 364.90021 -286.559498)
		(stroke
			(width 0.05715)
			(type default)
		)
		(layer "In6.Cu")
	)
	(gr_line
		(start 364.901988 -283.318458)
		(end 364.902496 -283.318204)
		(stroke
			(width 0.05715)
			(type default)
		)
		(layer "In6.Cu")
	)
	(gr_line
		(start 364.902496 -283.318204)
		(end 364.903766 -283.317442)
		(stroke
			(width 0.05715)
			(type default)
		)
		(layer "In6.Cu")
	)
	(gr_line
		(start 364.939834 -334.672178)
		(end 364.948978 -334.723486)
		(stroke
			(width 0.07112)
			(type default)
		)
		(layer "In6.Cu")
	)
	(gr_line
		(start 364.948978 -334.723486)
		(end 364.949232 -334.723994)
		(stroke
			(width 0.07112)
			(type default)
		)
		(layer "In6.Cu")
	)
	(gr_line
		(start 364.994952 -286.724852)
		(end 364.996222 -286.724344)
		(stroke
			(width 0.05715)
			(type default)
		)
		(layer "In6.Cu")
	)
	(gr_line
		(start 364.997746 -283.483558)
		(end 364.998762 -283.48305)
		(stroke
			(width 0.05715)
			(type default)
		)
		(layer "In6.Cu")
	)
	(gr_line
		(start 365.012732 -286.236156)
		(end 364.71479 -286.236156)
		(stroke
			(width 0.05715)
			(type default)
		)
		(layer "In6.Cu")
	)
	(gr_line
		(start 365.012732 -284.616144)
		(end 364.71479 -284.616144)
		(stroke
			(width 0.05715)
			(type default)
		)
		(layer "In6.Cu")
	)
	(gr_line
		(start 365.012732 -282.996132)
		(end 364.71479 -282.996132)
		(stroke
			(width 0.05715)
			(type default)
		)
		(layer "In6.Cu")
	)
	(gr_line
		(start 365.03102 -286.704278)
		(end 365.036354 -286.700976)
		(stroke
			(width 0.05715)
			(type default)
		)
		(layer "In6.Cu")
	)
	(gr_line
		(start 365.036354 -286.700976)
		(end 365.036862 -286.700722)
		(stroke
			(width 0.05715)
			(type default)
		)
		(layer "In6.Cu")
	)
	(gr_arc
		(start 365.036862 -286.700722)
		(mid 365.038643 -286.699456)
		(end 365.040418 -286.698182)
		(stroke
			(width 0.05715)
			(type default)
		)
		(layer "In6.Cu")
	)
	(gr_line
		(start 365.039402 -296.353484)
		(end 365.039402 -296.325036)
		(stroke
			(width 0.05715)
			(type default)
		)
		(layer "In6.Cu")
	)
	(gr_line
		(start 365.039402 -296.325036)
		(end 365.085122 -296.279316)
		(stroke
			(width 0.05715)
			(type default)
		)
		(layer "In6.Cu")
	)
	(gr_arc
		(start 365.04118 -286.697674)
		(mid 365.04449 -286.6954)
		(end 365.047784 -286.693102)
		(stroke
			(width 0.05715)
			(type default)
		)
		(layer "In6.Cu")
	)
	(gr_line
		(start 365.064548 -378.665994)
		(end 364.89513 -379.127258)
		(stroke
			(width 0.07112)
			(type default)
		)
		(layer "In6.Cu")
	)
	(gr_line
		(start 365.065056 -378.66574)
		(end 365.064548 -378.665994)
		(stroke
			(width 0.07112)
			(type default)
		)
		(layer "In6.Cu")
	)
	(gr_line
		(start 365.082074 -286.305498)
		(end 365.012732 -286.236156)
		(stroke
			(width 0.05715)
			(type default)
		)
		(layer "In6.Cu")
	)
	(gr_line
		(start 365.082074 -283.065474)
		(end 365.012732 -282.996132)
		(stroke
			(width 0.05715)
			(type default)
		)
		(layer "In6.Cu")
	)
	(gr_line
		(start 365.095536 -284.698948)
		(end 365.012732 -284.616144)
		(stroke
			(width 0.05715)
			(type default)
		)
		(layer "In6.Cu")
	)
	(gr_arc
		(start 365.095536 -284.698948)
		(mid 365.097322 -284.710398)
		(end 365.099346 -284.721808)
		(stroke
			(width 0.05715)
			(type default)
		)
		(layer "In6.Cu")
	)
	(gr_line
		(start 365.105442 -378.55525)
		(end 365.065056 -378.66574)
		(stroke
			(width 0.07112)
			(type default)
		)
		(layer "In6.Cu")
	)
	(gr_arc
		(start 365.270288 -286.34182)
		(mid 365.27231 -286.330409)
		(end 365.274098 -286.31896)
		(stroke
			(width 0.05715)
			(type default)
		)
		(layer "In6.Cu")
	)
	(gr_arc
		(start 365.270288 -283.101796)
		(mid 365.272309 -283.090385)
		(end 365.274098 -283.078936)
		(stroke
			(width 0.05715)
			(type default)
		)
		(layer "In6.Cu")
	)
	(gr_line
		(start 365.274098 -286.31896)
		(end 365.356902 -286.236156)
		(stroke
			(width 0.05715)
			(type default)
		)
		(layer "In6.Cu")
	)
	(gr_line
		(start 365.274098 -283.078936)
		(end 365.356902 -282.996132)
		(stroke
			(width 0.05715)
			(type default)
		)
		(layer "In6.Cu")
	)
	(gr_line
		(start 365.28756 -284.685486)
		(end 365.356902 -284.616144)
		(stroke
			(width 0.05715)
			(type default)
		)
		(layer "In6.Cu")
	)
	(gr_line
		(start 365.321342 -296.353484)
		(end 365.321342 -296.325036)
		(stroke
			(width 0.05715)
			(type default)
		)
		(layer "In6.Cu")
	)
	(gr_line
		(start 365.321342 -296.325036)
		(end 365.275622 -296.279316)
		(stroke
			(width 0.05715)
			(type default)
		)
		(layer "In6.Cu")
	)
	(gr_line
		(start 365.356902 -286.236156)
		(end 365.654844 -286.236156)
		(stroke
			(width 0.05715)
			(type default)
		)
		(layer "In6.Cu")
	)
	(gr_line
		(start 365.356902 -284.616144)
		(end 365.654844 -284.616144)
		(stroke
			(width 0.05715)
			(type default)
		)
		(layer "In6.Cu")
	)
	(gr_line
		(start 365.356902 -282.996132)
		(end 365.654844 -282.996132)
		(stroke
			(width 0.05715)
			(type default)
		)
		(layer "In6.Cu")
	)
	(gr_line
		(start 365.84382 -295.634664)
		(end 365.84255 -295.633902)
		(stroke
			(width 0.05715)
			(type default)
		)
		(layer "In6.Cu")
	)
	(gr_line
		(start 365.847884 -295.63695)
		(end 365.84636 -295.635934)
		(stroke
			(width 0.05715)
			(type default)
		)
		(layer "In6.Cu")
	)
	(gr_line
		(start 365.849408 -295.637712)
		(end 365.847884 -295.63695)
		(stroke
			(width 0.05715)
			(type default)
		)
		(layer "In6.Cu")
	)
	(gr_line
		(start 365.9378 -295.468548)
		(end 365.937292 -295.468294)
		(stroke
			(width 0.05715)
			(type default)
		)
		(layer "In6.Cu")
	)
	(gr_line
		(start 365.938816 -295.469056)
		(end 365.9378 -295.468548)
		(stroke
			(width 0.05715)
			(type default)
		)
		(layer "In6.Cu")
	)
	(gr_line
		(start 365.940594 -295.470072)
		(end 365.938816 -295.469056)
		(stroke
			(width 0.05715)
			(type default)
		)
		(layer "In6.Cu")
	)
	(gr_line
		(start 365.94288 -295.471596)
		(end 365.942118 -295.471088)
		(stroke
			(width 0.05715)
			(type default)
		)
		(layer "In6.Cu")
	)
	(gr_line
		(start 365.969296 -295.486836)
		(end 365.968534 -295.486328)
		(stroke
			(width 0.05715)
			(type default)
		)
		(layer "In6.Cu")
	)
	(gr_line
		(start 365.970058 -295.487344)
		(end 365.969296 -295.486836)
		(stroke
			(width 0.05715)
			(type default)
		)
		(layer "In6.Cu")
	)
	(gr_line
		(start 365.976916 -295.491408)
		(end 365.970058 -295.487344)
		(stroke
			(width 0.05715)
			(type default)
		)
		(layer "In6.Cu")
	)
	(gr_line
		(start 365.984028 -296.353484)
		(end 365.984028 -296.325036)
		(stroke
			(width 0.05715)
			(type default)
		)
		(layer "In6.Cu")
	)
	(gr_line
		(start 365.984028 -296.325036)
		(end 366.029748 -296.279316)
		(stroke
			(width 0.05715)
			(type default)
		)
		(layer "In6.Cu")
	)
	(gr_arc
		(start 365.98479 -295.496996)
		(mid 365.980865 -295.494185)
		(end 365.976916 -295.491408)
		(stroke
			(width 0.05715)
			(type default)
		)
		(layer "In6.Cu")
	)
	(gr_line
		(start 366.022382 -306.216558)
		(end 366.022636 -306.216558)
		(stroke
			(width 0.07112)
			(type default)
		)
		(layer "In6.Cu")
	)
	(gr_line
		(start 366.265968 -296.353484)
		(end 366.265968 -296.325036)
		(stroke
			(width 0.05715)
			(type default)
		)
		(layer "In6.Cu")
	)
	(gr_line
		(start 366.265968 -296.325036)
		(end 366.220248 -296.279316)
		(stroke
			(width 0.05715)
			(type default)
		)
		(layer "In6.Cu")
	)
	(gr_line
		(start 366.782858 -285.911798)
		(end 366.78235 -285.911544)
		(stroke
			(width 0.05715)
			(type default)
		)
		(layer "In6.Cu")
	)
	(gr_line
		(start 366.783874 -295.634664)
		(end 366.782604 -295.633902)
		(stroke
			(width 0.05715)
			(type default)
		)
		(layer "In6.Cu")
	)
	(gr_line
		(start 366.787938 -295.63695)
		(end 366.786414 -295.635934)
		(stroke
			(width 0.05715)
			(type default)
		)
		(layer "In6.Cu")
	)
	(gr_line
		(start 366.789462 -295.637712)
		(end 366.787938 -295.63695)
		(stroke
			(width 0.05715)
			(type default)
		)
		(layer "In6.Cu")
	)
	(gr_line
		(start 366.79505 -284.931358)
		(end 366.79505 -284.931104)
		(stroke
			(width 0.05715)
			(type default)
		)
		(layer "In6.Cu")
	)
	(gr_line
		(start 366.79505 -284.931104)
		(end 366.80013 -284.928056)
		(stroke
			(width 0.05715)
			(type default)
		)
		(layer "In6.Cu")
	)
	(gr_line
		(start 366.80013 -284.928056)
		(end 366.800384 -284.928056)
		(stroke
			(width 0.05715)
			(type default)
		)
		(layer "In6.Cu")
	)
	(gr_arc
		(start 366.875568 -285.105602)
		(mid 366.876076 -285.105348)
		(end 366.876584 -285.105094)
		(stroke
			(width 0.05715)
			(type default)
		)
		(layer "In6.Cu")
	)
	(gr_line
		(start 366.876584 -285.105094)
		(end 366.877854 -285.104332)
		(stroke
			(width 0.05715)
			(type default)
		)
		(layer "In6.Cu")
	)
	(gr_line
		(start 366.877854 -295.468548)
		(end 366.877346 -295.468294)
		(stroke
			(width 0.05715)
			(type default)
		)
		(layer "In6.Cu")
	)
	(gr_line
		(start 366.877854 -285.104332)
		(end 366.880394 -285.102808)
		(stroke
			(width 0.05715)
			(type default)
		)
		(layer "In6.Cu")
	)
	(gr_line
		(start 366.87887 -295.469056)
		(end 366.877854 -295.468548)
		(stroke
			(width 0.05715)
			(type default)
		)
		(layer "In6.Cu")
	)
	(gr_line
		(start 366.880648 -295.470072)
		(end 366.87887 -295.469056)
		(stroke
			(width 0.05715)
			(type default)
		)
		(layer "In6.Cu")
	)
	(gr_line
		(start 366.882934 -295.471596)
		(end 366.882172 -295.471088)
		(stroke
			(width 0.05715)
			(type default)
		)
		(layer "In6.Cu")
	)
	(gr_arc
		(start 366.884712 -285.750508)
		(mid 366.882682 -285.749234)
		(end 366.880648 -285.747968)
		(stroke
			(width 0.05715)
			(type default)
		)
		(layer "In6.Cu")
	)
	(gr_line
		(start 366.90935 -295.486836)
		(end 366.908588 -295.486328)
		(stroke
			(width 0.05715)
			(type default)
		)
		(layer "In6.Cu")
	)
	(gr_line
		(start 366.910112 -295.487344)
		(end 366.90935 -295.486836)
		(stroke
			(width 0.05715)
			(type default)
		)
		(layer "In6.Cu")
	)
	(gr_line
		(start 366.91697 -295.491408)
		(end 366.910112 -295.487344)
		(stroke
			(width 0.05715)
			(type default)
		)
		(layer "In6.Cu")
	)
	(gr_line
		(start 366.923828 -296.353484)
		(end 366.923828 -296.325036)
		(stroke
			(width 0.05715)
			(type default)
		)
		(layer "In6.Cu")
	)
	(gr_line
		(start 366.923828 -296.325036)
		(end 366.969548 -296.279316)
		(stroke
			(width 0.05715)
			(type default)
		)
		(layer "In6.Cu")
	)
	(gr_arc
		(start 366.924844 -295.496996)
		(mid 366.920919 -295.494185)
		(end 366.91697 -295.491408)
		(stroke
			(width 0.05715)
			(type default)
		)
		(layer "In6.Cu")
	)
	(gr_line
		(start 366.969548 -296.007028)
		(end 366.969802 -296.006774)
		(stroke
			(width 0.05715)
			(type default)
		)
		(layer "In6.Cu")
	)
	(gr_arc
		(start 366.969548 -287.856168)
		(mid 366.969548 -287.855279)
		(end 366.969548 -287.85439)
		(stroke
			(width 0.05715)
			(type default)
		)
		(layer "In6.Cu")
	)
	(gr_line
		(start 366.969802 -295.95572)
		(end 366.969548 -295.955974)
		(stroke
			(width 0.05715)
			(type default)
		)
		(layer "In6.Cu")
	)
	(gr_line
		(start 367.160048 -296.086022)
		(end 367.160302 -296.085768)
		(stroke
			(width 0.05715)
			(type default)
		)
		(layer "In6.Cu")
	)
	(gr_line
		(start 367.205768 -296.353484)
		(end 367.205768 -296.325036)
		(stroke
			(width 0.05715)
			(type default)
		)
		(layer "In6.Cu")
	)
	(gr_line
		(start 367.205768 -296.325036)
		(end 367.160048 -296.279316)
		(stroke
			(width 0.05715)
			(type default)
		)
		(layer "In6.Cu")
	)
	(gr_arc
		(start 367.212626 -289.01136)
		(mid 367.209443 -289.013635)
		(end 367.206276 -289.015932)
		(stroke
			(width 0.05715)
			(type default)
		)
		(layer "In6.Cu")
	)
	(gr_line
		(start 367.21796 -289.007804)
		(end 367.21923 -289.007042)
		(stroke
			(width 0.05715)
			(type default)
		)
		(layer "In6.Cu")
	)
	(gr_arc
		(start 367.218214 -287.388046)
		(mid 367.210551 -287.39319)
		(end 367.202974 -287.39846)
		(stroke
			(width 0.05715)
			(type default)
		)
		(layer "In6.Cu")
	)
	(gr_line
		(start 367.218214 -287.388046)
		(end 367.219484 -287.387284)
		(stroke
			(width 0.05715)
			(type default)
		)
		(layer "In6.Cu")
	)
	(gr_line
		(start 367.219484 -287.387284)
		(end 367.220246 -287.386776)
		(stroke
			(width 0.05715)
			(type default)
		)
		(layer "In6.Cu")
	)
	(gr_line
		(start 367.222024 -289.005518)
		(end 367.222786 -289.00501)
		(stroke
			(width 0.05715)
			(type default)
		)
		(layer "In6.Cu")
	)
	(gr_line
		(start 367.222786 -289.00501)
		(end 367.224056 -289.004248)
		(stroke
			(width 0.05715)
			(type default)
		)
		(layer "In6.Cu")
	)
	(gr_line
		(start 367.224056 -289.004248)
		(end 367.22558 -289.003486)
		(stroke
			(width 0.05715)
			(type default)
		)
		(layer "In6.Cu")
	)
	(gr_line
		(start 367.227104 -289.00247)
		(end 367.227612 -289.002216)
		(stroke
			(width 0.05715)
			(type default)
		)
		(layer "In6.Cu")
	)
	(gr_line
		(start 367.227612 -289.002216)
		(end 367.230152 -289.000946)
		(stroke
			(width 0.05715)
			(type default)
		)
		(layer "In6.Cu")
	)
	(gr_line
		(start 367.230152 -289.000946)
		(end 367.230914 -289.000438)
		(stroke
			(width 0.05715)
			(type default)
		)
		(layer "In6.Cu")
	)
	(gr_line
		(start 367.230914 -289.000438)
		(end 367.23193 -288.99993)
		(stroke
			(width 0.05715)
			(type default)
		)
		(layer "In6.Cu")
	)
	(gr_line
		(start 367.246662 -287.371282)
		(end 367.247424 -287.370774)
		(stroke
			(width 0.05715)
			(type default)
		)
		(layer "In6.Cu")
	)
	(gr_line
		(start 367.248694 -287.370012)
		(end 367.250472 -287.36925)
		(stroke
			(width 0.05715)
			(type default)
		)
		(layer "In6.Cu")
	)
	(gr_line
		(start 367.251742 -287.368488)
		(end 367.252504 -287.36798)
		(stroke
			(width 0.05715)
			(type default)
		)
		(layer "In6.Cu")
	)
	(gr_line
		(start 367.251996 -284.128464)
		(end 367.252504 -284.12821)
		(stroke
			(width 0.05715)
			(type default)
		)
		(layer "In6.Cu")
	)
	(gr_line
		(start 367.252504 -284.12821)
		(end 367.253774 -284.127448)
		(stroke
			(width 0.05715)
			(type default)
		)
		(layer "In6.Cu")
	)
	(gr_line
		(start 367.253774 -284.127448)
		(end 367.255806 -284.126432)
		(stroke
			(width 0.05715)
			(type default)
		)
		(layer "In6.Cu")
	)
	(gr_line
		(start 367.255806 -284.126432)
		(end 367.25606 -284.126178)
		(stroke
			(width 0.05715)
			(type default)
		)
		(layer "In6.Cu")
	)
	(gr_line
		(start 367.322608 -289.168078)
		(end 367.324132 -289.167062)
		(stroke
			(width 0.05715)
			(type default)
		)
		(layer "In6.Cu")
	)
	(gr_line
		(start 367.324132 -289.167062)
		(end 367.32464 -289.166808)
		(stroke
			(width 0.05715)
			(type default)
		)
		(layer "In6.Cu")
	)
	(gr_line
		(start 367.341404 -284.297374)
		(end 367.341658 -284.29712)
		(stroke
			(width 0.05715)
			(type default)
		)
		(layer "In6.Cu")
	)
	(gr_line
		(start 367.346484 -287.53435)
		(end 367.346992 -287.534096)
		(stroke
			(width 0.05715)
			(type default)
		)
		(layer "In6.Cu")
	)
	(gr_line
		(start 367.346992 -287.534096)
		(end 367.347754 -287.533588)
		(stroke
			(width 0.05715)
			(type default)
		)
		(layer "In6.Cu")
	)
	(gr_line
		(start 367.347754 -287.533588)
		(end 367.34877 -287.53308)
		(stroke
			(width 0.05715)
			(type default)
		)
		(layer "In6.Cu")
	)
	(gr_line
		(start 367.34877 -287.53308)
		(end 367.35004 -287.532318)
		(stroke
			(width 0.05715)
			(type default)
		)
		(layer "In6.Cu")
	)
	(gr_line
		(start 367.35004 -287.532318)
		(end 367.350802 -287.53181)
		(stroke
			(width 0.05715)
			(type default)
		)
		(layer "In6.Cu")
	)
	(gr_line
		(start 367.350802 -287.53181)
		(end 367.352072 -287.531048)
		(stroke
			(width 0.05715)
			(type default)
		)
		(layer "In6.Cu")
	)
	(gr_line
		(start 367.352072 -287.531048)
		(end 367.352834 -287.53054)
		(stroke
			(width 0.05715)
			(type default)
		)
		(layer "In6.Cu")
	)
	(gr_line
		(start 367.352072 -284.291024)
		(end 367.35258 -284.29077)
		(stroke
			(width 0.05715)
			(type default)
		)
		(layer "In6.Cu")
	)
	(gr_arc
		(start 367.397538 -288.208974)
		(mid 367.394372 -288.206676)
		(end 367.391188 -288.204402)
		(stroke
			(width 0.05715)
			(type default)
		)
		(layer "In6.Cu")
	)
	(gr_line
		(start 367.439448 -295.145968)
		(end 367.439194 -295.145968)
		(stroke
			(width 0.05715)
			(type default)
		)
		(layer "In6.Cu")
	)
	(gr_line
		(start 367.630202 -295.145968)
		(end 367.629948 -295.145968)
		(stroke
			(width 0.05715)
			(type default)
		)
		(layer "In6.Cu")
	)
	(gr_line
		(start 367.723166 -295.634156)
		(end 367.721896 -295.633394)
		(stroke
			(width 0.05715)
			(type default)
		)
		(layer "In6.Cu")
	)
	(gr_line
		(start 367.83264 -286.236156)
		(end 367.534698 -286.236156)
		(stroke
			(width 0.05715)
			(type default)
		)
		(layer "In6.Cu")
	)
	(gr_line
		(start 367.83264 -284.616144)
		(end 367.534698 -284.616144)
		(stroke
			(width 0.05715)
			(type default)
		)
		(layer "In6.Cu")
	)
	(gr_line
		(start 367.83264 -282.996132)
		(end 367.534698 -282.996132)
		(stroke
			(width 0.05715)
			(type default)
		)
		(layer "In6.Cu")
	)
	(gr_line
		(start 367.874296 -296.353484)
		(end 367.874296 -296.325036)
		(stroke
			(width 0.05715)
			(type default)
		)
		(layer "In6.Cu")
	)
	(gr_line
		(start 367.874296 -296.325036)
		(end 367.920016 -296.279316)
		(stroke
			(width 0.05715)
			(type default)
		)
		(layer "In6.Cu")
	)
	(gr_line
		(start 367.901982 -286.305498)
		(end 367.83264 -286.236156)
		(stroke
			(width 0.05715)
			(type default)
		)
		(layer "In6.Cu")
	)
	(gr_line
		(start 367.901982 -283.065474)
		(end 367.83264 -282.996132)
		(stroke
			(width 0.05715)
			(type default)
		)
		(layer "In6.Cu")
	)
	(gr_line
		(start 367.915444 -284.698948)
		(end 367.83264 -284.616144)
		(stroke
			(width 0.05715)
			(type default)
		)
		(layer "In6.Cu")
	)
	(gr_arc
		(start 367.915444 -284.698948)
		(mid 367.917236 -284.71027)
		(end 367.919254 -284.721554)
		(stroke
			(width 0.05715)
			(type default)
		)
		(layer "In6.Cu")
	)
	(gr_line
		(start 367.919508 -296.007282)
		(end 367.919508 -296.006774)
		(stroke
			(width 0.05715)
			(type default)
		)
		(layer "In6.Cu")
	)
	(gr_arc
		(start 368.090196 -286.34182)
		(mid 368.092218 -286.330409)
		(end 368.094006 -286.31896)
		(stroke
			(width 0.05715)
			(type default)
		)
		(layer "In6.Cu")
	)
	(gr_arc
		(start 368.090196 -283.101796)
		(mid 368.092217 -283.090385)
		(end 368.094006 -283.078936)
		(stroke
			(width 0.05715)
			(type default)
		)
		(layer "In6.Cu")
	)
	(gr_line
		(start 368.094006 -286.31896)
		(end 368.17681 -286.236156)
		(stroke
			(width 0.05715)
			(type default)
		)
		(layer "In6.Cu")
	)
	(gr_line
		(start 368.094006 -283.078936)
		(end 368.17681 -282.996132)
		(stroke
			(width 0.05715)
			(type default)
		)
		(layer "In6.Cu")
	)
	(gr_line
		(start 368.107468 -284.685486)
		(end 368.17681 -284.616144)
		(stroke
			(width 0.05715)
			(type default)
		)
		(layer "In6.Cu")
	)
	(gr_line
		(start 368.110516 -296.086276)
		(end 368.110516 -296.085768)
		(stroke
			(width 0.05715)
			(type default)
		)
		(layer "In6.Cu")
	)
	(gr_line
		(start 368.156236 -296.353484)
		(end 368.156236 -296.325036)
		(stroke
			(width 0.05715)
			(type default)
		)
		(layer "In6.Cu")
	)
	(gr_line
		(start 368.156236 -296.325036)
		(end 368.110516 -296.279316)
		(stroke
			(width 0.05715)
			(type default)
		)
		(layer "In6.Cu")
	)
	(gr_line
		(start 368.17681 -286.236156)
		(end 368.474752 -286.236156)
		(stroke
			(width 0.05715)
			(type default)
		)
		(layer "In6.Cu")
	)
	(gr_line
		(start 368.17681 -284.616144)
		(end 368.474752 -284.616144)
		(stroke
			(width 0.05715)
			(type default)
		)
		(layer "In6.Cu")
	)
	(gr_line
		(start 368.17681 -282.996132)
		(end 368.474752 -282.996132)
		(stroke
			(width 0.05715)
			(type default)
		)
		(layer "In6.Cu")
	)
	(gr_line
		(start 368.18443 -285.099252)
		(end 368.18316 -285.09849)
		(stroke
			(width 0.05715)
			(type default)
		)
		(layer "In6.Cu")
	)
	(gr_line
		(start 368.18697 -285.100776)
		(end 368.186208 -285.100268)
		(stroke
			(width 0.05715)
			(type default)
		)
		(layer "In6.Cu")
	)
	(gr_line
		(start 368.189256 -287.370012)
		(end 368.19078 -287.368996)
		(stroke
			(width 0.05715)
			(type default)
		)
		(layer "In6.Cu")
	)
	(gr_line
		(start 368.189256 -285.102046)
		(end 368.18824 -285.101538)
		(stroke
			(width 0.05715)
			(type default)
		)
		(layer "In6.Cu")
	)
	(gr_line
		(start 368.19078 -285.103062)
		(end 368.189256 -285.102046)
		(stroke
			(width 0.05715)
			(type default)
		)
		(layer "In6.Cu")
	)
	(gr_line
		(start 368.191796 -287.368488)
		(end 368.192558 -287.36798)
		(stroke
			(width 0.05715)
			(type default)
		)
		(layer "In6.Cu")
	)
	(gr_line
		(start 368.191796 -285.10357)
		(end 368.19078 -285.103062)
		(stroke
			(width 0.05715)
			(type default)
		)
		(layer "In6.Cu")
	)
	(gr_line
		(start 368.198908 -285.107634)
		(end 368.197892 -285.107126)
		(stroke
			(width 0.05715)
			(type default)
		)
		(layer "In6.Cu")
	)
	(gr_line
		(start 368.199416 -285.107888)
		(end 368.198908 -285.107634)
		(stroke
			(width 0.05715)
			(type default)
		)
		(layer "In6.Cu")
	)
	(gr_line
		(start 368.286538 -287.53435)
		(end 368.287046 -287.534096)
		(stroke
			(width 0.05715)
			(type default)
		)
		(layer "In6.Cu")
	)
	(gr_line
		(start 368.287046 -287.534096)
		(end 368.287808 -287.533588)
		(stroke
			(width 0.05715)
			(type default)
		)
		(layer "In6.Cu")
	)
	(gr_line
		(start 368.287046 -284.938216)
		(end 368.284252 -284.936692)
		(stroke
			(width 0.05715)
			(type default)
		)
		(layer "In6.Cu")
	)
	(gr_line
		(start 368.287808 -287.533588)
		(end 368.288824 -287.53308)
		(stroke
			(width 0.05715)
			(type default)
		)
		(layer "In6.Cu")
	)
	(gr_line
		(start 368.287808 -284.938724)
		(end 368.287046 -284.938216)
		(stroke
			(width 0.05715)
			(type default)
		)
		(layer "In6.Cu")
	)
	(gr_line
		(start 368.288824 -287.53308)
		(end 368.290094 -287.532318)
		(stroke
			(width 0.05715)
			(type default)
		)
		(layer "In6.Cu")
	)
	(gr_line
		(start 368.288824 -284.939232)
		(end 368.287808 -284.938724)
		(stroke
			(width 0.05715)
			(type default)
		)
		(layer "In6.Cu")
	)
	(gr_line
		(start 368.290094 -287.532318)
		(end 368.290856 -287.53181)
		(stroke
			(width 0.05715)
			(type default)
		)
		(layer "In6.Cu")
	)
	(gr_line
		(start 368.290602 -284.940248)
		(end 368.288824 -284.939232)
		(stroke
			(width 0.05715)
			(type default)
		)
		(layer "In6.Cu")
	)
	(gr_line
		(start 368.290856 -287.53181)
		(end 368.292126 -287.531048)
		(stroke
			(width 0.05715)
			(type default)
		)
		(layer "In6.Cu")
	)
	(gr_line
		(start 368.292126 -287.531048)
		(end 368.292888 -287.53054)
		(stroke
			(width 0.05715)
			(type default)
		)
		(layer "In6.Cu")
	)
	(gr_line
		(start 368.293142 -284.941772)
		(end 368.292126 -284.941264)
		(stroke
			(width 0.05715)
			(type default)
		)
		(layer "In6.Cu")
	)
	(gr_line
		(start 368.294158 -284.942534)
		(end 368.293142 -284.941772)
		(stroke
			(width 0.05715)
			(type default)
		)
		(layer "In6.Cu")
	)
	(gr_line
		(start 368.319304 -284.957012)
		(end 368.318796 -284.956758)
		(stroke
			(width 0.05715)
			(type default)
		)
		(layer "In6.Cu")
	)
	(gr_line
		(start 368.320066 -284.95752)
		(end 368.319304 -284.957012)
		(stroke
			(width 0.05715)
			(type default)
		)
		(layer "In6.Cu")
	)
	(gr_line
		(start 368.326924 -284.961584)
		(end 368.320066 -284.95752)
		(stroke
			(width 0.05715)
			(type default)
		)
		(layer "In6.Cu")
	)
	(gr_arc
		(start 368.334798 -284.967172)
		(mid 368.330873 -284.964361)
		(end 368.326924 -284.961584)
		(stroke
			(width 0.05715)
			(type default)
		)
		(layer "In6.Cu")
	)
	(gr_line
		(start 368.379502 -295.145968)
		(end 368.379248 -295.145968)
		(stroke
			(width 0.05715)
			(type default)
		)
		(layer "In6.Cu")
	)
	(gr_line
		(start 368.570256 -295.145968)
		(end 368.570002 -295.145968)
		(stroke
			(width 0.05715)
			(type default)
		)
		(layer "In6.Cu")
	)
	(gr_line
		(start 368.66195 -286.558482)
		(end 368.662458 -286.558228)
		(stroke
			(width 0.05715)
			(type default)
		)
		(layer "In6.Cu")
	)
	(gr_line
		(start 368.789966 -286.70504)
		(end 368.794792 -286.702246)
		(stroke
			(width 0.05715)
			(type default)
		)
		(layer "In6.Cu")
	)
	(gr_line
		(start 368.794792 -286.702246)
		(end 368.796824 -286.700722)
		(stroke
			(width 0.05715)
			(type default)
		)
		(layer "In6.Cu")
	)
	(gr_arc
		(start 368.796824 -286.700722)
		(mid 368.80154 -286.697445)
		(end 368.806222 -286.694118)
		(stroke
			(width 0.05715)
			(type default)
		)
		(layer "In6.Cu")
	)
	(gr_line
		(start 368.806476 -296.353484)
		(end 368.806476 -296.325036)
		(stroke
			(width 0.05715)
			(type default)
		)
		(layer "In6.Cu")
	)
	(gr_line
		(start 368.806476 -296.325036)
		(end 368.852196 -296.279316)
		(stroke
			(width 0.05715)
			(type default)
		)
		(layer "In6.Cu")
	)
	(gr_arc
		(start 369.08486 -294.79494)
		(mid 369.088785 -294.797751)
		(end 369.092734 -294.800528)
		(stroke
			(width 0.05715)
			(type default)
		)
		(layer "In6.Cu")
	)
	(gr_arc
		(start 369.08486 -293.174928)
		(mid 369.087648 -293.176842)
		(end 369.090448 -293.178738)
		(stroke
			(width 0.05715)
			(type default)
		)
		(layer "In6.Cu")
	)
	(gr_arc
		(start 369.08486 -291.554916)
		(mid 369.088785 -291.557727)
		(end 369.092734 -291.560504)
		(stroke
			(width 0.05715)
			(type default)
		)
		(layer "In6.Cu")
	)
	(gr_arc
		(start 369.08486 -289.934904)
		(mid 369.088785 -289.937715)
		(end 369.092734 -289.940492)
		(stroke
			(width 0.05715)
			(type default)
		)
		(layer "In6.Cu")
	)
	(gr_arc
		(start 369.08486 -285.075122)
		(mid 369.088785 -285.077933)
		(end 369.092734 -285.08071)
		(stroke
			(width 0.05715)
			(type default)
		)
		(layer "In6.Cu")
	)
	(gr_line
		(start 369.088416 -296.353484)
		(end 369.088416 -296.325036)
		(stroke
			(width 0.05715)
			(type default)
		)
		(layer "In6.Cu")
	)
	(gr_line
		(start 369.088416 -296.325036)
		(end 369.042696 -296.279316)
		(stroke
			(width 0.05715)
			(type default)
		)
		(layer "In6.Cu")
	)
	(gr_arc
		(start 369.09121 -293.1795)
		(mid 369.091972 -293.180009)
		(end 369.092734 -293.180516)
		(stroke
			(width 0.05715)
			(type default)
		)
		(layer "In6.Cu")
	)
	(gr_line
		(start 369.09248 -294.800528)
		(end 369.092734 -294.800528)
		(stroke
			(width 0.05715)
			(type default)
		)
		(layer "In6.Cu")
	)
	(gr_arc
		(start 369.09248 -294.800528)
		(mid 369.095522 -294.802569)
		(end 369.098576 -294.804592)
		(stroke
			(width 0.05715)
			(type default)
		)
		(layer "In6.Cu")
	)
	(gr_arc
		(start 369.093496 -293.181024)
		(mid 369.093115 -293.18077)
		(end 369.092734 -293.180516)
		(stroke
			(width 0.05715)
			(type default)
		)
		(layer "In6.Cu")
	)
	(gr_arc
		(start 369.093496 -291.561012)
		(mid 369.093115 -291.560758)
		(end 369.092734 -291.560504)
		(stroke
			(width 0.05715)
			(type default)
		)
		(layer "In6.Cu")
	)
	(gr_arc
		(start 369.093496 -289.941)
		(mid 369.093115 -289.940746)
		(end 369.092734 -289.940492)
		(stroke
			(width 0.05715)
			(type default)
		)
		(layer "In6.Cu")
	)
	(gr_line
		(start 369.095528 -285.082742)
		(end 369.092734 -285.08071)
		(stroke
			(width 0.05715)
			(type default)
		)
		(layer "In6.Cu")
	)
	(gr_line
		(start 369.100608 -293.185088)
		(end 369.093496 -293.181024)
		(stroke
			(width 0.05715)
			(type default)
		)
		(layer "In6.Cu")
	)
	(gr_line
		(start 369.100608 -291.565076)
		(end 369.093496 -291.561012)
		(stroke
			(width 0.05715)
			(type default)
		)
		(layer "In6.Cu")
	)
	(gr_line
		(start 369.100608 -289.945064)
		(end 369.093496 -289.941)
		(stroke
			(width 0.05715)
			(type default)
		)
		(layer "In6.Cu")
	)
	(gr_line
		(start 369.100608 -285.08579)
		(end 369.095528 -285.082742)
		(stroke
			(width 0.05715)
			(type default)
		)
		(layer "In6.Cu")
	)
	(gr_line
		(start 369.103656 -294.807132)
		(end 369.098576 -294.804592)
		(stroke
			(width 0.05715)
			(type default)
		)
		(layer "In6.Cu")
	)
	(gr_line
		(start 369.12042 -293.855394)
		(end 369.121182 -293.854886)
		(stroke
			(width 0.05715)
			(type default)
		)
		(layer "In6.Cu")
	)
	(gr_line
		(start 369.121944 -293.854378)
		(end 369.130834 -293.849298)
		(stroke
			(width 0.05715)
			(type default)
		)
		(layer "In6.Cu")
	)
	(gr_line
		(start 369.127024 -289.960558)
		(end 369.126262 -289.96005)
		(stroke
			(width 0.05715)
			(type default)
		)
		(layer "In6.Cu")
	)
	(gr_line
		(start 369.129818 -290.609782)
		(end 369.13058 -290.609274)
		(stroke
			(width 0.05715)
			(type default)
		)
		(layer "In6.Cu")
	)
	(gr_line
		(start 369.132358 -290.608258)
		(end 369.133628 -290.607496)
		(stroke
			(width 0.05715)
			(type default)
		)
		(layer "In6.Cu")
	)
	(gr_line
		(start 369.132612 -293.20363)
		(end 369.13185 -293.203376)
		(stroke
			(width 0.05715)
			(type default)
		)
		(layer "In6.Cu")
	)
	(gr_line
		(start 369.133628 -289.964368)
		(end 369.127024 -289.960558)
		(stroke
			(width 0.05715)
			(type default)
		)
		(layer "In6.Cu")
	)
	(gr_line
		(start 369.153186 -292.216078)
		(end 369.15344 -292.216078)
		(stroke
			(width 0.05715)
			(type default)
		)
		(layer "In6.Cu")
	)
	(gr_line
		(start 369.196874 -293.020496)
		(end 369.196874 -293.02075)
		(stroke
			(width 0.05715)
			(type default)
		)
		(layer "In6.Cu")
	)
	(gr_line
		(start 369.22329 -289.795966)
		(end 369.222528 -289.795458)
		(stroke
			(width 0.05715)
			(type default)
		)
		(layer "In6.Cu")
	)
	(gr_line
		(start 369.22837 -293.03853)
		(end 369.228116 -293.038784)
		(stroke
			(width 0.05715)
			(type default)
		)
		(layer "In6.Cu")
	)
	(gr_line
		(start 369.236244 -290.768532)
		(end 369.235736 -290.768786)
		(stroke
			(width 0.05715)
			(type default)
		)
		(layer "In6.Cu")
	)
	(gr_arc
		(start 369.236244 -289.803332)
		(mid 369.235102 -289.802569)
		(end 369.233958 -289.801808)
		(stroke
			(width 0.05715)
			(type default)
		)
		(layer "In6.Cu")
	)
	(gr_arc
		(start 369.239292 -294.006778)
		(mid 369.241963 -294.005261)
		(end 369.244626 -294.00373)
		(stroke
			(width 0.05715)
			(type default)
		)
		(layer "In6.Cu")
	)
	(gr_arc
		(start 369.244626 -293.048182)
		(mid 369.241963 -293.046524)
		(end 369.239292 -293.04488)
		(stroke
			(width 0.05715)
			(type default)
		)
		(layer "In6.Cu")
	)
	(gr_line
		(start 369.248436 -292.381432)
		(end 369.249198 -292.380924)
		(stroke
			(width 0.05715)
			(type default)
		)
		(layer "In6.Cu")
	)
	(gr_line
		(start 369.267994 -294.680132)
		(end 369.250214 -294.670226)
		(stroke
			(width 0.05715)
			(type default)
		)
		(layer "In6.Cu")
	)
	(gr_line
		(start 369.26901 -294.682164)
		(end 369.267994 -294.680132)
		(stroke
			(width 0.05715)
			(type default)
		)
		(layer "In6.Cu")
	)
	(gr_arc
		(start 369.271296 -294.683688)
		(mid 369.270154 -294.682924)
		(end 369.26901 -294.682164)
		(stroke
			(width 0.05715)
			(type default)
		)
		(layer "In6.Cu")
	)
	(gr_arc
		(start 369.279424 -289.120326)
		(mid 369.280441 -289.119565)
		(end 369.281456 -289.118802)
		(stroke
			(width 0.05715)
			(type default)
		)
		(layer "In6.Cu")
	)
	(gr_line
		(start 369.32362 -283.769054)
		(end 369.323874 -283.767784)
		(stroke
			(width 0.05715)
			(type default)
		)
		(layer "In6.Cu")
	)
	(gr_arc
		(start 369.324128 -283.76626)
		(mid 369.324 -283.767022)
		(end 369.323874 -283.767784)
		(stroke
			(width 0.05715)
			(type default)
		)
		(layer "In6.Cu")
	)
	(gr_line
		(start 369.505738 -285.389066)
		(end 369.505992 -285.390336)
		(stroke
			(width 0.05715)
			(type default)
		)
		(layer "In6.Cu")
	)
	(gr_arc
		(start 369.506246 -285.392114)
		(mid 369.50612 -285.391225)
		(end 369.505992 -285.390336)
		(stroke
			(width 0.05715)
			(type default)
		)
		(layer "In6.Cu")
	)
	(gr_line
		(start 369.5065 -287.081214)
		(end 369.506246 -287.082484)
		(stroke
			(width 0.05715)
			(type default)
		)
		(layer "In6.Cu")
	)
	(gr_line
		(start 369.510056 -287.03651)
		(end 369.510056 -287.038288)
		(stroke
			(width 0.05715)
			(type default)
		)
		(layer "In6.Cu")
	)
	(gr_arc
		(start 369.565428 -286.579564)
		(mid 369.55879 -286.584215)
		(end 369.55222 -286.588962)
		(stroke
			(width 0.05715)
			(type default)
		)
		(layer "In6.Cu")
	)
	(gr_line
		(start 369.565428 -286.579564)
		(end 369.568222 -286.57804)
		(stroke
			(width 0.05715)
			(type default)
		)
		(layer "In6.Cu")
	)
	(gr_line
		(start 369.697508 -283.483812)
		(end 369.698778 -283.48305)
		(stroke
			(width 0.05715)
			(type default)
		)
		(layer "In6.Cu")
	)
	(gr_line
		(start 369.744498 -296.353484)
		(end 369.744498 -296.325036)
		(stroke
			(width 0.05715)
			(type default)
		)
		(layer "In6.Cu")
	)
	(gr_line
		(start 369.744498 -296.325036)
		(end 369.790218 -296.279316)
		(stroke
			(width 0.05715)
			(type default)
		)
		(layer "In6.Cu")
	)
	(gr_line
		(start 369.78971 -296.007282)
		(end 369.78971 -296.006774)
		(stroke
			(width 0.05715)
			(type default)
		)
		(layer "In6.Cu")
	)
	(gr_line
		(start 369.931442 -300.289976)
		(end 369.920774 -300.264322)
		(stroke
			(width 0.07112)
			(type default)
		)
		(layer "In6.Cu")
	)
	(gr_line
		(start 369.946682 -300.31309)
		(end 369.931442 -300.289976)
		(stroke
			(width 0.07112)
			(type default)
		)
		(layer "In6.Cu")
	)
	(gr_line
		(start 369.946936 -300.31309)
		(end 369.946682 -300.31309)
		(stroke
			(width 0.07112)
			(type default)
		)
		(layer "In6.Cu")
	)
	(gr_line
		(start 369.980718 -296.086276)
		(end 369.980718 -296.085768)
		(stroke
			(width 0.05715)
			(type default)
		)
		(layer "In6.Cu")
	)
	(gr_line
		(start 370.026438 -296.353484)
		(end 370.026438 -296.325036)
		(stroke
			(width 0.05715)
			(type default)
		)
		(layer "In6.Cu")
	)
	(gr_line
		(start 370.026438 -296.325036)
		(end 369.980718 -296.279316)
		(stroke
			(width 0.05715)
			(type default)
		)
		(layer "In6.Cu")
	)
	(gr_line
		(start 370.535962 -281.702256)
		(end 370.543074 -281.698192)
		(stroke
			(width 0.05715)
			(type default)
		)
		(layer "In6.Cu")
	)
	(gr_line
		(start 370.543836 -295.634664)
		(end 370.542566 -295.633902)
		(stroke
			(width 0.05715)
			(type default)
		)
		(layer "In6.Cu")
	)
	(gr_line
		(start 370.5479 -295.63695)
		(end 370.546376 -295.635934)
		(stroke
			(width 0.05715)
			(type default)
		)
		(layer "In6.Cu")
	)
	(gr_line
		(start 370.549424 -295.637712)
		(end 370.5479 -295.63695)
		(stroke
			(width 0.05715)
			(type default)
		)
		(layer "In6.Cu")
	)
	(gr_line
		(start 370.637816 -295.468548)
		(end 370.637308 -295.468294)
		(stroke
			(width 0.05715)
			(type default)
		)
		(layer "In6.Cu")
	)
	(gr_line
		(start 370.638832 -295.469056)
		(end 370.637816 -295.468548)
		(stroke
			(width 0.05715)
			(type default)
		)
		(layer "In6.Cu")
	)
	(gr_line
		(start 370.64061 -295.470072)
		(end 370.638832 -295.469056)
		(stroke
			(width 0.05715)
			(type default)
		)
		(layer "In6.Cu")
	)
	(gr_line
		(start 370.642896 -295.471596)
		(end 370.642134 -295.471088)
		(stroke
			(width 0.05715)
			(type default)
		)
		(layer "In6.Cu")
	)
	(gr_line
		(start 370.652802 -286.236156)
		(end 370.35486 -286.236156)
		(stroke
			(width 0.05715)
			(type default)
		)
		(layer "In6.Cu")
	)
	(gr_line
		(start 370.652802 -284.616144)
		(end 370.35486 -284.616144)
		(stroke
			(width 0.05715)
			(type default)
		)
		(layer "In6.Cu")
	)
	(gr_line
		(start 370.652802 -282.996132)
		(end 370.35486 -282.996132)
		(stroke
			(width 0.05715)
			(type default)
		)
		(layer "In6.Cu")
	)
	(gr_line
		(start 370.652802 -281.37612)
		(end 370.35486 -281.37612)
		(stroke
			(width 0.05715)
			(type default)
		)
		(layer "In6.Cu")
	)
	(gr_line
		(start 370.669312 -295.486836)
		(end 370.66855 -295.486328)
		(stroke
			(width 0.05715)
			(type default)
		)
		(layer "In6.Cu")
	)
	(gr_line
		(start 370.670074 -295.487344)
		(end 370.669312 -295.486836)
		(stroke
			(width 0.05715)
			(type default)
		)
		(layer "In6.Cu")
	)
	(gr_line
		(start 370.676932 -295.491408)
		(end 370.670074 -295.487344)
		(stroke
			(width 0.05715)
			(type default)
		)
		(layer "In6.Cu")
	)
	(gr_line
		(start 370.684552 -296.353484)
		(end 370.684552 -296.325036)
		(stroke
			(width 0.05715)
			(type default)
		)
		(layer "In6.Cu")
	)
	(gr_line
		(start 370.684552 -296.325036)
		(end 370.730272 -296.279316)
		(stroke
			(width 0.05715)
			(type default)
		)
		(layer "In6.Cu")
	)
	(gr_arc
		(start 370.68506 -295.496996)
		(mid 370.681009 -295.494183)
		(end 370.676932 -295.491408)
		(stroke
			(width 0.05715)
			(type default)
		)
		(layer "In6.Cu")
	)
	(gr_line
		(start 370.722144 -286.305498)
		(end 370.652802 -286.236156)
		(stroke
			(width 0.05715)
			(type default)
		)
		(layer "In6.Cu")
	)
	(gr_line
		(start 370.722144 -281.445462)
		(end 370.652802 -281.37612)
		(stroke
			(width 0.05715)
			(type default)
		)
		(layer "In6.Cu")
	)
	(gr_line
		(start 370.729764 -296.007282)
		(end 370.729764 -296.006774)
		(stroke
			(width 0.05715)
			(type default)
		)
		(layer "In6.Cu")
	)
	(gr_line
		(start 370.735606 -284.698948)
		(end 370.652802 -284.616144)
		(stroke
			(width 0.05715)
			(type default)
		)
		(layer "In6.Cu")
	)
	(gr_arc
		(start 370.735606 -284.698948)
		(mid 370.737392 -284.710398)
		(end 370.739416 -284.721808)
		(stroke
			(width 0.05715)
			(type default)
		)
		(layer "In6.Cu")
	)
	(gr_line
		(start 370.735606 -283.078936)
		(end 370.652802 -282.996132)
		(stroke
			(width 0.05715)
			(type default)
		)
		(layer "In6.Cu")
	)
	(gr_arc
		(start 370.735606 -283.078936)
		(mid 370.737397 -283.090258)
		(end 370.739416 -283.101542)
		(stroke
			(width 0.05715)
			(type default)
		)
		(layer "In6.Cu")
	)
	(gr_line
		(start 370.891308 -397.156432)
		(end 370.943632 -397.208756)
		(stroke
			(width 0.07112)
			(type default)
		)
		(layer "In6.Cu")
	)
	(gr_arc
		(start 370.910358 -286.34182)
		(mid 370.91238 -286.330409)
		(end 370.914168 -286.31896)
		(stroke
			(width 0.05715)
			(type default)
		)
		(layer "In6.Cu")
	)
	(gr_arc
		(start 370.910358 -281.481784)
		(mid 370.912381 -281.470374)
		(end 370.914168 -281.458924)
		(stroke
			(width 0.05715)
			(type default)
		)
		(layer "In6.Cu")
	)
	(gr_line
		(start 370.914168 -286.31896)
		(end 370.996972 -286.236156)
		(stroke
			(width 0.05715)
			(type default)
		)
		(layer "In6.Cu")
	)
	(gr_line
		(start 370.914168 -281.458924)
		(end 370.996972 -281.37612)
		(stroke
			(width 0.05715)
			(type default)
		)
		(layer "In6.Cu")
	)
	(gr_line
		(start 370.920772 -296.086276)
		(end 370.920772 -296.085768)
		(stroke
			(width 0.05715)
			(type default)
		)
		(layer "In6.Cu")
	)
	(gr_line
		(start 370.92763 -284.685486)
		(end 370.996972 -284.616144)
		(stroke
			(width 0.05715)
			(type default)
		)
		(layer "In6.Cu")
	)
	(gr_line
		(start 370.92763 -283.065474)
		(end 370.996972 -282.996132)
		(stroke
			(width 0.05715)
			(type default)
		)
		(layer "In6.Cu")
	)
	(gr_line
		(start 370.943632 -397.388588)
		(end 370.797074 -397.535146)
		(stroke
			(width 0.07112)
			(type default)
		)
		(layer "In6.Cu")
	)
	(gr_line
		(start 370.943632 -397.208756)
		(end 370.943632 -397.388588)
		(stroke
			(width 0.07112)
			(type default)
		)
		(layer "In6.Cu")
	)
	(gr_line
		(start 370.966492 -296.353484)
		(end 370.966492 -296.325036)
		(stroke
			(width 0.05715)
			(type default)
		)
		(layer "In6.Cu")
	)
	(gr_line
		(start 370.966492 -296.325036)
		(end 370.920772 -296.279316)
		(stroke
			(width 0.05715)
			(type default)
		)
		(layer "In6.Cu")
	)
	(gr_line
		(start 370.996972 -286.236156)
		(end 371.294914 -286.236156)
		(stroke
			(width 0.05715)
			(type default)
		)
		(layer "In6.Cu")
	)
	(gr_line
		(start 370.996972 -284.616144)
		(end 371.294914 -284.616144)
		(stroke
			(width 0.05715)
			(type default)
		)
		(layer "In6.Cu")
	)
	(gr_line
		(start 370.996972 -282.996132)
		(end 371.294914 -282.996132)
		(stroke
			(width 0.05715)
			(type default)
		)
		(layer "In6.Cu")
	)
	(gr_line
		(start 370.996972 -281.37612)
		(end 371.294914 -281.37612)
		(stroke
			(width 0.05715)
			(type default)
		)
		(layer "In6.Cu")
	)
	(gr_line
		(start 371.17655 -397.734536)
		(end 370.998242 -397.734536)
		(stroke
			(width 0.07112)
			(type default)
		)
		(layer "In6.Cu")
	)
	(gr_line
		(start 371.199156 -283.815536)
		(end 371.199156 -283.816044)
		(stroke
			(width 0.05715)
			(type default)
		)
		(layer "In6.Cu")
	)
	(gr_line
		(start 371.291358 -397.849344)
		(end 371.17655 -397.734536)
		(stroke
			(width 0.07112)
			(type default)
		)
		(layer "In6.Cu")
	)
	(gr_arc
		(start 371.386608 -283.771848)
		(mid 371.386355 -283.770451)
		(end 371.3861 -283.769054)
		(stroke
			(width 0.05715)
			(type default)
		)
		(layer "In6.Cu")
	)
	(gr_line
		(start 371.48262 -284.294072)
		(end 371.481858 -284.293564)
		(stroke
			(width 0.05715)
			(type default)
		)
		(layer "In6.Cu")
	)
	(gr_line
		(start 371.487954 -284.29712)
		(end 371.48643 -284.296104)
		(stroke
			(width 0.05715)
			(type default)
		)
		(layer "In6.Cu")
	)
	(gr_line
		(start 371.48897 -284.297628)
		(end 371.487954 -284.29712)
		(stroke
			(width 0.05715)
			(type default)
		)
		(layer "In6.Cu")
	)
	(gr_line
		(start 371.489478 -284.297882)
		(end 371.48897 -284.297628)
		(stroke
			(width 0.05715)
			(type default)
		)
		(layer "In6.Cu")
	)
	(gr_line
		(start 371.57787 -295.468548)
		(end 371.577362 -295.468294)
		(stroke
			(width 0.05715)
			(type default)
		)
		(layer "In6.Cu")
	)
	(gr_line
		(start 371.580664 -284.130242)
		(end 371.577616 -284.128464)
		(stroke
			(width 0.05715)
			(type default)
		)
		(layer "In6.Cu")
	)
	(gr_line
		(start 371.583204 -284.131766)
		(end 371.582188 -284.131258)
		(stroke
			(width 0.05715)
			(type default)
		)
		(layer "In6.Cu")
	)
	(gr_line
		(start 371.58422 -284.132528)
		(end 371.583204 -284.131766)
		(stroke
			(width 0.05715)
			(type default)
		)
		(layer "In6.Cu")
	)
	(gr_line
		(start 371.609366 -284.147006)
		(end 371.608858 -284.146752)
		(stroke
			(width 0.05715)
			(type default)
		)
		(layer "In6.Cu")
	)
	(gr_line
		(start 371.610128 -284.147514)
		(end 371.609366 -284.147006)
		(stroke
			(width 0.05715)
			(type default)
		)
		(layer "In6.Cu")
	)
	(gr_line
		(start 371.616986 -284.151578)
		(end 371.610128 -284.147514)
		(stroke
			(width 0.05715)
			(type default)
		)
		(layer "In6.Cu")
	)
	(gr_line
		(start 371.624352 -296.353484)
		(end 371.624352 -296.325036)
		(stroke
			(width 0.05715)
			(type default)
		)
		(layer "In6.Cu")
	)
	(gr_line
		(start 371.624352 -296.325036)
		(end 371.670072 -296.279316)
		(stroke
			(width 0.05715)
			(type default)
		)
		(layer "In6.Cu")
	)
	(gr_arc
		(start 371.62486 -284.157166)
		(mid 371.620935 -284.154355)
		(end 371.616986 -284.151578)
		(stroke
			(width 0.05715)
			(type default)
		)
		(layer "In6.Cu")
	)
	(gr_line
		(start 371.669564 -296.007282)
		(end 371.669564 -296.006774)
		(stroke
			(width 0.05715)
			(type default)
		)
		(layer "In6.Cu")
	)
	(gr_line
		(start 371.860064 -286.229552)
		(end 371.860064 -286.236156)
		(stroke
			(width 0.05715)
			(type default)
		)
		(layer "In6.Cu")
	)
	(gr_line
		(start 371.860572 -296.086276)
		(end 371.860572 -296.085768)
		(stroke
			(width 0.05715)
			(type default)
		)
		(layer "In6.Cu")
	)
	(gr_line
		(start 371.906292 -296.353484)
		(end 371.906292 -296.325036)
		(stroke
			(width 0.05715)
			(type default)
		)
		(layer "In6.Cu")
	)
	(gr_line
		(start 371.906292 -296.325036)
		(end 371.860572 -296.279316)
		(stroke
			(width 0.05715)
			(type default)
		)
		(layer "In6.Cu")
	)
	(gr_line
		(start 371.913658 -407.96972)
		(end 372.050056 -408.657806)
		(stroke
			(width 0.07112)
			(type default)
		)
		(layer "In6.Cu")
	)
	(gr_line
		(start 372.091204 -397.156432)
		(end 372.143528 -397.208756)
		(stroke
			(width 0.07112)
			(type default)
		)
		(layer "In6.Cu")
	)
	(gr_line
		(start 372.13286 -409.076144)
		(end 372.269258 -409.76423)
		(stroke
			(width 0.07112)
			(type default)
		)
		(layer "In6.Cu")
	)
	(gr_line
		(start 372.143528 -397.388588)
		(end 371.99697 -397.535146)
		(stroke
			(width 0.07112)
			(type default)
		)
		(layer "In6.Cu")
	)
	(gr_line
		(start 372.143528 -397.208756)
		(end 372.143528 -397.388588)
		(stroke
			(width 0.07112)
			(type default)
		)
		(layer "In6.Cu")
	)
	(gr_arc
		(start 372.185692 -398.914366)
		(mid 372.185692 -398.913858)
		(end 372.185692 -398.91335)
		(stroke
			(width 0.07112)
			(type default)
		)
		(layer "In6.Cu")
	)
	(gr_line
		(start 372.190518 -407.914856)
		(end 372.190264 -407.914856)
		(stroke
			(width 0.07112)
			(type default)
		)
		(layer "In6.Cu")
	)
	(gr_line
		(start 372.191788 -407.915872)
		(end 372.351554 -408.022806)
		(stroke
			(width 0.07112)
			(type default)
		)
		(layer "In6.Cu")
	)
	(gr_line
		(start 372.351554 -408.022806)
		(end 372.434612 -408.441652)
		(stroke
			(width 0.07112)
			(type default)
		)
		(layer "In6.Cu")
	)
	(gr_line
		(start 372.352062 -410.182568)
		(end 372.48846 -410.8704)
		(stroke
			(width 0.07112)
			(type default)
		)
		(layer "In6.Cu")
	)
	(gr_line
		(start 372.376446 -397.734536)
		(end 372.198138 -397.734536)
		(stroke
			(width 0.07112)
			(type default)
		)
		(layer "In6.Cu")
	)
	(gr_line
		(start 372.41099 -409.022296)
		(end 372.570756 -409.12923)
		(stroke
			(width 0.07112)
			(type default)
		)
		(layer "In6.Cu")
	)
	(gr_line
		(start 372.417086 -285.910528)
		(end 372.41607 -285.91002)
		(stroke
			(width 0.05715)
			(type default)
		)
		(layer "In6.Cu")
	)
	(gr_line
		(start 372.418864 -285.911798)
		(end 372.417086 -285.910528)
		(stroke
			(width 0.05715)
			(type default)
		)
		(layer "In6.Cu")
	)
	(gr_line
		(start 372.425722 -418.412168)
		(end 372.762272 -418.748718)
		(stroke
			(width 0.05715)
			(type default)
		)
		(layer "In6.Cu")
	)
	(gr_line
		(start 372.426738 -285.916116)
		(end 372.425976 -285.915862)
		(stroke
			(width 0.05715)
			(type default)
		)
		(layer "In6.Cu")
	)
	(gr_line
		(start 372.434612 -408.441652)
		(end 372.327678 -408.601672)
		(stroke
			(width 0.07112)
			(type default)
		)
		(layer "In6.Cu")
	)
	(gr_line
		(start 372.491254 -397.849344)
		(end 372.376446 -397.734536)
		(stroke
			(width 0.07112)
			(type default)
		)
		(layer "In6.Cu")
	)
	(gr_line
		(start 372.511574 -285.74492)
		(end 372.510558 -285.744412)
		(stroke
			(width 0.05715)
			(type default)
		)
		(layer "In6.Cu")
	)
	(gr_line
		(start 372.517162 -285.748222)
		(end 372.513606 -285.74619)
		(stroke
			(width 0.05715)
			(type default)
		)
		(layer "In6.Cu")
	)
	(gr_line
		(start 372.530624 -315.71692)
		(end 372.521734 -315.706252)
		(stroke
			(width 0.07112)
			(type default)
		)
		(layer "In6.Cu")
	)
	(gr_line
		(start 372.538244 -315.72835)
		(end 372.538244 -315.728096)
		(stroke
			(width 0.07112)
			(type default)
		)
		(layer "In6.Cu")
	)
	(gr_line
		(start 372.538244 -315.728096)
		(end 372.530624 -315.71692)
		(stroke
			(width 0.07112)
			(type default)
		)
		(layer "In6.Cu")
	)
	(gr_line
		(start 372.564406 -296.377106)
		(end 372.564406 -296.348658)
		(stroke
			(width 0.05715)
			(type default)
		)
		(layer "In6.Cu")
	)
	(gr_line
		(start 372.564406 -296.348658)
		(end 372.610126 -296.302938)
		(stroke
			(width 0.05715)
			(type default)
		)
		(layer "In6.Cu")
	)
	(gr_line
		(start 372.570756 -409.12923)
		(end 372.653814 -409.548076)
		(stroke
			(width 0.07112)
			(type default)
		)
		(layer "In6.Cu")
	)
	(gr_line
		(start 372.609618 -295.956482)
		(end 372.609618 -295.955974)
		(stroke
			(width 0.05715)
			(type default)
		)
		(layer "In6.Cu")
	)
	(gr_line
		(start 372.630192 -410.12872)
		(end 372.789958 -410.235654)
		(stroke
			(width 0.07112)
			(type default)
		)
		(layer "In6.Cu")
	)
	(gr_line
		(start 372.653814 -409.548076)
		(end 372.54688 -409.708096)
		(stroke
			(width 0.07112)
			(type default)
		)
		(layer "In6.Cu")
	)
	(gr_line
		(start 372.716552 -415.09569)
		(end 372.425722 -415.38652)
		(stroke
			(width 0.07112)
			(type default)
		)
		(layer "In6.Cu")
	)
	(gr_line
		(start 372.789958 -410.235654)
		(end 372.873016 -410.6545)
		(stroke
			(width 0.07112)
			(type default)
		)
		(layer "In6.Cu")
	)
	(gr_line
		(start 372.800626 -296.035476)
		(end 372.800626 -296.034968)
		(stroke
			(width 0.05715)
			(type default)
		)
		(layer "In6.Cu")
	)
	(gr_line
		(start 372.846346 -296.377106)
		(end 372.846346 -296.348658)
		(stroke
			(width 0.05715)
			(type default)
		)
		(layer "In6.Cu")
	)
	(gr_line
		(start 372.846346 -296.348658)
		(end 372.800626 -296.302938)
		(stroke
			(width 0.05715)
			(type default)
		)
		(layer "In6.Cu")
	)
	(gr_line
		(start 372.873016 -410.6545)
		(end 372.765828 -410.814266)
		(stroke
			(width 0.07112)
			(type default)
		)
		(layer "In6.Cu")
	)
	(gr_line
		(start 372.888256 -294.821356)
		(end 372.884446 -294.81907)
		(stroke
			(width 0.05715)
			(type default)
		)
		(layer "In6.Cu")
	)
	(gr_line
		(start 372.888256 -291.581332)
		(end 372.884446 -291.579046)
		(stroke
			(width 0.05715)
			(type default)
		)
		(layer "In6.Cu")
	)
	(gr_line
		(start 372.888256 -285.101538)
		(end 372.884446 -285.099252)
		(stroke
			(width 0.05715)
			(type default)
		)
		(layer "In6.Cu")
	)
	(gr_line
		(start 372.888256 -283.481526)
		(end 372.884446 -283.47924)
		(stroke
			(width 0.05715)
			(type default)
		)
		(layer "In6.Cu")
	)
	(gr_line
		(start 372.889272 -294.821864)
		(end 372.888256 -294.821356)
		(stroke
			(width 0.05715)
			(type default)
		)
		(layer "In6.Cu")
	)
	(gr_line
		(start 372.889272 -291.58184)
		(end 372.888256 -291.581332)
		(stroke
			(width 0.05715)
			(type default)
		)
		(layer "In6.Cu")
	)
	(gr_line
		(start 372.889272 -285.102046)
		(end 372.888256 -285.101538)
		(stroke
			(width 0.05715)
			(type default)
		)
		(layer "In6.Cu")
	)
	(gr_line
		(start 372.889272 -283.482034)
		(end 372.888256 -283.481526)
		(stroke
			(width 0.05715)
			(type default)
		)
		(layer "In6.Cu")
	)
	(gr_line
		(start 372.890796 -294.82288)
		(end 372.889272 -294.821864)
		(stroke
			(width 0.05715)
			(type default)
		)
		(layer "In6.Cu")
	)
	(gr_line
		(start 372.890796 -293.849044)
		(end 372.891812 -293.848536)
		(stroke
			(width 0.05715)
			(type default)
		)
		(layer "In6.Cu")
	)
	(gr_line
		(start 372.890796 -292.229032)
		(end 372.891812 -292.228524)
		(stroke
			(width 0.05715)
			(type default)
		)
		(layer "In6.Cu")
	)
	(gr_line
		(start 372.890796 -291.582856)
		(end 372.889272 -291.58184)
		(stroke
			(width 0.05715)
			(type default)
		)
		(layer "In6.Cu")
	)
	(gr_line
		(start 372.890796 -290.60902)
		(end 372.891812 -290.608512)
		(stroke
			(width 0.05715)
			(type default)
		)
		(layer "In6.Cu")
	)
	(gr_line
		(start 372.890796 -288.989008)
		(end 372.891812 -288.9885)
		(stroke
			(width 0.05715)
			(type default)
		)
		(layer "In6.Cu")
	)
	(gr_line
		(start 372.890796 -285.103062)
		(end 372.889272 -285.102046)
		(stroke
			(width 0.05715)
			(type default)
		)
		(layer "In6.Cu")
	)
	(gr_line
		(start 372.890796 -284.129226)
		(end 372.891812 -284.128718)
		(stroke
			(width 0.05715)
			(type default)
		)
		(layer "In6.Cu")
	)
	(gr_line
		(start 372.890796 -283.48305)
		(end 372.889272 -283.482034)
		(stroke
			(width 0.05715)
			(type default)
		)
		(layer "In6.Cu")
	)
	(gr_line
		(start 372.890796 -282.509214)
		(end 372.891812 -282.508706)
		(stroke
			(width 0.05715)
			(type default)
		)
		(layer "In6.Cu")
	)
	(gr_line
		(start 372.891304 -294.823134)
		(end 372.890796 -294.82288)
		(stroke
			(width 0.05715)
			(type default)
		)
		(layer "In6.Cu")
	)
	(gr_line
		(start 372.891304 -291.58311)
		(end 372.890796 -291.582856)
		(stroke
			(width 0.05715)
			(type default)
		)
		(layer "In6.Cu")
	)
	(gr_line
		(start 372.891304 -285.103316)
		(end 372.890796 -285.103062)
		(stroke
			(width 0.05715)
			(type default)
		)
		(layer "In6.Cu")
	)
	(gr_line
		(start 372.891304 -283.483304)
		(end 372.890796 -283.48305)
		(stroke
			(width 0.05715)
			(type default)
		)
		(layer "In6.Cu")
	)
	(gr_line
		(start 372.891812 -293.848536)
		(end 372.892574 -293.848028)
		(stroke
			(width 0.05715)
			(type default)
		)
		(layer "In6.Cu")
	)
	(gr_line
		(start 372.891812 -292.228524)
		(end 372.892574 -292.228016)
		(stroke
			(width 0.05715)
			(type default)
		)
		(layer "In6.Cu")
	)
	(gr_line
		(start 372.891812 -290.608512)
		(end 372.892574 -290.608004)
		(stroke
			(width 0.05715)
			(type default)
		)
		(layer "In6.Cu")
	)
	(gr_line
		(start 372.891812 -288.9885)
		(end 372.892574 -288.987992)
		(stroke
			(width 0.05715)
			(type default)
		)
		(layer "In6.Cu")
	)
	(gr_line
		(start 372.891812 -284.128718)
		(end 372.892574 -284.12821)
		(stroke
			(width 0.05715)
			(type default)
		)
		(layer "In6.Cu")
	)
	(gr_line
		(start 372.891812 -282.508706)
		(end 372.892574 -282.508198)
		(stroke
			(width 0.05715)
			(type default)
		)
		(layer "In6.Cu")
	)
	(gr_line
		(start 372.892574 -293.848028)
		(end 372.893844 -293.847266)
		(stroke
			(width 0.05715)
			(type default)
		)
		(layer "In6.Cu")
	)
	(gr_line
		(start 372.892574 -292.228016)
		(end 372.893844 -292.227254)
		(stroke
			(width 0.05715)
			(type default)
		)
		(layer "In6.Cu")
	)
	(gr_line
		(start 372.892574 -290.608004)
		(end 372.893844 -290.607242)
		(stroke
			(width 0.05715)
			(type default)
		)
		(layer "In6.Cu")
	)
	(gr_line
		(start 372.892574 -288.987992)
		(end 372.893844 -288.98723)
		(stroke
			(width 0.05715)
			(type default)
		)
		(layer "In6.Cu")
	)
	(gr_line
		(start 372.892574 -284.12821)
		(end 372.893844 -284.127448)
		(stroke
			(width 0.05715)
			(type default)
		)
		(layer "In6.Cu")
	)
	(gr_line
		(start 372.892574 -282.508198)
		(end 372.893844 -282.507436)
		(stroke
			(width 0.05715)
			(type default)
		)
		(layer "In6.Cu")
	)
	(gr_line
		(start 372.893844 -293.204646)
		(end 372.892574 -293.203884)
		(stroke
			(width 0.05715)
			(type default)
		)
		(layer "In6.Cu")
	)
	(gr_line
		(start 372.893844 -289.964622)
		(end 372.892574 -289.96386)
		(stroke
			(width 0.05715)
			(type default)
		)
		(layer "In6.Cu")
	)
	(gr_line
		(start 372.952772 -421.080692)
		(end 372.953026 -421.080438)
		(stroke
			(width 0.05715)
			(type default)
		)
		(layer "In6.Cu")
	)
	(gr_line
		(start 372.977918 -294.6527)
		(end 372.976902 -294.652192)
		(stroke
			(width 0.05715)
			(type default)
		)
		(layer "In6.Cu")
	)
	(gr_line
		(start 372.977918 -291.412676)
		(end 372.976902 -291.412168)
		(stroke
			(width 0.05715)
			(type default)
		)
		(layer "In6.Cu")
	)
	(gr_line
		(start 372.977918 -284.932882)
		(end 372.976902 -284.932374)
		(stroke
			(width 0.05715)
			(type default)
		)
		(layer "In6.Cu")
	)
	(gr_line
		(start 372.977918 -283.31287)
		(end 372.976902 -283.312362)
		(stroke
			(width 0.05715)
			(type default)
		)
		(layer "In6.Cu")
	)
	(gr_line
		(start 372.978934 -294.653462)
		(end 372.977918 -294.6527)
		(stroke
			(width 0.05715)
			(type default)
		)
		(layer "In6.Cu")
	)
	(gr_line
		(start 372.978934 -291.413438)
		(end 372.977918 -291.412676)
		(stroke
			(width 0.05715)
			(type default)
		)
		(layer "In6.Cu")
	)
	(gr_line
		(start 372.978934 -284.933644)
		(end 372.977918 -284.932882)
		(stroke
			(width 0.05715)
			(type default)
		)
		(layer "In6.Cu")
	)
	(gr_line
		(start 372.978934 -283.313632)
		(end 372.977918 -283.31287)
		(stroke
			(width 0.05715)
			(type default)
		)
		(layer "In6.Cu")
	)
	(gr_line
		(start 372.984268 -294.65651)
		(end 372.983506 -294.656002)
		(stroke
			(width 0.05715)
			(type default)
		)
		(layer "In6.Cu")
	)
	(gr_line
		(start 372.984268 -291.416486)
		(end 372.983506 -291.415978)
		(stroke
			(width 0.05715)
			(type default)
		)
		(layer "In6.Cu")
	)
	(gr_line
		(start 372.984268 -284.936692)
		(end 372.983506 -284.936184)
		(stroke
			(width 0.05715)
			(type default)
		)
		(layer "In6.Cu")
	)
	(gr_line
		(start 372.984268 -283.31668)
		(end 372.983506 -283.316172)
		(stroke
			(width 0.05715)
			(type default)
		)
		(layer "In6.Cu")
	)
	(gr_line
		(start 372.985792 -294.014652)
		(end 372.987062 -294.01389)
		(stroke
			(width 0.05715)
			(type default)
		)
		(layer "In6.Cu")
	)
	(gr_line
		(start 372.985792 -292.39464)
		(end 372.987062 -292.393878)
		(stroke
			(width 0.05715)
			(type default)
		)
		(layer "In6.Cu")
	)
	(gr_line
		(start 372.985792 -290.774628)
		(end 372.987062 -290.773866)
		(stroke
			(width 0.05715)
			(type default)
		)
		(layer "In6.Cu")
	)
	(gr_line
		(start 372.985792 -289.154616)
		(end 372.987062 -289.153854)
		(stroke
			(width 0.05715)
			(type default)
		)
		(layer "In6.Cu")
	)
	(gr_line
		(start 372.985792 -284.294834)
		(end 372.987062 -284.294072)
		(stroke
			(width 0.05715)
			(type default)
		)
		(layer "In6.Cu")
	)
	(gr_line
		(start 372.985792 -282.674822)
		(end 372.987062 -282.67406)
		(stroke
			(width 0.05715)
			(type default)
		)
		(layer "In6.Cu")
	)
	(gr_line
		(start 372.987062 -294.658034)
		(end 372.984268 -294.65651)
		(stroke
			(width 0.05715)
			(type default)
		)
		(layer "In6.Cu")
	)
	(gr_line
		(start 372.987062 -294.01389)
		(end 372.987824 -294.013382)
		(stroke
			(width 0.05715)
			(type default)
		)
		(layer "In6.Cu")
	)
	(gr_line
		(start 372.987062 -292.393878)
		(end 372.987824 -292.39337)
		(stroke
			(width 0.05715)
			(type default)
		)
		(layer "In6.Cu")
	)
	(gr_line
		(start 372.987062 -291.41801)
		(end 372.984268 -291.416486)
		(stroke
			(width 0.05715)
			(type default)
		)
		(layer "In6.Cu")
	)
	(gr_line
		(start 372.987062 -290.773866)
		(end 372.987824 -290.773358)
		(stroke
			(width 0.05715)
			(type default)
		)
		(layer "In6.Cu")
	)
	(gr_line
		(start 372.987062 -289.153854)
		(end 372.987824 -289.153346)
		(stroke
			(width 0.05715)
			(type default)
		)
		(layer "In6.Cu")
	)
	(gr_line
		(start 372.987062 -284.938216)
		(end 372.984268 -284.936692)
		(stroke
			(width 0.05715)
			(type default)
		)
		(layer "In6.Cu")
	)
	(gr_line
		(start 372.987062 -284.294072)
		(end 372.987824 -284.293564)
		(stroke
			(width 0.05715)
			(type default)
		)
		(layer "In6.Cu")
	)
	(gr_line
		(start 372.987062 -283.318204)
		(end 372.984268 -283.31668)
		(stroke
			(width 0.05715)
			(type default)
		)
		(layer "In6.Cu")
	)
	(gr_line
		(start 372.987062 -282.67406)
		(end 372.987824 -282.673552)
		(stroke
			(width 0.05715)
			(type default)
		)
		(layer "In6.Cu")
	)
	(gr_line
		(start 372.987824 -294.658542)
		(end 372.987062 -294.658034)
		(stroke
			(width 0.05715)
			(type default)
		)
		(layer "In6.Cu")
	)
	(gr_line
		(start 372.987824 -294.013382)
		(end 372.98884 -294.012874)
		(stroke
			(width 0.05715)
			(type default)
		)
		(layer "In6.Cu")
	)
	(gr_line
		(start 372.987824 -293.03853)
		(end 372.987316 -293.038276)
		(stroke
			(width 0.05715)
			(type default)
		)
		(layer "In6.Cu")
	)
	(gr_line
		(start 372.987824 -292.39337)
		(end 372.98884 -292.392862)
		(stroke
			(width 0.05715)
			(type default)
		)
		(layer "In6.Cu")
	)
	(gr_line
		(start 372.987824 -291.418518)
		(end 372.987062 -291.41801)
		(stroke
			(width 0.05715)
			(type default)
		)
		(layer "In6.Cu")
	)
	(gr_line
		(start 372.987824 -290.773358)
		(end 372.98884 -290.77285)
		(stroke
			(width 0.05715)
			(type default)
		)
		(layer "In6.Cu")
	)
	(gr_line
		(start 372.987824 -289.798506)
		(end 372.987316 -289.798252)
		(stroke
			(width 0.05715)
			(type default)
		)
		(layer "In6.Cu")
	)
	(gr_line
		(start 372.987824 -289.153346)
		(end 372.98884 -289.152838)
		(stroke
			(width 0.05715)
			(type default)
		)
		(layer "In6.Cu")
	)
	(gr_line
		(start 372.987824 -284.938724)
		(end 372.987062 -284.938216)
		(stroke
			(width 0.05715)
			(type default)
		)
		(layer "In6.Cu")
	)
	(gr_line
		(start 372.987824 -284.293564)
		(end 372.98884 -284.293056)
		(stroke
			(width 0.05715)
			(type default)
		)
		(layer "In6.Cu")
	)
	(gr_line
		(start 372.987824 -283.318712)
		(end 372.987062 -283.318204)
		(stroke
			(width 0.05715)
			(type default)
		)
		(layer "In6.Cu")
	)
	(gr_line
		(start 372.987824 -282.673552)
		(end 372.98884 -282.673044)
		(stroke
			(width 0.05715)
			(type default)
		)
		(layer "In6.Cu")
	)
	(gr_line
		(start 372.98884 -293.039038)
		(end 372.987824 -293.03853)
		(stroke
			(width 0.05715)
			(type default)
		)
		(layer "In6.Cu")
	)
	(gr_line
		(start 372.98884 -289.799014)
		(end 372.987824 -289.798506)
		(stroke
			(width 0.05715)
			(type default)
		)
		(layer "In6.Cu")
	)
	(gr_line
		(start 372.998492 -415.09569)
		(end 373.289322 -415.38652)
		(stroke
			(width 0.07112)
			(type default)
		)
		(layer "In6.Cu")
	)
	(gr_line
		(start 373.289322 -418.412168)
		(end 372.952772 -418.748718)
		(stroke
			(width 0.05715)
			(type default)
		)
		(layer "In6.Cu")
	)
	(gr_line
		(start 373.291354 -397.156432)
		(end 373.343678 -397.208756)
		(stroke
			(width 0.07112)
			(type default)
		)
		(layer "In6.Cu")
	)
	(gr_line
		(start 373.316246 -406.83053)
		(end 373.3165 -406.830784)
		(stroke
			(width 0.07112)
			(type default)
		)
		(layer "In6.Cu")
	)
	(gr_line
		(start 373.3165 -406.830784)
		(end 373.61622 -407.464768)
		(stroke
			(width 0.07112)
			(type default)
		)
		(layer "In6.Cu")
	)
	(gr_line
		(start 373.343678 -397.412972)
		(end 373.221504 -397.535146)
		(stroke
			(width 0.07112)
			(type default)
		)
		(layer "In6.Cu")
	)
	(gr_line
		(start 373.343678 -397.208756)
		(end 373.343678 -397.412972)
		(stroke
			(width 0.07112)
			(type default)
		)
		(layer "In6.Cu")
	)
	(gr_line
		(start 373.361966 -295.633394)
		(end 373.361712 -295.633394)
		(stroke
			(width 0.05715)
			(type default)
		)
		(layer "In6.Cu")
	)
	(gr_line
		(start 373.47271 -284.616144)
		(end 373.174768 -284.616144)
		(stroke
			(width 0.05715)
			(type default)
		)
		(layer "In6.Cu")
	)
	(gr_line
		(start 373.47271 -282.996132)
		(end 373.174768 -282.996132)
		(stroke
			(width 0.05715)
			(type default)
		)
		(layer "In6.Cu")
	)
	(gr_line
		(start 373.47271 -281.37612)
		(end 373.174768 -281.37612)
		(stroke
			(width 0.05715)
			(type default)
		)
		(layer "In6.Cu")
	)
	(gr_line
		(start 373.503952 -296.372534)
		(end 373.503952 -296.344086)
		(stroke
			(width 0.05715)
			(type default)
		)
		(layer "In6.Cu")
	)
	(gr_line
		(start 373.503952 -296.344086)
		(end 373.549672 -296.298366)
		(stroke
			(width 0.05715)
			(type default)
		)
		(layer "In6.Cu")
	)
	(gr_line
		(start 373.542052 -281.445462)
		(end 373.47271 -281.37612)
		(stroke
			(width 0.05715)
			(type default)
		)
		(layer "In6.Cu")
	)
	(gr_line
		(start 373.555514 -284.698948)
		(end 373.47271 -284.616144)
		(stroke
			(width 0.05715)
			(type default)
		)
		(layer "In6.Cu")
	)
	(gr_arc
		(start 373.555514 -284.698948)
		(mid 373.557306 -284.71027)
		(end 373.559324 -284.721554)
		(stroke
			(width 0.05715)
			(type default)
		)
		(layer "In6.Cu")
	)
	(gr_line
		(start 373.555514 -283.078936)
		(end 373.47271 -282.996132)
		(stroke
			(width 0.05715)
			(type default)
		)
		(layer "In6.Cu")
	)
	(gr_arc
		(start 373.555514 -283.078936)
		(mid 373.557305 -283.090258)
		(end 373.559324 -283.101542)
		(stroke
			(width 0.05715)
			(type default)
		)
		(layer "In6.Cu")
	)
	(gr_line
		(start 373.57304 -406.710642)
		(end 373.754142 -406.775412)
		(stroke
			(width 0.07112)
			(type default)
		)
		(layer "In6.Cu")
	)
	(gr_line
		(start 373.576342 -397.734536)
		(end 373.422672 -397.734536)
		(stroke
			(width 0.07112)
			(type default)
		)
		(layer "In6.Cu")
	)
	(gr_line
		(start 373.69115 -397.849344)
		(end 373.576342 -397.734536)
		(stroke
			(width 0.07112)
			(type default)
		)
		(layer "In6.Cu")
	)
	(gr_arc
		(start 373.730266 -281.481784)
		(mid 373.732289 -281.470374)
		(end 373.734076 -281.458924)
		(stroke
			(width 0.05715)
			(type default)
		)
		(layer "In6.Cu")
	)
	(gr_line
		(start 373.734076 -281.458924)
		(end 373.81688 -281.37612)
		(stroke
			(width 0.05715)
			(type default)
		)
		(layer "In6.Cu")
	)
	(gr_line
		(start 373.747538 -284.685486)
		(end 373.81688 -284.616144)
		(stroke
			(width 0.05715)
			(type default)
		)
		(layer "In6.Cu")
	)
	(gr_line
		(start 373.747538 -283.065474)
		(end 373.81688 -282.996132)
		(stroke
			(width 0.05715)
			(type default)
		)
		(layer "In6.Cu")
	)
	(gr_line
		(start 373.754142 -406.775412)
		(end 373.936514 -407.161238)
		(stroke
			(width 0.07112)
			(type default)
		)
		(layer "In6.Cu")
	)
	(gr_line
		(start 373.771922 -403.837648)
		(end 373.771922 -404.538688)
		(stroke
			(width 0.07112)
			(type default)
		)
		(layer "In6.Cu")
	)
	(gr_line
		(start 373.771922 -402.709888)
		(end 373.771922 -403.410928)
		(stroke
			(width 0.07112)
			(type default)
		)
		(layer "In6.Cu")
	)
	(gr_arc
		(start 373.784876 -294.79494)
		(mid 373.788801 -294.797751)
		(end 373.79275 -294.800528)
		(stroke
			(width 0.05715)
			(type default)
		)
		(layer "In6.Cu")
	)
	(gr_arc
		(start 373.784876 -293.174928)
		(mid 373.788801 -293.177739)
		(end 373.79275 -293.180516)
		(stroke
			(width 0.05715)
			(type default)
		)
		(layer "In6.Cu")
	)
	(gr_line
		(start 373.785892 -296.372534)
		(end 373.785892 -296.344086)
		(stroke
			(width 0.05715)
			(type default)
		)
		(layer "In6.Cu")
	)
	(gr_line
		(start 373.785892 -296.344086)
		(end 373.740172 -296.298366)
		(stroke
			(width 0.05715)
			(type default)
		)
		(layer "In6.Cu")
	)
	(gr_arc
		(start 373.793512 -294.801036)
		(mid 373.793131 -294.800782)
		(end 373.79275 -294.800528)
		(stroke
			(width 0.05715)
			(type default)
		)
		(layer "In6.Cu")
	)
	(gr_arc
		(start 373.793512 -293.181024)
		(mid 373.793131 -293.18077)
		(end 373.79275 -293.180516)
		(stroke
			(width 0.05715)
			(type default)
		)
		(layer "In6.Cu")
	)
	(gr_line
		(start 373.798592 -407.85034)
		(end 374.098566 -408.484324)
		(stroke
			(width 0.07112)
			(type default)
		)
		(layer "In6.Cu")
	)
	(gr_line
		(start 373.800878 -293.185342)
		(end 373.793512 -293.181024)
		(stroke
			(width 0.05715)
			(type default)
		)
		(layer "In6.Cu")
	)
	(gr_line
		(start 373.801132 -294.805354)
		(end 373.793512 -294.801036)
		(stroke
			(width 0.05715)
			(type default)
		)
		(layer "In6.Cu")
	)
	(gr_line
		(start 373.815102 -290.618418)
		(end 373.816626 -290.617402)
		(stroke
			(width 0.05715)
			(type default)
		)
		(layer "In6.Cu")
	)
	(gr_line
		(start 373.81688 -284.616144)
		(end 374.114822 -284.616144)
		(stroke
			(width 0.05715)
			(type default)
		)
		(layer "In6.Cu")
	)
	(gr_line
		(start 373.81688 -282.996132)
		(end 374.114822 -282.996132)
		(stroke
			(width 0.05715)
			(type default)
		)
		(layer "In6.Cu")
	)
	(gr_line
		(start 373.81688 -281.37612)
		(end 374.114822 -281.37612)
		(stroke
			(width 0.05715)
			(type default)
		)
		(layer "In6.Cu")
	)
	(gr_line
		(start 373.826024 -293.852092)
		(end 373.832628 -293.848282)
		(stroke
			(width 0.05715)
			(type default)
		)
		(layer "In6.Cu")
	)
	(gr_line
		(start 373.829834 -291.587428)
		(end 373.82958 -291.587174)
		(stroke
			(width 0.05715)
			(type default)
		)
		(layer "In6.Cu")
	)
	(gr_line
		(start 373.83085 -293.202868)
		(end 373.829072 -293.201598)
		(stroke
			(width 0.05715)
			(type default)
		)
		(layer "In6.Cu")
	)
	(gr_line
		(start 373.832374 -293.203884)
		(end 373.83085 -293.202868)
		(stroke
			(width 0.05715)
			(type default)
		)
		(layer "In6.Cu")
	)
	(gr_line
		(start 373.848376 -288.352992)
		(end 373.848376 -288.353246)
		(stroke
			(width 0.05715)
			(type default)
		)
		(layer "In6.Cu")
	)
	(gr_line
		(start 373.925338 -293.037006)
		(end 373.924322 -293.036498)
		(stroke
			(width 0.05715)
			(type default)
		)
		(layer "In6.Cu")
	)
	(gr_line
		(start 373.927116 -291.423344)
		(end 373.925846 -291.422582)
		(stroke
			(width 0.05715)
			(type default)
		)
		(layer "In6.Cu")
	)
	(gr_arc
		(start 373.930418 -289.154108)
		(mid 373.93258 -289.152843)
		(end 373.934736 -289.151568)
		(stroke
			(width 0.05715)
			(type default)
		)
		(layer "In6.Cu")
	)
	(gr_line
		(start 373.931434 -294.660574)
		(end 373.931942 -294.660828)
		(stroke
			(width 0.05715)
			(type default)
		)
		(layer "In6.Cu")
	)
	(gr_line
		(start 373.936514 -407.161238)
		(end 373.871744 -407.342594)
		(stroke
			(width 0.07112)
			(type default)
		)
		(layer "In6.Cu")
	)
	(gr_arc
		(start 373.939308 -294.006778)
		(mid 373.941979 -294.005261)
		(end 373.944642 -294.00373)
		(stroke
			(width 0.05715)
			(type default)
		)
		(layer "In6.Cu")
	)
	(gr_arc
		(start 373.939308 -290.766754)
		(mid 373.941979 -290.765237)
		(end 373.944642 -290.763706)
		(stroke
			(width 0.05715)
			(type default)
		)
		(layer "In6.Cu")
	)
	(gr_arc
		(start 373.944642 -293.048182)
		(mid 373.941347 -293.046139)
		(end 373.938038 -293.044118)
		(stroke
			(width 0.05715)
			(type default)
		)
		(layer "In6.Cu")
	)
	(gr_arc
		(start 373.944642 -289.808158)
		(mid 373.9416 -289.80637)
		(end 373.938546 -289.804602)
		(stroke
			(width 0.05715)
			(type default)
		)
		(layer "In6.Cu")
	)
	(gr_line
		(start 373.961406 -288.198052)
		(end 373.958358 -288.196274)
		(stroke
			(width 0.05715)
			(type default)
		)
		(layer "In6.Cu")
	)
	(gr_line
		(start 373.9642 -288.199576)
		(end 373.961406 -288.198052)
		(stroke
			(width 0.05715)
			(type default)
		)
		(layer "In6.Cu")
	)
	(gr_arc
		(start 373.97309 -288.205926)
		(mid 373.968661 -288.202729)
		(end 373.9642 -288.199576)
		(stroke
			(width 0.05715)
			(type default)
		)
		(layer "In6.Cu")
	)
	(gr_line
		(start 374.019064 -283.815536)
		(end 374.019064 -283.816044)
		(stroke
			(width 0.05715)
			(type default)
		)
		(layer "In6.Cu")
	)
	(gr_line
		(start 374.055132 -407.730198)
		(end 374.236488 -407.794968)
		(stroke
			(width 0.07112)
			(type default)
		)
		(layer "In6.Cu")
	)
	(gr_line
		(start 374.055132 -403.838918)
		(end 374.191022 -403.974808)
		(stroke
			(width 0.07112)
			(type default)
		)
		(layer "In6.Cu")
	)
	(gr_line
		(start 374.055132 -402.711158)
		(end 374.191022 -402.847048)
		(stroke
			(width 0.07112)
			(type default)
		)
		(layer "In6.Cu")
	)
	(gr_line
		(start 374.191022 -404.401528)
		(end 374.055132 -404.537418)
		(stroke
			(width 0.07112)
			(type default)
		)
		(layer "In6.Cu")
	)
	(gr_line
		(start 374.191022 -403.974808)
		(end 374.191022 -404.401528)
		(stroke
			(width 0.07112)
			(type default)
		)
		(layer "In6.Cu")
	)
	(gr_line
		(start 374.191022 -403.273768)
		(end 374.055132 -403.409658)
		(stroke
			(width 0.07112)
			(type default)
		)
		(layer "In6.Cu")
	)
	(gr_line
		(start 374.191022 -402.847048)
		(end 374.191022 -403.273768)
		(stroke
			(width 0.07112)
			(type default)
		)
		(layer "In6.Cu")
	)
	(gr_line
		(start 374.205754 -285.389066)
		(end 374.206008 -285.390336)
		(stroke
			(width 0.05715)
			(type default)
		)
		(layer "In6.Cu")
	)
	(gr_arc
		(start 374.206262 -285.392114)
		(mid 374.206136 -285.391225)
		(end 374.206008 -285.390336)
		(stroke
			(width 0.05715)
			(type default)
		)
		(layer "In6.Cu")
	)
	(gr_line
		(start 374.206516 -287.081214)
		(end 374.206262 -287.082484)
		(stroke
			(width 0.05715)
			(type default)
		)
		(layer "In6.Cu")
	)
	(gr_arc
		(start 374.206516 -283.771848)
		(mid 374.206263 -283.770451)
		(end 374.206008 -283.769054)
		(stroke
			(width 0.05715)
			(type default)
		)
		(layer "In6.Cu")
	)
	(gr_line
		(start 374.210072 -287.03651)
		(end 374.210072 -287.038288)
		(stroke
			(width 0.05715)
			(type default)
		)
		(layer "In6.Cu")
	)
	(gr_line
		(start 374.236488 -407.794968)
		(end 374.41886 -408.181048)
		(stroke
			(width 0.07112)
			(type default)
		)
		(layer "In6.Cu")
	)
	(gr_arc
		(start 374.265444 -286.579564)
		(mid 374.258806 -286.584216)
		(end 374.252236 -286.588962)
		(stroke
			(width 0.05715)
			(type default)
		)
		(layer "In6.Cu")
	)
	(gr_line
		(start 374.265444 -286.579564)
		(end 374.268238 -286.57804)
		(stroke
			(width 0.05715)
			(type default)
		)
		(layer "In6.Cu")
	)
	(gr_line
		(start 374.302528 -285.914084)
		(end 374.301766 -285.913576)
		(stroke
			(width 0.05715)
			(type default)
		)
		(layer "In6.Cu")
	)
	(gr_line
		(start 374.303798 -285.914846)
		(end 374.302528 -285.914084)
		(stroke
			(width 0.05715)
			(type default)
		)
		(layer "In6.Cu")
	)
	(gr_line
		(start 374.308878 -284.297628)
		(end 374.306338 -284.296104)
		(stroke
			(width 0.05715)
			(type default)
		)
		(layer "In6.Cu")
	)
	(gr_line
		(start 374.309386 -284.297882)
		(end 374.308878 -284.297628)
		(stroke
			(width 0.05715)
			(type default)
		)
		(layer "In6.Cu")
	)
	(gr_line
		(start 374.341898 -408.998928)
		(end 374.641872 -409.633166)
		(stroke
			(width 0.07112)
			(type default)
		)
		(layer "In6.Cu")
	)
	(gr_line
		(start 374.398794 -285.749238)
		(end 374.397778 -285.74873)
		(stroke
			(width 0.05715)
			(type default)
		)
		(layer "In6.Cu")
	)
	(gr_line
		(start 374.400826 -284.130496)
		(end 374.397524 -284.128464)
		(stroke
			(width 0.05715)
			(type default)
		)
		(layer "In6.Cu")
	)
	(gr_line
		(start 374.401842 -295.470834)
		(end 374.399302 -295.46931)
		(stroke
			(width 0.05715)
			(type default)
		)
		(layer "In6.Cu")
	)
	(gr_line
		(start 374.404128 -284.132528)
		(end 374.402096 -284.131258)
		(stroke
			(width 0.05715)
			(type default)
		)
		(layer "In6.Cu")
	)
	(gr_line
		(start 374.41886 -408.181048)
		(end 374.35409 -408.36215)
		(stroke
			(width 0.07112)
			(type default)
		)
		(layer "In6.Cu")
	)
	(gr_line
		(start 374.429274 -284.147006)
		(end 374.428766 -284.146752)
		(stroke
			(width 0.05715)
			(type default)
		)
		(layer "In6.Cu")
	)
	(gr_line
		(start 374.430036 -284.147514)
		(end 374.429274 -284.147006)
		(stroke
			(width 0.05715)
			(type default)
		)
		(layer "In6.Cu")
	)
	(gr_line
		(start 374.436894 -284.151578)
		(end 374.430036 -284.147514)
		(stroke
			(width 0.05715)
			(type default)
		)
		(layer "In6.Cu")
	)
	(gr_arc
		(start 374.444768 -284.157166)
		(mid 374.440843 -284.154355)
		(end 374.436894 -284.151578)
		(stroke
			(width 0.05715)
			(type default)
		)
		(layer "In6.Cu")
	)
	(gr_line
		(start 374.471946 -423.374566)
		(end 374.904762 -423.60596)
		(stroke
			(width 0.05715)
			(type default)
		)
		(layer "In6.Cu")
	)
	(gr_line
		(start 374.49125 -397.156432)
		(end 374.543574 -397.208756)
		(stroke
			(width 0.07112)
			(type default)
		)
		(layer "In6.Cu")
	)
	(gr_line
		(start 374.534176 -296.556176)
		(end 374.534176 -296.528236)
		(stroke
			(width 0.05715)
			(type default)
		)
		(layer "In6.Cu")
	)
	(gr_line
		(start 374.534176 -296.528236)
		(end 374.579896 -296.482516)
		(stroke
			(width 0.05715)
			(type default)
		)
		(layer "In6.Cu")
	)
	(gr_line
		(start 374.534684 -296.556684)
		(end 374.534176 -296.556176)
		(stroke
			(width 0.05715)
			(type default)
		)
		(layer "In6.Cu")
	)
	(gr_line
		(start 374.543574 -397.388588)
		(end 374.397016 -397.535146)
		(stroke
			(width 0.07112)
			(type default)
		)
		(layer "In6.Cu")
	)
	(gr_line
		(start 374.543574 -397.208756)
		(end 374.543574 -397.388588)
		(stroke
			(width 0.07112)
			(type default)
		)
		(layer "In6.Cu")
	)
	(gr_line
		(start 374.561862 -423.206418)
		(end 374.562116 -423.206418)
		(stroke
			(width 0.05715)
			(type default)
		)
		(layer "In6.Cu")
	)
	(gr_line
		(start 374.563386 -423.206164)
		(end 374.661938 -423.176192)
		(stroke
			(width 0.05715)
			(type default)
		)
		(layer "In6.Cu")
	)
	(gr_line
		(start 374.598438 -408.87904)
		(end 374.779794 -408.94381)
		(stroke
			(width 0.07112)
			(type default)
		)
		(layer "In6.Cu")
	)
	(gr_line
		(start 374.661938 -423.176192)
		(end 374.964452 -423.33799)
		(stroke
			(width 0.05715)
			(type default)
		)
		(layer "In6.Cu")
	)
	(gr_line
		(start 374.776492 -397.734536)
		(end 374.598184 -397.734536)
		(stroke
			(width 0.07112)
			(type default)
		)
		(layer "In6.Cu")
	)
	(gr_line
		(start 374.779794 -408.94381)
		(end 374.96242 -409.32989)
		(stroke
			(width 0.07112)
			(type default)
		)
		(layer "In6.Cu")
	)
	(gr_line
		(start 374.816116 -296.556176)
		(end 374.816116 -296.528236)
		(stroke
			(width 0.05715)
			(type default)
		)
		(layer "In6.Cu")
	)
	(gr_line
		(start 374.816116 -296.528236)
		(end 374.770396 -296.482516)
		(stroke
			(width 0.05715)
			(type default)
		)
		(layer "In6.Cu")
	)
	(gr_line
		(start 374.816624 -296.556684)
		(end 374.816116 -296.556176)
		(stroke
			(width 0.05715)
			(type default)
		)
		(layer "In6.Cu")
	)
	(gr_line
		(start 374.8913 -397.849344)
		(end 374.776492 -397.734536)
		(stroke
			(width 0.07112)
			(type default)
		)
		(layer "In6.Cu")
	)
	(gr_line
		(start 374.96242 -409.32989)
		(end 374.897396 -409.510992)
		(stroke
			(width 0.07112)
			(type default)
		)
		(layer "In6.Cu")
	)
	(gr_line
		(start 374.964452 -423.33799)
		(end 374.99417 -423.436288)
		(stroke
			(width 0.05715)
			(type default)
		)
		(layer "In6.Cu")
	)
	(gr_line
		(start 374.971818 -403.811232)
		(end 374.971818 -404.512272)
		(stroke
			(width 0.07112)
			(type default)
		)
		(layer "In6.Cu")
	)
	(gr_line
		(start 374.971818 -402.683472)
		(end 374.971818 -403.384512)
		(stroke
			(width 0.07112)
			(type default)
		)
		(layer "In6.Cu")
	)
	(gr_arc
		(start 375.18975 -285.881572)
		(mid 375.192158 -285.883356)
		(end 375.194576 -285.885128)
		(stroke
			(width 0.05715)
			(type default)
		)
		(layer "In6.Cu")
	)
	(gr_line
		(start 375.19483 -285.885128)
		(end 375.194576 -285.885128)
		(stroke
			(width 0.05715)
			(type default)
		)
		(layer "In6.Cu")
	)
	(gr_line
		(start 375.199656 -285.888176)
		(end 375.19483 -285.885128)
		(stroke
			(width 0.05715)
			(type default)
		)
		(layer "In6.Cu")
	)
	(gr_line
		(start 375.207022 -423.767504)
		(end 375.639584 -423.998644)
		(stroke
			(width 0.05715)
			(type default)
		)
		(layer "In6.Cu")
	)
	(gr_line
		(start 375.249694 -286.554418)
		(end 375.250456 -286.55391)
		(stroke
			(width 0.05715)
			(type default)
		)
		(layer "In6.Cu")
	)
	(gr_line
		(start 375.255028 -403.812502)
		(end 375.390918 -403.948392)
		(stroke
			(width 0.07112)
			(type default)
		)
		(layer "In6.Cu")
	)
	(gr_line
		(start 375.255028 -402.684742)
		(end 375.390918 -402.820632)
		(stroke
			(width 0.07112)
			(type default)
		)
		(layer "In6.Cu")
	)
	(gr_line
		(start 375.298462 -423.598848)
		(end 375.39676 -423.56913)
		(stroke
			(width 0.05715)
			(type default)
		)
		(layer "In6.Cu")
	)
	(gr_line
		(start 375.327164 -295.462706)
		(end 375.324878 -295.461436)
		(stroke
			(width 0.05715)
			(type default)
		)
		(layer "In6.Cu")
	)
	(gr_line
		(start 375.329196 -295.463722)
		(end 375.327164 -295.462706)
		(stroke
			(width 0.05715)
			(type default)
		)
		(layer "In6.Cu")
	)
	(gr_line
		(start 375.330466 -295.464484)
		(end 375.329196 -295.463722)
		(stroke
			(width 0.05715)
			(type default)
		)
		(layer "In6.Cu")
	)
	(gr_line
		(start 375.331228 -295.464992)
		(end 375.330466 -295.464484)
		(stroke
			(width 0.05715)
			(type default)
		)
		(layer "In6.Cu")
	)
	(gr_line
		(start 375.333768 -295.466262)
		(end 375.331228 -295.464992)
		(stroke
			(width 0.05715)
			(type default)
		)
		(layer "In6.Cu")
	)
	(gr_line
		(start 375.33453 -295.46677)
		(end 375.333768 -295.466262)
		(stroke
			(width 0.05715)
			(type default)
		)
		(layer "In6.Cu")
	)
	(gr_line
		(start 375.335546 -295.467278)
		(end 375.33453 -295.46677)
		(stroke
			(width 0.05715)
			(type default)
		)
		(layer "In6.Cu")
	)
	(gr_line
		(start 375.336308 -295.467786)
		(end 375.335546 -295.467278)
		(stroke
			(width 0.05715)
			(type default)
		)
		(layer "In6.Cu")
	)
	(gr_line
		(start 375.34469 -295.472612)
		(end 375.336308 -295.467786)
		(stroke
			(width 0.05715)
			(type default)
		)
		(layer "In6.Cu")
	)
	(gr_line
		(start 375.345198 -295.472866)
		(end 375.34469 -295.472612)
		(stroke
			(width 0.05715)
			(type default)
		)
		(layer "In6.Cu")
	)
	(gr_line
		(start 375.363232 -295.491408)
		(end 375.345198 -295.472866)
		(stroke
			(width 0.05715)
			(type default)
		)
		(layer "In6.Cu")
	)
	(gr_line
		(start 375.390918 -404.375112)
		(end 375.255028 -404.511002)
		(stroke
			(width 0.07112)
			(type default)
		)
		(layer "In6.Cu")
	)
	(gr_line
		(start 375.390918 -403.948392)
		(end 375.390918 -404.375112)
		(stroke
			(width 0.07112)
			(type default)
		)
		(layer "In6.Cu")
	)
	(gr_line
		(start 375.390918 -403.247352)
		(end 375.255028 -403.383242)
		(stroke
			(width 0.07112)
			(type default)
		)
		(layer "In6.Cu")
	)
	(gr_line
		(start 375.390918 -402.820632)
		(end 375.390918 -403.247352)
		(stroke
			(width 0.07112)
			(type default)
		)
		(layer "In6.Cu")
	)
	(gr_line
		(start 375.39676 -423.56913)
		(end 375.699274 -423.730928)
		(stroke
			(width 0.05715)
			(type default)
		)
		(layer "In6.Cu")
	)
	(gr_line
		(start 375.488962 -418.412168)
		(end 375.779792 -418.702998)
		(stroke
			(width 0.07112)
			(type default)
		)
		(layer "In6.Cu")
	)
	(gr_line
		(start 375.536968 -296.604182)
		(end 375.536968 -296.589704)
		(stroke
			(width 0.05715)
			(type default)
		)
		(layer "In6.Cu")
	)
	(gr_line
		(start 375.536968 -296.589704)
		(end 375.581926 -296.544746)
		(stroke
			(width 0.05715)
			(type default)
		)
		(layer "In6.Cu")
	)
	(gr_line
		(start 375.581926 -296.544746)
		(end 375.581926 -296.530014)
		(stroke
			(width 0.05715)
			(type default)
		)
		(layer "In6.Cu")
	)
	(gr_line
		(start 375.691146 -397.156432)
		(end 375.74347 -397.208756)
		(stroke
			(width 0.07112)
			(type default)
		)
		(layer "In6.Cu")
	)
	(gr_line
		(start 375.699274 -423.730928)
		(end 375.728992 -423.828972)
		(stroke
			(width 0.05715)
			(type default)
		)
		(layer "In6.Cu")
	)
	(gr_line
		(start 375.74347 -397.388588)
		(end 375.596912 -397.535146)
		(stroke
			(width 0.07112)
			(type default)
		)
		(layer "In6.Cu")
	)
	(gr_line
		(start 375.74347 -397.208756)
		(end 375.74347 -397.388588)
		(stroke
			(width 0.07112)
			(type default)
		)
		(layer "In6.Cu")
	)
	(gr_line
		(start 375.779792 -420.04361)
		(end 375.779792 -420.72433)
		(stroke
			(width 0.07112)
			(type default)
		)
		(layer "In6.Cu")
	)
	(gr_line
		(start 375.779792 -415.09569)
		(end 375.488962 -415.38652)
		(stroke
			(width 0.07112)
			(type default)
		)
		(layer "In6.Cu")
	)
	(gr_line
		(start 375.8184 -296.603674)
		(end 375.8184 -296.575734)
		(stroke
			(width 0.05715)
			(type default)
		)
		(layer "In6.Cu")
	)
	(gr_line
		(start 375.8184 -296.575734)
		(end 375.773696 -296.53103)
		(stroke
			(width 0.05715)
			(type default)
		)
		(layer "In6.Cu")
	)
	(gr_line
		(start 375.818908 -296.604182)
		(end 375.8184 -296.603674)
		(stroke
			(width 0.05715)
			(type default)
		)
		(layer "In6.Cu")
	)
	(gr_line
		(start 375.941844 -424.160188)
		(end 376.374406 -424.391328)
		(stroke
			(width 0.05715)
			(type default)
		)
		(layer "In6.Cu")
	)
	(gr_line
		(start 375.976388 -397.734536)
		(end 375.79808 -397.734536)
		(stroke
			(width 0.07112)
			(type default)
		)
		(layer "In6.Cu")
	)
	(gr_line
		(start 376.033284 -423.991532)
		(end 376.131582 -423.961814)
		(stroke
			(width 0.05715)
			(type default)
		)
		(layer "In6.Cu")
	)
	(gr_line
		(start 376.061732 -415.09569)
		(end 376.352562 -415.38652)
		(stroke
			(width 0.07112)
			(type default)
		)
		(layer "In6.Cu")
	)
	(gr_line
		(start 376.063002 -420.04488)
		(end 376.188732 -420.17061)
		(stroke
			(width 0.07112)
			(type default)
		)
		(layer "In6.Cu")
	)
	(gr_line
		(start 376.091196 -397.849344)
		(end 375.976388 -397.734536)
		(stroke
			(width 0.07112)
			(type default)
		)
		(layer "In6.Cu")
	)
	(gr_line
		(start 376.131582 -423.961814)
		(end 376.434096 -424.123612)
		(stroke
			(width 0.05715)
			(type default)
		)
		(layer "In6.Cu")
	)
	(gr_line
		(start 376.171714 -402.921978)
		(end 376.171714 -403.623018)
		(stroke
			(width 0.07112)
			(type default)
		)
		(layer "In6.Cu")
	)
	(gr_line
		(start 376.188732 -420.59733)
		(end 376.063002 -420.72306)
		(stroke
			(width 0.07112)
			(type default)
		)
		(layer "In6.Cu")
	)
	(gr_line
		(start 376.188732 -420.17061)
		(end 376.188732 -420.59733)
		(stroke
			(width 0.07112)
			(type default)
		)
		(layer "In6.Cu")
	)
	(gr_line
		(start 376.352562 -418.412168)
		(end 376.061732 -418.702998)
		(stroke
			(width 0.07112)
			(type default)
		)
		(layer "In6.Cu")
	)
	(gr_line
		(start 376.434096 -424.123612)
		(end 376.463814 -424.221656)
		(stroke
			(width 0.05715)
			(type default)
		)
		(layer "In6.Cu")
	)
	(gr_line
		(start 376.454924 -402.923248)
		(end 376.590814 -403.059138)
		(stroke
			(width 0.07112)
			(type default)
		)
		(layer "In6.Cu")
	)
	(gr_line
		(start 376.590814 -403.485858)
		(end 376.454924 -403.621748)
		(stroke
			(width 0.07112)
			(type default)
		)
		(layer "In6.Cu")
	)
	(gr_line
		(start 376.590814 -403.059138)
		(end 376.590814 -403.485858)
		(stroke
			(width 0.07112)
			(type default)
		)
		(layer "In6.Cu")
	)
	(gr_line
		(start 376.878088 -424.660568)
		(end 377.31065 -424.891708)
		(stroke
			(width 0.05715)
			(type default)
		)
		(layer "In6.Cu")
	)
	(gr_line
		(start 376.891296 -397.156432)
		(end 376.94362 -397.208756)
		(stroke
			(width 0.07112)
			(type default)
		)
		(layer "In6.Cu")
	)
	(gr_line
		(start 376.94362 -397.388588)
		(end 376.797062 -397.535146)
		(stroke
			(width 0.07112)
			(type default)
		)
		(layer "In6.Cu")
	)
	(gr_line
		(start 376.94362 -397.208756)
		(end 376.94362 -397.388588)
		(stroke
			(width 0.07112)
			(type default)
		)
		(layer "In6.Cu")
	)
	(gr_line
		(start 376.969528 -424.491912)
		(end 377.067572 -424.46194)
		(stroke
			(width 0.05715)
			(type default)
		)
		(layer "In6.Cu")
	)
	(gr_line
		(start 377.067572 -424.46194)
		(end 377.37034 -424.623992)
		(stroke
			(width 0.05715)
			(type default)
		)
		(layer "In6.Cu")
	)
	(gr_line
		(start 377.113038 -422.53408)
		(end 377.754388 -422.763442)
		(stroke
			(width 0.07112)
			(type default)
		)
		(layer "In6.Cu")
	)
	(gr_line
		(start 377.113292 -422.533826)
		(end 377.113038 -422.53408)
		(stroke
			(width 0.07112)
			(type default)
		)
		(layer "In6.Cu")
	)
	(gr_line
		(start 377.176538 -397.734536)
		(end 376.99823 -397.734536)
		(stroke
			(width 0.07112)
			(type default)
		)
		(layer "In6.Cu")
	)
	(gr_line
		(start 377.20905 -422.267634)
		(end 377.37034 -422.191434)
		(stroke
			(width 0.07112)
			(type default)
		)
		(layer "In6.Cu")
	)
	(gr_line
		(start 377.291346 -397.849344)
		(end 377.176538 -397.734536)
		(stroke
			(width 0.07112)
			(type default)
		)
		(layer "In6.Cu")
	)
	(gr_line
		(start 377.37034 -424.623992)
		(end 377.400058 -424.722036)
		(stroke
			(width 0.05715)
			(type default)
		)
		(layer "In6.Cu")
	)
	(gr_line
		(start 377.37034 -422.191434)
		(end 377.772422 -422.335198)
		(stroke
			(width 0.07112)
			(type default)
		)
		(layer "In6.Cu")
	)
	(gr_line
		(start 377.371864 -403.187154)
		(end 377.371864 -403.888194)
		(stroke
			(width 0.07112)
			(type default)
		)
		(layer "In6.Cu")
	)
	(gr_line
		(start 377.404122 -409.921202)
		(end 377.849384 -410.463492)
		(stroke
			(width 0.07112)
			(type default)
		)
		(layer "In6.Cu")
	)
	(gr_line
		(start 377.622308 -409.742132)
		(end 377.622562 -409.742132)
		(stroke
			(width 0.07112)
			(type default)
		)
		(layer "In6.Cu")
	)
	(gr_line
		(start 377.623832 -409.742386)
		(end 377.815602 -409.761182)
		(stroke
			(width 0.07112)
			(type default)
		)
		(layer "In6.Cu")
	)
	(gr_line
		(start 377.655074 -403.188424)
		(end 377.790964 -403.324314)
		(stroke
			(width 0.07112)
			(type default)
		)
		(layer "In6.Cu")
	)
	(gr_line
		(start 377.772422 -422.335198)
		(end 377.848622 -422.496488)
		(stroke
			(width 0.07112)
			(type default)
		)
		(layer "In6.Cu")
	)
	(gr_line
		(start 377.790964 -403.751034)
		(end 377.655074 -403.886924)
		(stroke
			(width 0.07112)
			(type default)
		)
		(layer "In6.Cu")
	)
	(gr_line
		(start 377.790964 -403.324314)
		(end 377.790964 -403.751034)
		(stroke
			(width 0.07112)
			(type default)
		)
		(layer "In6.Cu")
	)
	(gr_line
		(start 377.815602 -409.761182)
		(end 378.086366 -410.091382)
		(stroke
			(width 0.07112)
			(type default)
		)
		(layer "In6.Cu")
	)
	(gr_line
		(start 377.849384 -410.463492)
		(end 377.849638 -410.463492)
		(stroke
			(width 0.07112)
			(type default)
		)
		(layer "In6.Cu")
	)
	(gr_line
		(start 377.896882 -406.898602)
		(end 378.39269 -407.39441)
		(stroke
			(width 0.07112)
			(type default)
		)
		(layer "In6.Cu")
	)
	(gr_line
		(start 377.990354 -425.254928)
		(end 378.422916 -425.486068)
		(stroke
			(width 0.05715)
			(type default)
		)
		(layer "In6.Cu")
	)
	(gr_line
		(start 378.081794 -425.086272)
		(end 378.179838 -425.056554)
		(stroke
			(width 0.05715)
			(type default)
		)
		(layer "In6.Cu")
	)
	(gr_line
		(start 378.086366 -410.091382)
		(end 378.067824 -410.283152)
		(stroke
			(width 0.07112)
			(type default)
		)
		(layer "In6.Cu")
	)
	(gr_line
		(start 378.091192 -397.156432)
		(end 378.143516 -397.208756)
		(stroke
			(width 0.07112)
			(type default)
		)
		(layer "In6.Cu")
	)
	(gr_line
		(start 378.09805 -406.699212)
		(end 378.290074 -406.699212)
		(stroke
			(width 0.07112)
			(type default)
		)
		(layer "In6.Cu")
	)
	(gr_line
		(start 378.135896 -351.621852)
		(end 378.135388 -351.643442)
		(stroke
			(width 0.07112)
			(type default)
		)
		(layer "In6.Cu")
	)
	(gr_line
		(start 378.139452 -351.601278)
		(end 378.135896 -351.621852)
		(stroke
			(width 0.07112)
			(type default)
		)
		(layer "In6.Cu")
	)
	(gr_line
		(start 378.143516 -397.388588)
		(end 377.996958 -397.535146)
		(stroke
			(width 0.07112)
			(type default)
		)
		(layer "In6.Cu")
	)
	(gr_line
		(start 378.143516 -397.208756)
		(end 378.143516 -397.388588)
		(stroke
			(width 0.07112)
			(type default)
		)
		(layer "In6.Cu")
	)
	(gr_line
		(start 378.155962 -422.906952)
		(end 378.797312 -423.136314)
		(stroke
			(width 0.07112)
			(type default)
		)
		(layer "In6.Cu")
	)
	(gr_line
		(start 378.179838 -425.056554)
		(end 378.482606 -425.218352)
		(stroke
			(width 0.05715)
			(type default)
		)
		(layer "In6.Cu")
	)
	(gr_line
		(start 378.252228 -422.64076)
		(end 378.413518 -422.56456)
		(stroke
			(width 0.07112)
			(type default)
		)
		(layer "In6.Cu")
	)
	(gr_line
		(start 378.290074 -406.699212)
		(end 378.59208 -407.001218)
		(stroke
			(width 0.07112)
			(type default)
		)
		(layer "In6.Cu")
	)
	(gr_line
		(start 378.376434 -397.734536)
		(end 378.198126 -397.734536)
		(stroke
			(width 0.07112)
			(type default)
		)
		(layer "In6.Cu")
	)
	(gr_line
		(start 378.413518 -422.56456)
		(end 378.815346 -422.70807)
		(stroke
			(width 0.07112)
			(type default)
		)
		(layer "In6.Cu")
	)
	(gr_line
		(start 378.482606 -425.218352)
		(end 378.512324 -425.316396)
		(stroke
			(width 0.05715)
			(type default)
		)
		(layer "In6.Cu")
	)
	(gr_line
		(start 378.491242 -397.849344)
		(end 378.376434 -397.734536)
		(stroke
			(width 0.07112)
			(type default)
		)
		(layer "In6.Cu")
	)
	(gr_line
		(start 378.552202 -418.412168)
		(end 378.843032 -418.702998)
		(stroke
			(width 0.07112)
			(type default)
		)
		(layer "In6.Cu")
	)
	(gr_line
		(start 378.57176 -402.912834)
		(end 378.57176 -403.613874)
		(stroke
			(width 0.07112)
			(type default)
		)
		(layer "In6.Cu")
	)
	(gr_line
		(start 378.59208 -407.001218)
		(end 378.59208 -407.193242)
		(stroke
			(width 0.07112)
			(type default)
		)
		(layer "In6.Cu")
	)
	(gr_line
		(start 378.815346 -422.70807)
		(end 378.891546 -422.86936)
		(stroke
			(width 0.07112)
			(type default)
		)
		(layer "In6.Cu")
	)
	(gr_line
		(start 378.843032 -419.477698)
		(end 378.843032 -420.178738)
		(stroke
			(width 0.07112)
			(type default)
		)
		(layer "In6.Cu")
	)
	(gr_line
		(start 378.843032 -415.09569)
		(end 378.552202 -415.38652)
		(stroke
			(width 0.07112)
			(type default)
		)
		(layer "In6.Cu")
	)
	(gr_line
		(start 378.85497 -402.914104)
		(end 378.99086 -403.049994)
		(stroke
			(width 0.07112)
			(type default)
		)
		(layer "In6.Cu")
	)
	(gr_line
		(start 378.881894 -425.731432)
		(end 379.314456 -425.962572)
		(stroke
			(width 0.05715)
			(type default)
		)
		(layer "In6.Cu")
	)
	(gr_line
		(start 378.97308 -425.562776)
		(end 379.071378 -425.532804)
		(stroke
			(width 0.05715)
			(type default)
		)
		(layer "In6.Cu")
	)
	(gr_line
		(start 378.99086 -403.476714)
		(end 378.85497 -403.612604)
		(stroke
			(width 0.07112)
			(type default)
		)
		(layer "In6.Cu")
	)
	(gr_line
		(start 378.99086 -403.049994)
		(end 378.99086 -403.476714)
		(stroke
			(width 0.07112)
			(type default)
		)
		(layer "In6.Cu")
	)
	(gr_line
		(start 379.071378 -425.532804)
		(end 379.374146 -425.694856)
		(stroke
			(width 0.05715)
			(type default)
		)
		(layer "In6.Cu")
	)
	(gr_line
		(start 379.088396 -351.759266)
		(end 379.088142 -351.759266)
		(stroke
			(width 0.07112)
			(type default)
		)
		(layer "In6.Cu")
	)
	(gr_line
		(start 379.124972 -415.09569)
		(end 379.415802 -415.38652)
		(stroke
			(width 0.07112)
			(type default)
		)
		(layer "In6.Cu")
	)
	(gr_line
		(start 379.126242 -419.478968)
		(end 379.262132 -419.614858)
		(stroke
			(width 0.07112)
			(type default)
		)
		(layer "In6.Cu")
	)
	(gr_line
		(start 379.262132 -420.041578)
		(end 379.126242 -420.177468)
		(stroke
			(width 0.07112)
			(type default)
		)
		(layer "In6.Cu")
	)
	(gr_line
		(start 379.262132 -419.614858)
		(end 379.262132 -420.041578)
		(stroke
			(width 0.07112)
			(type default)
		)
		(layer "In6.Cu")
	)
	(gr_line
		(start 379.291342 -397.156432)
		(end 379.343666 -397.208756)
		(stroke
			(width 0.07112)
			(type default)
		)
		(layer "In6.Cu")
	)
	(gr_line
		(start 379.314456 -425.962572)
		(end 379.31471 -425.962572)
		(stroke
			(width 0.05715)
			(type default)
		)
		(layer "In6.Cu")
	)
	(gr_line
		(start 379.343666 -397.401796)
		(end 379.210316 -397.535146)
		(stroke
			(width 0.07112)
			(type default)
		)
		(layer "In6.Cu")
	)
	(gr_line
		(start 379.343666 -397.208756)
		(end 379.343666 -397.401796)
		(stroke
			(width 0.07112)
			(type default)
		)
		(layer "In6.Cu")
	)
	(gr_line
		(start 379.374146 -425.694856)
		(end 379.403864 -425.7929)
		(stroke
			(width 0.05715)
			(type default)
		)
		(layer "In6.Cu")
	)
	(gr_line
		(start 379.415802 -418.412168)
		(end 379.124972 -418.702998)
		(stroke
			(width 0.07112)
			(type default)
		)
		(layer "In6.Cu")
	)
	(gr_line
		(start 379.57633 -397.734536)
		(end 379.411484 -397.734536)
		(stroke
			(width 0.07112)
			(type default)
		)
		(layer "In6.Cu")
	)
	(gr_line
		(start 379.691138 -397.849344)
		(end 379.57633 -397.734536)
		(stroke
			(width 0.07112)
			(type default)
		)
		(layer "In6.Cu")
	)
	(gr_line
		(start 379.77191 -402.886418)
		(end 379.77191 -403.587458)
		(stroke
			(width 0.07112)
			(type default)
		)
		(layer "In6.Cu")
	)
	(gr_line
		(start 379.837188 -422.364408)
		(end 379.958854 -422.4147)
		(stroke
			(width 0.07112)
			(type default)
		)
		(layer "In6.Cu")
	)
	(gr_line
		(start 379.946662 -422.103042)
		(end 380.124208 -422.029636)
		(stroke
			(width 0.07112)
			(type default)
		)
		(layer "In6.Cu")
	)
	(gr_line
		(start 379.958854 -422.4147)
		(end 380.485396 -422.632632)
		(stroke
			(width 0.07112)
			(type default)
		)
		(layer "In6.Cu")
	)
	(gr_line
		(start 380.05512 -402.887688)
		(end 380.19101 -403.023578)
		(stroke
			(width 0.07112)
			(type default)
		)
		(layer "In6.Cu")
	)
	(gr_line
		(start 380.124208 -422.029636)
		(end 380.518924 -422.192704)
		(stroke
			(width 0.07112)
			(type default)
		)
		(layer "In6.Cu")
	)
	(gr_line
		(start 380.19101 -403.450298)
		(end 380.05512 -403.586188)
		(stroke
			(width 0.07112)
			(type default)
		)
		(layer "In6.Cu")
	)
	(gr_line
		(start 380.19101 -403.023578)
		(end 380.19101 -403.450298)
		(stroke
			(width 0.07112)
			(type default)
		)
		(layer "In6.Cu")
	)
	(gr_line
		(start 380.318264 -320.366898)
		(end 380.318518 -320.366898)
		(stroke
			(width 0.07112)
			(type default)
		)
		(layer "In6.Cu")
	)
	(gr_line
		(start 380.485396 -422.632632)
		(end 380.63297 -422.693846)
		(stroke
			(width 0.07112)
			(type default)
		)
		(layer "In6.Cu")
	)
	(gr_line
		(start 380.491238 -397.156432)
		(end 380.536958 -397.202152)
		(stroke
			(width 0.07112)
			(type default)
		)
		(layer "In6.Cu")
	)
	(gr_line
		(start 380.518924 -422.192704)
		(end 380.59233 -422.370504)
		(stroke
			(width 0.07112)
			(type default)
		)
		(layer "In6.Cu")
	)
	(gr_line
		(start 380.536958 -397.381984)
		(end 380.383796 -397.535146)
		(stroke
			(width 0.07112)
			(type default)
		)
		(layer "In6.Cu")
	)
	(gr_line
		(start 380.536958 -397.202152)
		(end 380.536958 -397.381984)
		(stroke
			(width 0.07112)
			(type default)
		)
		(layer "In6.Cu")
	)
	(gr_line
		(start 380.593092 -422.372282)
		(end 380.740666 -422.433242)
		(stroke
			(width 0.07112)
			(type default)
		)
		(layer "In6.Cu")
	)
	(gr_line
		(start 380.729236 -310.822086)
		(end 380.720346 -310.811418)
		(stroke
			(width 0.07112)
			(type default)
		)
		(layer "In6.Cu")
	)
	(gr_line
		(start 380.736856 -310.833516)
		(end 380.736856 -310.833262)
		(stroke
			(width 0.07112)
			(type default)
		)
		(layer "In6.Cu")
	)
	(gr_line
		(start 380.736856 -310.833262)
		(end 380.729236 -310.822086)
		(stroke
			(width 0.07112)
			(type default)
		)
		(layer "In6.Cu")
	)
	(gr_line
		(start 380.77648 -397.734536)
		(end 380.584964 -397.734536)
		(stroke
			(width 0.07112)
			(type default)
		)
		(layer "In6.Cu")
	)
	(gr_line
		(start 380.879604 -422.795954)
		(end 381.527558 -423.064432)
		(stroke
			(width 0.07112)
			(type default)
		)
		(layer "In6.Cu")
	)
	(gr_line
		(start 380.891288 -397.849344)
		(end 380.77648 -397.734536)
		(stroke
			(width 0.07112)
			(type default)
		)
		(layer "In6.Cu")
	)
	(gr_line
		(start 380.939548 -402.90242)
		(end 380.939548 -403.60346)
		(stroke
			(width 0.07112)
			(type default)
		)
		(layer "In6.Cu")
	)
	(gr_line
		(start 380.988824 -422.534842)
		(end 381.16637 -422.461182)
		(stroke
			(width 0.07112)
			(type default)
		)
		(layer "In6.Cu")
	)
	(gr_line
		(start 381.153416 -343.878154)
		(end 381.153416 -343.877646)
		(stroke
			(width 0.07112)
			(type default)
		)
		(layer "In6.Cu")
	)
	(gr_line
		(start 381.16637 -422.461182)
		(end 381.560832 -422.624504)
		(stroke
			(width 0.07112)
			(type default)
		)
		(layer "In6.Cu")
	)
	(gr_line
		(start 381.222758 -402.90369)
		(end 381.358648 -403.03958)
		(stroke
			(width 0.07112)
			(type default)
		)
		(layer "In6.Cu")
	)
	(gr_line
		(start 381.358648 -403.4663)
		(end 381.222758 -403.60219)
		(stroke
			(width 0.07112)
			(type default)
		)
		(layer "In6.Cu")
	)
	(gr_line
		(start 381.358648 -403.03958)
		(end 381.358648 -403.4663)
		(stroke
			(width 0.07112)
			(type default)
		)
		(layer "In6.Cu")
	)
	(gr_line
		(start 381.453898 -310.22798)
		(end 381.445008 -310.217312)
		(stroke
			(width 0.07112)
			(type default)
		)
		(layer "In6.Cu")
	)
	(gr_line
		(start 381.461518 -310.23941)
		(end 381.461518 -310.239156)
		(stroke
			(width 0.07112)
			(type default)
		)
		(layer "In6.Cu")
	)
	(gr_line
		(start 381.461518 -310.239156)
		(end 381.453898 -310.22798)
		(stroke
			(width 0.07112)
			(type default)
		)
		(layer "In6.Cu")
	)
	(gr_line
		(start 381.527558 -423.064432)
		(end 381.533908 -423.066972)
		(stroke
			(width 0.07112)
			(type default)
		)
		(layer "In6.Cu")
	)
	(gr_line
		(start 381.560832 -422.624504)
		(end 381.634492 -422.80205)
		(stroke
			(width 0.07112)
			(type default)
		)
		(layer "In6.Cu")
	)
	(gr_line
		(start 381.615442 -418.412168)
		(end 381.906272 -418.702998)
		(stroke
			(width 0.07112)
			(type default)
		)
		(layer "In6.Cu")
	)
	(gr_line
		(start 381.622808 -426.785024)
		(end 381.749808 -426.912024)
		(stroke
			(width 0.05715)
			(type default)
		)
		(layer "In6.Cu")
	)
	(gr_line
		(start 381.622808 -426.594524)
		(end 381.749808 -426.467524)
		(stroke
			(width 0.05715)
			(type default)
		)
		(layer "In6.Cu")
	)
	(gr_line
		(start 381.635254 -422.803828)
		(end 381.641858 -422.806622)
		(stroke
			(width 0.07112)
			(type default)
		)
		(layer "In6.Cu")
	)
	(gr_line
		(start 381.691134 -397.156432)
		(end 381.743458 -397.208756)
		(stroke
			(width 0.07112)
			(type default)
		)
		(layer "In6.Cu")
	)
	(gr_line
		(start 381.743458 -397.388588)
		(end 381.5969 -397.535146)
		(stroke
			(width 0.07112)
			(type default)
		)
		(layer "In6.Cu")
	)
	(gr_line
		(start 381.743458 -397.208756)
		(end 381.743458 -397.388588)
		(stroke
			(width 0.07112)
			(type default)
		)
		(layer "In6.Cu")
	)
	(gr_line
		(start 381.749808 -426.912024)
		(end 381.749808 -427.289976)
		(stroke
			(width 0.05715)
			(type default)
		)
		(layer "In6.Cu")
	)
	(gr_line
		(start 381.749808 -426.467524)
		(end 381.749808 -426.089826)
		(stroke
			(width 0.05715)
			(type default)
		)
		(layer "In6.Cu")
	)
	(gr_line
		(start 381.906272 -419.587426)
		(end 381.906272 -420.288466)
		(stroke
			(width 0.07112)
			(type default)
		)
		(layer "In6.Cu")
	)
	(gr_line
		(start 381.906272 -415.09569)
		(end 381.615442 -415.38652)
		(stroke
			(width 0.07112)
			(type default)
		)
		(layer "In6.Cu")
	)
	(gr_line
		(start 381.906272 -413.404558)
		(end 381.906272 -414.105598)
		(stroke
			(width 0.07112)
			(type default)
		)
		(layer "In6.Cu")
	)
	(gr_line
		(start 381.921512 -423.2275)
		(end 382.56972 -423.495978)
		(stroke
			(width 0.07112)
			(type default)
		)
		(layer "In6.Cu")
	)
	(gr_line
		(start 381.976376 -397.734536)
		(end 381.798068 -397.734536)
		(stroke
			(width 0.07112)
			(type default)
		)
		(layer "In6.Cu")
	)
	(gr_line
		(start 382.030986 -422.966388)
		(end 382.208532 -422.892728)
		(stroke
			(width 0.07112)
			(type default)
		)
		(layer "In6.Cu")
	)
	(gr_line
		(start 382.091184 -397.849344)
		(end 381.976376 -397.734536)
		(stroke
			(width 0.07112)
			(type default)
		)
		(layer "In6.Cu")
	)
	(gr_line
		(start 382.099312 -343.757758)
		(end 382.099312 -343.75725)
		(stroke
			(width 0.07112)
			(type default)
		)
		(layer "In6.Cu")
	)
	(gr_line
		(start 382.17856 -309.633874)
		(end 382.16967 -309.623206)
		(stroke
			(width 0.07112)
			(type default)
		)
		(layer "In6.Cu")
	)
	(gr_line
		(start 382.18618 -309.645304)
		(end 382.18618 -309.64505)
		(stroke
			(width 0.07112)
			(type default)
		)
		(layer "In6.Cu")
	)
	(gr_line
		(start 382.18618 -309.64505)
		(end 382.17856 -309.633874)
		(stroke
			(width 0.07112)
			(type default)
		)
		(layer "In6.Cu")
	)
	(gr_line
		(start 382.188212 -415.09569)
		(end 382.479042 -415.38652)
		(stroke
			(width 0.07112)
			(type default)
		)
		(layer "In6.Cu")
	)
	(gr_line
		(start 382.189482 -419.588696)
		(end 382.325372 -419.724586)
		(stroke
			(width 0.07112)
			(type default)
		)
		(layer "In6.Cu")
	)
	(gr_line
		(start 382.189482 -413.405828)
		(end 382.325372 -413.541718)
		(stroke
			(width 0.07112)
			(type default)
		)
		(layer "In6.Cu")
	)
	(gr_line
		(start 382.208532 -422.892728)
		(end 382.602994 -423.05605)
		(stroke
			(width 0.07112)
			(type default)
		)
		(layer "In6.Cu")
	)
	(gr_line
		(start 382.325372 -420.151306)
		(end 382.189482 -420.287196)
		(stroke
			(width 0.07112)
			(type default)
		)
		(layer "In6.Cu")
	)
	(gr_line
		(start 382.325372 -419.724586)
		(end 382.325372 -420.151306)
		(stroke
			(width 0.07112)
			(type default)
		)
		(layer "In6.Cu")
	)
	(gr_line
		(start 382.325372 -413.968438)
		(end 382.189482 -414.104328)
		(stroke
			(width 0.07112)
			(type default)
		)
		(layer "In6.Cu")
	)
	(gr_line
		(start 382.325372 -413.541718)
		(end 382.325372 -413.968438)
		(stroke
			(width 0.07112)
			(type default)
		)
		(layer "In6.Cu")
	)
	(gr_line
		(start 382.479042 -418.412168)
		(end 382.188212 -418.702998)
		(stroke
			(width 0.07112)
			(type default)
		)
		(layer "In6.Cu")
	)
	(gr_line
		(start 382.602994 -423.05605)
		(end 382.676654 -423.23385)
		(stroke
			(width 0.07112)
			(type default)
		)
		(layer "In6.Cu")
	)
	(gr_line
		(start 382.891284 -397.156432)
		(end 382.933448 -397.198596)
		(stroke
			(width 0.07112)
			(type default)
		)
		(layer "In6.Cu")
	)
	(gr_line
		(start 382.933448 -397.378428)
		(end 382.77673 -397.535146)
		(stroke
			(width 0.07112)
			(type default)
		)
		(layer "In6.Cu")
	)
	(gr_line
		(start 382.933448 -397.198596)
		(end 382.933448 -397.378428)
		(stroke
			(width 0.07112)
			(type default)
		)
		(layer "In6.Cu")
	)
	(gr_line
		(start 382.963674 -423.6593)
		(end 383.612136 -423.927778)
		(stroke
			(width 0.07112)
			(type default)
		)
		(layer "In6.Cu")
	)
	(gr_line
		(start 383.006346 -343.408)
		(end 383.006346 -343.407492)
		(stroke
			(width 0.07112)
			(type default)
		)
		(layer "In6.Cu")
	)
	(gr_line
		(start 383.072894 -423.397934)
		(end 383.250694 -423.324274)
		(stroke
			(width 0.07112)
			(type default)
		)
		(layer "In6.Cu")
	)
	(gr_line
		(start 383.128012 -309.311802)
		(end 383.119122 -309.301134)
		(stroke
			(width 0.07112)
			(type default)
		)
		(layer "In6.Cu")
	)
	(gr_line
		(start 383.135632 -309.323232)
		(end 383.135632 -309.322978)
		(stroke
			(width 0.07112)
			(type default)
		)
		(layer "In6.Cu")
	)
	(gr_line
		(start 383.135632 -309.322978)
		(end 383.128012 -309.311802)
		(stroke
			(width 0.07112)
			(type default)
		)
		(layer "In6.Cu")
	)
	(gr_line
		(start 383.176526 -397.734536)
		(end 382.977898 -397.734536)
		(stroke
			(width 0.07112)
			(type default)
		)
		(layer "In6.Cu")
	)
	(gr_line
		(start 383.250694 -423.324274)
		(end 383.645156 -423.487596)
		(stroke
			(width 0.07112)
			(type default)
		)
		(layer "In6.Cu")
	)
	(gr_line
		(start 383.291334 -397.849344)
		(end 383.176526 -397.734536)
		(stroke
			(width 0.07112)
			(type default)
		)
		(layer "In6.Cu")
	)
	(gr_arc
		(start 383.601976 -9.272016)
		(mid 384.656976 -8.83502)
		(end 385.093972 -7.78002)
		(stroke
			(width 0.2)
			(type default)
		)
		(layer "In6.Cu")
	)
	(gr_line
		(start 383.612898 -427.548802)
		(end 383.62255 -427.548802)
		(stroke
			(width 0.07112)
			(type default)
		)
		(layer "In6.Cu")
	)
	(gr_line
		(start 383.614168 -427.832012)
		(end 383.749804 -427.967648)
		(stroke
			(width 0.07112)
			(type default)
		)
		(layer "In6.Cu")
	)
	(gr_line
		(start 383.62255 -427.548802)
		(end 383.749804 -427.421548)
		(stroke
			(width 0.07112)
			(type default)
		)
		(layer "In6.Cu")
	)
	(gr_line
		(start 383.645156 -423.487596)
		(end 383.71907 -423.665396)
		(stroke
			(width 0.07112)
			(type default)
		)
		(layer "In6.Cu")
	)
	(gr_line
		(start 383.749804 -427.967648)
		(end 383.749804 -428.28972)
		(stroke
			(width 0.07112)
			(type default)
		)
		(layer "In6.Cu")
	)
	(gr_line
		(start 383.749804 -427.421548)
		(end 383.749804 -427.089824)
		(stroke
			(width 0.07112)
			(type default)
		)
		(layer "In6.Cu")
	)
	(gr_line
		(start 383.900172 -423.741342)
		(end 383.900172 -423.74185)
		(stroke
			(width 0.07112)
			(type default)
		)
		(layer "In6.Cu")
	)
	(gr_line
		(start 383.922016 -422.86936)
		(end 384.5052 -423.258996)
		(stroke
			(width 0.07112)
			(type default)
		)
		(layer "In6.Cu")
	)
	(gr_line
		(start 384.080512 -422.634664)
		(end 384.26898 -422.597072)
		(stroke
			(width 0.07112)
			(type default)
		)
		(layer "In6.Cu")
	)
	(gr_line
		(start 384.09118 -397.156432)
		(end 384.143504 -397.208756)
		(stroke
			(width 0.07112)
			(type default)
		)
		(layer "In6.Cu")
	)
	(gr_line
		(start 384.143504 -397.388588)
		(end 383.996946 -397.535146)
		(stroke
			(width 0.07112)
			(type default)
		)
		(layer "In6.Cu")
	)
	(gr_line
		(start 384.143504 -397.208756)
		(end 384.143504 -397.388588)
		(stroke
			(width 0.07112)
			(type default)
		)
		(layer "In6.Cu")
	)
	(gr_line
		(start 384.224276 -343.253314)
		(end 384.224276 -343.252806)
		(stroke
			(width 0.07112)
			(type default)
		)
		(layer "In6.Cu")
	)
	(gr_line
		(start 384.26898 -422.597072)
		(end 384.624072 -422.834308)
		(stroke
			(width 0.07112)
			(type default)
		)
		(layer "In6.Cu")
	)
	(gr_line
		(start 384.376422 -397.734536)
		(end 384.198114 -397.734536)
		(stroke
			(width 0.07112)
			(type default)
		)
		(layer "In6.Cu")
	)
	(gr_line
		(start 384.49123 -397.849344)
		(end 384.376422 -397.734536)
		(stroke
			(width 0.07112)
			(type default)
		)
		(layer "In6.Cu")
	)
	(gr_line
		(start 384.624072 -422.834308)
		(end 384.661664 -423.02303)
		(stroke
			(width 0.07112)
			(type default)
		)
		(layer "In6.Cu")
	)
	(gr_line
		(start 384.678682 -418.412168)
		(end 384.969512 -418.702998)
		(stroke
			(width 0.07112)
			(type default)
		)
		(layer "In6.Cu")
	)
	(gr_line
		(start 384.846322 -342.874092)
		(end 384.846322 -342.873584)
		(stroke
			(width 0.07112)
			(type default)
		)
		(layer "In6.Cu")
	)
	(gr_line
		(start 384.848608 -352.630994)
		(end 384.848354 -352.630232)
		(stroke
			(width 0.07112)
			(type default)
		)
		(layer "In6.Cu")
	)
	(gr_line
		(start 384.85318 -352.641916)
		(end 384.848862 -352.631248)
		(stroke
			(width 0.07112)
			(type default)
		)
		(layer "In6.Cu")
	)
	(gr_line
		(start 384.859784 -423.495978)
		(end 385.442968 -423.885614)
		(stroke
			(width 0.07112)
			(type default)
		)
		(layer "In6.Cu")
	)
	(gr_line
		(start 384.969512 -419.552882)
		(end 384.969512 -420.253922)
		(stroke
			(width 0.07112)
			(type default)
		)
		(layer "In6.Cu")
	)
	(gr_line
		(start 384.969512 -415.09569)
		(end 384.678682 -415.38652)
		(stroke
			(width 0.07112)
			(type default)
		)
		(layer "In6.Cu")
	)
	(gr_line
		(start 384.969512 -413.76219)
		(end 384.969512 -414.46323)
		(stroke
			(width 0.07112)
			(type default)
		)
		(layer "In6.Cu")
	)
	(gr_line
		(start 384.983482 -404.337012)
		(end 385.479544 -404.833074)
		(stroke
			(width 0.07112)
			(type default)
		)
		(layer "In6.Cu")
	)
	(gr_line
		(start 385.018026 -423.261282)
		(end 385.206748 -423.22369)
		(stroke
			(width 0.07112)
			(type default)
		)
		(layer "In6.Cu")
	)
	(gr_line
		(start 385.093972 -7.78002)
		(end 385.093972 0.40005)
		(stroke
			(width 0.2)
			(type default)
		)
		(layer "In6.Cu")
	)
	(gr_line
		(start 385.113784 -352.533966)
		(end 385.109212 -352.523044)
		(stroke
			(width 0.07112)
			(type default)
		)
		(layer "In6.Cu")
	)
	(gr_line
		(start 385.18465 -404.137622)
		(end 385.376928 -404.137622)
		(stroke
			(width 0.07112)
			(type default)
		)
		(layer "In6.Cu")
	)
	(gr_line
		(start 385.206748 -423.22369)
		(end 385.56184 -423.460926)
		(stroke
			(width 0.07112)
			(type default)
		)
		(layer "In6.Cu")
	)
	(gr_line
		(start 385.251452 -415.09569)
		(end 385.542282 -415.38652)
		(stroke
			(width 0.07112)
			(type default)
		)
		(layer "In6.Cu")
	)
	(gr_line
		(start 385.252722 -419.554152)
		(end 385.388612 -419.690042)
		(stroke
			(width 0.07112)
			(type default)
		)
		(layer "In6.Cu")
	)
	(gr_line
		(start 385.252722 -413.76346)
		(end 385.388612 -413.89935)
		(stroke
			(width 0.07112)
			(type default)
		)
		(layer "In6.Cu")
	)
	(gr_line
		(start 385.29133 -397.156432)
		(end 385.343654 -397.208756)
		(stroke
			(width 0.07112)
			(type default)
		)
		(layer "In6.Cu")
	)
	(gr_line
		(start 385.343654 -397.405352)
		(end 385.21386 -397.535146)
		(stroke
			(width 0.07112)
			(type default)
		)
		(layer "In6.Cu")
	)
	(gr_line
		(start 385.343654 -397.208756)
		(end 385.343654 -397.405352)
		(stroke
			(width 0.07112)
			(type default)
		)
		(layer "In6.Cu")
	)
	(gr_line
		(start 385.376928 -404.137622)
		(end 385.678934 -404.439628)
		(stroke
			(width 0.07112)
			(type default)
		)
		(layer "In6.Cu")
	)
	(gr_line
		(start 385.388612 -420.116762)
		(end 385.252722 -420.252652)
		(stroke
			(width 0.07112)
			(type default)
		)
		(layer "In6.Cu")
	)
	(gr_line
		(start 385.388612 -419.690042)
		(end 385.388612 -420.116762)
		(stroke
			(width 0.07112)
			(type default)
		)
		(layer "In6.Cu")
	)
	(gr_line
		(start 385.388612 -414.32607)
		(end 385.252722 -414.46196)
		(stroke
			(width 0.07112)
			(type default)
		)
		(layer "In6.Cu")
	)
	(gr_line
		(start 385.388612 -413.89935)
		(end 385.388612 -414.32607)
		(stroke
			(width 0.07112)
			(type default)
		)
		(layer "In6.Cu")
	)
	(gr_line
		(start 385.542282 -418.412168)
		(end 385.251452 -418.702998)
		(stroke
			(width 0.07112)
			(type default)
		)
		(layer "In6.Cu")
	)
	(gr_line
		(start 385.56184 -423.460926)
		(end 385.599432 -423.649648)
		(stroke
			(width 0.07112)
			(type default)
		)
		(layer "In6.Cu")
	)
	(gr_line
		(start 385.576318 -397.734536)
		(end 385.415028 -397.734536)
		(stroke
			(width 0.07112)
			(type default)
		)
		(layer "In6.Cu")
	)
	(gr_line
		(start 385.601972 -12.288012)
		(end 260.800088 -12.288012)
		(stroke
			(width 0.2)
			(type default)
		)
		(layer "In6.Cu")
	)
	(gr_arc
		(start 385.601972 -12.288012)
		(mid 387.375417 -11.553448)
		(end 388.109968 -9.780016)
		(stroke
			(width 0.2)
			(type default)
		)
		(layer "In6.Cu")
	)
	(gr_line
		(start 385.60756 -426.830744)
		(end 385.7498 -426.972984)
		(stroke
			(width 0.07112)
			(type default)
		)
		(layer "In6.Cu")
	)
	(gr_line
		(start 385.60756 -426.548804)
		(end 385.7498 -426.406564)
		(stroke
			(width 0.07112)
			(type default)
		)
		(layer "In6.Cu")
	)
	(gr_line
		(start 385.678934 -404.439628)
		(end 385.678934 -404.631906)
		(stroke
			(width 0.07112)
			(type default)
		)
		(layer "In6.Cu")
	)
	(gr_line
		(start 385.691126 -397.849344)
		(end 385.576318 -397.734536)
		(stroke
			(width 0.07112)
			(type default)
		)
		(layer "In6.Cu")
	)
	(gr_line
		(start 385.7498 -426.972984)
		(end 385.7498 -427.289976)
		(stroke
			(width 0.07112)
			(type default)
		)
		(layer "In6.Cu")
	)
	(gr_line
		(start 385.7498 -426.406564)
		(end 385.7498 -426.089826)
		(stroke
			(width 0.07112)
			(type default)
		)
		(layer "In6.Cu")
	)
	(gr_line
		(start 385.77266 -342.65743)
		(end 385.77266 -342.656922)
		(stroke
			(width 0.07112)
			(type default)
		)
		(layer "In6.Cu")
	)
	(gr_line
		(start 385.810506 -422.514014)
		(end 386.373878 -422.932098)
		(stroke
			(width 0.07112)
			(type default)
		)
		(layer "In6.Cu")
	)
	(gr_line
		(start 385.810506 -422.51376)
		(end 385.810506 -422.514014)
		(stroke
			(width 0.07112)
			(type default)
		)
		(layer "In6.Cu")
	)
	(gr_line
		(start 385.980178 -422.287192)
		(end 386.170424 -422.258998)
		(stroke
			(width 0.07112)
			(type default)
		)
		(layer "In6.Cu")
	)
	(gr_line
		(start 386.155692 -403.732492)
		(end 386.651754 -404.228554)
		(stroke
			(width 0.07112)
			(type default)
		)
		(layer "In6.Cu")
	)
	(gr_line
		(start 386.170424 -422.258998)
		(end 386.513324 -422.513506)
		(stroke
			(width 0.07112)
			(type default)
		)
		(layer "In6.Cu")
	)
	(gr_line
		(start 386.35686 -403.533102)
		(end 386.549138 -403.533102)
		(stroke
			(width 0.07112)
			(type default)
		)
		(layer "In6.Cu")
	)
	(gr_line
		(start 386.479288 -411.39745)
		(end 387.139942 -411.633924)
		(stroke
			(width 0.07112)
			(type default)
		)
		(layer "In6.Cu")
	)
	(gr_line
		(start 386.491226 -397.156432)
		(end 386.54355 -397.208756)
		(stroke
			(width 0.07112)
			(type default)
		)
		(layer "In6.Cu")
	)
	(gr_line
		(start 386.513324 -422.513506)
		(end 386.541518 -422.703752)
		(stroke
			(width 0.07112)
			(type default)
		)
		(layer "In6.Cu")
	)
	(gr_line
		(start 386.541772 -422.70553)
		(end 386.685282 -422.811956)
		(stroke
			(width 0.07112)
			(type default)
		)
		(layer "In6.Cu")
	)
	(gr_line
		(start 386.54355 -397.388588)
		(end 386.396992 -397.535146)
		(stroke
			(width 0.07112)
			(type default)
		)
		(layer "In6.Cu")
	)
	(gr_line
		(start 386.54355 -397.208756)
		(end 386.54355 -397.388588)
		(stroke
			(width 0.07112)
			(type default)
		)
		(layer "In6.Cu")
	)
	(gr_line
		(start 386.549138 -403.533102)
		(end 386.851144 -403.835108)
		(stroke
			(width 0.07112)
			(type default)
		)
		(layer "In6.Cu")
	)
	(gr_line
		(start 386.575554 -411.131258)
		(end 386.749544 -411.048708)
		(stroke
			(width 0.07112)
			(type default)
		)
		(layer "In6.Cu")
	)
	(gr_line
		(start 386.628386 -351.792032)
		(end 386.628132 -351.79127)
		(stroke
			(width 0.07112)
			(type default)
		)
		(layer "In6.Cu")
	)
	(gr_line
		(start 386.704586 -342.517984)
		(end 386.704586 -342.517476)
		(stroke
			(width 0.07112)
			(type default)
		)
		(layer "In6.Cu")
	)
	(gr_line
		(start 386.716524 -423.186098)
		(end 387.279896 -423.604182)
		(stroke
			(width 0.07112)
			(type default)
		)
		(layer "In6.Cu")
	)
	(gr_line
		(start 386.749544 -411.048708)
		(end 387.151626 -411.192472)
		(stroke
			(width 0.07112)
			(type default)
		)
		(layer "In6.Cu")
	)
	(gr_line
		(start 386.776468 -397.734536)
		(end 386.59816 -397.734536)
		(stroke
			(width 0.07112)
			(type default)
		)
		(layer "In6.Cu")
	)
	(gr_line
		(start 386.851144 -403.835108)
		(end 386.851144 -404.027386)
		(stroke
			(width 0.07112)
			(type default)
		)
		(layer "In6.Cu")
	)
	(gr_line
		(start 386.886196 -422.959276)
		(end 387.076188 -422.931082)
		(stroke
			(width 0.07112)
			(type default)
		)
		(layer "In6.Cu")
	)
	(gr_line
		(start 386.88899 -351.683828)
		(end 386.888736 -351.683574)
		(stroke
			(width 0.07112)
			(type default)
		)
		(layer "In6.Cu")
	)
	(gr_line
		(start 386.891276 -397.849344)
		(end 386.776468 -397.734536)
		(stroke
			(width 0.07112)
			(type default)
		)
		(layer "In6.Cu")
	)
	(gr_line
		(start 387.076188 -422.931082)
		(end 387.419342 -423.18559)
		(stroke
			(width 0.07112)
			(type default)
		)
		(layer "In6.Cu")
	)
	(gr_line
		(start 387.151626 -411.192472)
		(end 387.233922 -411.366716)
		(stroke
			(width 0.07112)
			(type default)
		)
		(layer "In6.Cu")
	)
	(gr_line
		(start 387.279896 -423.604182)
		(end 387.348476 -423.654982)
		(stroke
			(width 0.07112)
			(type default)
		)
		(layer "In6.Cu")
	)
	(gr_line
		(start 387.419342 -423.18559)
		(end 387.447536 -423.375836)
		(stroke
			(width 0.07112)
			(type default)
		)
		(layer "In6.Cu")
	)
	(gr_line
		(start 387.44779 -423.377614)
		(end 387.51637 -423.428414)
		(stroke
			(width 0.07112)
			(type default)
		)
		(layer "In6.Cu")
	)
	(gr_arc
		(start 387.601968 2.908046)
		(mid 385.828585 2.173457)
		(end 385.093972 0.40005)
		(stroke
			(width 0.2)
			(type default)
		)
		(layer "In6.Cu")
	)
	(gr_line
		(start 387.601968 2.908046)
		(end 456.202034 2.908046)
		(stroke
			(width 0.2)
			(type default)
		)
		(layer "In6.Cu")
	)
	(gr_line
		(start 387.607556 -427.830742)
		(end 387.749796 -427.972982)
		(stroke
			(width 0.07112)
			(type default)
		)
		(layer "In6.Cu")
	)
	(gr_line
		(start 387.607556 -427.548802)
		(end 387.749796 -427.406562)
		(stroke
			(width 0.07112)
			(type default)
		)
		(layer "In6.Cu")
	)
	(gr_line
		(start 387.622542 -423.858182)
		(end 388.18566 -424.276012)
		(stroke
			(width 0.07112)
			(type default)
		)
		(layer "In6.Cu")
	)
	(gr_line
		(start 387.649212 -342.459056)
		(end 387.649212 -342.458548)
		(stroke
			(width 0.07112)
			(type default)
		)
		(layer "In6.Cu")
	)
	(gr_line
		(start 387.691376 -397.156432)
		(end 387.736588 -397.201644)
		(stroke
			(width 0.07112)
			(type default)
		)
		(layer "In6.Cu")
	)
	(gr_line
		(start 387.736588 -397.381476)
		(end 387.582918 -397.535146)
		(stroke
			(width 0.07112)
			(type default)
		)
		(layer "In6.Cu")
	)
	(gr_line
		(start 387.736588 -397.201644)
		(end 387.736588 -397.381476)
		(stroke
			(width 0.07112)
			(type default)
		)
		(layer "In6.Cu")
	)
	(gr_line
		(start 387.741922 -418.412168)
		(end 388.032752 -418.702998)
		(stroke
			(width 0.07112)
			(type default)
		)
		(layer "In6.Cu")
	)
	(gr_line
		(start 387.749796 -427.972982)
		(end 387.749796 -428.28972)
		(stroke
			(width 0.07112)
			(type default)
		)
		(layer "In6.Cu")
	)
	(gr_line
		(start 387.749796 -427.406562)
		(end 387.749796 -427.089824)
		(stroke
			(width 0.07112)
			(type default)
		)
		(layer "In6.Cu")
	)
	(gr_line
		(start 387.757162 -351.189036)
		(end 387.757162 -351.188782)
		(stroke
			(width 0.07112)
			(type default)
		)
		(layer "In6.Cu")
	)
	(gr_line
		(start 387.79196 -423.63136)
		(end 387.982206 -423.603166)
		(stroke
			(width 0.07112)
			(type default)
		)
		(layer "In6.Cu")
	)
	(gr_line
		(start 387.976364 -397.734536)
		(end 387.784086 -397.734536)
		(stroke
			(width 0.07112)
			(type default)
		)
		(layer "In6.Cu")
	)
	(gr_line
		(start 387.982206 -423.603166)
		(end 388.32536 -423.857674)
		(stroke
			(width 0.07112)
			(type default)
		)
		(layer "In6.Cu")
	)
	(gr_line
		(start 388.032752 -419.578028)
		(end 388.032752 -420.279068)
		(stroke
			(width 0.07112)
			(type default)
		)
		(layer "In6.Cu")
	)
	(gr_line
		(start 388.032752 -415.09569)
		(end 387.741922 -415.38652)
		(stroke
			(width 0.07112)
			(type default)
		)
		(layer "In6.Cu")
	)
	(gr_line
		(start 388.032752 -413.748982)
		(end 388.032752 -414.450022)
		(stroke
			(width 0.07112)
			(type default)
		)
		(layer "In6.Cu")
	)
	(gr_line
		(start 388.091172 -397.849344)
		(end 387.976364 -397.734536)
		(stroke
			(width 0.07112)
			(type default)
		)
		(layer "In6.Cu")
	)
	(gr_line
		(start 388.109968 -0.508)
		(end 388.109968 -9.780016)
		(stroke
			(width 0.2)
			(type default)
		)
		(layer "In6.Cu")
	)
	(gr_line
		(start 388.18566 -424.276012)
		(end 388.18566 -424.275758)
		(stroke
			(width 0.07112)
			(type default)
		)
		(layer "In6.Cu")
	)
	(gr_line
		(start 388.314692 -415.09569)
		(end 388.605522 -415.38652)
		(stroke
			(width 0.07112)
			(type default)
		)
		(layer "In6.Cu")
	)
	(gr_line
		(start 388.315962 -419.579298)
		(end 388.451852 -419.715188)
		(stroke
			(width 0.07112)
			(type default)
		)
		(layer "In6.Cu")
	)
	(gr_line
		(start 388.315962 -413.750252)
		(end 388.451852 -413.886142)
		(stroke
			(width 0.07112)
			(type default)
		)
		(layer "In6.Cu")
	)
	(gr_line
		(start 388.32536 -423.857674)
		(end 388.353554 -424.04792)
		(stroke
			(width 0.07112)
			(type default)
		)
		(layer "In6.Cu")
	)
	(gr_line
		(start 388.451852 -420.141908)
		(end 388.315962 -420.277798)
		(stroke
			(width 0.07112)
			(type default)
		)
		(layer "In6.Cu")
	)
	(gr_line
		(start 388.451852 -419.715188)
		(end 388.451852 -420.141908)
		(stroke
			(width 0.07112)
			(type default)
		)
		(layer "In6.Cu")
	)
	(gr_line
		(start 388.451852 -414.312862)
		(end 388.315962 -414.448752)
		(stroke
			(width 0.07112)
			(type default)
		)
		(layer "In6.Cu")
	)
	(gr_line
		(start 388.451852 -413.886142)
		(end 388.451852 -414.312862)
		(stroke
			(width 0.07112)
			(type default)
		)
		(layer "In6.Cu")
	)
	(gr_line
		(start 388.596632 -342.304878)
		(end 388.596632 -342.30437)
		(stroke
			(width 0.07112)
			(type default)
		)
		(layer "In6.Cu")
	)
	(gr_line
		(start 388.605522 -418.412168)
		(end 388.314692 -418.702998)
		(stroke
			(width 0.07112)
			(type default)
		)
		(layer "In6.Cu")
	)
	(gr_line
		(start 388.891272 -397.156432)
		(end 388.943596 -397.208756)
		(stroke
			(width 0.07112)
			(type default)
		)
		(layer "In6.Cu")
	)
	(gr_line
		(start 388.943596 -397.388588)
		(end 388.797038 -397.535146)
		(stroke
			(width 0.07112)
			(type default)
		)
		(layer "In6.Cu")
	)
	(gr_line
		(start 388.943596 -397.208756)
		(end 388.943596 -397.388588)
		(stroke
			(width 0.07112)
			(type default)
		)
		(layer "In6.Cu")
	)
	(gr_line
		(start 389.109204 -423.06367)
		(end 389.554212 -423.605706)
		(stroke
			(width 0.07112)
			(type default)
		)
		(layer "In6.Cu")
	)
	(gr_line
		(start 389.176514 -397.734536)
		(end 388.998206 -397.734536)
		(stroke
			(width 0.07112)
			(type default)
		)
		(layer "In6.Cu")
	)
	(gr_line
		(start 389.291322 -397.849344)
		(end 389.176514 -397.734536)
		(stroke
			(width 0.07112)
			(type default)
		)
		(layer "In6.Cu")
	)
	(gr_line
		(start 389.328914 -422.884854)
		(end 389.52043 -422.90365)
		(stroke
			(width 0.07112)
			(type default)
		)
		(layer "In6.Cu")
	)
	(gr_line
		(start 389.511794 -411.24124)
		(end 390.159748 -411.509718)
		(stroke
			(width 0.07112)
			(type default)
		)
		(layer "In6.Cu")
	)
	(gr_line
		(start 389.52043 -422.90365)
		(end 389.791448 -423.23385)
		(stroke
			(width 0.07112)
			(type default)
		)
		(layer "In6.Cu")
	)
	(gr_line
		(start 389.555228 -342.224868)
		(end 389.555228 -342.22436)
		(stroke
			(width 0.07112)
			(type default)
		)
		(layer "In6.Cu")
	)
	(gr_line
		(start 389.588248 -426.569886)
		(end 389.622538 -426.569886)
		(stroke
			(width 0.07112)
			(type default)
		)
		(layer "In6.Cu")
	)
	(gr_line
		(start 389.589518 -426.853096)
		(end 389.749792 -427.01337)
		(stroke
			(width 0.07112)
			(type default)
		)
		(layer "In6.Cu")
	)
	(gr_line
		(start 389.619744 -410.980382)
		(end 389.619744 -410.980636)
		(stroke
			(width 0.07112)
			(type default)
		)
		(layer "In6.Cu")
	)
	(gr_line
		(start 389.621268 -410.980128)
		(end 389.799068 -410.906468)
		(stroke
			(width 0.07112)
			(type default)
		)
		(layer "In6.Cu")
	)
	(gr_line
		(start 389.622538 -426.569886)
		(end 389.749792 -426.442632)
		(stroke
			(width 0.07112)
			(type default)
		)
		(layer "In6.Cu")
	)
	(gr_line
		(start 389.749792 -427.01337)
		(end 389.749792 -427.289976)
		(stroke
			(width 0.07112)
			(type default)
		)
		(layer "In6.Cu")
	)
	(gr_line
		(start 389.749792 -426.442632)
		(end 389.749792 -426.089826)
		(stroke
			(width 0.07112)
			(type default)
		)
		(layer "In6.Cu")
	)
	(gr_line
		(start 389.791448 -423.23385)
		(end 389.772652 -423.425366)
		(stroke
			(width 0.07112)
			(type default)
		)
		(layer "In6.Cu")
	)
	(gr_line
		(start 389.799068 -410.906468)
		(end 390.19353 -411.06979)
		(stroke
			(width 0.07112)
			(type default)
		)
		(layer "In6.Cu")
	)
	(gr_line
		(start 389.824976 -423.935398)
		(end 390.26973 -424.477434)
		(stroke
			(width 0.07112)
			(type default)
		)
		(layer "In6.Cu")
	)
	(gr_line
		(start 390.044432 -423.756836)
		(end 390.235948 -423.775632)
		(stroke
			(width 0.07112)
			(type default)
		)
		(layer "In6.Cu")
	)
	(gr_line
		(start 390.159748 -411.509718)
		(end 390.160002 -411.509464)
		(stroke
			(width 0.07112)
			(type default)
		)
		(layer "In6.Cu")
	)
	(gr_line
		(start 390.19353 -411.06979)
		(end 390.26719 -411.24759)
		(stroke
			(width 0.07112)
			(type default)
		)
		(layer "In6.Cu")
	)
	(gr_line
		(start 390.235948 -423.775632)
		(end 390.506966 -424.105832)
		(stroke
			(width 0.07112)
			(type default)
		)
		(layer "In6.Cu")
	)
	(gr_line
		(start 390.267698 -411.249114)
		(end 390.267698 -411.24886)
		(stroke
			(width 0.07112)
			(type default)
		)
		(layer "In6.Cu")
	)
	(gr_line
		(start 390.500108 -350.204278)
		(end 390.500108 -350.204024)
		(stroke
			(width 0.07112)
			(type default)
		)
		(layer "In6.Cu")
	)
	(gr_line
		(start 390.506966 -424.105832)
		(end 390.487916 -424.297094)
		(stroke
			(width 0.07112)
			(type default)
		)
		(layer "In6.Cu")
	)
	(gr_line
		(start 390.805162 -418.412168)
		(end 391.095992 -418.702998)
		(stroke
			(width 0.07112)
			(type default)
		)
		(layer "In6.Cu")
	)
	(gr_line
		(start 391.095992 -419.61562)
		(end 391.095992 -420.31666)
		(stroke
			(width 0.07112)
			(type default)
		)
		(layer "In6.Cu")
	)
	(gr_line
		(start 391.095992 -415.09569)
		(end 390.805162 -415.38652)
		(stroke
			(width 0.07112)
			(type default)
		)
		(layer "In6.Cu")
	)
	(gr_line
		(start 391.095992 -413.616648)
		(end 391.095992 -414.317688)
		(stroke
			(width 0.07112)
			(type default)
		)
		(layer "In6.Cu")
	)
	(gr_line
		(start 391.136378 -421.531034)
		(end 391.28065 -421.879268)
		(stroke
			(width 0.07112)
			(type default)
		)
		(layer "In6.Cu")
	)
	(gr_line
		(start 391.28065 -421.879268)
		(end 391.549128 -422.52773)
		(stroke
			(width 0.07112)
			(type default)
		)
		(layer "In6.Cu")
	)
	(gr_line
		(start 391.377932 -415.09569)
		(end 391.668762 -415.38652)
		(stroke
			(width 0.07112)
			(type default)
		)
		(layer "In6.Cu")
	)
	(gr_line
		(start 391.379202 -419.61689)
		(end 391.515092 -419.75278)
		(stroke
			(width 0.07112)
			(type default)
		)
		(layer "In6.Cu")
	)
	(gr_line
		(start 391.379202 -413.617918)
		(end 391.515092 -413.753808)
		(stroke
			(width 0.07112)
			(type default)
		)
		(layer "In6.Cu")
	)
	(gr_line
		(start 391.396982 -421.423338)
		(end 391.541 -421.771572)
		(stroke
			(width 0.07112)
			(type default)
		)
		(layer "In6.Cu")
	)
	(gr_line
		(start 391.444988 -342.043004)
		(end 391.444988 -342.042496)
		(stroke
			(width 0.07112)
			(type default)
		)
		(layer "In6.Cu")
	)
	(gr_line
		(start 391.515092 -420.1795)
		(end 391.379202 -420.31539)
		(stroke
			(width 0.07112)
			(type default)
		)
		(layer "In6.Cu")
	)
	(gr_line
		(start 391.515092 -419.75278)
		(end 391.515092 -420.1795)
		(stroke
			(width 0.07112)
			(type default)
		)
		(layer "In6.Cu")
	)
	(gr_line
		(start 391.515092 -414.180528)
		(end 391.379202 -414.316418)
		(stroke
			(width 0.07112)
			(type default)
		)
		(layer "In6.Cu")
	)
	(gr_line
		(start 391.515092 -413.753808)
		(end 391.515092 -414.180528)
		(stroke
			(width 0.07112)
			(type default)
		)
		(layer "In6.Cu")
	)
	(gr_line
		(start 391.516362 -410.829506)
		(end 392.164316 -411.097984)
		(stroke
			(width 0.07112)
			(type default)
		)
		(layer "In6.Cu")
	)
	(gr_line
		(start 391.542778 -421.772334)
		(end 391.720578 -421.84574)
		(stroke
			(width 0.07112)
			(type default)
		)
		(layer "In6.Cu")
	)
	(gr_line
		(start 391.607548 -427.830742)
		(end 391.749788 -427.972982)
		(stroke
			(width 0.07112)
			(type default)
		)
		(layer "In6.Cu")
	)
	(gr_line
		(start 391.607548 -427.548802)
		(end 391.749788 -427.406562)
		(stroke
			(width 0.07112)
			(type default)
		)
		(layer "In6.Cu")
	)
	(gr_line
		(start 391.625582 -410.568394)
		(end 391.803382 -410.494734)
		(stroke
			(width 0.07112)
			(type default)
		)
		(layer "In6.Cu")
	)
	(gr_line
		(start 391.668762 -418.412168)
		(end 391.377932 -418.702998)
		(stroke
			(width 0.07112)
			(type default)
		)
		(layer "In6.Cu")
	)
	(gr_line
		(start 391.712196 -422.921176)
		(end 391.980674 -423.569638)
		(stroke
			(width 0.07112)
			(type default)
		)
		(layer "In6.Cu")
	)
	(gr_line
		(start 391.720578 -421.84574)
		(end 391.8839 -422.240202)
		(stroke
			(width 0.07112)
			(type default)
		)
		(layer "In6.Cu")
	)
	(gr_line
		(start 391.749788 -427.972982)
		(end 391.749788 -428.28972)
		(stroke
			(width 0.07112)
			(type default)
		)
		(layer "In6.Cu")
	)
	(gr_line
		(start 391.749788 -427.406562)
		(end 391.749788 -427.089824)
		(stroke
			(width 0.07112)
			(type default)
		)
		(layer "In6.Cu")
	)
	(gr_line
		(start 391.803382 -410.494734)
		(end 392.197844 -410.658056)
		(stroke
			(width 0.07112)
			(type default)
		)
		(layer "In6.Cu")
	)
	(gr_line
		(start 391.809478 -422.419526)
		(end 391.809732 -422.419526)
		(stroke
			(width 0.07112)
			(type default)
		)
		(layer "In6.Cu")
	)
	(gr_line
		(start 391.8839 -422.240202)
		(end 391.81024 -422.417748)
		(stroke
			(width 0.07112)
			(type default)
		)
		(layer "In6.Cu")
	)
	(gr_line
		(start 391.974578 -422.814496)
		(end 392.152124 -422.887902)
		(stroke
			(width 0.07112)
			(type default)
		)
		(layer "In6.Cu")
	)
	(gr_line
		(start 392.143742 -423.963338)
		(end 392.412474 -424.6118)
		(stroke
			(width 0.07112)
			(type default)
		)
		(layer "In6.Cu")
	)
	(gr_line
		(start 392.152124 -422.887902)
		(end 392.315446 -423.282364)
		(stroke
			(width 0.07112)
			(type default)
		)
		(layer "In6.Cu")
	)
	(gr_arc
		(start 392.185906 -349.122492)
		(mid 392.186032 -349.123)
		(end 392.18616 -349.123508)
		(stroke
			(width 0.07112)
			(type default)
		)
		(layer "In6.Cu")
	)
	(gr_line
		(start 392.197844 -410.658056)
		(end 392.271758 -410.835856)
		(stroke
			(width 0.07112)
			(type default)
		)
		(layer "In6.Cu")
	)
	(gr_line
		(start 392.241024 -423.461688)
		(end 392.241278 -423.461434)
		(stroke
			(width 0.07112)
			(type default)
		)
		(layer "In6.Cu")
	)
	(gr_line
		(start 392.315446 -423.282364)
		(end 392.241786 -423.45991)
		(stroke
			(width 0.07112)
			(type default)
		)
		(layer "In6.Cu")
	)
	(gr_line
		(start 392.406124 -423.856658)
		(end 392.58367 -423.930064)
		(stroke
			(width 0.07112)
			(type default)
		)
		(layer "In6.Cu")
	)
	(gr_line
		(start 392.412474 -424.6118)
		(end 392.412982 -424.613324)
		(stroke
			(width 0.07112)
			(type default)
		)
		(layer "In6.Cu")
	)
	(gr_line
		(start 392.558524 -411.261306)
		(end 393.206478 -411.529784)
		(stroke
			(width 0.07112)
			(type default)
		)
		(layer "In6.Cu")
	)
	(gr_line
		(start 392.58367 -423.930064)
		(end 392.746992 -424.324526)
		(stroke
			(width 0.07112)
			(type default)
		)
		(layer "In6.Cu")
	)
	(gr_line
		(start 392.66749 -410.99994)
		(end 392.845544 -410.92628)
		(stroke
			(width 0.07112)
			(type default)
		)
		(layer "In6.Cu")
	)
	(gr_line
		(start 392.672824 -424.50385)
		(end 392.673586 -424.505374)
		(stroke
			(width 0.07112)
			(type default)
		)
		(layer "In6.Cu")
	)
	(gr_line
		(start 392.746992 -424.324526)
		(end 392.673586 -424.502072)
		(stroke
			(width 0.07112)
			(type default)
		)
		(layer "In6.Cu")
	)
	(gr_line
		(start 392.845544 -410.92628)
		(end 393.240006 -411.089602)
		(stroke
			(width 0.07112)
			(type default)
		)
		(layer "In6.Cu")
	)
	(gr_line
		(start 393.003532 -426.68825)
		(end 393.004548 -426.689266)
		(stroke
			(width 0.07112)
			(type default)
		)
		(layer "In6.Cu")
	)
	(gr_line
		(start 393.240006 -411.089602)
		(end 393.313412 -411.267656)
		(stroke
			(width 0.07112)
			(type default)
		)
		(layer "In6.Cu")
	)
	(gr_line
		(start 393.288266 -341.496142)
		(end 393.288266 -341.495634)
		(stroke
			(width 0.07112)
			(type default)
		)
		(layer "In6.Cu")
	)
	(gr_line
		(start 393.586716 -426.849794)
		(end 393.587224 -426.849794)
		(stroke
			(width 0.07112)
			(type default)
		)
		(layer "In6.Cu")
	)
	(gr_line
		(start 393.587224 -426.849794)
		(end 393.61872 -426.849794)
		(stroke
			(width 0.07112)
			(type default)
		)
		(layer "In6.Cu")
	)
	(gr_line
		(start 393.58824 -426.567854)
		(end 393.588494 -426.567854)
		(stroke
			(width 0.07112)
			(type default)
		)
		(layer "In6.Cu")
	)
	(gr_line
		(start 393.589764 -426.566584)
		(end 393.749784 -426.406564)
		(stroke
			(width 0.07112)
			(type default)
		)
		(layer "In6.Cu")
	)
	(gr_line
		(start 393.61872 -426.849794)
		(end 393.749784 -426.980858)
		(stroke
			(width 0.07112)
			(type default)
		)
		(layer "In6.Cu")
	)
	(gr_line
		(start 393.749784 -426.980858)
		(end 393.749784 -427.289976)
		(stroke
			(width 0.07112)
			(type default)
		)
		(layer "In6.Cu")
	)
	(gr_line
		(start 393.749784 -426.406564)
		(end 393.749784 -426.089826)
		(stroke
			(width 0.07112)
			(type default)
		)
		(layer "In6.Cu")
	)
	(gr_line
		(start 393.860274 -410.56306)
		(end 394.508228 -410.831538)
		(stroke
			(width 0.07112)
			(type default)
		)
		(layer "In6.Cu")
	)
	(gr_line
		(start 393.868402 -418.412168)
		(end 394.159232 -418.702998)
		(stroke
			(width 0.07112)
			(type default)
		)
		(layer "In6.Cu")
	)
	(gr_line
		(start 393.969748 -410.301948)
		(end 394.147548 -410.228034)
		(stroke
			(width 0.07112)
			(type default)
		)
		(layer "In6.Cu")
	)
	(gr_line
		(start 394.147548 -410.228034)
		(end 394.54201 -410.391356)
		(stroke
			(width 0.07112)
			(type default)
		)
		(layer "In6.Cu")
	)
	(gr_line
		(start 394.159232 -419.72865)
		(end 394.159232 -420.42969)
		(stroke
			(width 0.07112)
			(type default)
		)
		(layer "In6.Cu")
	)
	(gr_line
		(start 394.159232 -415.09569)
		(end 393.868402 -415.38652)
		(stroke
			(width 0.07112)
			(type default)
		)
		(layer "In6.Cu")
	)
	(gr_line
		(start 394.247624 -421.79494)
		(end 394.38453 -422.482772)
		(stroke
			(width 0.07112)
			(type default)
		)
		(layer "In6.Cu")
	)
	(gr_line
		(start 394.441172 -415.09569)
		(end 394.732002 -415.38652)
		(stroke
			(width 0.07112)
			(type default)
		)
		(layer "In6.Cu")
	)
	(gr_line
		(start 394.442442 -419.72992)
		(end 394.578332 -419.86581)
		(stroke
			(width 0.07112)
			(type default)
		)
		(layer "In6.Cu")
	)
	(gr_line
		(start 394.467588 -422.90111)
		(end 394.604494 -423.589196)
		(stroke
			(width 0.07112)
			(type default)
		)
		(layer "In6.Cu")
	)
	(gr_line
		(start 394.525754 -421.741092)
		(end 394.685774 -421.848026)
		(stroke
			(width 0.07112)
			(type default)
		)
		(layer "In6.Cu")
	)
	(gr_line
		(start 394.54201 -410.391356)
		(end 394.615416 -410.56941)
		(stroke
			(width 0.07112)
			(type default)
		)
		(layer "In6.Cu")
	)
	(gr_line
		(start 394.578332 -420.29253)
		(end 394.442442 -420.42842)
		(stroke
			(width 0.07112)
			(type default)
		)
		(layer "In6.Cu")
	)
	(gr_line
		(start 394.578332 -419.86581)
		(end 394.578332 -420.29253)
		(stroke
			(width 0.07112)
			(type default)
		)
		(layer "In6.Cu")
	)
	(gr_line
		(start 394.685774 -421.848026)
		(end 394.769086 -422.266618)
		(stroke
			(width 0.07112)
			(type default)
		)
		(layer "In6.Cu")
	)
	(gr_line
		(start 394.70711 -424.105832)
		(end 394.707364 -424.105832)
		(stroke
			(width 0.07112)
			(type default)
		)
		(layer "In6.Cu")
	)
	(gr_line
		(start 394.732002 -418.412168)
		(end 394.441172 -418.702998)
		(stroke
			(width 0.07112)
			(type default)
		)
		(layer "In6.Cu")
	)
	(gr_line
		(start 394.745718 -422.847008)
		(end 394.905992 -422.954196)
		(stroke
			(width 0.07112)
			(type default)
		)
		(layer "In6.Cu")
	)
	(gr_line
		(start 394.769086 -422.266618)
		(end 394.662152 -422.426892)
		(stroke
			(width 0.07112)
			(type default)
		)
		(layer "In6.Cu")
	)
	(gr_arc
		(start 394.814552 -368.892582)
		(mid 394.814298 -368.892328)
		(end 394.814044 -368.892074)
		(stroke
			(width 0.07112)
			(type default)
		)
		(layer "In6.Cu")
	)
	(gr_line
		(start 394.905992 -422.954196)
		(end 394.989304 -423.372788)
		(stroke
			(width 0.07112)
			(type default)
		)
		(layer "In6.Cu")
	)
	(gr_line
		(start 394.989304 -423.372788)
		(end 394.882116 -423.533062)
		(stroke
			(width 0.07112)
			(type default)
		)
		(layer "In6.Cu")
	)
	(gr_line
		(start 395.227302 -341.48395)
		(end 395.227302 -341.483442)
		(stroke
			(width 0.07112)
			(type default)
		)
		(layer "In6.Cu")
	)
	(gr_line
		(start 395.588998 -348.06128)
		(end 395.589252 -348.06128)
		(stroke
			(width 0.07112)
			(type default)
		)
		(layer "In6.Cu")
	)
	(gr_line
		(start 395.60754 -427.830742)
		(end 395.74978 -427.972982)
		(stroke
			(width 0.07112)
			(type default)
		)
		(layer "In6.Cu")
	)
	(gr_line
		(start 395.60754 -427.548802)
		(end 395.74978 -427.406562)
		(stroke
			(width 0.07112)
			(type default)
		)
		(layer "In6.Cu")
	)
	(gr_line
		(start 395.67104 -403.676104)
		(end 395.783562 -403.707346)
		(stroke
			(width 0.07112)
			(type default)
		)
		(layer "In6.Cu")
	)
	(gr_line
		(start 395.674342 -411.314392)
		(end 396.322296 -411.58287)
		(stroke
			(width 0.07112)
			(type default)
		)
		(layer "In6.Cu")
	)
	(gr_line
		(start 395.747494 -403.403562)
		(end 395.915134 -403.30882)
		(stroke
			(width 0.07112)
			(type default)
		)
		(layer "In6.Cu")
	)
	(gr_line
		(start 395.74978 -427.972982)
		(end 395.74978 -428.28972)
		(stroke
			(width 0.07112)
			(type default)
		)
		(layer "In6.Cu")
	)
	(gr_line
		(start 395.74978 -427.406562)
		(end 395.74978 -427.089824)
		(stroke
			(width 0.07112)
			(type default)
		)
		(layer "In6.Cu")
	)
	(gr_line
		(start 395.783562 -411.05328)
		(end 395.961362 -410.97962)
		(stroke
			(width 0.07112)
			(type default)
		)
		(layer "In6.Cu")
	)
	(gr_line
		(start 395.783562 -403.7076)
		(end 396.346934 -403.863556)
		(stroke
			(width 0.07112)
			(type default)
		)
		(layer "In6.Cu")
	)
	(gr_line
		(start 395.783562 -403.707346)
		(end 395.783562 -403.7076)
		(stroke
			(width 0.07112)
			(type default)
		)
		(layer "In6.Cu")
	)
	(gr_line
		(start 395.849602 -347.95333)
		(end 395.849602 -347.953076)
		(stroke
			(width 0.07112)
			(type default)
		)
		(layer "In6.Cu")
	)
	(gr_line
		(start 395.915134 -403.30882)
		(end 396.326614 -403.422612)
		(stroke
			(width 0.07112)
			(type default)
		)
		(layer "In6.Cu")
	)
	(gr_line
		(start 395.961362 -410.97962)
		(end 396.355824 -411.142942)
		(stroke
			(width 0.07112)
			(type default)
		)
		(layer "In6.Cu")
	)
	(gr_arc
		(start 396.217648 -373.156226)
		(mid 396.217267 -373.155845)
		(end 396.216886 -373.155464)
		(stroke
			(width 0.07112)
			(type default)
		)
		(layer "In6.Cu")
	)
	(gr_line
		(start 396.322296 -411.58287)
		(end 396.32255 -411.58287)
		(stroke
			(width 0.07112)
			(type default)
		)
		(layer "In6.Cu")
	)
	(gr_line
		(start 396.326614 -403.422612)
		(end 396.421356 -403.590252)
		(stroke
			(width 0.07112)
			(type default)
		)
		(layer "In6.Cu")
	)
	(gr_line
		(start 396.355824 -411.142942)
		(end 396.429738 -411.320742)
		(stroke
			(width 0.07112)
			(type default)
		)
		(layer "In6.Cu")
	)
	(gr_line
		(start 396.632176 -410.409644)
		(end 397.28013 -410.678122)
		(stroke
			(width 0.07112)
			(type default)
		)
		(layer "In6.Cu")
	)
	(gr_line
		(start 396.706598 -347.462094)
		(end 396.706344 -347.461332)
		(stroke
			(width 0.07112)
			(type default)
		)
		(layer "In6.Cu")
	)
	(gr_line
		(start 396.74165 -410.148532)
		(end 396.919196 -410.074872)
		(stroke
			(width 0.07112)
			(type default)
		)
		(layer "In6.Cu")
	)
	(gr_line
		(start 396.919196 -410.074872)
		(end 397.313658 -410.238194)
		(stroke
			(width 0.07112)
			(type default)
		)
		(layer "In6.Cu")
	)
	(gr_line
		(start 396.931642 -418.412168)
		(end 397.222472 -418.702998)
		(stroke
			(width 0.07112)
			(type default)
		)
		(layer "In6.Cu")
	)
	(gr_line
		(start 397.222472 -424.593766)
		(end 397.222472 -425.294806)
		(stroke
			(width 0.07112)
			(type default)
		)
		(layer "In6.Cu")
	)
	(gr_line
		(start 397.222472 -423.466006)
		(end 397.222472 -424.167046)
		(stroke
			(width 0.07112)
			(type default)
		)
		(layer "In6.Cu")
	)
	(gr_line
		(start 397.222472 -422.338246)
		(end 397.222472 -423.039286)
		(stroke
			(width 0.07112)
			(type default)
		)
		(layer "In6.Cu")
	)
	(gr_line
		(start 397.222472 -421.210486)
		(end 397.222472 -421.911526)
		(stroke
			(width 0.07112)
			(type default)
		)
		(layer "In6.Cu")
	)
	(gr_line
		(start 397.222472 -415.09569)
		(end 396.931642 -415.38652)
		(stroke
			(width 0.07112)
			(type default)
		)
		(layer "In6.Cu")
	)
	(gr_line
		(start 397.28013 -410.678122)
		(end 397.284194 -410.679646)
		(stroke
			(width 0.07112)
			(type default)
		)
		(layer "In6.Cu")
	)
	(gr_arc
		(start 397.310864 -367.30305)
		(mid 397.31061 -367.302796)
		(end 397.310356 -367.302542)
		(stroke
			(width 0.07112)
			(type default)
		)
		(layer "In6.Cu")
	)
	(gr_line
		(start 397.313658 -410.238194)
		(end 397.387064 -410.41574)
		(stroke
			(width 0.07112)
			(type default)
		)
		(layer "In6.Cu")
	)
	(gr_line
		(start 397.387826 -410.417518)
		(end 397.392144 -410.419296)
		(stroke
			(width 0.07112)
			(type default)
		)
		(layer "In6.Cu")
	)
	(gr_arc
		(start 397.427958 -371.505988)
		(mid 397.427577 -371.505607)
		(end 397.427196 -371.505226)
		(stroke
			(width 0.07112)
			(type default)
		)
		(layer "In6.Cu")
	)
	(gr_line
		(start 397.504412 -415.09569)
		(end 397.795242 -415.38652)
		(stroke
			(width 0.07112)
			(type default)
		)
		(layer "In6.Cu")
	)
	(gr_line
		(start 397.505682 -424.595036)
		(end 397.641572 -424.730926)
		(stroke
			(width 0.07112)
			(type default)
		)
		(layer "In6.Cu")
	)
	(gr_line
		(start 397.505682 -423.467276)
		(end 397.641572 -423.603166)
		(stroke
			(width 0.07112)
			(type default)
		)
		(layer "In6.Cu")
	)
	(gr_line
		(start 397.505682 -422.339516)
		(end 397.641572 -422.475406)
		(stroke
			(width 0.07112)
			(type default)
		)
		(layer "In6.Cu")
	)
	(gr_line
		(start 397.505682 -421.211756)
		(end 397.641572 -421.347646)
		(stroke
			(width 0.07112)
			(type default)
		)
		(layer "In6.Cu")
	)
	(gr_line
		(start 397.641572 -425.157646)
		(end 397.505682 -425.293536)
		(stroke
			(width 0.07112)
			(type default)
		)
		(layer "In6.Cu")
	)
	(gr_line
		(start 397.641572 -424.730926)
		(end 397.641572 -425.157646)
		(stroke
			(width 0.07112)
			(type default)
		)
		(layer "In6.Cu")
	)
	(gr_line
		(start 397.641572 -424.029886)
		(end 397.505682 -424.165776)
		(stroke
			(width 0.07112)
			(type default)
		)
		(layer "In6.Cu")
	)
	(gr_line
		(start 397.641572 -423.603166)
		(end 397.641572 -424.029886)
		(stroke
			(width 0.07112)
			(type default)
		)
		(layer "In6.Cu")
	)
	(gr_line
		(start 397.641572 -422.902126)
		(end 397.505682 -423.038016)
		(stroke
			(width 0.07112)
			(type default)
		)
		(layer "In6.Cu")
	)
	(gr_line
		(start 397.641572 -422.475406)
		(end 397.641572 -422.902126)
		(stroke
			(width 0.07112)
			(type default)
		)
		(layer "In6.Cu")
	)
	(gr_line
		(start 397.641572 -421.774366)
		(end 397.505682 -421.910256)
		(stroke
			(width 0.07112)
			(type default)
		)
		(layer "In6.Cu")
	)
	(gr_line
		(start 397.641572 -421.347646)
		(end 397.641572 -421.774366)
		(stroke
			(width 0.07112)
			(type default)
		)
		(layer "In6.Cu")
	)
	(gr_line
		(start 397.674084 -410.84119)
		(end 398.322038 -411.109668)
		(stroke
			(width 0.07112)
			(type default)
		)
		(layer "In6.Cu")
	)
	(gr_line
		(start 397.783558 -410.580078)
		(end 397.961104 -410.506418)
		(stroke
			(width 0.07112)
			(type default)
		)
		(layer "In6.Cu")
	)
	(gr_line
		(start 397.795242 -418.412168)
		(end 397.504412 -418.702998)
		(stroke
			(width 0.07112)
			(type default)
		)
		(layer "In6.Cu")
	)
	(gr_line
		(start 397.961104 -410.506418)
		(end 398.355566 -410.66974)
		(stroke
			(width 0.07112)
			(type default)
		)
		(layer "In6.Cu")
	)
	(gr_arc
		(start 398.031208 -370.775992)
		(mid 398.030827 -370.775611)
		(end 398.030446 -370.77523)
		(stroke
			(width 0.07112)
			(type default)
		)
		(layer "In6.Cu")
	)
	(gr_line
		(start 398.107154 -366.606582)
		(end 398.1069 -366.606074)
		(stroke
			(width 0.07112)
			(type default)
		)
		(layer "In6.Cu")
	)
	(gr_line
		(start 398.355566 -410.66974)
		(end 398.428972 -410.847286)
		(stroke
			(width 0.07112)
			(type default)
		)
		(layer "In6.Cu")
	)
	(gr_line
		(start 398.429734 -410.849318)
		(end 398.429734 -410.849064)
		(stroke
			(width 0.07112)
			(type default)
		)
		(layer "In6.Cu")
	)
	(gr_line
		(start 398.429734 -410.849064)
		(end 398.429988 -410.849318)
		(stroke
			(width 0.07112)
			(type default)
		)
		(layer "In6.Cu")
	)
	(gr_line
		(start 398.429988 -410.849318)
		(end 398.429988 -410.849064)
		(stroke
			(width 0.07112)
			(type default)
		)
		(layer "In6.Cu")
	)
	(gr_line
		(start 398.607788 -426.830744)
		(end 398.750028 -426.972984)
		(stroke
			(width 0.07112)
			(type default)
		)
		(layer "In6.Cu")
	)
	(gr_line
		(start 398.607788 -426.548804)
		(end 398.750028 -426.406564)
		(stroke
			(width 0.07112)
			(type default)
		)
		(layer "In6.Cu")
	)
	(gr_line
		(start 398.68221 -377.026424)
		(end 398.681956 -377.026424)
		(stroke
			(width 0.07112)
			(type default)
		)
		(layer "In6.Cu")
	)
	(gr_line
		(start 398.716246 -411.27299)
		(end 399.363946 -411.541214)
		(stroke
			(width 0.07112)
			(type default)
		)
		(layer "In6.Cu")
	)
	(gr_line
		(start 398.750028 -426.972984)
		(end 398.750028 -427.289976)
		(stroke
			(width 0.07112)
			(type default)
		)
		(layer "In6.Cu")
	)
	(gr_line
		(start 398.750028 -426.406564)
		(end 398.750028 -426.089826)
		(stroke
			(width 0.07112)
			(type default)
		)
		(layer "In6.Cu")
	)
	(gr_line
		(start 398.82572 -411.011624)
		(end 399.003266 -410.937964)
		(stroke
			(width 0.07112)
			(type default)
		)
		(layer "In6.Cu")
	)
	(gr_line
		(start 399.003266 -410.937964)
		(end 399.397728 -411.10154)
		(stroke
			(width 0.07112)
			(type default)
		)
		(layer "In6.Cu")
	)
	(gr_line
		(start 399.363946 -411.541214)
		(end 399.3642 -411.541468)
		(stroke
			(width 0.07112)
			(type default)
		)
		(layer "In6.Cu")
	)
	(gr_line
		(start 399.397728 -411.10154)
		(end 399.471134 -411.279086)
		(stroke
			(width 0.07112)
			(type default)
		)
		(layer "In6.Cu")
	)
	(gr_line
		(start 399.734532 -410.473398)
		(end 400.389598 -410.723842)
		(stroke
			(width 0.07112)
			(type default)
		)
		(layer "In6.Cu")
	)
	(gr_line
		(start 399.83664 -410.209238)
		(end 400.012154 -410.130752)
		(stroke
			(width 0.07112)
			(type default)
		)
		(layer "In6.Cu")
	)
	(gr_line
		(start 399.884138 -424.272964)
		(end 399.809716 -425.029884)
		(stroke
			(width 0.07112)
			(type default)
		)
		(layer "In6.Cu")
	)
	(gr_line
		(start 399.952718 -423.574718)
		(end 399.884138 -424.272964)
		(stroke
			(width 0.07112)
			(type default)
		)
		(layer "In6.Cu")
	)
	(gr_line
		(start 399.994882 -418.412168)
		(end 400.285712 -418.702998)
		(stroke
			(width 0.07112)
			(type default)
		)
		(layer "In6.Cu")
	)
	(gr_line
		(start 400.012154 -410.130752)
		(end 400.411188 -410.282898)
		(stroke
			(width 0.07112)
			(type default)
		)
		(layer "In6.Cu")
	)
	(gr_line
		(start 400.062954 -422.452546)
		(end 399.994374 -423.150284)
		(stroke
			(width 0.07112)
			(type default)
		)
		(layer "In6.Cu")
	)
	(gr_line
		(start 400.111468 -368.65052)
		(end 400.11096 -368.650012)
		(stroke
			(width 0.07112)
			(type default)
		)
		(layer "In6.Cu")
	)
	(gr_line
		(start 400.164554 -424.300396)
		(end 400.090386 -425.057316)
		(stroke
			(width 0.07112)
			(type default)
		)
		(layer "In6.Cu")
	)
	(gr_line
		(start 400.234404 -423.60342)
		(end 400.356578 -423.752264)
		(stroke
			(width 0.07112)
			(type default)
		)
		(layer "In6.Cu")
	)
	(gr_line
		(start 400.285712 -419.690042)
		(end 400.285712 -420.391082)
		(stroke
			(width 0.07112)
			(type default)
		)
		(layer "In6.Cu")
	)
	(gr_line
		(start 400.285712 -415.09569)
		(end 399.994882 -415.38652)
		(stroke
			(width 0.07112)
			(type default)
		)
		(layer "In6.Cu")
	)
	(gr_line
		(start 400.314922 -424.177206)
		(end 400.166078 -424.299126)
		(stroke
			(width 0.07112)
			(type default)
		)
		(layer "In6.Cu")
	)
	(gr_line
		(start 400.32432 -374.338342)
		(end 400.32432 -374.338088)
		(stroke
			(width 0.07112)
			(type default)
		)
		(layer "In6.Cu")
	)
	(gr_line
		(start 400.344894 -422.480994)
		(end 400.467068 -422.629838)
		(stroke
			(width 0.07112)
			(type default)
		)
		(layer "In6.Cu")
	)
	(gr_line
		(start 400.356578 -423.752264)
		(end 400.314922 -424.177206)
		(stroke
			(width 0.07112)
			(type default)
		)
		(layer "In6.Cu")
	)
	(gr_line
		(start 400.411188 -410.282898)
		(end 400.48942 -410.45892)
		(stroke
			(width 0.07112)
			(type default)
		)
		(layer "In6.Cu")
	)
	(gr_line
		(start 400.425412 -423.05478)
		(end 400.276314 -423.176954)
		(stroke
			(width 0.07112)
			(type default)
		)
		(layer "In6.Cu")
	)
	(gr_line
		(start 400.463258 -374.092978)
		(end 400.463258 -374.09247)
		(stroke
			(width 0.07112)
			(type default)
		)
		(layer "In6.Cu")
	)
	(gr_line
		(start 400.467068 -422.629838)
		(end 400.425412 -423.05478)
		(stroke
			(width 0.07112)
			(type default)
		)
		(layer "In6.Cu")
	)
	(gr_line
		(start 400.567652 -415.09569)
		(end 400.858482 -415.38652)
		(stroke
			(width 0.07112)
			(type default)
		)
		(layer "In6.Cu")
	)
	(gr_line
		(start 400.568922 -419.691312)
		(end 400.704812 -419.827202)
		(stroke
			(width 0.07112)
			(type default)
		)
		(layer "In6.Cu")
	)
	(gr_line
		(start 400.607784 -427.830742)
		(end 400.750024 -427.972982)
		(stroke
			(width 0.07112)
			(type default)
		)
		(layer "In6.Cu")
	)
	(gr_line
		(start 400.607784 -427.548802)
		(end 400.750024 -427.406562)
		(stroke
			(width 0.07112)
			(type default)
		)
		(layer "In6.Cu")
	)
	(gr_line
		(start 400.631406 -379.605794)
		(end 400.631406 -379.58395)
		(stroke
			(width 0.07112)
			(type default)
		)
		(layer "In6.Cu")
	)
	(gr_line
		(start 400.634454 -379.626368)
		(end 400.631406 -379.605794)
		(stroke
			(width 0.07112)
			(type default)
		)
		(layer "In6.Cu")
	)
	(gr_line
		(start 400.64944 -379.724666)
		(end 400.649694 -379.724666)
		(stroke
			(width 0.07112)
			(type default)
		)
		(layer "In6.Cu")
	)
	(gr_line
		(start 400.649694 -379.724666)
		(end 400.647916 -379.712728)
		(stroke
			(width 0.07112)
			(type default)
		)
		(layer "In6.Cu")
	)
	(gr_line
		(start 400.65198 -379.73508)
		(end 400.64944 -379.724666)
		(stroke
			(width 0.07112)
			(type default)
		)
		(layer "In6.Cu")
	)
	(gr_line
		(start 400.704812 -420.253922)
		(end 400.568922 -420.389812)
		(stroke
			(width 0.07112)
			(type default)
		)
		(layer "In6.Cu")
	)
	(gr_line
		(start 400.704812 -419.827202)
		(end 400.704812 -420.253922)
		(stroke
			(width 0.07112)
			(type default)
		)
		(layer "In6.Cu")
	)
	(gr_line
		(start 400.750024 -427.972982)
		(end 400.750024 -428.28972)
		(stroke
			(width 0.07112)
			(type default)
		)
		(layer "In6.Cu")
	)
	(gr_line
		(start 400.750024 -427.406562)
		(end 400.750024 -427.089824)
		(stroke
			(width 0.07112)
			(type default)
		)
		(layer "In6.Cu")
	)
	(gr_line
		(start 400.788124 -410.876242)
		(end 401.44319 -411.126686)
		(stroke
			(width 0.07112)
			(type default)
		)
		(layer "In6.Cu")
	)
	(gr_line
		(start 400.799046 -364.83671)
		(end 400.799046 -364.836456)
		(stroke
			(width 0.07112)
			(type default)
		)
		(layer "In6.Cu")
	)
	(gr_line
		(start 400.858482 -418.412168)
		(end 400.567652 -418.702998)
		(stroke
			(width 0.07112)
			(type default)
		)
		(layer "In6.Cu")
	)
	(gr_line
		(start 400.889978 -410.612082)
		(end 401.065746 -410.533342)
		(stroke
			(width 0.07112)
			(type default)
		)
		(layer "In6.Cu")
	)
	(gr_line
		(start 400.913346 -379.583696)
		(end 400.913346 -379.58395)
		(stroke
			(width 0.07112)
			(type default)
		)
		(layer "In6.Cu")
	)
	(gr_line
		(start 400.985228 -381.73406)
		(end 401.08632 -381.57023)
		(stroke
			(width 0.07112)
			(type default)
		)
		(layer "In6.Cu")
	)
	(gr_line
		(start 401.065746 -410.533342)
		(end 401.46478 -410.685742)
		(stroke
			(width 0.07112)
			(type default)
		)
		(layer "In6.Cu")
	)
	(gr_line
		(start 401.08378 -382.149604)
		(end 400.985228 -381.73406)
		(stroke
			(width 0.07112)
			(type default)
		)
		(layer "In6.Cu")
	)
	(gr_line
		(start 401.24761 -382.250442)
		(end 401.08378 -382.149604)
		(stroke
			(width 0.07112)
			(type default)
		)
		(layer "In6.Cu")
	)
	(gr_line
		(start 401.442682 -367.259108)
		(end 401.442174 -367.258854)
		(stroke
			(width 0.07112)
			(type default)
		)
		(layer "In6.Cu")
	)
	(gr_line
		(start 401.46478 -410.685742)
		(end 401.543012 -410.861764)
		(stroke
			(width 0.07112)
			(type default)
		)
		(layer "In6.Cu")
	)
	(gr_line
		(start 401.523454 -382.186434)
		(end 401.361656 -381.503936)
		(stroke
			(width 0.07112)
			(type default)
		)
		(layer "In6.Cu")
	)
	(gr_line
		(start 401.53463 -407.685494)
		(end 402.19503 -407.921714)
		(stroke
			(width 0.07112)
			(type default)
		)
		(layer "In6.Cu")
	)
	(gr_arc
		(start 401.555458 -366.993424)
		(mid 401.555204 -366.99317)
		(end 401.55495 -366.992916)
		(stroke
			(width 0.07112)
			(type default)
		)
		(layer "In6.Cu")
	)
	(gr_line
		(start 401.630642 -407.419048)
		(end 401.80514 -407.336752)
		(stroke
			(width 0.07112)
			(type default)
		)
		(layer "In6.Cu")
	)
	(gr_line
		(start 401.676362 -375.94794)
		(end 401.676108 -375.94794)
		(stroke
			(width 0.07112)
			(type default)
		)
		(layer "In6.Cu")
	)
	(gr_line
		(start 401.80514 -407.336752)
		(end 402.206968 -407.480516)
		(stroke
			(width 0.07112)
			(type default)
		)
		(layer "In6.Cu")
	)
	(gr_line
		(start 401.841716 -411.279086)
		(end 402.496782 -411.52953)
		(stroke
			(width 0.07112)
			(type default)
		)
		(layer "In6.Cu")
	)
	(gr_line
		(start 401.94357 -411.014926)
		(end 402.119338 -410.93644)
		(stroke
			(width 0.07112)
			(type default)
		)
		(layer "In6.Cu")
	)
	(gr_line
		(start 401.998942 -426.097954)
		(end 401.999196 -426.0977)
		(stroke
			(width 0.07112)
			(type default)
		)
		(layer "In6.Cu")
	)
	(gr_line
		(start 402.007832 -405.430228)
		(end 402.68398 -405.617172)
		(stroke
			(width 0.07112)
			(type default)
		)
		(layer "In6.Cu")
	)
	(gr_line
		(start 402.084286 -405.157432)
		(end 402.251672 -405.062436)
		(stroke
			(width 0.07112)
			(type default)
		)
		(layer "In6.Cu")
	)
	(gr_line
		(start 402.119338 -410.93644)
		(end 402.518118 -411.08884)
		(stroke
			(width 0.07112)
			(type default)
		)
		(layer "In6.Cu")
	)
	(gr_line
		(start 402.184108 -388.947914)
		(end 402.20138 -388.756398)
		(stroke
			(width 0.07112)
			(type default)
		)
		(layer "In6.Cu")
	)
	(gr_line
		(start 402.19503 -407.921714)
		(end 402.194776 -407.922222)
		(stroke
			(width 0.07112)
			(type default)
		)
		(layer "In6.Cu")
	)
	(gr_line
		(start 402.204174 -381.57658)
		(end 402.204174 -381.14986)
		(stroke
			(width 0.07112)
			(type default)
		)
		(layer "In6.Cu")
	)
	(gr_line
		(start 402.204174 -381.14986)
		(end 402.340064 -381.01397)
		(stroke
			(width 0.07112)
			(type default)
		)
		(layer "In6.Cu")
	)
	(gr_line
		(start 402.204174 -380.44882)
		(end 402.204174 -380.0221)
		(stroke
			(width 0.07112)
			(type default)
		)
		(layer "In6.Cu")
	)
	(gr_line
		(start 402.204174 -380.0221)
		(end 402.340064 -379.88621)
		(stroke
			(width 0.07112)
			(type default)
		)
		(layer "In6.Cu")
	)
	(gr_line
		(start 402.204174 -379.32106)
		(end 402.204174 -378.89434)
		(stroke
			(width 0.07112)
			(type default)
		)
		(layer "In6.Cu")
	)
	(gr_line
		(start 402.204174 -378.89434)
		(end 402.340064 -378.75845)
		(stroke
			(width 0.07112)
			(type default)
		)
		(layer "In6.Cu")
	)
	(gr_line
		(start 402.206968 -407.480516)
		(end 402.289264 -407.65476)
		(stroke
			(width 0.07112)
			(type default)
		)
		(layer "In6.Cu")
	)
	(gr_arc
		(start 402.223986 -365.340138)
		(mid 402.275021 -365.384936)
		(end 402.328126 -365.42726)
		(stroke
			(width 0.07112)
			(type default)
		)
		(layer "In6.Cu")
	)
	(gr_line
		(start 402.229066 -423.575988)
		(end 401.929092 -424.209972)
		(stroke
			(width 0.07112)
			(type default)
		)
		(layer "In6.Cu")
	)
	(gr_line
		(start 402.251672 -405.062436)
		(end 402.663406 -405.176228)
		(stroke
			(width 0.07112)
			(type default)
		)
		(layer "In6.Cu")
	)
	(gr_arc
		(start 402.328126 -365.42726)
		(mid 402.387641 -365.470219)
		(end 402.449284 -365.510064)
		(stroke
			(width 0.07112)
			(type default)
		)
		(layer "In6.Cu")
	)
	(gr_line
		(start 402.340064 -381.71247)
		(end 402.204174 -381.57658)
		(stroke
			(width 0.07112)
			(type default)
		)
		(layer "In6.Cu")
	)
	(gr_line
		(start 402.340064 -380.58471)
		(end 402.204174 -380.44882)
		(stroke
			(width 0.07112)
			(type default)
		)
		(layer "In6.Cu")
	)
	(gr_line
		(start 402.340064 -379.45695)
		(end 402.204174 -379.32106)
		(stroke
			(width 0.07112)
			(type default)
		)
		(layer "In6.Cu")
	)
	(gr_arc
		(start 402.341334 -382.530604)
		(mid 402.341481 -382.538481)
		(end 402.341842 -382.546352)
		(stroke
			(width 0.07112)
			(type default)
		)
		(layer "In6.Cu")
	)
	(gr_line
		(start 402.366988 -424.265344)
		(end 402.185632 -424.330114)
		(stroke
			(width 0.07112)
			(type default)
		)
		(layer "In6.Cu")
	)
	(gr_arc
		(start 402.40585 -426.847762)
		(mid 402.405596 -426.847762)
		(end 402.405342 -426.847762)
		(stroke
			(width 0.07112)
			(type default)
		)
		(layer "In6.Cu")
	)
	(gr_line
		(start 402.439378 -384.989324)
		(end 402.485606 -384.80238)
		(stroke
			(width 0.07112)
			(type default)
		)
		(layer "In6.Cu")
	)
	(gr_line
		(start 402.45792 -389.275574)
		(end 402.184108 -388.947914)
		(stroke
			(width 0.07112)
			(type default)
		)
		(layer "In6.Cu")
	)
	(gr_line
		(start 402.48459 -423.698162)
		(end 402.54936 -423.879264)
		(stroke
			(width 0.07112)
			(type default)
		)
		(layer "In6.Cu")
	)
	(gr_line
		(start 402.518118 -411.08884)
		(end 402.596604 -411.264608)
		(stroke
			(width 0.07112)
			(type default)
		)
		(layer "In6.Cu")
	)
	(gr_line
		(start 402.54936 -423.879264)
		(end 402.366988 -424.265344)
		(stroke
			(width 0.07112)
			(type default)
		)
		(layer "In6.Cu")
	)
	(gr_line
		(start 402.590762 -426.847762)
		(end 402.614892 -426.847762)
		(stroke
			(width 0.07112)
			(type default)
		)
		(layer "In6.Cu")
	)
	(gr_line
		(start 402.592032 -426.564552)
		(end 402.75002 -426.406564)
		(stroke
			(width 0.07112)
			(type default)
		)
		(layer "In6.Cu")
	)
	(gr_line
		(start 402.614892 -426.847762)
		(end 402.75002 -426.98289)
		(stroke
			(width 0.07112)
			(type default)
		)
		(layer "In6.Cu")
	)
	(gr_line
		(start 402.623274 -381.71374)
		(end 402.623274 -381.0127)
		(stroke
			(width 0.07112)
			(type default)
		)
		(layer "In6.Cu")
	)
	(gr_line
		(start 402.623274 -380.58598)
		(end 402.623274 -379.88494)
		(stroke
			(width 0.07112)
			(type default)
		)
		(layer "In6.Cu")
	)
	(gr_line
		(start 402.623274 -379.45822)
		(end 402.623274 -378.75718)
		(stroke
			(width 0.07112)
			(type default)
		)
		(layer "In6.Cu")
	)
	(gr_line
		(start 402.64969 -389.292592)
		(end 402.45792 -389.275574)
		(stroke
			(width 0.07112)
			(type default)
		)
		(layer "In6.Cu")
	)
	(gr_line
		(start 402.65985 -385.355084)
		(end 402.439378 -384.989324)
		(stroke
			(width 0.07112)
			(type default)
		)
		(layer "In6.Cu")
	)
	(gr_line
		(start 402.663406 -405.176228)
		(end 402.758148 -405.343868)
		(stroke
			(width 0.07112)
			(type default)
		)
		(layer "In6.Cu")
	)
	(gr_line
		(start 402.711412 -422.556432)
		(end 402.411438 -423.190416)
		(stroke
			(width 0.07112)
			(type default)
		)
		(layer "In6.Cu")
	)
	(gr_line
		(start 402.75002 -426.98289)
		(end 402.75002 -427.289976)
		(stroke
			(width 0.07112)
			(type default)
		)
		(layer "In6.Cu")
	)
	(gr_line
		(start 402.75002 -426.406564)
		(end 402.75002 -426.089826)
		(stroke
			(width 0.07112)
			(type default)
		)
		(layer "In6.Cu")
	)
	(gr_line
		(start 402.75891 -405.345392)
		(end 402.759164 -405.345392)
		(stroke
			(width 0.07112)
			(type default)
		)
		(layer "In6.Cu")
	)
	(gr_line
		(start 402.846794 -385.401312)
		(end 402.65985 -385.355084)
		(stroke
			(width 0.07112)
			(type default)
		)
		(layer "In6.Cu")
	)
	(gr_line
		(start 402.84908 -423.245788)
		(end 402.667978 -423.310558)
		(stroke
			(width 0.07112)
			(type default)
		)
		(layer "In6.Cu")
	)
	(gr_line
		(start 402.867622 -389.111998)
		(end 402.418042 -388.573772)
		(stroke
			(width 0.07112)
			(type default)
		)
		(layer "In6.Cu")
	)
	(gr_arc
		(start 402.891244 -364.650528)
		(mid 402.890863 -364.650147)
		(end 402.890482 -364.649766)
		(stroke
			(width 0.07112)
			(type default)
		)
		(layer "In6.Cu")
	)
	(gr_line
		(start 402.899118 -387.99389)
		(end 402.918422 -387.802882)
		(stroke
			(width 0.07112)
			(type default)
		)
		(layer "In6.Cu")
	)
	(gr_line
		(start 402.9075 -389.813292)
		(end 402.924518 -389.621776)
		(stroke
			(width 0.07112)
			(type default)
		)
		(layer "In6.Cu")
	)
	(gr_line
		(start 402.918676 -387.80085)
		(end 402.918168 -387.80085)
		(stroke
			(width 0.07112)
			(type default)
		)
		(layer "In6.Cu")
	)
	(gr_line
		(start 402.966682 -422.67886)
		(end 403.031452 -422.859708)
		(stroke
			(width 0.07112)
			(type default)
		)
		(layer "In6.Cu")
	)
	(gr_line
		(start 403.022054 -385.955032)
		(end 403.068536 -385.768342)
		(stroke
			(width 0.07112)
			(type default)
		)
		(layer "In6.Cu")
	)
	(gr_line
		(start 403.031452 -422.859708)
		(end 402.84908 -423.245788)
		(stroke
			(width 0.07112)
			(type default)
		)
		(layer "In6.Cu")
	)
	(gr_line
		(start 403.058122 -418.412168)
		(end 403.348952 -418.702998)
		(stroke
			(width 0.07112)
			(type default)
		)
		(layer "In6.Cu")
	)
	(gr_line
		(start 403.089872 -385.25577)
		(end 402.727414 -384.655314)
		(stroke
			(width 0.07112)
			(type default)
		)
		(layer "In6.Cu")
	)
	(gr_line
		(start 403.090126 -364.45063)
		(end 403.090126 -364.450376)
		(stroke
			(width 0.07112)
			(type default)
		)
		(layer "In6.Cu")
	)
	(gr_line
		(start 403.16912 -388.324852)
		(end 402.899118 -387.99389)
		(stroke
			(width 0.07112)
			(type default)
		)
		(layer "In6.Cu")
	)
	(gr_line
		(start 403.181312 -390.140952)
		(end 402.9075 -389.813292)
		(stroke
			(width 0.07112)
			(type default)
		)
		(layer "In6.Cu")
	)
	(gr_line
		(start 403.182074 -407.06548)
		(end 403.853396 -407.269188)
		(stroke
			(width 0.07112)
			(type default)
		)
		(layer "In6.Cu")
	)
	(gr_line
		(start 403.193504 -421.536876)
		(end 402.893784 -422.17086)
		(stroke
			(width 0.07112)
			(type default)
		)
		(layer "In6.Cu")
	)
	(gr_line
		(start 403.242526 -386.320792)
		(end 403.022054 -385.955032)
		(stroke
			(width 0.07112)
			(type default)
		)
		(layer "In6.Cu")
	)
	(gr_line
		(start 403.265132 -406.794716)
		(end 403.435058 -406.704038)
		(stroke
			(width 0.07112)
			(type default)
		)
		(layer "In6.Cu")
	)
	(gr_line
		(start 403.331426 -422.226232)
		(end 403.150324 -422.291002)
		(stroke
			(width 0.07112)
			(type default)
		)
		(layer "In6.Cu")
	)
	(gr_line
		(start 403.348952 -419.502082)
		(end 403.348952 -420.203122)
		(stroke
			(width 0.07112)
			(type default)
		)
		(layer "In6.Cu")
	)
	(gr_line
		(start 403.348952 -415.09569)
		(end 403.058122 -415.38652)
		(stroke
			(width 0.07112)
			(type default)
		)
		(layer "In6.Cu")
	)
	(gr_line
		(start 403.360128 -388.344156)
		(end 403.16912 -388.324852)
		(stroke
			(width 0.07112)
			(type default)
		)
		(layer "In6.Cu")
	)
	(gr_line
		(start 403.361652 -388.34441)
		(end 403.361906 -388.34441)
		(stroke
			(width 0.07112)
			(type default)
		)
		(layer "In6.Cu")
	)
	(gr_line
		(start 403.372828 -390.15797)
		(end 403.181312 -390.140952)
		(stroke
			(width 0.07112)
			(type default)
		)
		(layer "In6.Cu")
	)
	(gr_line
		(start 403.419056 -393.69238)
		(end 403.77237 -393.787376)
		(stroke
			(width 0.07112)
			(type default)
		)
		(layer "In6.Cu")
	)
	(gr_line
		(start 403.429724 -386.366766)
		(end 403.242526 -386.320792)
		(stroke
			(width 0.07112)
			(type default)
		)
		(layer "In6.Cu")
	)
	(gr_line
		(start 403.435058 -406.704038)
		(end 403.843744 -406.827736)
		(stroke
			(width 0.07112)
			(type default)
		)
		(layer "In6.Cu")
	)
	(gr_line
		(start 403.449028 -421.65905)
		(end 403.513798 -421.840152)
		(stroke
			(width 0.07112)
			(type default)
		)
		(layer "In6.Cu")
	)
	(gr_arc
		(start 403.459696 -363.894624)
		(mid 403.459315 -363.894243)
		(end 403.458934 -363.893862)
		(stroke
			(width 0.07112)
			(type default)
		)
		(layer "In6.Cu")
	)
	(gr_line
		(start 403.513798 -421.840152)
		(end 403.331426 -422.226232)
		(stroke
			(width 0.07112)
			(type default)
		)
		(layer "In6.Cu")
	)
	(gr_line
		(start 403.580092 -388.166102)
		(end 403.136862 -387.622542)
		(stroke
			(width 0.07112)
			(type default)
		)
		(layer "In6.Cu")
	)
	(gr_line
		(start 403.591014 -389.977376)
		(end 403.14118 -389.439404)
		(stroke
			(width 0.07112)
			(type default)
		)
		(layer "In6.Cu")
	)
	(gr_line
		(start 403.612096 -388.867904)
		(end 403.6314 -388.676896)
		(stroke
			(width 0.07112)
			(type default)
		)
		(layer "In6.Cu")
	)
	(gr_line
		(start 403.630892 -415.09569)
		(end 403.921722 -415.38652)
		(stroke
			(width 0.07112)
			(type default)
		)
		(layer "In6.Cu")
	)
	(gr_line
		(start 403.632162 -419.503352)
		(end 403.768052 -419.639242)
		(stroke
			(width 0.07112)
			(type default)
		)
		(layer "In6.Cu")
	)
	(gr_line
		(start 403.633432 -410.729176)
		(end 404.281132 -410.998162)
		(stroke
			(width 0.07112)
			(type default)
		)
		(layer "In6.Cu")
	)
	(gr_line
		(start 403.658578 -363.694726)
		(end 403.658578 -363.694472)
		(stroke
			(width 0.07112)
			(type default)
		)
		(layer "In6.Cu")
	)
	(gr_line
		(start 403.672802 -386.221732)
		(end 403.310344 -385.621022)
		(stroke
			(width 0.07112)
			(type default)
		)
		(layer "In6.Cu")
	)
	(gr_line
		(start 403.742906 -410.468064)
		(end 403.92096 -410.394658)
		(stroke
			(width 0.07112)
			(type default)
		)
		(layer "In6.Cu")
	)
	(gr_line
		(start 403.768052 -420.065962)
		(end 403.632162 -420.201852)
		(stroke
			(width 0.07112)
			(type default)
		)
		(layer "In6.Cu")
	)
	(gr_line
		(start 403.768052 -419.639242)
		(end 403.768052 -420.065962)
		(stroke
			(width 0.07112)
			(type default)
		)
		(layer "In6.Cu")
	)
	(gr_line
		(start 403.77237 -393.787376)
		(end 403.772878 -393.786868)
		(stroke
			(width 0.07112)
			(type default)
		)
		(layer "In6.Cu")
	)
	(gr_line
		(start 403.819106 -394.385292)
		(end 403.913848 -394.031724)
		(stroke
			(width 0.07112)
			(type default)
		)
		(layer "In6.Cu")
	)
	(gr_line
		(start 403.843744 -406.827736)
		(end 403.934422 -406.997662)
		(stroke
			(width 0.07112)
			(type default)
		)
		(layer "In6.Cu")
	)
	(gr_line
		(start 403.882098 -389.198866)
		(end 403.612096 -388.867904)
		(stroke
			(width 0.07112)
			(type default)
		)
		(layer "In6.Cu")
	)
	(gr_line
		(start 403.92096 -410.394658)
		(end 404.315168 -410.558234)
		(stroke
			(width 0.07112)
			(type default)
		)
		(layer "In6.Cu")
	)
	(gr_line
		(start 403.921722 -418.412168)
		(end 403.630892 -418.702998)
		(stroke
			(width 0.07112)
			(type default)
		)
		(layer "In6.Cu")
	)
	(gr_line
		(start 404.035514 -393.961112)
		(end 404.088346 -393.930632)
		(stroke
			(width 0.07112)
			(type default)
		)
		(layer "In6.Cu")
	)
	(gr_line
		(start 404.073106 -389.21817)
		(end 403.882098 -389.198866)
		(stroke
			(width 0.07112)
			(type default)
		)
		(layer "In6.Cu")
	)
	(gr_line
		(start 404.07463 -389.218424)
		(end 404.074884 -389.218424)
		(stroke
			(width 0.07112)
			(type default)
		)
		(layer "In6.Cu")
	)
	(gr_line
		(start 404.088346 -393.930632)
		(end 404.176484 -393.842494)
		(stroke
			(width 0.07112)
			(type default)
		)
		(layer "In6.Cu")
	)
	(gr_line
		(start 404.176484 -393.842494)
		(end 404.176484 -393.716764)
		(stroke
			(width 0.07112)
			(type default)
		)
		(layer "In6.Cu")
	)
	(gr_line
		(start 404.293324 -389.039862)
		(end 403.850094 -388.49681)
		(stroke
			(width 0.07112)
			(type default)
		)
		(layer "In6.Cu")
	)
	(gr_line
		(start 404.315168 -410.558234)
		(end 404.388574 -410.736034)
		(stroke
			(width 0.07112)
			(type default)
		)
		(layer "In6.Cu")
	)
	(gr_line
		(start 404.325074 -389.741918)
		(end 404.344378 -389.550656)
		(stroke
			(width 0.07112)
			(type default)
		)
		(layer "In6.Cu")
	)
	(gr_line
		(start 404.595076 -390.07288)
		(end 404.325074 -389.741918)
		(stroke
			(width 0.07112)
			(type default)
		)
		(layer "In6.Cu")
	)
	(gr_line
		(start 404.607776 -427.830742)
		(end 404.750016 -427.972982)
		(stroke
			(width 0.07112)
			(type default)
		)
		(layer "In6.Cu")
	)
	(gr_line
		(start 404.607776 -427.548802)
		(end 404.750016 -427.406562)
		(stroke
			(width 0.07112)
			(type default)
		)
		(layer "In6.Cu")
	)
	(gr_line
		(start 404.618952 -393.69238)
		(end 404.972266 -393.787376)
		(stroke
			(width 0.07112)
			(type default)
		)
		(layer "In6.Cu")
	)
	(gr_line
		(start 404.66264 -423.855642)
		(end 404.470616 -423.855642)
		(stroke
			(width 0.07112)
			(type default)
		)
		(layer "In6.Cu")
	)
	(gr_line
		(start 404.743412 -406.187148)
		(end 405.419306 -406.374092)
		(stroke
			(width 0.07112)
			(type default)
		)
		(layer "In6.Cu")
	)
	(gr_line
		(start 404.750016 -427.972982)
		(end 404.750016 -428.28972)
		(stroke
			(width 0.07112)
			(type default)
		)
		(layer "In6.Cu")
	)
	(gr_line
		(start 404.750016 -427.406562)
		(end 404.750016 -427.089824)
		(stroke
			(width 0.07112)
			(type default)
		)
		(layer "In6.Cu")
	)
	(gr_line
		(start 404.765256 -423.160444)
		(end 404.269448 -423.656252)
		(stroke
			(width 0.07112)
			(type default)
		)
		(layer "In6.Cu")
	)
	(gr_line
		(start 404.786338 -390.092184)
		(end 404.595076 -390.07288)
		(stroke
			(width 0.07112)
			(type default)
		)
		(layer "In6.Cu")
	)
	(gr_line
		(start 404.82012 -405.914606)
		(end 404.987252 -405.81961)
		(stroke
			(width 0.07112)
			(type default)
		)
		(layer "In6.Cu")
	)
	(gr_line
		(start 404.964646 -423.553636)
		(end 404.66264 -423.855642)
		(stroke
			(width 0.07112)
			(type default)
		)
		(layer "In6.Cu")
	)
	(gr_line
		(start 404.964646 -423.361612)
		(end 404.964646 -423.553636)
		(stroke
			(width 0.07112)
			(type default)
		)
		(layer "In6.Cu")
	)
	(gr_line
		(start 404.972266 -393.787376)
		(end 404.972774 -393.786868)
		(stroke
			(width 0.07112)
			(type default)
		)
		(layer "In6.Cu")
	)
	(gr_line
		(start 404.987252 -405.81961)
		(end 405.398732 -405.933402)
		(stroke
			(width 0.07112)
			(type default)
		)
		(layer "In6.Cu")
	)
	(gr_line
		(start 405.006302 -389.91413)
		(end 404.563072 -389.370824)
		(stroke
			(width 0.07112)
			(type default)
		)
		(layer "In6.Cu")
	)
	(gr_line
		(start 405.019002 -394.385292)
		(end 405.113744 -394.031724)
		(stroke
			(width 0.07112)
			(type default)
		)
		(layer "In6.Cu")
	)
	(gr_line
		(start 405.23541 -393.961112)
		(end 405.288242 -393.930632)
		(stroke
			(width 0.07112)
			(type default)
		)
		(layer "In6.Cu")
	)
	(gr_line
		(start 405.288242 -393.930632)
		(end 405.37638 -393.842494)
		(stroke
			(width 0.07112)
			(type default)
		)
		(layer "In6.Cu")
	)
	(gr_line
		(start 405.37638 -393.842494)
		(end 405.37638 -393.716764)
		(stroke
			(width 0.07112)
			(type default)
		)
		(layer "In6.Cu")
	)
	(gr_line
		(start 405.398732 -405.933402)
		(end 405.493474 -406.101042)
		(stroke
			(width 0.07112)
			(type default)
		)
		(layer "In6.Cu")
	)
	(gr_line
		(start 405.4602 -423.058336)
		(end 405.267922 -423.058336)
		(stroke
			(width 0.07112)
			(type default)
		)
		(layer "In6.Cu")
	)
	(gr_line
		(start 405.49449 -406.102566)
		(end 405.49449 -406.102312)
		(stroke
			(width 0.07112)
			(type default)
		)
		(layer "In6.Cu")
	)
	(gr_line
		(start 405.562816 -422.362884)
		(end 405.066754 -422.858946)
		(stroke
			(width 0.07112)
			(type default)
		)
		(layer "In6.Cu")
	)
	(gr_line
		(start 405.612092 -409.14447)
		(end 406.272746 -409.38069)
		(stroke
			(width 0.07112)
			(type default)
		)
		(layer "In6.Cu")
	)
	(gr_line
		(start 405.708358 -408.878024)
		(end 405.882602 -408.795728)
		(stroke
			(width 0.07112)
			(type default)
		)
		(layer "In6.Cu")
	)
	(gr_line
		(start 405.730202 -410.378402)
		(end 406.350216 -410.635196)
		(stroke
			(width 0.07112)
			(type default)
		)
		(layer "In6.Cu")
	)
	(gr_arc
		(start 405.735028 -381.26543)
		(mid 405.735282 -381.265684)
		(end 405.735536 -381.265938)
		(stroke
			(width 0.07112)
			(type default)
		)
		(layer "In6.Cu")
	)
	(gr_line
		(start 405.762206 -422.75633)
		(end 405.4602 -423.058336)
		(stroke
			(width 0.07112)
			(type default)
		)
		(layer "In6.Cu")
	)
	(gr_line
		(start 405.762206 -422.564052)
		(end 405.762206 -422.75633)
		(stroke
			(width 0.07112)
			(type default)
		)
		(layer "In6.Cu")
	)
	(gr_line
		(start 405.819102 -393.69238)
		(end 406.172162 -393.787376)
		(stroke
			(width 0.07112)
			(type default)
		)
		(layer "In6.Cu")
	)
	(gr_line
		(start 405.839422 -410.116782)
		(end 405.997664 -410.051504)
		(stroke
			(width 0.07112)
			(type default)
		)
		(layer "In6.Cu")
	)
	(gr_line
		(start 405.882602 -408.795728)
		(end 406.284684 -408.939492)
		(stroke
			(width 0.07112)
			(type default)
		)
		(layer "In6.Cu")
	)
	(gr_line
		(start 405.997664 -410.051504)
		(end 406.39238 -410.214572)
		(stroke
			(width 0.07112)
			(type default)
		)
		(layer "In6.Cu")
	)
	(gr_line
		(start 406.121362 -418.412168)
		(end 406.412192 -418.702998)
		(stroke
			(width 0.07112)
			(type default)
		)
		(layer "In6.Cu")
	)
	(gr_line
		(start 406.156668 -426.776642)
		(end 406.156922 -426.776642)
		(stroke
			(width 0.07112)
			(type default)
		)
		(layer "In6.Cu")
	)
	(gr_line
		(start 406.172162 -393.787376)
		(end 406.17267 -393.786868)
		(stroke
			(width 0.07112)
			(type default)
		)
		(layer "In6.Cu")
	)
	(gr_line
		(start 406.218898 -394.385292)
		(end 406.31364 -394.031724)
		(stroke
			(width 0.07112)
			(type default)
		)
		(layer "In6.Cu")
	)
	(gr_line
		(start 406.284684 -408.939492)
		(end 406.367234 -409.113736)
		(stroke
			(width 0.07112)
			(type default)
		)
		(layer "In6.Cu")
	)
	(gr_line
		(start 406.39238 -410.214572)
		(end 406.457658 -410.373068)
		(stroke
			(width 0.07112)
			(type default)
		)
		(layer "In6.Cu")
	)
	(gr_line
		(start 406.412192 -419.566344)
		(end 406.412192 -420.267384)
		(stroke
			(width 0.07112)
			(type default)
		)
		(layer "In6.Cu")
	)
	(gr_line
		(start 406.412192 -415.09569)
		(end 406.121362 -415.38652)
		(stroke
			(width 0.07112)
			(type default)
		)
		(layer "In6.Cu")
	)
	(gr_line
		(start 406.412192 -413.377888)
		(end 406.412192 -414.078928)
		(stroke
			(width 0.07112)
			(type default)
		)
		(layer "In6.Cu")
	)
	(gr_line
		(start 406.435306 -393.961112)
		(end 406.488138 -393.930632)
		(stroke
			(width 0.07112)
			(type default)
		)
		(layer "In6.Cu")
	)
	(gr_line
		(start 406.488138 -393.930632)
		(end 406.576276 -393.842494)
		(stroke
			(width 0.07112)
			(type default)
		)
		(layer "In6.Cu")
	)
	(gr_arc
		(start 406.527 -382.177036)
		(mid 406.525874 -382.172587)
		(end 406.524714 -382.168146)
		(stroke
			(width 0.07112)
			(type default)
		)
		(layer "In6.Cu")
	)
	(gr_line
		(start 406.527254 -382.178052)
		(end 406.527 -382.177036)
		(stroke
			(width 0.07112)
			(type default)
		)
		(layer "In6.Cu")
	)
	(gr_line
		(start 406.576276 -393.842494)
		(end 406.576276 -393.716764)
		(stroke
			(width 0.07112)
			(type default)
		)
		(layer "In6.Cu")
	)
	(gr_line
		(start 406.59558 -426.548804)
		(end 406.623012 -426.548804)
		(stroke
			(width 0.07112)
			(type default)
		)
		(layer "In6.Cu")
	)
	(gr_line
		(start 406.59685 -426.832014)
		(end 406.750012 -426.985176)
		(stroke
			(width 0.07112)
			(type default)
		)
		(layer "In6.Cu")
	)
	(gr_line
		(start 406.623012 -426.548804)
		(end 406.750012 -426.421804)
		(stroke
			(width 0.07112)
			(type default)
		)
		(layer "In6.Cu")
	)
	(gr_line
		(start 406.694132 -415.09569)
		(end 406.984962 -415.38652)
		(stroke
			(width 0.07112)
			(type default)
		)
		(layer "In6.Cu")
	)
	(gr_line
		(start 406.695402 -419.567614)
		(end 406.831292 -419.703504)
		(stroke
			(width 0.07112)
			(type default)
		)
		(layer "In6.Cu")
	)
	(gr_line
		(start 406.695402 -413.379158)
		(end 406.831292 -413.515048)
		(stroke
			(width 0.07112)
			(type default)
		)
		(layer "In6.Cu")
	)
	(gr_line
		(start 406.744424 -410.798518)
		(end 407.37409 -411.059376)
		(stroke
			(width 0.07112)
			(type default)
		)
		(layer "In6.Cu")
	)
	(gr_line
		(start 406.750012 -426.985176)
		(end 406.750012 -427.289976)
		(stroke
			(width 0.07112)
			(type default)
		)
		(layer "In6.Cu")
	)
	(gr_line
		(start 406.750012 -426.421804)
		(end 406.750012 -426.089826)
		(stroke
			(width 0.07112)
			(type default)
		)
		(layer "In6.Cu")
	)
	(gr_line
		(start 406.831292 -420.130224)
		(end 406.695402 -420.266114)
		(stroke
			(width 0.07112)
			(type default)
		)
		(layer "In6.Cu")
	)
	(gr_line
		(start 406.831292 -419.703504)
		(end 406.831292 -420.130224)
		(stroke
			(width 0.07112)
			(type default)
		)
		(layer "In6.Cu")
	)
	(gr_line
		(start 406.831292 -413.941768)
		(end 406.695402 -414.077658)
		(stroke
			(width 0.07112)
			(type default)
		)
		(layer "In6.Cu")
	)
	(gr_line
		(start 406.831292 -413.515048)
		(end 406.831292 -413.941768)
		(stroke
			(width 0.07112)
			(type default)
		)
		(layer "In6.Cu")
	)
	(gr_line
		(start 406.853136 -424.097196)
		(end 406.662636 -424.071288)
		(stroke
			(width 0.07112)
			(type default)
		)
		(layer "In6.Cu")
	)
	(gr_line
		(start 406.85339 -410.536898)
		(end 407.01849 -410.468826)
		(stroke
			(width 0.07112)
			(type default)
		)
		(layer "In6.Cu")
	)
	(gr_line
		(start 406.984962 -418.412168)
		(end 406.694132 -418.702998)
		(stroke
			(width 0.07112)
			(type default)
		)
		(layer "In6.Cu")
	)
	(gr_line
		(start 407.01849 -410.468826)
		(end 407.412952 -410.631894)
		(stroke
			(width 0.07112)
			(type default)
		)
		(layer "In6.Cu")
	)
	(gr_line
		(start 407.018998 -393.69238)
		(end 407.372312 -393.787376)
		(stroke
			(width 0.07112)
			(type default)
		)
		(layer "In6.Cu")
	)
	(gr_line
		(start 407.048208 -423.42181)
		(end 406.49017 -423.846498)
		(stroke
			(width 0.07112)
			(type default)
		)
		(layer "In6.Cu")
	)
	(gr_line
		(start 407.161492 -368.17808)
		(end 407.161238 -368.17808)
		(stroke
			(width 0.07112)
			(type default)
		)
		(layer "In6.Cu")
	)
	(gr_line
		(start 407.181304 -392.732514)
		(end 407.181812 -392.683746)
		(stroke
			(width 0.07112)
			(type default)
		)
		(layer "In6.Cu")
	)
	(gr_line
		(start 407.192988 -423.838624)
		(end 406.853136 -424.097196)
		(stroke
			(width 0.07112)
			(type default)
		)
		(layer "In6.Cu")
	)
	(gr_line
		(start 407.213308 -368.365278)
		(end 407.162 -368.179858)
		(stroke
			(width 0.07112)
			(type default)
		)
		(layer "In6.Cu")
	)
	(gr_line
		(start 407.218896 -423.64787)
		(end 407.192988 -423.838624)
		(stroke
			(width 0.07112)
			(type default)
		)
		(layer "In6.Cu")
	)
	(gr_arc
		(start 407.229564 -392.5697)
		(mid 407.194496 -392.622034)
		(end 407.181812 -392.683746)
		(stroke
			(width 0.07112)
			(type default)
		)
		(layer "In6.Cu")
	)
	(gr_line
		(start 407.229564 -392.5697)
		(end 407.264108 -392.535156)
		(stroke
			(width 0.07112)
			(type default)
		)
		(layer "In6.Cu")
	)
	(gr_line
		(start 407.304494 -386.547106)
		(end 407.398982 -386.37972)
		(stroke
			(width 0.07112)
			(type default)
		)
		(layer "In6.Cu")
	)
	(gr_line
		(start 407.372312 -393.787376)
		(end 407.37282 -393.786868)
		(stroke
			(width 0.07112)
			(type default)
		)
		(layer "In6.Cu")
	)
	(gr_line
		(start 407.399998 -386.378196)
		(end 407.399744 -386.378196)
		(stroke
			(width 0.07112)
			(type default)
		)
		(layer "In6.Cu")
	)
	(gr_line
		(start 407.412952 -410.631894)
		(end 407.481532 -410.797248)
		(stroke
			(width 0.07112)
			(type default)
		)
		(layer "In6.Cu")
	)
	(gr_line
		(start 407.41854 -386.958586)
		(end 407.304494 -386.547106)
		(stroke
			(width 0.07112)
			(type default)
		)
		(layer "In6.Cu")
	)
	(gr_line
		(start 407.419048 -394.385292)
		(end 407.51379 -394.031724)
		(stroke
			(width 0.07112)
			(type default)
		)
		(layer "In6.Cu")
	)
	(gr_line
		(start 407.449782 -390.318498)
		(end 407.449782 -390.318244)
		(stroke
			(width 0.07112)
			(type default)
		)
		(layer "In6.Cu")
	)
	(gr_arc
		(start 407.451814 -392.34618)
		(mid 407.473882 -392.308703)
		(end 407.485088 -392.266678)
		(stroke
			(width 0.07112)
			(type default)
		)
		(layer "In6.Cu")
	)
	(gr_line
		(start 407.585164 -368.57559)
		(end 407.213308 -368.365278)
		(stroke
			(width 0.07112)
			(type default)
		)
		(layer "In6.Cu")
	)
	(gr_line
		(start 407.585926 -387.053328)
		(end 407.41854 -386.958586)
		(stroke
			(width 0.07112)
			(type default)
		)
		(layer "In6.Cu")
	)
	(gr_line
		(start 407.605992 -387.633972)
		(end 407.700734 -387.466586)
		(stroke
			(width 0.07112)
			(type default)
		)
		(layer "In6.Cu")
	)
	(gr_line
		(start 407.635456 -393.961112)
		(end 407.688288 -393.930632)
		(stroke
			(width 0.07112)
			(type default)
		)
		(layer "In6.Cu")
	)
	(gr_line
		(start 407.644346 -392.554206)
		(end 407.654252 -392.5443)
		(stroke
			(width 0.07112)
			(type default)
		)
		(layer "In6.Cu")
	)
	(gr_line
		(start 407.660856 -392.537696)
		(end 407.721054 -392.477498)
		(stroke
			(width 0.07112)
			(type default)
		)
		(layer "In6.Cu")
	)
	(gr_line
		(start 407.671778 -386.303266)
		(end 407.67127 -386.301742)
		(stroke
			(width 0.07112)
			(type default)
		)
		(layer "In6.Cu")
	)
	(gr_line
		(start 407.673302 -386.308854)
		(end 407.671778 -386.303266)
		(stroke
			(width 0.07112)
			(type default)
		)
		(layer "In6.Cu")
	)
	(gr_line
		(start 407.688288 -393.930632)
		(end 407.776426 -393.842494)
		(stroke
			(width 0.07112)
			(type default)
		)
		(layer "In6.Cu")
	)
	(gr_line
		(start 407.720038 -388.045452)
		(end 407.605992 -387.633972)
		(stroke
			(width 0.07112)
			(type default)
		)
		(layer "In6.Cu")
	)
	(gr_arc
		(start 407.721054 -392.477498)
		(mid 407.755989 -392.425165)
		(end 407.768298 -392.363452)
		(stroke
			(width 0.07112)
			(type default)
		)
		(layer "In6.Cu")
	)
	(gr_line
		(start 407.750772 -423.41419)
		(end 407.560272 -423.388282)
		(stroke
			(width 0.07112)
			(type default)
		)
		(layer "In6.Cu")
	)
	(gr_line
		(start 407.768298 -392.363452)
		(end 407.768298 -392.28014)
		(stroke
			(width 0.07112)
			(type default)
		)
		(layer "In6.Cu")
	)
	(gr_line
		(start 407.77033 -368.524282)
		(end 407.585164 -368.57559)
		(stroke
			(width 0.07112)
			(type default)
		)
		(layer "In6.Cu")
	)
	(gr_line
		(start 407.776426 -393.842494)
		(end 407.776426 -393.716764)
		(stroke
			(width 0.07112)
			(type default)
		)
		(layer "In6.Cu")
	)
	(gr_line
		(start 407.85923 -386.978652)
		(end 407.673556 -386.309616)
		(stroke
			(width 0.07112)
			(type default)
		)
		(layer "In6.Cu")
	)
	(gr_line
		(start 407.887424 -388.140194)
		(end 407.720038 -388.045452)
		(stroke
			(width 0.07112)
			(type default)
		)
		(layer "In6.Cu")
	)
	(gr_line
		(start 407.90749 -388.720838)
		(end 408.002232 -388.553452)
		(stroke
			(width 0.07112)
			(type default)
		)
		(layer "In6.Cu")
	)
	(gr_line
		(start 407.910792 -368.27841)
		(end 407.300176 -367.932716)
		(stroke
			(width 0.07112)
			(type default)
		)
		(layer "In6.Cu")
	)
	(gr_line
		(start 407.945844 -422.738804)
		(end 407.387806 -423.163746)
		(stroke
			(width 0.07112)
			(type default)
		)
		(layer "In6.Cu")
	)
	(gr_line
		(start 407.952448 -411.298898)
		(end 408.572208 -411.555692)
		(stroke
			(width 0.07112)
			(type default)
		)
		(layer "In6.Cu")
	)
	(gr_line
		(start 408.021536 -389.132318)
		(end 407.90749 -388.720838)
		(stroke
			(width 0.07112)
			(type default)
		)
		(layer "In6.Cu")
	)
	(gr_line
		(start 408.061668 -411.037532)
		(end 408.219656 -410.972)
		(stroke
			(width 0.07112)
			(type default)
		)
		(layer "In6.Cu")
	)
	(gr_line
		(start 408.089608 -424.87215)
		(end 408.089354 -424.871896)
		(stroke
			(width 0.07112)
			(type default)
		)
		(layer "In6.Cu")
	)
	(gr_line
		(start 408.090624 -423.155618)
		(end 407.750772 -423.41419)
		(stroke
			(width 0.07112)
			(type default)
		)
		(layer "In6.Cu")
	)
	(gr_line
		(start 408.116532 -422.964864)
		(end 408.090624 -423.155618)
		(stroke
			(width 0.07112)
			(type default)
		)
		(layer "In6.Cu")
	)
	(gr_line
		(start 408.143456 -368.733832)
		(end 408.143202 -368.733832)
		(stroke
			(width 0.07112)
			(type default)
		)
		(layer "In6.Cu")
	)
	(gr_line
		(start 408.160728 -388.065518)
		(end 407.973276 -387.389624)
		(stroke
			(width 0.07112)
			(type default)
		)
		(layer "In6.Cu")
	)
	(gr_line
		(start 408.188922 -389.226806)
		(end 408.021536 -389.132318)
		(stroke
			(width 0.07112)
			(type default)
		)
		(layer "In6.Cu")
	)
	(gr_line
		(start 408.190446 -389.227822)
		(end 408.1907 -389.227822)
		(stroke
			(width 0.07112)
			(type default)
		)
		(layer "In6.Cu")
	)
	(gr_line
		(start 408.195272 -368.92103)
		(end 408.143964 -368.735864)
		(stroke
			(width 0.07112)
			(type default)
		)
		(layer "In6.Cu")
	)
	(gr_line
		(start 408.218894 -393.69238)
		(end 408.572208 -393.787376)
		(stroke
			(width 0.07112)
			(type default)
		)
		(layer "In6.Cu")
	)
	(gr_line
		(start 408.219656 -410.972)
		(end 408.614118 -411.135322)
		(stroke
			(width 0.07112)
			(type default)
		)
		(layer "In6.Cu")
	)
	(gr_line
		(start 408.281886 -368.488468)
		(end 408.238706 -368.464084)
		(stroke
			(width 0.07112)
			(type default)
		)
		(layer "In6.Cu")
	)
	(gr_line
		(start 408.462226 -389.152384)
		(end 408.274774 -388.47649)
		(stroke
			(width 0.07112)
			(type default)
		)
		(layer "In6.Cu")
	)
	(gr_line
		(start 408.567128 -369.131342)
		(end 408.195272 -368.92103)
		(stroke
			(width 0.07112)
			(type default)
		)
		(layer "In6.Cu")
	)
	(gr_line
		(start 408.572208 -393.787376)
		(end 408.572716 -393.786868)
		(stroke
			(width 0.07112)
			(type default)
		)
		(layer "In6.Cu")
	)
	(gr_line
		(start 408.607768 -427.830742)
		(end 408.750008 -427.972982)
		(stroke
			(width 0.07112)
			(type default)
		)
		(layer "In6.Cu")
	)
	(gr_line
		(start 408.607768 -427.548802)
		(end 408.750008 -427.406562)
		(stroke
			(width 0.07112)
			(type default)
		)
		(layer "In6.Cu")
	)
	(gr_line
		(start 408.614118 -411.135322)
		(end 408.67965 -411.293564)
		(stroke
			(width 0.07112)
			(type default)
		)
		(layer "In6.Cu")
	)
	(gr_line
		(start 408.618944 -394.385292)
		(end 408.713686 -394.031724)
		(stroke
			(width 0.07112)
			(type default)
		)
		(layer "In6.Cu")
	)
	(gr_line
		(start 408.648408 -422.731184)
		(end 408.457908 -422.705276)
		(stroke
			(width 0.07112)
			(type default)
		)
		(layer "In6.Cu")
	)
	(gr_line
		(start 408.733244 -373.19585)
		(end 408.727402 -373.194326)
		(stroke
			(width 0.07112)
			(type default)
		)
		(layer "In6.Cu")
	)
	(gr_line
		(start 408.750008 -427.972982)
		(end 408.750008 -428.28972)
		(stroke
			(width 0.07112)
			(type default)
		)
		(layer "In6.Cu")
	)
	(gr_line
		(start 408.750008 -427.406562)
		(end 408.750008 -427.089824)
		(stroke
			(width 0.07112)
			(type default)
		)
		(layer "In6.Cu")
	)
	(gr_line
		(start 408.75204 -369.080034)
		(end 408.567128 -369.131342)
		(stroke
			(width 0.07112)
			(type default)
		)
		(layer "In6.Cu")
	)
	(gr_line
		(start 408.835352 -393.961112)
		(end 408.888184 -393.930632)
		(stroke
			(width 0.07112)
			(type default)
		)
		(layer "In6.Cu")
	)
	(gr_line
		(start 408.84348 -422.055798)
		(end 408.285442 -422.48074)
		(stroke
			(width 0.07112)
			(type default)
		)
		(layer "In6.Cu")
	)
	(gr_arc
		(start 408.858466 -372.535704)
		(mid 408.860368 -372.536725)
		(end 408.862276 -372.537736)
		(stroke
			(width 0.07112)
			(type default)
		)
		(layer "In6.Cu")
	)
	(gr_line
		(start 408.888184 -393.930632)
		(end 408.976322 -393.842494)
		(stroke
			(width 0.07112)
			(type default)
		)
		(layer "In6.Cu")
	)
	(gr_line
		(start 408.892756 -368.834162)
		(end 408.281886 -368.488468)
		(stroke
			(width 0.07112)
			(type default)
		)
		(layer "In6.Cu")
	)
	(gr_line
		(start 408.893518 -387.956552)
		(end 408.989022 -387.788912)
		(stroke
			(width 0.07112)
			(type default)
		)
		(layer "In6.Cu")
	)
	(gr_line
		(start 408.9019 -373.238014)
		(end 408.896312 -373.23649)
		(stroke
			(width 0.07112)
			(type default)
		)
		(layer "In6.Cu")
	)
	(gr_line
		(start 408.972004 -372.580916)
		(end 408.970734 -372.580662)
		(stroke
			(width 0.07112)
			(type default)
		)
		(layer "In6.Cu")
	)
	(gr_line
		(start 408.976322 -393.842494)
		(end 408.976322 -393.716764)
		(stroke
			(width 0.07112)
			(type default)
		)
		(layer "In6.Cu")
	)
	(gr_line
		(start 408.98826 -422.472612)
		(end 408.648408 -422.731184)
		(stroke
			(width 0.07112)
			(type default)
		)
		(layer "In6.Cu")
	)
	(gr_line
		(start 408.98953 -387.787896)
		(end 408.989784 -387.787642)
		(stroke
			(width 0.07112)
			(type default)
		)
		(layer "In6.Cu")
	)
	(gr_line
		(start 409.00604 -388.368286)
		(end 408.893518 -387.956552)
		(stroke
			(width 0.07112)
			(type default)
		)
		(layer "In6.Cu")
	)
	(gr_line
		(start 409.014168 -422.281858)
		(end 408.98826 -422.472612)
		(stroke
			(width 0.07112)
			(type default)
		)
		(layer "In6.Cu")
	)
	(gr_line
		(start 409.10256 -409.152598)
		(end 409.750514 -409.421076)
		(stroke
			(width 0.07112)
			(type default)
		)
		(layer "In6.Cu")
	)
	(gr_line
		(start 409.111704 -423.810938)
		(end 408.920188 -423.792142)
		(stroke
			(width 0.07112)
			(type default)
		)
		(layer "In6.Cu")
	)
	(gr_line
		(start 409.173426 -388.46379)
		(end 409.00604 -388.368286)
		(stroke
			(width 0.07112)
			(type default)
		)
		(layer "In6.Cu")
	)
	(gr_line
		(start 409.174696 -388.464552)
		(end 409.173934 -388.464044)
		(stroke
			(width 0.07112)
			(type default)
		)
		(layer "In6.Cu")
	)
	(gr_line
		(start 409.176728 -369.476782)
		(end 409.125674 -369.291362)
		(stroke
			(width 0.07112)
			(type default)
		)
		(layer "In6.Cu")
	)
	(gr_line
		(start 409.184602 -418.412168)
		(end 409.475432 -418.702998)
		(stroke
			(width 0.07112)
			(type default)
		)
		(layer "In6.Cu")
	)
	(gr_line
		(start 409.190952 -389.044688)
		(end 409.286202 -388.877048)
		(stroke
			(width 0.07112)
			(type default)
		)
		(layer "In6.Cu")
	)
	(gr_line
		(start 409.212034 -408.891486)
		(end 409.38958 -408.817572)
		(stroke
			(width 0.07112)
			(type default)
		)
		(layer "In6.Cu")
	)
	(gr_line
		(start 409.26385 -369.04422)
		(end 409.084018 -368.942366)
		(stroke
			(width 0.07112)
			(type default)
		)
		(layer "In6.Cu")
	)
	(gr_line
		(start 409.281884 -423.128694)
		(end 408.739594 -423.573702)
		(stroke
			(width 0.07112)
			(type default)
		)
		(layer "In6.Cu")
	)
	(gr_line
		(start 409.30322 -389.456422)
		(end 409.190952 -389.044688)
		(stroke
			(width 0.07112)
			(type default)
		)
		(layer "In6.Cu")
	)
	(gr_line
		(start 409.38958 -408.817572)
		(end 409.784296 -408.980894)
		(stroke
			(width 0.07112)
			(type default)
		)
		(layer "In6.Cu")
	)
	(gr_line
		(start 409.419044 -393.69238)
		(end 409.772358 -393.787376)
		(stroke
			(width 0.07112)
			(type default)
		)
		(layer "In6.Cu")
	)
	(gr_line
		(start 409.430728 -382.915922)
		(end 409.430474 -382.916176)
		(stroke
			(width 0.07112)
			(type default)
		)
		(layer "In6.Cu")
	)
	(gr_line
		(start 409.44165 -423.53992)
		(end 409.111704 -423.810938)
		(stroke
			(width 0.07112)
			(type default)
		)
		(layer "In6.Cu")
	)
	(gr_line
		(start 409.44673 -388.389622)
		(end 409.261818 -387.71322)
		(stroke
			(width 0.07112)
			(type default)
		)
		(layer "In6.Cu")
	)
	(gr_line
		(start 409.446984 -388.390384)
		(end 409.44673 -388.389622)
		(stroke
			(width 0.07112)
			(type default)
		)
		(layer "In6.Cu")
	)
	(gr_line
		(start 409.460446 -423.348404)
		(end 409.44165 -423.53992)
		(stroke
			(width 0.07112)
			(type default)
		)
		(layer "In6.Cu")
	)
	(gr_line
		(start 409.470606 -389.551926)
		(end 409.30322 -389.456422)
		(stroke
			(width 0.07112)
			(type default)
		)
		(layer "In6.Cu")
	)
	(gr_line
		(start 409.475432 -419.80104)
		(end 409.475432 -420.50208)
		(stroke
			(width 0.07112)
			(type default)
		)
		(layer "In6.Cu")
	)
	(gr_line
		(start 409.475432 -415.09569)
		(end 409.184602 -415.38652)
		(stroke
			(width 0.07112)
			(type default)
		)
		(layer "In6.Cu")
	)
	(gr_line
		(start 409.488386 -390.13257)
		(end 409.583636 -389.965438)
		(stroke
			(width 0.07112)
			(type default)
		)
		(layer "In6.Cu")
	)
	(gr_line
		(start 409.548584 -369.687094)
		(end 409.176728 -369.476782)
		(stroke
			(width 0.07112)
			(type default)
		)
		(layer "In6.Cu")
	)
	(gr_line
		(start 409.600654 -390.544304)
		(end 409.488386 -390.13257)
		(stroke
			(width 0.07112)
			(type default)
		)
		(layer "In6.Cu")
	)
	(gr_line
		(start 409.734004 -369.635532)
		(end 409.548584 -369.687094)
		(stroke
			(width 0.07112)
			(type default)
		)
		(layer "In6.Cu")
	)
	(gr_line
		(start 409.744164 -389.47852)
		(end 409.559252 -388.80161)
		(stroke
			(width 0.07112)
			(type default)
		)
		(layer "In6.Cu")
	)
	(gr_line
		(start 409.757372 -415.09569)
		(end 410.048202 -415.38652)
		(stroke
			(width 0.07112)
			(type default)
		)
		(layer "In6.Cu")
	)
	(gr_line
		(start 409.758642 -419.80231)
		(end 409.894532 -419.9382)
		(stroke
			(width 0.07112)
			(type default)
		)
		(layer "In6.Cu")
	)
	(gr_line
		(start 409.76804 -390.639554)
		(end 409.600654 -390.544304)
		(stroke
			(width 0.07112)
			(type default)
		)
		(layer "In6.Cu")
	)
	(gr_line
		(start 409.772358 -393.787376)
		(end 409.772866 -393.786868)
		(stroke
			(width 0.07112)
			(type default)
		)
		(layer "In6.Cu")
	)
	(gr_line
		(start 409.784296 -408.980894)
		(end 409.857956 -409.158948)
		(stroke
			(width 0.07112)
			(type default)
		)
		(layer "In6.Cu")
	)
	(gr_line
		(start 409.81884 -390.82091)
		(end 409.769564 -390.64057)
		(stroke
			(width 0.07112)
			(type default)
		)
		(layer "In6.Cu")
	)
	(gr_line
		(start 409.819094 -394.385292)
		(end 409.913836 -394.031724)
		(stroke
			(width 0.07112)
			(type default)
		)
		(layer "In6.Cu")
	)
	(gr_line
		(start 409.874212 -369.38966)
		(end 409.26385 -369.04422)
		(stroke
			(width 0.07112)
			(type default)
		)
		(layer "In6.Cu")
	)
	(gr_line
		(start 409.894532 -420.36492)
		(end 409.758642 -420.50081)
		(stroke
			(width 0.07112)
			(type default)
		)
		(layer "In6.Cu")
	)
	(gr_line
		(start 409.894532 -419.9382)
		(end 409.894532 -420.36492)
		(stroke
			(width 0.07112)
			(type default)
		)
		(layer "In6.Cu")
	)
	(gr_line
		(start 409.983432 -423.09542)
		(end 409.791916 -423.076624)
		(stroke
			(width 0.07112)
			(type default)
		)
		(layer "In6.Cu")
	)
	(gr_line
		(start 410.035502 -393.961112)
		(end 410.088334 -393.930632)
		(stroke
			(width 0.07112)
			(type default)
		)
		(layer "In6.Cu")
	)
	(gr_line
		(start 410.041598 -390.566402)
		(end 409.856686 -389.89)
		(stroke
			(width 0.07112)
			(type default)
		)
		(layer "In6.Cu")
	)
	(gr_line
		(start 410.048202 -418.412168)
		(end 409.757372 -418.702998)
		(stroke
			(width 0.07112)
			(type default)
		)
		(layer "In6.Cu")
	)
	(gr_line
		(start 410.088334 -393.930632)
		(end 410.176472 -393.842494)
		(stroke
			(width 0.07112)
			(type default)
		)
		(layer "In6.Cu")
	)
	(gr_line
		(start 410.090874 -390.746742)
		(end 410.041598 -390.566402)
		(stroke
			(width 0.07112)
			(type default)
		)
		(layer "In6.Cu")
	)
	(gr_line
		(start 410.127958 -388.028942)
		(end 410.22524 -387.862572)
		(stroke
			(width 0.07112)
			(type default)
		)
		(layer "In6.Cu")
	)
	(gr_line
		(start 410.153612 -422.41343)
		(end 409.611322 -422.858184)
		(stroke
			(width 0.07112)
			(type default)
		)
		(layer "In6.Cu")
	)
	(gr_line
		(start 410.176472 -393.842494)
		(end 410.176472 -393.716764)
		(stroke
			(width 0.07112)
			(type default)
		)
		(layer "In6.Cu")
	)
	(gr_line
		(start 410.235654 -388.441946)
		(end 410.127958 -388.028942)
		(stroke
			(width 0.07112)
			(type default)
		)
		(layer "In6.Cu")
	)
	(gr_line
		(start 410.246068 -369.600226)
		(end 410.245814 -369.599972)
		(stroke
			(width 0.07112)
			(type default)
		)
		(layer "In6.Cu")
	)
	(gr_line
		(start 410.313378 -422.824402)
		(end 409.983432 -423.09542)
		(stroke
			(width 0.07112)
			(type default)
		)
		(layer "In6.Cu")
	)
	(gr_line
		(start 410.332174 -422.63314)
		(end 410.313378 -422.824402)
		(stroke
			(width 0.07112)
			(type default)
		)
		(layer "In6.Cu")
	)
	(gr_line
		(start 410.362908 -410.961332)
		(end 411.010862 -411.22981)
		(stroke
			(width 0.07112)
			(type default)
		)
		(layer "In6.Cu")
	)
	(gr_line
		(start 410.402278 -388.539228)
		(end 410.235654 -388.441946)
		(stroke
			(width 0.07112)
			(type default)
		)
		(layer "In6.Cu")
	)
	(gr_line
		(start 410.4132 -389.120126)
		(end 410.510736 -388.953756)
		(stroke
			(width 0.07112)
			(type default)
		)
		(layer "In6.Cu")
	)
	(gr_line
		(start 410.472382 -410.70022)
		(end 410.650182 -410.62656)
		(stroke
			(width 0.07112)
			(type default)
		)
		(layer "In6.Cu")
	)
	(gr_line
		(start 410.483304 -422.142666)
		(end 410.48305 -422.14292)
		(stroke
			(width 0.07112)
			(type default)
		)
		(layer "In6.Cu")
	)
	(gr_line
		(start 410.52115 -389.53313)
		(end 410.4132 -389.120126)
		(stroke
			(width 0.07112)
			(type default)
		)
		(layer "In6.Cu")
	)
	(gr_line
		(start 410.59354 -426.865796)
		(end 410.623004 -426.865796)
		(stroke
			(width 0.07112)
			(type default)
		)
		(layer "In6.Cu")
	)
	(gr_line
		(start 410.59481 -426.582586)
		(end 410.750004 -426.427392)
		(stroke
			(width 0.07112)
			(type default)
		)
		(layer "In6.Cu")
	)
	(gr_line
		(start 410.61894 -393.69238)
		(end 410.972254 -393.787376)
		(stroke
			(width 0.07112)
			(type default)
		)
		(layer "In6.Cu")
	)
	(gr_line
		(start 410.623004 -426.865796)
		(end 410.750004 -426.992796)
		(stroke
			(width 0.07112)
			(type default)
		)
		(layer "In6.Cu")
	)
	(gr_line
		(start 410.650182 -410.62656)
		(end 411.044644 -410.789882)
		(stroke
			(width 0.07112)
			(type default)
		)
		(layer "In6.Cu")
	)
	(gr_line
		(start 410.676598 -388.46887)
		(end 410.498798 -387.789674)
		(stroke
			(width 0.07112)
			(type default)
		)
		(layer "In6.Cu")
	)
	(gr_line
		(start 410.68752 -389.630412)
		(end 410.52115 -389.53313)
		(stroke
			(width 0.07112)
			(type default)
		)
		(layer "In6.Cu")
	)
	(gr_line
		(start 410.698696 -390.21131)
		(end 410.795978 -390.045194)
		(stroke
			(width 0.07112)
			(type default)
		)
		(layer "In6.Cu")
	)
	(gr_line
		(start 410.750004 -426.992796)
		(end 410.750004 -427.289976)
		(stroke
			(width 0.07112)
			(type default)
		)
		(layer "In6.Cu")
	)
	(gr_line
		(start 410.750004 -426.427392)
		(end 410.750004 -426.089826)
		(stroke
			(width 0.07112)
			(type default)
		)
		(layer "In6.Cu")
	)
	(gr_line
		(start 410.784548 -409.84932)
		(end 411.432502 -410.117798)
		(stroke
			(width 0.07112)
			(type default)
		)
		(layer "In6.Cu")
	)
	(gr_line
		(start 410.806646 -390.624314)
		(end 410.698696 -390.21131)
		(stroke
			(width 0.07112)
			(type default)
		)
		(layer "In6.Cu")
	)
	(gr_line
		(start 410.893768 -409.588208)
		(end 411.071822 -409.514548)
		(stroke
			(width 0.07112)
			(type default)
		)
		(layer "In6.Cu")
	)
	(gr_line
		(start 410.96184 -389.5598)
		(end 410.784548 -388.881366)
		(stroke
			(width 0.07112)
			(type default)
		)
		(layer "In6.Cu")
	)
	(gr_line
		(start 410.972254 -393.787376)
		(end 410.972762 -393.786868)
		(stroke
			(width 0.07112)
			(type default)
		)
		(layer "In6.Cu")
	)
	(gr_line
		(start 410.973016 -390.721596)
		(end 410.806646 -390.624314)
		(stroke
			(width 0.07112)
			(type default)
		)
		(layer "In6.Cu")
	)
	(gr_line
		(start 411.010862 -411.22981)
		(end 411.011116 -411.22981)
		(stroke
			(width 0.07112)
			(type default)
		)
		(layer "In6.Cu")
	)
	(gr_line
		(start 411.01899 -394.385292)
		(end 411.113732 -394.031724)
		(stroke
			(width 0.07112)
			(type default)
		)
		(layer "In6.Cu")
	)
	(gr_line
		(start 411.044644 -410.789882)
		(end 411.118304 -410.967682)
		(stroke
			(width 0.07112)
			(type default)
		)
		(layer "In6.Cu")
	)
	(gr_line
		(start 411.071822 -409.514548)
		(end 411.466284 -409.67787)
		(stroke
			(width 0.07112)
			(type default)
		)
		(layer "In6.Cu")
	)
	(gr_arc
		(start 411.0863 -391.167366)
		(mid 411.086301 -391.166985)
		(end 411.0863 -391.166604)
		(stroke
			(width 0.07112)
			(type default)
		)
		(layer "In6.Cu")
	)
	(gr_line
		(start 411.235398 -393.961112)
		(end 411.28823 -393.930632)
		(stroke
			(width 0.07112)
			(type default)
		)
		(layer "In6.Cu")
	)
	(gr_line
		(start 411.247336 -390.650984)
		(end 411.06979 -389.97255)
		(stroke
			(width 0.07112)
			(type default)
		)
		(layer "In6.Cu")
	)
	(gr_line
		(start 411.28823 -393.930632)
		(end 411.376368 -393.842494)
		(stroke
			(width 0.07112)
			(type default)
		)
		(layer "In6.Cu")
	)
	(gr_line
		(start 411.376368 -393.842494)
		(end 411.376368 -393.716764)
		(stroke
			(width 0.07112)
			(type default)
		)
		(layer "In6.Cu")
	)
	(gr_line
		(start 411.384242 -423.610024)
		(end 411.227016 -423.526204)
		(stroke
			(width 0.07112)
			(type default)
		)
		(layer "In6.Cu")
	)
	(gr_line
		(start 411.432502 -410.117798)
		(end 411.432756 -410.117798)
		(stroke
			(width 0.07112)
			(type default)
		)
		(layer "In6.Cu")
	)
	(gr_line
		(start 411.466284 -409.67787)
		(end 411.539944 -409.85567)
		(stroke
			(width 0.07112)
			(type default)
		)
		(layer "In6.Cu")
	)
	(gr_arc
		(start 411.77845 -422.044622)
		(mid 411.778196 -422.044622)
		(end 411.777942 -422.044622)
		(stroke
			(width 0.07112)
			(type default)
		)
		(layer "In6.Cu")
	)
	(gr_line
		(start 411.792674 -423.486072)
		(end 411.384242 -423.610024)
		(stroke
			(width 0.07112)
			(type default)
		)
		(layer "In6.Cu")
	)
	(gr_line
		(start 411.795722 -423.057574)
		(end 411.143958 -423.25544)
		(stroke
			(width 0.07112)
			(type default)
		)
		(layer "In6.Cu")
	)
	(gr_line
		(start 411.81909 -393.69238)
		(end 412.17215 -393.787376)
		(stroke
			(width 0.07112)
			(type default)
		)
		(layer "In6.Cu")
	)
	(gr_line
		(start 411.876748 -423.3291)
		(end 411.792674 -423.486072)
		(stroke
			(width 0.07112)
			(type default)
		)
		(layer "In6.Cu")
	)
	(gr_line
		(start 411.933136 -422.014904)
		(end 411.93212 -422.015158)
		(stroke
			(width 0.07112)
			(type default)
		)
		(layer "In6.Cu")
	)
	(gr_line
		(start 412.17215 -393.787376)
		(end 412.172658 -393.786868)
		(stroke
			(width 0.07112)
			(type default)
		)
		(layer "In6.Cu")
	)
	(gr_line
		(start 412.172658 -389.582152)
		(end 412.190692 -389.155432)
		(stroke
			(width 0.07112)
			(type default)
		)
		(layer "In6.Cu")
	)
	(gr_line
		(start 412.190692 -389.155432)
		(end 412.33217 -389.025384)
		(stroke
			(width 0.07112)
			(type default)
		)
		(layer "In6.Cu")
	)
	(gr_line
		(start 412.218886 -394.385292)
		(end 412.313628 -394.031724)
		(stroke
			(width 0.07112)
			(type default)
		)
		(layer "In6.Cu")
	)
	(gr_line
		(start 412.220156 -388.455154)
		(end 412.23819 -388.028434)
		(stroke
			(width 0.07112)
			(type default)
		)
		(layer "In6.Cu")
	)
	(gr_line
		(start 412.23819 -388.028434)
		(end 412.379668 -387.89864)
		(stroke
			(width 0.07112)
			(type default)
		)
		(layer "In6.Cu")
	)
	(gr_line
		(start 412.247842 -418.412168)
		(end 412.538672 -418.702998)
		(stroke
			(width 0.07112)
			(type default)
		)
		(layer "In6.Cu")
	)
	(gr_line
		(start 412.267654 -387.328156)
		(end 412.285688 -386.901436)
		(stroke
			(width 0.07112)
			(type default)
		)
		(layer "In6.Cu")
	)
	(gr_line
		(start 412.285688 -386.901436)
		(end 412.427166 -386.771642)
		(stroke
			(width 0.07112)
			(type default)
		)
		(layer "In6.Cu")
	)
	(gr_line
		(start 412.30296 -389.72363)
		(end 412.172658 -389.582152)
		(stroke
			(width 0.07112)
			(type default)
		)
		(layer "In6.Cu")
	)
	(gr_line
		(start 412.333694 -389.024114)
		(end 412.333186 -389.024114)
		(stroke
			(width 0.07112)
			(type default)
		)
		(layer "In6.Cu")
	)
	(gr_line
		(start 412.350204 -388.596632)
		(end 412.220156 -388.455154)
		(stroke
			(width 0.07112)
			(type default)
		)
		(layer "In6.Cu")
	)
	(gr_line
		(start 412.35122 -388.597902)
		(end 412.351474 -388.597902)
		(stroke
			(width 0.07112)
			(type default)
		)
		(layer "In6.Cu")
	)
	(gr_line
		(start 412.381192 -387.897116)
		(end 412.380684 -387.896862)
		(stroke
			(width 0.07112)
			(type default)
		)
		(layer "In6.Cu")
	)
	(gr_line
		(start 412.397702 -387.469634)
		(end 412.267654 -387.328156)
		(stroke
			(width 0.07112)
			(type default)
		)
		(layer "In6.Cu")
	)
	(gr_line
		(start 412.398464 -387.471158)
		(end 412.398972 -387.470904)
		(stroke
			(width 0.07112)
			(type default)
		)
		(layer "In6.Cu")
	)
	(gr_line
		(start 412.42869 -386.770118)
		(end 412.427928 -386.770118)
		(stroke
			(width 0.07112)
			(type default)
		)
		(layer "In6.Cu")
	)
	(gr_line
		(start 412.435294 -393.961112)
		(end 412.488126 -393.930632)
		(stroke
			(width 0.07112)
			(type default)
		)
		(layer "In6.Cu")
	)
	(gr_line
		(start 412.488126 -393.930632)
		(end 412.576264 -393.842494)
		(stroke
			(width 0.07112)
			(type default)
		)
		(layer "In6.Cu")
	)
	(gr_line
		(start 412.538672 -419.495478)
		(end 412.538672 -420.196518)
		(stroke
			(width 0.07112)
			(type default)
		)
		(layer "In6.Cu")
	)
	(gr_line
		(start 412.538672 -415.09569)
		(end 412.247842 -415.38652)
		(stroke
			(width 0.07112)
			(type default)
		)
		(layer "In6.Cu")
	)
	(gr_line
		(start 412.576264 -393.842494)
		(end 412.576264 -393.716764)
		(stroke
			(width 0.07112)
			(type default)
		)
		(layer "In6.Cu")
	)
	(gr_line
		(start 412.585916 -389.736584)
		(end 412.614364 -389.055356)
		(stroke
			(width 0.07112)
			(type default)
		)
		(layer "In6.Cu")
	)
	(gr_line
		(start 412.60776 -427.830742)
		(end 412.75 -427.972982)
		(stroke
			(width 0.07112)
			(type default)
		)
		(layer "In6.Cu")
	)
	(gr_line
		(start 412.60776 -427.548802)
		(end 412.75 -427.406562)
		(stroke
			(width 0.07112)
			(type default)
		)
		(layer "In6.Cu")
	)
	(gr_line
		(start 412.614618 -389.05307)
		(end 412.61538 -389.033766)
		(stroke
			(width 0.07112)
			(type default)
		)
		(layer "In6.Cu")
	)
	(gr_line
		(start 412.63316 -388.60984)
		(end 412.662624 -387.908546)
		(stroke
			(width 0.07112)
			(type default)
		)
		(layer "In6.Cu")
	)
	(gr_line
		(start 412.680658 -387.482842)
		(end 412.710122 -386.780786)
		(stroke
			(width 0.07112)
			(type default)
		)
		(layer "In6.Cu")
	)
	(gr_line
		(start 412.75 -427.972982)
		(end 412.75 -428.28972)
		(stroke
			(width 0.07112)
			(type default)
		)
		(layer "In6.Cu")
	)
	(gr_line
		(start 412.75 -427.406562)
		(end 412.75 -427.089824)
		(stroke
			(width 0.07112)
			(type default)
		)
		(layer "In6.Cu")
	)
	(gr_line
		(start 412.820612 -415.09569)
		(end 413.111442 -415.38652)
		(stroke
			(width 0.07112)
			(type default)
		)
		(layer "In6.Cu")
	)
	(gr_line
		(start 412.821882 -419.496748)
		(end 412.957772 -419.632638)
		(stroke
			(width 0.07112)
			(type default)
		)
		(layer "In6.Cu")
	)
	(gr_line
		(start 412.957772 -420.059358)
		(end 412.821882 -420.195248)
		(stroke
			(width 0.07112)
			(type default)
		)
		(layer "In6.Cu")
	)
	(gr_line
		(start 412.957772 -419.632638)
		(end 412.957772 -420.059358)
		(stroke
			(width 0.07112)
			(type default)
		)
		(layer "In6.Cu")
	)
	(gr_line
		(start 413.018986 -393.69238)
		(end 413.3723 -393.787376)
		(stroke
			(width 0.07112)
			(type default)
		)
		(layer "In6.Cu")
	)
	(gr_line
		(start 413.111442 -418.412168)
		(end 412.820612 -418.702998)
		(stroke
			(width 0.07112)
			(type default)
		)
		(layer "In6.Cu")
	)
	(gr_line
		(start 413.349186 -390.87806)
		(end 413.349186 -390.45134)
		(stroke
			(width 0.07112)
			(type default)
		)
		(layer "In6.Cu")
	)
	(gr_line
		(start 413.349186 -390.45134)
		(end 413.485076 -390.31545)
		(stroke
			(width 0.07112)
			(type default)
		)
		(layer "In6.Cu")
	)
	(gr_line
		(start 413.349186 -389.7503)
		(end 413.349186 -389.32358)
		(stroke
			(width 0.07112)
			(type default)
		)
		(layer "In6.Cu")
	)
	(gr_line
		(start 413.349186 -389.32358)
		(end 413.485076 -389.18769)
		(stroke
			(width 0.07112)
			(type default)
		)
		(layer "In6.Cu")
	)
	(gr_line
		(start 413.349186 -388.62254)
		(end 413.349186 -388.19582)
		(stroke
			(width 0.07112)
			(type default)
		)
		(layer "In6.Cu")
	)
	(gr_line
		(start 413.349186 -388.19582)
		(end 413.485076 -388.05993)
		(stroke
			(width 0.07112)
			(type default)
		)
		(layer "In6.Cu")
	)
	(gr_line
		(start 413.3723 -393.787376)
		(end 413.372808 -393.786868)
		(stroke
			(width 0.07112)
			(type default)
		)
		(layer "In6.Cu")
	)
	(gr_line
		(start 413.419036 -394.385292)
		(end 413.513778 -394.031724)
		(stroke
			(width 0.07112)
			(type default)
		)
		(layer "In6.Cu")
	)
	(gr_line
		(start 413.48025 -424.044364)
		(end 413.32023 -423.93743)
		(stroke
			(width 0.07112)
			(type default)
		)
		(layer "In6.Cu")
	)
	(gr_line
		(start 413.485076 -391.01395)
		(end 413.349186 -390.87806)
		(stroke
			(width 0.07112)
			(type default)
		)
		(layer "In6.Cu")
	)
	(gr_line
		(start 413.485076 -389.88619)
		(end 413.349186 -389.7503)
		(stroke
			(width 0.07112)
			(type default)
		)
		(layer "In6.Cu")
	)
	(gr_line
		(start 413.485076 -388.75843)
		(end 413.349186 -388.62254)
		(stroke
			(width 0.07112)
			(type default)
		)
		(layer "In6.Cu")
	)
	(gr_line
		(start 413.635444 -393.961112)
		(end 413.688276 -393.930632)
		(stroke
			(width 0.07112)
			(type default)
		)
		(layer "In6.Cu")
	)
	(gr_line
		(start 413.688276 -393.930632)
		(end 413.776414 -393.842494)
		(stroke
			(width 0.07112)
			(type default)
		)
		(layer "In6.Cu")
	)
	(gr_line
		(start 413.768286 -391.01522)
		(end 413.768286 -390.31418)
		(stroke
			(width 0.07112)
			(type default)
		)
		(layer "In6.Cu")
	)
	(gr_line
		(start 413.768286 -389.88746)
		(end 413.768286 -389.18642)
		(stroke
			(width 0.07112)
			(type default)
		)
		(layer "In6.Cu")
	)
	(gr_line
		(start 413.768286 -388.7597)
		(end 413.768286 -388.05866)
		(stroke
			(width 0.07112)
			(type default)
		)
		(layer "In6.Cu")
	)
	(gr_line
		(start 413.776414 -393.842494)
		(end 413.776414 -393.716764)
		(stroke
			(width 0.07112)
			(type default)
		)
		(layer "In6.Cu")
	)
	(gr_line
		(start 413.898842 -423.961306)
		(end 413.48025 -424.044364)
		(stroke
			(width 0.07112)
			(type default)
		)
		(layer "In6.Cu")
	)
	(gr_line
		(start 413.948626 -422.404286)
		(end 413.948626 -422.40454)
		(stroke
			(width 0.07112)
			(type default)
		)
		(layer "In6.Cu")
	)
	(gr_line
		(start 413.951928 -423.52341)
		(end 413.264096 -423.660062)
		(stroke
			(width 0.07112)
			(type default)
		)
		(layer "In6.Cu")
	)
	(gr_line
		(start 414.005776 -423.801286)
		(end 413.898842 -423.961306)
		(stroke
			(width 0.07112)
			(type default)
		)
		(layer "In6.Cu")
	)
	(gr_line
		(start 414.20161 -422.765728)
		(end 414.031938 -422.67505)
		(stroke
			(width 0.07112)
			(type default)
		)
		(layer "In6.Cu")
	)
	(gr_line
		(start 414.218882 -393.69238)
		(end 414.572196 -393.787376)
		(stroke
			(width 0.07112)
			(type default)
		)
		(layer "In6.Cu")
	)
	(gr_line
		(start 414.370266 -423.440098)
		(end 413.951928 -423.52341)
		(stroke
			(width 0.07112)
			(type default)
		)
		(layer "In6.Cu")
	)
	(gr_line
		(start 414.42513 -423.716704)
		(end 414.006792 -423.799762)
		(stroke
			(width 0.07112)
			(type default)
		)
		(layer "In6.Cu")
	)
	(gr_line
		(start 414.50768 -422.234614)
		(end 413.948626 -422.404286)
		(stroke
			(width 0.07112)
			(type default)
		)
		(layer "In6.Cu")
	)
	(gr_line
		(start 414.507934 -422.23436)
		(end 414.50768 -422.234614)
		(stroke
			(width 0.07112)
			(type default)
		)
		(layer "In6.Cu")
	)
	(gr_line
		(start 414.549082 -390.83488)
		(end 414.549082 -390.40816)
		(stroke
			(width 0.07112)
			(type default)
		)
		(layer "In6.Cu")
	)
	(gr_line
		(start 414.549082 -390.40816)
		(end 414.684972 -390.27227)
		(stroke
			(width 0.07112)
			(type default)
		)
		(layer "In6.Cu")
	)
	(gr_line
		(start 414.549082 -389.70712)
		(end 414.549082 -389.2804)
		(stroke
			(width 0.07112)
			(type default)
		)
		(layer "In6.Cu")
	)
	(gr_line
		(start 414.549082 -389.2804)
		(end 414.684972 -389.14451)
		(stroke
			(width 0.07112)
			(type default)
		)
		(layer "In6.Cu")
	)
	(gr_line
		(start 414.572196 -393.787376)
		(end 414.572704 -393.786868)
		(stroke
			(width 0.07112)
			(type default)
		)
		(layer "In6.Cu")
	)
	(gr_line
		(start 414.576768 -387.250686)
		(end 414.597596 -386.82422)
		(stroke
			(width 0.07112)
			(type default)
		)
		(layer "In6.Cu")
	)
	(gr_line
		(start 414.58642 -423.824654)
		(end 414.426654 -423.71772)
		(stroke
			(width 0.07112)
			(type default)
		)
		(layer "In6.Cu")
	)
	(gr_line
		(start 414.597596 -386.82422)
		(end 414.740344 -386.695188)
		(stroke
			(width 0.07112)
			(type default)
		)
		(layer "In6.Cu")
	)
	(gr_line
		(start 414.610296 -422.641776)
		(end 414.20161 -422.765728)
		(stroke
			(width 0.07112)
			(type default)
		)
		(layer "In6.Cu")
	)
	(gr_line
		(start 414.618932 -394.385292)
		(end 414.713674 -394.031724)
		(stroke
			(width 0.07112)
			(type default)
		)
		(layer "In6.Cu")
	)
	(gr_line
		(start 414.619948 -422.200324)
		(end 414.507934 -422.23436)
		(stroke
			(width 0.07112)
			(type default)
		)
		(layer "In6.Cu")
	)
	(gr_arc
		(start 414.634172 -374.73128)
		(mid 414.634299 -374.731407)
		(end 414.634426 -374.731534)
		(stroke
			(width 0.07112)
			(type default)
		)
		(layer "In6.Cu")
	)
	(gr_line
		(start 414.684972 -390.97077)
		(end 414.549082 -390.83488)
		(stroke
			(width 0.07112)
			(type default)
		)
		(layer "In6.Cu")
	)
	(gr_line
		(start 414.684972 -389.84301)
		(end 414.549082 -389.70712)
		(stroke
			(width 0.07112)
			(type default)
		)
		(layer "In6.Cu")
	)
	(gr_line
		(start 414.700974 -422.47185)
		(end 414.610296 -422.641776)
		(stroke
			(width 0.07112)
			(type default)
		)
		(layer "In6.Cu")
	)
	(gr_line
		(start 414.706054 -387.39318)
		(end 414.576768 -387.250686)
		(stroke
			(width 0.07112)
			(type default)
		)
		(layer "In6.Cu")
	)
	(gr_line
		(start 414.741614 -386.693918)
		(end 414.74136 -386.693918)
		(stroke
			(width 0.07112)
			(type default)
		)
		(layer "In6.Cu")
	)
	(gr_line
		(start 414.83534 -393.961112)
		(end 414.888172 -393.930632)
		(stroke
			(width 0.07112)
			(type default)
		)
		(layer "In6.Cu")
	)
	(gr_line
		(start 414.888172 -393.930632)
		(end 414.97631 -393.842494)
		(stroke
			(width 0.07112)
			(type default)
		)
		(layer "In6.Cu")
	)
	(gr_line
		(start 414.968182 -390.97204)
		(end 414.968182 -390.271)
		(stroke
			(width 0.07112)
			(type default)
		)
		(layer "In6.Cu")
	)
	(gr_line
		(start 414.968182 -389.84428)
		(end 414.968182 -389.14324)
		(stroke
			(width 0.07112)
			(type default)
		)
		(layer "In6.Cu")
	)
	(gr_line
		(start 414.97631 -393.842494)
		(end 414.97631 -393.716764)
		(stroke
			(width 0.07112)
			(type default)
		)
		(layer "In6.Cu")
	)
	(gr_line
		(start 414.988756 -387.408166)
		(end 415.023046 -386.707888)
		(stroke
			(width 0.07112)
			(type default)
		)
		(layer "In6.Cu")
	)
	(gr_line
		(start 415.005266 -423.741342)
		(end 414.58642 -423.824654)
		(stroke
			(width 0.07112)
			(type default)
		)
		(layer "In6.Cu")
	)
	(gr_line
		(start 415.031174 -373.131334)
		(end 415.031428 -373.131334)
		(stroke
			(width 0.07112)
			(type default)
		)
		(layer "In6.Cu")
	)
	(gr_line
		(start 415.058098 -423.303446)
		(end 414.370266 -423.440098)
		(stroke
			(width 0.07112)
			(type default)
		)
		(layer "In6.Cu")
	)
	(gr_line
		(start 415.111946 -423.581576)
		(end 415.005266 -423.741342)
		(stroke
			(width 0.07112)
			(type default)
		)
		(layer "In6.Cu")
	)
	(gr_line
		(start 415.168842 -423.281602)
		(end 415.058098 -423.303446)
		(stroke
			(width 0.07112)
			(type default)
		)
		(layer "In6.Cu")
	)
	(gr_line
		(start 415.223706 -423.557954)
		(end 415.112962 -423.580052)
		(stroke
			(width 0.07112)
			(type default)
		)
		(layer "In6.Cu")
	)
	(gr_line
		(start 415.311082 -418.412168)
		(end 415.601912 -418.702998)
		(stroke
			(width 0.07112)
			(type default)
		)
		(layer "In6.Cu")
	)
	(gr_line
		(start 415.419032 -393.69238)
		(end 415.772346 -393.787376)
		(stroke
			(width 0.07112)
			(type default)
		)
		(layer "In6.Cu")
	)
	(gr_line
		(start 415.601912 -420.146988)
		(end 415.601912 -420.709852)
		(stroke
			(width 0.07112)
			(type default)
		)
		(layer "In6.Cu")
	)
	(gr_line
		(start 415.601912 -419.299644)
		(end 415.601912 -419.862508)
		(stroke
			(width 0.07112)
			(type default)
		)
		(layer "In6.Cu")
	)
	(gr_line
		(start 415.601912 -415.09569)
		(end 415.311082 -415.38652)
		(stroke
			(width 0.07112)
			(type default)
		)
		(layer "In6.Cu")
	)
	(gr_line
		(start 415.749232 -389.6233)
		(end 415.749232 -389.19658)
		(stroke
			(width 0.07112)
			(type default)
		)
		(layer "In6.Cu")
	)
	(gr_line
		(start 415.749232 -389.19658)
		(end 415.885122 -389.06069)
		(stroke
			(width 0.07112)
			(type default)
		)
		(layer "In6.Cu")
	)
	(gr_line
		(start 415.749232 -388.49554)
		(end 415.749232 -388.06882)
		(stroke
			(width 0.07112)
			(type default)
		)
		(layer "In6.Cu")
	)
	(gr_line
		(start 415.749232 -388.06882)
		(end 415.885122 -387.93293)
		(stroke
			(width 0.07112)
			(type default)
		)
		(layer "In6.Cu")
	)
	(gr_line
		(start 415.749232 -387.36778)
		(end 415.749232 -386.94106)
		(stroke
			(width 0.07112)
			(type default)
		)
		(layer "In6.Cu")
	)
	(gr_line
		(start 415.749232 -386.94106)
		(end 415.885122 -386.80517)
		(stroke
			(width 0.07112)
			(type default)
		)
		(layer "In6.Cu")
	)
	(gr_line
		(start 415.772346 -393.787376)
		(end 415.772854 -393.786868)
		(stroke
			(width 0.07112)
			(type default)
		)
		(layer "In6.Cu")
	)
	(gr_line
		(start 415.819082 -394.385292)
		(end 415.913824 -394.031724)
		(stroke
			(width 0.07112)
			(type default)
		)
		(layer "In6.Cu")
	)
	(gr_line
		(start 415.883852 -415.09569)
		(end 416.174682 -415.38652)
		(stroke
			(width 0.07112)
			(type default)
		)
		(layer "In6.Cu")
	)
	(gr_line
		(start 415.885122 -420.148258)
		(end 416.023044 -420.28618)
		(stroke
			(width 0.07112)
			(type default)
		)
		(layer "In6.Cu")
	)
	(gr_line
		(start 415.885122 -419.300914)
		(end 416.023044 -419.438836)
		(stroke
			(width 0.07112)
			(type default)
		)
		(layer "In6.Cu")
	)
	(gr_line
		(start 415.885122 -389.75919)
		(end 415.749232 -389.6233)
		(stroke
			(width 0.07112)
			(type default)
		)
		(layer "In6.Cu")
	)
	(gr_line
		(start 415.885122 -388.63143)
		(end 415.749232 -388.49554)
		(stroke
			(width 0.07112)
			(type default)
		)
		(layer "In6.Cu")
	)
	(gr_line
		(start 415.885122 -387.50367)
		(end 415.749232 -387.36778)
		(stroke
			(width 0.07112)
			(type default)
		)
		(layer "In6.Cu")
	)
	(gr_line
		(start 415.922206 -372.097554)
		(end 415.921952 -372.097554)
		(stroke
			(width 0.07112)
			(type default)
		)
		(layer "In6.Cu")
	)
	(gr_line
		(start 415.953448 -376.67438)
		(end 415.953194 -376.674634)
		(stroke
			(width 0.07112)
			(type default)
		)
		(layer "In6.Cu")
	)
	(gr_line
		(start 416.023044 -420.57066)
		(end 415.885122 -420.708582)
		(stroke
			(width 0.07112)
			(type default)
		)
		(layer "In6.Cu")
	)
	(gr_line
		(start 416.023044 -420.28618)
		(end 416.023044 -420.57066)
		(stroke
			(width 0.07112)
			(type default)
		)
		(layer "In6.Cu")
	)
	(gr_line
		(start 416.023044 -419.723316)
		(end 415.885122 -419.861238)
		(stroke
			(width 0.07112)
			(type default)
		)
		(layer "In6.Cu")
	)
	(gr_line
		(start 416.023044 -419.438836)
		(end 416.023044 -419.723316)
		(stroke
			(width 0.07112)
			(type default)
		)
		(layer "In6.Cu")
	)
	(gr_line
		(start 416.03549 -393.961112)
		(end 416.088322 -393.930632)
		(stroke
			(width 0.07112)
			(type default)
		)
		(layer "In6.Cu")
	)
	(gr_line
		(start 416.088322 -393.930632)
		(end 416.17646 -393.842494)
		(stroke
			(width 0.07112)
			(type default)
		)
		(layer "In6.Cu")
	)
	(gr_line
		(start 416.168332 -389.76046)
		(end 416.168332 -389.05942)
		(stroke
			(width 0.07112)
			(type default)
		)
		(layer "In6.Cu")
	)
	(gr_line
		(start 416.168332 -388.6327)
		(end 416.168332 -387.93166)
		(stroke
			(width 0.07112)
			(type default)
		)
		(layer "In6.Cu")
	)
	(gr_line
		(start 416.168332 -387.50494)
		(end 416.168332 -386.8039)
		(stroke
			(width 0.07112)
			(type default)
		)
		(layer "In6.Cu")
	)
	(gr_line
		(start 416.174682 -418.412168)
		(end 415.883852 -418.702998)
		(stroke
			(width 0.07112)
			(type default)
		)
		(layer "In6.Cu")
	)
	(gr_line
		(start 416.17646 -393.842494)
		(end 416.17646 -393.716764)
		(stroke
			(width 0.07112)
			(type default)
		)
		(layer "In6.Cu")
	)
	(gr_line
		(start 416.618928 -393.69238)
		(end 416.972242 -393.787376)
		(stroke
			(width 0.07112)
			(type default)
		)
		(layer "In6.Cu")
	)
	(gr_line
		(start 416.972242 -393.787376)
		(end 416.97275 -393.786868)
		(stroke
			(width 0.07112)
			(type default)
		)
		(layer "In6.Cu")
	)
	(gr_line
		(start 417.00196 -379.406912)
		(end 417.005262 -379.398784)
		(stroke
			(width 0.07112)
			(type default)
		)
		(layer "In6.Cu")
	)
	(gr_line
		(start 417.018978 -394.385292)
		(end 417.11372 -394.031724)
		(stroke
			(width 0.07112)
			(type default)
		)
		(layer "In6.Cu")
	)
	(gr_line
		(start 417.235386 -393.961112)
		(end 417.288218 -393.930632)
		(stroke
			(width 0.07112)
			(type default)
		)
		(layer "In6.Cu")
	)
	(gr_line
		(start 417.26231 -379.514862)
		(end 417.265612 -379.506988)
		(stroke
			(width 0.07112)
			(type default)
		)
		(layer "In6.Cu")
	)
	(gr_line
		(start 417.288218 -393.930632)
		(end 417.376356 -393.842494)
		(stroke
			(width 0.07112)
			(type default)
		)
		(layer "In6.Cu")
	)
	(gr_line
		(start 417.317174 -371.471952)
		(end 417.317682 -371.472206)
		(stroke
			(width 0.07112)
			(type default)
		)
		(layer "In6.Cu")
	)
	(gr_arc
		(start 417.368228 -391.000488)
		(mid 417.368228 -391.000234)
		(end 417.368228 -390.99998)
		(stroke
			(width 0.07112)
			(type default)
		)
		(layer "In6.Cu")
	)
	(gr_line
		(start 417.376356 -393.842494)
		(end 417.376356 -393.716764)
		(stroke
			(width 0.07112)
			(type default)
		)
		(layer "In6.Cu")
	)
	(gr_line
		(start 417.427918 -371.813074)
		(end 417.428172 -371.813074)
		(stroke
			(width 0.07112)
			(type default)
		)
		(layer "In6.Cu")
	)
	(gr_line
		(start 417.469828 -389.59536)
		(end 417.63315 -389.200898)
		(stroke
			(width 0.07112)
			(type default)
		)
		(layer "In6.Cu")
	)
	(gr_line
		(start 417.543488 -389.77316)
		(end 417.469828 -389.59536)
		(stroke
			(width 0.07112)
			(type default)
		)
		(layer "In6.Cu")
	)
	(gr_line
		(start 417.63315 -389.200898)
		(end 417.81095 -389.127238)
		(stroke
			(width 0.07112)
			(type default)
		)
		(layer "In6.Cu")
	)
	(gr_line
		(start 417.8046 -389.88238)
		(end 418.073078 -389.234172)
		(stroke
			(width 0.07112)
			(type default)
		)
		(layer "In6.Cu")
	)
	(gr_line
		(start 417.819078 -393.69238)
		(end 418.172138 -393.787376)
		(stroke
			(width 0.07112)
			(type default)
		)
		(layer "In6.Cu")
	)
	(gr_line
		(start 417.901628 -388.553198)
		(end 418.06495 -388.158736)
		(stroke
			(width 0.07112)
			(type default)
		)
		(layer "In6.Cu")
	)
	(gr_line
		(start 417.975288 -388.730744)
		(end 417.901628 -388.553198)
		(stroke
			(width 0.07112)
			(type default)
		)
		(layer "In6.Cu")
	)
	(gr_line
		(start 418.06495 -388.158736)
		(end 418.24275 -388.085076)
		(stroke
			(width 0.07112)
			(type default)
		)
		(layer "In6.Cu")
	)
	(gr_line
		(start 418.073078 -389.234172)
		(end 418.136578 -389.08101)
		(stroke
			(width 0.07112)
			(type default)
		)
		(layer "In6.Cu")
	)
	(gr_line
		(start 418.172138 -393.787376)
		(end 418.172646 -393.786868)
		(stroke
			(width 0.07112)
			(type default)
		)
		(layer "In6.Cu")
	)
	(gr_line
		(start 418.218874 -394.385292)
		(end 418.313616 -394.031724)
		(stroke
			(width 0.07112)
			(type default)
		)
		(layer "In6.Cu")
	)
	(gr_line
		(start 418.2364 -388.839964)
		(end 418.504878 -388.192264)
		(stroke
			(width 0.07112)
			(type default)
		)
		(layer "In6.Cu")
	)
	(gr_line
		(start 418.374322 -418.412168)
		(end 418.665152 -418.702998)
		(stroke
			(width 0.07112)
			(type default)
		)
		(layer "In6.Cu")
	)
	(gr_line
		(start 418.435282 -393.961112)
		(end 418.488114 -393.930632)
		(stroke
			(width 0.07112)
			(type default)
		)
		(layer "In6.Cu")
	)
	(gr_line
		(start 418.488114 -393.930632)
		(end 418.576252 -393.842494)
		(stroke
			(width 0.07112)
			(type default)
		)
		(layer "In6.Cu")
	)
	(gr_line
		(start 418.540692 -389.964422)
		(end 418.704268 -389.570214)
		(stroke
			(width 0.07112)
			(type default)
		)
		(layer "In6.Cu")
	)
	(gr_line
		(start 418.576252 -393.842494)
		(end 418.576252 -393.716764)
		(stroke
			(width 0.07112)
			(type default)
		)
		(layer "In6.Cu")
	)
	(gr_line
		(start 418.614352 -390.142222)
		(end 418.540692 -389.964422)
		(stroke
			(width 0.07112)
			(type default)
		)
		(layer "In6.Cu")
	)
	(gr_line
		(start 418.665152 -419.478714)
		(end 418.665152 -420.179754)
		(stroke
			(width 0.07112)
			(type default)
		)
		(layer "In6.Cu")
	)
	(gr_line
		(start 418.692076 -415.068766)
		(end 418.374322 -415.38652)
		(stroke
			(width 0.07112)
			(type default)
		)
		(layer "In6.Cu")
	)
	(gr_line
		(start 418.704268 -389.570214)
		(end 418.882068 -389.496554)
		(stroke
			(width 0.07112)
			(type default)
		)
		(layer "In6.Cu")
	)
	(gr_line
		(start 418.875464 -390.251696)
		(end 419.144196 -389.603996)
		(stroke
			(width 0.07112)
			(type default)
		)
		(layer "In6.Cu")
	)
	(gr_line
		(start 418.948362 -419.479984)
		(end 419.084252 -419.615874)
		(stroke
			(width 0.07112)
			(type default)
		)
		(layer "In6.Cu")
	)
	(gr_arc
		(start 418.96157 -375.020332)
		(mid 418.962586 -375.021348)
		(end 418.963602 -375.022364)
		(stroke
			(width 0.07112)
			(type default)
		)
		(layer "In6.Cu")
	)
	(gr_line
		(start 418.972746 -388.922768)
		(end 419.136322 -388.528306)
		(stroke
			(width 0.07112)
			(type default)
		)
		(layer "In6.Cu")
	)
	(gr_arc
		(start 418.973254 -375.031762)
		(mid 418.972365 -375.030999)
		(end 418.971476 -375.030238)
		(stroke
			(width 0.07112)
			(type default)
		)
		(layer "In6.Cu")
	)
	(gr_line
		(start 418.975286 -415.123884)
		(end 419.237922 -415.38652)
		(stroke
			(width 0.07112)
			(type default)
		)
		(layer "In6.Cu")
	)
	(gr_line
		(start 418.975286 -415.067496)
		(end 418.975286 -415.123884)
		(stroke
			(width 0.07112)
			(type default)
		)
		(layer "In6.Cu")
	)
	(gr_line
		(start 419.018974 -393.69238)
		(end 419.372288 -393.787376)
		(stroke
			(width 0.07112)
			(type default)
		)
		(layer "In6.Cu")
	)
	(gr_line
		(start 419.046406 -389.100568)
		(end 418.972746 -388.922768)
		(stroke
			(width 0.07112)
			(type default)
		)
		(layer "In6.Cu")
	)
	(gr_line
		(start 419.084252 -420.042594)
		(end 418.948362 -420.178484)
		(stroke
			(width 0.07112)
			(type default)
		)
		(layer "In6.Cu")
	)
	(gr_line
		(start 419.084252 -419.615874)
		(end 419.084252 -420.042594)
		(stroke
			(width 0.07112)
			(type default)
		)
		(layer "In6.Cu")
	)
	(gr_line
		(start 419.136322 -388.528306)
		(end 419.314122 -388.4549)
		(stroke
			(width 0.07112)
			(type default)
		)
		(layer "In6.Cu")
	)
	(gr_line
		(start 419.237922 -418.412168)
		(end 418.947092 -418.702998)
		(stroke
			(width 0.07112)
			(type default)
		)
		(layer "In6.Cu")
	)
	(gr_line
		(start 419.307518 -389.210042)
		(end 419.576504 -388.562088)
		(stroke
			(width 0.07112)
			(type default)
		)
		(layer "In6.Cu")
	)
	(gr_line
		(start 419.3159 -388.454138)
		(end 419.315646 -388.453884)
		(stroke
			(width 0.07112)
			(type default)
		)
		(layer "In6.Cu")
	)
	(gr_line
		(start 419.372288 -393.787376)
		(end 419.372796 -393.786868)
		(stroke
			(width 0.07112)
			(type default)
		)
		(layer "In6.Cu")
	)
	(gr_line
		(start 419.4048 -387.880606)
		(end 419.568376 -387.486144)
		(stroke
			(width 0.07112)
			(type default)
		)
		(layer "In6.Cu")
	)
	(gr_line
		(start 419.419024 -394.385292)
		(end 419.513766 -394.031724)
		(stroke
			(width 0.07112)
			(type default)
		)
		(layer "In6.Cu")
	)
	(gr_line
		(start 419.47846 -388.05866)
		(end 419.4048 -387.880606)
		(stroke
			(width 0.07112)
			(type default)
		)
		(layer "In6.Cu")
	)
	(gr_line
		(start 419.568376 -387.486144)
		(end 419.74643 -387.412484)
		(stroke
			(width 0.07112)
			(type default)
		)
		(layer "In6.Cu")
	)
	(gr_line
		(start 419.635432 -393.961112)
		(end 419.688264 -393.930632)
		(stroke
			(width 0.07112)
			(type default)
		)
		(layer "In6.Cu")
	)
	(gr_line
		(start 419.688264 -393.930632)
		(end 419.776402 -393.842494)
		(stroke
			(width 0.07112)
			(type default)
		)
		(layer "In6.Cu")
	)
	(gr_line
		(start 419.739826 -388.168134)
		(end 420.008558 -387.52018)
		(stroke
			(width 0.07112)
			(type default)
		)
		(layer "In6.Cu")
	)
	(gr_line
		(start 419.776402 -393.842494)
		(end 419.776402 -393.716764)
		(stroke
			(width 0.07112)
			(type default)
		)
		(layer "In6.Cu")
	)
	(gr_line
		(start 420.219124 -393.69238)
		(end 420.572184 -393.787376)
		(stroke
			(width 0.07112)
			(type default)
		)
		(layer "In6.Cu")
	)
	(gr_line
		(start 420.572184 -393.787376)
		(end 420.572692 -393.786868)
		(stroke
			(width 0.07112)
			(type default)
		)
		(layer "In6.Cu")
	)
	(gr_line
		(start 420.61892 -394.385292)
		(end 420.713662 -394.031724)
		(stroke
			(width 0.07112)
			(type default)
		)
		(layer "In6.Cu")
	)
	(gr_line
		(start 420.835328 -393.961112)
		(end 420.88816 -393.930632)
		(stroke
			(width 0.07112)
			(type default)
		)
		(layer "In6.Cu")
	)
	(gr_line
		(start 420.866316 -390.281668)
		(end 421.029638 -389.887206)
		(stroke
			(width 0.07112)
			(type default)
		)
		(layer "In6.Cu")
	)
	(gr_line
		(start 420.88816 -393.930632)
		(end 420.976298 -393.842494)
		(stroke
			(width 0.07112)
			(type default)
		)
		(layer "In6.Cu")
	)
	(gr_line
		(start 420.939976 -390.459468)
		(end 420.866316 -390.281668)
		(stroke
			(width 0.07112)
			(type default)
		)
		(layer "In6.Cu")
	)
	(gr_line
		(start 420.976298 -393.842494)
		(end 420.976298 -393.716764)
		(stroke
			(width 0.07112)
			(type default)
		)
		(layer "In6.Cu")
	)
	(gr_line
		(start 421.029638 -389.887206)
		(end 421.207438 -389.813546)
		(stroke
			(width 0.07112)
			(type default)
		)
		(layer "In6.Cu")
	)
	(gr_line
		(start 421.047164 -381.316992)
		(end 421.047164 -381.316738)
		(stroke
			(width 0.07112)
			(type default)
		)
		(layer "In6.Cu")
	)
	(gr_line
		(start 421.201342 -390.568688)
		(end 421.469566 -389.92048)
		(stroke
			(width 0.07112)
			(type default)
		)
		(layer "In6.Cu")
	)
	(gr_line
		(start 421.209216 -389.812784)
		(end 421.25519 -389.701786)
		(stroke
			(width 0.07112)
			(type default)
		)
		(layer "In6.Cu")
	)
	(gr_line
		(start 421.298116 -389.239506)
		(end 421.461438 -388.845044)
		(stroke
			(width 0.07112)
			(type default)
		)
		(layer "In6.Cu")
	)
	(gr_line
		(start 421.33901 -381.268224)
		(end 421.33901 -381.268986)
		(stroke
			(width 0.07112)
			(type default)
		)
		(layer "In6.Cu")
	)
	(gr_line
		(start 421.371776 -389.417052)
		(end 421.298116 -389.239506)
		(stroke
			(width 0.07112)
			(type default)
		)
		(layer "In6.Cu")
	)
	(gr_line
		(start 421.41902 -393.69238)
		(end 421.772334 -393.787376)
		(stroke
			(width 0.07112)
			(type default)
		)
		(layer "In6.Cu")
	)
	(gr_line
		(start 421.461438 -388.845044)
		(end 421.639238 -388.771384)
		(stroke
			(width 0.07112)
			(type default)
		)
		(layer "In6.Cu")
	)
	(gr_line
		(start 421.469566 -389.92048)
		(end 421.515794 -389.809482)
		(stroke
			(width 0.07112)
			(type default)
		)
		(layer "In6.Cu")
	)
	(gr_line
		(start 421.632888 -389.526526)
		(end 421.901366 -388.878064)
		(stroke
			(width 0.07112)
			(type default)
		)
		(layer "In6.Cu")
	)
	(gr_line
		(start 421.729916 -388.197344)
		(end 421.893238 -387.802882)
		(stroke
			(width 0.07112)
			(type default)
		)
		(layer "In6.Cu")
	)
	(gr_line
		(start 421.772334 -393.787376)
		(end 421.772842 -393.786868)
		(stroke
			(width 0.07112)
			(type default)
		)
		(layer "In6.Cu")
	)
	(gr_line
		(start 421.803322 -388.37489)
		(end 421.729916 -388.197344)
		(stroke
			(width 0.07112)
			(type default)
		)
		(layer "In6.Cu")
	)
	(gr_line
		(start 421.80383 -388.376414)
		(end 421.804084 -388.376414)
		(stroke
			(width 0.07112)
			(type default)
		)
		(layer "In6.Cu")
	)
	(gr_line
		(start 421.81907 -394.385292)
		(end 421.913812 -394.031724)
		(stroke
			(width 0.07112)
			(type default)
		)
		(layer "In6.Cu")
	)
	(gr_line
		(start 421.893238 -387.802882)
		(end 422.070784 -387.729222)
		(stroke
			(width 0.07112)
			(type default)
		)
		(layer "In6.Cu")
	)
	(gr_line
		(start 422.035478 -393.961112)
		(end 422.08831 -393.930632)
		(stroke
			(width 0.07112)
			(type default)
		)
		(layer "In6.Cu")
	)
	(gr_line
		(start 422.064434 -388.484618)
		(end 422.333166 -387.835902)
		(stroke
			(width 0.07112)
			(type default)
		)
		(layer "In6.Cu")
	)
	(gr_line
		(start 422.072308 -387.728206)
		(end 422.072562 -387.727952)
		(stroke
			(width 0.07112)
			(type default)
		)
		(layer "In6.Cu")
	)
	(gr_line
		(start 422.072816 -387.72846)
		(end 422.072308 -387.728206)
		(stroke
			(width 0.07112)
			(type default)
		)
		(layer "In6.Cu")
	)
	(gr_line
		(start 422.08831 -393.930632)
		(end 422.176448 -393.842494)
		(stroke
			(width 0.07112)
			(type default)
		)
		(layer "In6.Cu")
	)
	(gr_line
		(start 422.176448 -393.842494)
		(end 422.176448 -393.716764)
		(stroke
			(width 0.07112)
			(type default)
		)
		(layer "In6.Cu")
	)
	(gr_line
		(start 423.009822 -380.284482)
		(end 423.009568 -380.284482)
		(stroke
			(width 0.07112)
			(type default)
		)
		(layer "In6.Cu")
	)
	(gr_line
		(start 423.04081 -380.12751)
		(end 423.04081 -380.128272)
		(stroke
			(width 0.07112)
			(type default)
		)
		(layer "In6.Cu")
	)
	(gr_line
		(start 423.650156 -389.667242)
		(end 423.721276 -389.24611)
		(stroke
			(width 0.07112)
			(type default)
		)
		(layer "In6.Cu")
	)
	(gr_line
		(start 423.721276 -389.24611)
		(end 423.878248 -389.135112)
		(stroke
			(width 0.07112)
			(type default)
		)
		(layer "In6.Cu")
	)
	(gr_line
		(start 423.761662 -389.82396)
		(end 423.650156 -389.667242)
		(stroke
			(width 0.07112)
			(type default)
		)
		(layer "In6.Cu")
	)
	(gr_line
		(start 423.879264 -389.133842)
		(end 423.879518 -389.133588)
		(stroke
			(width 0.07112)
			(type default)
		)
		(layer "In6.Cu")
	)
	(gr_line
		(start 423.879772 -389.133842)
		(end 423.879264 -389.133842)
		(stroke
			(width 0.07112)
			(type default)
		)
		(layer "In6.Cu")
	)
	(gr_line
		(start 423.985944 -388.068566)
		(end 424.1038 -387.658102)
		(stroke
			(width 0.07112)
			(type default)
		)
		(layer "In6.Cu")
	)
	(gr_line
		(start 424.040554 -389.87222)
		(end 424.157648 -389.180832)
		(stroke
			(width 0.07112)
			(type default)
		)
		(layer "In6.Cu")
	)
	(gr_line
		(start 424.078908 -388.236714)
		(end 423.985944 -388.068566)
		(stroke
			(width 0.07112)
			(type default)
		)
		(layer "In6.Cu")
	)
	(gr_line
		(start 424.1038 -387.658102)
		(end 424.272202 -387.565138)
		(stroke
			(width 0.07112)
			(type default)
		)
		(layer "In6.Cu")
	)
	(gr_line
		(start 424.350688 -388.316216)
		(end 424.544744 -387.642354)
		(stroke
			(width 0.07112)
			(type default)
		)
		(layer "In6.Cu")
	)
	(gr_line
		(start 424.714416 -381.350774)
		(end 424.714416 -381.350266)
		(stroke
			(width 0.07112)
			(type default)
		)
		(layer "In6.Cu")
	)
	(gr_line
		(start 424.97502 -381.45847)
		(end 424.97502 -381.458216)
		(stroke
			(width 0.07112)
			(type default)
		)
		(layer "In6.Cu")
	)
	(gr_line
		(start 426.542454 -375.401078)
		(end 426.538644 -375.397522)
		(stroke
			(width 0.07112)
			(type default)
		)
		(layer "In6.Cu")
	)
	(gr_line
		(start 426.54601 -375.404888)
		(end 426.546264 -375.404888)
		(stroke
			(width 0.07112)
			(type default)
		)
		(layer "In6.Cu")
	)
	(gr_line
		(start 426.546264 -375.404888)
		(end 426.542454 -375.401078)
		(stroke
			(width 0.07112)
			(type default)
		)
		(layer "In6.Cu")
	)
	(gr_line
		(start 428.38243 -377.541028)
		(end 428.382176 -377.54052)
		(stroke
			(width 0.07112)
			(type default)
		)
		(layer "In6.Cu")
	)
	(gr_line
		(start 428.387764 -377.608592)
		(end 428.387764 -377.585478)
		(stroke
			(width 0.07112)
			(type default)
		)
		(layer "In6.Cu")
	)
	(gr_line
		(start 428.387764 -377.585478)
		(end 428.383954 -377.562364)
		(stroke
			(width 0.07112)
			(type default)
		)
		(layer "In6.Cu")
	)
	(gr_line
		(start 455.694034 -9.780016)
		(end 455.694034 -0.508)
		(stroke
			(width 0.2)
			(type default)
		)
		(layer "In6.Cu")
	)
	(gr_arc
		(start 455.694034 -9.780016)
		(mid 456.428616 -11.553416)
		(end 458.20203 -12.288012)
		(stroke
			(width 0.2)
			(type default)
		)
		(layer "In6.Cu")
	)
	(gr_line
		(start 455.694034 -0.508)
		(end 388.109968 -0.508)
		(stroke
			(width 0.2)
			(type default)
		)
		(layer "In6.Cu")
	)
	(gr_arc
		(start 458.71003 -7.78002)
		(mid 459.147026 -8.83502)
		(end 460.202026 -9.272016)
		(stroke
			(width 0.2)
			(type default)
		)
		(layer "In6.Cu")
	)
	(gr_arc
		(start 458.71003 0.40005)
		(mid 457.975475 2.173515)
		(end 456.202034 2.908046)
		(stroke
			(width 0.2)
			(type default)
		)
		(layer "In6.Cu")
	)
	(gr_line
		(start 458.71003 0.40005)
		(end 458.71003 -7.78002)
		(stroke
			(width 0.2)
			(type default)
		)
		(layer "In6.Cu")
	)
	(gr_line
		(start 460.202026 -9.272016)
		(end 464.439 -9.272016)
		(stroke
			(width 0.2)
			(type default)
		)
		(layer "In6.Cu")
	)
	(gr_arc
		(start 463.300064 -441.481972)
		(mid 464.355064 -441.044976)
		(end 464.79206 -439.989976)
		(stroke
			(width 0.2)
			(type default)
		)
		(layer "In6.Cu")
	)
	(gr_line
		(start 464.439 -12.288012)
		(end 458.20203 -12.288012)
		(stroke
			(width 0.2)
			(type default)
		)
		(layer "In6.Cu")
	)
	(gr_line
		(start 464.439 -9.272016)
		(end 464.439 -12.288012)
		(stroke
			(width 0.2)
			(type default)
		)
		(layer "In6.Cu")
	)
	(gr_line
		(start 464.447636 -12.288012)
		(end 464.447636 -9.272016)
		(stroke
			(width 0.2)
			(type default)
		)
		(layer "In6.Cu")
	)
	(gr_line
		(start 464.447636 -9.272016)
		(end 469.799924 -9.272016)
		(stroke
			(width 0.2)
			(type default)
		)
		(layer "In6.Cu")
	)
	(gr_line
		(start 464.79206 -439.989976)
		(end 464.79206 -418.46881)
		(stroke
			(width 0.2)
			(type default)
		)
		(layer "In6.Cu")
	)
	(gr_line
		(start 464.79206 -418.46881)
		(end 467.808056 -418.46881)
		(stroke
			(width 0.2)
			(type default)
		)
		(layer "In6.Cu")
	)
	(gr_line
		(start 464.79206 -418.45738)
		(end 464.79206 -409.528264)
		(stroke
			(width 0.2)
			(type default)
		)
		(layer "In6.Cu")
	)
	(gr_arc
		(start 465.526628 -407.75509)
		(mid 464.983024 -408.568632)
		(end 464.79206 -409.528264)
		(stroke
			(width 0.2)
			(type default)
		)
		(layer "In6.Cu")
	)
	(gr_line
		(start 465.526628 -407.75509)
		(end 467.355174 -405.926544)
		(stroke
			(width 0.2)
			(type default)
		)
		(layer "In6.Cu")
	)
	(gr_arc
		(start 467.355174 -405.926544)
		(mid 467.678507 -405.442687)
		(end 467.792054 -404.871936)
		(stroke
			(width 0.2)
			(type default)
		)
		(layer "In6.Cu")
	)
	(gr_line
		(start 467.792054 -404.871936)
		(end 467.792054 -82.82813)
		(stroke
			(width 0.2)
			(type default)
		)
		(layer "In6.Cu")
	)
	(gr_arc
		(start 467.808056 -439.989976)
		(mid 468.245052 -441.044976)
		(end 469.300052 -441.481972)
		(stroke
			(width 0.2)
			(type default)
		)
		(layer "In6.Cu")
	)
	(gr_line
		(start 467.808056 -418.46881)
		(end 467.808056 -439.989976)
		(stroke
			(width 0.2)
			(type default)
		)
		(layer "In6.Cu")
	)
	(gr_line
		(start 467.808056 -418.45738)
		(end 464.79206 -418.45738)
		(stroke
			(width 0.2)
			(type default)
		)
		(layer "In6.Cu")
	)
	(gr_line
		(start 467.808056 -410.356812)
		(end 467.808056 -418.45738)
		(stroke
			(width 0.2)
			(type default)
		)
		(layer "In6.Cu")
	)
	(gr_arc
		(start 468.244936 -409.30195)
		(mid 467.921608 -409.785939)
		(end 467.808056 -410.356812)
		(stroke
			(width 0.2)
			(type default)
		)
		(layer "In6.Cu")
	)
	(gr_arc
		(start 468.526622 -81.054956)
		(mid 467.983009 -81.868496)
		(end 467.792054 -82.82813)
		(stroke
			(width 0.2)
			(type default)
		)
		(layer "In6.Cu")
	)
	(gr_line
		(start 468.526622 -81.054956)
		(end 470.85504 -78.726538)
		(stroke
			(width 0.2)
			(type default)
		)
		(layer "In6.Cu")
	)
	(gr_line
		(start 469.300052 -441.481972)
		(end 471.79992 -441.481972)
		(stroke
			(width 0.2)
			(type default)
		)
		(layer "In6.Cu")
	)
	(gr_line
		(start 469.487758 -408.059128)
		(end 468.244936 -409.30195)
		(stroke
			(width 0.2)
			(type default)
		)
		(layer "In6.Cu")
	)
	(gr_arc
		(start 469.487758 -408.059128)
		(mid 470.464844 -406.596826)
		(end 470.80805 -404.871936)
		(stroke
			(width 0.2)
			(type default)
		)
		(layer "In6.Cu")
	)
	(gr_line
		(start 469.799924 -12.288012)
		(end 464.447636 -12.288012)
		(stroke
			(width 0.2)
			(type default)
		)
		(layer "In6.Cu")
	)
	(gr_arc
		(start 469.799924 -9.272016)
		(mid 470.854924 -8.83502)
		(end 471.29192 -7.78002)
		(stroke
			(width 0.2)
			(type default)
		)
		(layer "In6.Cu")
	)
	(gr_line
		(start 469.799924 11.892026)
		(end 1.999996 11.892026)
		(stroke
			(width 0.2)
			(type default)
		)
		(layer "In6.Cu")
	)
	(gr_line
		(start 470.80805 -83.656678)
		(end 470.80805 -404.871936)
		(stroke
			(width 0.2)
			(type default)
		)
		(layer "In6.Cu")
	)
	(gr_arc
		(start 470.85504 -78.726538)
		(mid 471.178373 -78.242681)
		(end 471.29192 -77.67193)
		(stroke
			(width 0.2)
			(type default)
		)
		(layer "In6.Cu")
	)
	(gr_arc
		(start 471.245184 -82.601562)
		(mid 470.921671 -83.085639)
		(end 470.80805 -83.656678)
		(stroke
			(width 0.2)
			(type default)
		)
		(layer "In6.Cu")
	)
	(gr_line
		(start 471.29192 -77.67193)
		(end 471.29192 -13.780008)
		(stroke
			(width 0.2)
			(type default)
		)
		(layer "In6.Cu")
	)
	(gr_arc
		(start 471.29192 -13.780008)
		(mid 470.854924 -12.725008)
		(end 469.799924 -12.288012)
		(stroke
			(width 0.2)
			(type default)
		)
		(layer "In6.Cu")
	)
	(gr_line
		(start 471.29192 -7.78002)
		(end 471.29192 10.40003)
		(stroke
			(width 0.2)
			(type default)
		)
		(layer "In6.Cu")
	)
	(gr_arc
		(start 471.29192 10.40003)
		(mid 470.854924 11.45503)
		(end 469.799924 11.892026)
		(stroke
			(width 0.2)
			(type default)
		)
		(layer "In6.Cu")
	)
	(gr_line
		(start 472.987624 -80.859122)
		(end 471.245184 -82.601562)
		(stroke
			(width 0.2)
			(type default)
		)
		(layer "In6.Cu")
	)
	(gr_arc
		(start 472.987624 -80.859122)
		(mid 473.964715 -79.396821)
		(end 474.307916 -77.67193)
		(stroke
			(width 0.2)
			(type default)
		)
		(layer "In6.Cu")
	)
	(gr_arc
		(start 474.307916 -461.028288)
		(mid 474.744912 -462.083288)
		(end 475.799912 -462.520284)
		(stroke
			(width 0.2)
			(type default)
		)
		(layer "In6.Cu")
	)
	(gr_arc
		(start 474.307916 -443.989968)
		(mid 473.573331 -442.216561)
		(end 471.79992 -441.481972)
		(stroke
			(width 0.2)
			(type default)
		)
		(layer "In6.Cu")
	)
	(gr_line
		(start 474.307916 -443.989968)
		(end 474.307916 -461.028288)
		(stroke
			(width 0.2)
			(type default)
		)
		(layer "In6.Cu")
	)
	(gr_line
		(start 474.307916 10.40003)
		(end 474.307916 -77.67193)
		(stroke
			(width 0.2)
			(type default)
		)
		(layer "In6.Cu")
	)
	(gr_line
		(start 475.799912 -462.520284)
		(end 531.7998 -462.520284)
		(stroke
			(width 0.2)
			(type default)
		)
		(layer "In6.Cu")
	)
	(gr_arc
		(start 475.799912 11.892026)
		(mid 474.744912 11.45503)
		(end 474.307916 10.40003)
		(stroke
			(width 0.2)
			(type default)
		)
		(layer "In6.Cu")
	)
	(gr_line
		(start 513.5118 -451.028308)
		(end 513.5118 -312.408316)
		(stroke
			(width 0.2)
			(type default)
		)
		(layer "In6.Cu")
	)
	(gr_arc
		(start 513.5118 -451.028308)
		(mid 514.246378 -452.801725)
		(end 516.019796 -453.536304)
		(stroke
			(width 0.2)
			(type default)
		)
		(layer "In6.Cu")
	)
	(gr_arc
		(start 516.019796 -309.90032)
		(mid 514.246383 -310.634897)
		(end 513.5118 -312.408316)
		(stroke
			(width 0.2)
			(type default)
		)
		(layer "In6.Cu")
	)
	(gr_line
		(start 516.019796 -309.90032)
		(end 531.7998 -309.90032)
		(stroke
			(width 0.2)
			(type default)
		)
		(layer "In6.Cu")
	)
	(gr_arc
		(start 531.7998 -462.520284)
		(mid 532.8548 -462.083288)
		(end 533.291796 -461.028288)
		(stroke
			(width 0.2)
			(type default)
		)
		(layer "In6.Cu")
	)
	(gr_line
		(start 531.7998 -453.536304)
		(end 516.019796 -453.536304)
		(stroke
			(width 0.2)
			(type default)
		)
		(layer "In6.Cu")
	)
	(gr_arc
		(start 531.7998 -309.90032)
		(mid 532.8548 -309.463324)
		(end 533.291796 -308.408324)
		(stroke
			(width 0.2)
			(type default)
		)
		(layer "In6.Cu")
	)
	(gr_line
		(start 531.7998 11.892026)
		(end 475.799912 11.892026)
		(stroke
			(width 0.2)
			(type default)
		)
		(layer "In6.Cu")
	)
	(gr_line
		(start 533.291796 -461.028288)
		(end 533.291796 -455.0283)
		(stroke
			(width 0.2)
			(type default)
		)
		(layer "In6.Cu")
	)
	(gr_arc
		(start 533.291796 -455.0283)
		(mid 532.8548 -453.9733)
		(end 531.7998 -453.536304)
		(stroke
			(width 0.2)
			(type default)
		)
		(layer "In6.Cu")
	)
	(gr_line
		(start 533.291796 -308.408324)
		(end 533.291796 10.40003)
		(stroke
			(width 0.2)
			(type default)
		)
		(layer "In6.Cu")
	)
	(gr_arc
		(start 533.291796 10.40003)
		(mid 532.8548 11.45503)
		(end 531.7998 11.892026)
		(stroke
			(width 0.2)
			(type default)
		)
		(layer "In6.Cu")
	)
	(gr_line
		(start 0 -77.671676)
		(end 0 -13.780008)
		(stroke
			(width 1.016)
			(type default)
		)
		(layer "In7.Cu")
	)
	(gr_arc
		(start 0 -77.671676)
		(mid 0.152237 -78.436936)
		(end 0.585724 -79.085694)
		(stroke
			(width 1.016)
			(type default)
		)
		(layer "In7.Cu")
	)
	(gr_poly
		(pts
			(arc
				(start 279.248108 -392.23696)
				(mid 279.284029 -392.222081)
				(end 279.298908 -392.18616)
			)
			(arc
				(start 279.298908 -383.93116)
				(mid 279.284029 -383.895239)
				(end 279.248108 -383.88036)
			)
			(arc
				(start 275.026374 -383.88036)
				(mid 275.006851 -383.884261)
				(end 274.990306 -383.895346)
			)
			(arc
				(start 274.766278 -384.119374)
				(mid 274.755167 -384.135908)
				(end 274.751292 -384.155442)
			)
			(arc
				(start 274.751292 -392.107928)
				(mid 274.755193 -392.127451)
				(end 274.766278 -392.143996)
			)
			(arc
				(start 274.844256 -392.221974)
				(mid 274.86079 -392.233085)
				(end 274.880324 -392.23696)
			)
		)
		(stroke
			(width 0)
			(type solid)
		)
		(fill yes)
		(layer "In7.Cu")
		(net "P12V_MAIN_R_0")
	)
	(gr_poly
		(pts
			(arc
				(start 98.184208 -278.13635)
				(mid 97.777808 -278.13635)
				(end 98.184208 -278.13635)
			)
		)
		(stroke
			(width 0)
			(type solid)
		)
		(fill yes)
		(layer "In7.Cu")
		(net "P5E_CPU1_P1_RX_DN<1>")
	)
	(gr_poly
		(pts
			(arc
				(start 98.184208 -276.516338)
				(mid 97.777808 -276.516338)
				(end 98.184208 -276.516338)
			)
		)
		(stroke
			(width 0)
			(type solid)
		)
		(fill yes)
		(layer "In7.Cu")
		(net "P5E_CPU1_P1_RX_DN<0>")
	)
	(gr_poly
		(pts
			(arc
				(start 98.184208 -274.896326)
				(mid 97.777808 -274.896326)
				(end 98.184208 -274.896326)
			)
		)
		(stroke
			(width 0)
			(type solid)
		)
		(fill yes)
		(layer "In7.Cu")
		(net "P5E_CPU1_P1_RX_DN<2>")
	)
	(gr_poly
		(pts
			(arc
				(start 98.184208 -273.276314)
				(mid 97.777808 -273.276314)
				(end 98.184208 -273.276314)
			)
		)
		(stroke
			(width 0)
			(type solid)
		)
		(fill yes)
		(layer "In7.Cu")
		(net "P5E_CPU1_P0_RX_DN<1>")
	)
	(gr_poly
		(pts
			(arc
				(start 98.184208 -271.656302)
				(mid 97.777808 -271.656302)
				(end 98.184208 -271.656302)
			)
		)
		(stroke
			(width 0)
			(type solid)
		)
		(fill yes)
		(layer "In7.Cu")
		(net "P5E_CPU1_P0_RX_DN<0>")
	)
	(gr_poly
		(pts
			(arc
				(start 98.184208 -270.03629)
				(mid 97.777808 -270.03629)
				(end 98.184208 -270.03629)
			)
		)
		(stroke
			(width 0)
			(type solid)
		)
		(fill yes)
		(layer "In7.Cu")
		(net "P5E_CPU1_P0_RX_DN<2>")
	)
	(gr_poly
		(pts
			(arc
				(start 99.124262 -278.13635)
				(mid 98.717862 -278.13635)
				(end 99.124262 -278.13635)
			)
		)
		(stroke
			(width 0)
			(type solid)
		)
		(fill yes)
		(layer "In7.Cu")
		(net "P5E_CPU1_P1_RX_DP<1>")
	)
	(gr_poly
		(pts
			(arc
				(start 99.124262 -276.516338)
				(mid 98.717862 -276.516338)
				(end 99.124262 -276.516338)
			)
		)
		(stroke
			(width 0)
			(type solid)
		)
		(fill yes)
		(layer "In7.Cu")
		(net "P5E_CPU1_P1_RX_DP<0>")
	)
	(gr_poly
		(pts
			(arc
				(start 99.124262 -274.896326)
				(mid 98.717862 -274.896326)
				(end 99.124262 -274.896326)
			)
		)
		(stroke
			(width 0)
			(type solid)
		)
		(fill yes)
		(layer "In7.Cu")
		(net "P5E_CPU1_P1_RX_DP<2>")
	)
	(gr_poly
		(pts
			(arc
				(start 99.124262 -273.276314)
				(mid 98.717862 -273.276314)
				(end 99.124262 -273.276314)
			)
		)
		(stroke
			(width 0)
			(type solid)
		)
		(fill yes)
		(layer "In7.Cu")
		(net "P5E_CPU1_P0_RX_DP<1>")
	)
	(gr_poly
		(pts
			(arc
				(start 99.124262 -271.656302)
				(mid 98.717862 -271.656302)
				(end 99.124262 -271.656302)
			)
		)
		(stroke
			(width 0)
			(type solid)
		)
		(fill yes)
		(layer "In7.Cu")
		(net "P5E_CPU1_P0_RX_DP<0>")
	)
	(gr_poly
		(pts
			(arc
				(start 99.124262 -270.03629)
				(mid 98.717862 -270.03629)
				(end 99.124262 -270.03629)
			)
		)
		(stroke
			(width 0)
			(type solid)
		)
		(fill yes)
		(layer "In7.Cu")
		(net "P5E_CPU1_P0_RX_DP<2>")
	)
	(gr_poly
		(pts
			(arc
				(start 101.004116 -278.13635)
				(mid 100.597716 -278.13635)
				(end 101.004116 -278.13635)
			)
		)
		(stroke
			(width 0)
			(type solid)
		)
		(fill yes)
		(layer "In7.Cu")
		(net "P5E_CPU1_P1_RX_DN<4>")
	)
	(gr_poly
		(pts
			(arc
				(start 101.004116 -276.516338)
				(mid 100.597716 -276.516338)
				(end 101.004116 -276.516338)
			)
		)
		(stroke
			(width 0)
			(type solid)
		)
		(fill yes)
		(layer "In7.Cu")
		(net "P5E_CPU1_P1_RX_DN<3>")
	)
	(gr_poly
		(pts
			(arc
				(start 101.004116 -274.896326)
				(mid 100.597716 -274.896326)
				(end 101.004116 -274.896326)
			)
		)
		(stroke
			(width 0)
			(type solid)
		)
		(fill yes)
		(layer "In7.Cu")
		(net "P5E_CPU1_P1_RX_DN<5>")
	)
	(gr_poly
		(pts
			(arc
				(start 101.004116 -273.276314)
				(mid 100.597716 -273.276314)
				(end 101.004116 -273.276314)
			)
		)
		(stroke
			(width 0)
			(type solid)
		)
		(fill yes)
		(layer "In7.Cu")
		(net "P5E_CPU1_P0_RX_DN<4>")
	)
	(gr_poly
		(pts
			(arc
				(start 101.004116 -271.656302)
				(mid 100.597716 -271.656302)
				(end 101.004116 -271.656302)
			)
		)
		(stroke
			(width 0)
			(type solid)
		)
		(fill yes)
		(layer "In7.Cu")
		(net "P5E_CPU1_P0_RX_DN<3>")
	)
	(gr_poly
		(pts
			(arc
				(start 101.004116 -270.03629)
				(mid 100.597716 -270.03629)
				(end 101.004116 -270.03629)
			)
		)
		(stroke
			(width 0)
			(type solid)
		)
		(fill yes)
		(layer "In7.Cu")
		(net "P5E_CPU1_P0_RX_DN<5>")
	)
	(gr_poly
		(pts
			(arc
				(start 101.94417 -278.13635)
				(mid 101.53777 -278.13635)
				(end 101.94417 -278.13635)
			)
		)
		(stroke
			(width 0)
			(type solid)
		)
		(fill yes)
		(layer "In7.Cu")
		(net "P5E_CPU1_P1_RX_DP<4>")
	)
	(gr_poly
		(pts
			(arc
				(start 101.94417 -276.516338)
				(mid 101.53777 -276.516338)
				(end 101.94417 -276.516338)
			)
		)
		(stroke
			(width 0)
			(type solid)
		)
		(fill yes)
		(layer "In7.Cu")
		(net "P5E_CPU1_P1_RX_DP<3>")
	)
	(gr_poly
		(pts
			(arc
				(start 101.94417 -274.896326)
				(mid 101.53777 -274.896326)
				(end 101.94417 -274.896326)
			)
		)
		(stroke
			(width 0)
			(type solid)
		)
		(fill yes)
		(layer "In7.Cu")
		(net "P5E_CPU1_P1_RX_DP<5>")
	)
	(gr_poly
		(pts
			(arc
				(start 101.94417 -273.276314)
				(mid 101.53777 -273.276314)
				(end 101.94417 -273.276314)
			)
		)
		(stroke
			(width 0)
			(type solid)
		)
		(fill yes)
		(layer "In7.Cu")
		(net "P5E_CPU1_P0_RX_DP<4>")
	)
	(gr_poly
		(pts
			(arc
				(start 101.94417 -271.656302)
				(mid 101.53777 -271.656302)
				(end 101.94417 -271.656302)
			)
		)
		(stroke
			(width 0)
			(type solid)
		)
		(fill yes)
		(layer "In7.Cu")
		(net "P5E_CPU1_P0_RX_DP<3>")
	)
	(gr_poly
		(pts
			(arc
				(start 101.94417 -270.03629)
				(mid 101.53777 -270.03629)
				(end 101.94417 -270.03629)
			)
		)
		(stroke
			(width 0)
			(type solid)
		)
		(fill yes)
		(layer "In7.Cu")
		(net "P5E_CPU1_P0_RX_DP<5>")
	)
	(gr_poly
		(pts
			(arc
				(start 103.824278 -278.13635)
				(mid 103.417878 -278.13635)
				(end 103.824278 -278.13635)
			)
		)
		(stroke
			(width 0)
			(type solid)
		)
		(fill yes)
		(layer "In7.Cu")
		(net "P5E_CPU1_P1_RX_DN<7>")
	)
	(gr_poly
		(pts
			(arc
				(start 103.824278 -276.516338)
				(mid 103.417878 -276.516338)
				(end 103.824278 -276.516338)
			)
		)
		(stroke
			(width 0)
			(type solid)
		)
		(fill yes)
		(layer "In7.Cu")
		(net "P5E_CPU1_P1_RX_DN<6>")
	)
	(gr_poly
		(pts
			(arc
				(start 103.824278 -274.896326)
				(mid 103.417878 -274.896326)
				(end 103.824278 -274.896326)
			)
		)
		(stroke
			(width 0)
			(type solid)
		)
		(fill yes)
		(layer "In7.Cu")
		(net "P5E_CPU1_P1_RX_DN<8>")
	)
	(gr_poly
		(pts
			(arc
				(start 103.824278 -273.276314)
				(mid 103.417878 -273.276314)
				(end 103.824278 -273.276314)
			)
		)
		(stroke
			(width 0)
			(type solid)
		)
		(fill yes)
		(layer "In7.Cu")
		(net "P5E_CPU1_P0_RX_DN<7>")
	)
	(gr_poly
		(pts
			(arc
				(start 103.824278 -271.656302)
				(mid 103.417878 -271.656302)
				(end 103.824278 -271.656302)
			)
		)
		(stroke
			(width 0)
			(type solid)
		)
		(fill yes)
		(layer "In7.Cu")
		(net "P5E_CPU1_P0_RX_DN<6>")
	)
	(gr_poly
		(pts
			(arc
				(start 103.824278 -270.03629)
				(mid 103.417878 -270.03629)
				(end 103.824278 -270.03629)
			)
		)
		(stroke
			(width 0)
			(type solid)
		)
		(fill yes)
		(layer "In7.Cu")
		(net "P5E_CPU1_P0_RX_DN<8>")
	)
	(gr_poly
		(pts
			(arc
				(start 104.764332 -278.13635)
				(mid 104.357932 -278.13635)
				(end 104.764332 -278.13635)
			)
		)
		(stroke
			(width 0)
			(type solid)
		)
		(fill yes)
		(layer "In7.Cu")
		(net "P5E_CPU1_P1_RX_DP<7>")
	)
	(gr_poly
		(pts
			(arc
				(start 104.764332 -276.516338)
				(mid 104.357932 -276.516338)
				(end 104.764332 -276.516338)
			)
		)
		(stroke
			(width 0)
			(type solid)
		)
		(fill yes)
		(layer "In7.Cu")
		(net "P5E_CPU1_P1_RX_DP<6>")
	)
	(gr_poly
		(pts
			(arc
				(start 104.764332 -274.896326)
				(mid 104.357932 -274.896326)
				(end 104.764332 -274.896326)
			)
		)
		(stroke
			(width 0)
			(type solid)
		)
		(fill yes)
		(layer "In7.Cu")
		(net "P5E_CPU1_P1_RX_DP<8>")
	)
	(gr_poly
		(pts
			(arc
				(start 104.764332 -273.276314)
				(mid 104.357932 -273.276314)
				(end 104.764332 -273.276314)
			)
		)
		(stroke
			(width 0)
			(type solid)
		)
		(fill yes)
		(layer "In7.Cu")
		(net "P5E_CPU1_P0_RX_DP<7>")
	)
	(gr_poly
		(pts
			(arc
				(start 104.764332 -271.656302)
				(mid 104.357932 -271.656302)
				(end 104.764332 -271.656302)
			)
		)
		(stroke
			(width 0)
			(type solid)
		)
		(fill yes)
		(layer "In7.Cu")
		(net "P5E_CPU1_P0_RX_DP<6>")
	)
	(gr_poly
		(pts
			(arc
				(start 104.764332 -270.03629)
				(mid 104.357932 -270.03629)
				(end 104.764332 -270.03629)
			)
		)
		(stroke
			(width 0)
			(type solid)
		)
		(fill yes)
		(layer "In7.Cu")
		(net "P5E_CPU1_P0_RX_DP<8>")
	)
	(gr_poly
		(pts
			(arc
				(start 106.644186 -279.756362)
				(mid 106.237786 -279.756362)
				(end 106.644186 -279.756362)
			)
		)
		(stroke
			(width 0)
			(type solid)
		)
		(fill yes)
		(layer "In7.Cu")
		(net "P5E_CPU1_P1_RX_DN<11>")
	)
	(gr_poly
		(pts
			(arc
				(start 106.644186 -278.13635)
				(mid 106.237786 -278.13635)
				(end 106.644186 -278.13635)
			)
		)
		(stroke
			(width 0)
			(type solid)
		)
		(fill yes)
		(layer "In7.Cu")
		(net "P5E_CPU1_P1_RX_DN<10>")
	)
	(gr_poly
		(pts
			(arc
				(start 106.644186 -276.516338)
				(mid 106.237786 -276.516338)
				(end 106.644186 -276.516338)
			)
		)
		(stroke
			(width 0)
			(type solid)
		)
		(fill yes)
		(layer "In7.Cu")
		(net "P5E_CPU1_P1_RX_DN<9>")
	)
	(gr_poly
		(pts
			(arc
				(start 106.644186 -274.896326)
				(mid 106.237786 -274.896326)
				(end 106.644186 -274.896326)
			)
		)
		(stroke
			(width 0)
			(type solid)
		)
		(fill yes)
		(layer "In7.Cu")
		(net "P5E_CPU1_P1_RX_DN<12>")
	)
	(gr_poly
		(pts
			(arc
				(start 106.644186 -273.276314)
				(mid 106.237786 -273.276314)
				(end 106.644186 -273.276314)
			)
		)
		(stroke
			(width 0)
			(type solid)
		)
		(fill yes)
		(layer "In7.Cu")
		(net "P5E_CPU1_P0_RX_DN<10>")
	)
	(gr_poly
		(pts
			(arc
				(start 106.644186 -271.656302)
				(mid 106.237786 -271.656302)
				(end 106.644186 -271.656302)
			)
		)
		(stroke
			(width 0)
			(type solid)
		)
		(fill yes)
		(layer "In7.Cu")
		(net "P5E_CPU1_P0_RX_DN<9>")
	)
	(gr_poly
		(pts
			(arc
				(start 106.644186 -270.03629)
				(mid 106.237786 -270.03629)
				(end 106.644186 -270.03629)
			)
		)
		(stroke
			(width 0)
			(type solid)
		)
		(fill yes)
		(layer "In7.Cu")
		(net "P5E_CPU1_P0_RX_DN<11>")
	)
	(gr_poly
		(pts
			(arc
				(start 107.58424 -279.756362)
				(mid 107.17784 -279.756362)
				(end 107.58424 -279.756362)
			)
		)
		(stroke
			(width 0)
			(type solid)
		)
		(fill yes)
		(layer "In7.Cu")
		(net "P5E_CPU1_P1_RX_DP<11>")
	)
	(gr_poly
		(pts
			(arc
				(start 107.58424 -278.13635)
				(mid 107.17784 -278.13635)
				(end 107.58424 -278.13635)
			)
		)
		(stroke
			(width 0)
			(type solid)
		)
		(fill yes)
		(layer "In7.Cu")
		(net "P5E_CPU1_P1_RX_DP<10>")
	)
	(gr_poly
		(pts
			(arc
				(start 107.58424 -276.516338)
				(mid 107.17784 -276.516338)
				(end 107.58424 -276.516338)
			)
		)
		(stroke
			(width 0)
			(type solid)
		)
		(fill yes)
		(layer "In7.Cu")
		(net "P5E_CPU1_P1_RX_DP<9>")
	)
	(gr_poly
		(pts
			(arc
				(start 107.58424 -274.896326)
				(mid 107.17784 -274.896326)
				(end 107.58424 -274.896326)
			)
		)
		(stroke
			(width 0)
			(type solid)
		)
		(fill yes)
		(layer "In7.Cu")
		(net "P5E_CPU1_P1_RX_DP<12>")
	)
	(gr_poly
		(pts
			(arc
				(start 107.58424 -273.276314)
				(mid 107.17784 -273.276314)
				(end 107.58424 -273.276314)
			)
		)
		(stroke
			(width 0)
			(type solid)
		)
		(fill yes)
		(layer "In7.Cu")
		(net "P5E_CPU1_P0_RX_DP<10>")
	)
	(gr_poly
		(pts
			(arc
				(start 107.58424 -271.656302)
				(mid 107.17784 -271.656302)
				(end 107.58424 -271.656302)
			)
		)
		(stroke
			(width 0)
			(type solid)
		)
		(fill yes)
		(layer "In7.Cu")
		(net "P5E_CPU1_P0_RX_DP<9>")
	)
	(gr_poly
		(pts
			(arc
				(start 107.58424 -270.03629)
				(mid 107.17784 -270.03629)
				(end 107.58424 -270.03629)
			)
		)
		(stroke
			(width 0)
			(type solid)
		)
		(fill yes)
		(layer "In7.Cu")
		(net "P5E_CPU1_P0_RX_DP<11>")
	)
	(gr_poly
		(pts
			(arc
				(start 108.994194 -278.946356)
				(mid 108.587794 -278.946356)
				(end 108.994194 -278.946356)
			)
		)
		(stroke
			(width 0)
			(type solid)
		)
		(fill yes)
		(layer "In7.Cu")
		(net "P5E_CPU1_P1_RX_DN<13>")
	)
	(gr_poly
		(pts
			(arc
				(start 108.994194 -277.326344)
				(mid 108.587794 -277.326344)
				(end 108.994194 -277.326344)
			)
		)
		(stroke
			(width 0)
			(type solid)
		)
		(fill yes)
		(layer "In7.Cu")
		(net "P5E_CPU1_P1_RX_DN<14>")
	)
	(gr_poly
		(pts
			(arc
				(start 108.994194 -275.706332)
				(mid 108.587794 -275.706332)
				(end 108.994194 -275.706332)
			)
		)
		(stroke
			(width 0)
			(type solid)
		)
		(fill yes)
		(layer "In7.Cu")
		(net "P5E_CPU1_P1_RX_DN<15>")
	)
	(gr_poly
		(pts
			(arc
				(start 108.994194 -274.08632)
				(mid 108.587794 -274.08632)
				(end 108.994194 -274.08632)
			)
		)
		(stroke
			(width 0)
			(type solid)
		)
		(fill yes)
		(layer "In7.Cu")
		(net "P5E_CPU1_P0_RX_DN<13>")
	)
	(gr_poly
		(pts
			(arc
				(start 108.994194 -272.466308)
				(mid 108.587794 -272.466308)
				(end 108.994194 -272.466308)
			)
		)
		(stroke
			(width 0)
			(type solid)
		)
		(fill yes)
		(layer "In7.Cu")
		(net "P5E_CPU1_P0_RX_DN<12>")
	)
	(gr_poly
		(pts
			(arc
				(start 108.994194 -270.846296)
				(mid 108.587794 -270.846296)
				(end 108.994194 -270.846296)
			)
		)
		(stroke
			(width 0)
			(type solid)
		)
		(fill yes)
		(layer "In7.Cu")
		(net "P5E_CPU1_P0_RX_DN<14>")
	)
	(gr_poly
		(pts
			(arc
				(start 108.994194 -269.226284)
				(mid 108.587794 -269.226284)
				(end 108.994194 -269.226284)
			)
		)
		(stroke
			(width 0)
			(type solid)
		)
		(fill yes)
		(layer "In7.Cu")
		(net "P5E_CPU1_P0_RX_DN<15>")
	)
	(gr_poly
		(pts
			(arc
				(start 109.934248 -278.946356)
				(mid 109.527848 -278.946356)
				(end 109.934248 -278.946356)
			)
		)
		(stroke
			(width 0)
			(type solid)
		)
		(fill yes)
		(layer "In7.Cu")
		(net "P5E_CPU1_P1_RX_DP<13>")
	)
	(gr_poly
		(pts
			(arc
				(start 109.934248 -277.326344)
				(mid 109.527848 -277.326344)
				(end 109.934248 -277.326344)
			)
		)
		(stroke
			(width 0)
			(type solid)
		)
		(fill yes)
		(layer "In7.Cu")
		(net "P5E_CPU1_P1_RX_DP<14>")
	)
	(gr_poly
		(pts
			(arc
				(start 109.934248 -275.706332)
				(mid 109.527848 -275.706332)
				(end 109.934248 -275.706332)
			)
		)
		(stroke
			(width 0)
			(type solid)
		)
		(fill yes)
		(layer "In7.Cu")
		(net "P5E_CPU1_P1_RX_DP<15>")
	)
	(gr_poly
		(pts
			(arc
				(start 109.934248 -274.08632)
				(mid 109.527848 -274.08632)
				(end 109.934248 -274.08632)
			)
		)
		(stroke
			(width 0)
			(type solid)
		)
		(fill yes)
		(layer "In7.Cu")
		(net "P5E_CPU1_P0_RX_DP<13>")
	)
	(gr_poly
		(pts
			(arc
				(start 109.934248 -272.466308)
				(mid 109.527848 -272.466308)
				(end 109.934248 -272.466308)
			)
		)
		(stroke
			(width 0)
			(type solid)
		)
		(fill yes)
		(layer "In7.Cu")
		(net "P5E_CPU1_P0_RX_DP<12>")
	)
	(gr_poly
		(pts
			(arc
				(start 109.934248 -270.846296)
				(mid 109.527848 -270.846296)
				(end 109.934248 -270.846296)
			)
		)
		(stroke
			(width 0)
			(type solid)
		)
		(fill yes)
		(layer "In7.Cu")
		(net "P5E_CPU1_P0_RX_DP<14>")
	)
	(gr_poly
		(pts
			(arc
				(start 109.934248 -269.226284)
				(mid 109.527848 -269.226284)
				(end 109.934248 -269.226284)
			)
		)
		(stroke
			(width 0)
			(type solid)
		)
		(fill yes)
		(layer "In7.Cu")
		(net "P5E_CPU1_P0_RX_DP<15>")
	)
	(gr_poly
		(pts
			(arc
				(start 114.627914 -278.946356)
				(mid 114.221514 -278.946356)
				(end 114.627914 -278.946356)
			)
		)
		(stroke
			(width 0)
			(type solid)
		)
		(fill yes)
		(layer "In7.Cu")
		(net "P5E_CPU1_P3_TX_DP<2>")
	)
	(gr_poly
		(pts
			(arc
				(start 114.627914 -277.326344)
				(mid 114.221514 -277.326344)
				(end 114.627914 -277.326344)
			)
		)
		(stroke
			(width 0)
			(type solid)
		)
		(fill yes)
		(layer "In7.Cu")
		(net "P5E_CPU1_P3_TX_DP<1>")
	)
	(gr_poly
		(pts
			(arc
				(start 114.627914 -275.706332)
				(mid 114.221514 -275.706332)
				(end 114.627914 -275.706332)
			)
		)
		(stroke
			(width 0)
			(type solid)
		)
		(fill yes)
		(layer "In7.Cu")
		(net "P5E_CPU1_P3_TX_DP<0>")
	)
	(gr_poly
		(pts
			(arc
				(start 114.627914 -274.08632)
				(mid 114.221514 -274.08632)
				(end 114.627914 -274.08632)
			)
		)
		(stroke
			(width 0)
			(type solid)
		)
		(fill yes)
		(layer "In7.Cu")
		(net "P5E_CPU1_P2_TX_DP<2>")
	)
	(gr_poly
		(pts
			(arc
				(start 114.627914 -272.466308)
				(mid 114.221514 -272.466308)
				(end 114.627914 -272.466308)
			)
		)
		(stroke
			(width 0)
			(type solid)
		)
		(fill yes)
		(layer "In7.Cu")
		(net "P5E_CPU1_P2_TX_DP<3>")
	)
	(gr_poly
		(pts
			(arc
				(start 114.627914 -270.846296)
				(mid 114.221514 -270.846296)
				(end 114.627914 -270.846296)
			)
		)
		(stroke
			(width 0)
			(type solid)
		)
		(fill yes)
		(layer "In7.Cu")
		(net "P5E_CPU1_P2_TX_DP<1>")
	)
	(gr_poly
		(pts
			(arc
				(start 114.627914 -269.226284)
				(mid 114.221514 -269.226284)
				(end 114.627914 -269.226284)
			)
		)
		(stroke
			(width 0)
			(type solid)
		)
		(fill yes)
		(layer "In7.Cu")
		(net "P5E_CPU1_P2_TX_DP<0>")
	)
	(gr_poly
		(pts
			(arc
				(start 115.567968 -278.946356)
				(mid 115.161568 -278.946356)
				(end 115.567968 -278.946356)
			)
		)
		(stroke
			(width 0)
			(type solid)
		)
		(fill yes)
		(layer "In7.Cu")
		(net "P5E_CPU1_P3_TX_DN<2>")
	)
	(gr_poly
		(pts
			(arc
				(start 115.567968 -277.326344)
				(mid 115.161568 -277.326344)
				(end 115.567968 -277.326344)
			)
		)
		(stroke
			(width 0)
			(type solid)
		)
		(fill yes)
		(layer "In7.Cu")
		(net "P5E_CPU1_P3_TX_DN<1>")
	)
	(gr_poly
		(pts
			(arc
				(start 115.567968 -275.706332)
				(mid 115.161568 -275.706332)
				(end 115.567968 -275.706332)
			)
		)
		(stroke
			(width 0)
			(type solid)
		)
		(fill yes)
		(layer "In7.Cu")
		(net "P5E_CPU1_P3_TX_DN<0>")
	)
	(gr_poly
		(pts
			(arc
				(start 115.567968 -274.08632)
				(mid 115.161568 -274.08632)
				(end 115.567968 -274.08632)
			)
		)
		(stroke
			(width 0)
			(type solid)
		)
		(fill yes)
		(layer "In7.Cu")
		(net "P5E_CPU1_P2_TX_DN<2>")
	)
	(gr_poly
		(pts
			(arc
				(start 115.567968 -272.466308)
				(mid 115.161568 -272.466308)
				(end 115.567968 -272.466308)
			)
		)
		(stroke
			(width 0)
			(type solid)
		)
		(fill yes)
		(layer "In7.Cu")
		(net "P5E_CPU1_P2_TX_DN<3>")
	)
	(gr_poly
		(pts
			(arc
				(start 115.567968 -270.846296)
				(mid 115.161568 -270.846296)
				(end 115.567968 -270.846296)
			)
		)
		(stroke
			(width 0)
			(type solid)
		)
		(fill yes)
		(layer "In7.Cu")
		(net "P5E_CPU1_P2_TX_DN<1>")
	)
	(gr_poly
		(pts
			(arc
				(start 115.567968 -269.226284)
				(mid 115.161568 -269.226284)
				(end 115.567968 -269.226284)
			)
		)
		(stroke
			(width 0)
			(type solid)
		)
		(fill yes)
		(layer "In7.Cu")
		(net "P5E_CPU1_P2_TX_DN<0>")
	)
	(gr_poly
		(pts
			(arc
				(start 116.977922 -279.756362)
				(mid 116.571522 -279.756362)
				(end 116.977922 -279.756362)
			)
		)
		(stroke
			(width 0)
			(type solid)
		)
		(fill yes)
		(layer "In7.Cu")
		(net "P5E_CPU1_P3_TX_DP<4>")
	)
	(gr_poly
		(pts
			(arc
				(start 116.977922 -278.13635)
				(mid 116.571522 -278.13635)
				(end 116.977922 -278.13635)
			)
		)
		(stroke
			(width 0)
			(type solid)
		)
		(fill yes)
		(layer "In7.Cu")
		(net "P5E_CPU1_P3_TX_DP<5>")
	)
	(gr_poly
		(pts
			(arc
				(start 116.977922 -276.516338)
				(mid 116.571522 -276.516338)
				(end 116.977922 -276.516338)
			)
		)
		(stroke
			(width 0)
			(type solid)
		)
		(fill yes)
		(layer "In7.Cu")
		(net "P5E_CPU1_P3_TX_DP<6>")
	)
	(gr_poly
		(pts
			(arc
				(start 116.977922 -274.896326)
				(mid 116.571522 -274.896326)
				(end 116.977922 -274.896326)
			)
		)
		(stroke
			(width 0)
			(type solid)
		)
		(fill yes)
		(layer "In7.Cu")
		(net "P5E_CPU1_P3_TX_DP<3>")
	)
	(gr_poly
		(pts
			(arc
				(start 116.977922 -273.276314)
				(mid 116.571522 -273.276314)
				(end 116.977922 -273.276314)
			)
		)
		(stroke
			(width 0)
			(type solid)
		)
		(fill yes)
		(layer "In7.Cu")
		(net "P5E_CPU1_P2_TX_DP<5>")
	)
	(gr_poly
		(pts
			(arc
				(start 116.977922 -271.656302)
				(mid 116.571522 -271.656302)
				(end 116.977922 -271.656302)
			)
		)
		(stroke
			(width 0)
			(type solid)
		)
		(fill yes)
		(layer "In7.Cu")
		(net "P5E_CPU1_P2_TX_DP<6>")
	)
	(gr_poly
		(pts
			(arc
				(start 116.977922 -270.03629)
				(mid 116.571522 -270.03629)
				(end 116.977922 -270.03629)
			)
		)
		(stroke
			(width 0)
			(type solid)
		)
		(fill yes)
		(layer "In7.Cu")
		(net "P5E_CPU1_P2_TX_DP<4>")
	)
	(gr_poly
		(pts
			(arc
				(start 117.917976 -279.756362)
				(mid 117.511576 -279.756362)
				(end 117.917976 -279.756362)
			)
		)
		(stroke
			(width 0)
			(type solid)
		)
		(fill yes)
		(layer "In7.Cu")
		(net "P5E_CPU1_P3_TX_DN<4>")
	)
	(gr_poly
		(pts
			(arc
				(start 117.917976 -278.13635)
				(mid 117.511576 -278.13635)
				(end 117.917976 -278.13635)
			)
		)
		(stroke
			(width 0)
			(type solid)
		)
		(fill yes)
		(layer "In7.Cu")
		(net "P5E_CPU1_P3_TX_DN<5>")
	)
	(gr_poly
		(pts
			(arc
				(start 117.917976 -276.516338)
				(mid 117.511576 -276.516338)
				(end 117.917976 -276.516338)
			)
		)
		(stroke
			(width 0)
			(type solid)
		)
		(fill yes)
		(layer "In7.Cu")
		(net "P5E_CPU1_P3_TX_DN<6>")
	)
	(gr_poly
		(pts
			(arc
				(start 117.917976 -274.896326)
				(mid 117.511576 -274.896326)
				(end 117.917976 -274.896326)
			)
		)
		(stroke
			(width 0)
			(type solid)
		)
		(fill yes)
		(layer "In7.Cu")
		(net "P5E_CPU1_P3_TX_DN<3>")
	)
	(gr_poly
		(pts
			(arc
				(start 117.917976 -273.276314)
				(mid 117.511576 -273.276314)
				(end 117.917976 -273.276314)
			)
		)
		(stroke
			(width 0)
			(type solid)
		)
		(fill yes)
		(layer "In7.Cu")
		(net "P5E_CPU1_P2_TX_DN<5>")
	)
	(gr_poly
		(pts
			(arc
				(start 117.917976 -271.656302)
				(mid 117.511576 -271.656302)
				(end 117.917976 -271.656302)
			)
		)
		(stroke
			(width 0)
			(type solid)
		)
		(fill yes)
		(layer "In7.Cu")
		(net "P5E_CPU1_P2_TX_DN<6>")
	)
	(gr_poly
		(pts
			(arc
				(start 117.917976 -270.03629)
				(mid 117.511576 -270.03629)
				(end 117.917976 -270.03629)
			)
		)
		(stroke
			(width 0)
			(type solid)
		)
		(fill yes)
		(layer "In7.Cu")
		(net "P5E_CPU1_P2_TX_DN<4>")
	)
	(gr_poly
		(pts
			(arc
				(start 119.79783 -278.13635)
				(mid 119.39143 -278.13635)
				(end 119.79783 -278.13635)
			)
		)
		(stroke
			(width 0)
			(type solid)
		)
		(fill yes)
		(layer "In7.Cu")
		(net "P5E_CPU1_P3_TX_DP<8>")
	)
	(gr_poly
		(pts
			(arc
				(start 119.79783 -276.516338)
				(mid 119.39143 -276.516338)
				(end 119.79783 -276.516338)
			)
		)
		(stroke
			(width 0)
			(type solid)
		)
		(fill yes)
		(layer "In7.Cu")
		(net "P5E_CPU1_P3_TX_DP<9>")
	)
	(gr_poly
		(pts
			(arc
				(start 119.79783 -274.896326)
				(mid 119.39143 -274.896326)
				(end 119.79783 -274.896326)
			)
		)
		(stroke
			(width 0)
			(type solid)
		)
		(fill yes)
		(layer "In7.Cu")
		(net "P5E_CPU1_P3_TX_DP<7>")
	)
	(gr_poly
		(pts
			(arc
				(start 119.79783 -273.276314)
				(mid 119.39143 -273.276314)
				(end 119.79783 -273.276314)
			)
		)
		(stroke
			(width 0)
			(type solid)
		)
		(fill yes)
		(layer "In7.Cu")
		(net "P5E_CPU1_P2_TX_DP<8>")
	)
	(gr_poly
		(pts
			(arc
				(start 119.79783 -271.656302)
				(mid 119.39143 -271.656302)
				(end 119.79783 -271.656302)
			)
		)
		(stroke
			(width 0)
			(type solid)
		)
		(fill yes)
		(layer "In7.Cu")
		(net "P5E_CPU1_P2_TX_DP<9>")
	)
	(gr_poly
		(pts
			(arc
				(start 119.79783 -270.03629)
				(mid 119.39143 -270.03629)
				(end 119.79783 -270.03629)
			)
		)
		(stroke
			(width 0)
			(type solid)
		)
		(fill yes)
		(layer "In7.Cu")
		(net "P5E_CPU1_P2_TX_DP<7>")
	)
	(gr_poly
		(pts
			(arc
				(start 120.737884 -278.13635)
				(mid 120.331484 -278.13635)
				(end 120.737884 -278.13635)
			)
		)
		(stroke
			(width 0)
			(type solid)
		)
		(fill yes)
		(layer "In7.Cu")
		(net "P5E_CPU1_P3_TX_DN<8>")
	)
	(gr_poly
		(pts
			(arc
				(start 120.737884 -276.516338)
				(mid 120.331484 -276.516338)
				(end 120.737884 -276.516338)
			)
		)
		(stroke
			(width 0)
			(type solid)
		)
		(fill yes)
		(layer "In7.Cu")
		(net "P5E_CPU1_P3_TX_DN<9>")
	)
	(gr_poly
		(pts
			(arc
				(start 120.737884 -274.896326)
				(mid 120.331484 -274.896326)
				(end 120.737884 -274.896326)
			)
		)
		(stroke
			(width 0)
			(type solid)
		)
		(fill yes)
		(layer "In7.Cu")
		(net "P5E_CPU1_P3_TX_DN<7>")
	)
	(gr_poly
		(pts
			(arc
				(start 120.737884 -273.276314)
				(mid 120.331484 -273.276314)
				(end 120.737884 -273.276314)
			)
		)
		(stroke
			(width 0)
			(type solid)
		)
		(fill yes)
		(layer "In7.Cu")
		(net "P5E_CPU1_P2_TX_DN<8>")
	)
	(gr_poly
		(pts
			(arc
				(start 120.737884 -271.656302)
				(mid 120.331484 -271.656302)
				(end 120.737884 -271.656302)
			)
		)
		(stroke
			(width 0)
			(type solid)
		)
		(fill yes)
		(layer "In7.Cu")
		(net "P5E_CPU1_P2_TX_DN<9>")
	)
	(gr_poly
		(pts
			(arc
				(start 120.737884 -270.03629)
				(mid 120.331484 -270.03629)
				(end 120.737884 -270.03629)
			)
		)
		(stroke
			(width 0)
			(type solid)
		)
		(fill yes)
		(layer "In7.Cu")
		(net "P5E_CPU1_P2_TX_DN<7>")
	)
	(gr_poly
		(pts
			(arc
				(start 122.617992 -278.13635)
				(mid 122.211592 -278.13635)
				(end 122.617992 -278.13635)
			)
		)
		(stroke
			(width 0)
			(type solid)
		)
		(fill yes)
		(layer "In7.Cu")
		(net "P5E_CPU1_P3_TX_DP<11>")
	)
	(gr_poly
		(pts
			(arc
				(start 122.617992 -276.516338)
				(mid 122.211592 -276.516338)
				(end 122.617992 -276.516338)
			)
		)
		(stroke
			(width 0)
			(type solid)
		)
		(fill yes)
		(layer "In7.Cu")
		(net "P5E_CPU1_P3_TX_DP<12>")
	)
	(gr_poly
		(pts
			(arc
				(start 122.617992 -274.896326)
				(mid 122.211592 -274.896326)
				(end 122.617992 -274.896326)
			)
		)
		(stroke
			(width 0)
			(type solid)
		)
		(fill yes)
		(layer "In7.Cu")
		(net "P5E_CPU1_P3_TX_DP<10>")
	)
	(gr_poly
		(pts
			(arc
				(start 122.617992 -273.276314)
				(mid 122.211592 -273.276314)
				(end 122.617992 -273.276314)
			)
		)
		(stroke
			(width 0)
			(type solid)
		)
		(fill yes)
		(layer "In7.Cu")
		(net "P5E_CPU1_P2_TX_DP<11>")
	)
	(gr_poly
		(pts
			(arc
				(start 122.617992 -271.656302)
				(mid 122.211592 -271.656302)
				(end 122.617992 -271.656302)
			)
		)
		(stroke
			(width 0)
			(type solid)
		)
		(fill yes)
		(layer "In7.Cu")
		(net "P5E_CPU1_P2_TX_DP<12>")
	)
	(gr_poly
		(pts
			(arc
				(start 122.617992 -270.03629)
				(mid 122.211592 -270.03629)
				(end 122.617992 -270.03629)
			)
		)
		(stroke
			(width 0)
			(type solid)
		)
		(fill yes)
		(layer "In7.Cu")
		(net "P5E_CPU1_P2_TX_DP<10>")
	)
	(gr_poly
		(pts
			(arc
				(start 123.558046 -278.13635)
				(mid 123.151646 -278.13635)
				(end 123.558046 -278.13635)
			)
		)
		(stroke
			(width 0)
			(type solid)
		)
		(fill yes)
		(layer "In7.Cu")
		(net "P5E_CPU1_P3_TX_DN<11>")
	)
	(gr_poly
		(pts
			(arc
				(start 123.558046 -276.516338)
				(mid 123.151646 -276.516338)
				(end 123.558046 -276.516338)
			)
		)
		(stroke
			(width 0)
			(type solid)
		)
		(fill yes)
		(layer "In7.Cu")
		(net "P5E_CPU1_P3_TX_DN<12>")
	)
	(gr_poly
		(pts
			(arc
				(start 123.558046 -274.896326)
				(mid 123.151646 -274.896326)
				(end 123.558046 -274.896326)
			)
		)
		(stroke
			(width 0)
			(type solid)
		)
		(fill yes)
		(layer "In7.Cu")
		(net "P5E_CPU1_P3_TX_DN<10>")
	)
	(gr_poly
		(pts
			(arc
				(start 123.558046 -273.276314)
				(mid 123.151646 -273.276314)
				(end 123.558046 -273.276314)
			)
		)
		(stroke
			(width 0)
			(type solid)
		)
		(fill yes)
		(layer "In7.Cu")
		(net "P5E_CPU1_P2_TX_DN<11>")
	)
	(gr_poly
		(pts
			(arc
				(start 123.558046 -271.656302)
				(mid 123.151646 -271.656302)
				(end 123.558046 -271.656302)
			)
		)
		(stroke
			(width 0)
			(type solid)
		)
		(fill yes)
		(layer "In7.Cu")
		(net "P5E_CPU1_P2_TX_DN<12>")
	)
	(gr_poly
		(pts
			(arc
				(start 123.558046 -270.03629)
				(mid 123.151646 -270.03629)
				(end 123.558046 -270.03629)
			)
		)
		(stroke
			(width 0)
			(type solid)
		)
		(fill yes)
		(layer "In7.Cu")
		(net "P5E_CPU1_P2_TX_DN<10>")
	)
	(gr_poly
		(pts
			(arc
				(start 125.4379 -278.13635)
				(mid 125.0315 -278.13635)
				(end 125.4379 -278.13635)
			)
		)
		(stroke
			(width 0)
			(type solid)
		)
		(fill yes)
		(layer "In7.Cu")
		(net "P5E_CPU1_P3_TX_DP<14>")
	)
	(gr_poly
		(pts
			(arc
				(start 125.4379 -276.516338)
				(mid 125.0315 -276.516338)
				(end 125.4379 -276.516338)
			)
		)
		(stroke
			(width 0)
			(type solid)
		)
		(fill yes)
		(layer "In7.Cu")
		(net "P5E_CPU1_P3_TX_DP<15>")
	)
	(gr_poly
		(pts
			(arc
				(start 125.4379 -274.896326)
				(mid 125.0315 -274.896326)
				(end 125.4379 -274.896326)
			)
		)
		(stroke
			(width 0)
			(type solid)
		)
		(fill yes)
		(layer "In7.Cu")
		(net "P5E_CPU1_P3_TX_DP<13>")
	)
	(gr_poly
		(pts
			(arc
				(start 125.4379 -273.276314)
				(mid 125.0315 -273.276314)
				(end 125.4379 -273.276314)
			)
		)
		(stroke
			(width 0)
			(type solid)
		)
		(fill yes)
		(layer "In7.Cu")
		(net "P5E_CPU1_P2_TX_DP<14>")
	)
	(gr_poly
		(pts
			(arc
				(start 125.4379 -271.656302)
				(mid 125.0315 -271.656302)
				(end 125.4379 -271.656302)
			)
		)
		(stroke
			(width 0)
			(type solid)
		)
		(fill yes)
		(layer "In7.Cu")
		(net "P5E_CPU1_P2_TX_DP<15>")
	)
	(gr_poly
		(pts
			(arc
				(start 125.4379 -270.03629)
				(mid 125.0315 -270.03629)
				(end 125.4379 -270.03629)
			)
		)
		(stroke
			(width 0)
			(type solid)
		)
		(fill yes)
		(layer "In7.Cu")
		(net "P5E_CPU1_P2_TX_DP<13>")
	)
	(gr_poly
		(pts
			(arc
				(start 126.377954 -278.13635)
				(mid 125.971554 -278.13635)
				(end 126.377954 -278.13635)
			)
		)
		(stroke
			(width 0)
			(type solid)
		)
		(fill yes)
		(layer "In7.Cu")
		(net "P5E_CPU1_P3_TX_DN<14>")
	)
	(gr_poly
		(pts
			(arc
				(start 126.377954 -276.516338)
				(mid 125.971554 -276.516338)
				(end 126.377954 -276.516338)
			)
		)
		(stroke
			(width 0)
			(type solid)
		)
		(fill yes)
		(layer "In7.Cu")
		(net "P5E_CPU1_P3_TX_DN<15>")
	)
	(gr_poly
		(pts
			(arc
				(start 126.377954 -274.896326)
				(mid 125.971554 -274.896326)
				(end 126.377954 -274.896326)
			)
		)
		(stroke
			(width 0)
			(type solid)
		)
		(fill yes)
		(layer "In7.Cu")
		(net "P5E_CPU1_P3_TX_DN<13>")
	)
	(gr_poly
		(pts
			(arc
				(start 126.377954 -273.276314)
				(mid 125.971554 -273.276314)
				(end 126.377954 -273.276314)
			)
		)
		(stroke
			(width 0)
			(type solid)
		)
		(fill yes)
		(layer "In7.Cu")
		(net "P5E_CPU1_P2_TX_DN<14>")
	)
	(gr_poly
		(pts
			(arc
				(start 126.377954 -271.656302)
				(mid 125.971554 -271.656302)
				(end 126.377954 -271.656302)
			)
		)
		(stroke
			(width 0)
			(type solid)
		)
		(fill yes)
		(layer "In7.Cu")
		(net "P5E_CPU1_P2_TX_DN<15>")
	)
	(gr_poly
		(pts
			(arc
				(start 126.377954 -270.03629)
				(mid 125.971554 -270.03629)
				(end 126.377954 -270.03629)
			)
		)
		(stroke
			(width 0)
			(type solid)
		)
		(fill yes)
		(layer "In7.Cu")
		(net "P5E_CPU1_P2_TX_DN<13>")
	)
	(gr_poly
		(pts
			(arc
				(start 346.124276 -278.136096)
				(mid 345.717876 -278.136096)
				(end 346.124276 -278.136096)
			)
		)
		(stroke
			(width 0)
			(type solid)
		)
		(fill yes)
		(layer "In7.Cu")
		(net "P5E_CPU0_P1_RX_DN<1>")
	)
	(gr_poly
		(pts
			(arc
				(start 346.124276 -276.516084)
				(mid 345.717876 -276.516084)
				(end 346.124276 -276.516084)
			)
		)
		(stroke
			(width 0)
			(type solid)
		)
		(fill yes)
		(layer "In7.Cu")
		(net "P5E_CPU0_P1_RX_DN<0>")
	)
	(gr_poly
		(pts
			(arc
				(start 346.124276 -274.896072)
				(mid 345.717876 -274.896072)
				(end 346.124276 -274.896072)
			)
		)
		(stroke
			(width 0)
			(type solid)
		)
		(fill yes)
		(layer "In7.Cu")
		(net "P5E_CPU0_P1_RX_DN<2>")
	)
	(gr_poly
		(pts
			(arc
				(start 346.124276 -273.27606)
				(mid 345.717876 -273.27606)
				(end 346.124276 -273.27606)
			)
		)
		(stroke
			(width 0)
			(type solid)
		)
		(fill yes)
		(layer "In7.Cu")
		(net "P5E_CPU0_P0_RX_DN<1>")
	)
	(gr_poly
		(pts
			(arc
				(start 346.124276 -271.656048)
				(mid 345.717876 -271.656048)
				(end 346.124276 -271.656048)
			)
		)
		(stroke
			(width 0)
			(type solid)
		)
		(fill yes)
		(layer "In7.Cu")
		(net "P5E_CPU0_P0_RX_DN<0>")
	)
	(gr_poly
		(pts
			(arc
				(start 346.124276 -270.036036)
				(mid 345.717876 -270.036036)
				(end 346.124276 -270.036036)
			)
		)
		(stroke
			(width 0)
			(type solid)
		)
		(fill yes)
		(layer "In7.Cu")
		(net "P5E_CPU0_P0_RX_DN<2>")
	)
	(gr_poly
		(pts
			(arc
				(start 347.06433 -278.136096)
				(mid 346.65793 -278.136096)
				(end 347.06433 -278.136096)
			)
		)
		(stroke
			(width 0)
			(type solid)
		)
		(fill yes)
		(layer "In7.Cu")
		(net "P5E_CPU0_P1_RX_DP<1>")
	)
	(gr_poly
		(pts
			(arc
				(start 347.06433 -276.516084)
				(mid 346.65793 -276.516084)
				(end 347.06433 -276.516084)
			)
		)
		(stroke
			(width 0)
			(type solid)
		)
		(fill yes)
		(layer "In7.Cu")
		(net "P5E_CPU0_P1_RX_DP<0>")
	)
	(gr_poly
		(pts
			(arc
				(start 347.06433 -274.896072)
				(mid 346.65793 -274.896072)
				(end 347.06433 -274.896072)
			)
		)
		(stroke
			(width 0)
			(type solid)
		)
		(fill yes)
		(layer "In7.Cu")
		(net "P5E_CPU0_P1_RX_DP<2>")
	)
	(gr_poly
		(pts
			(arc
				(start 347.06433 -273.27606)
				(mid 346.65793 -273.27606)
				(end 347.06433 -273.27606)
			)
		)
		(stroke
			(width 0)
			(type solid)
		)
		(fill yes)
		(layer "In7.Cu")
		(net "P5E_CPU0_P0_RX_DP<1>")
	)
	(gr_poly
		(pts
			(arc
				(start 347.06433 -271.656048)
				(mid 346.65793 -271.656048)
				(end 347.06433 -271.656048)
			)
		)
		(stroke
			(width 0)
			(type solid)
		)
		(fill yes)
		(layer "In7.Cu")
		(net "P5E_CPU0_P0_RX_DP<0>")
	)
	(gr_poly
		(pts
			(arc
				(start 347.06433 -270.036036)
				(mid 346.65793 -270.036036)
				(end 347.06433 -270.036036)
			)
		)
		(stroke
			(width 0)
			(type solid)
		)
		(fill yes)
		(layer "In7.Cu")
		(net "P5E_CPU0_P0_RX_DP<2>")
	)
	(gr_poly
		(pts
			(arc
				(start 348.944184 -278.136096)
				(mid 348.537784 -278.136096)
				(end 348.944184 -278.136096)
			)
		)
		(stroke
			(width 0)
			(type solid)
		)
		(fill yes)
		(layer "In7.Cu")
		(net "P5E_CPU0_P1_RX_DN<4>")
	)
	(gr_poly
		(pts
			(arc
				(start 348.944184 -276.516084)
				(mid 348.537784 -276.516084)
				(end 348.944184 -276.516084)
			)
		)
		(stroke
			(width 0)
			(type solid)
		)
		(fill yes)
		(layer "In7.Cu")
		(net "P5E_CPU0_P1_RX_DN<3>")
	)
	(gr_poly
		(pts
			(arc
				(start 348.944184 -274.896072)
				(mid 348.537784 -274.896072)
				(end 348.944184 -274.896072)
			)
		)
		(stroke
			(width 0)
			(type solid)
		)
		(fill yes)
		(layer "In7.Cu")
		(net "P5E_CPU0_P1_RX_DN<5>")
	)
	(gr_poly
		(pts
			(arc
				(start 348.944184 -273.27606)
				(mid 348.537784 -273.27606)
				(end 348.944184 -273.27606)
			)
		)
		(stroke
			(width 0)
			(type solid)
		)
		(fill yes)
		(layer "In7.Cu")
		(net "P5E_CPU0_P0_RX_DN<4>")
	)
	(gr_poly
		(pts
			(arc
				(start 348.944184 -271.656048)
				(mid 348.537784 -271.656048)
				(end 348.944184 -271.656048)
			)
		)
		(stroke
			(width 0)
			(type solid)
		)
		(fill yes)
		(layer "In7.Cu")
		(net "P5E_CPU0_P0_RX_DN<3>")
	)
	(gr_poly
		(pts
			(arc
				(start 348.944184 -270.036036)
				(mid 348.537784 -270.036036)
				(end 348.944184 -270.036036)
			)
		)
		(stroke
			(width 0)
			(type solid)
		)
		(fill yes)
		(layer "In7.Cu")
		(net "P5E_CPU0_P0_RX_DN<5>")
	)
	(gr_poly
		(pts
			(arc
				(start 349.884238 -278.136096)
				(mid 349.477838 -278.136096)
				(end 349.884238 -278.136096)
			)
		)
		(stroke
			(width 0)
			(type solid)
		)
		(fill yes)
		(layer "In7.Cu")
		(net "P5E_CPU0_P1_RX_DP<4>")
	)
	(gr_poly
		(pts
			(arc
				(start 349.884238 -276.516084)
				(mid 349.477838 -276.516084)
				(end 349.884238 -276.516084)
			)
		)
		(stroke
			(width 0)
			(type solid)
		)
		(fill yes)
		(layer "In7.Cu")
		(net "P5E_CPU0_P1_RX_DP<3>")
	)
	(gr_poly
		(pts
			(arc
				(start 349.884238 -274.896072)
				(mid 349.477838 -274.896072)
				(end 349.884238 -274.896072)
			)
		)
		(stroke
			(width 0)
			(type solid)
		)
		(fill yes)
		(layer "In7.Cu")
		(net "P5E_CPU0_P1_RX_DP<5>")
	)
	(gr_poly
		(pts
			(arc
				(start 349.884238 -273.27606)
				(mid 349.477838 -273.27606)
				(end 349.884238 -273.27606)
			)
		)
		(stroke
			(width 0)
			(type solid)
		)
		(fill yes)
		(layer "In7.Cu")
		(net "P5E_CPU0_P0_RX_DP<4>")
	)
	(gr_poly
		(pts
			(arc
				(start 349.884238 -271.656048)
				(mid 349.477838 -271.656048)
				(end 349.884238 -271.656048)
			)
		)
		(stroke
			(width 0)
			(type solid)
		)
		(fill yes)
		(layer "In7.Cu")
		(net "P5E_CPU0_P0_RX_DP<3>")
	)
	(gr_poly
		(pts
			(arc
				(start 349.884238 -270.036036)
				(mid 349.477838 -270.036036)
				(end 349.884238 -270.036036)
			)
		)
		(stroke
			(width 0)
			(type solid)
		)
		(fill yes)
		(layer "In7.Cu")
		(net "P5E_CPU0_P0_RX_DP<5>")
	)
	(gr_poly
		(pts
			(arc
				(start 351.764346 -278.136096)
				(mid 351.357946 -278.136096)
				(end 351.764346 -278.136096)
			)
		)
		(stroke
			(width 0)
			(type solid)
		)
		(fill yes)
		(layer "In7.Cu")
		(net "P5E_CPU0_P1_RX_DN<7>")
	)
	(gr_poly
		(pts
			(arc
				(start 351.764346 -276.516084)
				(mid 351.357946 -276.516084)
				(end 351.764346 -276.516084)
			)
		)
		(stroke
			(width 0)
			(type solid)
		)
		(fill yes)
		(layer "In7.Cu")
		(net "P5E_CPU0_P1_RX_DN<6>")
	)
	(gr_poly
		(pts
			(arc
				(start 351.764346 -274.896072)
				(mid 351.357946 -274.896072)
				(end 351.764346 -274.896072)
			)
		)
		(stroke
			(width 0)
			(type solid)
		)
		(fill yes)
		(layer "In7.Cu")
		(net "P5E_CPU0_P1_RX_DN<8>")
	)
	(gr_poly
		(pts
			(arc
				(start 351.764346 -273.27606)
				(mid 351.357946 -273.27606)
				(end 351.764346 -273.27606)
			)
		)
		(stroke
			(width 0)
			(type solid)
		)
		(fill yes)
		(layer "In7.Cu")
		(net "P5E_CPU0_P0_RX_DN<7>")
	)
	(gr_poly
		(pts
			(arc
				(start 351.764346 -271.656048)
				(mid 351.357946 -271.656048)
				(end 351.764346 -271.656048)
			)
		)
		(stroke
			(width 0)
			(type solid)
		)
		(fill yes)
		(layer "In7.Cu")
		(net "P5E_CPU0_P0_RX_DN<6>")
	)
	(gr_poly
		(pts
			(arc
				(start 351.764346 -270.036036)
				(mid 351.357946 -270.036036)
				(end 351.764346 -270.036036)
			)
		)
		(stroke
			(width 0)
			(type solid)
		)
		(fill yes)
		(layer "In7.Cu")
		(net "P5E_CPU0_P0_RX_DN<8>")
	)
	(gr_poly
		(pts
			(arc
				(start 352.7044 -278.136096)
				(mid 352.298 -278.136096)
				(end 352.7044 -278.136096)
			)
		)
		(stroke
			(width 0)
			(type solid)
		)
		(fill yes)
		(layer "In7.Cu")
		(net "P5E_CPU0_P1_RX_DP<7>")
	)
	(gr_poly
		(pts
			(arc
				(start 352.7044 -276.516084)
				(mid 352.298 -276.516084)
				(end 352.7044 -276.516084)
			)
		)
		(stroke
			(width 0)
			(type solid)
		)
		(fill yes)
		(layer "In7.Cu")
		(net "P5E_CPU0_P1_RX_DP<6>")
	)
	(gr_poly
		(pts
			(arc
				(start 352.7044 -274.896072)
				(mid 352.298 -274.896072)
				(end 352.7044 -274.896072)
			)
		)
		(stroke
			(width 0)
			(type solid)
		)
		(fill yes)
		(layer "In7.Cu")
		(net "P5E_CPU0_P1_RX_DP<8>")
	)
	(gr_poly
		(pts
			(arc
				(start 352.7044 -273.27606)
				(mid 352.298 -273.27606)
				(end 352.7044 -273.27606)
			)
		)
		(stroke
			(width 0)
			(type solid)
		)
		(fill yes)
		(layer "In7.Cu")
		(net "P5E_CPU0_P0_RX_DP<7>")
	)
	(gr_poly
		(pts
			(arc
				(start 352.7044 -271.656048)
				(mid 352.298 -271.656048)
				(end 352.7044 -271.656048)
			)
		)
		(stroke
			(width 0)
			(type solid)
		)
		(fill yes)
		(layer "In7.Cu")
		(net "P5E_CPU0_P0_RX_DP<6>")
	)
	(gr_poly
		(pts
			(arc
				(start 352.7044 -270.036036)
				(mid 352.298 -270.036036)
				(end 352.7044 -270.036036)
			)
		)
		(stroke
			(width 0)
			(type solid)
		)
		(fill yes)
		(layer "In7.Cu")
		(net "P5E_CPU0_P0_RX_DP<8>")
	)
	(gr_poly
		(pts
			(arc
				(start 354.584254 -279.756108)
				(mid 354.177854 -279.756108)
				(end 354.584254 -279.756108)
			)
		)
		(stroke
			(width 0)
			(type solid)
		)
		(fill yes)
		(layer "In7.Cu")
		(net "P5E_CPU0_P1_RX_DN<11>")
	)
	(gr_poly
		(pts
			(arc
				(start 354.584254 -278.136096)
				(mid 354.177854 -278.136096)
				(end 354.584254 -278.136096)
			)
		)
		(stroke
			(width 0)
			(type solid)
		)
		(fill yes)
		(layer "In7.Cu")
		(net "P5E_CPU0_P1_RX_DN<10>")
	)
	(gr_poly
		(pts
			(arc
				(start 354.584254 -276.516084)
				(mid 354.177854 -276.516084)
				(end 354.584254 -276.516084)
			)
		)
		(stroke
			(width 0)
			(type solid)
		)
		(fill yes)
		(layer "In7.Cu")
		(net "P5E_CPU0_P1_RX_DN<9>")
	)
	(gr_poly
		(pts
			(arc
				(start 354.584254 -274.896072)
				(mid 354.177854 -274.896072)
				(end 354.584254 -274.896072)
			)
		)
		(stroke
			(width 0)
			(type solid)
		)
		(fill yes)
		(layer "In7.Cu")
		(net "P5E_CPU0_P1_RX_DN<12>")
	)
	(gr_poly
		(pts
			(arc
				(start 354.584254 -273.27606)
				(mid 354.177854 -273.27606)
				(end 354.584254 -273.27606)
			)
		)
		(stroke
			(width 0)
			(type solid)
		)
		(fill yes)
		(layer "In7.Cu")
		(net "P5E_CPU0_P0_RX_DN<10>")
	)
	(gr_poly
		(pts
			(arc
				(start 354.584254 -271.656048)
				(mid 354.177854 -271.656048)
				(end 354.584254 -271.656048)
			)
		)
		(stroke
			(width 0)
			(type solid)
		)
		(fill yes)
		(layer "In7.Cu")
		(net "P5E_CPU0_P0_RX_DN<9>")
	)
	(gr_poly
		(pts
			(arc
				(start 354.584254 -270.036036)
				(mid 354.177854 -270.036036)
				(end 354.584254 -270.036036)
			)
		)
		(stroke
			(width 0)
			(type solid)
		)
		(fill yes)
		(layer "In7.Cu")
		(net "P5E_CPU0_P0_RX_DN<11>")
	)
	(gr_poly
		(pts
			(arc
				(start 355.524308 -279.756108)
				(mid 355.117908 -279.756108)
				(end 355.524308 -279.756108)
			)
		)
		(stroke
			(width 0)
			(type solid)
		)
		(fill yes)
		(layer "In7.Cu")
		(net "P5E_CPU0_P1_RX_DP<11>")
	)
	(gr_poly
		(pts
			(arc
				(start 355.524308 -278.136096)
				(mid 355.117908 -278.136096)
				(end 355.524308 -278.136096)
			)
		)
		(stroke
			(width 0)
			(type solid)
		)
		(fill yes)
		(layer "In7.Cu")
		(net "P5E_CPU0_P1_RX_DP<10>")
	)
	(gr_poly
		(pts
			(arc
				(start 355.524308 -276.516084)
				(mid 355.117908 -276.516084)
				(end 355.524308 -276.516084)
			)
		)
		(stroke
			(width 0)
			(type solid)
		)
		(fill yes)
		(layer "In7.Cu")
		(net "P5E_CPU0_P1_RX_DP<9>")
	)
	(gr_poly
		(pts
			(arc
				(start 355.524308 -274.896072)
				(mid 355.117908 -274.896072)
				(end 355.524308 -274.896072)
			)
		)
		(stroke
			(width 0)
			(type solid)
		)
		(fill yes)
		(layer "In7.Cu")
		(net "P5E_CPU0_P1_RX_DP<12>")
	)
	(gr_poly
		(pts
			(arc
				(start 355.524308 -273.27606)
				(mid 355.117908 -273.27606)
				(end 355.524308 -273.27606)
			)
		)
		(stroke
			(width 0)
			(type solid)
		)
		(fill yes)
		(layer "In7.Cu")
		(net "P5E_CPU0_P0_RX_DP<10>")
	)
	(gr_poly
		(pts
			(arc
				(start 355.524308 -271.656048)
				(mid 355.117908 -271.656048)
				(end 355.524308 -271.656048)
			)
		)
		(stroke
			(width 0)
			(type solid)
		)
		(fill yes)
		(layer "In7.Cu")
		(net "P5E_CPU0_P0_RX_DP<9>")
	)
	(gr_poly
		(pts
			(arc
				(start 355.524308 -270.036036)
				(mid 355.117908 -270.036036)
				(end 355.524308 -270.036036)
			)
		)
		(stroke
			(width 0)
			(type solid)
		)
		(fill yes)
		(layer "In7.Cu")
		(net "P5E_CPU0_P0_RX_DP<11>")
	)
	(gr_poly
		(pts
			(arc
				(start 356.934262 -278.946102)
				(mid 356.527862 -278.946102)
				(end 356.934262 -278.946102)
			)
		)
		(stroke
			(width 0)
			(type solid)
		)
		(fill yes)
		(layer "In7.Cu")
		(net "P5E_CPU0_P1_RX_DN<13>")
	)
	(gr_poly
		(pts
			(arc
				(start 356.934262 -277.32609)
				(mid 356.527862 -277.32609)
				(end 356.934262 -277.32609)
			)
		)
		(stroke
			(width 0)
			(type solid)
		)
		(fill yes)
		(layer "In7.Cu")
		(net "P5E_CPU0_P1_RX_DN<14>")
	)
	(gr_poly
		(pts
			(arc
				(start 356.934262 -275.706078)
				(mid 356.527862 -275.706078)
				(end 356.934262 -275.706078)
			)
		)
		(stroke
			(width 0)
			(type solid)
		)
		(fill yes)
		(layer "In7.Cu")
		(net "P5E_CPU0_P1_RX_DN<15>")
	)
	(gr_poly
		(pts
			(arc
				(start 356.934262 -274.086066)
				(mid 356.527862 -274.086066)
				(end 356.934262 -274.086066)
			)
		)
		(stroke
			(width 0)
			(type solid)
		)
		(fill yes)
		(layer "In7.Cu")
		(net "P5E_CPU0_P0_RX_DN<13>")
	)
	(gr_poly
		(pts
			(arc
				(start 356.934262 -272.466054)
				(mid 356.527862 -272.466054)
				(end 356.934262 -272.466054)
			)
		)
		(stroke
			(width 0)
			(type solid)
		)
		(fill yes)
		(layer "In7.Cu")
		(net "P5E_CPU0_P0_RX_DN<12>")
	)
	(gr_poly
		(pts
			(arc
				(start 356.934262 -270.846042)
				(mid 356.527862 -270.846042)
				(end 356.934262 -270.846042)
			)
		)
		(stroke
			(width 0)
			(type solid)
		)
		(fill yes)
		(layer "In7.Cu")
		(net "P5E_CPU0_P0_RX_DN<14>")
	)
	(gr_poly
		(pts
			(arc
				(start 356.934262 -269.22603)
				(mid 356.527862 -269.22603)
				(end 356.934262 -269.22603)
			)
		)
		(stroke
			(width 0)
			(type solid)
		)
		(fill yes)
		(layer "In7.Cu")
		(net "P5E_CPU0_P0_RX_DN<15>")
	)
	(gr_poly
		(pts
			(arc
				(start 357.874316 -278.946102)
				(mid 357.467916 -278.946102)
				(end 357.874316 -278.946102)
			)
		)
		(stroke
			(width 0)
			(type solid)
		)
		(fill yes)
		(layer "In7.Cu")
		(net "P5E_CPU0_P1_RX_DP<13>")
	)
	(gr_poly
		(pts
			(arc
				(start 357.874316 -277.32609)
				(mid 357.467916 -277.32609)
				(end 357.874316 -277.32609)
			)
		)
		(stroke
			(width 0)
			(type solid)
		)
		(fill yes)
		(layer "In7.Cu")
		(net "P5E_CPU0_P1_RX_DP<14>")
	)
	(gr_poly
		(pts
			(arc
				(start 357.874316 -275.706078)
				(mid 357.467916 -275.706078)
				(end 357.874316 -275.706078)
			)
		)
		(stroke
			(width 0)
			(type solid)
		)
		(fill yes)
		(layer "In7.Cu")
		(net "P5E_CPU0_P1_RX_DP<15>")
	)
	(gr_poly
		(pts
			(arc
				(start 357.874316 -274.086066)
				(mid 357.467916 -274.086066)
				(end 357.874316 -274.086066)
			)
		)
		(stroke
			(width 0)
			(type solid)
		)
		(fill yes)
		(layer "In7.Cu")
		(net "P5E_CPU0_P0_RX_DP<13>")
	)
	(gr_poly
		(pts
			(arc
				(start 357.874316 -272.466054)
				(mid 357.467916 -272.466054)
				(end 357.874316 -272.466054)
			)
		)
		(stroke
			(width 0)
			(type solid)
		)
		(fill yes)
		(layer "In7.Cu")
		(net "P5E_CPU0_P0_RX_DP<12>")
	)
	(gr_poly
		(pts
			(arc
				(start 357.874316 -270.846042)
				(mid 357.467916 -270.846042)
				(end 357.874316 -270.846042)
			)
		)
		(stroke
			(width 0)
			(type solid)
		)
		(fill yes)
		(layer "In7.Cu")
		(net "P5E_CPU0_P0_RX_DP<14>")
	)
	(gr_poly
		(pts
			(arc
				(start 357.874316 -269.22603)
				(mid 357.467916 -269.22603)
				(end 357.874316 -269.22603)
			)
		)
		(stroke
			(width 0)
			(type solid)
		)
		(fill yes)
		(layer "In7.Cu")
		(net "P5E_CPU0_P0_RX_DP<15>")
	)
	(gr_poly
		(pts
			(arc
				(start 362.567982 -278.946102)
				(mid 362.161582 -278.946102)
				(end 362.567982 -278.946102)
			)
		)
		(stroke
			(width 0)
			(type solid)
		)
		(fill yes)
		(layer "In7.Cu")
		(net "P5E_CPU0_P3_TX_DP<2>")
	)
	(gr_poly
		(pts
			(arc
				(start 362.567982 -277.32609)
				(mid 362.161582 -277.32609)
				(end 362.567982 -277.32609)
			)
		)
		(stroke
			(width 0)
			(type solid)
		)
		(fill yes)
		(layer "In7.Cu")
		(net "P5E_CPU0_P3_TX_DP<1>")
	)
	(gr_poly
		(pts
			(arc
				(start 362.567982 -275.706078)
				(mid 362.161582 -275.706078)
				(end 362.567982 -275.706078)
			)
		)
		(stroke
			(width 0)
			(type solid)
		)
		(fill yes)
		(layer "In7.Cu")
		(net "P5E_CPU0_P3_TX_DP<0>")
	)
	(gr_poly
		(pts
			(arc
				(start 362.567982 -274.086066)
				(mid 362.161582 -274.086066)
				(end 362.567982 -274.086066)
			)
		)
		(stroke
			(width 0)
			(type solid)
		)
		(fill yes)
		(layer "In7.Cu")
		(net "P5E_CPU0_P2_TX_DP<2>")
	)
	(gr_poly
		(pts
			(arc
				(start 362.567982 -272.466054)
				(mid 362.161582 -272.466054)
				(end 362.567982 -272.466054)
			)
		)
		(stroke
			(width 0)
			(type solid)
		)
		(fill yes)
		(layer "In7.Cu")
		(net "P5E_CPU0_P2_TX_DP<3>")
	)
	(gr_poly
		(pts
			(arc
				(start 362.567982 -270.846042)
				(mid 362.161582 -270.846042)
				(end 362.567982 -270.846042)
			)
		)
		(stroke
			(width 0)
			(type solid)
		)
		(fill yes)
		(layer "In7.Cu")
		(net "P5E_CPU0_P2_TX_DP<1>")
	)
	(gr_poly
		(pts
			(arc
				(start 362.567982 -269.22603)
				(mid 362.161582 -269.22603)
				(end 362.567982 -269.22603)
			)
		)
		(stroke
			(width 0)
			(type solid)
		)
		(fill yes)
		(layer "In7.Cu")
		(net "P5E_CPU0_P2_TX_DP<0>")
	)
	(gr_poly
		(pts
			(arc
				(start 363.508036 -278.946102)
				(mid 363.101636 -278.946102)
				(end 363.508036 -278.946102)
			)
		)
		(stroke
			(width 0)
			(type solid)
		)
		(fill yes)
		(layer "In7.Cu")
		(net "P5E_CPU0_P3_TX_DN<2>")
	)
	(gr_poly
		(pts
			(arc
				(start 363.508036 -277.32609)
				(mid 363.101636 -277.32609)
				(end 363.508036 -277.32609)
			)
		)
		(stroke
			(width 0)
			(type solid)
		)
		(fill yes)
		(layer "In7.Cu")
		(net "P5E_CPU0_P3_TX_DN<1>")
	)
	(gr_poly
		(pts
			(arc
				(start 363.508036 -275.706078)
				(mid 363.101636 -275.706078)
				(end 363.508036 -275.706078)
			)
		)
		(stroke
			(width 0)
			(type solid)
		)
		(fill yes)
		(layer "In7.Cu")
		(net "P5E_CPU0_P3_TX_DN<0>")
	)
	(gr_poly
		(pts
			(arc
				(start 363.508036 -274.086066)
				(mid 363.101636 -274.086066)
				(end 363.508036 -274.086066)
			)
		)
		(stroke
			(width 0)
			(type solid)
		)
		(fill yes)
		(layer "In7.Cu")
		(net "P5E_CPU0_P2_TX_DN<2>")
	)
	(gr_poly
		(pts
			(arc
				(start 363.508036 -272.466054)
				(mid 363.101636 -272.466054)
				(end 363.508036 -272.466054)
			)
		)
		(stroke
			(width 0)
			(type solid)
		)
		(fill yes)
		(layer "In7.Cu")
		(net "P5E_CPU0_P2_TX_DN<3>")
	)
	(gr_poly
		(pts
			(arc
				(start 363.508036 -270.846042)
				(mid 363.101636 -270.846042)
				(end 363.508036 -270.846042)
			)
		)
		(stroke
			(width 0)
			(type solid)
		)
		(fill yes)
		(layer "In7.Cu")
		(net "P5E_CPU0_P2_TX_DN<1>")
	)
	(gr_poly
		(pts
			(arc
				(start 363.508036 -269.22603)
				(mid 363.101636 -269.22603)
				(end 363.508036 -269.22603)
			)
		)
		(stroke
			(width 0)
			(type solid)
		)
		(fill yes)
		(layer "In7.Cu")
		(net "P5E_CPU0_P2_TX_DN<0>")
	)
	(gr_poly
		(pts
			(arc
				(start 364.91799 -279.756108)
				(mid 364.51159 -279.756108)
				(end 364.91799 -279.756108)
			)
		)
		(stroke
			(width 0)
			(type solid)
		)
		(fill yes)
		(layer "In7.Cu")
		(net "P5E_CPU0_P3_TX_DP<4>")
	)
	(gr_poly
		(pts
			(arc
				(start 364.91799 -278.136096)
				(mid 364.51159 -278.136096)
				(end 364.91799 -278.136096)
			)
		)
		(stroke
			(width 0)
			(type solid)
		)
		(fill yes)
		(layer "In7.Cu")
		(net "P5E_CPU0_P3_TX_DP<5>")
	)
	(gr_poly
		(pts
			(arc
				(start 364.91799 -276.516084)
				(mid 364.51159 -276.516084)
				(end 364.91799 -276.516084)
			)
		)
		(stroke
			(width 0)
			(type solid)
		)
		(fill yes)
		(layer "In7.Cu")
		(net "P5E_CPU0_P3_TX_DP<6>")
	)
	(gr_poly
		(pts
			(arc
				(start 364.91799 -274.896072)
				(mid 364.51159 -274.896072)
				(end 364.91799 -274.896072)
			)
		)
		(stroke
			(width 0)
			(type solid)
		)
		(fill yes)
		(layer "In7.Cu")
		(net "P5E_CPU0_P3_TX_DP<3>")
	)
	(gr_poly
		(pts
			(arc
				(start 364.91799 -273.27606)
				(mid 364.51159 -273.27606)
				(end 364.91799 -273.27606)
			)
		)
		(stroke
			(width 0)
			(type solid)
		)
		(fill yes)
		(layer "In7.Cu")
		(net "P5E_CPU0_P2_TX_DP<5>")
	)
	(gr_poly
		(pts
			(arc
				(start 364.91799 -271.656048)
				(mid 364.51159 -271.656048)
				(end 364.91799 -271.656048)
			)
		)
		(stroke
			(width 0)
			(type solid)
		)
		(fill yes)
		(layer "In7.Cu")
		(net "P5E_CPU0_P2_TX_DP<6>")
	)
	(gr_poly
		(pts
			(arc
				(start 364.91799 -270.036036)
				(mid 364.51159 -270.036036)
				(end 364.91799 -270.036036)
			)
		)
		(stroke
			(width 0)
			(type solid)
		)
		(fill yes)
		(layer "In7.Cu")
		(net "P5E_CPU0_P2_TX_DP<4>")
	)
	(gr_poly
		(pts
			(arc
				(start 365.858044 -279.756108)
				(mid 365.451644 -279.756108)
				(end 365.858044 -279.756108)
			)
		)
		(stroke
			(width 0)
			(type solid)
		)
		(fill yes)
		(layer "In7.Cu")
		(net "P5E_CPU0_P3_TX_DN<4>")
	)
	(gr_poly
		(pts
			(arc
				(start 365.858044 -278.136096)
				(mid 365.451644 -278.136096)
				(end 365.858044 -278.136096)
			)
		)
		(stroke
			(width 0)
			(type solid)
		)
		(fill yes)
		(layer "In7.Cu")
		(net "P5E_CPU0_P3_TX_DN<5>")
	)
	(gr_poly
		(pts
			(arc
				(start 365.858044 -276.516084)
				(mid 365.451644 -276.516084)
				(end 365.858044 -276.516084)
			)
		)
		(stroke
			(width 0)
			(type solid)
		)
		(fill yes)
		(layer "In7.Cu")
		(net "P5E_CPU0_P3_TX_DN<6>")
	)
	(gr_poly
		(pts
			(arc
				(start 365.858044 -274.896072)
				(mid 365.451644 -274.896072)
				(end 365.858044 -274.896072)
			)
		)
		(stroke
			(width 0)
			(type solid)
		)
		(fill yes)
		(layer "In7.Cu")
		(net "P5E_CPU0_P3_TX_DN<3>")
	)
	(gr_poly
		(pts
			(arc
				(start 365.858044 -273.27606)
				(mid 365.451644 -273.27606)
				(end 365.858044 -273.27606)
			)
		)
		(stroke
			(width 0)
			(type solid)
		)
		(fill yes)
		(layer "In7.Cu")
		(net "P5E_CPU0_P2_TX_DN<5>")
	)
	(gr_poly
		(pts
			(arc
				(start 365.858044 -271.656048)
				(mid 365.451644 -271.656048)
				(end 365.858044 -271.656048)
			)
		)
		(stroke
			(width 0)
			(type solid)
		)
		(fill yes)
		(layer "In7.Cu")
		(net "P5E_CPU0_P2_TX_DN<6>")
	)
	(gr_poly
		(pts
			(arc
				(start 365.858044 -270.036036)
				(mid 365.451644 -270.036036)
				(end 365.858044 -270.036036)
			)
		)
		(stroke
			(width 0)
			(type solid)
		)
		(fill yes)
		(layer "In7.Cu")
		(net "P5E_CPU0_P2_TX_DN<4>")
	)
	(gr_poly
		(pts
			(arc
				(start 367.737898 -278.136096)
				(mid 367.331498 -278.136096)
				(end 367.737898 -278.136096)
			)
		)
		(stroke
			(width 0)
			(type solid)
		)
		(fill yes)
		(layer "In7.Cu")
		(net "P5E_CPU0_P3_TX_DP<8>")
	)
	(gr_poly
		(pts
			(arc
				(start 367.737898 -276.516084)
				(mid 367.331498 -276.516084)
				(end 367.737898 -276.516084)
			)
		)
		(stroke
			(width 0)
			(type solid)
		)
		(fill yes)
		(layer "In7.Cu")
		(net "P5E_CPU0_P3_TX_DP<9>")
	)
	(gr_poly
		(pts
			(arc
				(start 367.737898 -274.896072)
				(mid 367.331498 -274.896072)
				(end 367.737898 -274.896072)
			)
		)
		(stroke
			(width 0)
			(type solid)
		)
		(fill yes)
		(layer "In7.Cu")
		(net "P5E_CPU0_P3_TX_DP<7>")
	)
	(gr_poly
		(pts
			(arc
				(start 367.737898 -273.27606)
				(mid 367.331498 -273.27606)
				(end 367.737898 -273.27606)
			)
		)
		(stroke
			(width 0)
			(type solid)
		)
		(fill yes)
		(layer "In7.Cu")
		(net "P5E_CPU0_P2_TX_DP<8>")
	)
	(gr_poly
		(pts
			(arc
				(start 367.737898 -271.656048)
				(mid 367.331498 -271.656048)
				(end 367.737898 -271.656048)
			)
		)
		(stroke
			(width 0)
			(type solid)
		)
		(fill yes)
		(layer "In7.Cu")
		(net "P5E_CPU0_P2_TX_DP<9>")
	)
	(gr_poly
		(pts
			(arc
				(start 367.737898 -270.036036)
				(mid 367.331498 -270.036036)
				(end 367.737898 -270.036036)
			)
		)
		(stroke
			(width 0)
			(type solid)
		)
		(fill yes)
		(layer "In7.Cu")
		(net "P5E_CPU0_P2_TX_DP<7>")
	)
	(gr_poly
		(pts
			(arc
				(start 368.677952 -278.136096)
				(mid 368.271552 -278.136096)
				(end 368.677952 -278.136096)
			)
		)
		(stroke
			(width 0)
			(type solid)
		)
		(fill yes)
		(layer "In7.Cu")
		(net "P5E_CPU0_P3_TX_DN<8>")
	)
	(gr_poly
		(pts
			(arc
				(start 368.677952 -276.516084)
				(mid 368.271552 -276.516084)
				(end 368.677952 -276.516084)
			)
		)
		(stroke
			(width 0)
			(type solid)
		)
		(fill yes)
		(layer "In7.Cu")
		(net "P5E_CPU0_P3_TX_DN<9>")
	)
	(gr_poly
		(pts
			(arc
				(start 368.677952 -274.896072)
				(mid 368.271552 -274.896072)
				(end 368.677952 -274.896072)
			)
		)
		(stroke
			(width 0)
			(type solid)
		)
		(fill yes)
		(layer "In7.Cu")
		(net "P5E_CPU0_P3_TX_DN<7>")
	)
	(gr_poly
		(pts
			(arc
				(start 368.677952 -273.27606)
				(mid 368.271552 -273.27606)
				(end 368.677952 -273.27606)
			)
		)
		(stroke
			(width 0)
			(type solid)
		)
		(fill yes)
		(layer "In7.Cu")
		(net "P5E_CPU0_P2_TX_DN<8>")
	)
	(gr_poly
		(pts
			(arc
				(start 368.677952 -271.656048)
				(mid 368.271552 -271.656048)
				(end 368.677952 -271.656048)
			)
		)
		(stroke
			(width 0)
			(type solid)
		)
		(fill yes)
		(layer "In7.Cu")
		(net "P5E_CPU0_P2_TX_DN<9>")
	)
	(gr_poly
		(pts
			(arc
				(start 368.677952 -270.036036)
				(mid 368.271552 -270.036036)
				(end 368.677952 -270.036036)
			)
		)
		(stroke
			(width 0)
			(type solid)
		)
		(fill yes)
		(layer "In7.Cu")
		(net "P5E_CPU0_P2_TX_DN<7>")
	)
	(gr_poly
		(pts
			(arc
				(start 370.55806 -278.136096)
				(mid 370.15166 -278.136096)
				(end 370.55806 -278.136096)
			)
		)
		(stroke
			(width 0)
			(type solid)
		)
		(fill yes)
		(layer "In7.Cu")
		(net "P5E_CPU0_P3_TX_DP<11>")
	)
	(gr_poly
		(pts
			(arc
				(start 370.55806 -276.516084)
				(mid 370.15166 -276.516084)
				(end 370.55806 -276.516084)
			)
		)
		(stroke
			(width 0)
			(type solid)
		)
		(fill yes)
		(layer "In7.Cu")
		(net "P5E_CPU0_P3_TX_DP<12>")
	)
	(gr_poly
		(pts
			(arc
				(start 370.55806 -274.896072)
				(mid 370.15166 -274.896072)
				(end 370.55806 -274.896072)
			)
		)
		(stroke
			(width 0)
			(type solid)
		)
		(fill yes)
		(layer "In7.Cu")
		(net "P5E_CPU0_P3_TX_DP<10>")
	)
	(gr_poly
		(pts
			(arc
				(start 370.55806 -273.27606)
				(mid 370.15166 -273.27606)
				(end 370.55806 -273.27606)
			)
		)
		(stroke
			(width 0)
			(type solid)
		)
		(fill yes)
		(layer "In7.Cu")
		(net "P5E_CPU0_P2_TX_DP<11>")
	)
	(gr_poly
		(pts
			(arc
				(start 370.55806 -271.656048)
				(mid 370.15166 -271.656048)
				(end 370.55806 -271.656048)
			)
		)
		(stroke
			(width 0)
			(type solid)
		)
		(fill yes)
		(layer "In7.Cu")
		(net "P5E_CPU0_P2_TX_DP<12>")
	)
	(gr_poly
		(pts
			(arc
				(start 370.55806 -270.036036)
				(mid 370.15166 -270.036036)
				(end 370.55806 -270.036036)
			)
		)
		(stroke
			(width 0)
			(type solid)
		)
		(fill yes)
		(layer "In7.Cu")
		(net "P5E_CPU0_P2_TX_DP<10>")
	)
	(gr_poly
		(pts
			(arc
				(start 371.498114 -278.136096)
				(mid 371.091714 -278.136096)
				(end 371.498114 -278.136096)
			)
		)
		(stroke
			(width 0)
			(type solid)
		)
		(fill yes)
		(layer "In7.Cu")
		(net "P5E_CPU0_P3_TX_DN<11>")
	)
	(gr_poly
		(pts
			(arc
				(start 371.498114 -276.516084)
				(mid 371.091714 -276.516084)
				(end 371.498114 -276.516084)
			)
		)
		(stroke
			(width 0)
			(type solid)
		)
		(fill yes)
		(layer "In7.Cu")
		(net "P5E_CPU0_P3_TX_DN<12>")
	)
	(gr_poly
		(pts
			(arc
				(start 371.498114 -274.896072)
				(mid 371.091714 -274.896072)
				(end 371.498114 -274.896072)
			)
		)
		(stroke
			(width 0)
			(type solid)
		)
		(fill yes)
		(layer "In7.Cu")
		(net "P5E_CPU0_P3_TX_DN<10>")
	)
	(gr_poly
		(pts
			(arc
				(start 371.498114 -273.27606)
				(mid 371.091714 -273.27606)
				(end 371.498114 -273.27606)
			)
		)
		(stroke
			(width 0)
			(type solid)
		)
		(fill yes)
		(layer "In7.Cu")
		(net "P5E_CPU0_P2_TX_DN<11>")
	)
	(gr_poly
		(pts
			(arc
				(start 371.498114 -271.656048)
				(mid 371.091714 -271.656048)
				(end 371.498114 -271.656048)
			)
		)
		(stroke
			(width 0)
			(type solid)
		)
		(fill yes)
		(layer "In7.Cu")
		(net "P5E_CPU0_P2_TX_DN<12>")
	)
	(gr_poly
		(pts
			(arc
				(start 371.498114 -270.036036)
				(mid 371.091714 -270.036036)
				(end 371.498114 -270.036036)
			)
		)
		(stroke
			(width 0)
			(type solid)
		)
		(fill yes)
		(layer "In7.Cu")
		(net "P5E_CPU0_P2_TX_DN<10>")
	)
	(gr_poly
		(pts
			(arc
				(start 373.377968 -278.136096)
				(mid 372.971568 -278.136096)
				(end 373.377968 -278.136096)
			)
		)
		(stroke
			(width 0)
			(type solid)
		)
		(fill yes)
		(layer "In7.Cu")
		(net "P5E_CPU0_P3_TX_DP<14>")
	)
	(gr_poly
		(pts
			(arc
				(start 373.377968 -276.516084)
				(mid 372.971568 -276.516084)
				(end 373.377968 -276.516084)
			)
		)
		(stroke
			(width 0)
			(type solid)
		)
		(fill yes)
		(layer "In7.Cu")
		(net "P5E_CPU0_P3_TX_DP<15>")
	)
	(gr_poly
		(pts
			(arc
				(start 373.377968 -274.896072)
				(mid 372.971568 -274.896072)
				(end 373.377968 -274.896072)
			)
		)
		(stroke
			(width 0)
			(type solid)
		)
		(fill yes)
		(layer "In7.Cu")
		(net "P5E_CPU0_P3_TX_DP<13>")
	)
	(gr_poly
		(pts
			(arc
				(start 373.377968 -273.27606)
				(mid 372.971568 -273.27606)
				(end 373.377968 -273.27606)
			)
		)
		(stroke
			(width 0)
			(type solid)
		)
		(fill yes)
		(layer "In7.Cu")
		(net "P5E_CPU0_P2_TX_DP<14>")
	)
	(gr_poly
		(pts
			(arc
				(start 373.377968 -271.656048)
				(mid 372.971568 -271.656048)
				(end 373.377968 -271.656048)
			)
		)
		(stroke
			(width 0)
			(type solid)
		)
		(fill yes)
		(layer "In7.Cu")
		(net "P5E_CPU0_P2_TX_DP<15>")
	)
	(gr_poly
		(pts
			(arc
				(start 373.377968 -270.036036)
				(mid 372.971568 -270.036036)
				(end 373.377968 -270.036036)
			)
		)
		(stroke
			(width 0)
			(type solid)
		)
		(fill yes)
		(layer "In7.Cu")
		(net "P5E_CPU0_P2_TX_DP<13>")
	)
	(gr_poly
		(pts
			(arc
				(start 374.318022 -278.136096)
				(mid 373.911622 -278.136096)
				(end 374.318022 -278.136096)
			)
		)
		(stroke
			(width 0)
			(type solid)
		)
		(fill yes)
		(layer "In7.Cu")
		(net "P5E_CPU0_P3_TX_DN<14>")
	)
	(gr_poly
		(pts
			(arc
				(start 374.318022 -276.516084)
				(mid 373.911622 -276.516084)
				(end 374.318022 -276.516084)
			)
		)
		(stroke
			(width 0)
			(type solid)
		)
		(fill yes)
		(layer "In7.Cu")
		(net "P5E_CPU0_P3_TX_DN<15>")
	)
	(gr_poly
		(pts
			(arc
				(start 374.318022 -274.896072)
				(mid 373.911622 -274.896072)
				(end 374.318022 -274.896072)
			)
		)
		(stroke
			(width 0)
			(type solid)
		)
		(fill yes)
		(layer "In7.Cu")
		(net "P5E_CPU0_P3_TX_DN<13>")
	)
	(gr_poly
		(pts
			(arc
				(start 374.318022 -273.27606)
				(mid 373.911622 -273.27606)
				(end 374.318022 -273.27606)
			)
		)
		(stroke
			(width 0)
			(type solid)
		)
		(fill yes)
		(layer "In7.Cu")
		(net "P5E_CPU0_P2_TX_DN<14>")
	)
	(gr_poly
		(pts
			(arc
				(start 374.318022 -271.656048)
				(mid 373.911622 -271.656048)
				(end 374.318022 -271.656048)
			)
		)
		(stroke
			(width 0)
			(type solid)
		)
		(fill yes)
		(layer "In7.Cu")
		(net "P5E_CPU0_P2_TX_DN<15>")
	)
	(gr_poly
		(pts
			(arc
				(start 374.318022 -270.036036)
				(mid 373.911622 -270.036036)
				(end 374.318022 -270.036036)
			)
		)
		(stroke
			(width 0)
			(type solid)
		)
		(fill yes)
		(layer "In7.Cu")
		(net "P5E_CPU0_P2_TX_DN<13>")
	)
	(gr_poly
		(pts
			(arc
				(start 273.15541 -393.27836)
				(mid 273.174933 -393.274459)
				(end 273.191478 -393.263374)
			)
			(xy 273.191732 -393.26312) (xy 273.669252 -392.7856)
			(arc
				(start 273.669506 -392.785346)
				(mid 273.680617 -392.768812)
				(end 273.684492 -392.749278)
			)
			(arc
				(start 273.684492 -384.155442)
				(mid 273.680591 -384.135919)
				(end 273.669506 -384.119374)
			)
			(xy 273.669252 -384.11912) (xy 273.447764 -383.897632) (xy 273.447256 -383.897124)
			(arc
				(start 273.445478 -383.895346)
				(mid 273.428944 -383.884235)
				(end 273.40941 -383.88036)
			)
			(arc
				(start 239.542574 -383.88036)
				(mid 239.523051 -383.884261)
				(end 239.506506 -383.895346)
			)
			(xy 239.506252 -383.8956) (xy 239.03051 -384.371342) (xy 239.030256 -384.371596)
			(arc
				(start 239.028478 -384.373374)
				(mid 239.017367 -384.389908)
				(end 239.013492 -384.409442)
			)
			(arc
				(start 239.013492 -393.003278)
				(mid 239.017393 -393.022801)
				(end 239.028478 -393.039346)
			)
			(xy 239.028732 -393.0396) (xy 239.252252 -393.26312)
			(arc
				(start 239.252506 -393.263374)
				(mid 239.26904 -393.274485)
				(end 239.288574 -393.27836)
			)
		)
		(stroke
			(width 0)
			(type solid)
		)
		(fill yes)
		(layer "In7.Cu")
		(net "P12V_MAIN_R")
	)
	(gr_poly
		(pts
			(arc
				(start 228.921818 -436.47868)
				(mid 228.941341 -436.474779)
				(end 228.957886 -436.463694)
			)
			(arc
				(start 229.664514 -435.757066)
				(mid 229.675625 -435.740532)
				(end 229.6795 -435.720998)
			)
			(arc
				(start 229.6795 -422.180766)
				(mid 229.703653 -422.05925)
				(end 229.772464 -421.95623)
			)
			(arc
				(start 234.67314 -417.055554)
				(mid 234.776172 -416.986773)
				(end 234.897676 -416.96259)
			)
			(arc
				(start 272.037556 -416.96259)
				(mid 272.057079 -416.958689)
				(end 272.073624 -416.947604)
			)
			(arc
				(start 280.035254 -408.985974)
				(mid 280.046365 -408.96944)
				(end 280.05024 -408.949906)
			)
			(arc
				(start 280.05024 -394.963396)
				(mid 280.046339 -394.943873)
				(end 280.035254 -394.927328)
			)
			(xy 280.035 -394.927074) (xy 279.65146 -394.543534)
			(arc
				(start 279.651206 -394.54328)
				(mid 279.634672 -394.532169)
				(end 279.615138 -394.528294)
			)
			(arc
				(start 278.051514 -394.528294)
				(mid 278.036928 -394.530433)
				(end 278.023574 -394.536676)
			)
			(arc
				(start 278.023574 -394.536676)
				(mid 277.823537 -394.629726)
				(end 277.605236 -394.661644)
			)
			(arc
				(start 277.605236 -394.661644)
				(mid 277.421236 -394.639047)
				(end 277.248112 -394.572744)
			)
			(arc
				(start 277.248112 -394.572744)
				(mid 277.224236 -394.566797)
				(end 277.20036 -394.572744)
			)
			(arc
				(start 277.20036 -394.572744)
				(mid 277.027244 -394.639078)
				(end 276.843236 -394.661644)
			)
			(arc
				(start 276.843236 -394.661644)
				(mid 276.624932 -394.629737)
				(end 276.424898 -394.536676)
			)
			(arc
				(start 276.424898 -394.536676)
				(mid 276.411542 -394.53044)
				(end 276.396958 -394.528294)
			)
			(arc
				(start 269.04569 -394.528294)
				(mid 269.030398 -394.53065)
				(end 269.01648 -394.537438)
			)
			(arc
				(start 269.01648 -394.537438)
				(mid 268.808203 -394.640414)
				(end 268.578584 -394.675868)
			)
			(arc
				(start 268.578584 -394.675868)
				(mid 268.394584 -394.653271)
				(end 268.22146 -394.586968)
			)
			(arc
				(start 268.22146 -394.586968)
				(mid 268.197584 -394.581021)
				(end 268.173708 -394.586968)
			)
			(arc
				(start 268.173708 -394.586968)
				(mid 268.000592 -394.653302)
				(end 267.816584 -394.675868)
			)
			(arc
				(start 267.816584 -394.675868)
				(mid 267.586971 -394.640395)
				(end 267.378688 -394.537438)
			)
			(arc
				(start 267.378688 -394.537438)
				(mid 267.364793 -394.530577)
				(end 267.349478 -394.528294)
			)
			(arc
				(start 261.01929 -394.528294)
				(mid 261.003998 -394.53065)
				(end 260.99008 -394.537438)
			)
			(arc
				(start 260.99008 -394.537438)
				(mid 260.781803 -394.640414)
				(end 260.552184 -394.675868)
			)
			(arc
				(start 260.552184 -394.675868)
				(mid 260.368184 -394.653271)
				(end 260.19506 -394.586968)
			)
			(arc
				(start 260.19506 -394.586968)
				(mid 260.171184 -394.581021)
				(end 260.147308 -394.586968)
			)
			(arc
				(start 260.147308 -394.586968)
				(mid 259.974192 -394.653302)
				(end 259.790184 -394.675868)
			)
			(arc
				(start 259.790184 -394.675868)
				(mid 259.560571 -394.640395)
				(end 259.352288 -394.537438)
			)
			(arc
				(start 259.352288 -394.537438)
				(mid 259.338393 -394.530577)
				(end 259.323078 -394.528294)
			)
			(arc
				(start 252.99289 -394.528294)
				(mid 252.977598 -394.53065)
				(end 252.96368 -394.537438)
			)
			(arc
				(start 252.96368 -394.537438)
				(mid 252.755403 -394.640414)
				(end 252.525784 -394.675868)
			)
			(arc
				(start 252.525784 -394.675868)
				(mid 252.341784 -394.653271)
				(end 252.16866 -394.586968)
			)
			(arc
				(start 252.16866 -394.586968)
				(mid 252.144784 -394.581021)
				(end 252.120908 -394.586968)
			)
			(arc
				(start 252.120908 -394.586968)
				(mid 251.947792 -394.653302)
				(end 251.763784 -394.675868)
			)
			(arc
				(start 251.763784 -394.675868)
				(mid 251.534171 -394.640395)
				(end 251.325888 -394.537438)
			)
			(arc
				(start 251.325888 -394.537438)
				(mid 251.311993 -394.530577)
				(end 251.296678 -394.528294)
			)
			(arc
				(start 244.9576 -394.528294)
				(mid 244.942576 -394.530567)
				(end 244.928898 -394.537184)
			)
			(arc
				(start 244.928898 -394.537184)
				(mid 244.722849 -394.637373)
				(end 244.496336 -394.671804)
			)
			(arc
				(start 244.496336 -394.671804)
				(mid 244.312336 -394.649207)
				(end 244.139212 -394.582904)
			)
			(arc
				(start 244.139212 -394.582904)
				(mid 244.115336 -394.576957)
				(end 244.09146 -394.582904)
			)
			(arc
				(start 244.09146 -394.582904)
				(mid 243.918344 -394.649238)
				(end 243.734336 -394.671804)
			)
			(arc
				(start 243.734336 -394.671804)
				(mid 243.507823 -394.637371)
				(end 243.301774 -394.537184)
			)
			(arc
				(start 243.301774 -394.537184)
				(mid 243.288095 -394.53057)
				(end 243.273072 -394.528294)
			)
			(arc
				(start 239.250982 -394.528294)
				(mid 239.215061 -394.543173)
				(end 239.200182 -394.579094)
			)
			(arc
				(start 239.200182 -405.390096)
				(mid 239.176029 -405.511612)
				(end 239.107218 -405.614632)
			)
			(arc
				(start 238.94034 -405.78151)
				(mid 238.837308 -405.850291)
				(end 238.715804 -405.874474)
			)
			(arc
				(start 234.522264 -405.874474)
				(mid 234.400748 -405.850321)
				(end 234.297728 -405.78151)
			)
			(arc
				(start 233.595926 -405.079708)
				(mid 233.527145 -404.976676)
				(end 233.502962 -404.855172)
			)
			(arc
				(start 233.502962 -404.072344)
				(mid 233.499061 -404.052821)
				(end 233.487976 -404.036276)
			)
			(arc
				(start 233.3498 -403.8981)
				(mid 233.281019 -403.795068)
				(end 233.256836 -403.673564)
			)
			(arc
				(start 233.256836 -400.256502)
				(mid 233.252935 -400.236979)
				(end 233.24185 -400.220434)
			)
			(arc
				(start 233.236008 -400.214592)
				(mid 233.219474 -400.203481)
				(end 233.19994 -400.199606)
			)
			(arc
				(start 229.898956 -400.199606)
				(mid 229.879433 -400.203507)
				(end 229.862888 -400.214592)
			)
			(arc
				(start 229.848664 -400.228816)
				(mid 229.837553 -400.24535)
				(end 229.833678 -400.264884)
			)
			(arc
				(start 229.833678 -403.583648)
				(mid 229.809525 -403.705164)
				(end 229.740714 -403.808184)
			)
			(arc
				(start 229.66426 -403.884638)
				(mid 229.653149 -403.901172)
				(end 229.649274 -403.920706)
			)
			(arc
				(start 229.649274 -406.19299)
				(mid 229.625121 -406.314506)
				(end 229.55631 -406.417526)
			)
			(arc
				(start 227.443284 -408.530552)
				(mid 227.340252 -408.599333)
				(end 227.218748 -408.623516)
			)
			(arc
				(start 225.642424 -408.623516)
				(mid 225.623565 -408.627146)
				(end 225.607372 -408.637486)
			)
			(arc
				(start 225.607372 -408.637486)
				(mid 225.364908 -408.792887)
				(end 225.0821 -408.84729)
			)
			(arc
				(start 225.0821 -408.84729)
				(mid 224.549885 -408.630828)
				(end 224.319846 -408.10434)
			)
			(xy 224.319592 -408.094434) (xy 224.311972 -408.076654)
			(arc
				(start 222.874586 -406.639268)
				(mid 222.805805 -406.536236)
				(end 222.781622 -406.414732)
			)
			(arc
				(start 222.781622 -403.953472)
				(mid 222.777721 -403.933949)
				(end 222.766636 -403.917404)
			)
			(arc
				(start 222.681546 -403.832314)
				(mid 222.612765 -403.729282)
				(end 222.588582 -403.607778)
			)
			(xy 222.588582 -400.229832) (xy 222.580962 -400.21129) (xy 222.57766 -400.207988)
			(arc
				(start 219.197936 -400.207988)
				(mid 219.178413 -400.211889)
				(end 219.161868 -400.222974)
			)
			(xy 219.157296 -400.227546)
			(arc
				(start 219.157296 -403.583394)
				(mid 219.133143 -403.70491)
				(end 219.064332 -403.80793)
			)
			(arc
				(start 219.00007 -403.872192)
				(mid 218.988959 -403.888726)
				(end 218.985084 -403.90826)
			)
			(arc
				(start 218.985084 -406.217374)
				(mid 218.960931 -406.33889)
				(end 218.89212 -406.44191)
			)
			(arc
				(start 216.76614 -408.56789)
				(mid 216.663108 -408.636671)
				(end 216.541604 -408.660854)
			)
			(arc
				(start 214.93226 -408.660854)
				(mid 214.915131 -408.66392)
				(end 214.900002 -408.672538)
			)
			(arc
				(start 214.900002 -408.672538)
				(mid 214.672289 -408.802264)
				(end 214.4141 -408.84729)
			)
			(arc
				(start 214.4141 -408.84729)
				(mid 213.886272 -408.635069)
				(end 213.652354 -408.116532)
			)
			(xy 213.651846 -408.10688) (xy 213.644226 -408.089608)
			(arc
				(start 212.189822 -406.635204)
				(mid 212.121041 -406.532172)
				(end 212.096858 -406.410668)
			)
			(arc
				(start 212.096858 -403.916642)
				(mid 212.092957 -403.897119)
				(end 212.081872 -403.880574)
			)
			(arc
				(start 212.058504 -403.857206)
				(mid 211.989723 -403.754174)
				(end 211.96554 -403.63267)
			)
			(arc
				(start 211.96554 -400.29765)
				(mid 211.961639 -400.278127)
				(end 211.950554 -400.261582)
			)
			(arc
				(start 211.854542 -400.16557)
				(mid 211.838008 -400.154459)
				(end 211.818474 -400.150584)
			)
			(arc
				(start 208.578704 -400.150584)
				(mid 208.559181 -400.154485)
				(end 208.542636 -400.16557)
			)
			(arc
				(start 208.512156 -400.19605)
				(mid 208.501045 -400.212584)
				(end 208.49717 -400.232118)
			)
			(arc
				(start 208.49717 -403.534118)
				(mid 208.473017 -403.655634)
				(end 208.404206 -403.758654)
			)
			(arc
				(start 208.323688 -403.839172)
				(mid 208.312577 -403.855706)
				(end 208.308702 -403.87524)
			)
			(arc
				(start 208.308702 -406.275032)
				(mid 208.284549 -406.396548)
				(end 208.215738 -406.499568)
			)
			(arc
				(start 206.172562 -408.542744)
				(mid 206.06953 -408.611525)
				(end 205.948026 -408.635708)
			)
			(arc
				(start 204.293216 -408.635708)
				(mid 204.274946 -408.639107)
				(end 204.25918 -408.648916)
			)
			(arc
				(start 204.25918 -408.648916)
				(mid 204.021144 -408.79596)
				(end 203.7461 -408.84729)
			)
			(arc
				(start 203.7461 -408.84729)
				(mid 203.306844 -408.708001)
				(end 203.028042 -408.341068)
			)
			(xy 203.023978 -408.330146)
			(arc
				(start 201.5871 -406.893268)
				(mid 201.518319 -406.790236)
				(end 201.494136 -406.668732)
			)
			(arc
				(start 201.494136 -403.941026)
				(mid 201.490235 -403.921503)
				(end 201.47915 -403.904958)
			)
			(arc
				(start 201.373994 -403.799802)
				(mid 201.305213 -403.69677)
				(end 201.28103 -403.575266)
			)
			(arc
				(start 201.28103 -400.264884)
				(mid 201.277129 -400.245361)
				(end 201.266044 -400.228816)
			)
			(arc
				(start 201.221594 -400.184366)
				(mid 201.20506 -400.173255)
				(end 201.185526 -400.16938)
			)
			(arc
				(start 197.9168 -400.16938)
				(mid 197.897277 -400.173281)
				(end 197.880732 -400.184366)
			)
			(arc
				(start 197.844156 -400.220942)
				(mid 197.833045 -400.237476)
				(end 197.82917 -400.25701)
			)
			(arc
				(start 197.82917 -403.58314)
				(mid 197.805017 -403.704656)
				(end 197.736206 -403.807676)
			)
			(arc
				(start 195.6435 -405.900382)
				(mid 195.540468 -405.969163)
				(end 195.418964 -405.993346)
			)
			(arc
				(start 191.073786 -405.993346)
				(mid 190.95227 -405.969193)
				(end 190.84925 -405.900382)
			)
			(arc
				(start 188.07938 -403.130512)
				(mid 188.010599 -403.02748)
				(end 187.986416 -402.905976)
			)
			(arc
				(start 187.986416 -400.258534)
				(mid 187.971537 -400.222613)
				(end 187.935616 -400.207734)
			)
			(arc
				(start 184.616598 -400.207734)
				(mid 184.597075 -400.211635)
				(end 184.58053 -400.22272)
			)
			(xy 184.575958 -400.227292) (xy 184.575958 -405.83104) (xy 184.598818 -405.85898)
			(arc
				(start 184.617106 -405.862536)
				(mid 184.925224 -406.236932)
				(end 184.617106 -406.611328)
			)
			(xy 184.598818 -406.614884) (xy 184.575958 -406.642824)
			(arc
				(start 184.575958 -410.555694)
				(mid 184.579859 -410.575217)
				(end 184.590944 -410.591762)
			)
			(arc
				(start 184.926986 -410.927804)
				(mid 184.94352 -410.938915)
				(end 184.963054 -410.94279)
			)
			(arc
				(start 187.965334 -410.94279)
				(mid 188.08685 -410.966943)
				(end 188.18987 -411.035754)
			)
			(arc
				(start 188.836808 -411.682692)
				(mid 188.853342 -411.693803)
				(end 188.872876 -411.697678)
			)
			(arc
				(start 195.270882 -411.697678)
				(mid 195.392398 -411.721831)
				(end 195.495418 -411.790642)
			)
			(arc
				(start 196.65696 -412.952184)
				(mid 196.725741 -413.055216)
				(end 196.749924 -413.17672)
			)
			(arc
				(start 196.749924 -421.558466)
				(mid 196.753825 -421.577989)
				(end 196.76491 -421.594534)
			)
			(arc
				(start 205.961996 -430.79162)
				(mid 206.030777 -430.894652)
				(end 206.05496 -431.016156)
			)
			(arc
				(start 206.05496 -435.078378)
				(mid 206.058861 -435.097901)
				(end 206.069946 -435.114446)
			)
			(arc
				(start 207.419194 -436.463694)
				(mid 207.435728 -436.474805)
				(end 207.455262 -436.47868)
			)
		)
		(stroke
			(width 0)
			(type solid)
		)
		(fill yes)
		(layer "In7.Cu")
		(net "P12V_PSU")
	)
	(gr_poly
		(pts
			(xy 531.7998 -462.519268) (xy 531.855569 -462.518759) (xy 531.966796 -462.510424) (xy 532.077089 -462.4938)
			(xy 532.185831 -462.46898) (xy 532.292414 -462.436103) (xy 532.396243 -462.395354) (xy 532.496736 -462.346959)
			(xy 532.593331 -462.291189) (xy 532.685488 -462.228357) (xy 532.772692 -462.158813) (xy 532.854456 -462.082947)
			(xy 532.930321 -462.001183) (xy 532.999864 -461.913979) (xy 533.062695 -461.821821) (xy 533.118464 -461.725225)
			(xy 533.166858 -461.624732) (xy 533.207607 -461.520903) (xy 533.240483 -461.41432) (xy 533.265302 -461.305577)
			(xy 533.281925 -461.195284) (xy 533.29026 -461.084057) (xy 533.29078 -461.028288) (xy 533.29078 -455.0283)
			(xy 533.290259 -454.972531) (xy 533.281923 -454.861305) (xy 533.265299 -454.751013) (xy 533.24048 -454.642271)
			(xy 533.207603 -454.535688) (xy 533.166854 -454.43186) (xy 533.118459 -454.331368) (xy 533.06269 -454.234773)
			(xy 532.999859 -454.142616) (xy 532.930316 -454.055412) (xy 532.854451 -453.973649) (xy 532.772688 -453.897784)
			(xy 532.685484 -453.828241) (xy 532.593327 -453.76541) (xy 532.496732 -453.709641) (xy 532.39624 -453.661246)
			(xy 532.292412 -453.620497) (xy 532.185829 -453.58762) (xy 532.077087 -453.562801) (xy 531.966795 -453.546177)
			(xy 531.855569 -453.537841) (xy 531.7998 -453.53732) (xy 516.019796 -453.53732) (xy 515.949414 -453.536826)
			(xy 515.808871 -453.528933) (xy 515.668991 -453.513172) (xy 515.530216 -453.489593) (xy 515.392981 -453.45827)
			(xy 515.257718 -453.419302) (xy 515.124852 -453.37281) (xy 514.994803 -453.318942) (xy 514.867978 -453.257866)
			(xy 514.744778 -453.189776) (xy 514.625589 -453.114884) (xy 514.510787 -453.033428) (xy 514.400733 -452.945663)
			(xy 514.295773 -452.851865) (xy 514.196238 -452.75233) (xy 514.10244 -452.64737) (xy 514.014674 -452.537316)
			(xy 513.933218 -452.422514) (xy 513.858326 -452.303325) (xy 513.790236 -452.180125) (xy 513.72916 -452.053301)
			(xy 513.675292 -451.923251) (xy 513.6288 -451.790386) (xy 513.589831 -451.655123) (xy 513.558507 -451.517888)
			(xy 513.534928 -451.379113) (xy 513.519167 -451.239233) (xy 513.511274 -451.09869) (xy 513.510784 -451.028308)
			(xy 513.510784 -312.408316) (xy 513.511268 -312.337933) (xy 513.51916 -312.197389) (xy 513.53492 -312.057508)
			(xy 513.558498 -311.918731) (xy 513.589821 -311.781495) (xy 513.628789 -311.646231) (xy 513.67528 -311.513364)
			(xy 513.729148 -311.383313) (xy 513.790224 -311.256488) (xy 513.858314 -311.133286) (xy 513.933205 -311.014096)
			(xy 514.014662 -310.899292) (xy 514.102427 -310.789237) (xy 514.196225 -310.684276) (xy 514.295761 -310.584739)
			(xy 514.400722 -310.49094) (xy 514.510776 -310.403174) (xy 514.625579 -310.321716) (xy 514.744769 -310.246824)
			(xy 514.86797 -310.178733) (xy 514.994795 -310.117656) (xy 515.124845 -310.063787) (xy 515.257712 -310.017295)
			(xy 515.392976 -309.978326) (xy 515.530212 -309.947002) (xy 515.668989 -309.923423) (xy 515.808869 -309.907662)
			(xy 515.949413 -309.899769) (xy 516.019796 -309.899304) (xy 531.7998 -309.899304) (xy 531.855569 -309.898783)
			(xy 531.966796 -309.890447) (xy 532.077089 -309.873823) (xy 532.185831 -309.849004) (xy 532.292415 -309.816128)
			(xy 532.396243 -309.775378) (xy 532.496737 -309.726984) (xy 532.593332 -309.671215) (xy 532.68549 -309.608384)
			(xy 532.772695 -309.538841) (xy 532.854459 -309.462976) (xy 532.930326 -309.381213) (xy 532.99987 -309.294009)
			(xy 533.062703 -309.201852) (xy 533.118473 -309.105258) (xy 533.166869 -309.004765) (xy 533.20762 -308.900937)
			(xy 533.240498 -308.794355) (xy 533.265319 -308.685613) (xy 533.281945 -308.57532) (xy 533.290282 -308.464093)
			(xy 533.29078 -308.408324) (xy 533.29078 10.40003) (xy 533.290257 10.455798) (xy 533.28192 10.567023)
			(xy 533.265294 10.677313) (xy 533.240473 10.786053) (xy 533.207596 10.892634) (xy 533.166845 10.99646)
			(xy 533.11845 11.09695) (xy 533.06268 11.193543) (xy 532.999848 11.285698) (xy 532.930305 11.3729)
			(xy 532.85444 11.454661) (xy 532.772677 11.530525) (xy 532.685474 11.600066) (xy 532.593318 11.662896)
			(xy 532.496724 11.718664) (xy 532.396232 11.767057) (xy 532.292406 11.807806) (xy 532.185824 11.840681)
			(xy 532.077084 11.8655) (xy 531.966793 11.882123) (xy 531.855568 11.890459) (xy 531.7998 11.89101)
			(xy 475.799912 11.89101) (xy 475.744142 11.890489) (xy 475.632915 11.882155) (xy 475.522621 11.865531)
			(xy 475.413878 11.840713) (xy 475.307293 11.807837) (xy 475.203464 11.767088) (xy 475.10297 11.718694)
			(xy 475.006373 11.662926) (xy 474.914214 11.600094) (xy 474.827008 11.530552) (xy 474.745243 11.454687)
			(xy 474.669376 11.372924) (xy 474.599831 11.28572) (xy 474.536997 11.193563) (xy 474.481225 11.096967)
			(xy 474.432829 10.996475) (xy 474.392077 10.892646) (xy 474.359198 10.786063) (xy 474.334376 10.67732)
			(xy 474.31775 10.567027) (xy 474.309413 10.4558) (xy 474.308932 10.40003) (xy 474.308932 7.335466)
			(xy 526.704041 7.335466) (xy 526.704041 7.464606) (xy 526.711991 7.593501) (xy 526.727861 7.721661)
			(xy 526.75159 7.848602) (xy 526.783089 7.973841) (xy 526.822238 8.096904) (xy 526.868889 8.217323)
			(xy 526.922864 8.334642) (xy 526.983959 8.448416) (xy 527.051942 8.558213) (xy 527.126556 8.663616)
			(xy 527.207517 8.764226) (xy 527.294517 8.859661) (xy 527.387228 8.94956) (xy 527.485298 9.033581)
			(xy 527.588353 9.111405) (xy 527.696004 9.182737) (xy 527.807843 9.247307) (xy 527.923444 9.304869)
			(xy 528.042369 9.355206) (xy 528.164168 9.398126) (xy 528.288378 9.433467) (xy 528.414527 9.461094)
			(xy 528.542139 9.480903) (xy 528.670728 9.492819) (xy 528.799806 9.496796) (xy 528.928884 9.492819)
			(xy 529.057473 9.480903) (xy 529.185085 9.461094) (xy 529.311234 9.433467) (xy 529.435444 9.398126)
			(xy 529.557243 9.355206) (xy 529.676168 9.304869) (xy 529.791769 9.247307) (xy 529.903608 9.182737)
			(xy 530.011259 9.111405) (xy 530.114314 9.033581) (xy 530.212384 8.94956) (xy 530.305095 8.859661)
			(xy 530.392095 8.764226) (xy 530.473056 8.663616) (xy 530.54767 8.558213) (xy 530.615653 8.448416)
			(xy 530.676748 8.334642) (xy 530.730723 8.217323) (xy 530.777374 8.096904) (xy 530.816523 7.973841)
			(xy 530.848022 7.848602) (xy 530.871751 7.721661) (xy 530.887621 7.593501) (xy 530.895571 7.464606)
			(xy 530.896068 7.400036) (xy 530.895571 7.335466) (xy 530.887621 7.206571) (xy 530.871751 7.078411)
			(xy 530.848022 6.95147) (xy 530.816523 6.826231) (xy 530.777374 6.703168) (xy 530.730723 6.582749)
			(xy 530.676748 6.46543) (xy 530.615653 6.351656) (xy 530.54767 6.241859) (xy 530.473056 6.136456)
			(xy 530.392095 6.035846) (xy 530.305095 5.940411) (xy 530.212384 5.850512) (xy 530.114314 5.766491)
			(xy 530.011259 5.688667) (xy 529.903608 5.617335) (xy 529.791769 5.552765) (xy 529.676168 5.495203)
			(xy 529.557243 5.444866) (xy 529.435444 5.401946) (xy 529.311234 5.366605) (xy 529.185085 5.338978)
			(xy 529.057473 5.319169) (xy 528.928884 5.307253) (xy 528.799806 5.303277) (xy 528.670728 5.307253)
			(xy 528.542139 5.319169) (xy 528.414527 5.338978) (xy 528.288378 5.366605) (xy 528.164168 5.401946)
			(xy 528.042369 5.444866) (xy 527.923444 5.495203) (xy 527.807843 5.552765) (xy 527.696004 5.617335)
			(xy 527.588353 5.688667) (xy 527.485298 5.766491) (xy 527.387228 5.850512) (xy 527.294517 5.940411)
			(xy 527.207517 6.035846) (xy 527.126556 6.136456) (xy 527.051942 6.241859) (xy 526.983959 6.351656)
			(xy 526.922864 6.46543) (xy 526.868889 6.582749) (xy 526.822238 6.703168) (xy 526.783089 6.826231)
			(xy 526.75159 6.95147) (xy 526.727861 7.078411) (xy 526.711991 7.206571) (xy 526.704041 7.335466)
			(xy 474.308932 7.335466) (xy 474.308932 -12.515904) (xy 476.704141 -12.515904) (xy 476.704141 -12.386764)
			(xy 476.712091 -12.257869) (xy 476.727961 -12.129709) (xy 476.75169 -12.002768) (xy 476.783189 -11.877529)
			(xy 476.822338 -11.754466) (xy 476.868989 -11.634047) (xy 476.922964 -11.516728) (xy 476.984059 -11.402954)
			(xy 477.052042 -11.293157) (xy 477.126656 -11.187754) (xy 477.207617 -11.087144) (xy 477.294617 -10.991709)
			(xy 477.387328 -10.90181) (xy 477.485398 -10.817789) (xy 477.588453 -10.739965) (xy 477.696104 -10.668633)
			(xy 477.807943 -10.604063) (xy 477.923544 -10.546501) (xy 478.042469 -10.496164) (xy 478.164268 -10.453244)
			(xy 478.288478 -10.417903) (xy 478.414627 -10.390276) (xy 478.542239 -10.370467) (xy 478.670828 -10.358551)
			(xy 478.799906 -10.354575) (xy 478.928984 -10.358551) (xy 479.057573 -10.370467) (xy 479.185185 -10.390276)
			(xy 479.311334 -10.417903) (xy 479.435544 -10.453244) (xy 479.557343 -10.496164) (xy 479.676268 -10.546501)
			(xy 479.791869 -10.604063) (xy 479.903708 -10.668633) (xy 480.011359 -10.739965) (xy 480.114414 -10.817789)
			(xy 480.212484 -10.90181) (xy 480.305195 -10.991709) (xy 480.392195 -11.087144) (xy 480.473156 -11.187754)
			(xy 480.54777 -11.293157) (xy 480.615753 -11.402954) (xy 480.676848 -11.516728) (xy 480.730823 -11.634047)
			(xy 480.777474 -11.754466) (xy 480.816623 -11.877529) (xy 480.848122 -12.002768) (xy 480.871851 -12.129709)
			(xy 480.887721 -12.257869) (xy 480.895671 -12.386764) (xy 480.896168 -12.451334) (xy 480.895671 -12.515904)
			(xy 480.887721 -12.644799) (xy 480.871851 -12.772959) (xy 480.848122 -12.8999) (xy 480.816623 -13.025139)
			(xy 480.777474 -13.148202) (xy 480.730823 -13.268621) (xy 480.676848 -13.38594) (xy 480.615753 -13.499714)
			(xy 480.54777 -13.609511) (xy 480.473156 -13.714914) (xy 480.392195 -13.815524) (xy 480.305195 -13.910959)
			(xy 480.212484 -14.000858) (xy 480.114414 -14.084879) (xy 480.011359 -14.162703) (xy 479.903708 -14.234035)
			(xy 479.791869 -14.298605) (xy 479.676268 -14.356167) (xy 479.557343 -14.406504) (xy 479.435544 -14.449424)
			(xy 479.311334 -14.484765) (xy 479.185185 -14.512392) (xy 479.057573 -14.532201) (xy 478.928984 -14.544117)
			(xy 478.799906 -14.548094) (xy 478.670828 -14.544117) (xy 478.542239 -14.532201) (xy 478.414627 -14.512392)
			(xy 478.288478 -14.484765) (xy 478.164268 -14.449424) (xy 478.042469 -14.406504) (xy 477.923544 -14.356167)
			(xy 477.807943 -14.298605) (xy 477.696104 -14.234035) (xy 477.588453 -14.162703) (xy 477.485398 -14.084879)
			(xy 477.387328 -14.000858) (xy 477.294617 -13.910959) (xy 477.207617 -13.815524) (xy 477.126656 -13.714914)
			(xy 477.052042 -13.609511) (xy 476.984059 -13.499714) (xy 476.922964 -13.38594) (xy 476.868989 -13.268621)
			(xy 476.822338 -13.148202) (xy 476.783189 -13.025139) (xy 476.75169 -12.8999) (xy 476.727961 -12.772959)
			(xy 476.712091 -12.644799) (xy 476.704141 -12.515904) (xy 474.308932 -12.515904) (xy 474.308932 -77.67193)
			(xy 474.308458 -77.765117) (xy 474.300759 -77.951331) (xy 474.28537 -78.137067) (xy 474.262318 -78.32201)
			(xy 474.231642 -78.505841) (xy 474.193396 -78.688247) (xy 474.147643 -78.868917) (xy 474.094463 -79.047542)
			(xy 474.033945 -79.223817) (xy 473.966195 -79.397439) (xy 473.891327 -79.568113) (xy 473.809469 -79.735548)
			(xy 473.720761 -79.899456) (xy 473.625355 -80.059558) (xy 473.523414 -80.21558) (xy 473.415112 -80.367256)
			(xy 473.300633 -80.514327) (xy 473.180175 -80.65654) (xy 473.053942 -80.793654) (xy 472.988386 -80.859884)
			(xy 471.245946 -82.602324) (xy 471.208633 -82.640304) (xy 471.138899 -82.72077) (xy 471.07508 -82.806006)
			(xy 471.017504 -82.895576) (xy 470.966464 -82.989025) (xy 470.922218 -83.085876) (xy 470.884993 -83.185636)
			(xy 470.854978 -83.287798) (xy 470.832326 -83.391839) (xy 470.817153 -83.497232) (xy 470.809535 -83.603438)
			(xy 470.809066 -83.656678) (xy 470.809066 -328.137828) (xy 473.204275 -328.137828) (xy 473.204275 -328.008688)
			(xy 473.212225 -327.879793) (xy 473.228095 -327.751633) (xy 473.251824 -327.624692) (xy 473.283323 -327.499453)
			(xy 473.322472 -327.37639) (xy 473.369123 -327.255971) (xy 473.423098 -327.138652) (xy 473.484193 -327.024878)
			(xy 473.552176 -326.915081) (xy 473.62679 -326.809678) (xy 473.707751 -326.709068) (xy 473.794751 -326.613633)
			(xy 473.887462 -326.523734) (xy 473.985532 -326.439713) (xy 474.088587 -326.361889) (xy 474.196238 -326.290557)
			(xy 474.308077 -326.225987) (xy 474.423678 -326.168425) (xy 474.542603 -326.118088) (xy 474.664402 -326.075168)
			(xy 474.788612 -326.039827) (xy 474.914761 -326.0122) (xy 475.042373 -325.992391) (xy 475.170962 -325.980475)
			(xy 475.30004 -325.976499) (xy 475.429118 -325.980475) (xy 475.557707 -325.992391) (xy 475.685319 -326.0122)
			(xy 475.811468 -326.039827) (xy 475.935678 -326.075168) (xy 476.057477 -326.118088) (xy 476.176402 -326.168425)
			(xy 476.292003 -326.225987) (xy 476.403842 -326.290557) (xy 476.511493 -326.361889) (xy 476.614548 -326.439713)
			(xy 476.712618 -326.523734) (xy 476.805329 -326.613633) (xy 476.892329 -326.709068) (xy 476.97329 -326.809678)
			(xy 477.047904 -326.915081) (xy 477.115887 -327.024878) (xy 477.176982 -327.138652) (xy 477.230957 -327.255971)
			(xy 477.277608 -327.37639) (xy 477.316757 -327.499453) (xy 477.348256 -327.624692) (xy 477.371985 -327.751633)
			(xy 477.387855 -327.879793) (xy 477.395805 -328.008688) (xy 477.396302 -328.073258) (xy 477.395805 -328.137828)
			(xy 477.387855 -328.266723) (xy 477.371985 -328.394883) (xy 477.348256 -328.521824) (xy 477.316757 -328.647063)
			(xy 477.277608 -328.770126) (xy 477.230957 -328.890545) (xy 477.176982 -329.007864) (xy 477.115887 -329.121638)
			(xy 477.047904 -329.231435) (xy 476.97329 -329.336838) (xy 476.892329 -329.437448) (xy 476.805329 -329.532883)
			(xy 476.712618 -329.622782) (xy 476.614548 -329.706803) (xy 476.511493 -329.784627) (xy 476.403842 -329.855959)
			(xy 476.292003 -329.920529) (xy 476.176402 -329.978091) (xy 476.057477 -330.028428) (xy 475.935678 -330.071348)
			(xy 475.811468 -330.106689) (xy 475.685319 -330.134316) (xy 475.557707 -330.154125) (xy 475.429118 -330.166041)
			(xy 475.30004 -330.170018) (xy 475.170962 -330.166041) (xy 475.042373 -330.154125) (xy 474.914761 -330.134316)
			(xy 474.788612 -330.106689) (xy 474.664402 -330.071348) (xy 474.542603 -330.028428) (xy 474.423678 -329.978091)
			(xy 474.308077 -329.920529) (xy 474.196238 -329.855959) (xy 474.088587 -329.784627) (xy 473.985532 -329.706803)
			(xy 473.887462 -329.622782) (xy 473.794751 -329.532883) (xy 473.707751 -329.437448) (xy 473.62679 -329.336838)
			(xy 473.552176 -329.231435) (xy 473.484193 -329.121638) (xy 473.423098 -329.007864) (xy 473.369123 -328.890545)
			(xy 473.322472 -328.770126) (xy 473.283323 -328.647063) (xy 473.251824 -328.521824) (xy 473.228095 -328.394883)
			(xy 473.212225 -328.266723) (xy 473.204275 -328.137828) (xy 470.809066 -328.137828) (xy 470.809066 -404.871936)
			(xy 470.808592 -404.965123) (xy 470.800892 -405.151337) (xy 470.785503 -405.337074) (xy 470.762451 -405.522016)
			(xy 470.731776 -405.705847) (xy 470.693529 -405.888254) (xy 470.647776 -406.068924) (xy 470.594596 -406.247549)
			(xy 470.534079 -406.423823) (xy 470.466329 -406.597446) (xy 470.391461 -406.76812) (xy 470.309603 -406.935555)
			(xy 470.220896 -407.099463) (xy 470.12549 -407.259566) (xy 470.02355 -407.415588) (xy 469.915248 -407.567265)
			(xy 469.80077 -407.714335) (xy 469.680312 -407.856549) (xy 469.554079 -407.993664) (xy 469.48852 -408.05989)
			(xy 468.245698 -409.302712) (xy 468.208406 -409.340689) (xy 468.138712 -409.421147) (xy 468.074932 -409.506369)
			(xy 468.017391 -409.595922) (xy 467.966382 -409.68935) (xy 467.922165 -409.786178) (xy 467.884964 -409.885911)
			(xy 467.85497 -409.988044) (xy 467.832334 -410.092055) (xy 467.817172 -410.197416) (xy 467.809562 -410.303589)
			(xy 467.809072 -410.356812) (xy 467.809072 -439.989976) (xy 467.809593 -440.045746) (xy 467.817926 -440.156975)
			(xy 467.834548 -440.26727) (xy 467.859367 -440.376014) (xy 467.892242 -440.4826) (xy 467.93299 -440.586431)
			(xy 467.981383 -440.686926) (xy 468.037152 -440.783525) (xy 468.099983 -440.875685) (xy 468.169525 -440.962893)
			(xy 468.24539 -441.044659) (xy 468.327153 -441.120528) (xy 468.414357 -441.190075) (xy 468.506514 -441.25291)
			(xy 468.60311 -441.308683) (xy 468.703603 -441.357081) (xy 468.807432 -441.397835) (xy 468.914016 -441.430715)
			(xy 469.022759 -441.455538) (xy 469.133053 -441.472166) (xy 469.244282 -441.480505) (xy 469.300052 -441.480956)
			(xy 471.79992 -441.480956) (xy 471.870302 -441.48145) (xy 472.010845 -441.489344) (xy 472.150724 -441.505105)
			(xy 472.2895 -441.528685) (xy 472.426735 -441.560009) (xy 472.561998 -441.598978) (xy 472.694863 -441.64547)
			(xy 472.824912 -441.699339) (xy 472.951736 -441.760414) (xy 473.074936 -441.828505) (xy 473.194125 -441.903396)
			(xy 473.308927 -441.984852) (xy 473.418981 -442.072617) (xy 473.523941 -442.166415) (xy 473.623477 -442.26595)
			(xy 473.717275 -442.37091) (xy 473.80504 -442.480964) (xy 473.886497 -442.595765) (xy 473.961389 -442.714953)
			(xy 474.02948 -442.838153) (xy 474.090556 -442.964977) (xy 474.144426 -443.095026) (xy 474.190918 -443.227891)
			(xy 474.229888 -443.363154) (xy 474.261212 -443.500389) (xy 474.284793 -443.639164) (xy 474.300555 -443.779043)
			(xy 474.308449 -443.919586) (xy 474.308932 -443.989968) (xy 474.308932 -458.092864) (xy 526.704041 -458.092864)
			(xy 526.704041 -457.963724) (xy 526.711991 -457.834829) (xy 526.727861 -457.706669) (xy 526.75159 -457.579728)
			(xy 526.783089 -457.454489) (xy 526.822238 -457.331426) (xy 526.868889 -457.211007) (xy 526.922864 -457.093688)
			(xy 526.983959 -456.979914) (xy 527.051942 -456.870117) (xy 527.126556 -456.764714) (xy 527.207517 -456.664104)
			(xy 527.294517 -456.568669) (xy 527.387228 -456.47877) (xy 527.485298 -456.394749) (xy 527.588353 -456.316925)
			(xy 527.696004 -456.245593) (xy 527.807843 -456.181023) (xy 527.923444 -456.123461) (xy 528.042369 -456.073124)
			(xy 528.164168 -456.030204) (xy 528.288378 -455.994863) (xy 528.414527 -455.967236) (xy 528.542139 -455.947427)
			(xy 528.670728 -455.935511) (xy 528.799806 -455.931535) (xy 528.928884 -455.935511) (xy 529.057473 -455.947427)
			(xy 529.185085 -455.967236) (xy 529.311234 -455.994863) (xy 529.435444 -456.030204) (xy 529.557243 -456.073124)
			(xy 529.676168 -456.123461) (xy 529.791769 -456.181023) (xy 529.903608 -456.245593) (xy 530.011259 -456.316925)
			(xy 530.114314 -456.394749) (xy 530.212384 -456.47877) (xy 530.305095 -456.568669) (xy 530.392095 -456.664104)
			(xy 530.473056 -456.764714) (xy 530.54767 -456.870117) (xy 530.615653 -456.979914) (xy 530.676748 -457.093688)
			(xy 530.730723 -457.211007) (xy 530.777374 -457.331426) (xy 530.816523 -457.454489) (xy 530.848022 -457.579728)
			(xy 530.871751 -457.706669) (xy 530.887621 -457.834829) (xy 530.895571 -457.963724) (xy 530.896068 -458.028294)
			(xy 530.895571 -458.092864) (xy 530.887621 -458.221759) (xy 530.871751 -458.349919) (xy 530.848022 -458.47686)
			(xy 530.816523 -458.602099) (xy 530.777374 -458.725162) (xy 530.730723 -458.845581) (xy 530.676748 -458.9629)
			(xy 530.615653 -459.076674) (xy 530.54767 -459.186471) (xy 530.473056 -459.291874) (xy 530.392095 -459.392484)
			(xy 530.305095 -459.487919) (xy 530.212384 -459.577818) (xy 530.114314 -459.661839) (xy 530.011259 -459.739663)
			(xy 529.903608 -459.810995) (xy 529.791769 -459.875565) (xy 529.676168 -459.933127) (xy 529.557243 -459.983464)
			(xy 529.435444 -460.026384) (xy 529.311234 -460.061725) (xy 529.185085 -460.089352) (xy 529.057473 -460.109161)
			(xy 528.928884 -460.121077) (xy 528.799806 -460.125054) (xy 528.670728 -460.121077) (xy 528.542139 -460.109161)
			(xy 528.414527 -460.089352) (xy 528.288378 -460.061725) (xy 528.164168 -460.026384) (xy 528.042369 -459.983464)
			(xy 527.923444 -459.933127) (xy 527.807843 -459.875565) (xy 527.696004 -459.810995) (xy 527.588353 -459.739663)
			(xy 527.485298 -459.661839) (xy 527.387228 -459.577818) (xy 527.294517 -459.487919) (xy 527.207517 -459.392484)
			(xy 527.126556 -459.291874) (xy 527.051942 -459.186471) (xy 526.983959 -459.076674) (xy 526.922864 -458.9629)
			(xy 526.868889 -458.845581) (xy 526.822238 -458.725162) (xy 526.783089 -458.602099) (xy 526.75159 -458.47686)
			(xy 526.727861 -458.349919) (xy 526.711991 -458.221759) (xy 526.704041 -458.092864) (xy 474.308932 -458.092864)
			(xy 474.308932 -461.028288) (xy 474.30944 -461.084058) (xy 474.317775 -461.195285) (xy 474.334398 -461.305579)
			(xy 474.359217 -461.414322) (xy 474.392093 -461.520906) (xy 474.432843 -461.624735) (xy 474.481238 -461.725228)
			(xy 474.537007 -461.821824) (xy 474.599839 -461.913982) (xy 474.669383 -462.001187) (xy 474.745248 -462.082952)
			(xy 474.827013 -462.158817) (xy 474.914218 -462.228361) (xy 475.006376 -462.291193) (xy 475.102972 -462.346962)
			(xy 475.203465 -462.395357) (xy 475.307294 -462.436107) (xy 475.413878 -462.468983) (xy 475.522621 -462.493802)
			(xy 475.632915 -462.510425) (xy 475.744142 -462.51876) (xy 475.799912 -462.519268)
		)
		(stroke
			(width 0)
			(type solid)
		)
		(fill yes)
		(layer "In7.Cu")
		(net "T1_GND")
	)
	(gr_poly
		(pts
			(xy 255.800098 -33.611058) (xy 255.832245 -33.610555) (xy 255.89599 -33.602163) (xy 255.958093 -33.585522)
			(xy 256.017493 -33.560917) (xy 256.073173 -33.528769) (xy 256.124181 -33.489628) (xy 256.169643 -33.444164)
			(xy 256.208781 -33.393155) (xy 256.240927 -33.337473) (xy 256.265529 -33.278072) (xy 256.282167 -33.215968)
			(xy 256.290557 -33.152223) (xy 256.29108 -33.120076) (xy 256.29108 -11.780012) (xy 256.291564 -11.709629)
			(xy 256.299456 -11.569085) (xy 256.315217 -11.429205) (xy 256.338795 -11.290428) (xy 256.370118 -11.153191)
			(xy 256.409086 -11.017927) (xy 256.455577 -10.885061) (xy 256.509445 -10.75501) (xy 256.570521 -10.628184)
			(xy 256.638611 -10.504983) (xy 256.713502 -10.385793) (xy 256.794959 -10.27099) (xy 256.882724 -10.160934)
			(xy 256.976523 -10.055973) (xy 257.076059 -9.956436) (xy 257.181019 -9.862637) (xy 257.291074 -9.774871)
			(xy 257.405876 -9.693414) (xy 257.525065 -9.618521) (xy 257.648266 -9.55043) (xy 257.775092 -9.489354)
			(xy 257.905142 -9.435484) (xy 258.038008 -9.388992) (xy 258.173272 -9.350023) (xy 258.310508 -9.318699)
			(xy 258.449285 -9.295119) (xy 258.589165 -9.279358) (xy 258.729709 -9.271465) (xy 258.800092 -9.271)
			(xy 383.601976 -9.271) (xy 383.657746 -9.270492) (xy 383.768975 -9.262159) (xy 383.87927 -9.245536)
			(xy 383.988015 -9.220718) (xy 384.094601 -9.187842) (xy 384.198432 -9.147093) (xy 384.298927 -9.098699)
			(xy 384.395525 -9.04293) (xy 384.487685 -8.980099) (xy 384.574892 -8.910555) (xy 384.656659 -8.83469)
			(xy 384.732527 -8.752926) (xy 384.802073 -8.665721) (xy 384.864907 -8.573562) (xy 384.920679 -8.476966)
			(xy 384.969076 -8.376472) (xy 385.009828 -8.272642) (xy 385.042706 -8.166058) (xy 385.067528 -8.057314)
			(xy 385.084154 -7.947019) (xy 385.092491 -7.83579) (xy 385.092956 -7.78002) (xy 385.092956 0.40005)
			(xy 385.093451 0.470432) (xy 385.101346 0.610973) (xy 385.117109 0.750851) (xy 385.14069 0.889625)
			(xy 385.172015 1.026859) (xy 385.210985 1.16212) (xy 385.257478 1.294984) (xy 385.311348 1.425032)
			(xy 385.372424 1.551855) (xy 385.440515 1.675053) (xy 385.515407 1.79424) (xy 385.596863 1.909041)
			(xy 385.684628 2.019094) (xy 385.778426 2.124052) (xy 385.877961 2.223587) (xy 385.98292 2.317383)
			(xy 386.092974 2.405148) (xy 386.207775 2.486603) (xy 386.326962 2.561494) (xy 386.450161 2.629584)
			(xy 386.576985 2.69066) (xy 386.707033 2.744528) (xy 386.839897 2.79102) (xy 386.975158 2.829989)
			(xy 387.112392 2.861313) (xy 387.251166 2.884893) (xy 387.391045 2.900655) (xy 387.531586 2.908549)
			(xy 387.601968 2.909062) (xy 456.202034 2.909062) (xy 456.272416 2.908567) (xy 456.412959 2.900673)
			(xy 456.552838 2.884911) (xy 456.691613 2.861331) (xy 456.828848 2.830006) (xy 456.96411 2.791037)
			(xy 457.096975 2.744544) (xy 457.227024 2.690676) (xy 457.353848 2.6296) (xy 457.477048 2.561509)
			(xy 457.596236 2.486618) (xy 457.711038 2.405161) (xy 457.821092 2.317396) (xy 457.926052 2.223599)
			(xy 458.025588 2.124064) (xy 458.119386 2.019104) (xy 458.207152 1.909051) (xy 458.288609 1.79425)
			(xy 458.363501 1.675062) (xy 458.431592 1.551862) (xy 458.492669 1.425039) (xy 458.546539 1.29499)
			(xy 458.593032 1.162126) (xy 458.632002 1.026863) (xy 458.663327 0.889629) (xy 458.686909 0.750854)
			(xy 458.702672 0.610975) (xy 458.710567 0.470432) (xy 458.711046 0.40005) (xy 458.711046 -4.844596)
			(xy 464.704165 -4.844596) (xy 464.704165 -4.715456) (xy 464.712115 -4.586561) (xy 464.727985 -4.458401)
			(xy 464.751714 -4.33146) (xy 464.783213 -4.206221) (xy 464.822362 -4.083158) (xy 464.869013 -3.962739)
			(xy 464.922988 -3.84542) (xy 464.984083 -3.731646) (xy 465.052066 -3.621849) (xy 465.12668 -3.516446)
			(xy 465.207641 -3.415836) (xy 465.294641 -3.320401) (xy 465.387352 -3.230502) (xy 465.485422 -3.146481)
			(xy 465.588477 -3.068657) (xy 465.696128 -2.997325) (xy 465.807967 -2.932755) (xy 465.923568 -2.875193)
			(xy 466.042493 -2.824856) (xy 466.164292 -2.781936) (xy 466.288502 -2.746595) (xy 466.414651 -2.718968)
			(xy 466.542263 -2.699159) (xy 466.670852 -2.687243) (xy 466.79993 -2.683267) (xy 466.929008 -2.687243)
			(xy 467.057597 -2.699159) (xy 467.185209 -2.718968) (xy 467.311358 -2.746595) (xy 467.435568 -2.781936)
			(xy 467.557367 -2.824856) (xy 467.676292 -2.875193) (xy 467.791893 -2.932755) (xy 467.903732 -2.997325)
			(xy 468.011383 -3.068657) (xy 468.114438 -3.146481) (xy 468.212508 -3.230502) (xy 468.305219 -3.320401)
			(xy 468.392219 -3.415836) (xy 468.47318 -3.516446) (xy 468.547794 -3.621849) (xy 468.615777 -3.731646)
			(xy 468.676872 -3.84542) (xy 468.730847 -3.962739) (xy 468.777498 -4.083158) (xy 468.816647 -4.206221)
			(xy 468.848146 -4.33146) (xy 468.871875 -4.458401) (xy 468.887745 -4.586561) (xy 468.895695 -4.715456)
			(xy 468.896192 -4.780026) (xy 468.895695 -4.844596) (xy 468.887745 -4.973491) (xy 468.871875 -5.101651)
			(xy 468.848146 -5.228592) (xy 468.816647 -5.353831) (xy 468.777498 -5.476894) (xy 468.730847 -5.597313)
			(xy 468.676872 -5.714632) (xy 468.615777 -5.828406) (xy 468.547794 -5.938203) (xy 468.47318 -6.043606)
			(xy 468.392219 -6.144216) (xy 468.305219 -6.239651) (xy 468.212508 -6.32955) (xy 468.114438 -6.413571)
			(xy 468.011383 -6.491395) (xy 467.903732 -6.562727) (xy 467.791893 -6.627297) (xy 467.676292 -6.684859)
			(xy 467.557367 -6.735196) (xy 467.435568 -6.778116) (xy 467.311358 -6.813457) (xy 467.185209 -6.841084)
			(xy 467.057597 -6.860893) (xy 466.929008 -6.872809) (xy 466.79993 -6.876786) (xy 466.670852 -6.872809)
			(xy 466.542263 -6.860893) (xy 466.414651 -6.841084) (xy 466.288502 -6.813457) (xy 466.164292 -6.778116)
			(xy 466.042493 -6.735196) (xy 465.923568 -6.684859) (xy 465.807967 -6.627297) (xy 465.696128 -6.562727)
			(xy 465.588477 -6.491395) (xy 465.485422 -6.413571) (xy 465.387352 -6.32955) (xy 465.294641 -6.239651)
			(xy 465.207641 -6.144216) (xy 465.12668 -6.043606) (xy 465.052066 -5.938203) (xy 464.984083 -5.828406)
			(xy 464.922988 -5.714632) (xy 464.869013 -5.597313) (xy 464.822362 -5.476894) (xy 464.783213 -5.353831)
			(xy 464.751714 -5.228592) (xy 464.727985 -5.101651) (xy 464.712115 -4.973491) (xy 464.704165 -4.844596)
			(xy 458.711046 -4.844596) (xy 458.711046 -7.78002) (xy 458.711555 -7.835789) (xy 458.719892 -7.947014)
			(xy 458.736517 -8.057305) (xy 458.761338 -8.166046) (xy 458.794216 -8.272628) (xy 458.834967 -8.376454)
			(xy 458.883362 -8.476945) (xy 458.939132 -8.573538) (xy 459.001965 -8.665694) (xy 459.071509 -8.752896)
			(xy 459.147375 -8.834658) (xy 459.229138 -8.910521) (xy 459.316343 -8.980062) (xy 459.4085 -9.042892)
			(xy 459.505096 -9.098659) (xy 459.605588 -9.147052) (xy 459.709416 -9.187799) (xy 459.815999 -9.220674)
			(xy 459.92474 -9.245491) (xy 460.035032 -9.262113) (xy 460.146257 -9.270446) (xy 460.202026 -9.271)
			(xy 469.799924 -9.271) (xy 469.855693 -9.270478) (xy 469.966918 -9.262141) (xy 470.07721 -9.245516)
			(xy 470.18595 -9.220695) (xy 470.292532 -9.187817) (xy 470.396359 -9.147067) (xy 470.49685 -9.098672)
			(xy 470.593444 -9.042903) (xy 470.685601 -8.980071) (xy 470.772804 -8.910528) (xy 470.854566 -8.834664)
			(xy 470.930431 -8.752901) (xy 470.999974 -8.665697) (xy 471.062805 -8.573541) (xy 471.118574 -8.476947)
			(xy 471.166969 -8.376455) (xy 471.207719 -8.272628) (xy 471.240596 -8.166046) (xy 471.265416 -8.057306)
			(xy 471.282041 -7.947014) (xy 471.290378 -7.835789) (xy 471.290904 -7.78002) (xy 471.290904 10.40003)
			(xy 471.290381 10.455799) (xy 471.282044 10.567024) (xy 471.265419 10.677315) (xy 471.240598 10.786055)
			(xy 471.20772 10.892637) (xy 471.16697 10.996464) (xy 471.118574 11.096955) (xy 471.062805 11.193548)
			(xy 470.999973 11.285705) (xy 470.930431 11.372908) (xy 470.854566 11.45467) (xy 470.772803 11.530534)
			(xy 470.6856 11.600077) (xy 470.593443 11.662908) (xy 470.49685 11.718677) (xy 470.396358 11.767072)
			(xy 470.292531 11.807822) (xy 470.18595 11.840699) (xy 470.077209 11.86552) (xy 469.966918 11.882145)
			(xy 469.855693 11.890482) (xy 469.799924 11.89101) (xy 1.999996 11.89101) (xy 1.944227 11.890488)
			(xy 1.833001 11.882153) (xy 1.722709 11.865529) (xy 1.613968 11.840709) (xy 1.507385 11.807832) (xy 1.403558 11.767083)
			(xy 1.303066 11.718688) (xy 1.206471 11.662919) (xy 1.114314 11.600087) (xy 1.027111 11.530545) (xy 0.945348 11.454679)
			(xy 0.869483 11.372916) (xy 0.79994 11.285712) (xy 0.737109 11.193555) (xy 0.68134 11.096961) (xy 0.632946 10.996469)
			(xy 0.592196 10.892641) (xy 0.55932 10.786058) (xy 0.534501 10.677317) (xy 0.517877 10.567025) (xy 0.509541 10.455799)
			(xy 0.509016 10.40003) (xy 0.509016 9.916973) (xy 385.651997 9.916973) (xy 385.651997 10.002723)
			(xy 385.659909 10.088106) (xy 385.675665 10.172396) (xy 385.699132 10.254872) (xy 385.730108 10.334831)
			(xy 385.76833 10.411591) (xy 385.813471 10.484497) (xy 385.865147 10.552926) (xy 385.922916 10.616296)
			(xy 385.986286 10.674065) (xy 386.054715 10.725741) (xy 386.127621 10.770882) (xy 386.204381 10.809104)
			(xy 386.28434 10.84008) (xy 386.366816 10.863547) (xy 386.451106 10.879303) (xy 386.536489 10.887215)
			(xy 386.622239 10.887215) (xy 386.707622 10.879303) (xy 386.791912 10.863547) (xy 386.874388 10.84008)
			(xy 386.954347 10.809104) (xy 387.031107 10.770882) (xy 387.104013 10.725741) (xy 387.172442 10.674065)
			(xy 387.235812 10.616296) (xy 387.293581 10.552926) (xy 387.345257 10.484497) (xy 387.390398 10.411591)
			(xy 387.42862 10.334831) (xy 387.459596 10.254872) (xy 387.483063 10.172396) (xy 387.498819 10.088106)
			(xy 387.506731 10.002723) (xy 387.507226 9.959848) (xy 387.506731 9.916973) (xy 392.001997 9.916973)
			(xy 392.001997 10.002723) (xy 392.009909 10.088106) (xy 392.025665 10.172396) (xy 392.049132 10.254872)
			(xy 392.080108 10.334831) (xy 392.11833 10.411591) (xy 392.163471 10.484497) (xy 392.215147 10.552926)
			(xy 392.272916 10.616296) (xy 392.336286 10.674065) (xy 392.404715 10.725741) (xy 392.477621 10.770882)
			(xy 392.554381 10.809104) (xy 392.63434 10.84008) (xy 392.716816 10.863547) (xy 392.801106 10.879303)
			(xy 392.886489 10.887215) (xy 392.972239 10.887215) (xy 393.057622 10.879303) (xy 393.141912 10.863547)
			(xy 393.224388 10.84008) (xy 393.304347 10.809104) (xy 393.381107 10.770882) (xy 393.454013 10.725741)
			(xy 393.522442 10.674065) (xy 393.585812 10.616296) (xy 393.643581 10.552926) (xy 393.695257 10.484497)
			(xy 393.740398 10.411591) (xy 393.77862 10.334831) (xy 393.809596 10.254872) (xy 393.833063 10.172396)
			(xy 393.848819 10.088106) (xy 393.856731 10.002723) (xy 393.857226 9.959848) (xy 393.856731 9.916973)
			(xy 436.390783 9.916973) (xy 436.390783 10.002723) (xy 436.398695 10.088106) (xy 436.414451 10.172396)
			(xy 436.437918 10.254872) (xy 436.468894 10.334831) (xy 436.507116 10.411591) (xy 436.552257 10.484497)
			(xy 436.603933 10.552926) (xy 436.661702 10.616296) (xy 436.725072 10.674065) (xy 436.793501 10.725741)
			(xy 436.866407 10.770882) (xy 436.943167 10.809104) (xy 437.023126 10.84008) (xy 437.105602 10.863547)
			(xy 437.189892 10.879303) (xy 437.275275 10.887215) (xy 437.361025 10.887215) (xy 437.446408 10.879303)
			(xy 437.530698 10.863547) (xy 437.613174 10.84008) (xy 437.693133 10.809104) (xy 437.769893 10.770882)
			(xy 437.842799 10.725741) (xy 437.911228 10.674065) (xy 437.974598 10.616296) (xy 438.032367 10.552926)
			(xy 438.084043 10.484497) (xy 438.129184 10.411591) (xy 438.167406 10.334831) (xy 438.198382 10.254872)
			(xy 438.221849 10.172396) (xy 438.237605 10.088106) (xy 438.245517 10.002723) (xy 438.246012 9.959848)
			(xy 438.245517 9.916973) (xy 442.740783 9.916973) (xy 442.740783 10.002723) (xy 442.748695 10.088106)
			(xy 442.764451 10.172396) (xy 442.787918 10.254872) (xy 442.818894 10.334831) (xy 442.857116 10.411591)
			(xy 442.902257 10.484497) (xy 442.953933 10.552926) (xy 443.011702 10.616296) (xy 443.075072 10.674065)
			(xy 443.143501 10.725741) (xy 443.216407 10.770882) (xy 443.293167 10.809104) (xy 443.373126 10.84008)
			(xy 443.455602 10.863547) (xy 443.539892 10.879303) (xy 443.625275 10.887215) (xy 443.711025 10.887215)
			(xy 443.796408 10.879303) (xy 443.880698 10.863547) (xy 443.963174 10.84008) (xy 444.043133 10.809104)
			(xy 444.119893 10.770882) (xy 444.192799 10.725741) (xy 444.261228 10.674065) (xy 444.324598 10.616296)
			(xy 444.382367 10.552926) (xy 444.434043 10.484497) (xy 444.479184 10.411591) (xy 444.517406 10.334831)
			(xy 444.548382 10.254872) (xy 444.571849 10.172396) (xy 444.587605 10.088106) (xy 444.595517 10.002723)
			(xy 444.596012 9.959848) (xy 444.595517 9.916973) (xy 444.587605 9.83159) (xy 444.571849 9.7473)
			(xy 444.548382 9.664824) (xy 444.517406 9.584865) (xy 444.479184 9.508105) (xy 444.434043 9.435199)
			(xy 444.382367 9.36677) (xy 444.324598 9.3034) (xy 444.261228 9.245631) (xy 444.192799 9.193955)
			(xy 444.119893 9.148814) (xy 444.043133 9.110592) (xy 443.963174 9.079616) (xy 443.880698 9.056149)
			(xy 443.796408 9.040393) (xy 443.711025 9.032481) (xy 443.625275 9.032481) (xy 443.539892 9.040393)
			(xy 443.455602 9.056149) (xy 443.373126 9.079616) (xy 443.293167 9.110592) (xy 443.216407 9.148814)
			(xy 443.143501 9.193955) (xy 443.075072 9.245631) (xy 443.011702 9.3034) (xy 442.953933 9.36677)
			(xy 442.902257 9.435199) (xy 442.857116 9.508105) (xy 442.818894 9.584865) (xy 442.787918 9.664824)
			(xy 442.764451 9.7473) (xy 442.748695 9.83159) (xy 442.740783 9.916973) (xy 438.245517 9.916973)
			(xy 438.237605 9.83159) (xy 438.221849 9.7473) (xy 438.198382 9.664824) (xy 438.167406 9.584865)
			(xy 438.129184 9.508105) (xy 438.084043 9.435199) (xy 438.032367 9.36677) (xy 437.974598 9.3034)
			(xy 437.911228 9.245631) (xy 437.842799 9.193955) (xy 437.769893 9.148814) (xy 437.693133 9.110592)
			(xy 437.613174 9.079616) (xy 437.530698 9.056149) (xy 437.446408 9.040393) (xy 437.361025 9.032481)
			(xy 437.275275 9.032481) (xy 437.189892 9.040393) (xy 437.105602 9.056149) (xy 437.023126 9.079616)
			(xy 436.943167 9.110592) (xy 436.866407 9.148814) (xy 436.793501 9.193955) (xy 436.725072 9.245631)
			(xy 436.661702 9.3034) (xy 436.603933 9.36677) (xy 436.552257 9.435199) (xy 436.507116 9.508105)
			(xy 436.468894 9.584865) (xy 436.437918 9.664824) (xy 436.414451 9.7473) (xy 436.398695 9.83159)
			(xy 436.390783 9.916973) (xy 393.856731 9.916973) (xy 393.848819 9.83159) (xy 393.833063 9.7473)
			(xy 393.809596 9.664824) (xy 393.77862 9.584865) (xy 393.740398 9.508105) (xy 393.695257 9.435199)
			(xy 393.643581 9.36677) (xy 393.585812 9.3034) (xy 393.522442 9.245631) (xy 393.454013 9.193955)
			(xy 393.381107 9.148814) (xy 393.304347 9.110592) (xy 393.224388 9.079616) (xy 393.141912 9.056149)
			(xy 393.057622 9.040393) (xy 392.972239 9.032481) (xy 392.886489 9.032481) (xy 392.801106 9.040393)
			(xy 392.716816 9.056149) (xy 392.63434 9.079616) (xy 392.554381 9.110592) (xy 392.477621 9.148814)
			(xy 392.404715 9.193955) (xy 392.336286 9.245631) (xy 392.272916 9.3034) (xy 392.215147 9.36677)
			(xy 392.163471 9.435199) (xy 392.11833 9.508105) (xy 392.080108 9.584865) (xy 392.049132 9.664824)
			(xy 392.025665 9.7473) (xy 392.009909 9.83159) (xy 392.001997 9.916973) (xy 387.506731 9.916973)
			(xy 387.498819 9.83159) (xy 387.483063 9.7473) (xy 387.459596 9.664824) (xy 387.42862 9.584865) (xy 387.390398 9.508105)
			(xy 387.345257 9.435199) (xy 387.293581 9.36677) (xy 387.235812 9.3034) (xy 387.172442 9.245631)
			(xy 387.104013 9.193955) (xy 387.031107 9.148814) (xy 386.954347 9.110592) (xy 386.874388 9.079616)
			(xy 386.791912 9.056149) (xy 386.707622 9.040393) (xy 386.622239 9.032481) (xy 386.536489 9.032481)
			(xy 386.451106 9.040393) (xy 386.366816 9.056149) (xy 386.28434 9.079616) (xy 386.204381 9.110592)
			(xy 386.127621 9.148814) (xy 386.054715 9.193955) (xy 385.986286 9.245631) (xy 385.922916 9.3034)
			(xy 385.865147 9.36677) (xy 385.813471 9.435199) (xy 385.76833 9.508105) (xy 385.730108 9.584865)
			(xy 385.699132 9.664824) (xy 385.675665 9.7473) (xy 385.659909 9.83159) (xy 385.651997 9.916973)
			(xy 0.509016 9.916973) (xy 0.509016 7.335466) (xy 2.904225 7.335466) (xy 2.904225 7.464606) (xy 2.912175 7.593501)
			(xy 2.928045 7.721661) (xy 2.951774 7.848602) (xy 2.983273 7.973841) (xy 3.022422 8.096904) (xy 3.069073 8.217323)
			(xy 3.123048 8.334642) (xy 3.184143 8.448416) (xy 3.252126 8.558213) (xy 3.32674 8.663616) (xy 3.407701 8.764226)
			(xy 3.494701 8.859661) (xy 3.587412 8.94956) (xy 3.685482 9.033581) (xy 3.788537 9.111405) (xy 3.896188 9.182737)
			(xy 4.008027 9.247307) (xy 4.123628 9.304869) (xy 4.242553 9.355206) (xy 4.364352 9.398126) (xy 4.488562 9.433467)
			(xy 4.614711 9.461094) (xy 4.742323 9.480903) (xy 4.870912 9.492819) (xy 4.99999 9.496796) (xy 5.129068 9.492819)
			(xy 5.257657 9.480903) (xy 5.385269 9.461094) (xy 5.511418 9.433467) (xy 5.635628 9.398126) (xy 5.757427 9.355206)
			(xy 5.876352 9.304869) (xy 5.991953 9.247307) (xy 6.103792 9.182737) (xy 6.211443 9.111405) (xy 6.314498 9.033581)
			(xy 6.412568 8.94956) (xy 6.505279 8.859661) (xy 6.51416 8.849919) (xy 208.661241 8.849919) (xy 208.661241 8.935669)
			(xy 208.669153 9.021052) (xy 208.684909 9.105342) (xy 208.708376 9.187818) (xy 208.739352 9.267777)
			(xy 208.777574 9.344537) (xy 208.822715 9.417443) (xy 208.874391 9.485872) (xy 208.93216 9.549242)
			(xy 208.99553 9.607011) (xy 209.063959 9.658687) (xy 209.136865 9.703828) (xy 209.213625 9.74205)
			(xy 209.293584 9.773026) (xy 209.37606 9.796493) (xy 209.46035 9.812249) (xy 209.545733 9.820161)
			(xy 209.631483 9.820161) (xy 209.716866 9.812249) (xy 209.801156 9.796493) (xy 209.883632 9.773026)
			(xy 209.963591 9.74205) (xy 210.040351 9.703828) (xy 210.113257 9.658687) (xy 210.181686 9.607011)
			(xy 210.245056 9.549242) (xy 210.302825 9.485872) (xy 210.354501 9.417443) (xy 210.399642 9.344537)
			(xy 210.437864 9.267777) (xy 210.46884 9.187818) (xy 210.492307 9.105342) (xy 210.508063 9.021052)
			(xy 210.515975 8.935669) (xy 210.51647 8.892794) (xy 210.515975 8.849919) (xy 215.011241 8.849919)
			(xy 215.011241 8.935669) (xy 215.019153 9.021052) (xy 215.034909 9.105342) (xy 215.058376 9.187818)
			(xy 215.089352 9.267777) (xy 215.127574 9.344537) (xy 215.172715 9.417443) (xy 215.224391 9.485872)
			(xy 215.28216 9.549242) (xy 215.34553 9.607011) (xy 215.413959 9.658687) (xy 215.486865 9.703828)
			(xy 215.563625 9.74205) (xy 215.643584 9.773026) (xy 215.72606 9.796493) (xy 215.81035 9.812249)
			(xy 215.895733 9.820161) (xy 215.981483 9.820161) (xy 216.066866 9.812249) (xy 216.151156 9.796493)
			(xy 216.233632 9.773026) (xy 216.313591 9.74205) (xy 216.390351 9.703828) (xy 216.463257 9.658687)
			(xy 216.531686 9.607011) (xy 216.595056 9.549242) (xy 216.652825 9.485872) (xy 216.704501 9.417443)
			(xy 216.749642 9.344537) (xy 216.787864 9.267777) (xy 216.81884 9.187818) (xy 216.842307 9.105342)
			(xy 216.858063 9.021052) (xy 216.865975 8.935669) (xy 216.86647 8.892794) (xy 216.865975 8.849919)
			(xy 296.143921 8.849919) (xy 296.143921 8.935669) (xy 296.151833 9.021052) (xy 296.167589 9.105342)
			(xy 296.191056 9.187818) (xy 296.222032 9.267777) (xy 296.260254 9.344537) (xy 296.305395 9.417443)
			(xy 296.357071 9.485872) (xy 296.41484 9.549242) (xy 296.47821 9.607011) (xy 296.546639 9.658687)
			(xy 296.619545 9.703828) (xy 296.696305 9.74205) (xy 296.776264 9.773026) (xy 296.85874 9.796493)
			(xy 296.94303 9.812249) (xy 297.028413 9.820161) (xy 297.114163 9.820161) (xy 297.199546 9.812249)
			(xy 297.283836 9.796493) (xy 297.366312 9.773026) (xy 297.446271 9.74205) (xy 297.523031 9.703828)
			(xy 297.595937 9.658687) (xy 297.664366 9.607011) (xy 297.727736 9.549242) (xy 297.785505 9.485872)
			(xy 297.837181 9.417443) (xy 297.882322 9.344537) (xy 297.920544 9.267777) (xy 297.95152 9.187818)
			(xy 297.974987 9.105342) (xy 297.990743 9.021052) (xy 297.998655 8.935669) (xy 297.99915 8.892794)
			(xy 297.998655 8.849919) (xy 302.493921 8.849919) (xy 302.493921 8.935669) (xy 302.501833 9.021052)
			(xy 302.517589 9.105342) (xy 302.541056 9.187818) (xy 302.572032 9.267777) (xy 302.610254 9.344537)
			(xy 302.655395 9.417443) (xy 302.707071 9.485872) (xy 302.76484 9.549242) (xy 302.82821 9.607011)
			(xy 302.896639 9.658687) (xy 302.969545 9.703828) (xy 303.046305 9.74205) (xy 303.126264 9.773026)
			(xy 303.20874 9.796493) (xy 303.29303 9.812249) (xy 303.378413 9.820161) (xy 303.464163 9.820161)
			(xy 303.549546 9.812249) (xy 303.633836 9.796493) (xy 303.716312 9.773026) (xy 303.796271 9.74205)
			(xy 303.873031 9.703828) (xy 303.945937 9.658687) (xy 304.014366 9.607011) (xy 304.077736 9.549242)
			(xy 304.135505 9.485872) (xy 304.187181 9.417443) (xy 304.232322 9.344537) (xy 304.270544 9.267777)
			(xy 304.30152 9.187818) (xy 304.324987 9.105342) (xy 304.340743 9.021052) (xy 304.348655 8.935669)
			(xy 304.34915 8.892794) (xy 304.348655 8.849919) (xy 311.155321 8.849919) (xy 311.155321 8.935669)
			(xy 311.163233 9.021052) (xy 311.178989 9.105342) (xy 311.202456 9.187818) (xy 311.233432 9.267777)
			(xy 311.271654 9.344537) (xy 311.316795 9.417443) (xy 311.368471 9.485872) (xy 311.42624 9.549242)
			(xy 311.48961 9.607011) (xy 311.558039 9.658687) (xy 311.630945 9.703828) (xy 311.707705 9.74205)
			(xy 311.787664 9.773026) (xy 311.87014 9.796493) (xy 311.95443 9.812249) (xy 312.039813 9.820161)
			(xy 312.125563 9.820161) (xy 312.210946 9.812249) (xy 312.295236 9.796493) (xy 312.377712 9.773026)
			(xy 312.457671 9.74205) (xy 312.534431 9.703828) (xy 312.607337 9.658687) (xy 312.675766 9.607011)
			(xy 312.739136 9.549242) (xy 312.796905 9.485872) (xy 312.848581 9.417443) (xy 312.893722 9.344537)
			(xy 312.931944 9.267777) (xy 312.96292 9.187818) (xy 312.986387 9.105342) (xy 313.002143 9.021052)
			(xy 313.010055 8.935669) (xy 313.01055 8.892794) (xy 313.010055 8.849919) (xy 317.505321 8.849919)
			(xy 317.505321 8.935669) (xy 317.513233 9.021052) (xy 317.528989 9.105342) (xy 317.552456 9.187818)
			(xy 317.583432 9.267777) (xy 317.621654 9.344537) (xy 317.666795 9.417443) (xy 317.718471 9.485872)
			(xy 317.77624 9.549242) (xy 317.83961 9.607011) (xy 317.908039 9.658687) (xy 317.980945 9.703828)
			(xy 318.057705 9.74205) (xy 318.137664 9.773026) (xy 318.22014 9.796493) (xy 318.30443 9.812249)
			(xy 318.389813 9.820161) (xy 318.475563 9.820161) (xy 318.560946 9.812249) (xy 318.645236 9.796493)
			(xy 318.727712 9.773026) (xy 318.807671 9.74205) (xy 318.884431 9.703828) (xy 318.957337 9.658687)
			(xy 319.025766 9.607011) (xy 319.089136 9.549242) (xy 319.146905 9.485872) (xy 319.198581 9.417443)
			(xy 319.243722 9.344537) (xy 319.281944 9.267777) (xy 319.31292 9.187818) (xy 319.336387 9.105342)
			(xy 319.352143 9.021052) (xy 319.360055 8.935669) (xy 319.36055 8.892794) (xy 319.360055 8.849919)
			(xy 361.894107 8.849919) (xy 361.894107 8.935669) (xy 361.902019 9.021052) (xy 361.917775 9.105342)
			(xy 361.941242 9.187818) (xy 361.972218 9.267777) (xy 362.01044 9.344537) (xy 362.055581 9.417443)
			(xy 362.107257 9.485872) (xy 362.165026 9.549242) (xy 362.228396 9.607011) (xy 362.296825 9.658687)
			(xy 362.369731 9.703828) (xy 362.446491 9.74205) (xy 362.52645 9.773026) (xy 362.608926 9.796493)
			(xy 362.693216 9.812249) (xy 362.778599 9.820161) (xy 362.864349 9.820161) (xy 362.949732 9.812249)
			(xy 363.034022 9.796493) (xy 363.116498 9.773026) (xy 363.196457 9.74205) (xy 363.273217 9.703828)
			(xy 363.346123 9.658687) (xy 363.414552 9.607011) (xy 363.477922 9.549242) (xy 363.535691 9.485872)
			(xy 363.587367 9.417443) (xy 363.632508 9.344537) (xy 363.67073 9.267777) (xy 363.701706 9.187818)
			(xy 363.725173 9.105342) (xy 363.740929 9.021052) (xy 363.748841 8.935669) (xy 363.749336 8.892794)
			(xy 363.748841 8.849919) (xy 368.244107 8.849919) (xy 368.244107 8.935669) (xy 368.252019 9.021052)
			(xy 368.267775 9.105342) (xy 368.291242 9.187818) (xy 368.322218 9.267777) (xy 368.36044 9.344537)
			(xy 368.405581 9.417443) (xy 368.457257 9.485872) (xy 368.515026 9.549242) (xy 368.578396 9.607011)
			(xy 368.646825 9.658687) (xy 368.719731 9.703828) (xy 368.796491 9.74205) (xy 368.87645 9.773026)
			(xy 368.958926 9.796493) (xy 369.043216 9.812249) (xy 369.128599 9.820161) (xy 369.214349 9.820161)
			(xy 369.299732 9.812249) (xy 369.384022 9.796493) (xy 369.466498 9.773026) (xy 369.546457 9.74205)
			(xy 369.623217 9.703828) (xy 369.696123 9.658687) (xy 369.764552 9.607011) (xy 369.827922 9.549242)
			(xy 369.885691 9.485872) (xy 369.937367 9.417443) (xy 369.982508 9.344537) (xy 370.02073 9.267777)
			(xy 370.051706 9.187818) (xy 370.075173 9.105342) (xy 370.090929 9.021052) (xy 370.098841 8.935669)
			(xy 370.099336 8.892794) (xy 370.098841 8.849919) (xy 370.090929 8.764536) (xy 370.075173 8.680246)
			(xy 370.051706 8.59777) (xy 370.02073 8.517811) (xy 369.982508 8.441051) (xy 369.937367 8.368145)
			(xy 369.885691 8.299716) (xy 369.827922 8.236346) (xy 369.764552 8.178577) (xy 369.696123 8.126901)
			(xy 369.623217 8.08176) (xy 369.546457 8.043538) (xy 369.466498 8.012562) (xy 369.384022 7.989095)
			(xy 369.299732 7.973339) (xy 369.214349 7.965427) (xy 369.128599 7.965427) (xy 369.043216 7.973339)
			(xy 368.958926 7.989095) (xy 368.87645 8.012562) (xy 368.796491 8.043538) (xy 368.719731 8.08176)
			(xy 368.646825 8.126901) (xy 368.578396 8.178577) (xy 368.515026 8.236346) (xy 368.457257 8.299716)
			(xy 368.405581 8.368145) (xy 368.36044 8.441051) (xy 368.322218 8.517811) (xy 368.291242 8.59777)
			(xy 368.267775 8.680246) (xy 368.252019 8.764536) (xy 368.244107 8.849919) (xy 363.748841 8.849919)
			(xy 363.740929 8.764536) (xy 363.725173 8.680246) (xy 363.701706 8.59777) (xy 363.67073 8.517811)
			(xy 363.632508 8.441051) (xy 363.587367 8.368145) (xy 363.535691 8.299716) (xy 363.477922 8.236346)
			(xy 363.414552 8.178577) (xy 363.346123 8.126901) (xy 363.273217 8.08176) (xy 363.196457 8.043538)
			(xy 363.116498 8.012562) (xy 363.034022 7.989095) (xy 362.949732 7.973339) (xy 362.864349 7.965427)
			(xy 362.778599 7.965427) (xy 362.693216 7.973339) (xy 362.608926 7.989095) (xy 362.52645 8.012562)
			(xy 362.446491 8.043538) (xy 362.369731 8.08176) (xy 362.296825 8.126901) (xy 362.228396 8.178577)
			(xy 362.165026 8.236346) (xy 362.107257 8.299716) (xy 362.055581 8.368145) (xy 362.01044 8.441051)
			(xy 361.972218 8.517811) (xy 361.941242 8.59777) (xy 361.917775 8.680246) (xy 361.902019 8.764536)
			(xy 361.894107 8.849919) (xy 319.360055 8.849919) (xy 319.352143 8.764536) (xy 319.336387 8.680246)
			(xy 319.31292 8.59777) (xy 319.281944 8.517811) (xy 319.243722 8.441051) (xy 319.198581 8.368145)
			(xy 319.146905 8.299716) (xy 319.089136 8.236346) (xy 319.025766 8.178577) (xy 318.957337 8.126901)
			(xy 318.884431 8.08176) (xy 318.807671 8.043538) (xy 318.727712 8.012562) (xy 318.645236 7.989095)
			(xy 318.560946 7.973339) (xy 318.475563 7.965427) (xy 318.389813 7.965427) (xy 318.30443 7.973339)
			(xy 318.22014 7.989095) (xy 318.137664 8.012562) (xy 318.057705 8.043538) (xy 317.980945 8.08176)
			(xy 317.908039 8.126901) (xy 317.83961 8.178577) (xy 317.77624 8.236346) (xy 317.718471 8.299716)
			(xy 317.666795 8.368145) (xy 317.621654 8.441051) (xy 317.583432 8.517811) (xy 317.552456 8.59777)
			(xy 317.528989 8.680246) (xy 317.513233 8.764536) (xy 317.505321 8.849919) (xy 313.010055 8.849919)
			(xy 313.002143 8.764536) (xy 312.986387 8.680246) (xy 312.96292 8.59777) (xy 312.931944 8.517811)
			(xy 312.893722 8.441051) (xy 312.848581 8.368145) (xy 312.796905 8.299716) (xy 312.739136 8.236346)
			(xy 312.675766 8.178577) (xy 312.607337 8.126901) (xy 312.534431 8.08176) (xy 312.457671 8.043538)
			(xy 312.377712 8.012562) (xy 312.295236 7.989095) (xy 312.210946 7.973339) (xy 312.125563 7.965427)
			(xy 312.039813 7.965427) (xy 311.95443 7.973339) (xy 311.87014 7.989095) (xy 311.787664 8.012562)
			(xy 311.707705 8.043538) (xy 311.630945 8.08176) (xy 311.558039 8.126901) (xy 311.48961 8.178577)
			(xy 311.42624 8.236346) (xy 311.368471 8.299716) (xy 311.316795 8.368145) (xy 311.271654 8.441051)
			(xy 311.233432 8.517811) (xy 311.202456 8.59777) (xy 311.178989 8.680246) (xy 311.163233 8.764536)
			(xy 311.155321 8.849919) (xy 304.348655 8.849919) (xy 304.340743 8.764536) (xy 304.324987 8.680246)
			(xy 304.30152 8.59777) (xy 304.270544 8.517811) (xy 304.232322 8.441051) (xy 304.187181 8.368145)
			(xy 304.135505 8.299716) (xy 304.077736 8.236346) (xy 304.014366 8.178577) (xy 303.945937 8.126901)
			(xy 303.873031 8.08176) (xy 303.796271 8.043538) (xy 303.716312 8.012562) (xy 303.633836 7.989095)
			(xy 303.549546 7.973339) (xy 303.464163 7.965427) (xy 303.378413 7.965427) (xy 303.29303 7.973339)
			(xy 303.20874 7.989095) (xy 303.126264 8.012562) (xy 303.046305 8.043538) (xy 302.969545 8.08176)
			(xy 302.896639 8.126901) (xy 302.82821 8.178577) (xy 302.76484 8.236346) (xy 302.707071 8.299716)
			(xy 302.655395 8.368145) (xy 302.610254 8.441051) (xy 302.572032 8.517811) (xy 302.541056 8.59777)
			(xy 302.517589 8.680246) (xy 302.501833 8.764536) (xy 302.493921 8.849919) (xy 297.998655 8.849919)
			(xy 297.990743 8.764536) (xy 297.974987 8.680246) (xy 297.95152 8.59777) (xy 297.920544 8.517811)
			(xy 297.882322 8.441051) (xy 297.837181 8.368145) (xy 297.785505 8.299716) (xy 297.727736 8.236346)
			(xy 297.664366 8.178577) (xy 297.595937 8.126901) (xy 297.523031 8.08176) (xy 297.446271 8.043538)
			(xy 297.366312 8.012562) (xy 297.283836 7.989095) (xy 297.199546 7.973339) (xy 297.114163 7.965427)
			(xy 297.028413 7.965427) (xy 296.94303 7.973339) (xy 296.85874 7.989095) (xy 296.776264 8.012562)
			(xy 296.696305 8.043538) (xy 296.619545 8.08176) (xy 296.546639 8.126901) (xy 296.47821 8.178577)
			(xy 296.41484 8.236346) (xy 296.357071 8.299716) (xy 296.305395 8.368145) (xy 296.260254 8.441051)
			(xy 296.222032 8.517811) (xy 296.191056 8.59777) (xy 296.167589 8.680246) (xy 296.151833 8.764536)
			(xy 296.143921 8.849919) (xy 216.865975 8.849919) (xy 216.858063 8.764536) (xy 216.842307 8.680246)
			(xy 216.81884 8.59777) (xy 216.787864 8.517811) (xy 216.749642 8.441051) (xy 216.704501 8.368145)
			(xy 216.652825 8.299716) (xy 216.595056 8.236346) (xy 216.531686 8.178577) (xy 216.463257 8.126901)
			(xy 216.390351 8.08176) (xy 216.313591 8.043538) (xy 216.233632 8.012562) (xy 216.151156 7.989095)
			(xy 216.066866 7.973339) (xy 215.981483 7.965427) (xy 215.895733 7.965427) (xy 215.81035 7.973339)
			(xy 215.72606 7.989095) (xy 215.643584 8.012562) (xy 215.563625 8.043538) (xy 215.486865 8.08176)
			(xy 215.413959 8.126901) (xy 215.34553 8.178577) (xy 215.28216 8.236346) (xy 215.224391 8.299716)
			(xy 215.172715 8.368145) (xy 215.127574 8.441051) (xy 215.089352 8.517811) (xy 215.058376 8.59777)
			(xy 215.034909 8.680246) (xy 215.019153 8.764536) (xy 215.011241 8.849919) (xy 210.515975 8.849919)
			(xy 210.508063 8.764536) (xy 210.492307 8.680246) (xy 210.46884 8.59777) (xy 210.437864 8.517811)
			(xy 210.399642 8.441051) (xy 210.354501 8.368145) (xy 210.302825 8.299716) (xy 210.245056 8.236346)
			(xy 210.181686 8.178577) (xy 210.113257 8.126901) (xy 210.040351 8.08176) (xy 209.963591 8.043538)
			(xy 209.883632 8.012562) (xy 209.801156 7.989095) (xy 209.716866 7.973339) (xy 209.631483 7.965427)
			(xy 209.545733 7.965427) (xy 209.46035 7.973339) (xy 209.37606 7.989095) (xy 209.293584 8.012562)
			(xy 209.213625 8.043538) (xy 209.136865 8.08176) (xy 209.063959 8.126901) (xy 208.99553 8.178577)
			(xy 208.93216 8.236346) (xy 208.874391 8.299716) (xy 208.822715 8.368145) (xy 208.777574 8.441051)
			(xy 208.739352 8.517811) (xy 208.708376 8.59777) (xy 208.684909 8.680246) (xy 208.669153 8.764536)
			(xy 208.661241 8.849919) (xy 6.51416 8.849919) (xy 6.592279 8.764226) (xy 6.67324 8.663616) (xy 6.747854 8.558213)
			(xy 6.815837 8.448416) (xy 6.876932 8.334642) (xy 6.930907 8.217323) (xy 6.977558 8.096904) (xy 7.016707 7.973841)
			(xy 7.048206 7.848602) (xy 7.071935 7.721661) (xy 7.087805 7.593501) (xy 7.095755 7.464606) (xy 7.096252 7.400036)
			(xy 7.095755 7.335466) (xy 7.092973 7.290359) (xy 93.985575 7.290359) (xy 93.985575 7.376109) (xy 93.993487 7.461492)
			(xy 94.009243 7.545782) (xy 94.03271 7.628258) (xy 94.063686 7.708217) (xy 94.101908 7.784977) (xy 94.147049 7.857883)
			(xy 94.198725 7.926312) (xy 94.256494 7.989682) (xy 94.319864 8.047451) (xy 94.388293 8.099127) (xy 94.461199 8.144268)
			(xy 94.537959 8.18249) (xy 94.617918 8.213466) (xy 94.700394 8.236933) (xy 94.784684 8.252689) (xy 94.870067 8.260601)
			(xy 94.955817 8.260601) (xy 95.0412 8.252689) (xy 95.12549 8.236933) (xy 95.207966 8.213466) (xy 95.287925 8.18249)
			(xy 95.364685 8.144268) (xy 95.437591 8.099127) (xy 95.50602 8.047451) (xy 95.56939 7.989682) (xy 95.627159 7.926312)
			(xy 95.678835 7.857883) (xy 95.723976 7.784977) (xy 95.762198 7.708217) (xy 95.793174 7.628258) (xy 95.816641 7.545782)
			(xy 95.832397 7.461492) (xy 95.840309 7.376109) (xy 95.840804 7.333234) (xy 95.840309 7.290359) (xy 100.335575 7.290359)
			(xy 100.335575 7.376109) (xy 100.343487 7.461492) (xy 100.359243 7.545782) (xy 100.38271 7.628258)
			(xy 100.413686 7.708217) (xy 100.451908 7.784977) (xy 100.497049 7.857883) (xy 100.548725 7.926312)
			(xy 100.606494 7.989682) (xy 100.669864 8.047451) (xy 100.738293 8.099127) (xy 100.811199 8.144268)
			(xy 100.887959 8.18249) (xy 100.967918 8.213466) (xy 101.050394 8.236933) (xy 101.134684 8.252689)
			(xy 101.220067 8.260601) (xy 101.305817 8.260601) (xy 101.3912 8.252689) (xy 101.47549 8.236933)
			(xy 101.557966 8.213466) (xy 101.637925 8.18249) (xy 101.714685 8.144268) (xy 101.787591 8.099127)
			(xy 101.85602 8.047451) (xy 101.91939 7.989682) (xy 101.977159 7.926312) (xy 102.028835 7.857883)
			(xy 102.073976 7.784977) (xy 102.112198 7.708217) (xy 102.143174 7.628258) (xy 102.166641 7.545782)
			(xy 102.182397 7.461492) (xy 102.190309 7.376109) (xy 102.190804 7.333234) (xy 102.190309 7.290359)
			(xy 181.468255 7.290359) (xy 181.468255 7.376109) (xy 181.476167 7.461492) (xy 181.491923 7.545782)
			(xy 181.51539 7.628258) (xy 181.546366 7.708217) (xy 181.584588 7.784977) (xy 181.629729 7.857883)
			(xy 181.681405 7.926312) (xy 181.739174 7.989682) (xy 181.802544 8.047451) (xy 181.870973 8.099127)
			(xy 181.943879 8.144268) (xy 182.020639 8.18249) (xy 182.100598 8.213466) (xy 182.183074 8.236933)
			(xy 182.267364 8.252689) (xy 182.352747 8.260601) (xy 182.438497 8.260601) (xy 182.52388 8.252689)
			(xy 182.60817 8.236933) (xy 182.690646 8.213466) (xy 182.770605 8.18249) (xy 182.847365 8.144268)
			(xy 182.920271 8.099127) (xy 182.9887 8.047451) (xy 183.05207 7.989682) (xy 183.109839 7.926312)
			(xy 183.161515 7.857883) (xy 183.206656 7.784977) (xy 183.244878 7.708217) (xy 183.275854 7.628258)
			(xy 183.299321 7.545782) (xy 183.315077 7.461492) (xy 183.322989 7.376109) (xy 183.323484 7.333234)
			(xy 183.322989 7.290359) (xy 187.818255 7.290359) (xy 187.818255 7.376109) (xy 187.826167 7.461492)
			(xy 187.841923 7.545782) (xy 187.86539 7.628258) (xy 187.896366 7.708217) (xy 187.934588 7.784977)
			(xy 187.979729 7.857883) (xy 188.031405 7.926312) (xy 188.089174 7.989682) (xy 188.152544 8.047451)
			(xy 188.220973 8.099127) (xy 188.293879 8.144268) (xy 188.370639 8.18249) (xy 188.450598 8.213466)
			(xy 188.533074 8.236933) (xy 188.617364 8.252689) (xy 188.702747 8.260601) (xy 188.788497 8.260601)
			(xy 188.87388 8.252689) (xy 188.95817 8.236933) (xy 189.040646 8.213466) (xy 189.120605 8.18249)
			(xy 189.197365 8.144268) (xy 189.270271 8.099127) (xy 189.3387 8.047451) (xy 189.40207 7.989682)
			(xy 189.459839 7.926312) (xy 189.511515 7.857883) (xy 189.556656 7.784977) (xy 189.594878 7.708217)
			(xy 189.625854 7.628258) (xy 189.649321 7.545782) (xy 189.665077 7.461492) (xy 189.672989 7.376109)
			(xy 189.673484 7.333234) (xy 189.672989 7.290359) (xy 189.665077 7.204976) (xy 189.649321 7.120686)
			(xy 189.625854 7.03821) (xy 189.594878 6.958251) (xy 189.556656 6.881491) (xy 189.511515 6.808585)
			(xy 189.459839 6.740156) (xy 189.40207 6.676786) (xy 189.3387 6.619017) (xy 189.270271 6.567341)
			(xy 189.197365 6.5222) (xy 189.120605 6.483978) (xy 189.040646 6.453002) (xy 188.95817 6.429535)
			(xy 188.87388 6.413779) (xy 188.788497 6.405867) (xy 188.702747 6.405867) (xy 188.617364 6.413779)
			(xy 188.533074 6.429535) (xy 188.450598 6.453002) (xy 188.370639 6.483978) (xy 188.293879 6.5222)
			(xy 188.220973 6.567341) (xy 188.152544 6.619017) (xy 188.089174 6.676786) (xy 188.031405 6.740156)
			(xy 187.979729 6.808585) (xy 187.934588 6.881491) (xy 187.896366 6.958251) (xy 187.86539 7.03821)
			(xy 187.841923 7.120686) (xy 187.826167 7.204976) (xy 187.818255 7.290359) (xy 183.322989 7.290359)
			(xy 183.315077 7.204976) (xy 183.299321 7.120686) (xy 183.275854 7.03821) (xy 183.244878 6.958251)
			(xy 183.206656 6.881491) (xy 183.161515 6.808585) (xy 183.109839 6.740156) (xy 183.05207 6.676786)
			(xy 182.9887 6.619017) (xy 182.920271 6.567341) (xy 182.847365 6.5222) (xy 182.770605 6.483978) (xy 182.690646 6.453002)
			(xy 182.60817 6.429535) (xy 182.52388 6.413779) (xy 182.438497 6.405867) (xy 182.352747 6.405867)
			(xy 182.267364 6.413779) (xy 182.183074 6.429535) (xy 182.100598 6.453002) (xy 182.020639 6.483978)
			(xy 181.943879 6.5222) (xy 181.870973 6.567341) (xy 181.802544 6.619017) (xy 181.739174 6.676786)
			(xy 181.681405 6.740156) (xy 181.629729 6.808585) (xy 181.584588 6.881491) (xy 181.546366 6.958251)
			(xy 181.51539 7.03821) (xy 181.491923 7.120686) (xy 181.476167 7.204976) (xy 181.468255 7.290359)
			(xy 102.190309 7.290359) (xy 102.182397 7.204976) (xy 102.166641 7.120686) (xy 102.143174 7.03821)
			(xy 102.112198 6.958251) (xy 102.073976 6.881491) (xy 102.028835 6.808585) (xy 101.977159 6.740156)
			(xy 101.91939 6.676786) (xy 101.85602 6.619017) (xy 101.787591 6.567341) (xy 101.714685 6.5222) (xy 101.637925 6.483978)
			(xy 101.557966 6.453002) (xy 101.47549 6.429535) (xy 101.3912 6.413779) (xy 101.305817 6.405867)
			(xy 101.220067 6.405867) (xy 101.134684 6.413779) (xy 101.050394 6.429535) (xy 100.967918 6.453002)
			(xy 100.887959 6.483978) (xy 100.811199 6.5222) (xy 100.738293 6.567341) (xy 100.669864 6.619017)
			(xy 100.606494 6.676786) (xy 100.548725 6.740156) (xy 100.497049 6.808585) (xy 100.451908 6.881491)
			(xy 100.413686 6.958251) (xy 100.38271 7.03821) (xy 100.359243 7.120686) (xy 100.343487 7.204976)
			(xy 100.335575 7.290359) (xy 95.840309 7.290359) (xy 95.832397 7.204976) (xy 95.816641 7.120686)
			(xy 95.793174 7.03821) (xy 95.762198 6.958251) (xy 95.723976 6.881491) (xy 95.678835 6.808585) (xy 95.627159 6.740156)
			(xy 95.56939 6.676786) (xy 95.50602 6.619017) (xy 95.437591 6.567341) (xy 95.364685 6.5222) (xy 95.287925 6.483978)
			(xy 95.207966 6.453002) (xy 95.12549 6.429535) (xy 95.0412 6.413779) (xy 94.955817 6.405867) (xy 94.870067 6.405867)
			(xy 94.784684 6.413779) (xy 94.700394 6.429535) (xy 94.617918 6.453002) (xy 94.537959 6.483978) (xy 94.461199 6.5222)
			(xy 94.388293 6.567341) (xy 94.319864 6.619017) (xy 94.256494 6.676786) (xy 94.198725 6.740156) (xy 94.147049 6.808585)
			(xy 94.101908 6.881491) (xy 94.063686 6.958251) (xy 94.03271 7.03821) (xy 94.009243 7.120686) (xy 93.993487 7.204976)
			(xy 93.985575 7.290359) (xy 7.092973 7.290359) (xy 7.087805 7.206571) (xy 7.071935 7.078411) (xy 7.048206 6.95147)
			(xy 7.016707 6.826231) (xy 6.977558 6.703168) (xy 6.930907 6.582749) (xy 6.876932 6.46543) (xy 6.815837 6.351656)
			(xy 6.747854 6.241859) (xy 6.67324 6.136456) (xy 6.592279 6.035846) (xy 6.505279 5.940411) (xy 6.412568 5.850512)
			(xy 6.314498 5.766491) (xy 6.211443 5.688667) (xy 6.103792 5.617335) (xy 5.991953 5.552765) (xy 5.876352 5.495203)
			(xy 5.757427 5.444866) (xy 5.635628 5.401946) (xy 5.511418 5.366605) (xy 5.385269 5.338978) (xy 5.257657 5.319169)
			(xy 5.129068 5.307253) (xy 4.99999 5.303277) (xy 4.870912 5.307253) (xy 4.742323 5.319169) (xy 4.614711 5.338978)
			(xy 4.488562 5.366605) (xy 4.364352 5.401946) (xy 4.242553 5.444866) (xy 4.123628 5.495203) (xy 4.008027 5.552765)
			(xy 3.896188 5.617335) (xy 3.788537 5.688667) (xy 3.685482 5.766491) (xy 3.587412 5.850512) (xy 3.494701 5.940411)
			(xy 3.407701 6.035846) (xy 3.32674 6.136456) (xy 3.252126 6.241859) (xy 3.184143 6.351656) (xy 3.123048 6.46543)
			(xy 3.069073 6.582749) (xy 3.022422 6.703168) (xy 2.983273 6.826231) (xy 2.951774 6.95147) (xy 2.928045 7.078411)
			(xy 2.912175 7.206571) (xy 2.904225 7.335466) (xy 0.509016 7.335466) (xy 0.509016 4.750359) (xy 93.985575 4.750359)
			(xy 93.985575 4.836109) (xy 93.993487 4.921492) (xy 94.009243 5.005782) (xy 94.03271 5.088258) (xy 94.063686 5.168217)
			(xy 94.101908 5.244977) (xy 94.147049 5.317883) (xy 94.198725 5.386312) (xy 94.256494 5.449682) (xy 94.319864 5.507451)
			(xy 94.388293 5.559127) (xy 94.461199 5.604268) (xy 94.537959 5.64249) (xy 94.617918 5.673466) (xy 94.700394 5.696933)
			(xy 94.784684 5.712689) (xy 94.870067 5.720601) (xy 94.955817 5.720601) (xy 95.0412 5.712689) (xy 95.12549 5.696933)
			(xy 95.207966 5.673466) (xy 95.287925 5.64249) (xy 95.308598 5.632196) (xy 98.842576 5.632196) (xy 98.842576 6.495796)
			(xy 98.84308 6.525332) (xy 98.851124 6.583854) (xy 98.867061 6.640736) (xy 98.890596 6.694918) (xy 98.921289 6.745391)
			(xy 98.958569 6.791214) (xy 99.001741 6.831534) (xy 99.050001 6.8656) (xy 99.102451 6.892777) (xy 99.158112 6.912559)
			(xy 99.215949 6.924578) (xy 99.274884 6.928609) (xy 99.333819 6.924578) (xy 99.391656 6.912559) (xy 99.447317 6.892777)
			(xy 99.499767 6.8656) (xy 99.548027 6.831534) (xy 99.591199 6.791214) (xy 99.628479 6.745391) (xy 99.659172 6.694918)
			(xy 99.682707 6.640736) (xy 99.698644 6.583854) (xy 99.706688 6.525332) (xy 99.707192 6.495796) (xy 99.707192 5.632196)
			(xy 99.706688 5.60266) (xy 99.698644 5.544138) (xy 99.682707 5.487256) (xy 99.659172 5.433074) (xy 99.628479 5.382601)
			(xy 99.591199 5.336778) (xy 99.548027 5.296458) (xy 99.499767 5.262392) (xy 99.447317 5.235215) (xy 99.391656 5.215433)
			(xy 99.333819 5.203414) (xy 99.274884 5.199383) (xy 99.215949 5.203414) (xy 99.158112 5.215433) (xy 99.102451 5.235215)
			(xy 99.050001 5.262392) (xy 99.001741 5.296458) (xy 98.958569 5.336778) (xy 98.921289 5.382601) (xy 98.890596 5.433074)
			(xy 98.867061 5.487256) (xy 98.851124 5.544138) (xy 98.84308 5.60266) (xy 98.842576 5.632196) (xy 95.308598 5.632196)
			(xy 95.364685 5.604268) (xy 95.437591 5.559127) (xy 95.50602 5.507451) (xy 95.56939 5.449682) (xy 95.627159 5.386312)
			(xy 95.678835 5.317883) (xy 95.723976 5.244977) (xy 95.762198 5.168217) (xy 95.793174 5.088258) (xy 95.816641 5.005782)
			(xy 95.832397 4.921492) (xy 95.840309 4.836109) (xy 95.840804 4.793234) (xy 95.840309 4.750359) (xy 100.335575 4.750359)
			(xy 100.335575 4.836109) (xy 100.343487 4.921492) (xy 100.359243 5.005782) (xy 100.38271 5.088258)
			(xy 100.413686 5.168217) (xy 100.451908 5.244977) (xy 100.497049 5.317883) (xy 100.548725 5.386312)
			(xy 100.606494 5.449682) (xy 100.669864 5.507451) (xy 100.738293 5.559127) (xy 100.811199 5.604268)
			(xy 100.887959 5.64249) (xy 100.967918 5.673466) (xy 101.050394 5.696933) (xy 101.134684 5.712689)
			(xy 101.220067 5.720601) (xy 101.305817 5.720601) (xy 101.3912 5.712689) (xy 101.47549 5.696933)
			(xy 101.557966 5.673466) (xy 101.637925 5.64249) (xy 101.714685 5.604268) (xy 101.787591 5.559127)
			(xy 101.85602 5.507451) (xy 101.91939 5.449682) (xy 101.977159 5.386312) (xy 102.028835 5.317883)
			(xy 102.073976 5.244977) (xy 102.112198 5.168217) (xy 102.143174 5.088258) (xy 102.166641 5.005782)
			(xy 102.182397 4.921492) (xy 102.190309 4.836109) (xy 102.190804 4.793234) (xy 102.190309 4.750359)
			(xy 181.468255 4.750359) (xy 181.468255 4.836109) (xy 181.476167 4.921492) (xy 181.491923 5.005782)
			(xy 181.51539 5.088258) (xy 181.546366 5.168217) (xy 181.584588 5.244977) (xy 181.629729 5.317883)
			(xy 181.681405 5.386312) (xy 181.739174 5.449682) (xy 181.802544 5.507451) (xy 181.870973 5.559127)
			(xy 181.943879 5.604268) (xy 182.020639 5.64249) (xy 182.100598 5.673466) (xy 182.183074 5.696933)
			(xy 182.267364 5.712689) (xy 182.352747 5.720601) (xy 182.438497 5.720601) (xy 182.52388 5.712689)
			(xy 182.60817 5.696933) (xy 182.690646 5.673466) (xy 182.770605 5.64249) (xy 182.791278 5.632196)
			(xy 183.953912 5.632196) (xy 183.953912 6.495796) (xy 183.954416 6.525332) (xy 183.96246 6.583854)
			(xy 183.978397 6.640736) (xy 184.001932 6.694918) (xy 184.032625 6.745391) (xy 184.069905 6.791214)
			(xy 184.113077 6.831534) (xy 184.161337 6.8656) (xy 184.213787 6.892777) (xy 184.269448 6.912559)
			(xy 184.327285 6.924578) (xy 184.38622 6.928609) (xy 184.445155 6.924578) (xy 184.502992 6.912559)
			(xy 184.558653 6.892777) (xy 184.611103 6.8656) (xy 184.659363 6.831534) (xy 184.702535 6.791214)
			(xy 184.739815 6.745391) (xy 184.770508 6.694918) (xy 184.794043 6.640736) (xy 184.80998 6.583854)
			(xy 184.818024 6.525332) (xy 184.818528 6.495796) (xy 184.818528 6.309919) (xy 208.661241 6.309919)
			(xy 208.661241 6.395669) (xy 208.669153 6.481052) (xy 208.684909 6.565342) (xy 208.708376 6.647818)
			(xy 208.739352 6.727777) (xy 208.777574 6.804537) (xy 208.822715 6.877443) (xy 208.874391 6.945872)
			(xy 208.93216 7.009242) (xy 208.99553 7.067011) (xy 209.063959 7.118687) (xy 209.136865 7.163828)
			(xy 209.213625 7.20205) (xy 209.293584 7.233026) (xy 209.37606 7.256493) (xy 209.46035 7.272249)
			(xy 209.545733 7.280161) (xy 209.631483 7.280161) (xy 209.716866 7.272249) (xy 209.801156 7.256493)
			(xy 209.883632 7.233026) (xy 209.963591 7.20205) (xy 210.040351 7.163828) (xy 210.113257 7.118687)
			(xy 210.181686 7.067011) (xy 210.245056 7.009242) (xy 210.302825 6.945872) (xy 210.354501 6.877443)
			(xy 210.399642 6.804537) (xy 210.437864 6.727777) (xy 210.46884 6.647818) (xy 210.492307 6.565342)
			(xy 210.508063 6.481052) (xy 210.515975 6.395669) (xy 210.51647 6.352794) (xy 210.515975 6.309919)
			(xy 215.011241 6.309919) (xy 215.011241 6.395669) (xy 215.019153 6.481052) (xy 215.034909 6.565342)
			(xy 215.058376 6.647818) (xy 215.089352 6.727777) (xy 215.127574 6.804537) (xy 215.172715 6.877443)
			(xy 215.224391 6.945872) (xy 215.28216 7.009242) (xy 215.34553 7.067011) (xy 215.413959 7.118687)
			(xy 215.486865 7.163828) (xy 215.563625 7.20205) (xy 215.643584 7.233026) (xy 215.72606 7.256493)
			(xy 215.81035 7.272249) (xy 215.895733 7.280161) (xy 215.981483 7.280161) (xy 216.066866 7.272249)
			(xy 216.151156 7.256493) (xy 216.233632 7.233026) (xy 216.313591 7.20205) (xy 216.390351 7.163828)
			(xy 216.463257 7.118687) (xy 216.531686 7.067011) (xy 216.595056 7.009242) (xy 216.652825 6.945872)
			(xy 216.704501 6.877443) (xy 216.749642 6.804537) (xy 216.787864 6.727777) (xy 216.81884 6.647818)
			(xy 216.842307 6.565342) (xy 216.858063 6.481052) (xy 216.865975 6.395669) (xy 216.86647 6.352794)
			(xy 216.865975 6.309919) (xy 296.143921 6.309919) (xy 296.143921 6.395669) (xy 296.151833 6.481052)
			(xy 296.167589 6.565342) (xy 296.191056 6.647818) (xy 296.222032 6.727777) (xy 296.260254 6.804537)
			(xy 296.305395 6.877443) (xy 296.357071 6.945872) (xy 296.41484 7.009242) (xy 296.47821 7.067011)
			(xy 296.546639 7.118687) (xy 296.619545 7.163828) (xy 296.696305 7.20205) (xy 296.776264 7.233026)
			(xy 296.85874 7.256493) (xy 296.94303 7.272249) (xy 297.028413 7.280161) (xy 297.114163 7.280161)
			(xy 297.199546 7.272249) (xy 297.283836 7.256493) (xy 297.366312 7.233026) (xy 297.446271 7.20205)
			(xy 297.523031 7.163828) (xy 297.595937 7.118687) (xy 297.664366 7.067011) (xy 297.727736 7.009242)
			(xy 297.785505 6.945872) (xy 297.837181 6.877443) (xy 297.882322 6.804537) (xy 297.920544 6.727777)
			(xy 297.95152 6.647818) (xy 297.974987 6.565342) (xy 297.990743 6.481052) (xy 297.998655 6.395669)
			(xy 297.99915 6.352794) (xy 297.998655 6.309919) (xy 302.493921 6.309919) (xy 302.493921 6.395669)
			(xy 302.501833 6.481052) (xy 302.517589 6.565342) (xy 302.541056 6.647818) (xy 302.572032 6.727777)
			(xy 302.610254 6.804537) (xy 302.655395 6.877443) (xy 302.707071 6.945872) (xy 302.76484 7.009242)
			(xy 302.82821 7.067011) (xy 302.896639 7.118687) (xy 302.969545 7.163828) (xy 303.046305 7.20205)
			(xy 303.126264 7.233026) (xy 303.20874 7.256493) (xy 303.29303 7.272249) (xy 303.378413 7.280161)
			(xy 303.464163 7.280161) (xy 303.549546 7.272249) (xy 303.633836 7.256493) (xy 303.716312 7.233026)
			(xy 303.796271 7.20205) (xy 303.873031 7.163828) (xy 303.945937 7.118687) (xy 304.014366 7.067011)
			(xy 304.077736 7.009242) (xy 304.135505 6.945872) (xy 304.187181 6.877443) (xy 304.232322 6.804537)
			(xy 304.270544 6.727777) (xy 304.30152 6.647818) (xy 304.324987 6.565342) (xy 304.340743 6.481052)
			(xy 304.348655 6.395669) (xy 304.34915 6.352794) (xy 304.348655 6.309919) (xy 311.155321 6.309919)
			(xy 311.155321 6.395669) (xy 311.163233 6.481052) (xy 311.178989 6.565342) (xy 311.202456 6.647818)
			(xy 311.233432 6.727777) (xy 311.271654 6.804537) (xy 311.316795 6.877443) (xy 311.368471 6.945872)
			(xy 311.42624 7.009242) (xy 311.48961 7.067011) (xy 311.558039 7.118687) (xy 311.630945 7.163828)
			(xy 311.707705 7.20205) (xy 311.787664 7.233026) (xy 311.87014 7.256493) (xy 311.95443 7.272249)
			(xy 312.039813 7.280161) (xy 312.125563 7.280161) (xy 312.210946 7.272249) (xy 312.295236 7.256493)
			(xy 312.377712 7.233026) (xy 312.457671 7.20205) (xy 312.478344 7.191756) (xy 316.012068 7.191756)
			(xy 316.012068 8.055356) (xy 316.012572 8.08491) (xy 316.020621 8.143466) (xy 316.036567 8.200381)
			(xy 316.060116 8.254595) (xy 316.090827 8.305098) (xy 316.128129 8.350948) (xy 316.171326 8.391291)
			(xy 316.219615 8.425377) (xy 316.272095 8.45257) (xy 316.32779 8.472364) (xy 316.385661 8.48439)
			(xy 316.44463 8.488424) (xy 316.503599 8.48439) (xy 316.56147 8.472364) (xy 316.617165 8.45257) (xy 316.669645 8.425377)
			(xy 316.717934 8.391291) (xy 316.761131 8.350948) (xy 316.798433 8.305098) (xy 316.829144 8.254595)
			(xy 316.852693 8.200381) (xy 316.868639 8.143466) (xy 316.876688 8.08491) (xy 316.877192 8.055356)
			(xy 316.877192 7.191756) (xy 316.876688 7.162202) (xy 316.868639 7.103646) (xy 316.852693 7.046731)
			(xy 316.829144 6.992517) (xy 316.798433 6.942014) (xy 316.761131 6.896164) (xy 316.717934 6.855821)
			(xy 316.669645 6.821735) (xy 316.617165 6.794542) (xy 316.56147 6.774748) (xy 316.503599 6.762722)
			(xy 316.44463 6.758689) (xy 316.385661 6.762722) (xy 316.32779 6.774748) (xy 316.272095 6.794542)
			(xy 316.219615 6.821735) (xy 316.171326 6.855821) (xy 316.128129 6.896164) (xy 316.090827 6.942014)
			(xy 316.060116 6.992517) (xy 316.036567 7.046731) (xy 316.020621 7.103646) (xy 316.012572 7.162202)
			(xy 316.012068 7.191756) (xy 312.478344 7.191756) (xy 312.534431 7.163828) (xy 312.607337 7.118687)
			(xy 312.675766 7.067011) (xy 312.739136 7.009242) (xy 312.796905 6.945872) (xy 312.848581 6.877443)
			(xy 312.893722 6.804537) (xy 312.931944 6.727777) (xy 312.96292 6.647818) (xy 312.986387 6.565342)
			(xy 313.002143 6.481052) (xy 313.010055 6.395669) (xy 313.01055 6.352794) (xy 313.010055 6.309919)
			(xy 317.505321 6.309919) (xy 317.505321 6.395669) (xy 317.513233 6.481052) (xy 317.528989 6.565342)
			(xy 317.552456 6.647818) (xy 317.583432 6.727777) (xy 317.621654 6.804537) (xy 317.666795 6.877443)
			(xy 317.718471 6.945872) (xy 317.77624 7.009242) (xy 317.83961 7.067011) (xy 317.908039 7.118687)
			(xy 317.980945 7.163828) (xy 318.057705 7.20205) (xy 318.137664 7.233026) (xy 318.22014 7.256493)
			(xy 318.30443 7.272249) (xy 318.389813 7.280161) (xy 318.475563 7.280161) (xy 318.560946 7.272249)
			(xy 318.645236 7.256493) (xy 318.727712 7.233026) (xy 318.807671 7.20205) (xy 318.884431 7.163828)
			(xy 318.957337 7.118687) (xy 319.025766 7.067011) (xy 319.089136 7.009242) (xy 319.146905 6.945872)
			(xy 319.198581 6.877443) (xy 319.243722 6.804537) (xy 319.281944 6.727777) (xy 319.31292 6.647818)
			(xy 319.336387 6.565342) (xy 319.352143 6.481052) (xy 319.360055 6.395669) (xy 319.36055 6.352794)
			(xy 319.360055 6.309919) (xy 361.894107 6.309919) (xy 361.894107 6.395669) (xy 361.902019 6.481052)
			(xy 361.917775 6.565342) (xy 361.941242 6.647818) (xy 361.972218 6.727777) (xy 362.01044 6.804537)
			(xy 362.055581 6.877443) (xy 362.107257 6.945872) (xy 362.165026 7.009242) (xy 362.228396 7.067011)
			(xy 362.296825 7.118687) (xy 362.369731 7.163828) (xy 362.446491 7.20205) (xy 362.52645 7.233026)
			(xy 362.608926 7.256493) (xy 362.693216 7.272249) (xy 362.778599 7.280161) (xy 362.864349 7.280161)
			(xy 362.949732 7.272249) (xy 363.034022 7.256493) (xy 363.116498 7.233026) (xy 363.196457 7.20205)
			(xy 363.21713 7.191756) (xy 364.379764 7.191756) (xy 364.379764 8.055356) (xy 364.380268 8.084892)
			(xy 364.388312 8.143414) (xy 364.404249 8.200296) (xy 364.427784 8.254478) (xy 364.458477 8.304951)
			(xy 364.495757 8.350774) (xy 364.538929 8.391094) (xy 364.587189 8.42516) (xy 364.639639 8.452337)
			(xy 364.6953 8.472119) (xy 364.753137 8.484138) (xy 364.812072 8.488169) (xy 364.871007 8.484138)
			(xy 364.928844 8.472119) (xy 364.984505 8.452337) (xy 365.036955 8.42516) (xy 365.085215 8.391094)
			(xy 365.128387 8.350774) (xy 365.165667 8.304951) (xy 365.19636 8.254478) (xy 365.219895 8.200296)
			(xy 365.235832 8.143414) (xy 365.243876 8.084892) (xy 365.24438 8.055356) (xy 365.24438 7.376973)
			(xy 385.651997 7.376973) (xy 385.651997 7.462723) (xy 385.659909 7.548106) (xy 385.675665 7.632396)
			(xy 385.699132 7.714872) (xy 385.730108 7.794831) (xy 385.76833 7.871591) (xy 385.813471 7.944497)
			(xy 385.865147 8.012926) (xy 385.922916 8.076296) (xy 385.986286 8.134065) (xy 386.054715 8.185741)
			(xy 386.127621 8.230882) (xy 386.204381 8.269104) (xy 386.28434 8.30008) (xy 386.366816 8.323547)
			(xy 386.451106 8.339303) (xy 386.536489 8.347215) (xy 386.622239 8.347215) (xy 386.707622 8.339303)
			(xy 386.791912 8.323547) (xy 386.874388 8.30008) (xy 386.954347 8.269104) (xy 386.97502 8.25881)
			(xy 390.508744 8.25881) (xy 390.508744 9.12241) (xy 390.509248 9.151964) (xy 390.517297 9.21052)
			(xy 390.533243 9.267435) (xy 390.556792 9.321649) (xy 390.587503 9.372152) (xy 390.624805 9.418002)
			(xy 390.668002 9.458345) (xy 390.716291 9.492431) (xy 390.768771 9.519624) (xy 390.824466 9.539418)
			(xy 390.882337 9.551444) (xy 390.941306 9.555478) (xy 391.000275 9.551444) (xy 391.058146 9.539418)
			(xy 391.113841 9.519624) (xy 391.166321 9.492431) (xy 391.21461 9.458345) (xy 391.257807 9.418002)
			(xy 391.295109 9.372152) (xy 391.32582 9.321649) (xy 391.349369 9.267435) (xy 391.365315 9.21052)
			(xy 391.373364 9.151964) (xy 391.373868 9.12241) (xy 391.373868 8.25881) (xy 391.373364 8.229256)
			(xy 391.365315 8.1707) (xy 391.349369 8.113785) (xy 391.32582 8.059571) (xy 391.295109 8.009068)
			(xy 391.257807 7.963218) (xy 391.21461 7.922875) (xy 391.166321 7.888789) (xy 391.113841 7.861596)
			(xy 391.058146 7.841802) (xy 391.000275 7.829776) (xy 390.941306 7.825743) (xy 390.882337 7.829776)
			(xy 390.824466 7.841802) (xy 390.768771 7.861596) (xy 390.716291 7.888789) (xy 390.668002 7.922875)
			(xy 390.624805 7.963218) (xy 390.587503 8.009068) (xy 390.556792 8.059571) (xy 390.533243 8.113785)
			(xy 390.517297 8.1707) (xy 390.509248 8.229256) (xy 390.508744 8.25881) (xy 386.97502 8.25881) (xy 387.031107 8.230882)
			(xy 387.104013 8.185741) (xy 387.172442 8.134065) (xy 387.235812 8.076296) (xy 387.293581 8.012926)
			(xy 387.345257 7.944497) (xy 387.390398 7.871591) (xy 387.42862 7.794831) (xy 387.459596 7.714872)
			(xy 387.483063 7.632396) (xy 387.498819 7.548106) (xy 387.506731 7.462723) (xy 387.507226 7.419848)
			(xy 387.506731 7.376973) (xy 392.001997 7.376973) (xy 392.001997 7.462723) (xy 392.009909 7.548106)
			(xy 392.025665 7.632396) (xy 392.049132 7.714872) (xy 392.080108 7.794831) (xy 392.11833 7.871591)
			(xy 392.163471 7.944497) (xy 392.215147 8.012926) (xy 392.272916 8.076296) (xy 392.336286 8.134065)
			(xy 392.404715 8.185741) (xy 392.477621 8.230882) (xy 392.554381 8.269104) (xy 392.63434 8.30008)
			(xy 392.716816 8.323547) (xy 392.801106 8.339303) (xy 392.886489 8.347215) (xy 392.972239 8.347215)
			(xy 393.057622 8.339303) (xy 393.141912 8.323547) (xy 393.224388 8.30008) (xy 393.304347 8.269104)
			(xy 393.381107 8.230882) (xy 393.454013 8.185741) (xy 393.522442 8.134065) (xy 393.585812 8.076296)
			(xy 393.643581 8.012926) (xy 393.695257 7.944497) (xy 393.740398 7.871591) (xy 393.77862 7.794831)
			(xy 393.809596 7.714872) (xy 393.833063 7.632396) (xy 393.848819 7.548106) (xy 393.856731 7.462723)
			(xy 393.857226 7.419848) (xy 393.856731 7.376973) (xy 436.390783 7.376973) (xy 436.390783 7.462723)
			(xy 436.398695 7.548106) (xy 436.414451 7.632396) (xy 436.437918 7.714872) (xy 436.468894 7.794831)
			(xy 436.507116 7.871591) (xy 436.552257 7.944497) (xy 436.603933 8.012926) (xy 436.661702 8.076296)
			(xy 436.725072 8.134065) (xy 436.793501 8.185741) (xy 436.866407 8.230882) (xy 436.943167 8.269104)
			(xy 437.023126 8.30008) (xy 437.105602 8.323547) (xy 437.189892 8.339303) (xy 437.275275 8.347215)
			(xy 437.361025 8.347215) (xy 437.446408 8.339303) (xy 437.530698 8.323547) (xy 437.613174 8.30008)
			(xy 437.693133 8.269104) (xy 437.713806 8.25881) (xy 438.87644 8.25881) (xy 438.87644 9.12241) (xy 438.876944 9.151946)
			(xy 438.884988 9.210468) (xy 438.900925 9.26735) (xy 438.92446 9.321532) (xy 438.955153 9.372005)
			(xy 438.992433 9.417828) (xy 439.035605 9.458148) (xy 439.083865 9.492214) (xy 439.136315 9.519391)
			(xy 439.191976 9.539173) (xy 439.249813 9.551192) (xy 439.308748 9.555223) (xy 439.367683 9.551192)
			(xy 439.42552 9.539173) (xy 439.481181 9.519391) (xy 439.533631 9.492214) (xy 439.581891 9.458148)
			(xy 439.625063 9.417828) (xy 439.662343 9.372005) (xy 439.693036 9.321532) (xy 439.716571 9.26735)
			(xy 439.732508 9.210468) (xy 439.740552 9.151946) (xy 439.741056 9.12241) (xy 439.741056 8.25881)
			(xy 439.740552 8.229274) (xy 439.732508 8.170752) (xy 439.716571 8.11387) (xy 439.693036 8.059688)
			(xy 439.662343 8.009215) (xy 439.625063 7.963392) (xy 439.581891 7.923072) (xy 439.533631 7.889006)
			(xy 439.481181 7.861829) (xy 439.42552 7.842047) (xy 439.367683 7.830028) (xy 439.308748 7.825997)
			(xy 439.249813 7.830028) (xy 439.191976 7.842047) (xy 439.136315 7.861829) (xy 439.083865 7.889006)
			(xy 439.035605 7.923072) (xy 438.992433 7.963392) (xy 438.955153 8.009215) (xy 438.92446 8.059688)
			(xy 438.900925 8.11387) (xy 438.884988 8.170752) (xy 438.876944 8.229274) (xy 438.87644 8.25881)
			(xy 437.713806 8.25881) (xy 437.769893 8.230882) (xy 437.842799 8.185741) (xy 437.911228 8.134065)
			(xy 437.974598 8.076296) (xy 438.032367 8.012926) (xy 438.084043 7.944497) (xy 438.129184 7.871591)
			(xy 438.167406 7.794831) (xy 438.198382 7.714872) (xy 438.221849 7.632396) (xy 438.237605 7.548106)
			(xy 438.245517 7.462723) (xy 438.246012 7.419848) (xy 438.245517 7.376973) (xy 442.740783 7.376973)
			(xy 442.740783 7.462723) (xy 442.748695 7.548106) (xy 442.764451 7.632396) (xy 442.787918 7.714872)
			(xy 442.818894 7.794831) (xy 442.857116 7.871591) (xy 442.902257 7.944497) (xy 442.953933 8.012926)
			(xy 443.011702 8.076296) (xy 443.075072 8.134065) (xy 443.143501 8.185741) (xy 443.216407 8.230882)
			(xy 443.293167 8.269104) (xy 443.373126 8.30008) (xy 443.455602 8.323547) (xy 443.539892 8.339303)
			(xy 443.625275 8.347215) (xy 443.711025 8.347215) (xy 443.796408 8.339303) (xy 443.880698 8.323547)
			(xy 443.963174 8.30008) (xy 444.043133 8.269104) (xy 444.119893 8.230882) (xy 444.192799 8.185741)
			(xy 444.261228 8.134065) (xy 444.324598 8.076296) (xy 444.382367 8.012926) (xy 444.434043 7.944497)
			(xy 444.479184 7.871591) (xy 444.517406 7.794831) (xy 444.548382 7.714872) (xy 444.571849 7.632396)
			(xy 444.587605 7.548106) (xy 444.595517 7.462723) (xy 444.596012 7.419848) (xy 444.595517 7.376973)
			(xy 444.587605 7.29159) (xy 444.571849 7.2073) (xy 444.548382 7.124824) (xy 444.517406 7.044865)
			(xy 444.479184 6.968105) (xy 444.434043 6.895199) (xy 444.382367 6.82677) (xy 444.324598 6.7634)
			(xy 444.261228 6.705631) (xy 444.192799 6.653955) (xy 444.119893 6.608814) (xy 444.043133 6.570592)
			(xy 443.963174 6.539616) (xy 443.880698 6.516149) (xy 443.796408 6.500393) (xy 443.711025 6.492481)
			(xy 443.625275 6.492481) (xy 443.539892 6.500393) (xy 443.455602 6.516149) (xy 443.373126 6.539616)
			(xy 443.293167 6.570592) (xy 443.216407 6.608814) (xy 443.143501 6.653955) (xy 443.075072 6.705631)
			(xy 443.011702 6.7634) (xy 442.953933 6.82677) (xy 442.902257 6.895199) (xy 442.857116 6.968105)
			(xy 442.818894 7.044865) (xy 442.787918 7.124824) (xy 442.764451 7.2073) (xy 442.748695 7.29159)
			(xy 442.740783 7.376973) (xy 438.245517 7.376973) (xy 438.237605 7.29159) (xy 438.221849 7.2073)
			(xy 438.198382 7.124824) (xy 438.167406 7.044865) (xy 438.129184 6.968105) (xy 438.084043 6.895199)
			(xy 438.032367 6.82677) (xy 437.974598 6.7634) (xy 437.911228 6.705631) (xy 437.842799 6.653955)
			(xy 437.769893 6.608814) (xy 437.693133 6.570592) (xy 437.613174 6.539616) (xy 437.530698 6.516149)
			(xy 437.446408 6.500393) (xy 437.361025 6.492481) (xy 437.275275 6.492481) (xy 437.189892 6.500393)
			(xy 437.105602 6.516149) (xy 437.023126 6.539616) (xy 436.943167 6.570592) (xy 436.866407 6.608814)
			(xy 436.793501 6.653955) (xy 436.725072 6.705631) (xy 436.661702 6.7634) (xy 436.603933 6.82677)
			(xy 436.552257 6.895199) (xy 436.507116 6.968105) (xy 436.468894 7.044865) (xy 436.437918 7.124824)
			(xy 436.414451 7.2073) (xy 436.398695 7.29159) (xy 436.390783 7.376973) (xy 393.856731 7.376973)
			(xy 393.848819 7.29159) (xy 393.833063 7.2073) (xy 393.809596 7.124824) (xy 393.77862 7.044865) (xy 393.740398 6.968105)
			(xy 393.695257 6.895199) (xy 393.643581 6.82677) (xy 393.585812 6.7634) (xy 393.522442 6.705631)
			(xy 393.454013 6.653955) (xy 393.381107 6.608814) (xy 393.304347 6.570592) (xy 393.224388 6.539616)
			(xy 393.141912 6.516149) (xy 393.057622 6.500393) (xy 392.972239 6.492481) (xy 392.886489 6.492481)
			(xy 392.801106 6.500393) (xy 392.716816 6.516149) (xy 392.63434 6.539616) (xy 392.554381 6.570592)
			(xy 392.477621 6.608814) (xy 392.404715 6.653955) (xy 392.336286 6.705631) (xy 392.272916 6.7634)
			(xy 392.215147 6.82677) (xy 392.163471 6.895199) (xy 392.11833 6.968105) (xy 392.080108 7.044865)
			(xy 392.049132 7.124824) (xy 392.025665 7.2073) (xy 392.009909 7.29159) (xy 392.001997 7.376973)
			(xy 387.506731 7.376973) (xy 387.498819 7.29159) (xy 387.483063 7.2073) (xy 387.459596 7.124824)
			(xy 387.42862 7.044865) (xy 387.390398 6.968105) (xy 387.345257 6.895199) (xy 387.293581 6.82677)
			(xy 387.235812 6.7634) (xy 387.172442 6.705631) (xy 387.104013 6.653955) (xy 387.031107 6.608814)
			(xy 386.954347 6.570592) (xy 386.874388 6.539616) (xy 386.791912 6.516149) (xy 386.707622 6.500393)
			(xy 386.622239 6.492481) (xy 386.536489 6.492481) (xy 386.451106 6.500393) (xy 386.366816 6.516149)
			(xy 386.28434 6.539616) (xy 386.204381 6.570592) (xy 386.127621 6.608814) (xy 386.054715 6.653955)
			(xy 385.986286 6.705631) (xy 385.922916 6.7634) (xy 385.865147 6.82677) (xy 385.813471 6.895199)
			(xy 385.76833 6.968105) (xy 385.730108 7.044865) (xy 385.699132 7.124824) (xy 385.675665 7.2073)
			(xy 385.659909 7.29159) (xy 385.651997 7.376973) (xy 365.24438 7.376973) (xy 365.24438 7.191756)
			(xy 365.243876 7.16222) (xy 365.235832 7.103698) (xy 365.219895 7.046816) (xy 365.19636 6.992634)
			(xy 365.165667 6.942161) (xy 365.128387 6.896338) (xy 365.085215 6.856018) (xy 365.036955 6.821952)
			(xy 364.984505 6.794775) (xy 364.928844 6.774993) (xy 364.871007 6.762974) (xy 364.812072 6.758943)
			(xy 364.753137 6.762974) (xy 364.6953 6.774993) (xy 364.639639 6.794775) (xy 364.587189 6.821952)
			(xy 364.538929 6.856018) (xy 364.495757 6.896338) (xy 364.458477 6.942161) (xy 364.427784 6.992634)
			(xy 364.404249 7.046816) (xy 364.388312 7.103698) (xy 364.380268 7.16222) (xy 364.379764 7.191756)
			(xy 363.21713 7.191756) (xy 363.273217 7.163828) (xy 363.346123 7.118687) (xy 363.414552 7.067011)
			(xy 363.477922 7.009242) (xy 363.535691 6.945872) (xy 363.587367 6.877443) (xy 363.632508 6.804537)
			(xy 363.67073 6.727777) (xy 363.701706 6.647818) (xy 363.725173 6.565342) (xy 363.740929 6.481052)
			(xy 363.748841 6.395669) (xy 363.749336 6.352794) (xy 363.748841 6.309919) (xy 368.244107 6.309919)
			(xy 368.244107 6.395669) (xy 368.252019 6.481052) (xy 368.267775 6.565342) (xy 368.291242 6.647818)
			(xy 368.322218 6.727777) (xy 368.36044 6.804537) (xy 368.405581 6.877443) (xy 368.457257 6.945872)
			(xy 368.515026 7.009242) (xy 368.578396 7.067011) (xy 368.646825 7.118687) (xy 368.719731 7.163828)
			(xy 368.796491 7.20205) (xy 368.87645 7.233026) (xy 368.958926 7.256493) (xy 369.043216 7.272249)
			(xy 369.128599 7.280161) (xy 369.214349 7.280161) (xy 369.299732 7.272249) (xy 369.384022 7.256493)
			(xy 369.466498 7.233026) (xy 369.546457 7.20205) (xy 369.623217 7.163828) (xy 369.696123 7.118687)
			(xy 369.764552 7.067011) (xy 369.827922 7.009242) (xy 369.885691 6.945872) (xy 369.937367 6.877443)
			(xy 369.982508 6.804537) (xy 370.02073 6.727777) (xy 370.051706 6.647818) (xy 370.075173 6.565342)
			(xy 370.090929 6.481052) (xy 370.098841 6.395669) (xy 370.099336 6.352794) (xy 370.098841 6.309919)
			(xy 370.090929 6.224536) (xy 370.075173 6.140246) (xy 370.051706 6.05777) (xy 370.02073 5.977811)
			(xy 369.982508 5.901051) (xy 369.937367 5.828145) (xy 369.885691 5.759716) (xy 369.827922 5.696346)
			(xy 369.764552 5.638577) (xy 369.696123 5.586901) (xy 369.623217 5.54176) (xy 369.546457 5.503538)
			(xy 369.466498 5.472562) (xy 369.384022 5.449095) (xy 369.299732 5.433339) (xy 369.214349 5.425427)
			(xy 369.128599 5.425427) (xy 369.043216 5.433339) (xy 368.958926 5.449095) (xy 368.87645 5.472562)
			(xy 368.796491 5.503538) (xy 368.719731 5.54176) (xy 368.646825 5.586901) (xy 368.578396 5.638577)
			(xy 368.515026 5.696346) (xy 368.457257 5.759716) (xy 368.405581 5.828145) (xy 368.36044 5.901051)
			(xy 368.322218 5.977811) (xy 368.291242 6.05777) (xy 368.267775 6.140246) (xy 368.252019 6.224536)
			(xy 368.244107 6.309919) (xy 363.748841 6.309919) (xy 363.740929 6.224536) (xy 363.725173 6.140246)
			(xy 363.701706 6.05777) (xy 363.67073 5.977811) (xy 363.632508 5.901051) (xy 363.587367 5.828145)
			(xy 363.535691 5.759716) (xy 363.477922 5.696346) (xy 363.414552 5.638577) (xy 363.346123 5.586901)
			(xy 363.273217 5.54176) (xy 363.196457 5.503538) (xy 363.116498 5.472562) (xy 363.034022 5.449095)
			(xy 362.949732 5.433339) (xy 362.864349 5.425427) (xy 362.778599 5.425427) (xy 362.693216 5.433339)
			(xy 362.608926 5.449095) (xy 362.52645 5.472562) (xy 362.446491 5.503538) (xy 362.369731 5.54176)
			(xy 362.296825 5.586901) (xy 362.228396 5.638577) (xy 362.165026 5.696346) (xy 362.107257 5.759716)
			(xy 362.055581 5.828145) (xy 362.01044 5.901051) (xy 361.972218 5.977811) (xy 361.941242 6.05777)
			(xy 361.917775 6.140246) (xy 361.902019 6.224536) (xy 361.894107 6.309919) (xy 319.360055 6.309919)
			(xy 319.352143 6.224536) (xy 319.336387 6.140246) (xy 319.31292 6.05777) (xy 319.281944 5.977811)
			(xy 319.243722 5.901051) (xy 319.198581 5.828145) (xy 319.146905 5.759716) (xy 319.089136 5.696346)
			(xy 319.025766 5.638577) (xy 318.957337 5.586901) (xy 318.884431 5.54176) (xy 318.807671 5.503538)
			(xy 318.727712 5.472562) (xy 318.645236 5.449095) (xy 318.560946 5.433339) (xy 318.475563 5.425427)
			(xy 318.389813 5.425427) (xy 318.30443 5.433339) (xy 318.22014 5.449095) (xy 318.137664 5.472562)
			(xy 318.057705 5.503538) (xy 317.980945 5.54176) (xy 317.908039 5.586901) (xy 317.83961 5.638577)
			(xy 317.77624 5.696346) (xy 317.718471 5.759716) (xy 317.666795 5.828145) (xy 317.621654 5.901051)
			(xy 317.583432 5.977811) (xy 317.552456 6.05777) (xy 317.528989 6.140246) (xy 317.513233 6.224536)
			(xy 317.505321 6.309919) (xy 313.010055 6.309919) (xy 313.002143 6.224536) (xy 312.986387 6.140246)
			(xy 312.96292 6.05777) (xy 312.931944 5.977811) (xy 312.893722 5.901051) (xy 312.848581 5.828145)
			(xy 312.796905 5.759716) (xy 312.739136 5.696346) (xy 312.675766 5.638577) (xy 312.607337 5.586901)
			(xy 312.534431 5.54176) (xy 312.457671 5.503538) (xy 312.377712 5.472562) (xy 312.295236 5.449095)
			(xy 312.210946 5.433339) (xy 312.125563 5.425427) (xy 312.039813 5.425427) (xy 311.95443 5.433339)
			(xy 311.87014 5.449095) (xy 311.787664 5.472562) (xy 311.707705 5.503538) (xy 311.630945 5.54176)
			(xy 311.558039 5.586901) (xy 311.48961 5.638577) (xy 311.42624 5.696346) (xy 311.368471 5.759716)
			(xy 311.316795 5.828145) (xy 311.271654 5.901051) (xy 311.233432 5.977811) (xy 311.202456 6.05777)
			(xy 311.178989 6.140246) (xy 311.163233 6.224536) (xy 311.155321 6.309919) (xy 304.348655 6.309919)
			(xy 304.340743 6.224536) (xy 304.324987 6.140246) (xy 304.30152 6.05777) (xy 304.270544 5.977811)
			(xy 304.232322 5.901051) (xy 304.187181 5.828145) (xy 304.135505 5.759716) (xy 304.077736 5.696346)
			(xy 304.014366 5.638577) (xy 303.945937 5.586901) (xy 303.873031 5.54176) (xy 303.796271 5.503538)
			(xy 303.716312 5.472562) (xy 303.633836 5.449095) (xy 303.549546 5.433339) (xy 303.464163 5.425427)
			(xy 303.378413 5.425427) (xy 303.29303 5.433339) (xy 303.20874 5.449095) (xy 303.126264 5.472562)
			(xy 303.046305 5.503538) (xy 302.969545 5.54176) (xy 302.896639 5.586901) (xy 302.82821 5.638577)
			(xy 302.76484 5.696346) (xy 302.707071 5.759716) (xy 302.655395 5.828145) (xy 302.610254 5.901051)
			(xy 302.572032 5.977811) (xy 302.541056 6.05777) (xy 302.517589 6.140246) (xy 302.501833 6.224536)
			(xy 302.493921 6.309919) (xy 297.998655 6.309919) (xy 297.990743 6.224536) (xy 297.974987 6.140246)
			(xy 297.95152 6.05777) (xy 297.920544 5.977811) (xy 297.882322 5.901051) (xy 297.837181 5.828145)
			(xy 297.785505 5.759716) (xy 297.727736 5.696346) (xy 297.664366 5.638577) (xy 297.595937 5.586901)
			(xy 297.523031 5.54176) (xy 297.446271 5.503538) (xy 297.366312 5.472562) (xy 297.283836 5.449095)
			(xy 297.199546 5.433339) (xy 297.114163 5.425427) (xy 297.028413 5.425427) (xy 296.94303 5.433339)
			(xy 296.85874 5.449095) (xy 296.776264 5.472562) (xy 296.696305 5.503538) (xy 296.619545 5.54176)
			(xy 296.546639 5.586901) (xy 296.47821 5.638577) (xy 296.41484 5.696346) (xy 296.357071 5.759716)
			(xy 296.305395 5.828145) (xy 296.260254 5.901051) (xy 296.222032 5.977811) (xy 296.191056 6.05777)
			(xy 296.167589 6.140246) (xy 296.151833 6.224536) (xy 296.143921 6.309919) (xy 216.865975 6.309919)
			(xy 216.858063 6.224536) (xy 216.842307 6.140246) (xy 216.81884 6.05777) (xy 216.787864 5.977811)
			(xy 216.749642 5.901051) (xy 216.704501 5.828145) (xy 216.652825 5.759716) (xy 216.595056 5.696346)
			(xy 216.531686 5.638577) (xy 216.463257 5.586901) (xy 216.390351 5.54176) (xy 216.313591 5.503538)
			(xy 216.233632 5.472562) (xy 216.151156 5.449095) (xy 216.066866 5.433339) (xy 215.981483 5.425427)
			(xy 215.895733 5.425427) (xy 215.81035 5.433339) (xy 215.72606 5.449095) (xy 215.643584 5.472562)
			(xy 215.563625 5.503538) (xy 215.486865 5.54176) (xy 215.413959 5.586901) (xy 215.34553 5.638577)
			(xy 215.28216 5.696346) (xy 215.224391 5.759716) (xy 215.172715 5.828145) (xy 215.127574 5.901051)
			(xy 215.089352 5.977811) (xy 215.058376 6.05777) (xy 215.034909 6.140246) (xy 215.019153 6.224536)
			(xy 215.011241 6.309919) (xy 210.515975 6.309919) (xy 210.508063 6.224536) (xy 210.492307 6.140246)
			(xy 210.46884 6.05777) (xy 210.437864 5.977811) (xy 210.399642 5.901051) (xy 210.354501 5.828145)
			(xy 210.302825 5.759716) (xy 210.245056 5.696346) (xy 210.181686 5.638577) (xy 210.113257 5.586901)
			(xy 210.040351 5.54176) (xy 209.963591 5.503538) (xy 209.883632 5.472562) (xy 209.801156 5.449095)
			(xy 209.716866 5.433339) (xy 209.631483 5.425427) (xy 209.545733 5.425427) (xy 209.46035 5.433339)
			(xy 209.37606 5.449095) (xy 209.293584 5.472562) (xy 209.213625 5.503538) (xy 209.136865 5.54176)
			(xy 209.063959 5.586901) (xy 208.99553 5.638577) (xy 208.93216 5.696346) (xy 208.874391 5.759716)
			(xy 208.822715 5.828145) (xy 208.777574 5.901051) (xy 208.739352 5.977811) (xy 208.708376 6.05777)
			(xy 208.684909 6.140246) (xy 208.669153 6.224536) (xy 208.661241 6.309919) (xy 184.818528 6.309919)
			(xy 184.818528 5.632196) (xy 184.818024 5.60266) (xy 184.80998 5.544138) (xy 184.794043 5.487256)
			(xy 184.770508 5.433074) (xy 184.739815 5.382601) (xy 184.702535 5.336778) (xy 184.659363 5.296458)
			(xy 184.611103 5.262392) (xy 184.558653 5.235215) (xy 184.502992 5.215433) (xy 184.445155 5.203414)
			(xy 184.38622 5.199383) (xy 184.327285 5.203414) (xy 184.269448 5.215433) (xy 184.213787 5.235215)
			(xy 184.161337 5.262392) (xy 184.113077 5.296458) (xy 184.069905 5.336778) (xy 184.032625 5.382601)
			(xy 184.001932 5.433074) (xy 183.978397 5.487256) (xy 183.96246 5.544138) (xy 183.954416 5.60266)
			(xy 183.953912 5.632196) (xy 182.791278 5.632196) (xy 182.847365 5.604268) (xy 182.920271 5.559127)
			(xy 182.9887 5.507451) (xy 183.05207 5.449682) (xy 183.109839 5.386312) (xy 183.161515 5.317883)
			(xy 183.206656 5.244977) (xy 183.244878 5.168217) (xy 183.275854 5.088258) (xy 183.299321 5.005782)
			(xy 183.315077 4.921492) (xy 183.322989 4.836109) (xy 183.323484 4.793234) (xy 183.322989 4.750359)
			(xy 187.818255 4.750359) (xy 187.818255 4.836109) (xy 187.826167 4.921492) (xy 187.841923 5.005782)
			(xy 187.86539 5.088258) (xy 187.896366 5.168217) (xy 187.934588 5.244977) (xy 187.979729 5.317883)
			(xy 188.031405 5.386312) (xy 188.089174 5.449682) (xy 188.152544 5.507451) (xy 188.220973 5.559127)
			(xy 188.293879 5.604268) (xy 188.370639 5.64249) (xy 188.450598 5.673466) (xy 188.533074 5.696933)
			(xy 188.617364 5.712689) (xy 188.702747 5.720601) (xy 188.788497 5.720601) (xy 188.87388 5.712689)
			(xy 188.95817 5.696933) (xy 189.040646 5.673466) (xy 189.120605 5.64249) (xy 189.197365 5.604268)
			(xy 189.270271 5.559127) (xy 189.3387 5.507451) (xy 189.40207 5.449682) (xy 189.459839 5.386312)
			(xy 189.511515 5.317883) (xy 189.556656 5.244977) (xy 189.594878 5.168217) (xy 189.625854 5.088258)
			(xy 189.649321 5.005782) (xy 189.665077 4.921492) (xy 189.672989 4.836109) (xy 189.673484 4.793234)
			(xy 189.672989 4.750359) (xy 189.665077 4.664976) (xy 189.649321 4.580686) (xy 189.625854 4.49821)
			(xy 189.594878 4.418251) (xy 189.556656 4.341491) (xy 189.511515 4.268585) (xy 189.459839 4.200156)
			(xy 189.40207 4.136786) (xy 189.3387 4.079017) (xy 189.270271 4.027341) (xy 189.197365 3.9822) (xy 189.120605 3.943978)
			(xy 189.040646 3.913002) (xy 188.95817 3.889535) (xy 188.87388 3.873779) (xy 188.788497 3.865867)
			(xy 188.702747 3.865867) (xy 188.617364 3.873779) (xy 188.533074 3.889535) (xy 188.450598 3.913002)
			(xy 188.370639 3.943978) (xy 188.293879 3.9822) (xy 188.220973 4.027341) (xy 188.152544 4.079017)
			(xy 188.089174 4.136786) (xy 188.031405 4.200156) (xy 187.979729 4.268585) (xy 187.934588 4.341491)
			(xy 187.896366 4.418251) (xy 187.86539 4.49821) (xy 187.841923 4.580686) (xy 187.826167 4.664976)
			(xy 187.818255 4.750359) (xy 183.322989 4.750359) (xy 183.315077 4.664976) (xy 183.299321 4.580686)
			(xy 183.275854 4.49821) (xy 183.244878 4.418251) (xy 183.206656 4.341491) (xy 183.161515 4.268585)
			(xy 183.109839 4.200156) (xy 183.05207 4.136786) (xy 182.9887 4.079017) (xy 182.920271 4.027341)
			(xy 182.847365 3.9822) (xy 182.770605 3.943978) (xy 182.690646 3.913002) (xy 182.60817 3.889535)
			(xy 182.52388 3.873779) (xy 182.438497 3.865867) (xy 182.352747 3.865867) (xy 182.267364 3.873779)
			(xy 182.183074 3.889535) (xy 182.100598 3.913002) (xy 182.020639 3.943978) (xy 181.943879 3.9822)
			(xy 181.870973 4.027341) (xy 181.802544 4.079017) (xy 181.739174 4.136786) (xy 181.681405 4.200156)
			(xy 181.629729 4.268585) (xy 181.584588 4.341491) (xy 181.546366 4.418251) (xy 181.51539 4.49821)
			(xy 181.491923 4.580686) (xy 181.476167 4.664976) (xy 181.468255 4.750359) (xy 102.190309 4.750359)
			(xy 102.182397 4.664976) (xy 102.166641 4.580686) (xy 102.143174 4.49821) (xy 102.112198 4.418251)
			(xy 102.073976 4.341491) (xy 102.028835 4.268585) (xy 101.977159 4.200156) (xy 101.91939 4.136786)
			(xy 101.85602 4.079017) (xy 101.787591 4.027341) (xy 101.714685 3.9822) (xy 101.637925 3.943978)
			(xy 101.557966 3.913002) (xy 101.47549 3.889535) (xy 101.3912 3.873779) (xy 101.305817 3.865867)
			(xy 101.220067 3.865867) (xy 101.134684 3.873779) (xy 101.050394 3.889535) (xy 100.967918 3.913002)
			(xy 100.887959 3.943978) (xy 100.811199 3.9822) (xy 100.738293 4.027341) (xy 100.669864 4.079017)
			(xy 100.606494 4.136786) (xy 100.548725 4.200156) (xy 100.497049 4.268585) (xy 100.451908 4.341491)
			(xy 100.413686 4.418251) (xy 100.38271 4.49821) (xy 100.359243 4.580686) (xy 100.343487 4.664976)
			(xy 100.335575 4.750359) (xy 95.840309 4.750359) (xy 95.832397 4.664976) (xy 95.816641 4.580686)
			(xy 95.793174 4.49821) (xy 95.762198 4.418251) (xy 95.723976 4.341491) (xy 95.678835 4.268585) (xy 95.627159 4.200156)
			(xy 95.56939 4.136786) (xy 95.50602 4.079017) (xy 95.437591 4.027341) (xy 95.364685 3.9822) (xy 95.287925 3.943978)
			(xy 95.207966 3.913002) (xy 95.12549 3.889535) (xy 95.0412 3.873779) (xy 94.955817 3.865867) (xy 94.870067 3.865867)
			(xy 94.784684 3.873779) (xy 94.700394 3.889535) (xy 94.617918 3.913002) (xy 94.537959 3.943978) (xy 94.461199 3.9822)
			(xy 94.388293 4.027341) (xy 94.319864 4.079017) (xy 94.256494 4.136786) (xy 94.198725 4.200156) (xy 94.147049 4.268585)
			(xy 94.101908 4.341491) (xy 94.063686 4.418251) (xy 94.03271 4.49821) (xy 94.009243 4.580686) (xy 93.993487 4.664976)
			(xy 93.985575 4.750359) (xy 0.509016 4.750359) (xy 0.509016 -7.78002) (xy 0.509537 -7.835789) (xy 0.517873 -7.947015)
			(xy 0.534497 -8.057308) (xy 0.559316 -8.166049) (xy 0.592193 -8.272632) (xy 0.632942 -8.37646) (xy 0.681336 -8.476953)
			(xy 0.737105 -8.573548) (xy 0.799937 -8.665705) (xy 0.86948 -8.752909) (xy 0.945345 -8.834672) (xy 1.027108 -8.910538)
			(xy 1.114312 -8.980081) (xy 1.206469 -9.042912) (xy 1.303064 -9.098682) (xy 1.403556 -9.147076) (xy 1.507384 -9.187826)
			(xy 1.613967 -9.220703) (xy 1.722708 -9.245523) (xy 1.833001 -9.262147) (xy 1.944227 -9.270482) (xy 1.999996 -9.271)
			(xy 9.10209 -9.271) (xy 9.15786 -9.270479) (xy 9.269087 -9.262144) (xy 9.37938 -9.245521) (xy 9.488123 -9.220702)
			(xy 9.594707 -9.187826) (xy 9.698536 -9.147077) (xy 9.79903 -9.098683) (xy 9.895626 -9.042915) (xy 9.987784 -8.980083)
			(xy 10.07499 -8.910541) (xy 10.156754 -8.834676) (xy 10.232621 -8.752912) (xy 10.302165 -8.665708)
			(xy 10.364999 -8.573551) (xy 10.420769 -8.476956) (xy 10.469165 -8.376463) (xy 10.509916 -8.272635)
			(xy 10.542794 -8.166052) (xy 10.567616 -8.05731) (xy 10.584241 -7.947017) (xy 10.592578 -7.83579)
			(xy 10.59307 -7.78002) (xy 10.59307 0.40005) (xy 10.593555 0.470432) (xy 10.601447 0.610976) (xy 10.617208 0.750856)
			(xy 10.640787 0.889632) (xy 10.67211 1.026868) (xy 10.711079 1.162131) (xy 10.757571 1.294997) (xy 10.811439 1.425046)
			(xy 10.872515 1.551871) (xy 10.940606 1.675072) (xy 11.015497 1.794261) (xy 11.096954 1.909063) (xy 11.184719 2.019118)
			(xy 11.278518 2.124078) (xy 11.378053 2.223614) (xy 11.483014 2.317412) (xy 11.593068 2.405178) (xy 11.707871 2.486634)
			(xy 11.82706 2.561525) (xy 11.950261 2.629616) (xy 12.077085 2.690692) (xy 12.207135 2.74456) (xy 12.340001 2.791052)
			(xy 12.475264 2.83002) (xy 12.6125 2.861343) (xy 12.751276 2.884922) (xy 12.891156 2.900683) (xy 13.0317 2.908575)
			(xy 13.102082 2.909062) (xy 81.701894 2.909062) (xy 81.772277 2.908568) (xy 81.912821 2.900676) (xy 82.052702 2.884916)
			(xy 82.191479 2.861337) (xy 82.328715 2.830015) (xy 82.46398 2.791046) (xy 82.596846 2.744555) (xy 82.726897 2.690688)
			(xy 82.853723 2.629613) (xy 82.976925 2.561522) (xy 83.096116 2.486632) (xy 83.210919 2.405176) (xy 83.320975 2.317411)
			(xy 83.425937 2.223613) (xy 83.439191 2.210359) (xy 93.985575 2.210359) (xy 93.985575 2.296109) (xy 93.993487 2.381492)
			(xy 94.009243 2.465782) (xy 94.03271 2.548258) (xy 94.063686 2.628217) (xy 94.101908 2.704977) (xy 94.147049 2.777883)
			(xy 94.198725 2.846312) (xy 94.256494 2.909682) (xy 94.319864 2.967451) (xy 94.388293 3.019127) (xy 94.461199 3.064268)
			(xy 94.537959 3.10249) (xy 94.617918 3.133466) (xy 94.700394 3.156933) (xy 94.784684 3.172689) (xy 94.870067 3.180601)
			(xy 94.955817 3.180601) (xy 95.0412 3.172689) (xy 95.12549 3.156933) (xy 95.207966 3.133466) (xy 95.287925 3.10249)
			(xy 95.308598 3.092196) (xy 98.842576 3.092196) (xy 98.842576 3.955796) (xy 98.84308 3.985332) (xy 98.851124 4.043854)
			(xy 98.867061 4.100736) (xy 98.890596 4.154918) (xy 98.921289 4.205391) (xy 98.958569 4.251214) (xy 99.001741 4.291534)
			(xy 99.050001 4.3256) (xy 99.102451 4.352777) (xy 99.158112 4.372559) (xy 99.215949 4.384578) (xy 99.274884 4.388609)
			(xy 99.333819 4.384578) (xy 99.391656 4.372559) (xy 99.447317 4.352777) (xy 99.499767 4.3256) (xy 99.548027 4.291534)
			(xy 99.591199 4.251214) (xy 99.628479 4.205391) (xy 99.659172 4.154918) (xy 99.682707 4.100736) (xy 99.698644 4.043854)
			(xy 99.706688 3.985332) (xy 99.707192 3.955796) (xy 99.707192 3.092196) (xy 99.706688 3.06266) (xy 99.698644 3.004138)
			(xy 99.682707 2.947256) (xy 99.659172 2.893074) (xy 99.628479 2.842601) (xy 99.591199 2.796778) (xy 99.548027 2.756458)
			(xy 99.499767 2.722392) (xy 99.447317 2.695215) (xy 99.391656 2.675433) (xy 99.333819 2.663414) (xy 99.274884 2.659383)
			(xy 99.215949 2.663414) (xy 99.158112 2.675433) (xy 99.102451 2.695215) (xy 99.050001 2.722392) (xy 99.001741 2.756458)
			(xy 98.958569 2.796778) (xy 98.921289 2.842601) (xy 98.890596 2.893074) (xy 98.867061 2.947256) (xy 98.851124 3.004138)
			(xy 98.84308 3.06266) (xy 98.842576 3.092196) (xy 95.308598 3.092196) (xy 95.364685 3.064268) (xy 95.437591 3.019127)
			(xy 95.50602 2.967451) (xy 95.56939 2.909682) (xy 95.627159 2.846312) (xy 95.678835 2.777883) (xy 95.723976 2.704977)
			(xy 95.762198 2.628217) (xy 95.793174 2.548258) (xy 95.816641 2.465782) (xy 95.832397 2.381492) (xy 95.840309 2.296109)
			(xy 95.840804 2.253234) (xy 95.840309 2.210359) (xy 100.335575 2.210359) (xy 100.335575 2.296109)
			(xy 100.343487 2.381492) (xy 100.359243 2.465782) (xy 100.38271 2.548258) (xy 100.413686 2.628217)
			(xy 100.451908 2.704977) (xy 100.497049 2.777883) (xy 100.548725 2.846312) (xy 100.606494 2.909682)
			(xy 100.669864 2.967451) (xy 100.738293 3.019127) (xy 100.811199 3.064268) (xy 100.887959 3.10249)
			(xy 100.967918 3.133466) (xy 101.050394 3.156933) (xy 101.134684 3.172689) (xy 101.220067 3.180601)
			(xy 101.305817 3.180601) (xy 101.3912 3.172689) (xy 101.47549 3.156933) (xy 101.557966 3.133466)
			(xy 101.637925 3.10249) (xy 101.714685 3.064268) (xy 101.787591 3.019127) (xy 101.85602 2.967451)
			(xy 101.91939 2.909682) (xy 101.977159 2.846312) (xy 102.028835 2.777883) (xy 102.073976 2.704977)
			(xy 102.112198 2.628217) (xy 102.143174 2.548258) (xy 102.166641 2.465782) (xy 102.182397 2.381492)
			(xy 102.190309 2.296109) (xy 102.190804 2.253234) (xy 102.190309 2.210359) (xy 181.468255 2.210359)
			(xy 181.468255 2.296109) (xy 181.476167 2.381492) (xy 181.491923 2.465782) (xy 181.51539 2.548258)
			(xy 181.546366 2.628217) (xy 181.584588 2.704977) (xy 181.629729 2.777883) (xy 181.681405 2.846312)
			(xy 181.739174 2.909682) (xy 181.802544 2.967451) (xy 181.870973 3.019127) (xy 181.943879 3.064268)
			(xy 182.020639 3.10249) (xy 182.100598 3.133466) (xy 182.183074 3.156933) (xy 182.267364 3.172689)
			(xy 182.352747 3.180601) (xy 182.438497 3.180601) (xy 182.52388 3.172689) (xy 182.60817 3.156933)
			(xy 182.690646 3.133466) (xy 182.770605 3.10249) (xy 182.791278 3.092196) (xy 183.953912 3.092196)
			(xy 183.953912 3.955796) (xy 183.954416 3.985332) (xy 183.96246 4.043854) (xy 183.978397 4.100736)
			(xy 184.001932 4.154918) (xy 184.032625 4.205391) (xy 184.069905 4.251214) (xy 184.113077 4.291534)
			(xy 184.161337 4.3256) (xy 184.213787 4.352777) (xy 184.269448 4.372559) (xy 184.327285 4.384578)
			(xy 184.38622 4.388609) (xy 184.445155 4.384578) (xy 184.502992 4.372559) (xy 184.558653 4.352777)
			(xy 184.611103 4.3256) (xy 184.659363 4.291534) (xy 184.702535 4.251214) (xy 184.739815 4.205391)
			(xy 184.770508 4.154918) (xy 184.794043 4.100736) (xy 184.80998 4.043854) (xy 184.818024 3.985332)
			(xy 184.818528 3.955796) (xy 184.818528 3.769919) (xy 208.661241 3.769919) (xy 208.661241 3.855669)
			(xy 208.669153 3.941052) (xy 208.684909 4.025342) (xy 208.708376 4.107818) (xy 208.739352 4.187777)
			(xy 208.777574 4.264537) (xy 208.822715 4.337443) (xy 208.874391 4.405872) (xy 208.93216 4.469242)
			(xy 208.99553 4.527011) (xy 209.063959 4.578687) (xy 209.136865 4.623828) (xy 209.213625 4.66205)
			(xy 209.293584 4.693026) (xy 209.37606 4.716493) (xy 209.46035 4.732249) (xy 209.545733 4.740161)
			(xy 209.631483 4.740161) (xy 209.716866 4.732249) (xy 209.801156 4.716493) (xy 209.883632 4.693026)
			(xy 209.963591 4.66205) (xy 209.984264 4.651756) (xy 213.517988 4.651756) (xy 213.517988 5.515356)
			(xy 213.518492 5.54491) (xy 213.526541 5.603466) (xy 213.542487 5.660381) (xy 213.566036 5.714595)
			(xy 213.596747 5.765098) (xy 213.634049 5.810948) (xy 213.677246 5.851291) (xy 213.725535 5.885377)
			(xy 213.778015 5.91257) (xy 213.83371 5.932364) (xy 213.891581 5.94439) (xy 213.95055 5.948424) (xy 214.009519 5.94439)
			(xy 214.06739 5.932364) (xy 214.123085 5.91257) (xy 214.175565 5.885377) (xy 214.223854 5.851291)
			(xy 214.267051 5.810948) (xy 214.304353 5.765098) (xy 214.335064 5.714595) (xy 214.358613 5.660381)
			(xy 214.374559 5.603466) (xy 214.382608 5.54491) (xy 214.383112 5.515356) (xy 214.383112 4.651756)
			(xy 214.382608 4.622202) (xy 214.374559 4.563646) (xy 214.358613 4.506731) (xy 214.335064 4.452517)
			(xy 214.304353 4.402014) (xy 214.267051 4.356164) (xy 214.223854 4.315821) (xy 214.175565 4.281735)
			(xy 214.123085 4.254542) (xy 214.06739 4.234748) (xy 214.009519 4.222722) (xy 213.95055 4.218689)
			(xy 213.891581 4.222722) (xy 213.83371 4.234748) (xy 213.778015 4.254542) (xy 213.725535 4.281735)
			(xy 213.677246 4.315821) (xy 213.634049 4.356164) (xy 213.596747 4.402014) (xy 213.566036 4.452517)
			(xy 213.542487 4.506731) (xy 213.526541 4.563646) (xy 213.518492 4.622202) (xy 213.517988 4.651756)
			(xy 209.984264 4.651756) (xy 210.040351 4.623828) (xy 210.113257 4.578687) (xy 210.181686 4.527011)
			(xy 210.245056 4.469242) (xy 210.302825 4.405872) (xy 210.354501 4.337443) (xy 210.399642 4.264537)
			(xy 210.437864 4.187777) (xy 210.46884 4.107818) (xy 210.492307 4.025342) (xy 210.508063 3.941052)
			(xy 210.515975 3.855669) (xy 210.51647 3.812794) (xy 210.515975 3.769919) (xy 215.011241 3.769919)
			(xy 215.011241 3.855669) (xy 215.019153 3.941052) (xy 215.034909 4.025342) (xy 215.058376 4.107818)
			(xy 215.089352 4.187777) (xy 215.127574 4.264537) (xy 215.172715 4.337443) (xy 215.224391 4.405872)
			(xy 215.28216 4.469242) (xy 215.34553 4.527011) (xy 215.413959 4.578687) (xy 215.486865 4.623828)
			(xy 215.563625 4.66205) (xy 215.643584 4.693026) (xy 215.72606 4.716493) (xy 215.81035 4.732249)
			(xy 215.895733 4.740161) (xy 215.981483 4.740161) (xy 216.066866 4.732249) (xy 216.151156 4.716493)
			(xy 216.233632 4.693026) (xy 216.313591 4.66205) (xy 216.390351 4.623828) (xy 216.463257 4.578687)
			(xy 216.531686 4.527011) (xy 216.595056 4.469242) (xy 216.652825 4.405872) (xy 216.704501 4.337443)
			(xy 216.749642 4.264537) (xy 216.787864 4.187777) (xy 216.81884 4.107818) (xy 216.842307 4.025342)
			(xy 216.858063 3.941052) (xy 216.865975 3.855669) (xy 216.86647 3.812794) (xy 216.865975 3.769919)
			(xy 296.143921 3.769919) (xy 296.143921 3.855669) (xy 296.151833 3.941052) (xy 296.167589 4.025342)
			(xy 296.191056 4.107818) (xy 296.222032 4.187777) (xy 296.260254 4.264537) (xy 296.305395 4.337443)
			(xy 296.357071 4.405872) (xy 296.41484 4.469242) (xy 296.47821 4.527011) (xy 296.546639 4.578687)
			(xy 296.619545 4.623828) (xy 296.696305 4.66205) (xy 296.776264 4.693026) (xy 296.85874 4.716493)
			(xy 296.94303 4.732249) (xy 297.028413 4.740161) (xy 297.114163 4.740161) (xy 297.199546 4.732249)
			(xy 297.283836 4.716493) (xy 297.366312 4.693026) (xy 297.446271 4.66205) (xy 297.466944 4.651756)
			(xy 298.629324 4.651756) (xy 298.629324 5.515356) (xy 298.629828 5.54491) (xy 298.637877 5.603466)
			(xy 298.653823 5.660381) (xy 298.677372 5.714595) (xy 298.708083 5.765098) (xy 298.745385 5.810948)
			(xy 298.788582 5.851291) (xy 298.836871 5.885377) (xy 298.889351 5.91257) (xy 298.945046 5.932364)
			(xy 299.002917 5.94439) (xy 299.061886 5.948424) (xy 299.120855 5.94439) (xy 299.178726 5.932364)
			(xy 299.234421 5.91257) (xy 299.286901 5.885377) (xy 299.33519 5.851291) (xy 299.378387 5.810948)
			(xy 299.415689 5.765098) (xy 299.4464 5.714595) (xy 299.469949 5.660381) (xy 299.485895 5.603466)
			(xy 299.493944 5.54491) (xy 299.494448 5.515356) (xy 299.494448 4.651756) (xy 299.493944 4.622202)
			(xy 299.485895 4.563646) (xy 299.469949 4.506731) (xy 299.4464 4.452517) (xy 299.415689 4.402014)
			(xy 299.378387 4.356164) (xy 299.33519 4.315821) (xy 299.286901 4.281735) (xy 299.234421 4.254542)
			(xy 299.178726 4.234748) (xy 299.120855 4.222722) (xy 299.061886 4.218689) (xy 299.002917 4.222722)
			(xy 298.945046 4.234748) (xy 298.889351 4.254542) (xy 298.836871 4.281735) (xy 298.788582 4.315821)
			(xy 298.745385 4.356164) (xy 298.708083 4.402014) (xy 298.677372 4.452517) (xy 298.653823 4.506731)
			(xy 298.637877 4.563646) (xy 298.629828 4.622202) (xy 298.629324 4.651756) (xy 297.466944 4.651756)
			(xy 297.523031 4.623828) (xy 297.595937 4.578687) (xy 297.664366 4.527011) (xy 297.727736 4.469242)
			(xy 297.785505 4.405872) (xy 297.837181 4.337443) (xy 297.882322 4.264537) (xy 297.920544 4.187777)
			(xy 297.95152 4.107818) (xy 297.974987 4.025342) (xy 297.990743 3.941052) (xy 297.998655 3.855669)
			(xy 297.99915 3.812794) (xy 297.998655 3.769919) (xy 302.493921 3.769919) (xy 302.493921 3.855669)
			(xy 302.501833 3.941052) (xy 302.517589 4.025342) (xy 302.541056 4.107818) (xy 302.572032 4.187777)
			(xy 302.610254 4.264537) (xy 302.655395 4.337443) (xy 302.707071 4.405872) (xy 302.76484 4.469242)
			(xy 302.82821 4.527011) (xy 302.896639 4.578687) (xy 302.969545 4.623828) (xy 303.046305 4.66205)
			(xy 303.126264 4.693026) (xy 303.20874 4.716493) (xy 303.29303 4.732249) (xy 303.378413 4.740161)
			(xy 303.464163 4.740161) (xy 303.549546 4.732249) (xy 303.633836 4.716493) (xy 303.716312 4.693026)
			(xy 303.796271 4.66205) (xy 303.873031 4.623828) (xy 303.945937 4.578687) (xy 304.014366 4.527011)
			(xy 304.077736 4.469242) (xy 304.135505 4.405872) (xy 304.187181 4.337443) (xy 304.232322 4.264537)
			(xy 304.270544 4.187777) (xy 304.30152 4.107818) (xy 304.324987 4.025342) (xy 304.340743 3.941052)
			(xy 304.348655 3.855669) (xy 304.34915 3.812794) (xy 304.348655 3.769919) (xy 311.155321 3.769919)
			(xy 311.155321 3.855669) (xy 311.163233 3.941052) (xy 311.178989 4.025342) (xy 311.202456 4.107818)
			(xy 311.233432 4.187777) (xy 311.271654 4.264537) (xy 311.316795 4.337443) (xy 311.368471 4.405872)
			(xy 311.42624 4.469242) (xy 311.48961 4.527011) (xy 311.558039 4.578687) (xy 311.630945 4.623828)
			(xy 311.707705 4.66205) (xy 311.787664 4.693026) (xy 311.87014 4.716493) (xy 311.95443 4.732249)
			(xy 312.039813 4.740161) (xy 312.125563 4.740161) (xy 312.210946 4.732249) (xy 312.295236 4.716493)
			(xy 312.377712 4.693026) (xy 312.457671 4.66205) (xy 312.478344 4.651756) (xy 316.012068 4.651756)
			(xy 316.012068 5.515356) (xy 316.012572 5.54491) (xy 316.020621 5.603466) (xy 316.036567 5.660381)
			(xy 316.060116 5.714595) (xy 316.090827 5.765098) (xy 316.128129 5.810948) (xy 316.171326 5.851291)
			(xy 316.219615 5.885377) (xy 316.272095 5.91257) (xy 316.32779 5.932364) (xy 316.385661 5.94439)
			(xy 316.44463 5.948424) (xy 316.503599 5.94439) (xy 316.56147 5.932364) (xy 316.617165 5.91257) (xy 316.669645 5.885377)
			(xy 316.717934 5.851291) (xy 316.761131 5.810948) (xy 316.798433 5.765098) (xy 316.829144 5.714595)
			(xy 316.852693 5.660381) (xy 316.868639 5.603466) (xy 316.876688 5.54491) (xy 316.877192 5.515356)
			(xy 316.877192 4.651756) (xy 316.876688 4.622202) (xy 316.868639 4.563646) (xy 316.852693 4.506731)
			(xy 316.829144 4.452517) (xy 316.798433 4.402014) (xy 316.761131 4.356164) (xy 316.717934 4.315821)
			(xy 316.669645 4.281735) (xy 316.617165 4.254542) (xy 316.56147 4.234748) (xy 316.503599 4.222722)
			(xy 316.44463 4.218689) (xy 316.385661 4.222722) (xy 316.32779 4.234748) (xy 316.272095 4.254542)
			(xy 316.219615 4.281735) (xy 316.171326 4.315821) (xy 316.128129 4.356164) (xy 316.090827 4.402014)
			(xy 316.060116 4.452517) (xy 316.036567 4.506731) (xy 316.020621 4.563646) (xy 316.012572 4.622202)
			(xy 316.012068 4.651756) (xy 312.478344 4.651756) (xy 312.534431 4.623828) (xy 312.607337 4.578687)
			(xy 312.675766 4.527011) (xy 312.739136 4.469242) (xy 312.796905 4.405872) (xy 312.848581 4.337443)
			(xy 312.893722 4.264537) (xy 312.931944 4.187777) (xy 312.96292 4.107818) (xy 312.986387 4.025342)
			(xy 313.002143 3.941052) (xy 313.010055 3.855669) (xy 313.01055 3.812794) (xy 313.010055 3.769919)
			(xy 317.505321 3.769919) (xy 317.505321 3.855669) (xy 317.513233 3.941052) (xy 317.528989 4.025342)
			(xy 317.552456 4.107818) (xy 317.583432 4.187777) (xy 317.621654 4.264537) (xy 317.666795 4.337443)
			(xy 317.718471 4.405872) (xy 317.77624 4.469242) (xy 317.83961 4.527011) (xy 317.908039 4.578687)
			(xy 317.980945 4.623828) (xy 318.057705 4.66205) (xy 318.137664 4.693026) (xy 318.22014 4.716493)
			(xy 318.30443 4.732249) (xy 318.389813 4.740161) (xy 318.475563 4.740161) (xy 318.560946 4.732249)
			(xy 318.645236 4.716493) (xy 318.727712 4.693026) (xy 318.807671 4.66205) (xy 318.884431 4.623828)
			(xy 318.957337 4.578687) (xy 319.025766 4.527011) (xy 319.089136 4.469242) (xy 319.146905 4.405872)
			(xy 319.198581 4.337443) (xy 319.243722 4.264537) (xy 319.281944 4.187777) (xy 319.31292 4.107818)
			(xy 319.336387 4.025342) (xy 319.352143 3.941052) (xy 319.360055 3.855669) (xy 319.36055 3.812794)
			(xy 319.360055 3.769919) (xy 361.894107 3.769919) (xy 361.894107 3.855669) (xy 361.902019 3.941052)
			(xy 361.917775 4.025342) (xy 361.941242 4.107818) (xy 361.972218 4.187777) (xy 362.01044 4.264537)
			(xy 362.055581 4.337443) (xy 362.107257 4.405872) (xy 362.165026 4.469242) (xy 362.228396 4.527011)
			(xy 362.296825 4.578687) (xy 362.369731 4.623828) (xy 362.446491 4.66205) (xy 362.52645 4.693026)
			(xy 362.608926 4.716493) (xy 362.693216 4.732249) (xy 362.778599 4.740161) (xy 362.864349 4.740161)
			(xy 362.949732 4.732249) (xy 363.034022 4.716493) (xy 363.116498 4.693026) (xy 363.196457 4.66205)
			(xy 363.21713 4.651756) (xy 364.379764 4.651756) (xy 364.379764 5.515356) (xy 364.380268 5.544892)
			(xy 364.388312 5.603414) (xy 364.404249 5.660296) (xy 364.427784 5.714478) (xy 364.458477 5.764951)
			(xy 364.495757 5.810774) (xy 364.538929 5.851094) (xy 364.587189 5.88516) (xy 364.639639 5.912337)
			(xy 364.6953 5.932119) (xy 364.753137 5.944138) (xy 364.812072 5.948169) (xy 364.871007 5.944138)
			(xy 364.928844 5.932119) (xy 364.984505 5.912337) (xy 365.036955 5.88516) (xy 365.085215 5.851094)
			(xy 365.128387 5.810774) (xy 365.165667 5.764951) (xy 365.19636 5.714478) (xy 365.219895 5.660296)
			(xy 365.235832 5.603414) (xy 365.243876 5.544892) (xy 365.24438 5.515356) (xy 365.24438 4.836973)
			(xy 385.651997 4.836973) (xy 385.651997 4.922723) (xy 385.659909 5.008106) (xy 385.675665 5.092396)
			(xy 385.699132 5.174872) (xy 385.730108 5.254831) (xy 385.76833 5.331591) (xy 385.813471 5.404497)
			(xy 385.865147 5.472926) (xy 385.922916 5.536296) (xy 385.986286 5.594065) (xy 386.054715 5.645741)
			(xy 386.127621 5.690882) (xy 386.204381 5.729104) (xy 386.28434 5.76008) (xy 386.366816 5.783547)
			(xy 386.451106 5.799303) (xy 386.536489 5.807215) (xy 386.622239 5.807215) (xy 386.707622 5.799303)
			(xy 386.791912 5.783547) (xy 386.874388 5.76008) (xy 386.954347 5.729104) (xy 386.97502 5.71881)
			(xy 390.508744 5.71881) (xy 390.508744 6.58241) (xy 390.509248 6.611964) (xy 390.517297 6.67052)
			(xy 390.533243 6.727435) (xy 390.556792 6.781649) (xy 390.587503 6.832152) (xy 390.624805 6.878002)
			(xy 390.668002 6.918345) (xy 390.716291 6.952431) (xy 390.768771 6.979624) (xy 390.824466 6.999418)
			(xy 390.882337 7.011444) (xy 390.941306 7.015478) (xy 391.000275 7.011444) (xy 391.058146 6.999418)
			(xy 391.113841 6.979624) (xy 391.166321 6.952431) (xy 391.21461 6.918345) (xy 391.257807 6.878002)
			(xy 391.295109 6.832152) (xy 391.32582 6.781649) (xy 391.349369 6.727435) (xy 391.365315 6.67052)
			(xy 391.373364 6.611964) (xy 391.373868 6.58241) (xy 391.373868 5.71881) (xy 391.373364 5.689256)
			(xy 391.365315 5.6307) (xy 391.349369 5.573785) (xy 391.32582 5.519571) (xy 391.295109 5.469068)
			(xy 391.257807 5.423218) (xy 391.21461 5.382875) (xy 391.166321 5.348789) (xy 391.113841 5.321596)
			(xy 391.058146 5.301802) (xy 391.000275 5.289776) (xy 390.941306 5.285743) (xy 390.882337 5.289776)
			(xy 390.824466 5.301802) (xy 390.768771 5.321596) (xy 390.716291 5.348789) (xy 390.668002 5.382875)
			(xy 390.624805 5.423218) (xy 390.587503 5.469068) (xy 390.556792 5.519571) (xy 390.533243 5.573785)
			(xy 390.517297 5.6307) (xy 390.509248 5.689256) (xy 390.508744 5.71881) (xy 386.97502 5.71881) (xy 387.031107 5.690882)
			(xy 387.104013 5.645741) (xy 387.172442 5.594065) (xy 387.235812 5.536296) (xy 387.293581 5.472926)
			(xy 387.345257 5.404497) (xy 387.390398 5.331591) (xy 387.42862 5.254831) (xy 387.459596 5.174872)
			(xy 387.483063 5.092396) (xy 387.498819 5.008106) (xy 387.506731 4.922723) (xy 387.507226 4.879848)
			(xy 387.506731 4.836973) (xy 392.001997 4.836973) (xy 392.001997 4.922723) (xy 392.009909 5.008106)
			(xy 392.025665 5.092396) (xy 392.049132 5.174872) (xy 392.080108 5.254831) (xy 392.11833 5.331591)
			(xy 392.163471 5.404497) (xy 392.215147 5.472926) (xy 392.272916 5.536296) (xy 392.336286 5.594065)
			(xy 392.404715 5.645741) (xy 392.477621 5.690882) (xy 392.554381 5.729104) (xy 392.63434 5.76008)
			(xy 392.716816 5.783547) (xy 392.801106 5.799303) (xy 392.886489 5.807215) (xy 392.972239 5.807215)
			(xy 393.057622 5.799303) (xy 393.141912 5.783547) (xy 393.224388 5.76008) (xy 393.304347 5.729104)
			(xy 393.381107 5.690882) (xy 393.454013 5.645741) (xy 393.522442 5.594065) (xy 393.585812 5.536296)
			(xy 393.643581 5.472926) (xy 393.695257 5.404497) (xy 393.740398 5.331591) (xy 393.77862 5.254831)
			(xy 393.809596 5.174872) (xy 393.833063 5.092396) (xy 393.848819 5.008106) (xy 393.856731 4.922723)
			(xy 393.857226 4.879848) (xy 393.856731 4.836973) (xy 436.390783 4.836973) (xy 436.390783 4.922723)
			(xy 436.398695 5.008106) (xy 436.414451 5.092396) (xy 436.437918 5.174872) (xy 436.468894 5.254831)
			(xy 436.507116 5.331591) (xy 436.552257 5.404497) (xy 436.603933 5.472926) (xy 436.661702 5.536296)
			(xy 436.725072 5.594065) (xy 436.793501 5.645741) (xy 436.866407 5.690882) (xy 436.943167 5.729104)
			(xy 437.023126 5.76008) (xy 437.105602 5.783547) (xy 437.189892 5.799303) (xy 437.275275 5.807215)
			(xy 437.361025 5.807215) (xy 437.446408 5.799303) (xy 437.530698 5.783547) (xy 437.613174 5.76008)
			(xy 437.693133 5.729104) (xy 437.713806 5.71881) (xy 438.87644 5.71881) (xy 438.87644 6.58241) (xy 438.876944 6.611946)
			(xy 438.884988 6.670468) (xy 438.900925 6.72735) (xy 438.92446 6.781532) (xy 438.955153 6.832005)
			(xy 438.992433 6.877828) (xy 439.035605 6.918148) (xy 439.083865 6.952214) (xy 439.136315 6.979391)
			(xy 439.191976 6.999173) (xy 439.249813 7.011192) (xy 439.308748 7.015223) (xy 439.367683 7.011192)
			(xy 439.42552 6.999173) (xy 439.481181 6.979391) (xy 439.533631 6.952214) (xy 439.581891 6.918148)
			(xy 439.625063 6.877828) (xy 439.662343 6.832005) (xy 439.693036 6.781532) (xy 439.716571 6.72735)
			(xy 439.732508 6.670468) (xy 439.740552 6.611946) (xy 439.741056 6.58241) (xy 439.741056 5.71881)
			(xy 439.740552 5.689274) (xy 439.732508 5.630752) (xy 439.716571 5.57387) (xy 439.693036 5.519688)
			(xy 439.662343 5.469215) (xy 439.625063 5.423392) (xy 439.581891 5.383072) (xy 439.533631 5.349006)
			(xy 439.481181 5.321829) (xy 439.42552 5.302047) (xy 439.367683 5.290028) (xy 439.308748 5.285997)
			(xy 439.249813 5.290028) (xy 439.191976 5.302047) (xy 439.136315 5.321829) (xy 439.083865 5.349006)
			(xy 439.035605 5.383072) (xy 438.992433 5.423392) (xy 438.955153 5.469215) (xy 438.92446 5.519688)
			(xy 438.900925 5.57387) (xy 438.884988 5.630752) (xy 438.876944 5.689274) (xy 438.87644 5.71881)
			(xy 437.713806 5.71881) (xy 437.769893 5.690882) (xy 437.842799 5.645741) (xy 437.911228 5.594065)
			(xy 437.974598 5.536296) (xy 438.032367 5.472926) (xy 438.084043 5.404497) (xy 438.129184 5.331591)
			(xy 438.167406 5.254831) (xy 438.198382 5.174872) (xy 438.221849 5.092396) (xy 438.237605 5.008106)
			(xy 438.245517 4.922723) (xy 438.246012 4.879848) (xy 438.245517 4.836973) (xy 442.740783 4.836973)
			(xy 442.740783 4.922723) (xy 442.748695 5.008106) (xy 442.764451 5.092396) (xy 442.787918 5.174872)
			(xy 442.818894 5.254831) (xy 442.857116 5.331591) (xy 442.902257 5.404497) (xy 442.953933 5.472926)
			(xy 443.011702 5.536296) (xy 443.075072 5.594065) (xy 443.143501 5.645741) (xy 443.216407 5.690882)
			(xy 443.293167 5.729104) (xy 443.373126 5.76008) (xy 443.455602 5.783547) (xy 443.539892 5.799303)
			(xy 443.625275 5.807215) (xy 443.711025 5.807215) (xy 443.796408 5.799303) (xy 443.880698 5.783547)
			(xy 443.963174 5.76008) (xy 444.043133 5.729104) (xy 444.119893 5.690882) (xy 444.192799 5.645741)
			(xy 444.261228 5.594065) (xy 444.324598 5.536296) (xy 444.382367 5.472926) (xy 444.434043 5.404497)
			(xy 444.479184 5.331591) (xy 444.517406 5.254831) (xy 444.548382 5.174872) (xy 444.571849 5.092396)
			(xy 444.587605 5.008106) (xy 444.595517 4.922723) (xy 444.596012 4.879848) (xy 444.595517 4.836973)
			(xy 444.587605 4.75159) (xy 444.571849 4.6673) (xy 444.548382 4.584824) (xy 444.517406 4.504865)
			(xy 444.479184 4.428105) (xy 444.434043 4.355199) (xy 444.382367 4.28677) (xy 444.324598 4.2234)
			(xy 444.261228 4.165631) (xy 444.192799 4.113955) (xy 444.119893 4.068814) (xy 444.043133 4.030592)
			(xy 443.963174 3.999616) (xy 443.880698 3.976149) (xy 443.796408 3.960393) (xy 443.711025 3.952481)
			(xy 443.625275 3.952481) (xy 443.539892 3.960393) (xy 443.455602 3.976149) (xy 443.373126 3.999616)
			(xy 443.293167 4.030592) (xy 443.216407 4.068814) (xy 443.143501 4.113955) (xy 443.075072 4.165631)
			(xy 443.011702 4.2234) (xy 442.953933 4.28677) (xy 442.902257 4.355199) (xy 442.857116 4.428105)
			(xy 442.818894 4.504865) (xy 442.787918 4.584824) (xy 442.764451 4.6673) (xy 442.748695 4.75159)
			(xy 442.740783 4.836973) (xy 438.245517 4.836973) (xy 438.237605 4.75159) (xy 438.221849 4.6673)
			(xy 438.198382 4.584824) (xy 438.167406 4.504865) (xy 438.129184 4.428105) (xy 438.084043 4.355199)
			(xy 438.032367 4.28677) (xy 437.974598 4.2234) (xy 437.911228 4.165631) (xy 437.842799 4.113955)
			(xy 437.769893 4.068814) (xy 437.693133 4.030592) (xy 437.613174 3.999616) (xy 437.530698 3.976149)
			(xy 437.446408 3.960393) (xy 437.361025 3.952481) (xy 437.275275 3.952481) (xy 437.189892 3.960393)
			(xy 437.105602 3.976149) (xy 437.023126 3.999616) (xy 436.943167 4.030592) (xy 436.866407 4.068814)
			(xy 436.793501 4.113955) (xy 436.725072 4.165631) (xy 436.661702 4.2234) (xy 436.603933 4.28677)
			(xy 436.552257 4.355199) (xy 436.507116 4.428105) (xy 436.468894 4.504865) (xy 436.437918 4.584824)
			(xy 436.414451 4.6673) (xy 436.398695 4.75159) (xy 436.390783 4.836973) (xy 393.856731 4.836973)
			(xy 393.848819 4.75159) (xy 393.833063 4.6673) (xy 393.809596 4.584824) (xy 393.77862 4.504865) (xy 393.740398 4.428105)
			(xy 393.695257 4.355199) (xy 393.643581 4.28677) (xy 393.585812 4.2234) (xy 393.522442 4.165631)
			(xy 393.454013 4.113955) (xy 393.381107 4.068814) (xy 393.304347 4.030592) (xy 393.224388 3.999616)
			(xy 393.141912 3.976149) (xy 393.057622 3.960393) (xy 392.972239 3.952481) (xy 392.886489 3.952481)
			(xy 392.801106 3.960393) (xy 392.716816 3.976149) (xy 392.63434 3.999616) (xy 392.554381 4.030592)
			(xy 392.477621 4.068814) (xy 392.404715 4.113955) (xy 392.336286 4.165631) (xy 392.272916 4.2234)
			(xy 392.215147 4.28677) (xy 392.163471 4.355199) (xy 392.11833 4.428105) (xy 392.080108 4.504865)
			(xy 392.049132 4.584824) (xy 392.025665 4.6673) (xy 392.009909 4.75159) (xy 392.001997 4.836973)
			(xy 387.506731 4.836973) (xy 387.498819 4.75159) (xy 387.483063 4.6673) (xy 387.459596 4.584824)
			(xy 387.42862 4.504865) (xy 387.390398 4.428105) (xy 387.345257 4.355199) (xy 387.293581 4.28677)
			(xy 387.235812 4.2234) (xy 387.172442 4.165631) (xy 387.104013 4.113955) (xy 387.031107 4.068814)
			(xy 386.954347 4.030592) (xy 386.874388 3.999616) (xy 386.791912 3.976149) (xy 386.707622 3.960393)
			(xy 386.622239 3.952481) (xy 386.536489 3.952481) (xy 386.451106 3.960393) (xy 386.366816 3.976149)
			(xy 386.28434 3.999616) (xy 386.204381 4.030592) (xy 386.127621 4.068814) (xy 386.054715 4.113955)
			(xy 385.986286 4.165631) (xy 385.922916 4.2234) (xy 385.865147 4.28677) (xy 385.813471 4.355199)
			(xy 385.76833 4.428105) (xy 385.730108 4.504865) (xy 385.699132 4.584824) (xy 385.675665 4.6673)
			(xy 385.659909 4.75159) (xy 385.651997 4.836973) (xy 365.24438 4.836973) (xy 365.24438 4.651756)
			(xy 365.243876 4.62222) (xy 365.235832 4.563698) (xy 365.219895 4.506816) (xy 365.19636 4.452634)
			(xy 365.165667 4.402161) (xy 365.128387 4.356338) (xy 365.085215 4.316018) (xy 365.036955 4.281952)
			(xy 364.984505 4.254775) (xy 364.928844 4.234993) (xy 364.871007 4.222974) (xy 364.812072 4.218943)
			(xy 364.753137 4.222974) (xy 364.6953 4.234993) (xy 364.639639 4.254775) (xy 364.587189 4.281952)
			(xy 364.538929 4.316018) (xy 364.495757 4.356338) (xy 364.458477 4.402161) (xy 364.427784 4.452634)
			(xy 364.404249 4.506816) (xy 364.388312 4.563698) (xy 364.380268 4.62222) (xy 364.379764 4.651756)
			(xy 363.21713 4.651756) (xy 363.273217 4.623828) (xy 363.346123 4.578687) (xy 363.414552 4.527011)
			(xy 363.477922 4.469242) (xy 363.535691 4.405872) (xy 363.587367 4.337443) (xy 363.632508 4.264537)
			(xy 363.67073 4.187777) (xy 363.701706 4.107818) (xy 363.725173 4.025342) (xy 363.740929 3.941052)
			(xy 363.748841 3.855669) (xy 363.749336 3.812794) (xy 363.748841 3.769919) (xy 368.244107 3.769919)
			(xy 368.244107 3.855669) (xy 368.252019 3.941052) (xy 368.267775 4.025342) (xy 368.291242 4.107818)
			(xy 368.322218 4.187777) (xy 368.36044 4.264537) (xy 368.405581 4.337443) (xy 368.457257 4.405872)
			(xy 368.515026 4.469242) (xy 368.578396 4.527011) (xy 368.646825 4.578687) (xy 368.719731 4.623828)
			(xy 368.796491 4.66205) (xy 368.87645 4.693026) (xy 368.958926 4.716493) (xy 369.043216 4.732249)
			(xy 369.128599 4.740161) (xy 369.214349 4.740161) (xy 369.299732 4.732249) (xy 369.384022 4.716493)
			(xy 369.466498 4.693026) (xy 369.546457 4.66205) (xy 369.623217 4.623828) (xy 369.696123 4.578687)
			(xy 369.764552 4.527011) (xy 369.827922 4.469242) (xy 369.885691 4.405872) (xy 369.937367 4.337443)
			(xy 369.982508 4.264537) (xy 370.02073 4.187777) (xy 370.051706 4.107818) (xy 370.075173 4.025342)
			(xy 370.090929 3.941052) (xy 370.098841 3.855669) (xy 370.099336 3.812794) (xy 370.098841 3.769919)
			(xy 370.090929 3.684536) (xy 370.075173 3.600246) (xy 370.051706 3.51777) (xy 370.02073 3.437811)
			(xy 369.982508 3.361051) (xy 369.937367 3.288145) (xy 369.885691 3.219716) (xy 369.827922 3.156346)
			(xy 369.764552 3.098577) (xy 369.696123 3.046901) (xy 369.623217 3.00176) (xy 369.546457 2.963538)
			(xy 369.466498 2.932562) (xy 369.384022 2.909095) (xy 369.299732 2.893339) (xy 369.214349 2.885427)
			(xy 369.128599 2.885427) (xy 369.043216 2.893339) (xy 368.958926 2.909095) (xy 368.87645 2.932562)
			(xy 368.796491 2.963538) (xy 368.719731 3.00176) (xy 368.646825 3.046901) (xy 368.578396 3.098577)
			(xy 368.515026 3.156346) (xy 368.457257 3.219716) (xy 368.405581 3.288145) (xy 368.36044 3.361051)
			(xy 368.322218 3.437811) (xy 368.291242 3.51777) (xy 368.267775 3.600246) (xy 368.252019 3.684536)
			(xy 368.244107 3.769919) (xy 363.748841 3.769919) (xy 363.740929 3.684536) (xy 363.725173 3.600246)
			(xy 363.701706 3.51777) (xy 363.67073 3.437811) (xy 363.632508 3.361051) (xy 363.587367 3.288145)
			(xy 363.535691 3.219716) (xy 363.477922 3.156346) (xy 363.414552 3.098577) (xy 363.346123 3.046901)
			(xy 363.273217 3.00176) (xy 363.196457 2.963538) (xy 363.116498 2.932562) (xy 363.034022 2.909095)
			(xy 362.949732 2.893339) (xy 362.864349 2.885427) (xy 362.778599 2.885427) (xy 362.693216 2.893339)
			(xy 362.608926 2.909095) (xy 362.52645 2.932562) (xy 362.446491 2.963538) (xy 362.369731 3.00176)
			(xy 362.296825 3.046901) (xy 362.228396 3.098577) (xy 362.165026 3.156346) (xy 362.107257 3.219716)
			(xy 362.055581 3.288145) (xy 362.01044 3.361051) (xy 361.972218 3.437811) (xy 361.941242 3.51777)
			(xy 361.917775 3.600246) (xy 361.902019 3.684536) (xy 361.894107 3.769919) (xy 319.360055 3.769919)
			(xy 319.352143 3.684536) (xy 319.336387 3.600246) (xy 319.31292 3.51777) (xy 319.281944 3.437811)
			(xy 319.243722 3.361051) (xy 319.198581 3.288145) (xy 319.146905 3.219716) (xy 319.089136 3.156346)
			(xy 319.025766 3.098577) (xy 318.957337 3.046901) (xy 318.884431 3.00176) (xy 318.807671 2.963538)
			(xy 318.727712 2.932562) (xy 318.645236 2.909095) (xy 318.560946 2.893339) (xy 318.475563 2.885427)
			(xy 318.389813 2.885427) (xy 318.30443 2.893339) (xy 318.22014 2.909095) (xy 318.137664 2.932562)
			(xy 318.057705 2.963538) (xy 317.980945 3.00176) (xy 317.908039 3.046901) (xy 317.83961 3.098577)
			(xy 317.77624 3.156346) (xy 317.718471 3.219716) (xy 317.666795 3.288145) (xy 317.621654 3.361051)
			(xy 317.583432 3.437811) (xy 317.552456 3.51777) (xy 317.528989 3.600246) (xy 317.513233 3.684536)
			(xy 317.505321 3.769919) (xy 313.010055 3.769919) (xy 313.002143 3.684536) (xy 312.986387 3.600246)
			(xy 312.96292 3.51777) (xy 312.931944 3.437811) (xy 312.893722 3.361051) (xy 312.848581 3.288145)
			(xy 312.796905 3.219716) (xy 312.739136 3.156346) (xy 312.675766 3.098577) (xy 312.607337 3.046901)
			(xy 312.534431 3.00176) (xy 312.457671 2.963538) (xy 312.377712 2.932562) (xy 312.295236 2.909095)
			(xy 312.210946 2.893339) (xy 312.125563 2.885427) (xy 312.039813 2.885427) (xy 311.95443 2.893339)
			(xy 311.87014 2.909095) (xy 311.787664 2.932562) (xy 311.707705 2.963538) (xy 311.630945 3.00176)
			(xy 311.558039 3.046901) (xy 311.48961 3.098577) (xy 311.42624 3.156346) (xy 311.368471 3.219716)
			(xy 311.316795 3.288145) (xy 311.271654 3.361051) (xy 311.233432 3.437811) (xy 311.202456 3.51777)
			(xy 311.178989 3.600246) (xy 311.163233 3.684536) (xy 311.155321 3.769919) (xy 304.348655 3.769919)
			(xy 304.340743 3.684536) (xy 304.324987 3.600246) (xy 304.30152 3.51777) (xy 304.270544 3.437811)
			(xy 304.232322 3.361051) (xy 304.187181 3.288145) (xy 304.135505 3.219716) (xy 304.077736 3.156346)
			(xy 304.014366 3.098577) (xy 303.945937 3.046901) (xy 303.873031 3.00176) (xy 303.796271 2.963538)
			(xy 303.716312 2.932562) (xy 303.633836 2.909095) (xy 303.549546 2.893339) (xy 303.464163 2.885427)
			(xy 303.378413 2.885427) (xy 303.29303 2.893339) (xy 303.20874 2.909095) (xy 303.126264 2.932562)
			(xy 303.046305 2.963538) (xy 302.969545 3.00176) (xy 302.896639 3.046901) (xy 302.82821 3.098577)
			(xy 302.76484 3.156346) (xy 302.707071 3.219716) (xy 302.655395 3.288145) (xy 302.610254 3.361051)
			(xy 302.572032 3.437811) (xy 302.541056 3.51777) (xy 302.517589 3.600246) (xy 302.501833 3.684536)
			(xy 302.493921 3.769919) (xy 297.998655 3.769919) (xy 297.990743 3.684536) (xy 297.974987 3.600246)
			(xy 297.95152 3.51777) (xy 297.920544 3.437811) (xy 297.882322 3.361051) (xy 297.837181 3.288145)
			(xy 297.785505 3.219716) (xy 297.727736 3.156346) (xy 297.664366 3.098577) (xy 297.595937 3.046901)
			(xy 297.523031 3.00176) (xy 297.446271 2.963538) (xy 297.366312 2.932562) (xy 297.283836 2.909095)
			(xy 297.199546 2.893339) (xy 297.114163 2.885427) (xy 297.028413 2.885427) (xy 296.94303 2.893339)
			(xy 296.85874 2.909095) (xy 296.776264 2.932562) (xy 296.696305 2.963538) (xy 296.619545 3.00176)
			(xy 296.546639 3.046901) (xy 296.47821 3.098577) (xy 296.41484 3.156346) (xy 296.357071 3.219716)
			(xy 296.305395 3.288145) (xy 296.260254 3.361051) (xy 296.222032 3.437811) (xy 296.191056 3.51777)
			(xy 296.167589 3.600246) (xy 296.151833 3.684536) (xy 296.143921 3.769919) (xy 216.865975 3.769919)
			(xy 216.858063 3.684536) (xy 216.842307 3.600246) (xy 216.81884 3.51777) (xy 216.787864 3.437811)
			(xy 216.749642 3.361051) (xy 216.704501 3.288145) (xy 216.652825 3.219716) (xy 216.595056 3.156346)
			(xy 216.531686 3.098577) (xy 216.463257 3.046901) (xy 216.390351 3.00176) (xy 216.313591 2.963538)
			(xy 216.233632 2.932562) (xy 216.151156 2.909095) (xy 216.066866 2.893339) (xy 215.981483 2.885427)
			(xy 215.895733 2.885427) (xy 215.81035 2.893339) (xy 215.72606 2.909095) (xy 215.643584 2.932562)
			(xy 215.563625 2.963538) (xy 215.486865 3.00176) (xy 215.413959 3.046901) (xy 215.34553 3.098577)
			(xy 215.28216 3.156346) (xy 215.224391 3.219716) (xy 215.172715 3.288145) (xy 215.127574 3.361051)
			(xy 215.089352 3.437811) (xy 215.058376 3.51777) (xy 215.034909 3.600246) (xy 215.019153 3.684536)
			(xy 215.011241 3.769919) (xy 210.515975 3.769919) (xy 210.508063 3.684536) (xy 210.492307 3.600246)
			(xy 210.46884 3.51777) (xy 210.437864 3.437811) (xy 210.399642 3.361051) (xy 210.354501 3.288145)
			(xy 210.302825 3.219716) (xy 210.245056 3.156346) (xy 210.181686 3.098577) (xy 210.113257 3.046901)
			(xy 210.040351 3.00176) (xy 209.963591 2.963538) (xy 209.883632 2.932562) (xy 209.801156 2.909095)
			(xy 209.716866 2.893339) (xy 209.631483 2.885427) (xy 209.545733 2.885427) (xy 209.46035 2.893339)
			(xy 209.37606 2.909095) (xy 209.293584 2.932562) (xy 209.213625 2.963538) (xy 209.136865 3.00176)
			(xy 209.063959 3.046901) (xy 208.99553 3.098577) (xy 208.93216 3.156346) (xy 208.874391 3.219716)
			(xy 208.822715 3.288145) (xy 208.777574 3.361051) (xy 208.739352 3.437811) (xy 208.708376 3.51777)
			(xy 208.684909 3.600246) (xy 208.669153 3.684536) (xy 208.661241 3.769919) (xy 184.818528 3.769919)
			(xy 184.818528 3.092196) (xy 184.818024 3.06266) (xy 184.80998 3.004138) (xy 184.794043 2.947256)
			(xy 184.770508 2.893074) (xy 184.739815 2.842601) (xy 184.702535 2.796778) (xy 184.659363 2.756458)
			(xy 184.611103 2.722392) (xy 184.558653 2.695215) (xy 184.502992 2.675433) (xy 184.445155 2.663414)
			(xy 184.38622 2.659383) (xy 184.327285 2.663414) (xy 184.269448 2.675433) (xy 184.213787 2.695215)
			(xy 184.161337 2.722392) (xy 184.113077 2.756458) (xy 184.069905 2.796778) (xy 184.032625 2.842601)
			(xy 184.001932 2.893074) (xy 183.978397 2.947256) (xy 183.96246 3.004138) (xy 183.954416 3.06266)
			(xy 183.953912 3.092196) (xy 182.791278 3.092196) (xy 182.847365 3.064268) (xy 182.920271 3.019127)
			(xy 182.9887 2.967451) (xy 183.05207 2.909682) (xy 183.109839 2.846312) (xy 183.161515 2.777883)
			(xy 183.206656 2.704977) (xy 183.244878 2.628217) (xy 183.275854 2.548258) (xy 183.299321 2.465782)
			(xy 183.315077 2.381492) (xy 183.322989 2.296109) (xy 183.323484 2.253234) (xy 183.322989 2.210359)
			(xy 187.818255 2.210359) (xy 187.818255 2.296109) (xy 187.826167 2.381492) (xy 187.841923 2.465782)
			(xy 187.86539 2.548258) (xy 187.896366 2.628217) (xy 187.934588 2.704977) (xy 187.979729 2.777883)
			(xy 188.031405 2.846312) (xy 188.089174 2.909682) (xy 188.152544 2.967451) (xy 188.220973 3.019127)
			(xy 188.293879 3.064268) (xy 188.370639 3.10249) (xy 188.450598 3.133466) (xy 188.533074 3.156933)
			(xy 188.617364 3.172689) (xy 188.702747 3.180601) (xy 188.788497 3.180601) (xy 188.87388 3.172689)
			(xy 188.95817 3.156933) (xy 189.040646 3.133466) (xy 189.120605 3.10249) (xy 189.197365 3.064268)
			(xy 189.270271 3.019127) (xy 189.3387 2.967451) (xy 189.40207 2.909682) (xy 189.459839 2.846312)
			(xy 189.511515 2.777883) (xy 189.556656 2.704977) (xy 189.594878 2.628217) (xy 189.625854 2.548258)
			(xy 189.649321 2.465782) (xy 189.665077 2.381492) (xy 189.672989 2.296109) (xy 189.673484 2.253234)
			(xy 189.672989 2.210359) (xy 189.665077 2.124976) (xy 189.649321 2.040686) (xy 189.625854 1.95821)
			(xy 189.594878 1.878251) (xy 189.556656 1.801491) (xy 189.511515 1.728585) (xy 189.459839 1.660156)
			(xy 189.40207 1.596786) (xy 189.3387 1.539017) (xy 189.270271 1.487341) (xy 189.197365 1.4422) (xy 189.120605 1.403978)
			(xy 189.040646 1.373002) (xy 188.95817 1.349535) (xy 188.87388 1.333779) (xy 188.788497 1.325867)
			(xy 188.702747 1.325867) (xy 188.617364 1.333779) (xy 188.533074 1.349535) (xy 188.450598 1.373002)
			(xy 188.370639 1.403978) (xy 188.293879 1.4422) (xy 188.220973 1.487341) (xy 188.152544 1.539017)
			(xy 188.089174 1.596786) (xy 188.031405 1.660156) (xy 187.979729 1.728585) (xy 187.934588 1.801491)
			(xy 187.896366 1.878251) (xy 187.86539 1.95821) (xy 187.841923 2.040686) (xy 187.826167 2.124976)
			(xy 187.818255 2.210359) (xy 183.322989 2.210359) (xy 183.315077 2.124976) (xy 183.299321 2.040686)
			(xy 183.275854 1.95821) (xy 183.244878 1.878251) (xy 183.206656 1.801491) (xy 183.161515 1.728585)
			(xy 183.109839 1.660156) (xy 183.05207 1.596786) (xy 182.9887 1.539017) (xy 182.920271 1.487341)
			(xy 182.847365 1.4422) (xy 182.770605 1.403978) (xy 182.690646 1.373002) (xy 182.60817 1.349535)
			(xy 182.52388 1.333779) (xy 182.438497 1.325867) (xy 182.352747 1.325867) (xy 182.267364 1.333779)
			(xy 182.183074 1.349535) (xy 182.100598 1.373002) (xy 182.020639 1.403978) (xy 181.943879 1.4422)
			(xy 181.870973 1.487341) (xy 181.802544 1.539017) (xy 181.739174 1.596786) (xy 181.681405 1.660156)
			(xy 181.629729 1.728585) (xy 181.584588 1.801491) (xy 181.546366 1.878251) (xy 181.51539 1.95821)
			(xy 181.491923 2.040686) (xy 181.476167 2.124976) (xy 181.468255 2.210359) (xy 102.190309 2.210359)
			(xy 102.182397 2.124976) (xy 102.166641 2.040686) (xy 102.143174 1.95821) (xy 102.112198 1.878251)
			(xy 102.073976 1.801491) (xy 102.028835 1.728585) (xy 101.977159 1.660156) (xy 101.91939 1.596786)
			(xy 101.85602 1.539017) (xy 101.787591 1.487341) (xy 101.714685 1.4422) (xy 101.637925 1.403978)
			(xy 101.557966 1.373002) (xy 101.47549 1.349535) (xy 101.3912 1.333779) (xy 101.305817 1.325867)
			(xy 101.220067 1.325867) (xy 101.134684 1.333779) (xy 101.050394 1.349535) (xy 100.967918 1.373002)
			(xy 100.887959 1.403978) (xy 100.811199 1.4422) (xy 100.738293 1.487341) (xy 100.669864 1.539017)
			(xy 100.606494 1.596786) (xy 100.548725 1.660156) (xy 100.497049 1.728585) (xy 100.451908 1.801491)
			(xy 100.413686 1.878251) (xy 100.38271 1.95821) (xy 100.359243 2.040686) (xy 100.343487 2.124976)
			(xy 100.335575 2.210359) (xy 95.840309 2.210359) (xy 95.832397 2.124976) (xy 95.816641 2.040686)
			(xy 95.793174 1.95821) (xy 95.762198 1.878251) (xy 95.723976 1.801491) (xy 95.678835 1.728585) (xy 95.627159 1.660156)
			(xy 95.56939 1.596786) (xy 95.50602 1.539017) (xy 95.437591 1.487341) (xy 95.364685 1.4422) (xy 95.287925 1.403978)
			(xy 95.207966 1.373002) (xy 95.12549 1.349535) (xy 95.0412 1.333779) (xy 94.955817 1.325867) (xy 94.870067 1.325867)
			(xy 94.784684 1.333779) (xy 94.700394 1.349535) (xy 94.617918 1.373002) (xy 94.537959 1.403978) (xy 94.461199 1.4422)
			(xy 94.388293 1.487341) (xy 94.319864 1.539017) (xy 94.256494 1.596786) (xy 94.198725 1.660156) (xy 94.147049 1.728585)
			(xy 94.101908 1.801491) (xy 94.063686 1.878251) (xy 94.03271 1.95821) (xy 94.009243 2.040686) (xy 93.993487 2.124976)
			(xy 93.985575 2.210359) (xy 83.439191 2.210359) (xy 83.525475 2.124078) (xy 83.619275 2.019118) (xy 83.707042 1.909064)
			(xy 83.788501 1.794262) (xy 83.863394 1.675073) (xy 83.931487 1.551873) (xy 83.992565 1.425048) (xy 84.046435 1.294999)
			(xy 84.069209 1.229919) (xy 208.661241 1.229919) (xy 208.661241 1.315669) (xy 208.669153 1.401052)
			(xy 208.684909 1.485342) (xy 208.708376 1.567818) (xy 208.739352 1.647777) (xy 208.777574 1.724537)
			(xy 208.822715 1.797443) (xy 208.874391 1.865872) (xy 208.93216 1.929242) (xy 208.99553 1.987011)
			(xy 209.063959 2.038687) (xy 209.136865 2.083828) (xy 209.213625 2.12205) (xy 209.293584 2.153026)
			(xy 209.37606 2.176493) (xy 209.46035 2.192249) (xy 209.545733 2.200161) (xy 209.631483 2.200161)
			(xy 209.716866 2.192249) (xy 209.801156 2.176493) (xy 209.883632 2.153026) (xy 209.963591 2.12205)
			(xy 209.984264 2.111756) (xy 213.517988 2.111756) (xy 213.517988 2.975356) (xy 213.518492 3.00491)
			(xy 213.526541 3.063466) (xy 213.542487 3.120381) (xy 213.566036 3.174595) (xy 213.596747 3.225098)
			(xy 213.634049 3.270948) (xy 213.677246 3.311291) (xy 213.725535 3.345377) (xy 213.778015 3.37257)
			(xy 213.83371 3.392364) (xy 213.891581 3.40439) (xy 213.95055 3.408424) (xy 214.009519 3.40439) (xy 214.06739 3.392364)
			(xy 214.123085 3.37257) (xy 214.175565 3.345377) (xy 214.223854 3.311291) (xy 214.267051 3.270948)
			(xy 214.304353 3.225098) (xy 214.335064 3.174595) (xy 214.358613 3.120381) (xy 214.374559 3.063466)
			(xy 214.382608 3.00491) (xy 214.383112 2.975356) (xy 214.383112 2.111756) (xy 214.382608 2.082202)
			(xy 214.374559 2.023646) (xy 214.358613 1.966731) (xy 214.335064 1.912517) (xy 214.304353 1.862014)
			(xy 214.267051 1.816164) (xy 214.223854 1.775821) (xy 214.175565 1.741735) (xy 214.123085 1.714542)
			(xy 214.06739 1.694748) (xy 214.009519 1.682722) (xy 213.95055 1.678689) (xy 213.891581 1.682722)
			(xy 213.83371 1.694748) (xy 213.778015 1.714542) (xy 213.725535 1.741735) (xy 213.677246 1.775821)
			(xy 213.634049 1.816164) (xy 213.596747 1.862014) (xy 213.566036 1.912517) (xy 213.542487 1.966731)
			(xy 213.526541 2.023646) (xy 213.518492 2.082202) (xy 213.517988 2.111756) (xy 209.984264 2.111756)
			(xy 210.040351 2.083828) (xy 210.113257 2.038687) (xy 210.181686 1.987011) (xy 210.245056 1.929242)
			(xy 210.302825 1.865872) (xy 210.354501 1.797443) (xy 210.399642 1.724537) (xy 210.437864 1.647777)
			(xy 210.46884 1.567818) (xy 210.492307 1.485342) (xy 210.508063 1.401052) (xy 210.515975 1.315669)
			(xy 210.51647 1.272794) (xy 210.515975 1.229919) (xy 215.011241 1.229919) (xy 215.011241 1.315669)
			(xy 215.019153 1.401052) (xy 215.034909 1.485342) (xy 215.058376 1.567818) (xy 215.089352 1.647777)
			(xy 215.127574 1.724537) (xy 215.172715 1.797443) (xy 215.224391 1.865872) (xy 215.28216 1.929242)
			(xy 215.34553 1.987011) (xy 215.413959 2.038687) (xy 215.486865 2.083828) (xy 215.563625 2.12205)
			(xy 215.643584 2.153026) (xy 215.72606 2.176493) (xy 215.81035 2.192249) (xy 215.895733 2.200161)
			(xy 215.981483 2.200161) (xy 216.066866 2.192249) (xy 216.151156 2.176493) (xy 216.233632 2.153026)
			(xy 216.313591 2.12205) (xy 216.390351 2.083828) (xy 216.463257 2.038687) (xy 216.531686 1.987011)
			(xy 216.595056 1.929242) (xy 216.652825 1.865872) (xy 216.704501 1.797443) (xy 216.749642 1.724537)
			(xy 216.787864 1.647777) (xy 216.81884 1.567818) (xy 216.842307 1.485342) (xy 216.858063 1.401052)
			(xy 216.865975 1.315669) (xy 216.86647 1.272794) (xy 216.865975 1.229919) (xy 296.143921 1.229919)
			(xy 296.143921 1.315669) (xy 296.151833 1.401052) (xy 296.167589 1.485342) (xy 296.191056 1.567818)
			(xy 296.222032 1.647777) (xy 296.260254 1.724537) (xy 296.305395 1.797443) (xy 296.357071 1.865872)
			(xy 296.41484 1.929242) (xy 296.47821 1.987011) (xy 296.546639 2.038687) (xy 296.619545 2.083828)
			(xy 296.696305 2.12205) (xy 296.776264 2.153026) (xy 296.85874 2.176493) (xy 296.94303 2.192249)
			(xy 297.028413 2.200161) (xy 297.114163 2.200161) (xy 297.199546 2.192249) (xy 297.283836 2.176493)
			(xy 297.366312 2.153026) (xy 297.446271 2.12205) (xy 297.466944 2.111756) (xy 298.629324 2.111756)
			(xy 298.629324 2.975356) (xy 298.629828 3.00491) (xy 298.637877 3.063466) (xy 298.653823 3.120381)
			(xy 298.677372 3.174595) (xy 298.708083 3.225098) (xy 298.745385 3.270948) (xy 298.788582 3.311291)
			(xy 298.836871 3.345377) (xy 298.889351 3.37257) (xy 298.945046 3.392364) (xy 299.002917 3.40439)
			(xy 299.061886 3.408424) (xy 299.120855 3.40439) (xy 299.178726 3.392364) (xy 299.234421 3.37257)
			(xy 299.286901 3.345377) (xy 299.33519 3.311291) (xy 299.378387 3.270948) (xy 299.415689 3.225098)
			(xy 299.4464 3.174595) (xy 299.469949 3.120381) (xy 299.485895 3.063466) (xy 299.493944 3.00491)
			(xy 299.494448 2.975356) (xy 299.494448 2.111756) (xy 299.493944 2.082202) (xy 299.485895 2.023646)
			(xy 299.469949 1.966731) (xy 299.4464 1.912517) (xy 299.415689 1.862014) (xy 299.378387 1.816164)
			(xy 299.33519 1.775821) (xy 299.286901 1.741735) (xy 299.234421 1.714542) (xy 299.178726 1.694748)
			(xy 299.120855 1.682722) (xy 299.061886 1.678689) (xy 299.002917 1.682722) (xy 298.945046 1.694748)
			(xy 298.889351 1.714542) (xy 298.836871 1.741735) (xy 298.788582 1.775821) (xy 298.745385 1.816164)
			(xy 298.708083 1.862014) (xy 298.677372 1.912517) (xy 298.653823 1.966731) (xy 298.637877 2.023646)
			(xy 298.629828 2.082202) (xy 298.629324 2.111756) (xy 297.466944 2.111756) (xy 297.523031 2.083828)
			(xy 297.595937 2.038687) (xy 297.664366 1.987011) (xy 297.727736 1.929242) (xy 297.785505 1.865872)
			(xy 297.837181 1.797443) (xy 297.882322 1.724537) (xy 297.920544 1.647777) (xy 297.95152 1.567818)
			(xy 297.974987 1.485342) (xy 297.990743 1.401052) (xy 297.998655 1.315669) (xy 297.99915 1.272794)
			(xy 297.998655 1.229919) (xy 302.493921 1.229919) (xy 302.493921 1.315669) (xy 302.501833 1.401052)
			(xy 302.517589 1.485342) (xy 302.541056 1.567818) (xy 302.572032 1.647777) (xy 302.610254 1.724537)
			(xy 302.655395 1.797443) (xy 302.707071 1.865872) (xy 302.76484 1.929242) (xy 302.82821 1.987011)
			(xy 302.896639 2.038687) (xy 302.969545 2.083828) (xy 303.046305 2.12205) (xy 303.126264 2.153026)
			(xy 303.20874 2.176493) (xy 303.29303 2.192249) (xy 303.378413 2.200161) (xy 303.464163 2.200161)
			(xy 303.549546 2.192249) (xy 303.633836 2.176493) (xy 303.716312 2.153026) (xy 303.796271 2.12205)
			(xy 303.873031 2.083828) (xy 303.945937 2.038687) (xy 304.014366 1.987011) (xy 304.077736 1.929242)
			(xy 304.135505 1.865872) (xy 304.187181 1.797443) (xy 304.232322 1.724537) (xy 304.270544 1.647777)
			(xy 304.30152 1.567818) (xy 304.324987 1.485342) (xy 304.340743 1.401052) (xy 304.348655 1.315669)
			(xy 304.34915 1.272794) (xy 304.348655 1.229919) (xy 311.155321 1.229919) (xy 311.155321 1.315669)
			(xy 311.163233 1.401052) (xy 311.178989 1.485342) (xy 311.202456 1.567818) (xy 311.233432 1.647777)
			(xy 311.271654 1.724537) (xy 311.316795 1.797443) (xy 311.368471 1.865872) (xy 311.42624 1.929242)
			(xy 311.48961 1.987011) (xy 311.558039 2.038687) (xy 311.630945 2.083828) (xy 311.707705 2.12205)
			(xy 311.787664 2.153026) (xy 311.87014 2.176493) (xy 311.95443 2.192249) (xy 312.039813 2.200161)
			(xy 312.125563 2.200161) (xy 312.210946 2.192249) (xy 312.295236 2.176493) (xy 312.377712 2.153026)
			(xy 312.457671 2.12205) (xy 312.534431 2.083828) (xy 312.607337 2.038687) (xy 312.675766 1.987011)
			(xy 312.739136 1.929242) (xy 312.796905 1.865872) (xy 312.848581 1.797443) (xy 312.893722 1.724537)
			(xy 312.931944 1.647777) (xy 312.96292 1.567818) (xy 312.986387 1.485342) (xy 313.002143 1.401052)
			(xy 313.010055 1.315669) (xy 313.01055 1.272794) (xy 313.010055 1.229919) (xy 317.505321 1.229919)
			(xy 317.505321 1.315669) (xy 317.513233 1.401052) (xy 317.528989 1.485342) (xy 317.552456 1.567818)
			(xy 317.583432 1.647777) (xy 317.621654 1.724537) (xy 317.666795 1.797443) (xy 317.718471 1.865872)
			(xy 317.77624 1.929242) (xy 317.83961 1.987011) (xy 317.908039 2.038687) (xy 317.980945 2.083828)
			(xy 318.057705 2.12205) (xy 318.137664 2.153026) (xy 318.22014 2.176493) (xy 318.30443 2.192249)
			(xy 318.389813 2.200161) (xy 318.475563 2.200161) (xy 318.560946 2.192249) (xy 318.645236 2.176493)
			(xy 318.727712 2.153026) (xy 318.807671 2.12205) (xy 318.884431 2.083828) (xy 318.957337 2.038687)
			(xy 319.025766 1.987011) (xy 319.089136 1.929242) (xy 319.146905 1.865872) (xy 319.198581 1.797443)
			(xy 319.243722 1.724537) (xy 319.281944 1.647777) (xy 319.31292 1.567818) (xy 319.336387 1.485342)
			(xy 319.352143 1.401052) (xy 319.360055 1.315669) (xy 319.36055 1.272794) (xy 319.360055 1.229919)
			(xy 361.894107 1.229919) (xy 361.894107 1.315669) (xy 361.902019 1.401052) (xy 361.917775 1.485342)
			(xy 361.941242 1.567818) (xy 361.972218 1.647777) (xy 362.01044 1.724537) (xy 362.055581 1.797443)
			(xy 362.107257 1.865872) (xy 362.165026 1.929242) (xy 362.228396 1.987011) (xy 362.296825 2.038687)
			(xy 362.369731 2.083828) (xy 362.446491 2.12205) (xy 362.52645 2.153026) (xy 362.608926 2.176493)
			(xy 362.693216 2.192249) (xy 362.778599 2.200161) (xy 362.864349 2.200161) (xy 362.949732 2.192249)
			(xy 363.034022 2.176493) (xy 363.116498 2.153026) (xy 363.196457 2.12205) (xy 363.273217 2.083828)
			(xy 363.346123 2.038687) (xy 363.414552 1.987011) (xy 363.477922 1.929242) (xy 363.535691 1.865872)
			(xy 363.587367 1.797443) (xy 363.632508 1.724537) (xy 363.67073 1.647777) (xy 363.701706 1.567818)
			(xy 363.725173 1.485342) (xy 363.740929 1.401052) (xy 363.748841 1.315669) (xy 363.749336 1.272794)
			(xy 363.748841 1.229919) (xy 368.244107 1.229919) (xy 368.244107 1.315669) (xy 368.252019 1.401052)
			(xy 368.267775 1.485342) (xy 368.291242 1.567818) (xy 368.322218 1.647777) (xy 368.36044 1.724537)
			(xy 368.405581 1.797443) (xy 368.457257 1.865872) (xy 368.515026 1.929242) (xy 368.578396 1.987011)
			(xy 368.646825 2.038687) (xy 368.719731 2.083828) (xy 368.796491 2.12205) (xy 368.87645 2.153026)
			(xy 368.958926 2.176493) (xy 369.043216 2.192249) (xy 369.128599 2.200161) (xy 369.214349 2.200161)
			(xy 369.299732 2.192249) (xy 369.384022 2.176493) (xy 369.466498 2.153026) (xy 369.546457 2.12205)
			(xy 369.623217 2.083828) (xy 369.696123 2.038687) (xy 369.764552 1.987011) (xy 369.827922 1.929242)
			(xy 369.885691 1.865872) (xy 369.937367 1.797443) (xy 369.982508 1.724537) (xy 370.02073 1.647777)
			(xy 370.051706 1.567818) (xy 370.075173 1.485342) (xy 370.090929 1.401052) (xy 370.098841 1.315669)
			(xy 370.099336 1.272794) (xy 370.098841 1.229919) (xy 370.090929 1.144536) (xy 370.075173 1.060246)
			(xy 370.051706 0.97777) (xy 370.02073 0.897811) (xy 369.982508 0.821051) (xy 369.937367 0.748145)
			(xy 369.885691 0.679716) (xy 369.827922 0.616346) (xy 369.764552 0.558577) (xy 369.696123 0.506901)
			(xy 369.623217 0.46176) (xy 369.546457 0.423538) (xy 369.466498 0.392562) (xy 369.384022 0.369095)
			(xy 369.299732 0.353339) (xy 369.214349 0.345427) (xy 369.128599 0.345427) (xy 369.043216 0.353339)
			(xy 368.958926 0.369095) (xy 368.87645 0.392562) (xy 368.796491 0.423538) (xy 368.719731 0.46176)
			(xy 368.646825 0.506901) (xy 368.578396 0.558577) (xy 368.515026 0.616346) (xy 368.457257 0.679716)
			(xy 368.405581 0.748145) (xy 368.36044 0.821051) (xy 368.322218 0.897811) (xy 368.291242 0.97777)
			(xy 368.267775 1.060246) (xy 368.252019 1.144536) (xy 368.244107 1.229919) (xy 363.748841 1.229919)
			(xy 363.740929 1.144536) (xy 363.725173 1.060246) (xy 363.701706 0.97777) (xy 363.67073 0.897811)
			(xy 363.632508 0.821051) (xy 363.587367 0.748145) (xy 363.535691 0.679716) (xy 363.477922 0.616346)
			(xy 363.414552 0.558577) (xy 363.346123 0.506901) (xy 363.273217 0.46176) (xy 363.196457 0.423538)
			(xy 363.116498 0.392562) (xy 363.034022 0.369095) (xy 362.949732 0.353339) (xy 362.864349 0.345427)
			(xy 362.778599 0.345427) (xy 362.693216 0.353339) (xy 362.608926 0.369095) (xy 362.52645 0.392562)
			(xy 362.446491 0.423538) (xy 362.369731 0.46176) (xy 362.296825 0.506901) (xy 362.228396 0.558577)
			(xy 362.165026 0.616346) (xy 362.107257 0.679716) (xy 362.055581 0.748145) (xy 362.01044 0.821051)
			(xy 361.972218 0.897811) (xy 361.941242 0.97777) (xy 361.917775 1.060246) (xy 361.902019 1.144536)
			(xy 361.894107 1.229919) (xy 319.360055 1.229919) (xy 319.352143 1.144536) (xy 319.336387 1.060246)
			(xy 319.31292 0.97777) (xy 319.281944 0.897811) (xy 319.243722 0.821051) (xy 319.198581 0.748145)
			(xy 319.146905 0.679716) (xy 319.089136 0.616346) (xy 319.025766 0.558577) (xy 318.957337 0.506901)
			(xy 318.884431 0.46176) (xy 318.807671 0.423538) (xy 318.727712 0.392562) (xy 318.645236 0.369095)
			(xy 318.560946 0.353339) (xy 318.475563 0.345427) (xy 318.389813 0.345427) (xy 318.30443 0.353339)
			(xy 318.22014 0.369095) (xy 318.137664 0.392562) (xy 318.057705 0.423538) (xy 317.980945 0.46176)
			(xy 317.908039 0.506901) (xy 317.83961 0.558577) (xy 317.77624 0.616346) (xy 317.718471 0.679716)
			(xy 317.666795 0.748145) (xy 317.621654 0.821051) (xy 317.583432 0.897811) (xy 317.552456 0.97777)
			(xy 317.528989 1.060246) (xy 317.513233 1.144536) (xy 317.505321 1.229919) (xy 313.010055 1.229919)
			(xy 313.002143 1.144536) (xy 312.986387 1.060246) (xy 312.96292 0.97777) (xy 312.931944 0.897811)
			(xy 312.893722 0.821051) (xy 312.848581 0.748145) (xy 312.796905 0.679716) (xy 312.739136 0.616346)
			(xy 312.675766 0.558577) (xy 312.607337 0.506901) (xy 312.534431 0.46176) (xy 312.457671 0.423538)
			(xy 312.377712 0.392562) (xy 312.295236 0.369095) (xy 312.210946 0.353339) (xy 312.125563 0.345427)
			(xy 312.039813 0.345427) (xy 311.95443 0.353339) (xy 311.87014 0.369095) (xy 311.787664 0.392562)
			(xy 311.707705 0.423538) (xy 311.630945 0.46176) (xy 311.558039 0.506901) (xy 311.48961 0.558577)
			(xy 311.42624 0.616346) (xy 311.368471 0.679716) (xy 311.316795 0.748145) (xy 311.271654 0.821051)
			(xy 311.233432 0.897811) (xy 311.202456 0.97777) (xy 311.178989 1.060246) (xy 311.163233 1.144536)
			(xy 311.155321 1.229919) (xy 304.348655 1.229919) (xy 304.340743 1.144536) (xy 304.324987 1.060246)
			(xy 304.30152 0.97777) (xy 304.270544 0.897811) (xy 304.232322 0.821051) (xy 304.187181 0.748145)
			(xy 304.135505 0.679716) (xy 304.077736 0.616346) (xy 304.014366 0.558577) (xy 303.945937 0.506901)
			(xy 303.873031 0.46176) (xy 303.796271 0.423538) (xy 303.716312 0.392562) (xy 303.633836 0.369095)
			(xy 303.549546 0.353339) (xy 303.464163 0.345427) (xy 303.378413 0.345427) (xy 303.29303 0.353339)
			(xy 303.20874 0.369095) (xy 303.126264 0.392562) (xy 303.046305 0.423538) (xy 302.969545 0.46176)
			(xy 302.896639 0.506901) (xy 302.82821 0.558577) (xy 302.76484 0.616346) (xy 302.707071 0.679716)
			(xy 302.655395 0.748145) (xy 302.610254 0.821051) (xy 302.572032 0.897811) (xy 302.541056 0.97777)
			(xy 302.517589 1.060246) (xy 302.501833 1.144536) (xy 302.493921 1.229919) (xy 297.998655 1.229919)
			(xy 297.990743 1.144536) (xy 297.974987 1.060246) (xy 297.95152 0.97777) (xy 297.920544 0.897811)
			(xy 297.882322 0.821051) (xy 297.837181 0.748145) (xy 297.785505 0.679716) (xy 297.727736 0.616346)
			(xy 297.664366 0.558577) (xy 297.595937 0.506901) (xy 297.523031 0.46176) (xy 297.446271 0.423538)
			(xy 297.366312 0.392562) (xy 297.283836 0.369095) (xy 297.199546 0.353339) (xy 297.114163 0.345427)
			(xy 297.028413 0.345427) (xy 296.94303 0.353339) (xy 296.85874 0.369095) (xy 296.776264 0.392562)
			(xy 296.696305 0.423538) (xy 296.619545 0.46176) (xy 296.546639 0.506901) (xy 296.47821 0.558577)
			(xy 296.41484 0.616346) (xy 296.357071 0.679716) (xy 296.305395 0.748145) (xy 296.260254 0.821051)
			(xy 296.222032 0.897811) (xy 296.191056 0.97777) (xy 296.167589 1.060246) (xy 296.151833 1.144536)
			(xy 296.143921 1.229919) (xy 216.865975 1.229919) (xy 216.858063 1.144536) (xy 216.842307 1.060246)
			(xy 216.81884 0.97777) (xy 216.787864 0.897811) (xy 216.749642 0.821051) (xy 216.704501 0.748145)
			(xy 216.652825 0.679716) (xy 216.595056 0.616346) (xy 216.531686 0.558577) (xy 216.463257 0.506901)
			(xy 216.390351 0.46176) (xy 216.313591 0.423538) (xy 216.233632 0.392562) (xy 216.151156 0.369095)
			(xy 216.066866 0.353339) (xy 215.981483 0.345427) (xy 215.895733 0.345427) (xy 215.81035 0.353339)
			(xy 215.72606 0.369095) (xy 215.643584 0.392562) (xy 215.563625 0.423538) (xy 215.486865 0.46176)
			(xy 215.413959 0.506901) (xy 215.34553 0.558577) (xy 215.28216 0.616346) (xy 215.224391 0.679716)
			(xy 215.172715 0.748145) (xy 215.127574 0.821051) (xy 215.089352 0.897811) (xy 215.058376 0.97777)
			(xy 215.034909 1.060246) (xy 215.019153 1.144536) (xy 215.011241 1.229919) (xy 210.515975 1.229919)
			(xy 210.508063 1.144536) (xy 210.492307 1.060246) (xy 210.46884 0.97777) (xy 210.437864 0.897811)
			(xy 210.399642 0.821051) (xy 210.354501 0.748145) (xy 210.302825 0.679716) (xy 210.245056 0.616346)
			(xy 210.181686 0.558577) (xy 210.113257 0.506901) (xy 210.040351 0.46176) (xy 209.963591 0.423538)
			(xy 209.883632 0.392562) (xy 209.801156 0.369095) (xy 209.716866 0.353339) (xy 209.631483 0.345427)
			(xy 209.545733 0.345427) (xy 209.46035 0.353339) (xy 209.37606 0.369095) (xy 209.293584 0.392562)
			(xy 209.213625 0.423538) (xy 209.136865 0.46176) (xy 209.063959 0.506901) (xy 208.99553 0.558577)
			(xy 208.93216 0.616346) (xy 208.874391 0.679716) (xy 208.822715 0.748145) (xy 208.777574 0.821051)
			(xy 208.739352 0.897811) (xy 208.708376 0.97777) (xy 208.684909 1.060246) (xy 208.669153 1.144536)
			(xy 208.661241 1.229919) (xy 84.069209 1.229919) (xy 84.092929 1.162133) (xy 84.131901 1.02687) (xy 84.163226 0.889634)
			(xy 84.186808 0.750857) (xy 84.202571 0.610977) (xy 84.210467 0.470433) (xy 84.210906 0.40005) (xy 84.210906 -1.310081)
			(xy 208.661241 -1.310081) (xy 208.661241 -1.224331) (xy 208.669153 -1.138948) (xy 208.684909 -1.054658)
			(xy 208.708376 -0.972182) (xy 208.739352 -0.892223) (xy 208.777574 -0.815463) (xy 208.822715 -0.742557)
			(xy 208.874391 -0.674128) (xy 208.93216 -0.610758) (xy 208.99553 -0.552989) (xy 209.063959 -0.501313)
			(xy 209.136865 -0.456172) (xy 209.213625 -0.41795) (xy 209.293584 -0.386974) (xy 209.37606 -0.363507)
			(xy 209.46035 -0.347751) (xy 209.545733 -0.339839) (xy 209.631483 -0.339839) (xy 209.716866 -0.347751)
			(xy 209.801156 -0.363507) (xy 209.883632 -0.386974) (xy 209.963591 -0.41795) (xy 210.040351 -0.456172)
			(xy 210.113257 -0.501313) (xy 210.181686 -0.552989) (xy 210.245056 -0.610758) (xy 210.302825 -0.674128)
			(xy 210.354501 -0.742557) (xy 210.399642 -0.815463) (xy 210.437864 -0.892223) (xy 210.46884 -0.972182)
			(xy 210.492307 -1.054658) (xy 210.508063 -1.138948) (xy 210.515975 -1.224331) (xy 210.51647 -1.267206)
			(xy 210.515975 -1.310081) (xy 215.011241 -1.310081) (xy 215.011241 -1.224331) (xy 215.019153 -1.138948)
			(xy 215.034909 -1.054658) (xy 215.058376 -0.972182) (xy 215.089352 -0.892223) (xy 215.127574 -0.815463)
			(xy 215.172715 -0.742557) (xy 215.224391 -0.674128) (xy 215.28216 -0.610758) (xy 215.34553 -0.552989)
			(xy 215.413959 -0.501313) (xy 215.486865 -0.456172) (xy 215.563625 -0.41795) (xy 215.643584 -0.386974)
			(xy 215.72606 -0.363507) (xy 215.81035 -0.347751) (xy 215.895733 -0.339839) (xy 215.981483 -0.339839)
			(xy 216.066866 -0.347751) (xy 216.151156 -0.363507) (xy 216.233632 -0.386974) (xy 216.313591 -0.41795)
			(xy 216.390351 -0.456172) (xy 216.463257 -0.501313) (xy 216.531686 -0.552989) (xy 216.595056 -0.610758)
			(xy 216.652825 -0.674128) (xy 216.704501 -0.742557) (xy 216.749642 -0.815463) (xy 216.787864 -0.892223)
			(xy 216.81884 -0.972182) (xy 216.842307 -1.054658) (xy 216.858063 -1.138948) (xy 216.865975 -1.224331)
			(xy 216.86647 -1.267206) (xy 216.865975 -1.310081) (xy 296.143921 -1.310081) (xy 296.143921 -1.224331)
			(xy 296.151833 -1.138948) (xy 296.167589 -1.054658) (xy 296.191056 -0.972182) (xy 296.222032 -0.892223)
			(xy 296.260254 -0.815463) (xy 296.305395 -0.742557) (xy 296.357071 -0.674128) (xy 296.41484 -0.610758)
			(xy 296.47821 -0.552989) (xy 296.546639 -0.501313) (xy 296.619545 -0.456172) (xy 296.696305 -0.41795)
			(xy 296.776264 -0.386974) (xy 296.85874 -0.363507) (xy 296.94303 -0.347751) (xy 297.028413 -0.339839)
			(xy 297.114163 -0.339839) (xy 297.199546 -0.347751) (xy 297.283836 -0.363507) (xy 297.366312 -0.386974)
			(xy 297.446271 -0.41795) (xy 297.523031 -0.456172) (xy 297.595937 -0.501313) (xy 297.664366 -0.552989)
			(xy 297.727736 -0.610758) (xy 297.785505 -0.674128) (xy 297.837181 -0.742557) (xy 297.882322 -0.815463)
			(xy 297.920544 -0.892223) (xy 297.95152 -0.972182) (xy 297.974987 -1.054658) (xy 297.990743 -1.138948)
			(xy 297.998655 -1.224331) (xy 297.99915 -1.267206) (xy 297.998655 -1.310081) (xy 302.493921 -1.310081)
			(xy 302.493921 -1.224331) (xy 302.501833 -1.138948) (xy 302.517589 -1.054658) (xy 302.541056 -0.972182)
			(xy 302.572032 -0.892223) (xy 302.610254 -0.815463) (xy 302.655395 -0.742557) (xy 302.707071 -0.674128)
			(xy 302.76484 -0.610758) (xy 302.82821 -0.552989) (xy 302.896639 -0.501313) (xy 302.969545 -0.456172)
			(xy 303.046305 -0.41795) (xy 303.126264 -0.386974) (xy 303.20874 -0.363507) (xy 303.29303 -0.347751)
			(xy 303.378413 -0.339839) (xy 303.464163 -0.339839) (xy 303.549546 -0.347751) (xy 303.633836 -0.363507)
			(xy 303.716312 -0.386974) (xy 303.796271 -0.41795) (xy 303.873031 -0.456172) (xy 303.945937 -0.501313)
			(xy 304.014366 -0.552989) (xy 304.077736 -0.610758) (xy 304.135505 -0.674128) (xy 304.187181 -0.742557)
			(xy 304.232322 -0.815463) (xy 304.270544 -0.892223) (xy 304.30152 -0.972182) (xy 304.324987 -1.054658)
			(xy 304.340743 -1.138948) (xy 304.348655 -1.224331) (xy 304.34915 -1.267206) (xy 304.348655 -1.310081)
			(xy 311.155321 -1.310081) (xy 311.155321 -1.224331) (xy 311.163233 -1.138948) (xy 311.178989 -1.054658)
			(xy 311.202456 -0.972182) (xy 311.233432 -0.892223) (xy 311.271654 -0.815463) (xy 311.316795 -0.742557)
			(xy 311.368471 -0.674128) (xy 311.42624 -0.610758) (xy 311.48961 -0.552989) (xy 311.558039 -0.501313)
			(xy 311.630945 -0.456172) (xy 311.707705 -0.41795) (xy 311.787664 -0.386974) (xy 311.87014 -0.363507)
			(xy 311.95443 -0.347751) (xy 312.039813 -0.339839) (xy 312.125563 -0.339839) (xy 312.210946 -0.347751)
			(xy 312.295236 -0.363507) (xy 312.377712 -0.386974) (xy 312.457671 -0.41795) (xy 312.478344 -0.428244)
			(xy 316.012068 -0.428244) (xy 316.012068 0.435356) (xy 316.012572 0.46491) (xy 316.020621 0.523466)
			(xy 316.036567 0.580381) (xy 316.060116 0.634595) (xy 316.090827 0.685098) (xy 316.128129 0.730948)
			(xy 316.171326 0.771291) (xy 316.219615 0.805377) (xy 316.272095 0.83257) (xy 316.32779 0.852364)
			(xy 316.385661 0.86439) (xy 316.44463 0.868424) (xy 316.503599 0.86439) (xy 316.56147 0.852364) (xy 316.617165 0.83257)
			(xy 316.669645 0.805377) (xy 316.717934 0.771291) (xy 316.761131 0.730948) (xy 316.798433 0.685098)
			(xy 316.829144 0.634595) (xy 316.852693 0.580381) (xy 316.868639 0.523466) (xy 316.876688 0.46491)
			(xy 316.877192 0.435356) (xy 316.877192 -0.428244) (xy 316.876688 -0.457798) (xy 316.868639 -0.516354)
			(xy 316.852693 -0.573269) (xy 316.829144 -0.627483) (xy 316.798433 -0.677986) (xy 316.761131 -0.723836)
			(xy 316.717934 -0.764179) (xy 316.669645 -0.798265) (xy 316.617165 -0.825458) (xy 316.56147 -0.845252)
			(xy 316.503599 -0.857278) (xy 316.44463 -0.861312) (xy 316.385661 -0.857278) (xy 316.32779 -0.845252)
			(xy 316.272095 -0.825458) (xy 316.219615 -0.798265) (xy 316.171326 -0.764179) (xy 316.128129 -0.723836)
			(xy 316.090827 -0.677986) (xy 316.060116 -0.627483) (xy 316.036567 -0.573269) (xy 316.020621 -0.516354)
			(xy 316.012572 -0.457798) (xy 316.012068 -0.428244) (xy 312.478344 -0.428244) (xy 312.534431 -0.456172)
			(xy 312.607337 -0.501313) (xy 312.675766 -0.552989) (xy 312.739136 -0.610758) (xy 312.796905 -0.674128)
			(xy 312.848581 -0.742557) (xy 312.893722 -0.815463) (xy 312.931944 -0.892223) (xy 312.96292 -0.972182)
			(xy 312.986387 -1.054658) (xy 313.002143 -1.138948) (xy 313.010055 -1.224331) (xy 313.01055 -1.267206)
			(xy 313.010055 -1.310081) (xy 317.505321 -1.310081) (xy 317.505321 -1.224331) (xy 317.513233 -1.138948)
			(xy 317.528989 -1.054658) (xy 317.552456 -0.972182) (xy 317.583432 -0.892223) (xy 317.621654 -0.815463)
			(xy 317.666795 -0.742557) (xy 317.718471 -0.674128) (xy 317.77624 -0.610758) (xy 317.83961 -0.552989)
			(xy 317.908039 -0.501313) (xy 317.980945 -0.456172) (xy 318.057705 -0.41795) (xy 318.137664 -0.386974)
			(xy 318.22014 -0.363507) (xy 318.30443 -0.347751) (xy 318.389813 -0.339839) (xy 318.475563 -0.339839)
			(xy 318.560946 -0.347751) (xy 318.645236 -0.363507) (xy 318.727712 -0.386974) (xy 318.807671 -0.41795)
			(xy 318.884431 -0.456172) (xy 318.957337 -0.501313) (xy 319.025766 -0.552989) (xy 319.089136 -0.610758)
			(xy 319.146905 -0.674128) (xy 319.198581 -0.742557) (xy 319.243722 -0.815463) (xy 319.281944 -0.892223)
			(xy 319.31292 -0.972182) (xy 319.336387 -1.054658) (xy 319.352143 -1.138948) (xy 319.360055 -1.224331)
			(xy 319.36055 -1.267206) (xy 319.360055 -1.310081) (xy 361.894107 -1.310081) (xy 361.894107 -1.224331)
			(xy 361.902019 -1.138948) (xy 361.917775 -1.054658) (xy 361.941242 -0.972182) (xy 361.972218 -0.892223)
			(xy 362.01044 -0.815463) (xy 362.055581 -0.742557) (xy 362.107257 -0.674128) (xy 362.165026 -0.610758)
			(xy 362.228396 -0.552989) (xy 362.296825 -0.501313) (xy 362.369731 -0.456172) (xy 362.446491 -0.41795)
			(xy 362.52645 -0.386974) (xy 362.608926 -0.363507) (xy 362.693216 -0.347751) (xy 362.778599 -0.339839)
			(xy 362.864349 -0.339839) (xy 362.949732 -0.347751) (xy 363.034022 -0.363507) (xy 363.116498 -0.386974)
			(xy 363.196457 -0.41795) (xy 363.21713 -0.428244) (xy 364.379764 -0.428244) (xy 364.379764 0.435356)
			(xy 364.380268 0.464892) (xy 364.388312 0.523414) (xy 364.404249 0.580296) (xy 364.427784 0.634478)
			(xy 364.458477 0.684951) (xy 364.495757 0.730774) (xy 364.538929 0.771094) (xy 364.587189 0.80516)
			(xy 364.639639 0.832337) (xy 364.6953 0.852119) (xy 364.753137 0.864138) (xy 364.812072 0.868169)
			(xy 364.871007 0.864138) (xy 364.928844 0.852119) (xy 364.984505 0.832337) (xy 365.036955 0.80516)
			(xy 365.085215 0.771094) (xy 365.128387 0.730774) (xy 365.165667 0.684951) (xy 365.19636 0.634478)
			(xy 365.219895 0.580296) (xy 365.235832 0.523414) (xy 365.243876 0.464892) (xy 365.24438 0.435356)
			(xy 365.24438 -0.428244) (xy 365.243876 -0.45778) (xy 365.235832 -0.516302) (xy 365.219895 -0.573184)
			(xy 365.19636 -0.627366) (xy 365.165667 -0.677839) (xy 365.128387 -0.723662) (xy 365.085215 -0.763982)
			(xy 365.036955 -0.798048) (xy 364.984505 -0.825225) (xy 364.928844 -0.845007) (xy 364.871007 -0.857026)
			(xy 364.812072 -0.861057) (xy 364.753137 -0.857026) (xy 364.6953 -0.845007) (xy 364.639639 -0.825225)
			(xy 364.587189 -0.798048) (xy 364.538929 -0.763982) (xy 364.495757 -0.723662) (xy 364.458477 -0.677839)
			(xy 364.427784 -0.627366) (xy 364.404249 -0.573184) (xy 364.388312 -0.516302) (xy 364.380268 -0.45778)
			(xy 364.379764 -0.428244) (xy 363.21713 -0.428244) (xy 363.273217 -0.456172) (xy 363.346123 -0.501313)
			(xy 363.414552 -0.552989) (xy 363.477922 -0.610758) (xy 363.535691 -0.674128) (xy 363.587367 -0.742557)
			(xy 363.632508 -0.815463) (xy 363.67073 -0.892223) (xy 363.701706 -0.972182) (xy 363.725173 -1.054658)
			(xy 363.740929 -1.138948) (xy 363.748841 -1.224331) (xy 363.749336 -1.267206) (xy 363.748841 -1.310081)
			(xy 368.244107 -1.310081) (xy 368.244107 -1.224331) (xy 368.252019 -1.138948) (xy 368.267775 -1.054658)
			(xy 368.291242 -0.972182) (xy 368.322218 -0.892223) (xy 368.36044 -0.815463) (xy 368.405581 -0.742557)
			(xy 368.457257 -0.674128) (xy 368.515026 -0.610758) (xy 368.578396 -0.552989) (xy 368.646825 -0.501313)
			(xy 368.719731 -0.456172) (xy 368.796491 -0.41795) (xy 368.87645 -0.386974) (xy 368.958926 -0.363507)
			(xy 369.043216 -0.347751) (xy 369.128599 -0.339839) (xy 369.214349 -0.339839) (xy 369.299732 -0.347751)
			(xy 369.384022 -0.363507) (xy 369.466498 -0.386974) (xy 369.546457 -0.41795) (xy 369.623217 -0.456172)
			(xy 369.696123 -0.501313) (xy 369.764552 -0.552989) (xy 369.827922 -0.610758) (xy 369.885691 -0.674128)
			(xy 369.937367 -0.742557) (xy 369.982508 -0.815463) (xy 370.02073 -0.892223) (xy 370.051706 -0.972182)
			(xy 370.075173 -1.054658) (xy 370.090929 -1.138948) (xy 370.098841 -1.224331) (xy 370.099336 -1.267206)
			(xy 370.098841 -1.310081) (xy 370.090929 -1.395464) (xy 370.075173 -1.479754) (xy 370.051706 -1.56223)
			(xy 370.02073 -1.642189) (xy 369.982508 -1.718949) (xy 369.937367 -1.791855) (xy 369.885691 -1.860284)
			(xy 369.827922 -1.923654) (xy 369.764552 -1.981423) (xy 369.696123 -2.033099) (xy 369.623217 -2.07824)
			(xy 369.546457 -2.116462) (xy 369.466498 -2.147438) (xy 369.384022 -2.170905) (xy 369.299732 -2.186661)
			(xy 369.214349 -2.194573) (xy 369.128599 -2.194573) (xy 369.043216 -2.186661) (xy 368.958926 -2.170905)
			(xy 368.87645 -2.147438) (xy 368.796491 -2.116462) (xy 368.719731 -2.07824) (xy 368.646825 -2.033099)
			(xy 368.578396 -1.981423) (xy 368.515026 -1.923654) (xy 368.457257 -1.860284) (xy 368.405581 -1.791855)
			(xy 368.36044 -1.718949) (xy 368.322218 -1.642189) (xy 368.291242 -1.56223) (xy 368.267775 -1.479754)
			(xy 368.252019 -1.395464) (xy 368.244107 -1.310081) (xy 363.748841 -1.310081) (xy 363.740929 -1.395464)
			(xy 363.725173 -1.479754) (xy 363.701706 -1.56223) (xy 363.67073 -1.642189) (xy 363.632508 -1.718949)
			(xy 363.587367 -1.791855) (xy 363.535691 -1.860284) (xy 363.477922 -1.923654) (xy 363.414552 -1.981423)
			(xy 363.346123 -2.033099) (xy 363.273217 -2.07824) (xy 363.196457 -2.116462) (xy 363.116498 -2.147438)
			(xy 363.034022 -2.170905) (xy 362.949732 -2.186661) (xy 362.864349 -2.194573) (xy 362.778599 -2.194573)
			(xy 362.693216 -2.186661) (xy 362.608926 -2.170905) (xy 362.52645 -2.147438) (xy 362.446491 -2.116462)
			(xy 362.369731 -2.07824) (xy 362.296825 -2.033099) (xy 362.228396 -1.981423) (xy 362.165026 -1.923654)
			(xy 362.107257 -1.860284) (xy 362.055581 -1.791855) (xy 362.01044 -1.718949) (xy 361.972218 -1.642189)
			(xy 361.941242 -1.56223) (xy 361.917775 -1.479754) (xy 361.902019 -1.395464) (xy 361.894107 -1.310081)
			(xy 319.360055 -1.310081) (xy 319.352143 -1.395464) (xy 319.336387 -1.479754) (xy 319.31292 -1.56223)
			(xy 319.281944 -1.642189) (xy 319.243722 -1.718949) (xy 319.198581 -1.791855) (xy 319.146905 -1.860284)
			(xy 319.089136 -1.923654) (xy 319.025766 -1.981423) (xy 318.957337 -2.033099) (xy 318.884431 -2.07824)
			(xy 318.807671 -2.116462) (xy 318.727712 -2.147438) (xy 318.645236 -2.170905) (xy 318.560946 -2.186661)
			(xy 318.475563 -2.194573) (xy 318.389813 -2.194573) (xy 318.30443 -2.186661) (xy 318.22014 -2.170905)
			(xy 318.137664 -2.147438) (xy 318.057705 -2.116462) (xy 317.980945 -2.07824) (xy 317.908039 -2.033099)
			(xy 317.83961 -1.981423) (xy 317.77624 -1.923654) (xy 317.718471 -1.860284) (xy 317.666795 -1.791855)
			(xy 317.621654 -1.718949) (xy 317.583432 -1.642189) (xy 317.552456 -1.56223) (xy 317.528989 -1.479754)
			(xy 317.513233 -1.395464) (xy 317.505321 -1.310081) (xy 313.010055 -1.310081) (xy 313.002143 -1.395464)
			(xy 312.986387 -1.479754) (xy 312.96292 -1.56223) (xy 312.931944 -1.642189) (xy 312.893722 -1.718949)
			(xy 312.848581 -1.791855) (xy 312.796905 -1.860284) (xy 312.739136 -1.923654) (xy 312.675766 -1.981423)
			(xy 312.607337 -2.033099) (xy 312.534431 -2.07824) (xy 312.457671 -2.116462) (xy 312.377712 -2.147438)
			(xy 312.295236 -2.170905) (xy 312.210946 -2.186661) (xy 312.125563 -2.194573) (xy 312.039813 -2.194573)
			(xy 311.95443 -2.186661) (xy 311.87014 -2.170905) (xy 311.787664 -2.147438) (xy 311.707705 -2.116462)
			(xy 311.630945 -2.07824) (xy 311.558039 -2.033099) (xy 311.48961 -1.981423) (xy 311.42624 -1.923654)
			(xy 311.368471 -1.860284) (xy 311.316795 -1.791855) (xy 311.271654 -1.718949) (xy 311.233432 -1.642189)
			(xy 311.202456 -1.56223) (xy 311.178989 -1.479754) (xy 311.163233 -1.395464) (xy 311.155321 -1.310081)
			(xy 304.348655 -1.310081) (xy 304.340743 -1.395464) (xy 304.324987 -1.479754) (xy 304.30152 -1.56223)
			(xy 304.270544 -1.642189) (xy 304.232322 -1.718949) (xy 304.187181 -1.791855) (xy 304.135505 -1.860284)
			(xy 304.077736 -1.923654) (xy 304.014366 -1.981423) (xy 303.945937 -2.033099) (xy 303.873031 -2.07824)
			(xy 303.796271 -2.116462) (xy 303.716312 -2.147438) (xy 303.633836 -2.170905) (xy 303.549546 -2.186661)
			(xy 303.464163 -2.194573) (xy 303.378413 -2.194573) (xy 303.29303 -2.186661) (xy 303.20874 -2.170905)
			(xy 303.126264 -2.147438) (xy 303.046305 -2.116462) (xy 302.969545 -2.07824) (xy 302.896639 -2.033099)
			(xy 302.82821 -1.981423) (xy 302.76484 -1.923654) (xy 302.707071 -1.860284) (xy 302.655395 -1.791855)
			(xy 302.610254 -1.718949) (xy 302.572032 -1.642189) (xy 302.541056 -1.56223) (xy 302.517589 -1.479754)
			(xy 302.501833 -1.395464) (xy 302.493921 -1.310081) (xy 297.998655 -1.310081) (xy 297.990743 -1.395464)
			(xy 297.974987 -1.479754) (xy 297.95152 -1.56223) (xy 297.920544 -1.642189) (xy 297.882322 -1.718949)
			(xy 297.837181 -1.791855) (xy 297.785505 -1.860284) (xy 297.727736 -1.923654) (xy 297.664366 -1.981423)
			(xy 297.595937 -2.033099) (xy 297.523031 -2.07824) (xy 297.446271 -2.116462) (xy 297.366312 -2.147438)
			(xy 297.283836 -2.170905) (xy 297.199546 -2.186661) (xy 297.114163 -2.194573) (xy 297.028413 -2.194573)
			(xy 296.94303 -2.186661) (xy 296.85874 -2.170905) (xy 296.776264 -2.147438) (xy 296.696305 -2.116462)
			(xy 296.619545 -2.07824) (xy 296.546639 -2.033099) (xy 296.47821 -1.981423) (xy 296.41484 -1.923654)
			(xy 296.357071 -1.860284) (xy 296.305395 -1.791855) (xy 296.260254 -1.718949) (xy 296.222032 -1.642189)
			(xy 296.191056 -1.56223) (xy 296.167589 -1.479754) (xy 296.151833 -1.395464) (xy 296.143921 -1.310081)
			(xy 216.865975 -1.310081) (xy 216.858063 -1.395464) (xy 216.842307 -1.479754) (xy 216.81884 -1.56223)
			(xy 216.787864 -1.642189) (xy 216.749642 -1.718949) (xy 216.704501 -1.791855) (xy 216.652825 -1.860284)
			(xy 216.595056 -1.923654) (xy 216.531686 -1.981423) (xy 216.463257 -2.033099) (xy 216.390351 -2.07824)
			(xy 216.313591 -2.116462) (xy 216.233632 -2.147438) (xy 216.151156 -2.170905) (xy 216.066866 -2.186661)
			(xy 215.981483 -2.194573) (xy 215.895733 -2.194573) (xy 215.81035 -2.186661) (xy 215.72606 -2.170905)
			(xy 215.643584 -2.147438) (xy 215.563625 -2.116462) (xy 215.486865 -2.07824) (xy 215.413959 -2.033099)
			(xy 215.34553 -1.981423) (xy 215.28216 -1.923654) (xy 215.224391 -1.860284) (xy 215.172715 -1.791855)
			(xy 215.127574 -1.718949) (xy 215.089352 -1.642189) (xy 215.058376 -1.56223) (xy 215.034909 -1.479754)
			(xy 215.019153 -1.395464) (xy 215.011241 -1.310081) (xy 210.515975 -1.310081) (xy 210.508063 -1.395464)
			(xy 210.492307 -1.479754) (xy 210.46884 -1.56223) (xy 210.437864 -1.642189) (xy 210.399642 -1.718949)
			(xy 210.354501 -1.791855) (xy 210.302825 -1.860284) (xy 210.245056 -1.923654) (xy 210.181686 -1.981423)
			(xy 210.113257 -2.033099) (xy 210.040351 -2.07824) (xy 209.963591 -2.116462) (xy 209.883632 -2.147438)
			(xy 209.801156 -2.170905) (xy 209.716866 -2.186661) (xy 209.631483 -2.194573) (xy 209.545733 -2.194573)
			(xy 209.46035 -2.186661) (xy 209.37606 -2.170905) (xy 209.293584 -2.147438) (xy 209.213625 -2.116462)
			(xy 209.136865 -2.07824) (xy 209.063959 -2.033099) (xy 208.99553 -1.981423) (xy 208.93216 -1.923654)
			(xy 208.874391 -1.860284) (xy 208.822715 -1.791855) (xy 208.777574 -1.718949) (xy 208.739352 -1.642189)
			(xy 208.708376 -1.56223) (xy 208.684909 -1.479754) (xy 208.669153 -1.395464) (xy 208.661241 -1.310081)
			(xy 84.210906 -1.310081) (xy 84.210906 -7.78002) (xy 84.211428 -7.835789) (xy 84.219765 -7.947014)
			(xy 84.23639 -8.057306) (xy 84.26121 -8.166046) (xy 84.294088 -8.272628) (xy 84.334838 -8.376455)
			(xy 84.383233 -8.476947) (xy 84.439002 -8.573541) (xy 84.501834 -8.665697) (xy 84.571376 -8.7529)
			(xy 84.647241 -8.834663) (xy 84.729004 -8.910527) (xy 84.816208 -8.98007) (xy 84.908364 -9.042901)
			(xy 85.004959 -9.09867) (xy 85.10545 -9.147065) (xy 85.209277 -9.187814) (xy 85.315859 -9.220691)
			(xy 85.4246 -9.245511) (xy 85.534892 -9.262136) (xy 85.646117 -9.270472) (xy 85.701886 -9.271) (xy 122.102118 -9.271)
			(xy 122.157887 -9.270478) (xy 122.269113 -9.262141) (xy 122.379404 -9.245517) (xy 122.488145 -9.220696)
			(xy 122.594728 -9.187819) (xy 122.698555 -9.147069) (xy 122.799047 -9.098674) (xy 122.895641 -9.042905)
			(xy 122.987798 -8.980073) (xy 123.075001 -8.910531) (xy 123.156764 -8.834666) (xy 123.232629 -8.752903)
			(xy 123.302172 -8.665699) (xy 123.365004 -8.573543) (xy 123.420773 -8.476948) (xy 123.469168 -8.376457)
			(xy 123.509918 -8.27263) (xy 123.542796 -8.166047) (xy 123.567616 -8.057306) (xy 123.584241 -7.947015)
			(xy 123.592578 -7.835789) (xy 123.593098 -7.78002) (xy 123.593098 -4.879848) (xy 123.593581 -4.809465)
			(xy 123.601472 -4.66892) (xy 123.61723 -4.529038) (xy 123.640807 -4.39026) (xy 123.672128 -4.253022)
			(xy 123.711095 -4.117757) (xy 123.757586 -3.984889) (xy 123.811453 -3.854837) (xy 123.872528 -3.72801)
			(xy 123.940618 -3.604807) (xy 124.015509 -3.485616) (xy 124.096965 -3.370811) (xy 124.184731 -3.260755)
			(xy 124.278529 -3.155793) (xy 124.378065 -3.056255) (xy 124.483026 -2.962455) (xy 124.593081 -2.874688)
			(xy 124.707884 -2.79323) (xy 124.827074 -2.718337) (xy 124.950276 -2.650245) (xy 125.077102 -2.589169)
			(xy 125.207153 -2.535299) (xy 125.340021 -2.488807) (xy 125.475285 -2.449838) (xy 125.612523 -2.418514)
			(xy 125.7513 -2.394935) (xy 125.891182 -2.379175) (xy 126.031727 -2.371282) (xy 126.10211 -2.370836)
			(xy 194.701922 -2.370836) (xy 194.772304 -2.371321) (xy 194.912845 -2.379215) (xy 195.052723 -2.394977)
			(xy 195.191497 -2.418557) (xy 195.328731 -2.449881) (xy 195.463992 -2.488851) (xy 195.596856 -2.535344)
			(xy 195.726904 -2.589213) (xy 195.853726 -2.650289) (xy 195.976925 -2.71838) (xy 196.096111 -2.793273)
			(xy 196.210911 -2.87473) (xy 196.320963 -2.962495) (xy 196.425921 -3.056294) (xy 196.525454 -3.15583)
			(xy 196.61925 -3.26079) (xy 196.707012 -3.370845) (xy 196.788466 -3.485647) (xy 196.863355 -3.604836)
			(xy 196.931443 -3.728036) (xy 196.990215 -3.850081) (xy 208.661241 -3.850081) (xy 208.661241 -3.764331)
			(xy 208.669153 -3.678948) (xy 208.684909 -3.594658) (xy 208.708376 -3.512182) (xy 208.739352 -3.432223)
			(xy 208.777574 -3.355463) (xy 208.822715 -3.282557) (xy 208.874391 -3.214128) (xy 208.93216 -3.150758)
			(xy 208.99553 -3.092989) (xy 209.063959 -3.041313) (xy 209.136865 -2.996172) (xy 209.213625 -2.95795)
			(xy 209.293584 -2.926974) (xy 209.37606 -2.903507) (xy 209.46035 -2.887751) (xy 209.545733 -2.879839)
			(xy 209.631483 -2.879839) (xy 209.716866 -2.887751) (xy 209.801156 -2.903507) (xy 209.883632 -2.926974)
			(xy 209.963591 -2.95795) (xy 209.984264 -2.968244) (xy 213.517988 -2.968244) (xy 213.517988 -2.104644)
			(xy 213.518492 -2.07509) (xy 213.526541 -2.016534) (xy 213.542487 -1.959619) (xy 213.566036 -1.905405)
			(xy 213.596747 -1.854902) (xy 213.634049 -1.809052) (xy 213.677246 -1.768709) (xy 213.725535 -1.734623)
			(xy 213.778015 -1.70743) (xy 213.83371 -1.687636) (xy 213.891581 -1.67561) (xy 213.95055 -1.671577)
			(xy 214.009519 -1.67561) (xy 214.06739 -1.687636) (xy 214.123085 -1.70743) (xy 214.175565 -1.734623)
			(xy 214.223854 -1.768709) (xy 214.267051 -1.809052) (xy 214.304353 -1.854902) (xy 214.335064 -1.905405)
			(xy 214.358613 -1.959619) (xy 214.374559 -2.016534) (xy 214.382608 -2.07509) (xy 214.383112 -2.104644)
			(xy 214.383112 -2.968244) (xy 214.382608 -2.997798) (xy 214.374559 -3.056354) (xy 214.358613 -3.113269)
			(xy 214.335064 -3.167483) (xy 214.304353 -3.217986) (xy 214.267051 -3.263836) (xy 214.223854 -3.304179)
			(xy 214.175565 -3.338265) (xy 214.123085 -3.365458) (xy 214.06739 -3.385252) (xy 214.009519 -3.397278)
			(xy 213.95055 -3.401312) (xy 213.891581 -3.397278) (xy 213.83371 -3.385252) (xy 213.778015 -3.365458)
			(xy 213.725535 -3.338265) (xy 213.677246 -3.304179) (xy 213.634049 -3.263836) (xy 213.596747 -3.217986)
			(xy 213.566036 -3.167483) (xy 213.542487 -3.113269) (xy 213.526541 -3.056354) (xy 213.518492 -2.997798)
			(xy 213.517988 -2.968244) (xy 209.984264 -2.968244) (xy 210.040351 -2.996172) (xy 210.113257 -3.041313)
			(xy 210.181686 -3.092989) (xy 210.245056 -3.150758) (xy 210.302825 -3.214128) (xy 210.354501 -3.282557)
			(xy 210.399642 -3.355463) (xy 210.437864 -3.432223) (xy 210.46884 -3.512182) (xy 210.492307 -3.594658)
			(xy 210.508063 -3.678948) (xy 210.515975 -3.764331) (xy 210.51647 -3.807206) (xy 210.515975 -3.850081)
			(xy 215.011241 -3.850081) (xy 215.011241 -3.764331) (xy 215.019153 -3.678948) (xy 215.034909 -3.594658)
			(xy 215.058376 -3.512182) (xy 215.089352 -3.432223) (xy 215.127574 -3.355463) (xy 215.172715 -3.282557)
			(xy 215.224391 -3.214128) (xy 215.28216 -3.150758) (xy 215.34553 -3.092989) (xy 215.413959 -3.041313)
			(xy 215.486865 -2.996172) (xy 215.563625 -2.95795) (xy 215.643584 -2.926974) (xy 215.72606 -2.903507)
			(xy 215.81035 -2.887751) (xy 215.895733 -2.879839) (xy 215.981483 -2.879839) (xy 216.066866 -2.887751)
			(xy 216.151156 -2.903507) (xy 216.233632 -2.926974) (xy 216.313591 -2.95795) (xy 216.390351 -2.996172)
			(xy 216.463257 -3.041313) (xy 216.531686 -3.092989) (xy 216.595056 -3.150758) (xy 216.652825 -3.214128)
			(xy 216.704501 -3.282557) (xy 216.749642 -3.355463) (xy 216.787864 -3.432223) (xy 216.81884 -3.512182)
			(xy 216.842307 -3.594658) (xy 216.858063 -3.678948) (xy 216.865975 -3.764331) (xy 216.86647 -3.807206)
			(xy 216.865975 -3.850081) (xy 296.143921 -3.850081) (xy 296.143921 -3.764331) (xy 296.151833 -3.678948)
			(xy 296.167589 -3.594658) (xy 296.191056 -3.512182) (xy 296.222032 -3.432223) (xy 296.260254 -3.355463)
			(xy 296.305395 -3.282557) (xy 296.357071 -3.214128) (xy 296.41484 -3.150758) (xy 296.47821 -3.092989)
			(xy 296.546639 -3.041313) (xy 296.619545 -2.996172) (xy 296.696305 -2.95795) (xy 296.776264 -2.926974)
			(xy 296.85874 -2.903507) (xy 296.94303 -2.887751) (xy 297.028413 -2.879839) (xy 297.114163 -2.879839)
			(xy 297.199546 -2.887751) (xy 297.283836 -2.903507) (xy 297.366312 -2.926974) (xy 297.446271 -2.95795)
			(xy 297.466944 -2.968244) (xy 298.629324 -2.968244) (xy 298.629324 -2.104644) (xy 298.629828 -2.07509)
			(xy 298.637877 -2.016534) (xy 298.653823 -1.959619) (xy 298.677372 -1.905405) (xy 298.708083 -1.854902)
			(xy 298.745385 -1.809052) (xy 298.788582 -1.768709) (xy 298.836871 -1.734623) (xy 298.889351 -1.70743)
			(xy 298.945046 -1.687636) (xy 299.002917 -1.67561) (xy 299.061886 -1.671577) (xy 299.120855 -1.67561)
			(xy 299.178726 -1.687636) (xy 299.234421 -1.70743) (xy 299.286901 -1.734623) (xy 299.33519 -1.768709)
			(xy 299.378387 -1.809052) (xy 299.415689 -1.854902) (xy 299.4464 -1.905405) (xy 299.469949 -1.959619)
			(xy 299.485895 -2.016534) (xy 299.493944 -2.07509) (xy 299.494448 -2.104644) (xy 299.494448 -2.968244)
			(xy 299.493944 -2.997798) (xy 299.485895 -3.056354) (xy 299.469949 -3.113269) (xy 299.4464 -3.167483)
			(xy 299.415689 -3.217986) (xy 299.378387 -3.263836) (xy 299.33519 -3.304179) (xy 299.286901 -3.338265)
			(xy 299.234421 -3.365458) (xy 299.178726 -3.385252) (xy 299.120855 -3.397278) (xy 299.061886 -3.401312)
			(xy 299.002917 -3.397278) (xy 298.945046 -3.385252) (xy 298.889351 -3.365458) (xy 298.836871 -3.338265)
			(xy 298.788582 -3.304179) (xy 298.745385 -3.263836) (xy 298.708083 -3.217986) (xy 298.677372 -3.167483)
			(xy 298.653823 -3.113269) (xy 298.637877 -3.056354) (xy 298.629828 -2.997798) (xy 298.629324 -2.968244)
			(xy 297.466944 -2.968244) (xy 297.523031 -2.996172) (xy 297.595937 -3.041313) (xy 297.664366 -3.092989)
			(xy 297.727736 -3.150758) (xy 297.785505 -3.214128) (xy 297.837181 -3.282557) (xy 297.882322 -3.355463)
			(xy 297.920544 -3.432223) (xy 297.95152 -3.512182) (xy 297.974987 -3.594658) (xy 297.990743 -3.678948)
			(xy 297.998655 -3.764331) (xy 297.99915 -3.807206) (xy 297.998655 -3.850081) (xy 302.493921 -3.850081)
			(xy 302.493921 -3.764331) (xy 302.501833 -3.678948) (xy 302.517589 -3.594658) (xy 302.541056 -3.512182)
			(xy 302.572032 -3.432223) (xy 302.610254 -3.355463) (xy 302.655395 -3.282557) (xy 302.707071 -3.214128)
			(xy 302.76484 -3.150758) (xy 302.82821 -3.092989) (xy 302.896639 -3.041313) (xy 302.969545 -2.996172)
			(xy 303.046305 -2.95795) (xy 303.126264 -2.926974) (xy 303.20874 -2.903507) (xy 303.29303 -2.887751)
			(xy 303.378413 -2.879839) (xy 303.464163 -2.879839) (xy 303.549546 -2.887751) (xy 303.633836 -2.903507)
			(xy 303.716312 -2.926974) (xy 303.796271 -2.95795) (xy 303.873031 -2.996172) (xy 303.945937 -3.041313)
			(xy 304.014366 -3.092989) (xy 304.077736 -3.150758) (xy 304.135505 -3.214128) (xy 304.187181 -3.282557)
			(xy 304.232322 -3.355463) (xy 304.270544 -3.432223) (xy 304.30152 -3.512182) (xy 304.324987 -3.594658)
			(xy 304.340743 -3.678948) (xy 304.348655 -3.764331) (xy 304.34915 -3.807206) (xy 304.348655 -3.850081)
			(xy 311.155321 -3.850081) (xy 311.155321 -3.764331) (xy 311.163233 -3.678948) (xy 311.178989 -3.594658)
			(xy 311.202456 -3.512182) (xy 311.233432 -3.432223) (xy 311.271654 -3.355463) (xy 311.316795 -3.282557)
			(xy 311.368471 -3.214128) (xy 311.42624 -3.150758) (xy 311.48961 -3.092989) (xy 311.558039 -3.041313)
			(xy 311.630945 -2.996172) (xy 311.707705 -2.95795) (xy 311.787664 -2.926974) (xy 311.87014 -2.903507)
			(xy 311.95443 -2.887751) (xy 312.039813 -2.879839) (xy 312.125563 -2.879839) (xy 312.210946 -2.887751)
			(xy 312.295236 -2.903507) (xy 312.377712 -2.926974) (xy 312.457671 -2.95795) (xy 312.478344 -2.968244)
			(xy 316.012068 -2.968244) (xy 316.012068 -2.104644) (xy 316.012572 -2.07509) (xy 316.020621 -2.016534)
			(xy 316.036567 -1.959619) (xy 316.060116 -1.905405) (xy 316.090827 -1.854902) (xy 316.128129 -1.809052)
			(xy 316.171326 -1.768709) (xy 316.219615 -1.734623) (xy 316.272095 -1.70743) (xy 316.32779 -1.687636)
			(xy 316.385661 -1.67561) (xy 316.44463 -1.671577) (xy 316.503599 -1.67561) (xy 316.56147 -1.687636)
			(xy 316.617165 -1.70743) (xy 316.669645 -1.734623) (xy 316.717934 -1.768709) (xy 316.761131 -1.809052)
			(xy 316.798433 -1.854902) (xy 316.829144 -1.905405) (xy 316.852693 -1.959619) (xy 316.868639 -2.016534)
			(xy 316.876688 -2.07509) (xy 316.877192 -2.104644) (xy 316.877192 -2.968244) (xy 316.876688 -2.997798)
			(xy 316.868639 -3.056354) (xy 316.852693 -3.113269) (xy 316.829144 -3.167483) (xy 316.798433 -3.217986)
			(xy 316.761131 -3.263836) (xy 316.717934 -3.304179) (xy 316.669645 -3.338265) (xy 316.617165 -3.365458)
			(xy 316.56147 -3.385252) (xy 316.503599 -3.397278) (xy 316.44463 -3.401312) (xy 316.385661 -3.397278)
			(xy 316.32779 -3.385252) (xy 316.272095 -3.365458) (xy 316.219615 -3.338265) (xy 316.171326 -3.304179)
			(xy 316.128129 -3.263836) (xy 316.090827 -3.217986) (xy 316.060116 -3.167483) (xy 316.036567 -3.113269)
			(xy 316.020621 -3.056354) (xy 316.012572 -2.997798) (xy 316.012068 -2.968244) (xy 312.478344 -2.968244)
			(xy 312.534431 -2.996172) (xy 312.607337 -3.041313) (xy 312.675766 -3.092989) (xy 312.739136 -3.150758)
			(xy 312.796905 -3.214128) (xy 312.848581 -3.282557) (xy 312.893722 -3.355463) (xy 312.931944 -3.432223)
			(xy 312.96292 -3.512182) (xy 312.986387 -3.594658) (xy 313.002143 -3.678948) (xy 313.010055 -3.764331)
			(xy 313.01055 -3.807206) (xy 313.010055 -3.850081) (xy 317.505321 -3.850081) (xy 317.505321 -3.764331)
			(xy 317.513233 -3.678948) (xy 317.528989 -3.594658) (xy 317.552456 -3.512182) (xy 317.583432 -3.432223)
			(xy 317.621654 -3.355463) (xy 317.666795 -3.282557) (xy 317.718471 -3.214128) (xy 317.77624 -3.150758)
			(xy 317.83961 -3.092989) (xy 317.908039 -3.041313) (xy 317.980945 -2.996172) (xy 318.057705 -2.95795)
			(xy 318.137664 -2.926974) (xy 318.22014 -2.903507) (xy 318.30443 -2.887751) (xy 318.389813 -2.879839)
			(xy 318.475563 -2.879839) (xy 318.560946 -2.887751) (xy 318.645236 -2.903507) (xy 318.727712 -2.926974)
			(xy 318.807671 -2.95795) (xy 318.884431 -2.996172) (xy 318.957337 -3.041313) (xy 319.025766 -3.092989)
			(xy 319.089136 -3.150758) (xy 319.146905 -3.214128) (xy 319.198581 -3.282557) (xy 319.243722 -3.355463)
			(xy 319.281944 -3.432223) (xy 319.31292 -3.512182) (xy 319.336387 -3.594658) (xy 319.352143 -3.678948)
			(xy 319.360055 -3.764331) (xy 319.36055 -3.807206) (xy 319.360055 -3.850081) (xy 361.894107 -3.850081)
			(xy 361.894107 -3.764331) (xy 361.902019 -3.678948) (xy 361.917775 -3.594658) (xy 361.941242 -3.512182)
			(xy 361.972218 -3.432223) (xy 362.01044 -3.355463) (xy 362.055581 -3.282557) (xy 362.107257 -3.214128)
			(xy 362.165026 -3.150758) (xy 362.228396 -3.092989) (xy 362.296825 -3.041313) (xy 362.369731 -2.996172)
			(xy 362.446491 -2.95795) (xy 362.52645 -2.926974) (xy 362.608926 -2.903507) (xy 362.693216 -2.887751)
			(xy 362.778599 -2.879839) (xy 362.864349 -2.879839) (xy 362.949732 -2.887751) (xy 363.034022 -2.903507)
			(xy 363.116498 -2.926974) (xy 363.196457 -2.95795) (xy 363.21713 -2.968244) (xy 364.379764 -2.968244)
			(xy 364.379764 -2.104644) (xy 364.380268 -2.075108) (xy 364.388312 -2.016586) (xy 364.404249 -1.959704)
			(xy 364.427784 -1.905522) (xy 364.458477 -1.855049) (xy 364.495757 -1.809226) (xy 364.538929 -1.768906)
			(xy 364.587189 -1.73484) (xy 364.639639 -1.707663) (xy 364.6953 -1.687881) (xy 364.753137 -1.675862)
			(xy 364.812072 -1.671831) (xy 364.871007 -1.675862) (xy 364.928844 -1.687881) (xy 364.984505 -1.707663)
			(xy 365.036955 -1.73484) (xy 365.085215 -1.768906) (xy 365.128387 -1.809226) (xy 365.165667 -1.855049)
			(xy 365.19636 -1.905522) (xy 365.219895 -1.959704) (xy 365.235832 -2.016586) (xy 365.243876 -2.075108)
			(xy 365.24438 -2.104644) (xy 365.24438 -2.968244) (xy 365.243876 -2.99778) (xy 365.235832 -3.056302)
			(xy 365.219895 -3.113184) (xy 365.19636 -3.167366) (xy 365.165667 -3.217839) (xy 365.128387 -3.263662)
			(xy 365.085215 -3.303982) (xy 365.036955 -3.338048) (xy 364.984505 -3.365225) (xy 364.928844 -3.385007)
			(xy 364.871007 -3.397026) (xy 364.812072 -3.401057) (xy 364.753137 -3.397026) (xy 364.6953 -3.385007)
			(xy 364.639639 -3.365225) (xy 364.587189 -3.338048) (xy 364.538929 -3.303982) (xy 364.495757 -3.263662)
			(xy 364.458477 -3.217839) (xy 364.427784 -3.167366) (xy 364.404249 -3.113184) (xy 364.388312 -3.056302)
			(xy 364.380268 -2.99778) (xy 364.379764 -2.968244) (xy 363.21713 -2.968244) (xy 363.273217 -2.996172)
			(xy 363.346123 -3.041313) (xy 363.414552 -3.092989) (xy 363.477922 -3.150758) (xy 363.535691 -3.214128)
			(xy 363.587367 -3.282557) (xy 363.632508 -3.355463) (xy 363.67073 -3.432223) (xy 363.701706 -3.512182)
			(xy 363.725173 -3.594658) (xy 363.740929 -3.678948) (xy 363.748841 -3.764331) (xy 363.749336 -3.807206)
			(xy 363.748841 -3.850081) (xy 368.244107 -3.850081) (xy 368.244107 -3.764331) (xy 368.252019 -3.678948)
			(xy 368.267775 -3.594658) (xy 368.291242 -3.512182) (xy 368.322218 -3.432223) (xy 368.36044 -3.355463)
			(xy 368.405581 -3.282557) (xy 368.457257 -3.214128) (xy 368.515026 -3.150758) (xy 368.578396 -3.092989)
			(xy 368.646825 -3.041313) (xy 368.719731 -2.996172) (xy 368.796491 -2.95795) (xy 368.87645 -2.926974)
			(xy 368.958926 -2.903507) (xy 369.043216 -2.887751) (xy 369.128599 -2.879839) (xy 369.214349 -2.879839)
			(xy 369.299732 -2.887751) (xy 369.384022 -2.903507) (xy 369.466498 -2.926974) (xy 369.546457 -2.95795)
			(xy 369.623217 -2.996172) (xy 369.696123 -3.041313) (xy 369.764552 -3.092989) (xy 369.827922 -3.150758)
			(xy 369.885691 -3.214128) (xy 369.937367 -3.282557) (xy 369.982508 -3.355463) (xy 370.02073 -3.432223)
			(xy 370.051706 -3.512182) (xy 370.075173 -3.594658) (xy 370.090929 -3.678948) (xy 370.098841 -3.764331)
			(xy 370.099336 -3.807206) (xy 370.098841 -3.850081) (xy 370.090929 -3.935464) (xy 370.075173 -4.019754)
			(xy 370.051706 -4.10223) (xy 370.02073 -4.182189) (xy 369.982508 -4.258949) (xy 369.937367 -4.331855)
			(xy 369.885691 -4.400284) (xy 369.827922 -4.463654) (xy 369.764552 -4.521423) (xy 369.696123 -4.573099)
			(xy 369.623217 -4.61824) (xy 369.546457 -4.656462) (xy 369.466498 -4.687438) (xy 369.384022 -4.710905)
			(xy 369.299732 -4.726661) (xy 369.214349 -4.734573) (xy 369.128599 -4.734573) (xy 369.043216 -4.726661)
			(xy 368.958926 -4.710905) (xy 368.87645 -4.687438) (xy 368.796491 -4.656462) (xy 368.719731 -4.61824)
			(xy 368.646825 -4.573099) (xy 368.578396 -4.521423) (xy 368.515026 -4.463654) (xy 368.457257 -4.400284)
			(xy 368.405581 -4.331855) (xy 368.36044 -4.258949) (xy 368.322218 -4.182189) (xy 368.291242 -4.10223)
			(xy 368.267775 -4.019754) (xy 368.252019 -3.935464) (xy 368.244107 -3.850081) (xy 363.748841 -3.850081)
			(xy 363.740929 -3.935464) (xy 363.725173 -4.019754) (xy 363.701706 -4.10223) (xy 363.67073 -4.182189)
			(xy 363.632508 -4.258949) (xy 363.587367 -4.331855) (xy 363.535691 -4.400284) (xy 363.477922 -4.463654)
			(xy 363.414552 -4.521423) (xy 363.346123 -4.573099) (xy 363.273217 -4.61824) (xy 363.196457 -4.656462)
			(xy 363.116498 -4.687438) (xy 363.034022 -4.710905) (xy 362.949732 -4.726661) (xy 362.864349 -4.734573)
			(xy 362.778599 -4.734573) (xy 362.693216 -4.726661) (xy 362.608926 -4.710905) (xy 362.52645 -4.687438)
			(xy 362.446491 -4.656462) (xy 362.369731 -4.61824) (xy 362.296825 -4.573099) (xy 362.228396 -4.521423)
			(xy 362.165026 -4.463654) (xy 362.107257 -4.400284) (xy 362.055581 -4.331855) (xy 362.01044 -4.258949)
			(xy 361.972218 -4.182189) (xy 361.941242 -4.10223) (xy 361.917775 -4.019754) (xy 361.902019 -3.935464)
			(xy 361.894107 -3.850081) (xy 319.360055 -3.850081) (xy 319.352143 -3.935464) (xy 319.336387 -4.019754)
			(xy 319.31292 -4.10223) (xy 319.281944 -4.182189) (xy 319.243722 -4.258949) (xy 319.198581 -4.331855)
			(xy 319.146905 -4.400284) (xy 319.089136 -4.463654) (xy 319.025766 -4.521423) (xy 318.957337 -4.573099)
			(xy 318.884431 -4.61824) (xy 318.807671 -4.656462) (xy 318.727712 -4.687438) (xy 318.645236 -4.710905)
			(xy 318.560946 -4.726661) (xy 318.475563 -4.734573) (xy 318.389813 -4.734573) (xy 318.30443 -4.726661)
			(xy 318.22014 -4.710905) (xy 318.137664 -4.687438) (xy 318.057705 -4.656462) (xy 317.980945 -4.61824)
			(xy 317.908039 -4.573099) (xy 317.83961 -4.521423) (xy 317.77624 -4.463654) (xy 317.718471 -4.400284)
			(xy 317.666795 -4.331855) (xy 317.621654 -4.258949) (xy 317.583432 -4.182189) (xy 317.552456 -4.10223)
			(xy 317.528989 -4.019754) (xy 317.513233 -3.935464) (xy 317.505321 -3.850081) (xy 313.010055 -3.850081)
			(xy 313.002143 -3.935464) (xy 312.986387 -4.019754) (xy 312.96292 -4.10223) (xy 312.931944 -4.182189)
			(xy 312.893722 -4.258949) (xy 312.848581 -4.331855) (xy 312.796905 -4.400284) (xy 312.739136 -4.463654)
			(xy 312.675766 -4.521423) (xy 312.607337 -4.573099) (xy 312.534431 -4.61824) (xy 312.457671 -4.656462)
			(xy 312.377712 -4.687438) (xy 312.295236 -4.710905) (xy 312.210946 -4.726661) (xy 312.125563 -4.734573)
			(xy 312.039813 -4.734573) (xy 311.95443 -4.726661) (xy 311.87014 -4.710905) (xy 311.787664 -4.687438)
			(xy 311.707705 -4.656462) (xy 311.630945 -4.61824) (xy 311.558039 -4.573099) (xy 311.48961 -4.521423)
			(xy 311.42624 -4.463654) (xy 311.368471 -4.400284) (xy 311.316795 -4.331855) (xy 311.271654 -4.258949)
			(xy 311.233432 -4.182189) (xy 311.202456 -4.10223) (xy 311.178989 -4.019754) (xy 311.163233 -3.935464)
			(xy 311.155321 -3.850081) (xy 304.348655 -3.850081) (xy 304.340743 -3.935464) (xy 304.324987 -4.019754)
			(xy 304.30152 -4.10223) (xy 304.270544 -4.182189) (xy 304.232322 -4.258949) (xy 304.187181 -4.331855)
			(xy 304.135505 -4.400284) (xy 304.077736 -4.463654) (xy 304.014366 -4.521423) (xy 303.945937 -4.573099)
			(xy 303.873031 -4.61824) (xy 303.796271 -4.656462) (xy 303.716312 -4.687438) (xy 303.633836 -4.710905)
			(xy 303.549546 -4.726661) (xy 303.464163 -4.734573) (xy 303.378413 -4.734573) (xy 303.29303 -4.726661)
			(xy 303.20874 -4.710905) (xy 303.126264 -4.687438) (xy 303.046305 -4.656462) (xy 302.969545 -4.61824)
			(xy 302.896639 -4.573099) (xy 302.82821 -4.521423) (xy 302.76484 -4.463654) (xy 302.707071 -4.400284)
			(xy 302.655395 -4.331855) (xy 302.610254 -4.258949) (xy 302.572032 -4.182189) (xy 302.541056 -4.10223)
			(xy 302.517589 -4.019754) (xy 302.501833 -3.935464) (xy 302.493921 -3.850081) (xy 297.998655 -3.850081)
			(xy 297.990743 -3.935464) (xy 297.974987 -4.019754) (xy 297.95152 -4.10223) (xy 297.920544 -4.182189)
			(xy 297.882322 -4.258949) (xy 297.837181 -4.331855) (xy 297.785505 -4.400284) (xy 297.727736 -4.463654)
			(xy 297.664366 -4.521423) (xy 297.595937 -4.573099) (xy 297.523031 -4.61824) (xy 297.446271 -4.656462)
			(xy 297.366312 -4.687438) (xy 297.283836 -4.710905) (xy 297.199546 -4.726661) (xy 297.114163 -4.734573)
			(xy 297.028413 -4.734573) (xy 296.94303 -4.726661) (xy 296.85874 -4.710905) (xy 296.776264 -4.687438)
			(xy 296.696305 -4.656462) (xy 296.619545 -4.61824) (xy 296.546639 -4.573099) (xy 296.47821 -4.521423)
			(xy 296.41484 -4.463654) (xy 296.357071 -4.400284) (xy 296.305395 -4.331855) (xy 296.260254 -4.258949)
			(xy 296.222032 -4.182189) (xy 296.191056 -4.10223) (xy 296.167589 -4.019754) (xy 296.151833 -3.935464)
			(xy 296.143921 -3.850081) (xy 216.865975 -3.850081) (xy 216.858063 -3.935464) (xy 216.842307 -4.019754)
			(xy 216.81884 -4.10223) (xy 216.787864 -4.182189) (xy 216.749642 -4.258949) (xy 216.704501 -4.331855)
			(xy 216.652825 -4.400284) (xy 216.595056 -4.463654) (xy 216.531686 -4.521423) (xy 216.463257 -4.573099)
			(xy 216.390351 -4.61824) (xy 216.313591 -4.656462) (xy 216.233632 -4.687438) (xy 216.151156 -4.710905)
			(xy 216.066866 -4.726661) (xy 215.981483 -4.734573) (xy 215.895733 -4.734573) (xy 215.81035 -4.726661)
			(xy 215.72606 -4.710905) (xy 215.643584 -4.687438) (xy 215.563625 -4.656462) (xy 215.486865 -4.61824)
			(xy 215.413959 -4.573099) (xy 215.34553 -4.521423) (xy 215.28216 -4.463654) (xy 215.224391 -4.400284)
			(xy 215.172715 -4.331855) (xy 215.127574 -4.258949) (xy 215.089352 -4.182189) (xy 215.058376 -4.10223)
			(xy 215.034909 -4.019754) (xy 215.019153 -3.935464) (xy 215.011241 -3.850081) (xy 210.515975 -3.850081)
			(xy 210.508063 -3.935464) (xy 210.492307 -4.019754) (xy 210.46884 -4.10223) (xy 210.437864 -4.182189)
			(xy 210.399642 -4.258949) (xy 210.354501 -4.331855) (xy 210.302825 -4.400284) (xy 210.245056 -4.463654)
			(xy 210.181686 -4.521423) (xy 210.113257 -4.573099) (xy 210.040351 -4.61824) (xy 209.963591 -4.656462)
			(xy 209.883632 -4.687438) (xy 209.801156 -4.710905) (xy 209.716866 -4.726661) (xy 209.631483 -4.734573)
			(xy 209.545733 -4.734573) (xy 209.46035 -4.726661) (xy 209.37606 -4.710905) (xy 209.293584 -4.687438)
			(xy 209.213625 -4.656462) (xy 209.136865 -4.61824) (xy 209.063959 -4.573099) (xy 208.99553 -4.521423)
			(xy 208.93216 -4.463654) (xy 208.874391 -4.400284) (xy 208.822715 -4.331855) (xy 208.777574 -4.258949)
			(xy 208.739352 -4.182189) (xy 208.708376 -4.10223) (xy 208.684909 -4.019754) (xy 208.669153 -3.935464)
			(xy 208.661241 -3.850081) (xy 196.990215 -3.850081) (xy 196.992516 -3.85486) (xy 197.046381 -3.984909)
			(xy 197.09287 -4.117774) (xy 197.131836 -4.253037) (xy 197.163157 -4.390271) (xy 197.186733 -4.529046)
			(xy 197.202491 -4.668924) (xy 197.210381 -4.809466) (xy 197.210934 -4.879848) (xy 197.210934 -6.390081)
			(xy 208.661241 -6.390081) (xy 208.661241 -6.304331) (xy 208.669153 -6.218948) (xy 208.684909 -6.134658)
			(xy 208.708376 -6.052182) (xy 208.739352 -5.972223) (xy 208.777574 -5.895463) (xy 208.822715 -5.822557)
			(xy 208.874391 -5.754128) (xy 208.93216 -5.690758) (xy 208.99553 -5.632989) (xy 209.063959 -5.581313)
			(xy 209.136865 -5.536172) (xy 209.213625 -5.49795) (xy 209.293584 -5.466974) (xy 209.37606 -5.443507)
			(xy 209.46035 -5.427751) (xy 209.545733 -5.419839) (xy 209.631483 -5.419839) (xy 209.716866 -5.427751)
			(xy 209.801156 -5.443507) (xy 209.883632 -5.466974) (xy 209.963591 -5.49795) (xy 209.984264 -5.508244)
			(xy 213.517988 -5.508244) (xy 213.517988 -4.644644) (xy 213.518492 -4.61509) (xy 213.526541 -4.556534)
			(xy 213.542487 -4.499619) (xy 213.566036 -4.445405) (xy 213.596747 -4.394902) (xy 213.634049 -4.349052)
			(xy 213.677246 -4.308709) (xy 213.725535 -4.274623) (xy 213.778015 -4.24743) (xy 213.83371 -4.227636)
			(xy 213.891581 -4.21561) (xy 213.95055 -4.211577) (xy 214.009519 -4.21561) (xy 214.06739 -4.227636)
			(xy 214.123085 -4.24743) (xy 214.175565 -4.274623) (xy 214.223854 -4.308709) (xy 214.267051 -4.349052)
			(xy 214.304353 -4.394902) (xy 214.335064 -4.445405) (xy 214.358613 -4.499619) (xy 214.374559 -4.556534)
			(xy 214.382608 -4.61509) (xy 214.383112 -4.644644) (xy 214.383112 -5.508244) (xy 214.382608 -5.537798)
			(xy 214.374559 -5.596354) (xy 214.358613 -5.653269) (xy 214.335064 -5.707483) (xy 214.304353 -5.757986)
			(xy 214.267051 -5.803836) (xy 214.223854 -5.844179) (xy 214.175565 -5.878265) (xy 214.123085 -5.905458)
			(xy 214.06739 -5.925252) (xy 214.009519 -5.937278) (xy 213.95055 -5.941312) (xy 213.891581 -5.937278)
			(xy 213.83371 -5.925252) (xy 213.778015 -5.905458) (xy 213.725535 -5.878265) (xy 213.677246 -5.844179)
			(xy 213.634049 -5.803836) (xy 213.596747 -5.757986) (xy 213.566036 -5.707483) (xy 213.542487 -5.653269)
			(xy 213.526541 -5.596354) (xy 213.518492 -5.537798) (xy 213.517988 -5.508244) (xy 209.984264 -5.508244)
			(xy 210.040351 -5.536172) (xy 210.113257 -5.581313) (xy 210.181686 -5.632989) (xy 210.245056 -5.690758)
			(xy 210.302825 -5.754128) (xy 210.354501 -5.822557) (xy 210.399642 -5.895463) (xy 210.437864 -5.972223)
			(xy 210.46884 -6.052182) (xy 210.492307 -6.134658) (xy 210.508063 -6.218948) (xy 210.515975 -6.304331)
			(xy 210.51647 -6.347206) (xy 210.515975 -6.390081) (xy 215.011241 -6.390081) (xy 215.011241 -6.304331)
			(xy 215.019153 -6.218948) (xy 215.034909 -6.134658) (xy 215.058376 -6.052182) (xy 215.089352 -5.972223)
			(xy 215.127574 -5.895463) (xy 215.172715 -5.822557) (xy 215.224391 -5.754128) (xy 215.28216 -5.690758)
			(xy 215.34553 -5.632989) (xy 215.413959 -5.581313) (xy 215.486865 -5.536172) (xy 215.563625 -5.49795)
			(xy 215.643584 -5.466974) (xy 215.72606 -5.443507) (xy 215.81035 -5.427751) (xy 215.895733 -5.419839)
			(xy 215.981483 -5.419839) (xy 216.066866 -5.427751) (xy 216.151156 -5.443507) (xy 216.233632 -5.466974)
			(xy 216.313591 -5.49795) (xy 216.390351 -5.536172) (xy 216.463257 -5.581313) (xy 216.531686 -5.632989)
			(xy 216.595056 -5.690758) (xy 216.652825 -5.754128) (xy 216.704501 -5.822557) (xy 216.749642 -5.895463)
			(xy 216.787864 -5.972223) (xy 216.81884 -6.052182) (xy 216.842307 -6.134658) (xy 216.858063 -6.218948)
			(xy 216.865975 -6.304331) (xy 216.86647 -6.347206) (xy 216.865975 -6.390081) (xy 296.143921 -6.390081)
			(xy 296.143921 -6.304331) (xy 296.151833 -6.218948) (xy 296.167589 -6.134658) (xy 296.191056 -6.052182)
			(xy 296.222032 -5.972223) (xy 296.260254 -5.895463) (xy 296.305395 -5.822557) (xy 296.357071 -5.754128)
			(xy 296.41484 -5.690758) (xy 296.47821 -5.632989) (xy 296.546639 -5.581313) (xy 296.619545 -5.536172)
			(xy 296.696305 -5.49795) (xy 296.776264 -5.466974) (xy 296.85874 -5.443507) (xy 296.94303 -5.427751)
			(xy 297.028413 -5.419839) (xy 297.114163 -5.419839) (xy 297.199546 -5.427751) (xy 297.283836 -5.443507)
			(xy 297.366312 -5.466974) (xy 297.446271 -5.49795) (xy 297.466944 -5.508244) (xy 298.629324 -5.508244)
			(xy 298.629324 -4.644644) (xy 298.629828 -4.61509) (xy 298.637877 -4.556534) (xy 298.653823 -4.499619)
			(xy 298.677372 -4.445405) (xy 298.708083 -4.394902) (xy 298.745385 -4.349052) (xy 298.788582 -4.308709)
			(xy 298.836871 -4.274623) (xy 298.889351 -4.24743) (xy 298.945046 -4.227636) (xy 299.002917 -4.21561)
			(xy 299.061886 -4.211577) (xy 299.120855 -4.21561) (xy 299.178726 -4.227636) (xy 299.234421 -4.24743)
			(xy 299.286901 -4.274623) (xy 299.33519 -4.308709) (xy 299.378387 -4.349052) (xy 299.415689 -4.394902)
			(xy 299.4464 -4.445405) (xy 299.469949 -4.499619) (xy 299.485895 -4.556534) (xy 299.493944 -4.61509)
			(xy 299.494448 -4.644644) (xy 299.494448 -5.508244) (xy 299.493944 -5.537798) (xy 299.485895 -5.596354)
			(xy 299.469949 -5.653269) (xy 299.4464 -5.707483) (xy 299.415689 -5.757986) (xy 299.378387 -5.803836)
			(xy 299.33519 -5.844179) (xy 299.286901 -5.878265) (xy 299.234421 -5.905458) (xy 299.178726 -5.925252)
			(xy 299.120855 -5.937278) (xy 299.061886 -5.941312) (xy 299.002917 -5.937278) (xy 298.945046 -5.925252)
			(xy 298.889351 -5.905458) (xy 298.836871 -5.878265) (xy 298.788582 -5.844179) (xy 298.745385 -5.803836)
			(xy 298.708083 -5.757986) (xy 298.677372 -5.707483) (xy 298.653823 -5.653269) (xy 298.637877 -5.596354)
			(xy 298.629828 -5.537798) (xy 298.629324 -5.508244) (xy 297.466944 -5.508244) (xy 297.523031 -5.536172)
			(xy 297.595937 -5.581313) (xy 297.664366 -5.632989) (xy 297.727736 -5.690758) (xy 297.785505 -5.754128)
			(xy 297.837181 -5.822557) (xy 297.882322 -5.895463) (xy 297.920544 -5.972223) (xy 297.95152 -6.052182)
			(xy 297.974987 -6.134658) (xy 297.990743 -6.218948) (xy 297.998655 -6.304331) (xy 297.99915 -6.347206)
			(xy 297.998655 -6.390081) (xy 302.493921 -6.390081) (xy 302.493921 -6.304331) (xy 302.501833 -6.218948)
			(xy 302.517589 -6.134658) (xy 302.541056 -6.052182) (xy 302.572032 -5.972223) (xy 302.610254 -5.895463)
			(xy 302.655395 -5.822557) (xy 302.707071 -5.754128) (xy 302.76484 -5.690758) (xy 302.82821 -5.632989)
			(xy 302.896639 -5.581313) (xy 302.969545 -5.536172) (xy 303.046305 -5.49795) (xy 303.126264 -5.466974)
			(xy 303.20874 -5.443507) (xy 303.29303 -5.427751) (xy 303.378413 -5.419839) (xy 303.464163 -5.419839)
			(xy 303.549546 -5.427751) (xy 303.633836 -5.443507) (xy 303.716312 -5.466974) (xy 303.796271 -5.49795)
			(xy 303.873031 -5.536172) (xy 303.945937 -5.581313) (xy 304.014366 -5.632989) (xy 304.077736 -5.690758)
			(xy 304.135505 -5.754128) (xy 304.187181 -5.822557) (xy 304.232322 -5.895463) (xy 304.270544 -5.972223)
			(xy 304.30152 -6.052182) (xy 304.324987 -6.134658) (xy 304.340743 -6.218948) (xy 304.348655 -6.304331)
			(xy 304.34915 -6.347206) (xy 304.348655 -6.390081) (xy 311.155321 -6.390081) (xy 311.155321 -6.304331)
			(xy 311.163233 -6.218948) (xy 311.178989 -6.134658) (xy 311.202456 -6.052182) (xy 311.233432 -5.972223)
			(xy 311.271654 -5.895463) (xy 311.316795 -5.822557) (xy 311.368471 -5.754128) (xy 311.42624 -5.690758)
			(xy 311.48961 -5.632989) (xy 311.558039 -5.581313) (xy 311.630945 -5.536172) (xy 311.707705 -5.49795)
			(xy 311.787664 -5.466974) (xy 311.87014 -5.443507) (xy 311.95443 -5.427751) (xy 312.039813 -5.419839)
			(xy 312.125563 -5.419839) (xy 312.210946 -5.427751) (xy 312.295236 -5.443507) (xy 312.377712 -5.466974)
			(xy 312.457671 -5.49795) (xy 312.534431 -5.536172) (xy 312.607337 -5.581313) (xy 312.675766 -5.632989)
			(xy 312.739136 -5.690758) (xy 312.796905 -5.754128) (xy 312.848581 -5.822557) (xy 312.893722 -5.895463)
			(xy 312.931944 -5.972223) (xy 312.96292 -6.052182) (xy 312.986387 -6.134658) (xy 313.002143 -6.218948)
			(xy 313.010055 -6.304331) (xy 313.01055 -6.347206) (xy 313.010055 -6.390081) (xy 317.505321 -6.390081)
			(xy 317.505321 -6.304331) (xy 317.513233 -6.218948) (xy 317.528989 -6.134658) (xy 317.552456 -6.052182)
			(xy 317.583432 -5.972223) (xy 317.621654 -5.895463) (xy 317.666795 -5.822557) (xy 317.718471 -5.754128)
			(xy 317.77624 -5.690758) (xy 317.83961 -5.632989) (xy 317.908039 -5.581313) (xy 317.980945 -5.536172)
			(xy 318.057705 -5.49795) (xy 318.137664 -5.466974) (xy 318.22014 -5.443507) (xy 318.30443 -5.427751)
			(xy 318.389813 -5.419839) (xy 318.475563 -5.419839) (xy 318.560946 -5.427751) (xy 318.645236 -5.443507)
			(xy 318.727712 -5.466974) (xy 318.807671 -5.49795) (xy 318.884431 -5.536172) (xy 318.957337 -5.581313)
			(xy 319.025766 -5.632989) (xy 319.089136 -5.690758) (xy 319.146905 -5.754128) (xy 319.198581 -5.822557)
			(xy 319.243722 -5.895463) (xy 319.281944 -5.972223) (xy 319.31292 -6.052182) (xy 319.336387 -6.134658)
			(xy 319.352143 -6.218948) (xy 319.360055 -6.304331) (xy 319.36055 -6.347206) (xy 319.360055 -6.390081)
			(xy 361.894107 -6.390081) (xy 361.894107 -6.304331) (xy 361.902019 -6.218948) (xy 361.917775 -6.134658)
			(xy 361.941242 -6.052182) (xy 361.972218 -5.972223) (xy 362.01044 -5.895463) (xy 362.055581 -5.822557)
			(xy 362.107257 -5.754128) (xy 362.165026 -5.690758) (xy 362.228396 -5.632989) (xy 362.296825 -5.581313)
			(xy 362.369731 -5.536172) (xy 362.446491 -5.49795) (xy 362.52645 -5.466974) (xy 362.608926 -5.443507)
			(xy 362.693216 -5.427751) (xy 362.778599 -5.419839) (xy 362.864349 -5.419839) (xy 362.949732 -5.427751)
			(xy 363.034022 -5.443507) (xy 363.116498 -5.466974) (xy 363.196457 -5.49795) (xy 363.273217 -5.536172)
			(xy 363.346123 -5.581313) (xy 363.414552 -5.632989) (xy 363.477922 -5.690758) (xy 363.535691 -5.754128)
			(xy 363.587367 -5.822557) (xy 363.632508 -5.895463) (xy 363.67073 -5.972223) (xy 363.701706 -6.052182)
			(xy 363.725173 -6.134658) (xy 363.740929 -6.218948) (xy 363.748841 -6.304331) (xy 363.749336 -6.347206)
			(xy 363.748841 -6.390081) (xy 368.244107 -6.390081) (xy 368.244107 -6.304331) (xy 368.252019 -6.218948)
			(xy 368.267775 -6.134658) (xy 368.291242 -6.052182) (xy 368.322218 -5.972223) (xy 368.36044 -5.895463)
			(xy 368.405581 -5.822557) (xy 368.457257 -5.754128) (xy 368.515026 -5.690758) (xy 368.578396 -5.632989)
			(xy 368.646825 -5.581313) (xy 368.719731 -5.536172) (xy 368.796491 -5.49795) (xy 368.87645 -5.466974)
			(xy 368.958926 -5.443507) (xy 369.043216 -5.427751) (xy 369.128599 -5.419839) (xy 369.214349 -5.419839)
			(xy 369.299732 -5.427751) (xy 369.384022 -5.443507) (xy 369.466498 -5.466974) (xy 369.546457 -5.49795)
			(xy 369.623217 -5.536172) (xy 369.696123 -5.581313) (xy 369.764552 -5.632989) (xy 369.827922 -5.690758)
			(xy 369.885691 -5.754128) (xy 369.937367 -5.822557) (xy 369.982508 -5.895463) (xy 370.02073 -5.972223)
			(xy 370.051706 -6.052182) (xy 370.075173 -6.134658) (xy 370.090929 -6.218948) (xy 370.098841 -6.304331)
			(xy 370.099336 -6.347206) (xy 370.098841 -6.390081) (xy 370.090929 -6.475464) (xy 370.075173 -6.559754)
			(xy 370.051706 -6.64223) (xy 370.02073 -6.722189) (xy 369.982508 -6.798949) (xy 369.937367 -6.871855)
			(xy 369.885691 -6.940284) (xy 369.827922 -7.003654) (xy 369.764552 -7.061423) (xy 369.696123 -7.113099)
			(xy 369.623217 -7.15824) (xy 369.546457 -7.196462) (xy 369.466498 -7.227438) (xy 369.384022 -7.250905)
			(xy 369.299732 -7.266661) (xy 369.214349 -7.274573) (xy 369.128599 -7.274573) (xy 369.043216 -7.266661)
			(xy 368.958926 -7.250905) (xy 368.87645 -7.227438) (xy 368.796491 -7.196462) (xy 368.719731 -7.15824)
			(xy 368.646825 -7.113099) (xy 368.578396 -7.061423) (xy 368.515026 -7.003654) (xy 368.457257 -6.940284)
			(xy 368.405581 -6.871855) (xy 368.36044 -6.798949) (xy 368.322218 -6.722189) (xy 368.291242 -6.64223)
			(xy 368.267775 -6.559754) (xy 368.252019 -6.475464) (xy 368.244107 -6.390081) (xy 363.748841 -6.390081)
			(xy 363.740929 -6.475464) (xy 363.725173 -6.559754) (xy 363.701706 -6.64223) (xy 363.67073 -6.722189)
			(xy 363.632508 -6.798949) (xy 363.587367 -6.871855) (xy 363.535691 -6.940284) (xy 363.477922 -7.003654)
			(xy 363.414552 -7.061423) (xy 363.346123 -7.113099) (xy 363.273217 -7.15824) (xy 363.196457 -7.196462)
			(xy 363.116498 -7.227438) (xy 363.034022 -7.250905) (xy 362.949732 -7.266661) (xy 362.864349 -7.274573)
			(xy 362.778599 -7.274573) (xy 362.693216 -7.266661) (xy 362.608926 -7.250905) (xy 362.52645 -7.227438)
			(xy 362.446491 -7.196462) (xy 362.369731 -7.15824) (xy 362.296825 -7.113099) (xy 362.228396 -7.061423)
			(xy 362.165026 -7.003654) (xy 362.107257 -6.940284) (xy 362.055581 -6.871855) (xy 362.01044 -6.798949)
			(xy 361.972218 -6.722189) (xy 361.941242 -6.64223) (xy 361.917775 -6.559754) (xy 361.902019 -6.475464)
			(xy 361.894107 -6.390081) (xy 319.360055 -6.390081) (xy 319.352143 -6.475464) (xy 319.336387 -6.559754)
			(xy 319.31292 -6.64223) (xy 319.281944 -6.722189) (xy 319.243722 -6.798949) (xy 319.198581 -6.871855)
			(xy 319.146905 -6.940284) (xy 319.089136 -7.003654) (xy 319.025766 -7.061423) (xy 318.957337 -7.113099)
			(xy 318.884431 -7.15824) (xy 318.807671 -7.196462) (xy 318.727712 -7.227438) (xy 318.645236 -7.250905)
			(xy 318.560946 -7.266661) (xy 318.475563 -7.274573) (xy 318.389813 -7.274573) (xy 318.30443 -7.266661)
			(xy 318.22014 -7.250905) (xy 318.137664 -7.227438) (xy 318.057705 -7.196462) (xy 317.980945 -7.15824)
			(xy 317.908039 -7.113099) (xy 317.83961 -7.061423) (xy 317.77624 -7.003654) (xy 317.718471 -6.940284)
			(xy 317.666795 -6.871855) (xy 317.621654 -6.798949) (xy 317.583432 -6.722189) (xy 317.552456 -6.64223)
			(xy 317.528989 -6.559754) (xy 317.513233 -6.475464) (xy 317.505321 -6.390081) (xy 313.010055 -6.390081)
			(xy 313.002143 -6.475464) (xy 312.986387 -6.559754) (xy 312.96292 -6.64223) (xy 312.931944 -6.722189)
			(xy 312.893722 -6.798949) (xy 312.848581 -6.871855) (xy 312.796905 -6.940284) (xy 312.739136 -7.003654)
			(xy 312.675766 -7.061423) (xy 312.607337 -7.113099) (xy 312.534431 -7.15824) (xy 312.457671 -7.196462)
			(xy 312.377712 -7.227438) (xy 312.295236 -7.250905) (xy 312.210946 -7.266661) (xy 312.125563 -7.274573)
			(xy 312.039813 -7.274573) (xy 311.95443 -7.266661) (xy 311.87014 -7.250905) (xy 311.787664 -7.227438)
			(xy 311.707705 -7.196462) (xy 311.630945 -7.15824) (xy 311.558039 -7.113099) (xy 311.48961 -7.061423)
			(xy 311.42624 -7.003654) (xy 311.368471 -6.940284) (xy 311.316795 -6.871855) (xy 311.271654 -6.798949)
			(xy 311.233432 -6.722189) (xy 311.202456 -6.64223) (xy 311.178989 -6.559754) (xy 311.163233 -6.475464)
			(xy 311.155321 -6.390081) (xy 304.348655 -6.390081) (xy 304.340743 -6.475464) (xy 304.324987 -6.559754)
			(xy 304.30152 -6.64223) (xy 304.270544 -6.722189) (xy 304.232322 -6.798949) (xy 304.187181 -6.871855)
			(xy 304.135505 -6.940284) (xy 304.077736 -7.003654) (xy 304.014366 -7.061423) (xy 303.945937 -7.113099)
			(xy 303.873031 -7.15824) (xy 303.796271 -7.196462) (xy 303.716312 -7.227438) (xy 303.633836 -7.250905)
			(xy 303.549546 -7.266661) (xy 303.464163 -7.274573) (xy 303.378413 -7.274573) (xy 303.29303 -7.266661)
			(xy 303.20874 -7.250905) (xy 303.126264 -7.227438) (xy 303.046305 -7.196462) (xy 302.969545 -7.15824)
			(xy 302.896639 -7.113099) (xy 302.82821 -7.061423) (xy 302.76484 -7.003654) (xy 302.707071 -6.940284)
			(xy 302.655395 -6.871855) (xy 302.610254 -6.798949) (xy 302.572032 -6.722189) (xy 302.541056 -6.64223)
			(xy 302.517589 -6.559754) (xy 302.501833 -6.475464) (xy 302.493921 -6.390081) (xy 297.998655 -6.390081)
			(xy 297.990743 -6.475464) (xy 297.974987 -6.559754) (xy 297.95152 -6.64223) (xy 297.920544 -6.722189)
			(xy 297.882322 -6.798949) (xy 297.837181 -6.871855) (xy 297.785505 -6.940284) (xy 297.727736 -7.003654)
			(xy 297.664366 -7.061423) (xy 297.595937 -7.113099) (xy 297.523031 -7.15824) (xy 297.446271 -7.196462)
			(xy 297.366312 -7.227438) (xy 297.283836 -7.250905) (xy 297.199546 -7.266661) (xy 297.114163 -7.274573)
			(xy 297.028413 -7.274573) (xy 296.94303 -7.266661) (xy 296.85874 -7.250905) (xy 296.776264 -7.227438)
			(xy 296.696305 -7.196462) (xy 296.619545 -7.15824) (xy 296.546639 -7.113099) (xy 296.47821 -7.061423)
			(xy 296.41484 -7.003654) (xy 296.357071 -6.940284) (xy 296.305395 -6.871855) (xy 296.260254 -6.798949)
			(xy 296.222032 -6.722189) (xy 296.191056 -6.64223) (xy 296.167589 -6.559754) (xy 296.151833 -6.475464)
			(xy 296.143921 -6.390081) (xy 216.865975 -6.390081) (xy 216.858063 -6.475464) (xy 216.842307 -6.559754)
			(xy 216.81884 -6.64223) (xy 216.787864 -6.722189) (xy 216.749642 -6.798949) (xy 216.704501 -6.871855)
			(xy 216.652825 -6.940284) (xy 216.595056 -7.003654) (xy 216.531686 -7.061423) (xy 216.463257 -7.113099)
			(xy 216.390351 -7.15824) (xy 216.313591 -7.196462) (xy 216.233632 -7.227438) (xy 216.151156 -7.250905)
			(xy 216.066866 -7.266661) (xy 215.981483 -7.274573) (xy 215.895733 -7.274573) (xy 215.81035 -7.266661)
			(xy 215.72606 -7.250905) (xy 215.643584 -7.227438) (xy 215.563625 -7.196462) (xy 215.486865 -7.15824)
			(xy 215.413959 -7.113099) (xy 215.34553 -7.061423) (xy 215.28216 -7.003654) (xy 215.224391 -6.940284)
			(xy 215.172715 -6.871855) (xy 215.127574 -6.798949) (xy 215.089352 -6.722189) (xy 215.058376 -6.64223)
			(xy 215.034909 -6.559754) (xy 215.019153 -6.475464) (xy 215.011241 -6.390081) (xy 210.515975 -6.390081)
			(xy 210.508063 -6.475464) (xy 210.492307 -6.559754) (xy 210.46884 -6.64223) (xy 210.437864 -6.722189)
			(xy 210.399642 -6.798949) (xy 210.354501 -6.871855) (xy 210.302825 -6.940284) (xy 210.245056 -7.003654)
			(xy 210.181686 -7.061423) (xy 210.113257 -7.113099) (xy 210.040351 -7.15824) (xy 209.963591 -7.196462)
			(xy 209.883632 -7.227438) (xy 209.801156 -7.250905) (xy 209.716866 -7.266661) (xy 209.631483 -7.274573)
			(xy 209.545733 -7.274573) (xy 209.46035 -7.266661) (xy 209.37606 -7.250905) (xy 209.293584 -7.227438)
			(xy 209.213625 -7.196462) (xy 209.136865 -7.15824) (xy 209.063959 -7.113099) (xy 208.99553 -7.061423)
			(xy 208.93216 -7.003654) (xy 208.874391 -6.940284) (xy 208.822715 -6.871855) (xy 208.777574 -6.798949)
			(xy 208.739352 -6.722189) (xy 208.708376 -6.64223) (xy 208.684909 -6.559754) (xy 208.669153 -6.475464)
			(xy 208.661241 -6.390081) (xy 197.210934 -6.390081) (xy 197.210934 -7.78002) (xy 197.211456 -7.835788)
			(xy 197.219793 -7.947013) (xy 197.236418 -8.057304) (xy 197.261239 -8.166044) (xy 197.294116 -8.272625)
			(xy 197.334866 -8.376451) (xy 197.383261 -8.476941) (xy 197.439031 -8.573534) (xy 197.501863 -8.66569)
			(xy 197.571406 -8.752892) (xy 197.647271 -8.834653) (xy 197.729034 -8.910516) (xy 197.816238 -8.980057)
			(xy 197.908394 -9.042887) (xy 198.004989 -9.098654) (xy 198.10548 -9.147047) (xy 198.209307 -9.187795)
			(xy 198.315889 -9.22067) (xy 198.42463 -9.245488) (xy 198.534921 -9.262111) (xy 198.646146 -9.270445)
			(xy 198.701914 -9.271) (xy 223.300036 -9.271) (xy 223.370417 -9.271495) (xy 223.510959 -9.279389)
			(xy 223.650836 -9.295152) (xy 223.78961 -9.318732) (xy 223.926844 -9.350057) (xy 224.062105 -9.389027)
			(xy 224.194968 -9.435519) (xy 224.325015 -9.489388) (xy 224.451838 -9.550465) (xy 224.575036 -9.618556)
			(xy 224.694222 -9.693447) (xy 224.809022 -9.774904) (xy 224.919074 -9.862669) (xy 225.024032 -9.956467)
			(xy 225.123566 -10.056003) (xy 225.217361 -10.160962) (xy 225.305125 -10.271016) (xy 225.386579 -10.385818)
			(xy 225.461469 -10.505006) (xy 225.529557 -10.628205) (xy 225.590631 -10.755029) (xy 225.644498 -10.885077)
			(xy 225.690988 -11.017941) (xy 225.729955 -11.153203) (xy 225.761277 -11.290437) (xy 225.784855 -11.429211)
			(xy 225.800615 -11.569089) (xy 225.808507 -11.709631) (xy 225.809048 -11.780012) (xy 225.809048 -33.120076)
			(xy 225.809549 -33.152224) (xy 225.817939 -33.21597) (xy 225.834578 -33.278076) (xy 225.859182 -33.337478)
			(xy 225.891329 -33.39316) (xy 225.93047 -33.44417) (xy 225.975934 -33.489634) (xy 226.026945 -33.528774)
			(xy 226.082627 -33.560921) (xy 226.14203 -33.585524) (xy 226.204136 -33.602162) (xy 226.267882 -33.610551)
			(xy 226.30003 -33.611058)
		)
		(stroke
			(width 0)
			(type solid)
		)
		(fill yes)
		(layer "In7.Cu")
		(net "DELTA_L_GND_1")
	)
	(gr_poly
		(pts
			(xy 194.445128 -441.480956) (xy 194.455142 -441.480531) (xy 194.473642 -441.472854) (xy 194.487795 -441.458682)
			(xy 194.495445 -441.440171) (xy 194.495928 -441.430156) (xy 194.495928 -441.17006) (xy 194.49641 -441.126022)
			(xy 194.50409 -441.03828) (xy 194.519387 -440.951542) (xy 194.542185 -440.866466) (xy 194.572311 -440.783702)
			(xy 194.609536 -440.703878) (xy 194.653576 -440.627602) (xy 194.704095 -440.555454) (xy 194.760711 -440.487984)
			(xy 194.822991 -440.425704) (xy 194.890462 -440.369089) (xy 194.96261 -440.31857) (xy 195.038887 -440.274531)
			(xy 195.118711 -440.237308) (xy 195.201476 -440.207182) (xy 195.286551 -440.184385) (xy 195.37329 -440.169088)
			(xy 195.461032 -440.16141) (xy 195.50507 -440.160918) (xy 276.314916 -440.160918) (xy 276.358955 -440.161399)
			(xy 276.446699 -440.169077) (xy 276.533439 -440.184372) (xy 276.618516 -440.207169) (xy 276.701283 -440.237294)
			(xy 276.781109 -440.274518) (xy 276.857388 -440.318557) (xy 276.929538 -440.369076) (xy 276.99701 -440.425692)
			(xy 277.059292 -440.487972) (xy 277.115909 -440.555443) (xy 277.16643 -440.627592) (xy 277.210471 -440.703869)
			(xy 277.247697 -440.783695) (xy 277.277823 -440.866461) (xy 277.300622 -440.951538) (xy 277.31592 -441.038278)
			(xy 277.3236 -441.126021) (xy 277.324058 -441.17006) (xy 277.324058 -441.430156) (xy 277.324469 -441.440186)
			(xy 277.33213 -441.458725) (xy 277.346302 -441.472922) (xy 277.364828 -441.480614) (xy 277.374858 -441.480956)
			(xy 463.300064 -441.480956) (xy 463.355834 -441.480449) (xy 463.467062 -441.472116) (xy 463.577357 -441.455494)
			(xy 463.686101 -441.430676) (xy 463.792686 -441.397801) (xy 463.896517 -441.357052) (xy 463.997011 -441.308658)
			(xy 464.093608 -441.252889) (xy 464.185768 -441.190057) (xy 464.272974 -441.120513) (xy 464.354739 -441.044647)
			(xy 464.430606 -440.962883) (xy 464.50015 -440.875677) (xy 464.562982 -440.783519) (xy 464.618752 -440.686922)
			(xy 464.667147 -440.586428) (xy 464.707897 -440.482598) (xy 464.740773 -440.376013) (xy 464.765592 -440.267269)
			(xy 464.782215 -440.156974) (xy 464.790548 -440.045746) (xy 464.791044 -439.989976) (xy 464.791044 -409.528264)
			(xy 464.791546 -409.457891) (xy 464.799454 -409.317366) (xy 464.815227 -409.177505) (xy 464.838815 -409.038749)
			(xy 464.870143 -408.901532) (xy 464.909113 -408.766288) (xy 464.955604 -408.633441) (xy 465.009467 -408.503408)
			(xy 465.070535 -408.376599) (xy 465.138615 -408.253413) (xy 465.213493 -408.134236) (xy 465.294933 -408.019444)
			(xy 465.38268 -407.909398) (xy 465.476458 -407.804443) (xy 465.525866 -407.754328) (xy 467.354412 -405.925782)
			(xy 467.391703 -405.887819) (xy 467.461396 -405.807388) (xy 467.525176 -405.722192) (xy 467.582717 -405.632663)
			(xy 467.633725 -405.539259) (xy 467.677942 -405.442454) (xy 467.715142 -405.342742) (xy 467.745135 -405.240631)
			(xy 467.767768 -405.136641) (xy 467.782928 -405.031301) (xy 467.790535 -404.925148) (xy 467.791038 -404.871936)
			(xy 467.791038 -82.82813) (xy 467.791541 -82.757757) (xy 467.799451 -82.617233) (xy 467.815226 -82.477373)
			(xy 467.838815 -82.338618) (xy 467.870145 -82.201402) (xy 467.909116 -82.066159) (xy 467.955608 -81.933313)
			(xy 468.009473 -81.803282) (xy 468.070541 -81.676474) (xy 468.138622 -81.553289) (xy 468.213501 -81.434114)
			(xy 468.294942 -81.319323) (xy 468.382689 -81.209278) (xy 468.476467 -81.104324) (xy 468.52586 -81.054194)
			(xy 470.854278 -78.725776) (xy 470.891569 -78.687813) (xy 470.961264 -78.607383) (xy 471.025045 -78.522187)
			(xy 471.082586 -78.432659) (xy 471.133596 -78.339255) (xy 471.177813 -78.24245) (xy 471.215013 -78.142738)
			(xy 471.245007 -78.040626) (xy 471.267641 -77.936636) (xy 471.2828 -77.831296) (xy 471.290407 -77.725143)
			(xy 471.290904 -77.67193) (xy 471.290904 -13.780008) (xy 471.290383 -13.724238) (xy 471.282048 -13.613011)
			(xy 471.265425 -13.502718) (xy 471.240606 -13.393975) (xy 471.20773 -13.287391) (xy 471.166981 -13.183562)
			(xy 471.118587 -13.083068) (xy 471.062818 -12.986472) (xy 470.999987 -12.894314) (xy 470.930444 -12.807108)
			(xy 470.854579 -12.725344) (xy 470.772816 -12.649477) (xy 470.685612 -12.579932) (xy 470.593455 -12.517099)
			(xy 470.49686 -12.461328) (xy 470.396367 -12.412932) (xy 470.292539 -12.372181) (xy 470.185956 -12.339303)
			(xy 470.077214 -12.314481) (xy 469.966921 -12.297855) (xy 469.855694 -12.289518) (xy 469.799924 -12.289028)
			(xy 458.20203 -12.289028) (xy 458.131647 -12.288544) (xy 457.991102 -12.280653) (xy 457.85122 -12.264894)
			(xy 457.712443 -12.241316) (xy 457.575205 -12.209994) (xy 457.43994 -12.171027) (xy 457.307072 -12.124536)
			(xy 457.177021 -12.070668) (xy 457.050194 -12.009593) (xy 456.926991 -11.941503) (xy 456.8078 -11.866612)
			(xy 456.692996 -11.785156) (xy 456.582939 -11.69739) (xy 456.477977 -11.603592) (xy 456.378439 -11.504056)
			(xy 456.284639 -11.399096) (xy 456.196872 -11.289041) (xy 456.115413 -11.174238) (xy 456.04052 -11.055048)
			(xy 455.972428 -10.931847) (xy 455.911351 -10.805021) (xy 455.857481 -10.674971) (xy 455.810987 -10.542104)
			(xy 455.772017 -10.406839) (xy 455.740693 -10.269603) (xy 455.717113 -10.130825) (xy 455.701351 -9.990944)
			(xy 455.693457 -9.850399) (xy 455.693018 -9.780016) (xy 455.693018 -0.559816) (xy 455.692533 -0.549805)
			(xy 455.684877 -0.531304) (xy 455.670724 -0.517142) (xy 455.652229 -0.509474) (xy 455.642218 -0.509016)
			(xy 388.161784 -0.509016) (xy 388.15178 -0.509507) (xy 388.133296 -0.51717) (xy 388.119152 -0.531323)
			(xy 388.111501 -0.549811) (xy 388.110984 -0.559816) (xy 388.110984 -5.169916) (xy 388.849115 -5.169916)
			(xy 388.853124 -5.081915) (xy 388.865119 -4.994644) (xy 388.885001 -4.908825) (xy 388.912604 -4.825169)
			(xy 388.9477 -4.74437) (xy 388.989998 -4.667097) (xy 389.039147 -4.593991) (xy 389.094741 -4.525657)
			(xy 389.156318 -4.462662) (xy 389.223369 -4.405527) (xy 389.295338 -4.354726) (xy 389.371628 -4.31068)
			(xy 389.451607 -4.273754) (xy 389.534612 -4.244253) (xy 389.619957 -4.222424) (xy 389.706933 -4.208445)
			(xy 389.794819 -4.202433) (xy 389.882888 -4.204439) (xy 389.97041 -4.214444) (xy 390.05666 -4.232367)
			(xy 390.140922 -4.258059) (xy 390.222499 -4.291306) (xy 390.300715 -4.331834) (xy 390.374921 -4.379307)
			(xy 390.444503 -4.433331) (xy 390.508883 -4.493458) (xy 390.56753 -4.559191) (xy 390.619956 -4.629985)
			(xy 390.665727 -4.705252) (xy 390.704464 -4.78437) (xy 390.735846 -4.866683) (xy 390.759613 -4.951508)
			(xy 390.766825 -4.990667) (xy 394.939038 -4.990667) (xy 394.939038 -4.936133) (xy 394.946799 -4.882155)
			(xy 394.962162 -4.82983) (xy 394.984815 -4.780224) (xy 395.014296 -4.734346) (xy 395.050007 -4.693131)
			(xy 395.091219 -4.657417) (xy 395.137094 -4.627931) (xy 395.186698 -4.605274) (xy 395.239021 -4.589906)
			(xy 395.292999 -4.582141) (xy 395.320266 -4.581652) (xy 396.183866 -4.581652) (xy 396.21114 -4.582085)
			(xy 396.265132 -4.589844) (xy 396.317471 -4.605208) (xy 396.36709 -4.627864) (xy 396.41298 -4.657352)
			(xy 396.454205 -4.693071) (xy 396.489928 -4.734293) (xy 396.51942 -4.78018) (xy 396.542081 -4.829797)
			(xy 396.557449 -4.882135) (xy 396.565212 -4.936126) (xy 396.565212 -4.99067) (xy 398.538915 -4.99067)
			(xy 398.538915 -4.93613) (xy 398.546678 -4.882144) (xy 398.562044 -4.829813) (xy 398.584701 -4.780201)
			(xy 398.614188 -4.734318) (xy 398.649905 -4.6931) (xy 398.691125 -4.657383) (xy 398.737008 -4.627897)
			(xy 398.78662 -4.605241) (xy 398.838952 -4.589876) (xy 398.892938 -4.582115) (xy 398.920208 -4.581652)
			(xy 399.783808 -4.581652) (xy 399.811078 -4.582111) (xy 399.865063 -4.589874) (xy 399.917393 -4.60524)
			(xy 399.967004 -4.627898) (xy 400.012886 -4.657385) (xy 400.054104 -4.693102) (xy 400.08982 -4.734321)
			(xy 400.119306 -4.780203) (xy 400.141962 -4.829814) (xy 400.157328 -4.882145) (xy 400.16509 -4.93613)
			(xy 400.16509 -4.990666) (xy 402.138938 -4.990666) (xy 402.138938 -4.936134) (xy 402.146698 -4.882157)
			(xy 402.162061 -4.829833) (xy 402.184712 -4.780228) (xy 402.214192 -4.734351) (xy 402.249901 -4.693136)
			(xy 402.291111 -4.657422) (xy 402.336984 -4.627936) (xy 402.386586 -4.605278) (xy 402.438908 -4.589909)
			(xy 402.492884 -4.582142) (xy 402.52015 -4.581652) (xy 403.38375 -4.581652) (xy 403.411024 -4.582084)
			(xy 403.465019 -4.589841) (xy 403.517359 -4.605203) (xy 403.56698 -4.627859) (xy 403.612872 -4.657346)
			(xy 403.6541 -4.693065) (xy 403.689824 -4.734288) (xy 403.719317 -4.780176) (xy 403.741979 -4.829794)
			(xy 403.757349 -4.882132) (xy 403.765112 -4.936126) (xy 403.765112 -4.990672) (xy 405.739016 -4.990672)
			(xy 405.739016 -4.936128) (xy 405.746779 -4.882139) (xy 405.762147 -4.829805) (xy 405.784807 -4.78019)
			(xy 405.814298 -4.734306) (xy 405.850019 -4.693086) (xy 405.891243 -4.65737) (xy 405.937131 -4.627885)
			(xy 405.986748 -4.605231) (xy 406.039084 -4.589869) (xy 406.093074 -4.582112) (xy 406.120346 -4.581652)
			(xy 406.983946 -4.581652) (xy 407.011214 -4.582114) (xy 407.065195 -4.589881) (xy 407.117521 -4.605251)
			(xy 407.167127 -4.62791) (xy 407.213004 -4.657399) (xy 407.254217 -4.693115) (xy 407.289929 -4.734333)
			(xy 407.319412 -4.780213) (xy 407.342065 -4.829822) (xy 407.357429 -4.88215) (xy 407.36519 -4.936132)
			(xy 407.36519 -4.990668) (xy 407.36519 -4.99067) (xy 414.849015 -4.99067) (xy 414.849015 -4.93613)
			(xy 414.856778 -4.882144) (xy 414.872144 -4.829812) (xy 414.894801 -4.7802) (xy 414.924289 -4.734318)
			(xy 414.960006 -4.693099) (xy 415.001226 -4.657383) (xy 415.047109 -4.627896) (xy 415.096722 -4.60524)
			(xy 415.149054 -4.589875) (xy 415.20304 -4.582115) (xy 415.23031 -4.581652) (xy 416.09391 -4.581652)
			(xy 416.12118 -4.582111) (xy 416.175164 -4.589874) (xy 416.227495 -4.605241) (xy 416.277105 -4.627899)
			(xy 416.322987 -4.657386) (xy 416.364205 -4.693102) (xy 416.39992 -4.734321) (xy 416.429406 -4.780203)
			(xy 416.452062 -4.829815) (xy 416.467428 -4.882145) (xy 416.47519 -4.93613) (xy 416.47519 -4.990666)
			(xy 418.449038 -4.990666) (xy 418.449038 -4.936134) (xy 418.456798 -4.882156) (xy 418.472161 -4.829833)
			(xy 418.494813 -4.780227) (xy 418.524293 -4.734351) (xy 418.560002 -4.693136) (xy 418.601212 -4.657422)
			(xy 418.647085 -4.627936) (xy 418.696688 -4.605278) (xy 418.749009 -4.589909) (xy 418.802986 -4.582142)
			(xy 418.830252 -4.581652) (xy 419.693852 -4.581652) (xy 419.721126 -4.582084) (xy 419.77512 -4.589841)
			(xy 419.827461 -4.605204) (xy 419.877082 -4.627859) (xy 419.922973 -4.657347) (xy 419.9642 -4.693066)
			(xy 419.999924 -4.734288) (xy 420.029418 -4.780176) (xy 420.052079 -4.829794) (xy 420.067449 -4.882133)
			(xy 420.075212 -4.936126) (xy 420.075212 -4.990672) (xy 426.059016 -4.990672) (xy 426.059016 -4.936128)
			(xy 426.066779 -4.882139) (xy 426.082147 -4.829805) (xy 426.104807 -4.78019) (xy 426.134298 -4.734306)
			(xy 426.170019 -4.693086) (xy 426.211243 -4.65737) (xy 426.257131 -4.627885) (xy 426.306748 -4.605231)
			(xy 426.359084 -4.589869) (xy 426.413074 -4.582112) (xy 426.440346 -4.581652) (xy 427.303946 -4.581652)
			(xy 427.331214 -4.582114) (xy 427.385195 -4.589881) (xy 427.437521 -4.605251) (xy 427.487127 -4.62791)
			(xy 427.533004 -4.657399) (xy 427.574217 -4.693115) (xy 427.609929 -4.734333) (xy 427.639412 -4.780213)
			(xy 427.662065 -4.829822) (xy 427.677429 -4.88215) (xy 427.68519 -4.936132) (xy 427.68519 -4.990668)
			(xy 429.659038 -4.990668) (xy 429.659038 -4.936132) (xy 429.666799 -4.882152) (xy 429.682164 -4.829825)
			(xy 429.704818 -4.780217) (xy 429.734302 -4.734339) (xy 429.770014 -4.693123) (xy 429.811229 -4.657409)
			(xy 429.857107 -4.627924) (xy 429.906714 -4.605268) (xy 429.95904 -4.589902) (xy 430.01302 -4.582139)
			(xy 430.040288 -4.581652) (xy 430.903888 -4.581652) (xy 430.931161 -4.582087) (xy 430.985151 -4.589848)
			(xy 431.037487 -4.605214) (xy 431.087103 -4.627871) (xy 431.13299 -4.65736) (xy 431.174213 -4.693078)
			(xy 431.209933 -4.7343) (xy 431.239423 -4.780186) (xy 431.262082 -4.829802) (xy 431.27745 -4.882138)
			(xy 431.285212 -4.936127) (xy 431.285212 -4.990673) (xy 431.27745 -5.044662) (xy 431.262082 -5.096998)
			(xy 431.239423 -5.146614) (xy 431.209933 -5.1925) (xy 431.174213 -5.233722) (xy 431.13299 -5.26944)
			(xy 431.087103 -5.298929) (xy 431.037487 -5.321586) (xy 430.985151 -5.336952) (xy 430.931161 -5.344713)
			(xy 430.903888 -5.345176) (xy 430.040288 -5.345176) (xy 430.01302 -5.344661) (xy 429.95904 -5.336898)
			(xy 429.906714 -5.321532) (xy 429.857107 -5.298876) (xy 429.811229 -5.269391) (xy 429.770014 -5.233677)
			(xy 429.734302 -5.192461) (xy 429.704818 -5.146583) (xy 429.682164 -5.096975) (xy 429.666799 -5.044648)
			(xy 429.659038 -4.990668) (xy 427.68519 -4.990668) (xy 427.677429 -5.04465) (xy 427.662065 -5.096978)
			(xy 427.639412 -5.146587) (xy 427.609929 -5.192467) (xy 427.574217 -5.233685) (xy 427.533004 -5.269401)
			(xy 427.487127 -5.29889) (xy 427.437521 -5.321549) (xy 427.385195 -5.336919) (xy 427.331214 -5.344686)
			(xy 427.303946 -5.345176) (xy 426.440346 -5.345176) (xy 426.413074 -5.344688) (xy 426.359084 -5.336931)
			(xy 426.306748 -5.321569) (xy 426.257131 -5.298915) (xy 426.211243 -5.26943) (xy 426.170019 -5.233714)
			(xy 426.134298 -5.192494) (xy 426.104807 -5.14661) (xy 426.082147 -5.096995) (xy 426.066779 -5.044661)
			(xy 426.059016 -4.990672) (xy 420.075212 -4.990672) (xy 420.075212 -4.990674) (xy 420.067449 -5.044667)
			(xy 420.052079 -5.097006) (xy 420.029418 -5.146624) (xy 419.999924 -5.192512) (xy 419.9642 -5.233734)
			(xy 419.922973 -5.269453) (xy 419.877082 -5.298941) (xy 419.827461 -5.321596) (xy 419.77512 -5.336959)
			(xy 419.721126 -5.344716) (xy 419.693852 -5.345176) (xy 418.830252 -5.345176) (xy 418.802986 -5.344658)
			(xy 418.749009 -5.336891) (xy 418.696688 -5.321522) (xy 418.647085 -5.298864) (xy 418.601212 -5.269378)
			(xy 418.560002 -5.233664) (xy 418.524293 -5.192449) (xy 418.494813 -5.146573) (xy 418.472161 -5.096967)
			(xy 418.456798 -5.044644) (xy 418.449038 -4.990666) (xy 416.47519 -4.990666) (xy 416.47519 -4.99067)
			(xy 416.467428 -5.044655) (xy 416.452062 -5.096985) (xy 416.429406 -5.146597) (xy 416.39992 -5.192479)
			(xy 416.364205 -5.233698) (xy 416.322987 -5.269414) (xy 416.277105 -5.298901) (xy 416.227495 -5.321559)
			(xy 416.175164 -5.336926) (xy 416.12118 -5.344689) (xy 416.09391 -5.345176) (xy 415.23031 -5.345176)
			(xy 415.20304 -5.344685) (xy 415.149054 -5.336925) (xy 415.096722 -5.32156) (xy 415.047109 -5.298904)
			(xy 415.001226 -5.269417) (xy 414.960006 -5.233701) (xy 414.924289 -5.192482) (xy 414.894801 -5.1466)
			(xy 414.872144 -5.096988) (xy 414.856778 -5.044656) (xy 414.849015 -4.99067) (xy 407.36519 -4.99067)
			(xy 407.357429 -5.04465) (xy 407.342065 -5.096978) (xy 407.319412 -5.146587) (xy 407.289929 -5.192467)
			(xy 407.254217 -5.233685) (xy 407.213004 -5.269401) (xy 407.167127 -5.29889) (xy 407.117521 -5.321549)
			(xy 407.065195 -5.336919) (xy 407.011214 -5.344686) (xy 406.983946 -5.345176) (xy 406.120346 -5.345176)
			(xy 406.093074 -5.344688) (xy 406.039084 -5.336931) (xy 405.986748 -5.321569) (xy 405.937131 -5.298915)
			(xy 405.891243 -5.26943) (xy 405.850019 -5.233714) (xy 405.814298 -5.192494) (xy 405.784807 -5.14661)
			(xy 405.762147 -5.096995) (xy 405.746779 -5.044661) (xy 405.739016 -4.990672) (xy 403.765112 -4.990672)
			(xy 403.765112 -4.990674) (xy 403.757349 -5.044668) (xy 403.741979 -5.097006) (xy 403.719317 -5.146624)
			(xy 403.689824 -5.192512) (xy 403.6541 -5.233735) (xy 403.612872 -5.269454) (xy 403.56698 -5.298941)
			(xy 403.517359 -5.321597) (xy 403.465019 -5.336959) (xy 403.411024 -5.344716) (xy 403.38375 -5.345176)
			(xy 402.52015 -5.345176) (xy 402.492884 -5.344658) (xy 402.438908 -5.336891) (xy 402.386586 -5.321522)
			(xy 402.336984 -5.298864) (xy 402.291111 -5.269378) (xy 402.249901 -5.233664) (xy 402.214192 -5.192449)
			(xy 402.184712 -5.146572) (xy 402.162061 -5.096967) (xy 402.146698 -5.044643) (xy 402.138938 -4.990666)
			(xy 400.16509 -4.990666) (xy 400.16509 -4.99067) (xy 400.157328 -5.044655) (xy 400.141962 -5.096986)
			(xy 400.119306 -5.146597) (xy 400.08982 -5.192479) (xy 400.054104 -5.233698) (xy 400.012886 -5.269415)
			(xy 399.967004 -5.298902) (xy 399.917393 -5.32156) (xy 399.865063 -5.336926) (xy 399.811078 -5.344689)
			(xy 399.783808 -5.345176) (xy 398.920208 -5.345176) (xy 398.892938 -5.344685) (xy 398.838952 -5.336924)
			(xy 398.78662 -5.321559) (xy 398.737008 -5.298903) (xy 398.691125 -5.269417) (xy 398.649905 -5.2337)
			(xy 398.614188 -5.192482) (xy 398.584701 -5.146599) (xy 398.562044 -5.096987) (xy 398.546678 -5.044656)
			(xy 398.538915 -4.99067) (xy 396.565212 -4.99067) (xy 396.565212 -4.990674) (xy 396.557449 -5.044665)
			(xy 396.542081 -5.097003) (xy 396.51942 -5.14662) (xy 396.489928 -5.192507) (xy 396.454205 -5.233729)
			(xy 396.41298 -5.269448) (xy 396.36709 -5.298936) (xy 396.317471 -5.321592) (xy 396.265132 -5.336956)
			(xy 396.21114 -5.344715) (xy 396.183866 -5.345176) (xy 395.320266 -5.345176) (xy 395.292999 -5.344659)
			(xy 395.239021 -5.336894) (xy 395.186698 -5.321526) (xy 395.137094 -5.298869) (xy 395.091219 -5.269383)
			(xy 395.050007 -5.233669) (xy 395.014296 -5.192454) (xy 394.984815 -5.146576) (xy 394.962162 -5.09697)
			(xy 394.946799 -5.044645) (xy 394.939038 -4.990667) (xy 390.766825 -4.990667) (xy 390.775568 -5.038143)
			(xy 390.783579 -5.12587) (xy 390.78408 -5.169916) (xy 390.783579 -5.213962) (xy 390.775568 -5.301689)
			(xy 390.759613 -5.388324) (xy 390.735846 -5.473149) (xy 390.704464 -5.555462) (xy 390.665727 -5.63458)
			(xy 390.619956 -5.709847) (xy 390.56753 -5.780641) (xy 390.508883 -5.846374) (xy 390.444503 -5.906501)
			(xy 390.374921 -5.960525) (xy 390.300715 -6.007998) (xy 390.222499 -6.048526) (xy 390.140922 -6.081773)
			(xy 390.05666 -6.107465) (xy 389.97041 -6.125388) (xy 389.882888 -6.135393) (xy 389.794819 -6.137399)
			(xy 389.706933 -6.131387) (xy 389.619957 -6.117408) (xy 389.534612 -6.095579) (xy 389.451607 -6.066078)
			(xy 389.371628 -6.029152) (xy 389.295338 -5.985106) (xy 389.223369 -5.934305) (xy 389.156318 -5.87717)
			(xy 389.094741 -5.814175) (xy 389.039147 -5.745841) (xy 388.989998 -5.672735) (xy 388.9477 -5.595462)
			(xy 388.912604 -5.514663) (xy 388.885001 -5.431007) (xy 388.865119 -5.345188) (xy 388.853124 -5.257917)
			(xy 388.849115 -5.169916) (xy 388.110984 -5.169916) (xy 388.110984 -6.169914) (xy 453.015103 -6.169914)
			(xy 453.019108 -6.082006) (xy 453.031091 -5.994826) (xy 453.050951 -5.909097) (xy 453.078526 -5.825529)
			(xy 453.113585 -5.744815) (xy 453.155838 -5.667623) (xy 453.204936 -5.594594) (xy 453.260472 -5.526332)
			(xy 453.321984 -5.463402) (xy 453.388965 -5.406328) (xy 453.460858 -5.35558) (xy 453.537067 -5.31158)
			(xy 453.616962 -5.274693) (xy 453.699881 -5.245224) (xy 453.785136 -5.223417) (xy 453.87202 -5.209453)
			(xy 453.959814 -5.203447) (xy 454.047791 -5.205451) (xy 454.135221 -5.215446) (xy 454.22138 -5.23335)
			(xy 454.305554 -5.259014) (xy 454.387045 -5.292227) (xy 454.465179 -5.332713) (xy 454.539307 -5.380135)
			(xy 454.608815 -5.434102) (xy 454.673129 -5.494167) (xy 454.731713 -5.559831) (xy 454.784084 -5.63055)
			(xy 454.829807 -5.705738) (xy 454.868504 -5.784773) (xy 454.899853 -5.866999) (xy 454.923595 -5.951735)
			(xy 454.939533 -6.038279) (xy 454.947535 -6.125914) (xy 454.948036 -6.169914) (xy 454.947535 -6.213914)
			(xy 454.939533 -6.301549) (xy 454.923595 -6.388093) (xy 454.899853 -6.472829) (xy 454.868504 -6.555055)
			(xy 454.829807 -6.63409) (xy 454.784084 -6.709278) (xy 454.731713 -6.779997) (xy 454.673129 -6.845661)
			(xy 454.608815 -6.905726) (xy 454.539307 -6.959693) (xy 454.465179 -7.007115) (xy 454.387045 -7.047601)
			(xy 454.305554 -7.080814) (xy 454.22138 -7.106478) (xy 454.135221 -7.124382) (xy 454.047791 -7.134377)
			(xy 453.959814 -7.136381) (xy 453.87202 -7.130375) (xy 453.785136 -7.116411) (xy 453.699881 -7.094604)
			(xy 453.616962 -7.065135) (xy 453.537067 -7.028248) (xy 453.460858 -6.984248) (xy 453.388965 -6.9335)
			(xy 453.321984 -6.876426) (xy 453.260472 -6.813496) (xy 453.204936 -6.745234) (xy 453.155838 -6.672205)
			(xy 453.113585 -6.595013) (xy 453.078526 -6.514299) (xy 453.050951 -6.430731) (xy 453.031091 -6.345002)
			(xy 453.019108 -6.257822) (xy 453.015103 -6.169914) (xy 388.110984 -6.169914) (xy 388.110984 -6.752472)
			(xy 393.134283 -6.752472) (xy 393.134283 -6.697928) (xy 393.142045 -6.643939) (xy 393.157412 -6.591604)
			(xy 393.18007 -6.541988) (xy 393.209559 -6.496103) (xy 393.245278 -6.454881) (xy 393.286499 -6.419161)
			(xy 393.332385 -6.389672) (xy 393.382 -6.367013) (xy 393.434335 -6.351646) (xy 393.488324 -6.343883)
			(xy 393.515596 -6.343396) (xy 394.379196 -6.343396) (xy 394.406464 -6.343943) (xy 394.460446 -6.351704)
			(xy 394.512773 -6.367068) (xy 394.562381 -6.389723) (xy 394.60826 -6.419207) (xy 394.649476 -6.454921)
			(xy 394.68519 -6.496136) (xy 394.714675 -6.542015) (xy 394.73733 -6.591623) (xy 394.752695 -6.643951)
			(xy 394.760457 -6.697932) (xy 394.760457 -6.752468) (xy 394.760456 -6.752476) (xy 396.73416 -6.752476)
			(xy 396.73416 -6.697924) (xy 396.741924 -6.643928) (xy 396.757294 -6.591587) (xy 396.779956 -6.541966)
			(xy 396.809451 -6.496075) (xy 396.845176 -6.454849) (xy 396.886405 -6.419128) (xy 396.932299 -6.389638)
			(xy 396.981922 -6.36698) (xy 397.034265 -6.351616) (xy 397.088262 -6.343857) (xy 397.115538 -6.343396)
			(xy 397.979138 -6.343396) (xy 398.006403 -6.343969) (xy 398.060376 -6.351734) (xy 398.112695 -6.367101)
			(xy 398.162295 -6.389757) (xy 398.208166 -6.419241) (xy 398.249375 -6.454952) (xy 398.285082 -6.496164)
			(xy 398.314561 -6.542038) (xy 398.337212 -6.59164) (xy 398.352574 -6.643961) (xy 398.360334 -6.697935)
			(xy 398.360334 -6.752465) (xy 398.360333 -6.752471) (xy 400.334182 -6.752471) (xy 400.334182 -6.697929)
			(xy 400.341944 -6.643941) (xy 400.35731 -6.591607) (xy 400.379968 -6.541993) (xy 400.409455 -6.496108)
			(xy 400.445172 -6.454886) (xy 400.486392 -6.419167) (xy 400.532275 -6.389677) (xy 400.581888 -6.367017)
			(xy 400.634221 -6.351649) (xy 400.688209 -6.343884) (xy 400.71548 -6.343396) (xy 401.57908 -6.343396)
			(xy 401.606349 -6.343942) (xy 401.660332 -6.351701) (xy 401.712661 -6.367064) (xy 401.762272 -6.389718)
			(xy 401.808153 -6.419202) (xy 401.849371 -6.454915) (xy 401.885086 -6.496131) (xy 401.914573 -6.542011)
			(xy 401.937229 -6.59162) (xy 401.952595 -6.643948) (xy 401.960357 -6.697931) (xy 401.960357 -6.752469)
			(xy 401.960357 -6.752471) (xy 403.934382 -6.752471) (xy 403.934382 -6.697929) (xy 403.942144 -6.643941)
			(xy 403.95751 -6.591608) (xy 403.980167 -6.541994) (xy 404.009654 -6.496109) (xy 404.045371 -6.454888)
			(xy 404.08659 -6.419168) (xy 404.132473 -6.389679) (xy 404.182085 -6.367019) (xy 404.234418 -6.351649)
			(xy 404.288405 -6.343884) (xy 404.315676 -6.343396) (xy 405.179276 -6.343396) (xy 405.206545 -6.343942)
			(xy 405.260529 -6.3517) (xy 405.312858 -6.367063) (xy 405.362469 -6.389716) (xy 405.408351 -6.4192)
			(xy 405.449569 -6.454914) (xy 405.485285 -6.49613) (xy 405.514772 -6.54201) (xy 405.537429 -6.591619)
			(xy 405.552795 -6.643948) (xy 405.560557 -6.697931) (xy 405.560557 -6.752469) (xy 405.560556 -6.752476)
			(xy 413.04426 -6.752476) (xy 413.04426 -6.697924) (xy 413.052024 -6.643928) (xy 413.067394 -6.591586)
			(xy 413.090057 -6.541965) (xy 413.119551 -6.496074) (xy 413.155277 -6.454849) (xy 413.196506 -6.419127)
			(xy 413.2424 -6.389638) (xy 413.292024 -6.36698) (xy 413.344367 -6.351615) (xy 413.398364 -6.343857)
			(xy 413.42564 -6.343396) (xy 414.28924 -6.343396) (xy 414.316504 -6.343969) (xy 414.370478 -6.351734)
			(xy 414.422797 -6.367102) (xy 414.472397 -6.389758) (xy 414.518267 -6.419241) (xy 414.559476 -6.454953)
			(xy 414.595183 -6.496165) (xy 414.624662 -6.542039) (xy 414.647312 -6.591641) (xy 414.662674 -6.643961)
			(xy 414.670434 -6.697935) (xy 414.670434 -6.752465) (xy 414.670433 -6.752472) (xy 416.644282 -6.752472)
			(xy 416.644282 -6.697928) (xy 416.652045 -6.64394) (xy 416.667411 -6.591607) (xy 416.690068 -6.541992)
			(xy 416.719555 -6.496107) (xy 416.755273 -6.454885) (xy 416.796493 -6.419166) (xy 416.842376 -6.389677)
			(xy 416.89199 -6.367017) (xy 416.944323 -6.351648) (xy 416.99831 -6.343884) (xy 417.025582 -6.343396)
			(xy 417.889182 -6.343396) (xy 417.916451 -6.343942) (xy 417.970434 -6.351701) (xy 418.022763 -6.367064)
			(xy 418.072373 -6.389718) (xy 418.118254 -6.419202) (xy 418.159471 -6.454916) (xy 418.195187 -6.496132)
			(xy 418.224673 -6.542011) (xy 418.247329 -6.59162) (xy 418.262695 -6.643949) (xy 418.270457 -6.697931)
			(xy 418.270457 -6.752469) (xy 418.270457 -6.752471) (xy 424.254382 -6.752471) (xy 424.254382 -6.697929)
			(xy 424.262144 -6.643941) (xy 424.27751 -6.591608) (xy 424.300167 -6.541994) (xy 424.329654 -6.496109)
			(xy 424.365371 -6.454888) (xy 424.40659 -6.419168) (xy 424.452473 -6.389679) (xy 424.502085 -6.367019)
			(xy 424.554418 -6.351649) (xy 424.608405 -6.343884) (xy 424.635676 -6.343396) (xy 425.499276 -6.343396)
			(xy 425.526545 -6.343942) (xy 425.580529 -6.3517) (xy 425.632858 -6.367063) (xy 425.682469 -6.389716)
			(xy 425.728351 -6.4192) (xy 425.769569 -6.454914) (xy 425.805285 -6.49613) (xy 425.834772 -6.54201)
			(xy 425.857429 -6.591619) (xy 425.872795 -6.643948) (xy 425.880557 -6.697931) (xy 425.880557 -6.752469)
			(xy 425.880556 -6.752475) (xy 427.85426 -6.752475) (xy 427.85426 -6.697925) (xy 427.862023 -6.643931)
			(xy 427.877392 -6.591591) (xy 427.900053 -6.541971) (xy 427.929546 -6.496082) (xy 427.965269 -6.454856)
			(xy 428.006496 -6.419135) (xy 428.052387 -6.389645) (xy 428.102008 -6.366986) (xy 428.154348 -6.351619)
			(xy 428.208343 -6.343858) (xy 428.235618 -6.343396) (xy 429.099218 -6.343396) (xy 429.126484 -6.343968)
			(xy 429.180459 -6.35173) (xy 429.232781 -6.367096) (xy 429.282383 -6.38975) (xy 429.328257 -6.419234)
			(xy 429.369468 -6.454945) (xy 429.405177 -6.496157) (xy 429.434658 -6.542032) (xy 429.457311 -6.591636)
			(xy 429.472673 -6.643958) (xy 429.480434 -6.697934) (xy 429.480434 -6.752466) (xy 429.479412 -6.759571)
			(xy 431.465194 -6.759571) (xy 431.465194 -6.705029) (xy 431.472956 -6.651043) (xy 431.488322 -6.598711)
			(xy 431.510979 -6.549098) (xy 431.540465 -6.503214) (xy 431.576181 -6.461994) (xy 431.6174 -6.426276)
			(xy 431.663282 -6.396787) (xy 431.712894 -6.374128) (xy 431.765225 -6.35876) (xy 431.819211 -6.350996)
			(xy 431.846482 -6.350508) (xy 432.710082 -6.350508) (xy 432.737352 -6.35103) (xy 432.791336 -6.35879)
			(xy 432.843667 -6.374153) (xy 432.893279 -6.396808) (xy 432.939161 -6.426293) (xy 432.98038 -6.462007)
			(xy 433.016096 -6.503225) (xy 433.045583 -6.549106) (xy 433.068241 -6.598716) (xy 433.083607 -6.651046)
			(xy 433.091369 -6.70503) (xy 433.091369 -6.75247) (xy 445.449182 -6.75247) (xy 445.449182 -6.69793)
			(xy 445.456944 -6.643944) (xy 445.472308 -6.591613) (xy 445.494963 -6.542001) (xy 445.524448 -6.496117)
			(xy 445.560162 -6.454896) (xy 445.601379 -6.419177) (xy 445.647258 -6.389686) (xy 445.696868 -6.367025)
			(xy 445.749198 -6.351654) (xy 445.803182 -6.343886) (xy 445.830452 -6.343396) (xy 446.694052 -6.343396)
			(xy 446.721322 -6.34394) (xy 446.775308 -6.351696) (xy 446.827641 -6.367056) (xy 446.877255 -6.389709)
			(xy 446.923139 -6.419192) (xy 446.964361 -6.454905) (xy 447.00008 -6.496122) (xy 447.029568 -6.542003)
			(xy 447.052227 -6.591614) (xy 447.067594 -6.643945) (xy 447.075356 -6.69793) (xy 447.075356 -6.75247)
			(xy 447.067594 -6.806455) (xy 447.052227 -6.858786) (xy 447.029568 -6.908397) (xy 447.000079 -6.954278)
			(xy 446.964361 -6.995495) (xy 446.923139 -7.031208) (xy 446.877255 -7.060691) (xy 446.827641 -7.083344)
			(xy 446.775308 -7.098704) (xy 446.721322 -7.10646) (xy 446.694052 -7.10692) (xy 445.830452 -7.10692)
			(xy 445.803182 -7.106514) (xy 445.749198 -7.098746) (xy 445.696868 -7.083375) (xy 445.647258 -7.060714)
			(xy 445.601378 -7.031223) (xy 445.560162 -6.995504) (xy 445.524448 -6.954283) (xy 445.494963 -6.908399)
			(xy 445.472308 -6.858787) (xy 445.456944 -6.806455) (xy 445.449182 -6.75247) (xy 433.091369 -6.75247)
			(xy 433.091369 -6.75957) (xy 433.083607 -6.813554) (xy 433.068241 -6.865884) (xy 433.045583 -6.915494)
			(xy 433.016096 -6.961375) (xy 432.98038 -7.002593) (xy 432.939161 -7.038307) (xy 432.893279 -7.067792)
			(xy 432.843667 -7.090447) (xy 432.791336 -7.10581) (xy 432.737352 -7.11357) (xy 432.710082 -7.114032)
			(xy 431.846482 -7.114032) (xy 431.819211 -7.113604) (xy 431.765225 -7.10584) (xy 431.712894 -7.090472)
			(xy 431.663282 -7.067813) (xy 431.6174 -7.038324) (xy 431.576181 -7.002606) (xy 431.540465 -6.961386)
			(xy 431.510979 -6.915502) (xy 431.488322 -6.865889) (xy 431.472956 -6.813557) (xy 431.465194 -6.759571)
			(xy 429.479412 -6.759571) (xy 429.472673 -6.806442) (xy 429.457311 -6.858764) (xy 429.434658 -6.908368)
			(xy 429.405177 -6.954243) (xy 429.369468 -6.995455) (xy 429.328257 -7.031166) (xy 429.282383 -7.06065)
			(xy 429.232781 -7.083304) (xy 429.180459 -7.09867) (xy 429.126484 -7.106432) (xy 429.099218 -7.10692)
			(xy 428.235618 -7.10692) (xy 428.208343 -7.106542) (xy 428.154348 -7.098781) (xy 428.102008 -7.083414)
			(xy 428.052387 -7.060755) (xy 428.006496 -7.031265) (xy 427.965269 -6.995544) (xy 427.929546 -6.954318)
			(xy 427.900053 -6.908429) (xy 427.877392 -6.858809) (xy 427.862023 -6.806469) (xy 427.85426 -6.752475)
			(xy 425.880556 -6.752475) (xy 425.872795 -6.806452) (xy 425.857429 -6.858781) (xy 425.834772 -6.90839)
			(xy 425.805285 -6.95427) (xy 425.769569 -6.995486) (xy 425.728351 -7.0312) (xy 425.682469 -7.060684)
			(xy 425.632858 -7.083337) (xy 425.580529 -7.0987) (xy 425.526545 -7.106458) (xy 425.499276 -7.10692)
			(xy 424.635676 -7.10692) (xy 424.608405 -7.106516) (xy 424.554418 -7.098751) (xy 424.502085 -7.083381)
			(xy 424.452473 -7.060721) (xy 424.40659 -7.031232) (xy 424.365371 -6.995512) (xy 424.329654 -6.954291)
			(xy 424.300167 -6.908406) (xy 424.27751 -6.858792) (xy 424.262144 -6.806459) (xy 424.254382 -6.752471)
			(xy 418.270457 -6.752471) (xy 418.262695 -6.806451) (xy 418.247329 -6.85878) (xy 418.224673 -6.908389)
			(xy 418.195187 -6.954268) (xy 418.159471 -6.995484) (xy 418.118254 -7.031198) (xy 418.072373 -7.060682)
			(xy 418.022763 -7.083336) (xy 417.970434 -7.098699) (xy 417.916451 -7.106458) (xy 417.889182 -7.10692)
			(xy 417.025582 -7.10692) (xy 416.99831 -7.106516) (xy 416.944323 -7.098752) (xy 416.89199 -7.083383)
			(xy 416.842376 -7.060723) (xy 416.796493 -7.031234) (xy 416.755273 -6.995515) (xy 416.719555 -6.954293)
			(xy 416.690068 -6.908408) (xy 416.667411 -6.858793) (xy 416.652045 -6.806459) (xy 416.644282 -6.752472)
			(xy 414.670433 -6.752472) (xy 414.662674 -6.806439) (xy 414.647312 -6.858759) (xy 414.624662 -6.908361)
			(xy 414.595183 -6.954235) (xy 414.559476 -6.995447) (xy 414.518267 -7.031159) (xy 414.472397 -7.060642)
			(xy 414.422797 -7.083298) (xy 414.370478 -7.098666) (xy 414.316505 -7.106431) (xy 414.28924 -7.10692)
			(xy 413.42564 -7.10692) (xy 413.398364 -7.106543) (xy 413.344367 -7.098785) (xy 413.292024 -7.08342)
			(xy 413.2424 -7.060762) (xy 413.196506 -7.031273) (xy 413.155277 -6.995551) (xy 413.119551 -6.954326)
			(xy 413.090057 -6.908435) (xy 413.067394 -6.858814) (xy 413.052024 -6.806472) (xy 413.04426 -6.752476)
			(xy 405.560556 -6.752476) (xy 405.552795 -6.806452) (xy 405.537429 -6.858781) (xy 405.514772 -6.90839)
			(xy 405.485285 -6.95427) (xy 405.449569 -6.995486) (xy 405.408351 -7.0312) (xy 405.362469 -7.060684)
			(xy 405.312858 -7.083337) (xy 405.260529 -7.0987) (xy 405.206545 -7.106458) (xy 405.179276 -7.10692)
			(xy 404.315676 -7.10692) (xy 404.288405 -7.106516) (xy 404.234418 -7.098751) (xy 404.182085 -7.083381)
			(xy 404.132473 -7.060721) (xy 404.08659 -7.031232) (xy 404.045371 -6.995512) (xy 404.009654 -6.954291)
			(xy 403.980167 -6.908406) (xy 403.95751 -6.858792) (xy 403.942144 -6.806459) (xy 403.934382 -6.752471)
			(xy 401.960357 -6.752471) (xy 401.952595 -6.806452) (xy 401.937229 -6.85878) (xy 401.914573 -6.908389)
			(xy 401.885086 -6.954269) (xy 401.849371 -6.995485) (xy 401.808153 -7.031198) (xy 401.762272 -7.060682)
			(xy 401.712661 -7.083336) (xy 401.660332 -7.098699) (xy 401.606349 -7.106458) (xy 401.57908 -7.10692)
			(xy 400.71548 -7.10692) (xy 400.688209 -7.106516) (xy 400.634221 -7.098751) (xy 400.581888 -7.083383)
			(xy 400.532275 -7.060723) (xy 400.486392 -7.031233) (xy 400.445172 -6.995514) (xy 400.409455 -6.954292)
			(xy 400.379968 -6.908407) (xy 400.35731 -6.858793) (xy 400.341944 -6.806459) (xy 400.334182 -6.752471)
			(xy 398.360333 -6.752471) (xy 398.352574 -6.806439) (xy 398.337212 -6.85876) (xy 398.314561 -6.908362)
			(xy 398.285082 -6.954236) (xy 398.249375 -6.995448) (xy 398.208166 -7.031159) (xy 398.162295 -7.060643)
			(xy 398.112695 -7.083299) (xy 398.060376 -7.098666) (xy 398.006403 -7.106431) (xy 397.979138 -7.10692)
			(xy 397.115538 -7.10692) (xy 397.088262 -7.106543) (xy 397.034265 -7.098784) (xy 396.981922 -7.08342)
			(xy 396.932299 -7.060762) (xy 396.886405 -7.031272) (xy 396.845176 -6.995551) (xy 396.809451 -6.954325)
			(xy 396.779956 -6.908434) (xy 396.757294 -6.858813) (xy 396.741924 -6.806472) (xy 396.73416 -6.752476)
			(xy 394.760456 -6.752476) (xy 394.752695 -6.806449) (xy 394.73733 -6.858777) (xy 394.714675 -6.908385)
			(xy 394.68519 -6.954264) (xy 394.649476 -6.995479) (xy 394.60826 -7.031193) (xy 394.562381 -7.060677)
			(xy 394.512773 -7.083332) (xy 394.460446 -7.098696) (xy 394.406464 -7.106457) (xy 394.379196 -7.10692)
			(xy 393.515596 -7.10692) (xy 393.488324 -7.106517) (xy 393.434335 -7.098754) (xy 393.382 -7.083387)
			(xy 393.332385 -7.060728) (xy 393.286499 -7.031239) (xy 393.245278 -6.995519) (xy 393.209559 -6.954297)
			(xy 393.18007 -6.908412) (xy 393.157412 -6.858796) (xy 393.142045 -6.806461) (xy 393.134283 -6.752472)
			(xy 388.110984 -6.752472) (xy 388.110984 -9.780016) (xy 388.110499 -9.850398) (xy 388.102605 -9.99094)
			(xy 388.086844 -10.130819) (xy 388.063264 -10.269594) (xy 388.03194 -10.406828) (xy 387.992971 -10.54209)
			(xy 387.946478 -10.674954) (xy 387.892609 -10.805003) (xy 387.831533 -10.931826) (xy 387.763442 -11.055026)
			(xy 387.68855 -11.174213) (xy 387.607093 -11.289014) (xy 387.519328 -11.399067) (xy 387.425529 -11.504025)
			(xy 387.325993 -11.60356) (xy 387.221033 -11.697356) (xy 387.110979 -11.78512) (xy 386.996176 -11.866575)
			(xy 386.876988 -11.941465) (xy 386.753787 -12.009554) (xy 386.626963 -12.070627) (xy 386.496913 -12.124494)
			(xy 386.364048 -12.170984) (xy 386.228785 -12.209951) (xy 386.091551 -12.241273) (xy 385.952775 -12.26485)
			(xy 385.812896 -12.280609) (xy 385.672354 -12.2885) (xy 385.601972 -12.289028) (xy 260.800088 -12.289028)
			(xy 260.744319 -12.28955) (xy 260.633094 -12.297886) (xy 260.522803 -12.314511) (xy 260.414062 -12.339331)
			(xy 260.30748 -12.372208) (xy 260.234662 -12.400788) (xy 436.813452 -12.400788) (xy 436.813941 -12.359678)
			(xy 436.821529 -12.27781) (xy 436.83664 -12.196991) (xy 436.859145 -12.117912) (xy 436.888851 -12.041247)
			(xy 436.925505 -11.96765) (xy 436.968795 -11.89775) (xy 437.01835 -11.832142) (xy 437.073748 -11.771388)
			(xy 437.134516 -11.716006) (xy 437.200136 -11.666467) (xy 437.270047 -11.623195) (xy 437.343653 -11.58656)
			(xy 437.420326 -11.556873) (xy 437.499411 -11.534389) (xy 437.580234 -11.519298) (xy 437.662104 -11.511731)
			(xy 437.703214 -11.51128) (xy 437.747029 -11.511772) (xy 437.83424 -11.520318) (xy 437.920187 -11.537406)
			(xy 438.004035 -11.562868) (xy 438.084971 -11.596458) (xy 438.123838 -11.61669) (xy 438.135191 -11.622017)
			(xy 438.160237 -11.622017) (xy 438.17159 -11.61669) (xy 438.210465 -11.596477) (xy 438.291405 -11.562905)
			(xy 438.375252 -11.537448) (xy 438.461195 -11.520353) (xy 438.548401 -11.511784) (xy 438.592214 -11.51128)
			(xy 438.636029 -11.511772) (xy 438.72324 -11.520318) (xy 438.809187 -11.537406) (xy 438.893035 -11.562868)
			(xy 438.973971 -11.596458) (xy 439.012838 -11.61669) (xy 439.024191 -11.622017) (xy 439.049237 -11.622017)
			(xy 439.06059 -11.61669) (xy 439.099465 -11.596477) (xy 439.180405 -11.562905) (xy 439.264252 -11.537448)
			(xy 439.350195 -11.520353) (xy 439.437401 -11.511784) (xy 439.481214 -11.51128) (xy 439.521951 -11.511719)
			(xy 439.603086 -11.519152) (xy 439.683202 -11.533973) (xy 439.761626 -11.556057) (xy 439.837703 -11.585219)
			(xy 439.910794 -11.621216) (xy 439.94578 -11.64209) (xy 439.954798 -11.647053) (xy 439.975154 -11.650004)
			(xy 439.995036 -11.644737) (xy 440.003438 -11.638788) (xy 440.091322 -11.570462) (xy 440.10072 -11.54049)
			(xy 440.095894 -11.52525) (xy 440.083229 -11.482506) (xy 440.065483 -11.395136) (xy 440.056563 -11.306429)
			(xy 440.056016 -11.261852) (xy 440.056016 -11.26109) (xy 440.056438 -11.22287) (xy 440.062998 -11.146712)
			(xy 440.076079 -11.071399) (xy 440.095582 -10.997489) (xy 440.108086 -10.96137) (xy 440.110695 -10.953059)
			(xy 440.110679 -10.935651) (xy 440.108086 -10.927334) (xy 440.095582 -10.891215) (xy 440.076095 -10.817302)
			(xy 440.063015 -10.74199) (xy 440.056437 -10.665834) (xy 440.056016 -10.627614) (xy 440.056016 -10.626852)
			(xy 440.05652 -10.584504) (xy 440.064571 -10.50019) (xy 440.0806 -10.417024) (xy 440.104461 -10.335757)
			(xy 440.13594 -10.257127) (xy 440.174751 -10.181846) (xy 440.220541 -10.110594) (xy 440.272897 -10.044018)
			(xy 440.331345 -9.98272) (xy 440.395355 -9.927255) (xy 440.464347 -9.878126) (xy 440.537697 -9.835777)
			(xy 440.61474 -9.800593) (xy 440.694779 -9.772891) (xy 440.777088 -9.752923) (xy 440.860923 -9.74087)
			(xy 440.945524 -9.73684) (xy 441.030125 -9.74087) (xy 441.11396 -9.752923) (xy 441.196269 -9.772891)
			(xy 441.276308 -9.800593) (xy 441.353351 -9.835777) (xy 441.426701 -9.878126) (xy 441.495693 -9.927255)
			(xy 441.559703 -9.98272) (xy 441.618151 -10.044018) (xy 441.670507 -10.110594) (xy 441.716297 -10.181846)
			(xy 441.755108 -10.257127) (xy 441.786587 -10.335757) (xy 441.810448 -10.417024) (xy 441.826477 -10.50019)
			(xy 441.834528 -10.584504) (xy 441.835032 -10.626852) (xy 441.835032 -10.627614) (xy 441.834614 -10.665834)
			(xy 441.828053 -10.741992) (xy 441.814972 -10.817305) (xy 441.795467 -10.891215) (xy 441.782962 -10.927334)
			(xy 441.780399 -10.935656) (xy 441.780383 -10.953054) (xy 441.782962 -10.96137) (xy 441.795465 -10.997489)
			(xy 441.814952 -11.071403) (xy 441.828033 -11.146715) (xy 441.834611 -11.22287) (xy 441.835032 -11.26109)
			(xy 441.835032 -11.261852) (xy 441.834502 -11.302954) (xy 441.826922 -11.384807) (xy 441.811821 -11.465611)
			(xy 441.789329 -11.544677) (xy 441.759637 -11.621331) (xy 441.722999 -11.694918) (xy 441.679728 -11.764811)
			(xy 441.630192 -11.830413) (xy 441.574815 -11.891164) (xy 441.514068 -11.946546) (xy 441.44847 -11.996087)
			(xy 441.378581 -12.039364) (xy 441.304997 -12.076008) (xy 441.228346 -12.105706) (xy 441.149281 -12.128204)
			(xy 441.068478 -12.143312) (xy 440.986626 -12.150899) (xy 440.945524 -12.15136) (xy 440.945016 -12.15136)
			(xy 440.904322 -12.150875) (xy 440.823276 -12.143416) (xy 440.74325 -12.128584) (xy 440.664913 -12.106505)
			(xy 440.58892 -12.077363) (xy 440.515907 -12.041401) (xy 440.480958 -12.02055) (xy 440.471926 -12.015614)
			(xy 440.451579 -12.012649) (xy 440.431701 -12.017907) (xy 440.4233 -12.023852) (xy 440.335416 -12.092178)
			(xy 440.326018 -12.12215) (xy 440.330844 -12.13739) (xy 440.343568 -12.180123) (xy 440.361398 -12.267491)
			(xy 440.370394 -12.356204) (xy 440.370976 -12.400788) (xy 440.370415 -12.444238) (xy 440.361895 -12.530719)
			(xy 440.344992 -12.615959) (xy 440.319868 -12.699148) (xy 440.286761 -12.779495) (xy 440.266836 -12.81811)
			(xy 440.262961 -12.82623) (xy 440.260628 -12.84406) (xy 440.262264 -12.852908) (xy 440.272023 -12.900055)
			(xy 440.282457 -12.995773) (xy 440.283092 -13.043916) (xy 440.282667 -13.085188) (xy 440.275027 -13.167377)
			(xy 440.259804 -13.248505) (xy 440.23713 -13.327874) (xy 440.2072 -13.4048) (xy 440.170271 -13.478622)
			(xy 440.126661 -13.548705) (xy 440.076745 -13.614446) (xy 440.020952 -13.675279) (xy 439.959763 -13.730681)
			(xy 439.893704 -13.780175) (xy 439.823344 -13.823336) (xy 439.786522 -13.841984) (xy 439.778885 -13.846179)
			(xy 439.766763 -13.858679) (xy 439.759479 -13.874495) (xy 439.758328 -13.883132) (xy 439.755251 -13.911241)
			(xy 439.741951 -13.966197) (xy 439.720685 -14.018587) (xy 439.69192 -14.067266) (xy 439.656285 -14.111165)
			(xy 439.643167 -14.123162) (xy 440.58586 -14.123162) (xy 440.586283 -14.084873) (xy 440.592885 -14.008579)
			(xy 440.60603 -13.933136) (xy 440.625619 -13.859105) (xy 440.638184 -13.822934) (xy 440.640853 -13.814502)
			(xy 440.64084 -13.796827) (xy 440.638184 -13.78839) (xy 440.625655 -13.752208) (xy 440.606078 -13.678176)
			(xy 440.592927 -13.602738) (xy 440.586298 -13.52645) (xy 440.58586 -13.488162) (xy 440.586364 -13.445801)
			(xy 440.594417 -13.361464) (xy 440.610451 -13.278274) (xy 440.634319 -13.196984) (xy 440.665807 -13.118332)
			(xy 440.704629 -13.043029) (xy 440.750432 -12.971757) (xy 440.802803 -12.905161) (xy 440.861268 -12.843846)
			(xy 440.925296 -12.788365) (xy 440.994308 -12.739222) (xy 441.067678 -12.696862) (xy 441.144743 -12.661667)
			(xy 441.224805 -12.633958) (xy 441.307138 -12.613984) (xy 441.390997 -12.601927) (xy 441.475622 -12.597896)
			(xy 441.560247 -12.601927) (xy 441.644106 -12.613984) (xy 441.726439 -12.633958) (xy 441.806501 -12.661667)
			(xy 441.883566 -12.696862) (xy 441.956936 -12.739222) (xy 442.025948 -12.788365) (xy 442.089976 -12.843846)
			(xy 442.135955 -12.892066) (xy 445.44847 -12.892066) (xy 445.44847 -12.837534) (xy 445.456231 -12.783558)
			(xy 445.471594 -12.731236) (xy 445.494246 -12.681632) (xy 445.523728 -12.635757) (xy 445.559438 -12.594545)
			(xy 445.600649 -12.558834) (xy 445.646523 -12.529351) (xy 445.696126 -12.506697) (xy 445.748448 -12.491333)
			(xy 445.802424 -12.483571) (xy 445.82969 -12.483084) (xy 446.69329 -12.483084) (xy 446.720565 -12.483455)
			(xy 446.774559 -12.491217) (xy 446.826899 -12.506584) (xy 446.87652 -12.529244) (xy 446.92241 -12.558735)
			(xy 446.963636 -12.594456) (xy 446.999359 -12.635682) (xy 447.028851 -12.681571) (xy 447.051512 -12.731191)
			(xy 447.066881 -12.783531) (xy 447.074644 -12.837525) (xy 447.074644 -12.892075) (xy 447.066881 -12.946069)
			(xy 447.051512 -12.998409) (xy 447.028851 -13.048029) (xy 446.999359 -13.093918) (xy 446.963636 -13.135144)
			(xy 446.92241 -13.170865) (xy 446.87652 -13.200356) (xy 446.826899 -13.223016) (xy 446.774559 -13.238383)
			(xy 446.720565 -13.246145) (xy 446.69329 -13.246608) (xy 445.82969 -13.246608) (xy 445.802424 -13.246029)
			(xy 445.748448 -13.238267) (xy 445.696126 -13.222903) (xy 445.646523 -13.200249) (xy 445.600649 -13.170766)
			(xy 445.559438 -13.135055) (xy 445.523728 -13.093843) (xy 445.494246 -13.047968) (xy 445.471594 -12.998364)
			(xy 445.456231 -12.946042) (xy 445.44847 -12.892066) (xy 442.135955 -12.892066) (xy 442.148441 -12.905161)
			(xy 442.200812 -12.971757) (xy 442.246615 -13.043029) (xy 442.285437 -13.118332) (xy 442.316925 -13.196984)
			(xy 442.340793 -13.278274) (xy 442.356827 -13.361464) (xy 442.36488 -13.445801) (xy 442.365384 -13.488162)
			(xy 442.364966 -13.526452) (xy 442.358362 -13.602745) (xy 442.345216 -13.678188) (xy 442.325626 -13.752219)
			(xy 442.31306 -13.78839) (xy 442.310428 -13.796831) (xy 442.310415 -13.814498) (xy 442.31306 -13.822934)
			(xy 442.325598 -13.859113) (xy 442.345172 -13.933146) (xy 442.358321 -14.008585) (xy 442.364947 -14.084874)
			(xy 442.365384 -14.123162) (xy 442.36488 -14.165523) (xy 442.356827 -14.24986) (xy 442.340793 -14.33305)
			(xy 442.316925 -14.41434) (xy 442.285437 -14.492992) (xy 442.268155 -14.526514) (xy 449.780152 -14.526514)
			(xy 449.780656 -14.484153) (xy 449.788709 -14.399816) (xy 449.804743 -14.316626) (xy 449.828611 -14.235336)
			(xy 449.860099 -14.156684) (xy 449.898921 -14.081381) (xy 449.944724 -14.010109) (xy 449.997095 -13.943513)
			(xy 450.05556 -13.882198) (xy 450.119588 -13.826717) (xy 450.1886 -13.777574) (xy 450.26197 -13.735214)
			(xy 450.339035 -13.700019) (xy 450.419097 -13.67231) (xy 450.50143 -13.652336) (xy 450.585289 -13.640279)
			(xy 450.669914 -13.636248) (xy 450.754539 -13.640279) (xy 450.838398 -13.652336) (xy 450.920731 -13.67231)
			(xy 451.000793 -13.700019) (xy 451.077858 -13.735214) (xy 451.151228 -13.777574) (xy 451.22024 -13.826717)
			(xy 451.284268 -13.882198) (xy 451.342733 -13.943513) (xy 451.395104 -14.010109) (xy 451.440907 -14.081381)
			(xy 451.479729 -14.156684) (xy 451.511217 -14.235336) (xy 451.535085 -14.316626) (xy 451.551119 -14.399816)
			(xy 451.559172 -14.484153) (xy 451.559676 -14.526514) (xy 451.559114 -14.571839) (xy 451.549887 -14.662018)
			(xy 451.531531 -14.750791) (xy 451.504235 -14.837234) (xy 451.486778 -14.879066) (xy 451.483143 -14.888844)
			(xy 451.483128 -14.909681) (xy 451.486778 -14.919452) (xy 451.504318 -14.961366) (xy 451.53178 -15.047983)
			(xy 451.550267 -15.136947) (xy 451.559587 -15.227334) (xy 451.560184 -15.272766) (xy 451.560184 -15.273782)
			(xy 451.559623 -15.318552) (xy 451.550621 -15.407639) (xy 451.532717 -15.495371) (xy 451.506092 -15.580861)
			(xy 451.489064 -15.62227) (xy 451.485509 -15.631864) (xy 451.485503 -15.652304) (xy 451.489064 -15.661894)
			(xy 451.50607 -15.703278) (xy 451.532693 -15.788702) (xy 451.550602 -15.876368) (xy 451.559616 -15.96539)
			(xy 451.560184 -16.010128) (xy 451.560184 -16.010382) (xy 451.55968 -16.05273) (xy 451.551629 -16.137044)
			(xy 451.5356 -16.22021) (xy 451.511739 -16.301477) (xy 451.48026 -16.380107) (xy 451.441449 -16.455388)
			(xy 451.395659 -16.52664) (xy 451.343303 -16.593216) (xy 451.284855 -16.654514) (xy 451.220845 -16.709979)
			(xy 451.151853 -16.759108) (xy 451.078503 -16.801457) (xy 451.00146 -16.836641) (xy 450.921421 -16.864343)
			(xy 450.839112 -16.884311) (xy 450.755277 -16.896364) (xy 450.670676 -16.900395) (xy 450.586075 -16.896364)
			(xy 450.50224 -16.884311) (xy 450.419931 -16.864343) (xy 450.339892 -16.836641) (xy 450.262849 -16.801457)
			(xy 450.189499 -16.759108) (xy 450.120507 -16.709979) (xy 450.056497 -16.654514) (xy 449.998049 -16.593216)
			(xy 449.945693 -16.52664) (xy 449.899903 -16.455388) (xy 449.861092 -16.380107) (xy 449.829613 -16.301477)
			(xy 449.805752 -16.22021) (xy 449.789723 -16.137044) (xy 449.781672 -16.05273) (xy 449.781168 -16.010382)
			(xy 449.781168 -16.010128) (xy 449.781731 -15.96539) (xy 449.790749 -15.876368) (xy 449.808655 -15.788701)
			(xy 449.83527 -15.703273) (xy 449.852288 -15.661894) (xy 449.855865 -15.652307) (xy 449.855859 -15.63186)
			(xy 449.852288 -15.62227) (xy 449.835263 -15.580859) (xy 449.808628 -15.495372) (xy 449.790721 -15.40764)
			(xy 449.781723 -15.318552) (xy 449.781168 -15.273782) (xy 449.781749 -15.228458) (xy 449.79099 -15.138283)
			(xy 449.809345 -15.049513) (xy 449.836623 -14.963067) (xy 449.854066 -14.92123) (xy 449.857691 -14.911438)
			(xy 449.857571 -14.890584) (xy 449.853812 -14.880844) (xy 449.836183 -14.838823) (xy 449.808624 -14.751958)
			(xy 449.790079 -14.662732) (xy 449.780742 -14.57208) (xy 449.780152 -14.526514) (xy 442.268155 -14.526514)
			(xy 442.246615 -14.568295) (xy 442.200812 -14.639567) (xy 442.148441 -14.706163) (xy 442.089976 -14.767478)
			(xy 442.025948 -14.822959) (xy 441.956936 -14.872102) (xy 441.883566 -14.914462) (xy 441.806501 -14.949657)
			(xy 441.726439 -14.977366) (xy 441.644106 -14.99734) (xy 441.560247 -15.009397) (xy 441.475622 -15.013429)
			(xy 441.390997 -15.009397) (xy 441.307138 -14.99734) (xy 441.224805 -14.977366) (xy 441.144743 -14.949657)
			(xy 441.067678 -14.914462) (xy 440.994308 -14.872102) (xy 440.925296 -14.822959) (xy 440.861268 -14.767478)
			(xy 440.802803 -14.706163) (xy 440.750432 -14.639567) (xy 440.704629 -14.568295) (xy 440.665807 -14.492992)
			(xy 440.634319 -14.41434) (xy 440.610451 -14.33305) (xy 440.594417 -14.24986) (xy 440.586364 -14.165523)
			(xy 440.58586 -14.123162) (xy 439.643167 -14.123162) (xy 439.614561 -14.149324) (xy 439.567661 -14.180907)
			(xy 439.516614 -14.205222) (xy 439.462537 -14.221736) (xy 439.406615 -14.230088) (xy 439.378344 -14.230604)
			(xy 439.350975 -14.230111) (xy 439.296797 -14.2223) (xy 439.244294 -14.206817) (xy 439.194547 -14.183981)
			(xy 439.148579 -14.154262) (xy 439.127646 -14.136624) (xy 439.127392 -14.13637) (xy 439.120314 -14.130771)
			(xy 439.103391 -14.124533) (xy 439.094372 -14.124178) (xy 439.027316 -14.124178) (xy 439.018301 -14.124547)
			(xy 439.001384 -14.130787) (xy 438.994296 -14.13637) (xy 438.994296 -14.136624) (xy 438.994042 -14.136624)
			(xy 438.973108 -14.154261) (xy 438.927135 -14.183972) (xy 438.877388 -14.206808) (xy 438.824888 -14.2223)
			(xy 438.770713 -14.230129) (xy 438.743344 -14.230604) (xy 438.713998 -14.230028) (xy 438.656001 -14.221024)
			(xy 438.600065 -14.203253) (xy 438.547506 -14.177132) (xy 438.499563 -14.143277) (xy 438.457364 -14.102486)
			(xy 438.421903 -14.055718) (xy 438.394015 -14.004075) (xy 438.38368 -13.976604) (xy 438.380221 -13.968026)
			(xy 438.368225 -13.953963) (xy 438.360312 -13.949172) (xy 438.333388 -13.93444) (xy 438.324705 -13.93016)
			(xy 438.305508 -13.927807) (xy 438.29605 -13.929868) (xy 438.259095 -13.939128) (xy 438.184005 -13.952036)
			(xy 438.108086 -13.958466) (xy 438.06999 -13.958824) (xy 438.028658 -13.958363) (xy 437.94635 -13.95071)
			(xy 437.865107 -13.935453) (xy 437.78563 -13.912724) (xy 437.708605 -13.882718) (xy 437.634696 -13.845694)
			(xy 437.564542 -13.801972) (xy 437.498747 -13.751929) (xy 437.43788 -13.695998) (xy 437.382465 -13.634659)
			(xy 437.332981 -13.568444) (xy 437.289854 -13.497922) (xy 437.253456 -13.423703) (xy 437.224103 -13.346427)
			(xy 437.202046 -13.266761) (xy 437.187477 -13.185391) (xy 437.18353 -13.144246) (xy 437.182106 -13.133691)
			(xy 437.171856 -13.11505) (xy 437.163718 -13.108178) (xy 437.131484 -13.082996) (xy 437.071245 -13.027653)
			(xy 437.016344 -12.967011) (xy 436.967245 -12.901582) (xy 436.924364 -12.831919) (xy 436.888063 -12.758612)
			(xy 436.858649 -12.682281) (xy 436.83637 -12.603571) (xy 436.821416 -12.523147) (xy 436.813913 -12.441689)
			(xy 436.813452 -12.400788) (xy 260.234662 -12.400788) (xy 260.203654 -12.412958) (xy 260.103162 -12.461353)
			(xy 260.006569 -12.517122) (xy 259.914413 -12.579954) (xy 259.82721 -12.649497) (xy 259.745448 -12.725362)
			(xy 259.669584 -12.807125) (xy 259.601843 -12.89207) (xy 431.453248 -12.89207) (xy 431.453248 -12.83753)
			(xy 431.46101 -12.783546) (xy 431.476376 -12.731216) (xy 431.499035 -12.681606) (xy 431.528523 -12.635726)
			(xy 431.564241 -12.594509) (xy 431.605461 -12.558796) (xy 431.651345 -12.529313) (xy 431.700957 -12.506661)
			(xy 431.753289 -12.4913) (xy 431.807274 -12.483544) (xy 431.834544 -12.483084) (xy 432.698144 -12.483084)
			(xy 432.725415 -12.483482) (xy 432.7794 -12.491249) (xy 432.83173 -12.50662) (xy 432.881341 -12.529282)
			(xy 432.927222 -12.558772) (xy 432.968439 -12.594492) (xy 433.004154 -12.635713) (xy 433.033639 -12.681598)
			(xy 433.056295 -12.731211) (xy 433.07166 -12.783543) (xy 433.079422 -12.837529) (xy 433.079422 -12.892071)
			(xy 433.07166 -12.946057) (xy 433.056295 -12.998389) (xy 433.033639 -13.048002) (xy 433.004154 -13.093887)
			(xy 432.968439 -13.135108) (xy 432.927222 -13.170828) (xy 432.881341 -13.200318) (xy 432.83173 -13.22298)
			(xy 432.7794 -13.238351) (xy 432.725415 -13.246118) (xy 432.698144 -13.246608) (xy 431.834544 -13.246608)
			(xy 431.807274 -13.246056) (xy 431.753289 -13.2383) (xy 431.700957 -13.222939) (xy 431.651345 -13.200287)
			(xy 431.605461 -13.170804) (xy 431.564241 -13.135091) (xy 431.528523 -13.093874) (xy 431.499035 -13.047994)
			(xy 431.476376 -12.998384) (xy 431.46101 -12.946054) (xy 431.453248 -12.89207) (xy 259.601843 -12.89207)
			(xy 259.600042 -12.894329) (xy 259.537211 -12.986486) (xy 259.481443 -13.08308) (xy 259.43305 -13.183572)
			(xy 259.392301 -13.287399) (xy 259.359426 -13.393981) (xy 259.334607 -13.502722) (xy 259.317984 -13.613014)
			(xy 259.309649 -13.724239) (xy 259.309108 -13.780008) (xy 259.309108 -17.126458) (xy 310.265572 -17.126458)
			(xy 310.265992 -17.082972) (xy 310.273576 -16.996331) (xy 310.288682 -16.910681) (xy 310.311195 -16.826674)
			(xy 310.340944 -16.744948) (xy 310.377702 -16.666126) (xy 310.421191 -16.590808) (xy 310.471078 -16.519566)
			(xy 310.526985 -16.452943) (xy 310.588485 -16.391447) (xy 310.65511 -16.335544) (xy 310.726355 -16.285661)
			(xy 310.801676 -16.242177) (xy 310.8805 -16.205422) (xy 310.962227 -16.175678) (xy 311.046236 -16.15317)
			(xy 311.131887 -16.138068) (xy 311.218528 -16.13049) (xy 311.262014 -16.130016) (xy 311.287414 -16.130016)
			(xy 311.33271 -16.130609) (xy 311.422936 -16.13873) (xy 311.512071 -16.154907) (xy 311.599397 -16.179009)
			(xy 311.684211 -16.210841) (xy 311.76583 -16.250148) (xy 311.843598 -16.296613) (xy 311.916887 -16.349861)
			(xy 311.985108 -16.409465) (xy 312.047712 -16.474944) (xy 312.104194 -16.545772) (xy 312.1541 -16.621377)
			(xy 312.197028 -16.701151) (xy 312.232632 -16.784452) (xy 312.260626 -16.870609) (xy 312.280784 -16.958929)
			(xy 312.292944 -17.0487) (xy 312.297009 -17.1392) (xy 312.292944 -17.2297) (xy 312.280784 -17.319471)
			(xy 312.260626 -17.407791) (xy 312.232632 -17.493948) (xy 312.197028 -17.577249) (xy 312.163448 -17.639652)
			(xy 389.652738 -17.639652) (xy 389.652738 -17.585148) (xy 389.660494 -17.531197) (xy 389.675849 -17.4789)
			(xy 389.69849 -17.42932) (xy 389.727956 -17.383466) (xy 389.763647 -17.342273) (xy 389.804838 -17.306578)
			(xy 389.850688 -17.277107) (xy 389.900266 -17.254462) (xy 389.952562 -17.239102) (xy 390.006512 -17.23134)
			(xy 390.033764 -17.230852) (xy 390.897364 -17.230852) (xy 390.924616 -17.231393) (xy 390.978565 -17.239145)
			(xy 391.030862 -17.254496) (xy 391.080441 -17.277134) (xy 391.126294 -17.306598) (xy 391.167486 -17.342288)
			(xy 391.20318 -17.383477) (xy 391.232649 -17.429327) (xy 391.255291 -17.478905) (xy 391.270648 -17.5312)
			(xy 391.278405 -17.585148) (xy 391.278405 -17.639652) (xy 395.240738 -17.639652) (xy 395.240738 -17.585148)
			(xy 395.248494 -17.531197) (xy 395.263849 -17.4789) (xy 395.28649 -17.42932) (xy 395.315956 -17.383466)
			(xy 395.351647 -17.342273) (xy 395.392838 -17.306578) (xy 395.438688 -17.277107) (xy 395.488266 -17.254462)
			(xy 395.540562 -17.239102) (xy 395.594512 -17.23134) (xy 395.621764 -17.230852) (xy 396.485364 -17.230852)
			(xy 396.512616 -17.231393) (xy 396.566565 -17.239145) (xy 396.618862 -17.254496) (xy 396.668441 -17.277134)
			(xy 396.714294 -17.306598) (xy 396.755486 -17.342288) (xy 396.79118 -17.383477) (xy 396.820649 -17.429327)
			(xy 396.843291 -17.478905) (xy 396.858648 -17.5312) (xy 396.866405 -17.585148) (xy 396.866405 -17.639652)
			(xy 400.828738 -17.639652) (xy 400.828738 -17.585148) (xy 400.836494 -17.531197) (xy 400.851849 -17.4789)
			(xy 400.87449 -17.42932) (xy 400.903956 -17.383466) (xy 400.939647 -17.342273) (xy 400.980838 -17.306578)
			(xy 401.026688 -17.277107) (xy 401.076266 -17.254462) (xy 401.128562 -17.239102) (xy 401.182512 -17.23134)
			(xy 401.209764 -17.230852) (xy 402.073364 -17.230852) (xy 402.100616 -17.231393) (xy 402.154565 -17.239145)
			(xy 402.206862 -17.254496) (xy 402.256441 -17.277134) (xy 402.302294 -17.306598) (xy 402.343486 -17.342288)
			(xy 402.37918 -17.383477) (xy 402.408649 -17.429327) (xy 402.431291 -17.478905) (xy 402.446648 -17.5312)
			(xy 402.454405 -17.585148) (xy 402.454405 -17.639652) (xy 402.454301 -17.640372) (xy 406.415424 -17.640372)
			(xy 406.415424 -17.585828) (xy 406.423187 -17.53184) (xy 406.438554 -17.479507) (xy 406.461214 -17.429893)
			(xy 406.490704 -17.38401) (xy 406.526425 -17.342791) (xy 406.567649 -17.307076) (xy 406.613536 -17.277591)
			(xy 406.663152 -17.254938) (xy 406.715487 -17.239576) (xy 406.769476 -17.23182) (xy 406.796748 -17.23136)
			(xy 407.660348 -17.23136) (xy 407.687617 -17.231806) (xy 407.741598 -17.239573) (xy 407.793925 -17.254944)
			(xy 407.843532 -17.277604) (xy 407.88941 -17.307093) (xy 407.930624 -17.34281) (xy 407.966336 -17.384029)
			(xy 407.995819 -17.42991) (xy 408.018473 -17.47952) (xy 408.033837 -17.531849) (xy 408.041598 -17.585831)
			(xy 408.041598 -17.640369) (xy 408.041598 -17.640372) (xy 412.003424 -17.640372) (xy 412.003424 -17.585828)
			(xy 412.011187 -17.53184) (xy 412.026554 -17.479507) (xy 412.049214 -17.429893) (xy 412.078704 -17.38401)
			(xy 412.114425 -17.342791) (xy 412.155649 -17.307076) (xy 412.201536 -17.277591) (xy 412.251152 -17.254938)
			(xy 412.303487 -17.239576) (xy 412.357476 -17.23182) (xy 412.384748 -17.23136) (xy 413.248348 -17.23136)
			(xy 413.275617 -17.231806) (xy 413.329598 -17.239573) (xy 413.381925 -17.254944) (xy 413.431532 -17.277604)
			(xy 413.47741 -17.307093) (xy 413.518624 -17.34281) (xy 413.554336 -17.384029) (xy 413.583819 -17.42991)
			(xy 413.606473 -17.47952) (xy 413.621837 -17.531849) (xy 413.629598 -17.585831) (xy 413.629598 -17.639653)
			(xy 417.898538 -17.639653) (xy 417.898538 -17.585147) (xy 417.906295 -17.531195) (xy 417.92165 -17.478897)
			(xy 417.944292 -17.429315) (xy 417.97376 -17.383461) (xy 418.009453 -17.342267) (xy 418.050645 -17.306572)
			(xy 418.096498 -17.277102) (xy 418.146078 -17.254457) (xy 418.198376 -17.239099) (xy 418.252327 -17.231339)
			(xy 418.27958 -17.230852) (xy 419.14318 -17.230852) (xy 419.170431 -17.231394) (xy 419.224378 -17.239148)
			(xy 419.276673 -17.2545) (xy 419.326251 -17.277139) (xy 419.372101 -17.306604) (xy 419.413292 -17.342294)
			(xy 419.448984 -17.383483) (xy 419.478451 -17.429332) (xy 419.501093 -17.478908) (xy 419.516448 -17.531202)
			(xy 419.524205 -17.585149) (xy 419.524205 -17.639651) (xy 419.524205 -17.639653) (xy 423.486538 -17.639653)
			(xy 423.486538 -17.585147) (xy 423.494295 -17.531195) (xy 423.50965 -17.478897) (xy 423.532292 -17.429315)
			(xy 423.56176 -17.383461) (xy 423.597453 -17.342267) (xy 423.638645 -17.306572) (xy 423.684498 -17.277102)
			(xy 423.734078 -17.254457) (xy 423.786376 -17.239099) (xy 423.840327 -17.231339) (xy 423.86758 -17.230852)
			(xy 424.73118 -17.230852) (xy 424.758431 -17.231394) (xy 424.812378 -17.239148) (xy 424.864673 -17.2545)
			(xy 424.914251 -17.277139) (xy 424.960101 -17.306604) (xy 425.001292 -17.342294) (xy 425.036984 -17.383483)
			(xy 425.066451 -17.429332) (xy 425.089093 -17.478908) (xy 425.104448 -17.531202) (xy 425.112205 -17.585149)
			(xy 425.112205 -17.639651) (xy 425.112102 -17.640368) (xy 429.107346 -17.640368) (xy 429.107346 -17.585832)
			(xy 429.115108 -17.531852) (xy 429.130472 -17.479525) (xy 429.153127 -17.429918) (xy 429.182611 -17.38404)
			(xy 429.218324 -17.342824) (xy 429.25954 -17.307111) (xy 429.305418 -17.277627) (xy 429.355025 -17.254972)
			(xy 429.407352 -17.239608) (xy 429.461332 -17.231846) (xy 429.4886 -17.23136) (xy 430.3522 -17.23136)
			(xy 430.379471 -17.231802) (xy 430.433458 -17.239565) (xy 430.48579 -17.254931) (xy 430.535403 -17.277588)
			(xy 430.581287 -17.307076) (xy 430.622507 -17.342793) (xy 430.658224 -17.384013) (xy 430.687712 -17.429897)
			(xy 430.710369 -17.47951) (xy 430.725735 -17.531842) (xy 430.733498 -17.585829) (xy 430.733498 -17.640371)
			(xy 430.725735 -17.694358) (xy 430.710369 -17.74669) (xy 430.687712 -17.796303) (xy 430.658224 -17.842187)
			(xy 430.622507 -17.883407) (xy 430.581287 -17.919124) (xy 430.535403 -17.948612) (xy 430.48579 -17.971269)
			(xy 430.433458 -17.986635) (xy 430.379471 -17.994398) (xy 430.3522 -17.994884) (xy 429.4886 -17.994884)
			(xy 429.461332 -17.994354) (xy 429.407352 -17.986592) (xy 429.355025 -17.971228) (xy 429.305418 -17.948573)
			(xy 429.25954 -17.919089) (xy 429.218324 -17.883376) (xy 429.182611 -17.84216) (xy 429.153127 -17.796282)
			(xy 429.130472 -17.746675) (xy 429.115108 -17.694348) (xy 429.107346 -17.640368) (xy 425.112102 -17.640368)
			(xy 425.104448 -17.693598) (xy 425.089093 -17.745892) (xy 425.066451 -17.795468) (xy 425.036984 -17.841317)
			(xy 425.001292 -17.882506) (xy 424.960101 -17.918196) (xy 424.914251 -17.947661) (xy 424.864673 -17.9703)
			(xy 424.812378 -17.985652) (xy 424.758431 -17.993406) (xy 424.73118 -17.993868) (xy 423.86758 -17.993868)
			(xy 423.840327 -17.993461) (xy 423.786376 -17.985701) (xy 423.734078 -17.970343) (xy 423.684498 -17.947698)
			(xy 423.638645 -17.918228) (xy 423.597453 -17.882533) (xy 423.56176 -17.841339) (xy 423.532292 -17.795485)
			(xy 423.50965 -17.745903) (xy 423.494295 -17.693605) (xy 423.486538 -17.639653) (xy 419.524205 -17.639653)
			(xy 419.516448 -17.693598) (xy 419.501093 -17.745892) (xy 419.478451 -17.795468) (xy 419.448984 -17.841317)
			(xy 419.413292 -17.882506) (xy 419.372101 -17.918196) (xy 419.326251 -17.947661) (xy 419.276673 -17.9703)
			(xy 419.224378 -17.985652) (xy 419.170431 -17.993406) (xy 419.14318 -17.993868) (xy 418.27958 -17.993868)
			(xy 418.252327 -17.993461) (xy 418.198376 -17.985701) (xy 418.146078 -17.970343) (xy 418.096498 -17.947698)
			(xy 418.050645 -17.918228) (xy 418.009453 -17.882533) (xy 417.97376 -17.841339) (xy 417.944292 -17.795485)
			(xy 417.92165 -17.745903) (xy 417.906295 -17.693605) (xy 417.898538 -17.639653) (xy 413.629598 -17.639653)
			(xy 413.629598 -17.640369) (xy 413.621837 -17.694351) (xy 413.606473 -17.74668) (xy 413.583819 -17.79629)
			(xy 413.554336 -17.842171) (xy 413.518624 -17.88339) (xy 413.47741 -17.919107) (xy 413.431532 -17.948596)
			(xy 413.381925 -17.971256) (xy 413.329598 -17.986627) (xy 413.275617 -17.994394) (xy 413.248348 -17.994884)
			(xy 412.384748 -17.994884) (xy 412.357476 -17.99438) (xy 412.303487 -17.986624) (xy 412.251152 -17.971262)
			(xy 412.201536 -17.948609) (xy 412.155649 -17.919124) (xy 412.114425 -17.883409) (xy 412.078704 -17.84219)
			(xy 412.049214 -17.796307) (xy 412.026554 -17.746693) (xy 412.011187 -17.69436) (xy 412.003424 -17.640372)
			(xy 408.041598 -17.640372) (xy 408.033837 -17.694351) (xy 408.018473 -17.74668) (xy 407.995819 -17.79629)
			(xy 407.966336 -17.842171) (xy 407.930624 -17.88339) (xy 407.88941 -17.919107) (xy 407.843532 -17.948596)
			(xy 407.793925 -17.971256) (xy 407.741598 -17.986627) (xy 407.687617 -17.994394) (xy 407.660348 -17.994884)
			(xy 406.796748 -17.994884) (xy 406.769476 -17.99438) (xy 406.715487 -17.986624) (xy 406.663152 -17.971262)
			(xy 406.613536 -17.948609) (xy 406.567649 -17.919124) (xy 406.526425 -17.883409) (xy 406.490704 -17.84219)
			(xy 406.461214 -17.796307) (xy 406.438554 -17.746693) (xy 406.423187 -17.69436) (xy 406.415424 -17.640372)
			(xy 402.454301 -17.640372) (xy 402.446648 -17.6936) (xy 402.431291 -17.745895) (xy 402.408649 -17.795473)
			(xy 402.37918 -17.841323) (xy 402.343486 -17.882512) (xy 402.302294 -17.918202) (xy 402.256441 -17.947666)
			(xy 402.206862 -17.970304) (xy 402.154565 -17.985655) (xy 402.100616 -17.993407) (xy 402.073364 -17.993868)
			(xy 401.209764 -17.993868) (xy 401.182512 -17.99346) (xy 401.128562 -17.985698) (xy 401.076266 -17.970338)
			(xy 401.026688 -17.947693) (xy 400.980838 -17.918222) (xy 400.939647 -17.882527) (xy 400.903956 -17.841334)
			(xy 400.87449 -17.79548) (xy 400.851849 -17.7459) (xy 400.836494 -17.693603) (xy 400.828738 -17.639652)
			(xy 396.866405 -17.639652) (xy 396.858648 -17.6936) (xy 396.843291 -17.745895) (xy 396.820649 -17.795473)
			(xy 396.79118 -17.841323) (xy 396.755486 -17.882512) (xy 396.714294 -17.918202) (xy 396.668441 -17.947666)
			(xy 396.618862 -17.970304) (xy 396.566565 -17.985655) (xy 396.512616 -17.993407) (xy 396.485364 -17.993868)
			(xy 395.621764 -17.993868) (xy 395.594512 -17.99346) (xy 395.540562 -17.985698) (xy 395.488266 -17.970338)
			(xy 395.438688 -17.947693) (xy 395.392838 -17.918222) (xy 395.351647 -17.882527) (xy 395.315956 -17.841334)
			(xy 395.28649 -17.79548) (xy 395.263849 -17.7459) (xy 395.248494 -17.693603) (xy 395.240738 -17.639652)
			(xy 391.278405 -17.639652) (xy 391.270648 -17.6936) (xy 391.255291 -17.745895) (xy 391.232649 -17.795473)
			(xy 391.20318 -17.841323) (xy 391.167486 -17.882512) (xy 391.126294 -17.918202) (xy 391.080441 -17.947666)
			(xy 391.030862 -17.970304) (xy 390.978565 -17.985655) (xy 390.924616 -17.993407) (xy 390.897364 -17.993868)
			(xy 390.033764 -17.993868) (xy 390.006512 -17.99346) (xy 389.952562 -17.985698) (xy 389.900266 -17.970338)
			(xy 389.850688 -17.947693) (xy 389.804838 -17.918222) (xy 389.763647 -17.882527) (xy 389.727956 -17.841334)
			(xy 389.69849 -17.79548) (xy 389.675849 -17.7459) (xy 389.660494 -17.693603) (xy 389.652738 -17.639652)
			(xy 312.163448 -17.639652) (xy 312.1541 -17.657023) (xy 312.104194 -17.732628) (xy 312.047712 -17.803456)
			(xy 311.985108 -17.868935) (xy 311.916887 -17.928539) (xy 311.843598 -17.981787) (xy 311.76583 -18.028252)
			(xy 311.684211 -18.067559) (xy 311.599397 -18.099391) (xy 311.512071 -18.123493) (xy 311.422936 -18.13967)
			(xy 311.33271 -18.147791) (xy 311.287414 -18.1483) (xy 311.28716 -18.1483) (xy 311.242573 -18.147831)
			(xy 311.153739 -18.140039) (xy 311.065923 -18.124536) (xy 310.979792 -18.101438) (xy 310.896001 -18.070922)
			(xy 310.815188 -18.033221) (xy 310.737969 -17.988621) (xy 310.664929 -17.937461) (xy 310.596626 -17.88013)
			(xy 310.533579 -17.817066) (xy 310.476268 -17.748747) (xy 310.425128 -17.675693) (xy 310.380549 -17.598461)
			(xy 310.34287 -17.517638) (xy 310.312377 -17.433839) (xy 310.289303 -17.347701) (xy 310.273824 -17.259881)
			(xy 310.266056 -17.171045) (xy 310.265572 -17.126458) (xy 259.309108 -17.126458) (xy 259.309108 -19.164372)
			(xy 392.445424 -19.164372) (xy 392.445424 -19.109828) (xy 392.453187 -19.05584) (xy 392.468554 -19.003507)
			(xy 392.491214 -18.953893) (xy 392.520704 -18.90801) (xy 392.556425 -18.866791) (xy 392.597649 -18.831076)
			(xy 392.643536 -18.801591) (xy 392.693152 -18.778938) (xy 392.745487 -18.763576) (xy 392.799476 -18.75582)
			(xy 392.826748 -18.75536) (xy 393.690348 -18.75536) (xy 393.717617 -18.755806) (xy 393.771598 -18.763573)
			(xy 393.823925 -18.778944) (xy 393.873532 -18.801604) (xy 393.91941 -18.831093) (xy 393.960624 -18.86681)
			(xy 393.996336 -18.908029) (xy 394.025819 -18.95391) (xy 394.048473 -19.00352) (xy 394.063837 -19.055849)
			(xy 394.071598 -19.109831) (xy 394.071598 -19.163652) (xy 398.034738 -19.163652) (xy 398.034738 -19.109148)
			(xy 398.042494 -19.055197) (xy 398.057849 -19.0029) (xy 398.08049 -18.95332) (xy 398.109956 -18.907466)
			(xy 398.145647 -18.866273) (xy 398.186838 -18.830578) (xy 398.232688 -18.801107) (xy 398.282266 -18.778462)
			(xy 398.334562 -18.763102) (xy 398.388512 -18.75534) (xy 398.415764 -18.754852) (xy 399.279364 -18.754852)
			(xy 399.306616 -18.755393) (xy 399.360565 -18.763145) (xy 399.412862 -18.778496) (xy 399.462441 -18.801134)
			(xy 399.508294 -18.830598) (xy 399.549486 -18.866288) (xy 399.58518 -18.907477) (xy 399.614649 -18.953327)
			(xy 399.637291 -19.002905) (xy 399.652648 -19.0552) (xy 399.660405 -19.109148) (xy 399.660405 -19.163652)
			(xy 403.622738 -19.163652) (xy 403.622738 -19.109148) (xy 403.630494 -19.055197) (xy 403.645849 -19.0029)
			(xy 403.66849 -18.95332) (xy 403.697956 -18.907466) (xy 403.733647 -18.866273) (xy 403.774838 -18.830578)
			(xy 403.820688 -18.801107) (xy 403.870266 -18.778462) (xy 403.922562 -18.763102) (xy 403.976512 -18.75534)
			(xy 404.003764 -18.754852) (xy 404.867364 -18.754852) (xy 404.894616 -18.755393) (xy 404.948565 -18.763145)
			(xy 405.000862 -18.778496) (xy 405.050441 -18.801134) (xy 405.096294 -18.830598) (xy 405.137486 -18.866288)
			(xy 405.17318 -18.907477) (xy 405.202649 -18.953327) (xy 405.225291 -19.002905) (xy 405.240648 -19.0552)
			(xy 405.248405 -19.109148) (xy 405.248405 -19.163652) (xy 409.210738 -19.163652) (xy 409.210738 -19.109148)
			(xy 409.218494 -19.055197) (xy 409.233849 -19.0029) (xy 409.25649 -18.95332) (xy 409.285956 -18.907466)
			(xy 409.321647 -18.866273) (xy 409.362838 -18.830578) (xy 409.408688 -18.801107) (xy 409.458266 -18.778462)
			(xy 409.510562 -18.763102) (xy 409.564512 -18.75534) (xy 409.591764 -18.754852) (xy 410.455364 -18.754852)
			(xy 410.482616 -18.755393) (xy 410.536565 -18.763145) (xy 410.588862 -18.778496) (xy 410.638441 -18.801134)
			(xy 410.684294 -18.830598) (xy 410.725486 -18.866288) (xy 410.76118 -18.907477) (xy 410.790649 -18.953327)
			(xy 410.813291 -19.002905) (xy 410.828648 -19.0552) (xy 410.836405 -19.109148) (xy 410.836405 -19.163652)
			(xy 410.836405 -19.163653) (xy 415.104538 -19.163653) (xy 415.104538 -19.109147) (xy 415.112295 -19.055195)
			(xy 415.12765 -19.002897) (xy 415.150292 -18.953315) (xy 415.17976 -18.907461) (xy 415.215453 -18.866267)
			(xy 415.256645 -18.830572) (xy 415.302498 -18.801102) (xy 415.352078 -18.778457) (xy 415.404376 -18.763099)
			(xy 415.458327 -18.755339) (xy 415.48558 -18.754852) (xy 416.34918 -18.754852) (xy 416.376431 -18.755394)
			(xy 416.430378 -18.763148) (xy 416.482673 -18.7785) (xy 416.532251 -18.801139) (xy 416.578101 -18.830604)
			(xy 416.619292 -18.866294) (xy 416.654984 -18.907483) (xy 416.684451 -18.953332) (xy 416.707093 -19.002908)
			(xy 416.722448 -19.055202) (xy 416.730205 -19.109149) (xy 416.730205 -19.163651) (xy 416.730102 -19.164366)
			(xy 420.691346 -19.164366) (xy 420.691346 -19.109834) (xy 420.699107 -19.055857) (xy 420.714469 -19.003533)
			(xy 420.737121 -18.953928) (xy 420.766602 -18.908051) (xy 420.802312 -18.866837) (xy 420.843523 -18.831124)
			(xy 420.889396 -18.801639) (xy 420.938999 -18.778982) (xy 420.991321 -18.763614) (xy 421.045298 -18.755849)
			(xy 421.072564 -18.75536) (xy 421.936164 -18.75536) (xy 421.963438 -18.755777) (xy 422.017432 -18.763536)
			(xy 422.069772 -18.7789) (xy 422.119393 -18.801556) (xy 422.165284 -18.831045) (xy 422.20651 -18.866764)
			(xy 422.242234 -18.907988) (xy 422.271726 -18.953876) (xy 422.294388 -19.003494) (xy 422.309757 -19.055833)
			(xy 422.31752 -19.109826) (xy 422.31752 -19.163656) (xy 426.314515 -19.163656) (xy 426.314515 -19.109144)
			(xy 426.322273 -19.055185) (xy 426.337632 -19.002881) (xy 426.360278 -18.953294) (xy 426.38975 -18.907436)
			(xy 426.42545 -18.866238) (xy 426.466648 -18.830541) (xy 426.512508 -18.80107) (xy 426.562096 -18.778426)
			(xy 426.614401 -18.76307) (xy 426.66836 -18.755314) (xy 426.695616 -18.754852) (xy 427.559216 -18.754852)
			(xy 427.586464 -18.755419) (xy 427.640404 -18.763177) (xy 427.692691 -18.778532) (xy 427.742261 -18.801171)
			(xy 427.788105 -18.830635) (xy 427.829289 -18.866323) (xy 427.864975 -18.907508) (xy 427.894436 -18.953353)
			(xy 427.917074 -19.002924) (xy 427.932427 -19.055212) (xy 427.940182 -19.109152) (xy 427.940182 -19.163648)
			(xy 427.940181 -19.163656) (xy 431.902515 -19.163656) (xy 431.902515 -19.109144) (xy 431.910273 -19.055185)
			(xy 431.925632 -19.002881) (xy 431.948278 -18.953294) (xy 431.97775 -18.907436) (xy 432.01345 -18.866238)
			(xy 432.054648 -18.830541) (xy 432.100508 -18.80107) (xy 432.150096 -18.778426) (xy 432.202401 -18.76307)
			(xy 432.25636 -18.755314) (xy 432.283616 -18.754852) (xy 433.147216 -18.754852) (xy 433.174464 -18.755419)
			(xy 433.228404 -18.763177) (xy 433.280691 -18.778532) (xy 433.330261 -18.801171) (xy 433.376105 -18.830635)
			(xy 433.417289 -18.866323) (xy 433.452975 -18.907508) (xy 433.482436 -18.953353) (xy 433.505074 -19.002924)
			(xy 433.520427 -19.055212) (xy 433.528182 -19.109152) (xy 433.528182 -19.163648) (xy 433.520427 -19.217588)
			(xy 433.505074 -19.269876) (xy 433.482436 -19.319447) (xy 433.452975 -19.365292) (xy 433.417289 -19.406477)
			(xy 433.376105 -19.442165) (xy 433.330261 -19.471629) (xy 433.280691 -19.494268) (xy 433.228404 -19.509623)
			(xy 433.174464 -19.517381) (xy 433.147216 -19.517868) (xy 432.283616 -19.517868) (xy 432.25636 -19.517486)
			(xy 432.202401 -19.50973) (xy 432.150096 -19.494374) (xy 432.100508 -19.47173) (xy 432.054648 -19.442259)
			(xy 432.01345 -19.406562) (xy 431.97775 -19.365364) (xy 431.948278 -19.319506) (xy 431.925632 -19.269919)
			(xy 431.910273 -19.217615) (xy 431.902515 -19.163656) (xy 427.940181 -19.163656) (xy 427.932427 -19.217588)
			(xy 427.917074 -19.269876) (xy 427.894436 -19.319447) (xy 427.864975 -19.365292) (xy 427.829289 -19.406477)
			(xy 427.788105 -19.442165) (xy 427.742261 -19.471629) (xy 427.692691 -19.494268) (xy 427.640404 -19.509623)
			(xy 427.586464 -19.517381) (xy 427.559216 -19.517868) (xy 426.695616 -19.517868) (xy 426.66836 -19.517486)
			(xy 426.614401 -19.50973) (xy 426.562096 -19.494374) (xy 426.512508 -19.47173) (xy 426.466648 -19.442259)
			(xy 426.42545 -19.406562) (xy 426.38975 -19.365364) (xy 426.360278 -19.319506) (xy 426.337632 -19.269919)
			(xy 426.322273 -19.217615) (xy 426.314515 -19.163656) (xy 422.31752 -19.163656) (xy 422.31752 -19.164374)
			(xy 422.309757 -19.218367) (xy 422.294388 -19.270706) (xy 422.271726 -19.320324) (xy 422.242234 -19.366212)
			(xy 422.20651 -19.407436) (xy 422.165284 -19.443155) (xy 422.119393 -19.472644) (xy 422.069772 -19.4953)
			(xy 422.017432 -19.510664) (xy 421.963438 -19.518423) (xy 421.936164 -19.518884) (xy 421.072564 -19.518884)
			(xy 421.045298 -19.518351) (xy 420.991321 -19.510586) (xy 420.938999 -19.495218) (xy 420.889396 -19.472561)
			(xy 420.843523 -19.443076) (xy 420.802312 -19.407363) (xy 420.766602 -19.366149) (xy 420.737121 -19.320272)
			(xy 420.714469 -19.270667) (xy 420.699107 -19.218343) (xy 420.691346 -19.164366) (xy 416.730102 -19.164366)
			(xy 416.722448 -19.217598) (xy 416.707093 -19.269892) (xy 416.684451 -19.319468) (xy 416.654984 -19.365317)
			(xy 416.619292 -19.406506) (xy 416.578101 -19.442196) (xy 416.532251 -19.471661) (xy 416.482673 -19.4943)
			(xy 416.430378 -19.509652) (xy 416.376431 -19.517406) (xy 416.34918 -19.517868) (xy 415.48558 -19.517868)
			(xy 415.458327 -19.517461) (xy 415.404376 -19.509701) (xy 415.352078 -19.494343) (xy 415.302498 -19.471698)
			(xy 415.256645 -19.442228) (xy 415.215453 -19.406533) (xy 415.17976 -19.365339) (xy 415.150292 -19.319485)
			(xy 415.12765 -19.269903) (xy 415.112295 -19.217605) (xy 415.104538 -19.163653) (xy 410.836405 -19.163653)
			(xy 410.828648 -19.2176) (xy 410.813291 -19.269895) (xy 410.790649 -19.319473) (xy 410.76118 -19.365323)
			(xy 410.725486 -19.406512) (xy 410.684294 -19.442202) (xy 410.638441 -19.471666) (xy 410.588862 -19.494304)
			(xy 410.536565 -19.509655) (xy 410.482616 -19.517407) (xy 410.455364 -19.517868) (xy 409.591764 -19.517868)
			(xy 409.564512 -19.51746) (xy 409.510562 -19.509698) (xy 409.458266 -19.494338) (xy 409.408688 -19.471693)
			(xy 409.362838 -19.442222) (xy 409.321647 -19.406527) (xy 409.285956 -19.365334) (xy 409.25649 -19.31948)
			(xy 409.233849 -19.2699) (xy 409.218494 -19.217603) (xy 409.210738 -19.163652) (xy 405.248405 -19.163652)
			(xy 405.240648 -19.2176) (xy 405.225291 -19.269895) (xy 405.202649 -19.319473) (xy 405.17318 -19.365323)
			(xy 405.137486 -19.406512) (xy 405.096294 -19.442202) (xy 405.050441 -19.471666) (xy 405.000862 -19.494304)
			(xy 404.948565 -19.509655) (xy 404.894616 -19.517407) (xy 404.867364 -19.517868) (xy 404.003764 -19.517868)
			(xy 403.976512 -19.51746) (xy 403.922562 -19.509698) (xy 403.870266 -19.494338) (xy 403.820688 -19.471693)
			(xy 403.774838 -19.442222) (xy 403.733647 -19.406527) (xy 403.697956 -19.365334) (xy 403.66849 -19.31948)
			(xy 403.645849 -19.2699) (xy 403.630494 -19.217603) (xy 403.622738 -19.163652) (xy 399.660405 -19.163652)
			(xy 399.652648 -19.2176) (xy 399.637291 -19.269895) (xy 399.614649 -19.319473) (xy 399.58518 -19.365323)
			(xy 399.549486 -19.406512) (xy 399.508294 -19.442202) (xy 399.462441 -19.471666) (xy 399.412862 -19.494304)
			(xy 399.360565 -19.509655) (xy 399.306616 -19.517407) (xy 399.279364 -19.517868) (xy 398.415764 -19.517868)
			(xy 398.388512 -19.51746) (xy 398.334562 -19.509698) (xy 398.282266 -19.494338) (xy 398.232688 -19.471693)
			(xy 398.186838 -19.442222) (xy 398.145647 -19.406527) (xy 398.109956 -19.365334) (xy 398.08049 -19.31948)
			(xy 398.057849 -19.2699) (xy 398.042494 -19.217603) (xy 398.034738 -19.163652) (xy 394.071598 -19.163652)
			(xy 394.071598 -19.164369) (xy 394.063837 -19.218351) (xy 394.048473 -19.27068) (xy 394.025819 -19.32029)
			(xy 393.996336 -19.366171) (xy 393.960624 -19.40739) (xy 393.91941 -19.443107) (xy 393.873532 -19.472596)
			(xy 393.823925 -19.495256) (xy 393.771598 -19.510627) (xy 393.717617 -19.518394) (xy 393.690348 -19.518884)
			(xy 392.826748 -19.518884) (xy 392.799476 -19.51838) (xy 392.745487 -19.510624) (xy 392.693152 -19.495262)
			(xy 392.643536 -19.472609) (xy 392.597649 -19.443124) (xy 392.556425 -19.407409) (xy 392.520704 -19.36619)
			(xy 392.491214 -19.320307) (xy 392.468554 -19.270693) (xy 392.453187 -19.21836) (xy 392.445424 -19.164372)
			(xy 259.309108 -19.164372) (xy 259.309108 -20.4061) (xy 368.50594 -20.4061) (xy 368.510005 -20.315592)
			(xy 368.522167 -20.225813) (xy 368.542328 -20.137486) (xy 368.570325 -20.051322) (xy 368.605934 -19.968014)
			(xy 368.648867 -19.888233) (xy 368.698779 -19.812623) (xy 368.755267 -19.741791) (xy 368.817878 -19.676308)
			(xy 368.886107 -19.616701) (xy 368.959405 -19.56345) (xy 369.037181 -19.516984) (xy 369.118809 -19.477677)
			(xy 369.203632 -19.445846) (xy 369.290966 -19.421746) (xy 369.38011 -19.405573) (xy 369.470345 -19.397455)
			(xy 369.515644 -19.396964) (xy 369.560233 -19.397442) (xy 369.649072 -19.405219) (xy 369.736895 -19.420711)
			(xy 369.823033 -19.443798) (xy 369.906831 -19.474305) (xy 369.987651 -19.512001) (xy 370.064878 -19.556597)
			(xy 370.137923 -19.607756) (xy 370.206232 -19.665086) (xy 370.269283 -19.728153) (xy 370.326597 -19.796475)
			(xy 370.377737 -19.869533) (xy 370.422315 -19.946771) (xy 370.459991 -20.0276) (xy 370.490478 -20.111405)
			(xy 370.513544 -20.197549) (xy 370.529013 -20.285376) (xy 370.536768 -20.374217) (xy 370.537232 -20.418806)
			(xy 370.536774 -20.462284) (xy 370.529196 -20.54891) (xy 370.514098 -20.634545) (xy 370.491595 -20.71854)
			(xy 370.485037 -20.73656) (xy 440.464956 -20.73656) (xy 440.465378 -20.698271) (xy 440.471981 -20.621977)
			(xy 440.485126 -20.546534) (xy 440.504715 -20.472503) (xy 440.51728 -20.436332) (xy 440.51995 -20.4279)
			(xy 440.519937 -20.410225) (xy 440.51728 -20.401788) (xy 440.50475 -20.365606) (xy 440.485173 -20.291575)
			(xy 440.472022 -20.216136) (xy 440.465394 -20.139848) (xy 440.464956 -20.10156) (xy 440.46549 -20.057765)
			(xy 440.474106 -19.9706) (xy 440.49125 -19.884704) (xy 440.516756 -19.80091) (xy 440.550377 -19.72003)
			(xy 440.57062 -19.68119) (xy 440.576064 -19.669733) (xy 440.576046 -19.644397) (xy 440.57062 -19.63293)
			(xy 440.550398 -19.594081) (xy 440.51679 -19.513198) (xy 440.491286 -19.429406) (xy 440.474133 -19.343514)
			(xy 440.465497 -19.256354) (xy 440.464956 -19.21256) (xy 440.465378 -19.174271) (xy 440.471981 -19.097977)
			(xy 440.485126 -19.022534) (xy 440.504715 -18.948503) (xy 440.51728 -18.912332) (xy 440.51995 -18.9039)
			(xy 440.519937 -18.886225) (xy 440.51728 -18.877788) (xy 440.50475 -18.841606) (xy 440.485173 -18.767575)
			(xy 440.472022 -18.692136) (xy 440.465394 -18.615848) (xy 440.464956 -18.57756) (xy 440.465414 -18.53645)
			(xy 440.473005 -18.45458) (xy 440.488119 -18.373761) (xy 440.510626 -18.294681) (xy 440.540334 -18.218015)
			(xy 440.576991 -18.144418) (xy 440.620282 -18.074518) (xy 440.66984 -18.008911) (xy 440.72524 -17.948157)
			(xy 440.78601 -17.892775) (xy 440.851631 -17.843237) (xy 440.921544 -17.799965) (xy 440.995152 -17.76333)
			(xy 441.071826 -17.733644) (xy 441.150912 -17.71116) (xy 441.231736 -17.69607) (xy 441.313608 -17.688502)
			(xy 441.354718 -17.688052) (xy 441.395668 -17.688478) (xy 441.477223 -17.695989) (xy 441.557742 -17.710965)
			(xy 441.636544 -17.733279) (xy 441.712961 -17.762742) (xy 441.786347 -17.799105) (xy 441.856079 -17.842059)
			(xy 441.921567 -17.891241) (xy 441.982258 -17.946234) (xy 442.010292 -17.976088) (xy 442.017449 -17.983101)
			(xy 442.035585 -17.991562) (xy 442.055576 -17.99248) (xy 442.065156 -17.98955) (xy 442.102033 -17.976445)
			(xy 442.177582 -17.955997) (xy 442.254637 -17.94227) (xy 442.3326 -17.935373) (xy 442.371734 -17.93494)
			(xy 442.412849 -17.93538) (xy 442.494727 -17.942971) (xy 442.575557 -17.958083) (xy 442.654646 -17.980589)
			(xy 442.731323 -18.010296) (xy 442.804931 -18.046951) (xy 442.874843 -18.090241) (xy 442.940462 -18.139797)
			(xy 443.001229 -18.195196) (xy 443.056626 -18.255966) (xy 443.106179 -18.321587) (xy 443.149467 -18.391501)
			(xy 443.186119 -18.46511) (xy 443.213248 -18.535142) (xy 451.165468 -18.535142) (xy 451.165468 -18.534888)
			(xy 451.166052 -18.49015) (xy 451.175063 -18.401129) (xy 451.192964 -18.313462) (xy 451.219572 -18.228034)
			(xy 451.236588 -18.186654) (xy 451.240131 -18.177057) (xy 451.240147 -18.15662) (xy 451.236588 -18.14703)
			(xy 451.219555 -18.105656) (xy 451.192939 -18.020228) (xy 451.175038 -17.932559) (xy 451.166032 -17.843535)
			(xy 451.165468 -17.798796) (xy 451.165468 -17.798542) (xy 451.165972 -17.756194) (xy 451.174023 -17.67188)
			(xy 451.190052 -17.588714) (xy 451.213913 -17.507447) (xy 451.245392 -17.428817) (xy 451.284203 -17.353536)
			(xy 451.329993 -17.282284) (xy 451.382349 -17.215708) (xy 451.440797 -17.15441) (xy 451.504807 -17.098945)
			(xy 451.573799 -17.049816) (xy 451.647149 -17.007467) (xy 451.724192 -16.972283) (xy 451.804231 -16.944581)
			(xy 451.88654 -16.924613) (xy 451.970375 -16.91256) (xy 452.054976 -16.90853) (xy 452.139577 -16.91256)
			(xy 452.223412 -16.924613) (xy 452.305721 -16.944581) (xy 452.38576 -16.972283) (xy 452.462803 -17.007467)
			(xy 452.536153 -17.049816) (xy 452.605145 -17.098945) (xy 452.669155 -17.15441) (xy 452.727603 -17.215708)
			(xy 452.779959 -17.282284) (xy 452.825749 -17.353536) (xy 452.86456 -17.428817) (xy 452.896039 -17.507447)
			(xy 452.9199 -17.588714) (xy 452.935929 -17.67188) (xy 452.94398 -17.756194) (xy 452.944484 -17.798542)
			(xy 452.944484 -17.798796) (xy 452.943898 -17.843534) (xy 452.934888 -17.932555) (xy 452.916988 -18.020222)
			(xy 452.890379 -18.10565) (xy 452.873364 -18.14703) (xy 452.869775 -18.156614) (xy 452.869791 -18.177063)
			(xy 452.873364 -18.186654) (xy 452.890389 -18.228031) (xy 452.917007 -18.313458) (xy 452.934911 -18.401126)
			(xy 452.943919 -18.490149) (xy 452.944484 -18.534888) (xy 452.944484 -18.535142) (xy 452.94398 -18.57749)
			(xy 452.935929 -18.661804) (xy 452.9199 -18.74497) (xy 452.896039 -18.826237) (xy 452.86456 -18.904867)
			(xy 452.825749 -18.980148) (xy 452.779959 -19.0514) (xy 452.727603 -19.117976) (xy 452.669155 -19.179274)
			(xy 452.605145 -19.234739) (xy 452.536153 -19.283868) (xy 452.462803 -19.326217) (xy 452.38576 -19.361401)
			(xy 452.305721 -19.389103) (xy 452.223412 -19.409071) (xy 452.139577 -19.421124) (xy 452.054976 -19.425155)
			(xy 451.970375 -19.421124) (xy 451.88654 -19.409071) (xy 451.804231 -19.389103) (xy 451.724192 -19.361401)
			(xy 451.647149 -19.326217) (xy 451.573799 -19.283868) (xy 451.504807 -19.234739) (xy 451.440797 -19.179274)
			(xy 451.382349 -19.117976) (xy 451.329993 -19.0514) (xy 451.284203 -18.980148) (xy 451.245392 -18.904867)
			(xy 451.213913 -18.826237) (xy 451.190052 -18.74497) (xy 451.174023 -18.661804) (xy 451.165972 -18.57749)
			(xy 451.165468 -18.535142) (xy 443.213248 -18.535142) (xy 443.215823 -18.541788) (xy 443.238325 -18.620878)
			(xy 443.253434 -18.701708) (xy 443.261021 -18.783587) (xy 443.261496 -18.824702) (xy 443.261095 -18.862992)
			(xy 443.254486 -18.939286) (xy 443.241336 -19.014729) (xy 443.221741 -19.088759) (xy 443.209172 -19.12493)
			(xy 443.206519 -19.133366) (xy 443.20652 -19.151037) (xy 443.209172 -19.159474) (xy 443.221718 -19.195651)
			(xy 443.24129 -19.269684) (xy 443.254437 -19.345124) (xy 443.261061 -19.421414) (xy 443.261496 -19.459702)
			(xy 443.260982 -19.503497) (xy 443.252361 -19.590663) (xy 443.235212 -19.676559) (xy 443.209701 -19.760353)
			(xy 443.176076 -19.841233) (xy 443.155832 -19.880072) (xy 443.15041 -19.891537) (xy 443.150411 -19.916866)
			(xy 443.155832 -19.928332) (xy 443.176073 -19.967172) (xy 443.209679 -20.048057) (xy 443.235179 -20.131851)
			(xy 443.252328 -20.217745) (xy 443.260958 -20.304908) (xy 443.261496 -20.348702) (xy 443.261095 -20.386992)
			(xy 443.254486 -20.463286) (xy 443.241336 -20.538729) (xy 443.221741 -20.612759) (xy 443.209172 -20.64893)
			(xy 443.206519 -20.657366) (xy 443.20652 -20.675037) (xy 443.209172 -20.683474) (xy 443.221718 -20.719651)
			(xy 443.24129 -20.793684) (xy 443.254437 -20.869124) (xy 443.261061 -20.945414) (xy 443.261496 -20.983702)
			(xy 443.260989 -21.024815) (xy 443.253402 -21.106691) (xy 443.238293 -21.187518) (xy 443.215791 -21.266605)
			(xy 443.186088 -21.343279) (xy 443.149437 -21.416886) (xy 443.106152 -21.486797) (xy 443.0566 -21.552416)
			(xy 443.001205 -21.613183) (xy 442.94044 -21.66858) (xy 442.874823 -21.718133) (xy 442.804914 -21.761422)
			(xy 442.731309 -21.798075) (xy 442.654636 -21.827781) (xy 442.575549 -21.850286) (xy 442.494723 -21.865398)
			(xy 442.412847 -21.872988) (xy 442.371734 -21.873464) (xy 442.330778 -21.872996) (xy 442.249213 -21.865468)
			(xy 442.168686 -21.850472) (xy 442.089879 -21.828136) (xy 442.013459 -21.798648) (xy 441.940074 -21.762259)
			(xy 441.870346 -21.719277) (xy 441.804865 -21.670066) (xy 441.744186 -21.615042) (xy 441.71616 -21.585174)
			(xy 441.709037 -21.578124) (xy 441.690882 -21.569676) (xy 441.670879 -21.568774) (xy 441.661296 -21.571712)
			(xy 441.624502 -21.584749) (xy 441.549137 -21.605106) (xy 441.472276 -21.618771) (xy 441.394513 -21.625637)
			(xy 441.35548 -21.626068) (xy 441.354718 -21.626068) (xy 441.313612 -21.62557) (xy 441.23175 -21.617988)
			(xy 441.150936 -21.602885) (xy 441.07186 -21.580392) (xy 440.995197 -21.5507) (xy 440.9216 -21.514062)
			(xy 440.851696 -21.470791) (xy 440.786082 -21.421255) (xy 440.725318 -21.365878) (xy 440.669922 -21.305132)
			(xy 440.620366 -21.239533) (xy 440.577073 -21.169643) (xy 440.540412 -21.096058) (xy 440.510696 -21.019403)
			(xy 440.488178 -20.940335) (xy 440.473051 -20.859526) (xy 440.465443 -20.777666) (xy 440.464956 -20.73656)
			(xy 370.485037 -20.73656) (xy 370.461858 -20.800254) (xy 370.425114 -20.879065) (xy 370.381641 -20.954375)
			(xy 370.331772 -21.02561) (xy 370.275884 -21.092228) (xy 370.214404 -21.153723) (xy 370.147799 -21.209627)
			(xy 370.076576 -21.259513) (xy 370.001276 -21.303004) (xy 369.922473 -21.339767) (xy 369.840767 -21.369523)
			(xy 369.756778 -21.392046) (xy 369.671146 -21.407165) (xy 369.584522 -21.414763) (xy 369.541044 -21.415248)
			(xy 369.515644 -21.415248) (xy 369.470345 -21.414745) (xy 369.38011 -21.406627) (xy 369.290966 -21.390454)
			(xy 369.203632 -21.366354) (xy 369.118809 -21.334523) (xy 369.037181 -21.295216) (xy 368.959405 -21.24875)
			(xy 368.886107 -21.195499) (xy 368.817878 -21.135892) (xy 368.755267 -21.070409) (xy 368.698779 -20.999577)
			(xy 368.648867 -20.923967) (xy 368.605934 -20.844186) (xy 368.570325 -20.760878) (xy 368.542328 -20.674714)
			(xy 368.522167 -20.586387) (xy 368.510005 -20.496608) (xy 368.50594 -20.4061) (xy 259.309108 -20.4061)
			(xy 259.309108 -25.982422) (xy 440.239912 -25.982422) (xy 440.240419 -25.939461) (xy 440.248702 -25.85394)
			(xy 440.265193 -25.769616) (xy 440.289738 -25.687275) (xy 440.322109 -25.607684) (xy 440.362003 -25.531586)
			(xy 440.40905 -25.459689) (xy 440.46281 -25.392664) (xy 440.522782 -25.331135) (xy 440.588408 -25.275676)
			(xy 440.659076 -25.226803) (xy 440.69635 -25.205436) (xy 440.704332 -25.200469) (xy 440.716316 -25.186006)
			(xy 440.719718 -25.177242) (xy 440.733823 -25.137039) (xy 440.768699 -25.059297) (xy 440.810847 -24.985247)
			(xy 440.859883 -24.915565) (xy 440.915357 -24.850891) (xy 440.97676 -24.791817) (xy 441.043529 -24.738885)
			(xy 441.115054 -24.692579) (xy 441.190679 -24.653323) (xy 441.26971 -24.621478) (xy 441.351424 -24.597336)
			(xy 441.435072 -24.581116) (xy 441.519887 -24.572969) (xy 441.56249 -24.572468) (xy 441.562998 -24.572468)
			(xy 441.606762 -24.572982) (xy 441.693869 -24.581557) (xy 441.77971 -24.598653) (xy 441.863455 -24.624106)
			(xy 441.944293 -24.657667) (xy 441.983114 -24.677878) (xy 441.994467 -24.683205) (xy 442.019513 -24.683205)
			(xy 442.030866 -24.677878) (xy 442.069745 -24.657673) (xy 442.150684 -24.6241) (xy 442.23453 -24.598641)
			(xy 442.320472 -24.581544) (xy 442.407677 -24.572973) (xy 442.45149 -24.572468) (xy 442.495305 -24.572971)
			(xy 442.582516 -24.581515) (xy 442.668462 -24.5986) (xy 442.752311 -24.62406) (xy 442.833246 -24.657648)
			(xy 442.872114 -24.677878) (xy 442.883467 -24.683205) (xy 442.908513 -24.683205) (xy 442.919866 -24.677878)
			(xy 442.959061 -24.657499) (xy 443.040701 -24.623735) (xy 443.125286 -24.598229) (xy 443.211982 -24.581233)
			(xy 443.255908 -24.576532) (xy 443.266358 -24.575008) (xy 443.284755 -24.564681) (xy 443.297434 -24.547819)
			(xy 443.300358 -24.53767) (xy 443.310609 -24.496358) (xy 443.337964 -24.415751) (xy 443.372893 -24.338124)
			(xy 443.415077 -24.264189) (xy 443.464129 -24.19462) (xy 443.519603 -24.130055) (xy 443.580989 -24.071084)
			(xy 443.647727 -24.018245) (xy 443.719207 -23.972023) (xy 443.794775 -23.932839) (xy 443.87374 -23.901052)
			(xy 443.955381 -23.876952) (xy 444.038949 -23.86076) (xy 444.123683 -23.852625) (xy 444.166244 -23.852124)
			(xy 444.207348 -23.852525) (xy 444.289205 -23.860114) (xy 444.370013 -23.875224) (xy 444.449082 -23.897725)
			(xy 444.525738 -23.927425) (xy 444.599326 -23.964072) (xy 444.669219 -24.007352) (xy 444.734821 -24.056897)
			(xy 444.795571 -24.112283) (xy 444.850952 -24.173038) (xy 444.900491 -24.238644) (xy 444.943765 -24.30854)
			(xy 444.980405 -24.382132) (xy 445.0101 -24.45879) (xy 445.032594 -24.537861) (xy 445.047697 -24.61867)
			(xy 445.055279 -24.700528) (xy 445.055752 -24.741632) (xy 445.055238 -24.782654) (xy 445.04768 -24.864348)
			(xy 445.032631 -24.944999) (xy 445.01022 -25.023921) (xy 444.980635 -25.100445) (xy 444.94413 -25.173919)
			(xy 444.901014 -25.243719) (xy 444.851653 -25.309252) (xy 444.796467 -25.369961) (xy 444.735925 -25.425331)
			(xy 444.670542 -25.47489) (xy 444.600873 -25.518217) (xy 444.52751 -25.554945) (xy 444.451076 -25.584761)
			(xy 444.372222 -25.607412) (xy 444.291617 -25.622705) (xy 444.250826 -25.627076) (xy 444.240379 -25.628618)
			(xy 444.221981 -25.638935) (xy 444.2093 -25.655791) (xy 444.206376 -25.665938) (xy 444.196473 -25.705794)
			(xy 444.170375 -25.783666) (xy 444.137208 -25.8588) (xy 444.097254 -25.930555) (xy 444.050854 -25.998321)
			(xy 443.998403 -26.061519) (xy 443.940348 -26.119612) (xy 443.877184 -26.172104) (xy 443.809448 -26.218548)
			(xy 443.773814 -26.238962) (xy 443.765845 -26.243946) (xy 443.753852 -26.258396) (xy 443.750446 -26.267156)
			(xy 443.736369 -26.307378) (xy 443.701515 -26.385148) (xy 443.659384 -26.459228) (xy 443.61036 -26.528939)
			(xy 443.554893 -26.593641) (xy 443.493492 -26.652741) (xy 443.42672 -26.705698) (xy 443.355189 -26.752025)
			(xy 443.279554 -26.791298) (xy 443.200511 -26.823158) (xy 443.118782 -26.847311) (xy 443.035118 -26.863536)
			(xy 442.950285 -26.871685) (xy 442.907674 -26.872184) (xy 442.863879 -26.871639) (xy 442.776715 -26.863025)
			(xy 442.690819 -26.845883) (xy 442.607025 -26.82038) (xy 442.526144 -26.786761) (xy 442.487304 -26.76652)
			(xy 442.475838 -26.761102) (xy 442.45051 -26.761102) (xy 442.439044 -26.76652) (xy 442.400209 -26.786769)
			(xy 442.319322 -26.820374) (xy 442.235526 -26.845873) (xy 442.149632 -26.863019) (xy 442.062468 -26.871647)
			(xy 442.018674 -26.872184) (xy 441.974879 -26.871639) (xy 441.887715 -26.863025) (xy 441.801819 -26.845883)
			(xy 441.718025 -26.82038) (xy 441.637144 -26.786761) (xy 441.598304 -26.76652) (xy 441.586838 -26.761102)
			(xy 441.56151 -26.761102) (xy 441.550044 -26.76652) (xy 441.511209 -26.786769) (xy 441.430322 -26.820374)
			(xy 441.346526 -26.845873) (xy 441.260632 -26.863019) (xy 441.173468 -26.871647) (xy 441.129674 -26.872184)
			(xy 441.08856 -26.871712) (xy 441.006683 -26.864123) (xy 440.925855 -26.849012) (xy 440.846767 -26.826507)
			(xy 440.770092 -26.796802) (xy 440.696485 -26.760149) (xy 440.626574 -26.71686) (xy 440.560955 -26.667306)
			(xy 440.500188 -26.61191) (xy 440.444791 -26.551142) (xy 440.395237 -26.485523) (xy 440.351949 -26.415612)
			(xy 440.315297 -26.342004) (xy 440.285592 -26.265329) (xy 440.263088 -26.186241) (xy 440.247977 -26.105413)
			(xy 440.240388 -26.023536) (xy 440.239912 -25.982422) (xy 259.309108 -25.982422) (xy 259.309108 -32.117846)
			(xy 455.218281 -32.117846) (xy 455.218281 -31.988706) (xy 455.226231 -31.859811) (xy 455.242101 -31.731651)
			(xy 455.26583 -31.60471) (xy 455.297329 -31.479471) (xy 455.336478 -31.356408) (xy 455.383129 -31.235989)
			(xy 455.437104 -31.11867) (xy 455.498199 -31.004896) (xy 455.566182 -30.895099) (xy 455.640796 -30.789696)
			(xy 455.721757 -30.689086) (xy 455.808757 -30.593651) (xy 455.901468 -30.503752) (xy 455.999538 -30.419731)
			(xy 456.102593 -30.341907) (xy 456.210244 -30.270575) (xy 456.322083 -30.206005) (xy 456.437684 -30.148443)
			(xy 456.556609 -30.098106) (xy 456.678408 -30.055186) (xy 456.802618 -30.019845) (xy 456.928767 -29.992218)
			(xy 457.056379 -29.972409) (xy 457.184968 -29.960493) (xy 457.314046 -29.956517) (xy 457.443124 -29.960493)
			(xy 457.571713 -29.972409) (xy 457.699325 -29.992218) (xy 457.825474 -30.019845) (xy 457.949684 -30.055186)
			(xy 458.071483 -30.098106) (xy 458.190408 -30.148443) (xy 458.306009 -30.206005) (xy 458.417848 -30.270575)
			(xy 458.525499 -30.341907) (xy 458.628554 -30.419731) (xy 458.726624 -30.503752) (xy 458.819335 -30.593651)
			(xy 458.906335 -30.689086) (xy 458.987296 -30.789696) (xy 459.06191 -30.895099) (xy 459.129893 -31.004896)
			(xy 459.190988 -31.11867) (xy 459.244963 -31.235989) (xy 459.291614 -31.356408) (xy 459.330763 -31.479471)
			(xy 459.362262 -31.60471) (xy 459.385991 -31.731651) (xy 459.401861 -31.859811) (xy 459.409811 -31.988706)
			(xy 459.410308 -32.053276) (xy 459.409811 -32.117846) (xy 459.401861 -32.246741) (xy 459.385991 -32.374901)
			(xy 459.362262 -32.501842) (xy 459.330763 -32.627081) (xy 459.291614 -32.750144) (xy 459.244963 -32.870563)
			(xy 459.190988 -32.987882) (xy 459.129893 -33.101656) (xy 459.06191 -33.211453) (xy 458.987296 -33.316856)
			(xy 458.906335 -33.417466) (xy 458.819335 -33.512901) (xy 458.726624 -33.6028) (xy 458.628554 -33.686821)
			(xy 458.525499 -33.764645) (xy 458.417848 -33.835977) (xy 458.307206 -33.899856) (xy 461.798924 -33.899856)
			(xy 461.798924 -32.299656) (xy 461.799422 -32.222373) (xy 461.807378 -32.068013) (xy 461.823271 -31.914267)
			(xy 461.847057 -31.761543) (xy 461.878674 -31.610247) (xy 461.918037 -31.460778) (xy 461.965042 -31.313534)
			(xy 462.019566 -31.168904) (xy 462.081462 -31.027274) (xy 462.150567 -30.889017) (xy 462.226698 -30.754502)
			(xy 462.309652 -30.624083) (xy 462.399211 -30.498108) (xy 462.495135 -30.376911) (xy 462.597172 -30.260812)
			(xy 462.705049 -30.15012) (xy 462.818482 -30.045128) (xy 462.93717 -29.946115) (xy 463.060797 -29.853342)
			(xy 463.189036 -29.767057) (xy 463.321547 -29.687488) (xy 463.457979 -29.614846) (xy 463.597969 -29.549324)
			(xy 463.741146 -29.491095) (xy 463.887131 -29.440314) (xy 464.035537 -29.397115) (xy 464.185969 -29.361613)
			(xy 464.33803 -29.333903) (xy 464.491316 -29.314057) (xy 464.64542 -29.302128) (xy 464.799934 -29.298149)
			(xy 464.954448 -29.302128) (xy 465.108552 -29.314057) (xy 465.261838 -29.333903) (xy 465.413899 -29.361613)
			(xy 465.564331 -29.397115) (xy 465.712737 -29.440314) (xy 465.858722 -29.491095) (xy 466.001899 -29.549324)
			(xy 466.141889 -29.614846) (xy 466.278321 -29.687488) (xy 466.410832 -29.767057) (xy 466.539071 -29.853342)
			(xy 466.662698 -29.946115) (xy 466.781386 -30.045128) (xy 466.894819 -30.15012) (xy 467.002696 -30.260812)
			(xy 467.104733 -30.376911) (xy 467.200657 -30.498108) (xy 467.290216 -30.624083) (xy 467.37317 -30.754502)
			(xy 467.449301 -30.889017) (xy 467.518406 -31.027274) (xy 467.580302 -31.168904) (xy 467.634826 -31.313534)
			(xy 467.681831 -31.460778) (xy 467.721194 -31.610247) (xy 467.752811 -31.761543) (xy 467.776597 -31.914267)
			(xy 467.79249 -32.068013) (xy 467.800446 -32.222373) (xy 467.800944 -32.299656) (xy 467.800944 -33.899856)
			(xy 467.800446 -33.977139) (xy 467.79249 -34.131499) (xy 467.776597 -34.285245) (xy 467.752811 -34.437969)
			(xy 467.721194 -34.589265) (xy 467.681831 -34.738734) (xy 467.634826 -34.885978) (xy 467.580302 -35.030608)
			(xy 467.518406 -35.172238) (xy 467.449301 -35.310495) (xy 467.37317 -35.44501) (xy 467.290216 -35.575429)
			(xy 467.200657 -35.701404) (xy 467.104733 -35.822601) (xy 467.002696 -35.9387) (xy 466.894819 -36.049392)
			(xy 466.781386 -36.154384) (xy 466.662698 -36.253397) (xy 466.539071 -36.34617) (xy 466.410832 -36.432455)
			(xy 466.278321 -36.512024) (xy 466.141889 -36.584666) (xy 466.001899 -36.650188) (xy 465.858722 -36.708417)
			(xy 465.712737 -36.759198) (xy 465.564331 -36.802397) (xy 465.413899 -36.837899) (xy 465.261838 -36.865609)
			(xy 465.108552 -36.885455) (xy 464.954448 -36.897384) (xy 464.799934 -36.901364) (xy 464.64542 -36.897384)
			(xy 464.491316 -36.885455) (xy 464.33803 -36.865609) (xy 464.185969 -36.837899) (xy 464.035537 -36.802397)
			(xy 463.887131 -36.759198) (xy 463.741146 -36.708417) (xy 463.597969 -36.650188) (xy 463.457979 -36.584666)
			(xy 463.321547 -36.512024) (xy 463.189036 -36.432455) (xy 463.060797 -36.34617) (xy 462.93717 -36.253397)
			(xy 462.818482 -36.154384) (xy 462.705049 -36.049392) (xy 462.597172 -35.9387) (xy 462.495135 -35.822601)
			(xy 462.399211 -35.701404) (xy 462.309652 -35.575429) (xy 462.226698 -35.44501) (xy 462.150567 -35.310495)
			(xy 462.081462 -35.172238) (xy 462.019566 -35.030608) (xy 461.965042 -34.885978) (xy 461.918037 -34.738734)
			(xy 461.878674 -34.589265) (xy 461.847057 -34.437969) (xy 461.823271 -34.285245) (xy 461.807378 -34.131499)
			(xy 461.799422 -33.977139) (xy 461.798924 -33.899856) (xy 458.307206 -33.899856) (xy 458.306009 -33.900547)
			(xy 458.190408 -33.958109) (xy 458.071483 -34.008446) (xy 457.949684 -34.051366) (xy 457.825474 -34.086707)
			(xy 457.699325 -34.114334) (xy 457.571713 -34.134143) (xy 457.443124 -34.146059) (xy 457.314046 -34.150036)
			(xy 457.184968 -34.146059) (xy 457.056379 -34.134143) (xy 456.928767 -34.114334) (xy 456.802618 -34.086707)
			(xy 456.678408 -34.051366) (xy 456.556609 -34.008446) (xy 456.437684 -33.958109) (xy 456.322083 -33.900547)
			(xy 456.210244 -33.835977) (xy 456.102593 -33.764645) (xy 455.999538 -33.686821) (xy 455.901468 -33.6028)
			(xy 455.808757 -33.512901) (xy 455.721757 -33.417466) (xy 455.640796 -33.316856) (xy 455.566182 -33.211453)
			(xy 455.498199 -33.101656) (xy 455.437104 -32.987882) (xy 455.383129 -32.870563) (xy 455.336478 -32.750144)
			(xy 455.297329 -32.627081) (xy 455.26583 -32.501842) (xy 455.242101 -32.374901) (xy 455.226231 -32.246741)
			(xy 455.218281 -32.117846) (xy 259.309108 -32.117846) (xy 259.309108 -34.120074) (xy 259.308624 -34.190457)
			(xy 259.300733 -34.331001) (xy 259.284973 -34.470882) (xy 259.261395 -34.609659) (xy 259.230073 -34.746896)
			(xy 259.191105 -34.882161) (xy 259.144614 -35.015028) (xy 259.090747 -35.145079) (xy 259.029671 -35.271905)
			(xy 258.961581 -35.395107) (xy 258.88669 -35.514297) (xy 258.805233 -35.629101) (xy 258.717468 -35.739156)
			(xy 258.62367 -35.844118) (xy 258.524134 -35.943655) (xy 258.419173 -36.037454) (xy 258.309118 -36.12522)
			(xy 258.194315 -36.206678) (xy 258.075126 -36.28157) (xy 257.951924 -36.349661) (xy 257.825099 -36.410738)
			(xy 257.695048 -36.464606) (xy 257.562182 -36.511099) (xy 257.426917 -36.550068) (xy 257.289681 -36.581391)
			(xy 257.150904 -36.60497) (xy 257.011023 -36.620731) (xy 256.870479 -36.628623) (xy 256.800096 -36.629086)
			(xy 225.300032 -36.629086) (xy 225.229649 -36.628602) (xy 225.089105 -36.620711) (xy 224.949224 -36.604952)
			(xy 224.810447 -36.581374) (xy 224.673211 -36.550052) (xy 224.537946 -36.511084) (xy 224.40508 -36.464594)
			(xy 224.275029 -36.410726) (xy 224.148203 -36.349651) (xy 224.025001 -36.28156) (xy 223.905811 -36.206669)
			(xy 223.791008 -36.125213) (xy 223.680953 -36.037447) (xy 223.575992 -35.943648) (xy 223.476456 -35.844112)
			(xy 223.382657 -35.739152) (xy 223.294891 -35.629097) (xy 223.213434 -35.514294) (xy 223.138543 -35.395104)
			(xy 223.070452 -35.271902) (xy 223.009377 -35.145077) (xy 222.955509 -35.015026) (xy 222.909017 -34.882159)
			(xy 222.870049 -34.746895) (xy 222.838727 -34.609659) (xy 222.815149 -34.470882) (xy 222.799389 -34.331001)
			(xy 222.791498 -34.190457) (xy 222.79102 -34.120074) (xy 222.79102 -13.780008) (xy 222.790499 -13.724238)
			(xy 222.782164 -13.613011) (xy 222.765541 -13.502717) (xy 222.740722 -13.393974) (xy 222.707846 -13.287389)
			(xy 222.667097 -13.183559) (xy 222.618703 -13.083065) (xy 222.562935 -12.986469) (xy 222.500103 -12.894309)
			(xy 222.430561 -12.807103) (xy 222.354696 -12.725338) (xy 222.272933 -12.64947) (xy 222.185729 -12.579925)
			(xy 222.093572 -12.517091) (xy 221.996977 -12.461319) (xy 221.896485 -12.412922) (xy 221.792656 -12.37217)
			(xy 221.686073 -12.339291) (xy 221.57733 -12.314468) (xy 221.467037 -12.297841) (xy 221.35581 -12.289503)
			(xy 221.30004 -12.289028) (xy 196.701918 -12.289028) (xy 196.631535 -12.288544) (xy 196.49099 -12.280652)
			(xy 196.35111 -12.264892) (xy 196.212332 -12.241314) (xy 196.075095 -12.209992) (xy 195.939831 -12.171024)
			(xy 195.806964 -12.124532) (xy 195.676913 -12.070665) (xy 195.550086 -12.009589) (xy 195.426884 -11.941499)
			(xy 195.307694 -11.866608) (xy 195.19289 -11.785152) (xy 195.082834 -11.697386) (xy 194.977873 -11.603588)
			(xy 194.878335 -11.504052) (xy 194.784536 -11.399092) (xy 194.696769 -11.289037) (xy 194.615311 -11.174234)
			(xy 194.540418 -11.055045) (xy 194.472326 -10.931844) (xy 194.411249 -10.805018) (xy 194.35738 -10.674968)
			(xy 194.310887 -10.542102) (xy 194.271917 -10.406837) (xy 194.240593 -10.269601) (xy 194.217013 -10.130824)
			(xy 194.201251 -9.990943) (xy 194.193357 -9.850399) (xy 194.192906 -9.780016) (xy 194.192906 -5.839714)
			(xy 194.192489 -5.82969) (xy 194.184822 -5.811168) (xy 194.170649 -5.79699) (xy 194.152129 -5.789315)
			(xy 194.142106 -5.788914) (xy 126.661926 -5.788914) (xy 126.651902 -5.789329) (xy 126.633379 -5.796995)
			(xy 126.619202 -5.811169) (xy 126.611531 -5.82969) (xy 126.611126 -5.839714) (xy 126.611126 -9.780016)
			(xy 126.610632 -9.850398) (xy 126.602738 -9.990941) (xy 126.586977 -10.13082) (xy 126.563397 -10.269595)
			(xy 126.532074 -10.40683) (xy 126.51969 -10.449814) (xy 127.349257 -10.449814) (xy 127.353266 -10.361813)
			(xy 127.365261 -10.274542) (xy 127.385143 -10.188723) (xy 127.412746 -10.105067) (xy 127.447842 -10.024268)
			(xy 127.49014 -9.946995) (xy 127.539289 -9.873889) (xy 127.594883 -9.805555) (xy 127.65646 -9.74256)
			(xy 127.723511 -9.685425) (xy 127.79548 -9.634624) (xy 127.87177 -9.590578) (xy 127.951749 -9.553652)
			(xy 128.034754 -9.524151) (xy 128.120099 -9.502322) (xy 128.207075 -9.488343) (xy 128.294961 -9.482331)
			(xy 128.38303 -9.484337) (xy 128.470552 -9.494342) (xy 128.556802 -9.512265) (xy 128.641064 -9.537957)
			(xy 128.722641 -9.571204) (xy 128.800857 -9.611732) (xy 128.875063 -9.659205) (xy 128.944645 -9.713229)
			(xy 129.009025 -9.773356) (xy 129.067672 -9.839089) (xy 129.120098 -9.909883) (xy 129.165869 -9.98515)
			(xy 129.204606 -10.064268) (xy 129.235988 -10.146581) (xy 129.259755 -10.231406) (xy 129.266964 -10.270552)
			(xy 131.639267 -10.270552) (xy 131.639267 -10.216048) (xy 131.647024 -10.162097) (xy 131.66238 -10.1098)
			(xy 131.685023 -10.060221) (xy 131.714491 -10.014369) (xy 131.750185 -9.973177) (xy 131.791377 -9.937485)
			(xy 131.83723 -9.908018) (xy 131.88681 -9.885377) (xy 131.939107 -9.870022) (xy 131.993058 -9.862267)
			(xy 132.02031 -9.861804) (xy 132.88391 -9.861804) (xy 132.911162 -9.862266) (xy 132.96511 -9.870024)
			(xy 133.017405 -9.885381) (xy 133.066983 -9.908023) (xy 133.112833 -9.937491) (xy 133.154024 -9.973183)
			(xy 133.189715 -10.014375) (xy 133.219181 -10.060226) (xy 133.241823 -10.109804) (xy 133.257178 -10.1621)
			(xy 133.264934 -10.216048) (xy 133.264934 -10.270552) (xy 133.257178 -10.3245) (xy 133.241823 -10.376796)
			(xy 133.219181 -10.426374) (xy 133.189715 -10.472225) (xy 133.154024 -10.513417) (xy 133.112833 -10.549109)
			(xy 133.066983 -10.578577) (xy 133.017405 -10.601219) (xy 132.96511 -10.616576) (xy 132.911162 -10.624334)
			(xy 132.88391 -10.62482) (xy 132.02031 -10.62482) (xy 131.993058 -10.624333) (xy 131.939107 -10.616578)
			(xy 131.88681 -10.601223) (xy 131.83723 -10.578582) (xy 131.791377 -10.549115) (xy 131.750185 -10.513423)
			(xy 131.714491 -10.472231) (xy 131.685023 -10.426379) (xy 131.66238 -10.3768) (xy 131.647024 -10.324503)
			(xy 131.639267 -10.270552) (xy 129.266964 -10.270552) (xy 129.27571 -10.318041) (xy 129.283721 -10.405768)
			(xy 129.284222 -10.449814) (xy 129.283721 -10.49386) (xy 129.27571 -10.581587) (xy 129.259755 -10.668222)
			(xy 129.235988 -10.753047) (xy 129.213071 -10.813156) (xy 169.954611 -10.813156) (xy 169.954611 -10.758644)
			(xy 169.962369 -10.704687) (xy 169.977727 -10.652382) (xy 170.000372 -10.602796) (xy 170.029844 -10.556938)
			(xy 170.065542 -10.51574) (xy 170.106739 -10.480043) (xy 170.152598 -10.450571) (xy 170.202184 -10.427926)
			(xy 170.254488 -10.412568) (xy 170.308446 -10.404811) (xy 170.335702 -10.404348) (xy 171.199302 -10.404348)
			(xy 171.22655 -10.404922) (xy 171.280491 -10.412678) (xy 171.33278 -10.428032) (xy 171.382351 -10.45067)
			(xy 171.428196 -10.480133) (xy 171.469381 -10.515821) (xy 171.505068 -10.557006) (xy 171.534531 -10.602851)
			(xy 171.557169 -10.652422) (xy 171.572522 -10.704711) (xy 171.580278 -10.758652) (xy 171.580278 -10.813148)
			(xy 171.572522 -10.867089) (xy 171.557169 -10.919378) (xy 171.534531 -10.968949) (xy 171.505068 -11.014794)
			(xy 171.469381 -11.055979) (xy 171.428196 -11.091667) (xy 171.382351 -11.12113) (xy 171.33278 -11.143768)
			(xy 171.280491 -11.159122) (xy 171.22655 -11.166878) (xy 171.199302 -11.167364) (xy 170.335702 -11.167364)
			(xy 170.308446 -11.166989) (xy 170.254488 -11.159232) (xy 170.202184 -11.143874) (xy 170.152598 -11.121229)
			(xy 170.106739 -11.091757) (xy 170.065542 -11.05606) (xy 170.029844 -11.014862) (xy 170.000372 -10.969004)
			(xy 169.977727 -10.919418) (xy 169.962369 -10.867113) (xy 169.954611 -10.813156) (xy 129.213071 -10.813156)
			(xy 129.204606 -10.83536) (xy 129.165869 -10.914478) (xy 129.120098 -10.989745) (xy 129.067672 -11.060539)
			(xy 129.009025 -11.126272) (xy 128.944645 -11.186399) (xy 128.875063 -11.240423) (xy 128.800857 -11.287896)
			(xy 128.722641 -11.328424) (xy 128.641064 -11.361671) (xy 128.556802 -11.387363) (xy 128.470552 -11.405286)
			(xy 128.38303 -11.415291) (xy 128.294961 -11.417297) (xy 128.207075 -11.411285) (xy 128.120099 -11.397306)
			(xy 128.034754 -11.375477) (xy 127.951749 -11.345976) (xy 127.87177 -11.30905) (xy 127.79548 -11.265004)
			(xy 127.723511 -11.214203) (xy 127.65646 -11.157068) (xy 127.594883 -11.094073) (xy 127.539289 -11.025739)
			(xy 127.49014 -10.952633) (xy 127.447842 -10.87536) (xy 127.412746 -10.794561) (xy 127.385143 -10.710905)
			(xy 127.365261 -10.625086) (xy 127.353266 -10.537815) (xy 127.349257 -10.449814) (xy 126.51969 -10.449814)
			(xy 126.493105 -10.542092) (xy 126.446613 -10.674957) (xy 126.392744 -10.805006) (xy 126.331668 -10.93183)
			(xy 126.263578 -11.05503) (xy 126.188687 -11.174218) (xy 126.10723 -11.28902) (xy 126.019465 -11.399074)
			(xy 125.925667 -11.504033) (xy 125.826132 -11.603569) (xy 125.721172 -11.697366) (xy 125.611118 -11.785131)
			(xy 125.496317 -11.866588) (xy 125.495706 -11.866972) (xy 129.833804 -11.866972) (xy 129.833804 -11.812428)
			(xy 129.841567 -11.758438) (xy 129.856934 -11.706103) (xy 129.879594 -11.656488) (xy 129.909085 -11.610603)
			(xy 129.944805 -11.569383) (xy 129.986029 -11.533665) (xy 130.031916 -11.504179) (xy 130.081533 -11.481523)
			(xy 130.13387 -11.46616) (xy 130.18786 -11.458401) (xy 130.215132 -11.45794) (xy 131.078732 -11.45794)
			(xy 131.106 -11.458425) (xy 131.15998 -11.46619) (xy 131.212306 -11.481558) (xy 131.261913 -11.504216)
			(xy 131.30779 -11.533703) (xy 131.349004 -11.569419) (xy 131.384716 -11.610636) (xy 131.414199 -11.656515)
			(xy 131.436853 -11.706124) (xy 131.452217 -11.758451) (xy 131.459978 -11.812432) (xy 131.459978 -11.866968)
			(xy 131.452217 -11.920949) (xy 131.436853 -11.973276) (xy 131.432747 -11.982267) (xy 135.233942 -11.982267)
			(xy 135.233942 -11.927733) (xy 135.241703 -11.873755) (xy 135.257066 -11.82143) (xy 135.279719 -11.771824)
			(xy 135.309201 -11.725946) (xy 135.344912 -11.684731) (xy 135.386124 -11.649018) (xy 135.431999 -11.619533)
			(xy 135.481603 -11.596876) (xy 135.533927 -11.581509) (xy 135.587905 -11.573744) (xy 135.615172 -11.573256)
			(xy 136.478772 -11.573256) (xy 136.506046 -11.573682) (xy 136.560038 -11.581441) (xy 136.612377 -11.596805)
			(xy 136.661996 -11.619462) (xy 136.707885 -11.648951) (xy 136.74911 -11.68467) (xy 136.784832 -11.725893)
			(xy 136.814324 -11.77178) (xy 136.836985 -11.821397) (xy 136.852353 -11.873735) (xy 136.860116 -11.927726)
			(xy 136.860116 -11.982274) (xy 136.852353 -12.036265) (xy 136.836985 -12.088603) (xy 136.814324 -12.13822)
			(xy 136.784832 -12.184107) (xy 136.74911 -12.22533) (xy 136.707885 -12.261049) (xy 136.661996 -12.290538)
			(xy 136.612377 -12.313195) (xy 136.560038 -12.328559) (xy 136.506046 -12.336318) (xy 136.478772 -12.33678)
			(xy 135.615172 -12.33678) (xy 135.587905 -12.336256) (xy 135.533927 -12.328491) (xy 135.481603 -12.313124)
			(xy 135.431999 -12.290467) (xy 135.386124 -12.260982) (xy 135.344912 -12.225269) (xy 135.309201 -12.184054)
			(xy 135.279719 -12.138176) (xy 135.257066 -12.08857) (xy 135.241703 -12.036245) (xy 135.233942 -11.982267)
			(xy 131.432747 -11.982267) (xy 131.414199 -12.022885) (xy 131.384716 -12.068764) (xy 131.349004 -12.109981)
			(xy 131.30779 -12.145697) (xy 131.261913 -12.175184) (xy 131.212306 -12.197842) (xy 131.15998 -12.21321)
			(xy 131.106 -12.220975) (xy 131.078732 -12.221464) (xy 130.215132 -12.221464) (xy 130.18786 -12.220999)
			(xy 130.13387 -12.21324) (xy 130.081533 -12.197877) (xy 130.031916 -12.175221) (xy 129.986029 -12.145735)
			(xy 129.944805 -12.110017) (xy 129.909085 -12.068797) (xy 129.879594 -12.022912) (xy 129.856934 -11.973297)
			(xy 129.841567 -11.920962) (xy 129.833804 -11.866972) (xy 125.495706 -11.866972) (xy 125.377128 -11.941479)
			(xy 125.253928 -12.009569) (xy 125.127104 -12.070645) (xy 124.997055 -12.124513) (xy 124.86419 -12.171005)
			(xy 124.728928 -12.209974) (xy 124.591693 -12.241298) (xy 124.452918 -12.264877) (xy 124.313039 -12.280639)
			(xy 124.172496 -12.288532) (xy 124.102114 -12.289028) (xy 83.70189 -12.289028) (xy 83.631508 -12.288534)
			(xy 83.490965 -12.280641) (xy 83.351086 -12.26488) (xy 83.21231 -12.2413) (xy 83.075075 -12.209977)
			(xy 82.939812 -12.171008) (xy 82.806947 -12.124516) (xy 82.676898 -12.070648) (xy 82.550073 -12.009572)
			(xy 82.426873 -11.941482) (xy 82.307684 -11.866591) (xy 82.192882 -11.785134) (xy 82.082828 -11.697369)
			(xy 81.977868 -11.603571) (xy 81.878333 -11.504036) (xy 81.784535 -11.399076) (xy 81.696769 -11.289022)
			(xy 81.615313 -11.174221) (xy 81.540421 -11.055032) (xy 81.47233 -10.931832) (xy 81.411254 -10.805008)
			(xy 81.357386 -10.674959) (xy 81.310894 -10.542094) (xy 81.271924 -10.406831) (xy 81.240601 -10.269596)
			(xy 81.217021 -10.13082) (xy 81.20126 -9.990941) (xy 81.193366 -9.850398) (xy 81.192878 -9.780016)
			(xy 81.192878 -0.559816) (xy 81.192461 -0.549794) (xy 81.184793 -0.531276) (xy 81.170619 -0.517104)
			(xy 81.1521 -0.509438) (xy 81.142078 -0.509016) (xy 13.661898 -0.509016) (xy 13.651878 -0.509436)
			(xy 13.633365 -0.517107) (xy 13.619197 -0.53128) (xy 13.611532 -0.549796) (xy 13.611098 -0.559816)
			(xy 13.611098 -5.169916) (xy 14.349229 -5.169916) (xy 14.353238 -5.081915) (xy 14.365233 -4.994644)
			(xy 14.385115 -4.908825) (xy 14.412718 -4.825169) (xy 14.447814 -4.74437) (xy 14.490112 -4.667097)
			(xy 14.539261 -4.593991) (xy 14.594855 -4.525657) (xy 14.656432 -4.462662) (xy 14.723483 -4.405527)
			(xy 14.795452 -4.354726) (xy 14.871742 -4.31068) (xy 14.951721 -4.273754) (xy 15.034726 -4.244253)
			(xy 15.120071 -4.222424) (xy 15.207047 -4.208445) (xy 15.294933 -4.202433) (xy 15.383002 -4.204439)
			(xy 15.470524 -4.214444) (xy 15.556774 -4.232367) (xy 15.641036 -4.258059) (xy 15.722613 -4.291306)
			(xy 15.800829 -4.331834) (xy 15.875035 -4.379307) (xy 15.944617 -4.433331) (xy 16.008997 -4.493458)
			(xy 16.067644 -4.559191) (xy 16.12007 -4.629985) (xy 16.165841 -4.705252) (xy 16.204578 -4.78437)
			(xy 16.23596 -4.866683) (xy 16.259727 -4.951508) (xy 16.266939 -4.990667) (xy 20.439138 -4.990667)
			(xy 20.439138 -4.936133) (xy 20.446899 -4.882153) (xy 20.462263 -4.829827) (xy 20.484917 -4.78022)
			(xy 20.5144 -4.734341) (xy 20.550112 -4.693126) (xy 20.591325 -4.657412) (xy 20.637202 -4.627926)
			(xy 20.686808 -4.60527) (xy 20.739133 -4.589903) (xy 20.793113 -4.58214) (xy 20.82038 -4.581652)
			(xy 21.68398 -4.581652) (xy 21.711253 -4.582086) (xy 21.765244 -4.589846) (xy 21.817581 -4.605211)
			(xy 21.867198 -4.627869) (xy 21.913086 -4.657357) (xy 21.95431 -4.693076) (xy 21.990031 -4.734298)
			(xy 22.019522 -4.780184) (xy 22.042182 -4.8298) (xy 22.057549 -4.882136) (xy 22.065312 -4.936127)
			(xy 22.065312 -4.990671) (xy 24.039016 -4.990671) (xy 24.039016 -4.936129) (xy 24.046778 -4.882142)
			(xy 24.062145 -4.82981) (xy 24.084803 -4.780197) (xy 24.114292 -4.734314) (xy 24.15001 -4.693095)
			(xy 24.191231 -4.657379) (xy 24.237116 -4.627893) (xy 24.28673 -4.605237) (xy 24.339064 -4.589873)
			(xy 24.393051 -4.582114) (xy 24.420322 -4.581652) (xy 25.283922 -4.581652) (xy 25.311191 -4.582112)
			(xy 25.365175 -4.589876) (xy 25.417503 -4.605244) (xy 25.467113 -4.627903) (xy 25.512992 -4.65739)
			(xy 25.554209 -4.693107) (xy 25.589923 -4.734325) (xy 25.619408 -4.780207) (xy 25.642063 -4.829817)
			(xy 25.657428 -4.882147) (xy 25.66519 -4.936131) (xy 25.66519 -4.990667) (xy 27.639038 -4.990667)
			(xy 27.639038 -4.936133) (xy 27.646799 -4.882155) (xy 27.662162 -4.82983) (xy 27.684814 -4.780224)
			(xy 27.714296 -4.734347) (xy 27.750006 -4.693131) (xy 27.791218 -4.657417) (xy 27.837092 -4.627932)
			(xy 27.886696 -4.605274) (xy 27.93902 -4.589906) (xy 27.992997 -4.582141) (xy 28.020264 -4.581652)
			(xy 28.883864 -4.581652) (xy 28.911138 -4.582085) (xy 28.96513 -4.589843) (xy 29.017469 -4.605207)
			(xy 29.067089 -4.627863) (xy 29.112979 -4.657351) (xy 29.154205 -4.69307) (xy 29.189927 -4.734292)
			(xy 29.219419 -4.78018) (xy 29.24208 -4.829797) (xy 29.257449 -4.882134) (xy 29.265212 -4.936126)
			(xy 29.265212 -4.990667) (xy 31.239238 -4.990667) (xy 31.239238 -4.936133) (xy 31.246999 -4.882155)
			(xy 31.262361 -4.829831) (xy 31.285014 -4.780225) (xy 31.314495 -4.734348) (xy 31.350205 -4.693133)
			(xy 31.391416 -4.657419) (xy 31.43729 -4.627933) (xy 31.486893 -4.605275) (xy 31.539216 -4.589907)
			(xy 31.593193 -4.582141) (xy 31.62046 -4.581652) (xy 32.48406 -4.581652) (xy 32.511334 -4.582085)
			(xy 32.565327 -4.589843) (xy 32.617666 -4.605206) (xy 32.667286 -4.627862) (xy 32.713177 -4.65735)
			(xy 32.754403 -4.693068) (xy 32.790126 -4.734291) (xy 32.819619 -4.780178) (xy 32.84228 -4.829796)
			(xy 32.857649 -4.882134) (xy 32.865412 -4.936126) (xy 32.865412 -4.990671) (xy 40.349116 -4.990671)
			(xy 40.349116 -4.936129) (xy 40.356878 -4.882142) (xy 40.372245 -4.829809) (xy 40.394903 -4.780196)
			(xy 40.424392 -4.734313) (xy 40.460111 -4.693094) (xy 40.501332 -4.657378) (xy 40.547217 -4.627892)
			(xy 40.596832 -4.605237) (xy 40.649165 -4.589873) (xy 40.703153 -4.582114) (xy 40.730424 -4.581652)
			(xy 41.594024 -4.581652) (xy 41.621293 -4.582112) (xy 41.675276 -4.589877) (xy 41.727605 -4.605245)
			(xy 41.777214 -4.627903) (xy 41.823093 -4.657391) (xy 41.86431 -4.693107) (xy 41.900024 -4.734326)
			(xy 41.929508 -4.780207) (xy 41.952164 -4.829818) (xy 41.967528 -4.882147) (xy 41.97529 -4.936131)
			(xy 41.97529 -4.990667) (xy 43.949138 -4.990667) (xy 43.949138 -4.936133) (xy 43.956899 -4.882155)
			(xy 43.972262 -4.82983) (xy 43.994915 -4.780224) (xy 44.024396 -4.734346) (xy 44.060107 -4.693131)
			(xy 44.101319 -4.657417) (xy 44.147194 -4.627931) (xy 44.196798 -4.605274) (xy 44.249121 -4.589906)
			(xy 44.303099 -4.582141) (xy 44.330366 -4.581652) (xy 45.193966 -4.581652) (xy 45.22124 -4.582085)
			(xy 45.275232 -4.589844) (xy 45.327571 -4.605208) (xy 45.37719 -4.627864) (xy 45.42308 -4.657352)
			(xy 45.464305 -4.693071) (xy 45.500028 -4.734293) (xy 45.52952 -4.78018) (xy 45.552181 -4.829797)
			(xy 45.567549 -4.882135) (xy 45.575312 -4.936126) (xy 45.575312 -4.990667) (xy 51.559238 -4.990667)
			(xy 51.559238 -4.936133) (xy 51.566999 -4.882155) (xy 51.582361 -4.829831) (xy 51.605014 -4.780225)
			(xy 51.634495 -4.734348) (xy 51.670205 -4.693133) (xy 51.711416 -4.657419) (xy 51.75729 -4.627933)
			(xy 51.806893 -4.605275) (xy 51.859216 -4.589907) (xy 51.913193 -4.582141) (xy 51.94046 -4.581652)
			(xy 52.80406 -4.581652) (xy 52.831334 -4.582085) (xy 52.885327 -4.589843) (xy 52.937666 -4.605206)
			(xy 52.987286 -4.627862) (xy 53.033177 -4.65735) (xy 53.074403 -4.693068) (xy 53.110126 -4.734291)
			(xy 53.139619 -4.780178) (xy 53.16228 -4.829796) (xy 53.177649 -4.882134) (xy 53.185412 -4.936126)
			(xy 53.185412 -4.99067) (xy 55.159115 -4.99067) (xy 55.159115 -4.93613) (xy 55.166877 -4.882145)
			(xy 55.182243 -4.829814) (xy 55.2049 -4.780202) (xy 55.234387 -4.73432) (xy 55.270103 -4.693102)
			(xy 55.311322 -4.657386) (xy 55.357204 -4.627899) (xy 55.406816 -4.605242) (xy 55.459147 -4.589877)
			(xy 55.513132 -4.582115) (xy 55.540402 -4.581652) (xy 56.404002 -4.581652) (xy 56.431272 -4.582111)
			(xy 56.485258 -4.589873) (xy 56.537589 -4.605239) (xy 56.587201 -4.627896) (xy 56.633083 -4.657383)
			(xy 56.674302 -4.6931) (xy 56.710018 -4.734319) (xy 56.739505 -4.780201) (xy 56.762162 -4.829813)
			(xy 56.777528 -4.882144) (xy 56.78529 -4.93613) (xy 56.78529 -4.99067) (xy 56.777528 -5.044656) (xy 56.762162 -5.096987)
			(xy 56.739505 -5.146599) (xy 56.710018 -5.192481) (xy 56.674302 -5.2337) (xy 56.633083 -5.269417)
			(xy 56.587201 -5.298904) (xy 56.537589 -5.321561) (xy 56.485258 -5.336927) (xy 56.431272 -5.344689)
			(xy 56.404002 -5.345176) (xy 55.540402 -5.345176) (xy 55.513132 -5.344685) (xy 55.459147 -5.336923)
			(xy 55.406816 -5.321558) (xy 55.357204 -5.298901) (xy 55.311322 -5.269414) (xy 55.270103 -5.233698)
			(xy 55.234387 -5.19248) (xy 55.2049 -5.146598) (xy 55.182243 -5.096986) (xy 55.166877 -5.044655)
			(xy 55.159115 -4.99067) (xy 53.185412 -4.99067) (xy 53.185412 -4.990674) (xy 53.177649 -5.044666)
			(xy 53.16228 -5.097004) (xy 53.139619 -5.146622) (xy 53.110126 -5.192509) (xy 53.074403 -5.233732)
			(xy 53.033177 -5.26945) (xy 52.987286 -5.298938) (xy 52.937666 -5.321594) (xy 52.885327 -5.336957)
			(xy 52.831334 -5.344715) (xy 52.80406 -5.345176) (xy 51.94046 -5.345176) (xy 51.913194 -5.344659)
			(xy 51.859216 -5.336893) (xy 51.806893 -5.321525) (xy 51.75729 -5.298867) (xy 51.711416 -5.269381)
			(xy 51.670205 -5.233667) (xy 51.634495 -5.192452) (xy 51.605014 -5.146575) (xy 51.582361 -5.096969)
			(xy 51.566999 -5.044645) (xy 51.559238 -4.990667) (xy 45.575312 -4.990667) (xy 45.575312 -4.990674)
			(xy 45.567549 -5.044665) (xy 45.552181 -5.097003) (xy 45.52952 -5.14662) (xy 45.500028 -5.192507)
			(xy 45.464305 -5.233729) (xy 45.42308 -5.269448) (xy 45.37719 -5.298936) (xy 45.327571 -5.321592)
			(xy 45.275232 -5.336956) (xy 45.22124 -5.344715) (xy 45.193966 -5.345176) (xy 44.330366 -5.345176)
			(xy 44.303099 -5.344659) (xy 44.249121 -5.336894) (xy 44.196798 -5.321526) (xy 44.147194 -5.298869)
			(xy 44.101319 -5.269383) (xy 44.060107 -5.233669) (xy 44.024396 -5.192454) (xy 43.994915 -5.146576)
			(xy 43.972262 -5.09697) (xy 43.956899 -5.044645) (xy 43.949138 -4.990667) (xy 41.97529 -4.990667)
			(xy 41.97529 -4.990669) (xy 41.967528 -5.044653) (xy 41.952164 -5.096982) (xy 41.929508 -5.146593)
			(xy 41.900024 -5.192474) (xy 41.86431 -5.233693) (xy 41.823093 -5.269409) (xy 41.777214 -5.298897)
			(xy 41.727605 -5.321555) (xy 41.675276 -5.336923) (xy 41.621293 -5.344688) (xy 41.594024 -5.345176)
			(xy 40.730424 -5.345176) (xy 40.703153 -5.344686) (xy 40.649165 -5.336927) (xy 40.596832 -5.321563)
			(xy 40.547217 -5.298908) (xy 40.501332 -5.269422) (xy 40.460111 -5.233706) (xy 40.424392 -5.192487)
			(xy 40.394903 -5.146604) (xy 40.372245 -5.096991) (xy 40.356878 -5.044658) (xy 40.349116 -4.990671)
			(xy 32.865412 -4.990671) (xy 32.865412 -4.990674) (xy 32.857649 -5.044666) (xy 32.84228 -5.097004)
			(xy 32.819619 -5.146622) (xy 32.790126 -5.192509) (xy 32.754403 -5.233732) (xy 32.713177 -5.26945)
			(xy 32.667286 -5.298938) (xy 32.617666 -5.321594) (xy 32.565327 -5.336957) (xy 32.511334 -5.344715)
			(xy 32.48406 -5.345176) (xy 31.62046 -5.345176) (xy 31.593194 -5.344659) (xy 31.539216 -5.336893)
			(xy 31.486893 -5.321525) (xy 31.43729 -5.298867) (xy 31.391416 -5.269381) (xy 31.350205 -5.233667)
			(xy 31.314495 -5.192452) (xy 31.285014 -5.146575) (xy 31.262361 -5.096969) (xy 31.246999 -5.044645)
			(xy 31.239238 -4.990667) (xy 29.265212 -4.990667) (xy 29.265212 -4.990674) (xy 29.257449 -5.044666)
			(xy 29.24208 -5.097003) (xy 29.219419 -5.14662) (xy 29.189927 -5.192508) (xy 29.154205 -5.23373)
			(xy 29.112979 -5.269449) (xy 29.067089 -5.298937) (xy 29.017469 -5.321593) (xy 28.96513 -5.336957)
			(xy 28.911138 -5.344715) (xy 28.883864 -5.345176) (xy 28.020264 -5.345176) (xy 27.992997 -5.344659)
			(xy 27.93902 -5.336894) (xy 27.886696 -5.321526) (xy 27.837092 -5.298868) (xy 27.791218 -5.269383)
			(xy 27.750006 -5.233669) (xy 27.714296 -5.192453) (xy 27.684814 -5.146576) (xy 27.662162 -5.09697)
			(xy 27.646799 -5.044645) (xy 27.639038 -4.990667) (xy 25.66519 -4.990667) (xy 25.66519 -4.990669)
			(xy 25.657428 -5.044653) (xy 25.642063 -5.096983) (xy 25.619408 -5.146593) (xy 25.589923 -5.192475)
			(xy 25.554209 -5.233693) (xy 25.512992 -5.26941) (xy 25.467113 -5.298897) (xy 25.417503 -5.321556)
			(xy 25.365175 -5.336924) (xy 25.311191 -5.344688) (xy 25.283922 -5.345176) (xy 24.420322 -5.345176)
			(xy 24.393051 -5.344686) (xy 24.339064 -5.336927) (xy 24.28673 -5.321563) (xy 24.237116 -5.298907)
			(xy 24.191231 -5.269421) (xy 24.15001 -5.233705) (xy 24.114292 -5.192486) (xy 24.084803 -5.146603)
			(xy 24.062145 -5.09699) (xy 24.046778 -5.044658) (xy 24.039016 -4.990671) (xy 22.065312 -4.990671)
			(xy 22.065312 -4.990673) (xy 22.057549 -5.044664) (xy 22.042182 -5.097) (xy 22.019522 -5.146616)
			(xy 21.990031 -5.192502) (xy 21.95431 -5.233724) (xy 21.913086 -5.269443) (xy 21.867198 -5.298931)
			(xy 21.817581 -5.321589) (xy 21.765244 -5.336954) (xy 21.711253 -5.344714) (xy 21.68398 -5.345176)
			(xy 20.82038 -5.345176) (xy 20.793113 -5.34466) (xy 20.739133 -5.336897) (xy 20.686808 -5.32153)
			(xy 20.637202 -5.298874) (xy 20.591325 -5.269388) (xy 20.550112 -5.233674) (xy 20.5144 -5.192459)
			(xy 20.484917 -5.14658) (xy 20.462263 -5.096973) (xy 20.446899 -5.044647) (xy 20.439138 -4.990667)
			(xy 16.266939 -4.990667) (xy 16.275682 -5.038143) (xy 16.283693 -5.12587) (xy 16.284194 -5.169916)
			(xy 16.283693 -5.213962) (xy 16.275682 -5.301689) (xy 16.259727 -5.388324) (xy 16.23596 -5.473149)
			(xy 16.204578 -5.555462) (xy 16.165841 -5.63458) (xy 16.12007 -5.709847) (xy 16.067644 -5.780641)
			(xy 16.008997 -5.846374) (xy 15.944617 -5.906501) (xy 15.875035 -5.960525) (xy 15.800829 -6.007998)
			(xy 15.722613 -6.048526) (xy 15.641036 -6.081773) (xy 15.556774 -6.107465) (xy 15.470524 -6.125388)
			(xy 15.383002 -6.135393) (xy 15.294933 -6.137399) (xy 15.207047 -6.131387) (xy 15.120071 -6.117408)
			(xy 15.034726 -6.095579) (xy 14.951721 -6.066078) (xy 14.871742 -6.029152) (xy 14.795452 -5.985106)
			(xy 14.723483 -5.934305) (xy 14.656432 -5.87717) (xy 14.594855 -5.814175) (xy 14.539261 -5.745841)
			(xy 14.490112 -5.672735) (xy 14.447814 -5.595462) (xy 14.412718 -5.514663) (xy 14.385115 -5.431007)
			(xy 14.365233 -5.345188) (xy 14.353238 -5.257917) (xy 14.349229 -5.169916) (xy 13.611098 -5.169916)
			(xy 13.611098 -6.169914) (xy 78.515217 -6.169914) (xy 78.519222 -6.082006) (xy 78.531205 -5.994826)
			(xy 78.551065 -5.909097) (xy 78.57864 -5.825529) (xy 78.613699 -5.744815) (xy 78.655952 -5.667623)
			(xy 78.70505 -5.594594) (xy 78.760586 -5.526332) (xy 78.822098 -5.463402) (xy 78.889079 -5.406328)
			(xy 78.960972 -5.35558) (xy 79.037181 -5.31158) (xy 79.117076 -5.274693) (xy 79.199995 -5.245224)
			(xy 79.28525 -5.223417) (xy 79.372134 -5.209453) (xy 79.459928 -5.203447) (xy 79.547905 -5.205451)
			(xy 79.635335 -5.215446) (xy 79.721494 -5.23335) (xy 79.805668 -5.259014) (xy 79.887159 -5.292227)
			(xy 79.965293 -5.332713) (xy 80.039421 -5.380135) (xy 80.108929 -5.434102) (xy 80.173243 -5.494167)
			(xy 80.231827 -5.559831) (xy 80.284198 -5.63055) (xy 80.329921 -5.705738) (xy 80.368618 -5.784773)
			(xy 80.399967 -5.866999) (xy 80.423709 -5.951735) (xy 80.439647 -6.038279) (xy 80.447649 -6.125914)
			(xy 80.44815 -6.169914) (xy 80.447649 -6.213914) (xy 80.439647 -6.301549) (xy 80.423709 -6.388093)
			(xy 80.399967 -6.472829) (xy 80.368618 -6.555055) (xy 80.329921 -6.63409) (xy 80.284198 -6.709278)
			(xy 80.231827 -6.779997) (xy 80.173243 -6.845661) (xy 80.108929 -6.905726) (xy 80.039421 -6.959693)
			(xy 79.965293 -7.007115) (xy 79.887159 -7.047601) (xy 79.805668 -7.080814) (xy 79.721494 -7.106478)
			(xy 79.635335 -7.124382) (xy 79.547905 -7.134377) (xy 79.459928 -7.136381) (xy 79.372134 -7.130375)
			(xy 79.28525 -7.116411) (xy 79.199995 -7.094604) (xy 79.117076 -7.065135) (xy 79.037181 -7.028248)
			(xy 78.960972 -6.984248) (xy 78.889079 -6.9335) (xy 78.822098 -6.876426) (xy 78.760586 -6.813496)
			(xy 78.70505 -6.745234) (xy 78.655952 -6.672205) (xy 78.613699 -6.595013) (xy 78.57864 -6.514299)
			(xy 78.551065 -6.430731) (xy 78.531205 -6.345002) (xy 78.519222 -6.257822) (xy 78.515217 -6.169914)
			(xy 13.611098 -6.169914) (xy 13.611098 -6.75243) (xy 18.634432 -6.75243) (xy 18.634432 -6.69789)
			(xy 18.642194 -6.643907) (xy 18.65756 -6.591577) (xy 18.680216 -6.541966) (xy 18.709702 -6.496085)
			(xy 18.745417 -6.454867) (xy 18.786635 -6.419152) (xy 18.832516 -6.389666) (xy 18.882127 -6.36701)
			(xy 18.934457 -6.351644) (xy 18.98844 -6.343882) (xy 19.01571 -6.343396) (xy 19.87931 -6.343396)
			(xy 19.906579 -6.343886) (xy 19.960563 -6.351648) (xy 20.012892 -6.367013) (xy 20.062502 -6.389669)
			(xy 20.108382 -6.419155) (xy 20.1496 -6.45487) (xy 20.185315 -6.496088) (xy 20.214801 -6.541968)
			(xy 20.237457 -6.591578) (xy 20.252822 -6.643907) (xy 20.260584 -6.697891) (xy 20.260584 -6.752429)
			(xy 20.260584 -6.752431) (xy 22.234349 -6.752431) (xy 22.234349 -6.697889) (xy 22.242112 -6.643901)
			(xy 22.257478 -6.591568) (xy 22.280136 -6.541955) (xy 22.309624 -6.496071) (xy 22.345342 -6.45485)
			(xy 22.386562 -6.419133) (xy 22.432447 -6.389645) (xy 22.48206 -6.366987) (xy 22.534393 -6.351621)
			(xy 22.588381 -6.343859) (xy 22.615652 -6.343396) (xy 23.479252 -6.343396) (xy 23.506521 -6.343887)
			(xy 23.560504 -6.351648) (xy 23.612833 -6.367014) (xy 23.662443 -6.38967) (xy 23.708323 -6.419156)
			(xy 23.749541 -6.454871) (xy 23.785255 -6.496088) (xy 23.814741 -6.541969) (xy 23.837397 -6.591579)
			(xy 23.852762 -6.643908) (xy 23.860524 -6.697891) (xy 23.860524 -6.752429) (xy 23.860518 -6.752472)
			(xy 25.834283 -6.752472) (xy 25.834283 -6.697928) (xy 25.842045 -6.643939) (xy 25.857412 -6.591604)
			(xy 25.88007 -6.541989) (xy 25.909558 -6.496103) (xy 25.945277 -6.454881) (xy 25.986498 -6.419162)
			(xy 26.032384 -6.389673) (xy 26.081998 -6.367014) (xy 26.134333 -6.351646) (xy 26.188322 -6.343883)
			(xy 26.215594 -6.343396) (xy 27.079194 -6.343396) (xy 27.106462 -6.343943) (xy 27.160444 -6.351704)
			(xy 27.212772 -6.367068) (xy 27.26238 -6.389722) (xy 27.308259 -6.419207) (xy 27.349476 -6.45492)
			(xy 27.38519 -6.496136) (xy 27.414675 -6.542015) (xy 27.43733 -6.591623) (xy 27.452695 -6.64395)
			(xy 27.460457 -6.697932) (xy 27.460457 -6.752468) (xy 27.460456 -6.752472) (xy 29.434483 -6.752472)
			(xy 29.434483 -6.697928) (xy 29.442245 -6.643939) (xy 29.457611 -6.591605) (xy 29.480269 -6.54199)
			(xy 29.509757 -6.496105) (xy 29.545476 -6.454883) (xy 29.586697 -6.419163) (xy 29.632581 -6.389674)
			(xy 29.682196 -6.367015) (xy 29.73453 -6.351647) (xy 29.788518 -6.343883) (xy 29.81579 -6.343396)
			(xy 30.67939 -6.343396) (xy 30.706658 -6.343943) (xy 30.76064 -6.351703) (xy 30.812969 -6.367067)
			(xy 30.862578 -6.389721) (xy 30.908457 -6.419205) (xy 30.949674 -6.454919) (xy 30.985389 -6.496135)
			(xy 31.014874 -6.542014) (xy 31.03753 -6.591622) (xy 31.052895 -6.64395) (xy 31.060657 -6.697932)
			(xy 31.060657 -6.752468) (xy 31.060657 -6.75247) (xy 38.544482 -6.75247) (xy 38.544482 -6.69793)
			(xy 38.552244 -6.643944) (xy 38.567608 -6.591613) (xy 38.590264 -6.542) (xy 38.619749 -6.496116)
			(xy 38.655463 -6.454895) (xy 38.696679 -6.419176) (xy 38.74256 -6.389686) (xy 38.792169 -6.367025)
			(xy 38.844499 -6.351654) (xy 38.898484 -6.343886) (xy 38.925754 -6.343396) (xy 39.789354 -6.343396)
			(xy 39.816624 -6.34394) (xy 39.87061 -6.351696) (xy 39.922943 -6.367057) (xy 39.972556 -6.389709)
			(xy 40.01844 -6.419192) (xy 40.059662 -6.454906) (xy 40.09538 -6.496123) (xy 40.124869 -6.542004)
			(xy 40.147527 -6.591614) (xy 40.162894 -6.643945) (xy 40.170656 -6.69793) (xy 40.170656 -6.75247)
			(xy 40.170656 -6.752472) (xy 42.144383 -6.752472) (xy 42.144383 -6.697928) (xy 42.152145 -6.643939)
			(xy 42.167512 -6.591604) (xy 42.19017 -6.541988) (xy 42.219659 -6.496103) (xy 42.255378 -6.454881)
			(xy 42.296599 -6.419161) (xy 42.342485 -6.389672) (xy 42.3921 -6.367013) (xy 42.444435 -6.351646)
			(xy 42.498424 -6.343883) (xy 42.525696 -6.343396) (xy 43.389296 -6.343396) (xy 43.416564 -6.343943)
			(xy 43.470546 -6.351704) (xy 43.522873 -6.367068) (xy 43.572481 -6.389723) (xy 43.61836 -6.419207)
			(xy 43.659576 -6.454921) (xy 43.69529 -6.496136) (xy 43.724775 -6.542015) (xy 43.74743 -6.591623)
			(xy 43.762795 -6.643951) (xy 43.770557 -6.697932) (xy 43.770557 -6.752468) (xy 43.770556 -6.752472)
			(xy 49.754483 -6.752472) (xy 49.754483 -6.697928) (xy 49.762245 -6.643939) (xy 49.777611 -6.591605)
			(xy 49.800269 -6.54199) (xy 49.829757 -6.496105) (xy 49.865476 -6.454883) (xy 49.906697 -6.419163)
			(xy 49.952581 -6.389674) (xy 50.002196 -6.367015) (xy 50.05453 -6.351647) (xy 50.108518 -6.343883)
			(xy 50.13579 -6.343396) (xy 50.99939 -6.343396) (xy 51.026658 -6.343943) (xy 51.08064 -6.351703)
			(xy 51.132969 -6.367067) (xy 51.182578 -6.389721) (xy 51.228457 -6.419205) (xy 51.269674 -6.454919)
			(xy 51.305389 -6.496135) (xy 51.334874 -6.542014) (xy 51.35753 -6.591622) (xy 51.372895 -6.64395)
			(xy 51.380657 -6.697932) (xy 51.380657 -6.752468) (xy 51.380656 -6.752475) (xy 53.35436 -6.752475)
			(xy 53.35436 -6.697925) (xy 53.362124 -6.643929) (xy 53.377493 -6.591588) (xy 53.400155 -6.541967)
			(xy 53.429649 -6.496077) (xy 53.465374 -6.454851) (xy 53.506603 -6.41913) (xy 53.552495 -6.38964)
			(xy 53.602118 -6.366982) (xy 53.65446 -6.351617) (xy 53.708457 -6.343857) (xy 53.735732 -6.343396)
			(xy 54.599332 -6.343396) (xy 54.626597 -6.343969) (xy 54.680571 -6.351733) (xy 54.732891 -6.367099)
			(xy 54.782492 -6.389755) (xy 54.828364 -6.419238) (xy 54.869573 -6.45495) (xy 54.905281 -6.496162)
			(xy 54.93476 -6.542036) (xy 54.957412 -6.591639) (xy 54.972774 -6.64396) (xy 54.980534 -6.697935)
			(xy 54.980534 -6.752465) (xy 54.980533 -6.752471) (xy 56.954382 -6.752471) (xy 56.954382 -6.697929)
			(xy 56.962144 -6.643942) (xy 56.97751 -6.591608) (xy 57.000167 -6.541994) (xy 57.029654 -6.49611)
			(xy 57.06537 -6.454888) (xy 57.106589 -6.419169) (xy 57.152472 -6.389679) (xy 57.202084 -6.367019)
			(xy 57.254416 -6.35165) (xy 57.308403 -6.343884) (xy 57.335674 -6.343396) (xy 58.199274 -6.343396)
			(xy 58.226543 -6.343942) (xy 58.280527 -6.3517) (xy 58.332857 -6.367062) (xy 58.382468 -6.389716)
			(xy 58.42835 -6.4192) (xy 58.469569 -6.454913) (xy 58.505285 -6.496129) (xy 58.534772 -6.542009)
			(xy 58.557429 -6.591619) (xy 58.564228 -6.614772) (xy 70.948992 -6.614772) (xy 70.948992 -6.560228)
			(xy 70.956754 -6.506238) (xy 70.972121 -6.453903) (xy 70.994781 -6.404288) (xy 71.02427 -6.358403)
			(xy 71.05999 -6.317181) (xy 71.101212 -6.281463) (xy 71.147099 -6.251975) (xy 71.196715 -6.229317)
			(xy 71.24905 -6.213952) (xy 71.30304 -6.206191) (xy 71.330312 -6.205728) (xy 72.193912 -6.205728)
			(xy 72.22118 -6.206235) (xy 72.275161 -6.213998) (xy 72.327488 -6.229364) (xy 72.377095 -6.25202)
			(xy 72.422973 -6.281506) (xy 72.464188 -6.31722) (xy 72.499901 -6.358436) (xy 72.529385 -6.404315)
			(xy 72.55204 -6.453924) (xy 72.567404 -6.506251) (xy 72.575166 -6.560232) (xy 72.575166 -6.614768)
			(xy 72.567404 -6.668749) (xy 72.55204 -6.721076) (xy 72.529385 -6.770685) (xy 72.499901 -6.816564)
			(xy 72.464188 -6.85778) (xy 72.422973 -6.893494) (xy 72.377095 -6.92298) (xy 72.327488 -6.945636)
			(xy 72.275161 -6.961002) (xy 72.22118 -6.968765) (xy 72.193912 -6.969252) (xy 71.330312 -6.969252)
			(xy 71.30304 -6.968809) (xy 71.24905 -6.961048) (xy 71.196715 -6.945683) (xy 71.147099 -6.923025)
			(xy 71.101212 -6.893537) (xy 71.05999 -6.857819) (xy 71.02427 -6.816597) (xy 70.994781 -6.770712)
			(xy 70.972121 -6.721097) (xy 70.956754 -6.668762) (xy 70.948992 -6.614772) (xy 58.564228 -6.614772)
			(xy 58.572795 -6.643948) (xy 58.580557 -6.697931) (xy 58.580557 -6.752469) (xy 58.572795 -6.806452)
			(xy 58.557429 -6.858781) (xy 58.534772 -6.908391) (xy 58.505285 -6.954271) (xy 58.469569 -6.995487)
			(xy 58.42835 -7.0312) (xy 58.382468 -7.060684) (xy 58.332857 -7.083338) (xy 58.280527 -7.0987) (xy 58.226543 -7.106458)
			(xy 58.199274 -7.10692) (xy 57.335674 -7.10692) (xy 57.308403 -7.106516) (xy 57.254416 -7.09875)
			(xy 57.202084 -7.083381) (xy 57.152472 -7.060721) (xy 57.106589 -7.031231) (xy 57.06537 -6.995512)
			(xy 57.029654 -6.95429) (xy 57.000167 -6.908406) (xy 56.97751 -6.858792) (xy 56.962144 -6.806458)
			(xy 56.954382 -6.752471) (xy 54.980533 -6.752471) (xy 54.972774 -6.80644) (xy 54.957412 -6.858761)
			(xy 54.93476 -6.908364) (xy 54.905281 -6.954238) (xy 54.869573 -6.99545) (xy 54.828364 -7.031162)
			(xy 54.782492 -7.060645) (xy 54.732891 -7.083301) (xy 54.680571 -7.098667) (xy 54.626597 -7.106431)
			(xy 54.599332 -7.10692) (xy 53.735732 -7.10692) (xy 53.708457 -7.106543) (xy 53.65446 -7.098783)
			(xy 53.602118 -7.083418) (xy 53.552495 -7.06076) (xy 53.506603 -7.03127) (xy 53.465374 -6.995549)
			(xy 53.429649 -6.954323) (xy 53.400155 -6.908433) (xy 53.377493 -6.858812) (xy 53.362124 -6.806471)
			(xy 53.35436 -6.752475) (xy 51.380656 -6.752475) (xy 51.372895 -6.80645) (xy 51.35753 -6.858778)
			(xy 51.334874 -6.908386) (xy 51.305389 -6.954265) (xy 51.269674 -6.995481) (xy 51.228457 -7.031195)
			(xy 51.182578 -7.060679) (xy 51.132969 -7.083333) (xy 51.08064 -7.098697) (xy 51.026658 -7.106457)
			(xy 50.99939 -7.10692) (xy 50.13579 -7.10692) (xy 50.108518 -7.106517) (xy 50.05453 -7.098753) (xy 50.002196 -7.083385)
			(xy 49.952581 -7.060726) (xy 49.906697 -7.031237) (xy 49.865476 -6.995517) (xy 49.829757 -6.954295)
			(xy 49.800269 -6.90841) (xy 49.777611 -6.858795) (xy 49.762245 -6.806461) (xy 49.754483 -6.752472)
			(xy 43.770556 -6.752472) (xy 43.762795 -6.806449) (xy 43.74743 -6.858777) (xy 43.724775 -6.908385)
			(xy 43.69529 -6.954264) (xy 43.659576 -6.995479) (xy 43.61836 -7.031193) (xy 43.572481 -7.060677)
			(xy 43.522873 -7.083332) (xy 43.470546 -7.098696) (xy 43.416564 -7.106457) (xy 43.389296 -7.10692)
			(xy 42.525696 -7.10692) (xy 42.498424 -7.106517) (xy 42.444435 -7.098754) (xy 42.3921 -7.083387)
			(xy 42.342485 -7.060728) (xy 42.296599 -7.031239) (xy 42.255378 -6.995519) (xy 42.219659 -6.954297)
			(xy 42.19017 -6.908412) (xy 42.167512 -6.858796) (xy 42.152145 -6.806461) (xy 42.144383 -6.752472)
			(xy 40.170656 -6.752472) (xy 40.162894 -6.806455) (xy 40.147527 -6.858786) (xy 40.124869 -6.908396)
			(xy 40.09538 -6.954277) (xy 40.059661 -6.995494) (xy 40.01844 -7.031208) (xy 39.972556 -7.060691)
			(xy 39.922943 -7.083343) (xy 39.87061 -7.098704) (xy 39.816624 -7.10646) (xy 39.789354 -7.10692)
			(xy 38.925754 -7.10692) (xy 38.898484 -7.106514) (xy 38.844499 -7.098746) (xy 38.792169 -7.083375)
			(xy 38.74256 -7.060714) (xy 38.696679 -7.031224) (xy 38.655463 -6.995505) (xy 38.619749 -6.954284)
			(xy 38.590264 -6.9084) (xy 38.567608 -6.858787) (xy 38.552244 -6.806456) (xy 38.544482 -6.75247)
			(xy 31.060657 -6.75247) (xy 31.052895 -6.80645) (xy 31.03753 -6.858778) (xy 31.014874 -6.908386)
			(xy 30.985389 -6.954265) (xy 30.949674 -6.995481) (xy 30.908457 -7.031195) (xy 30.862578 -7.060679)
			(xy 30.812969 -7.083333) (xy 30.76064 -7.098697) (xy 30.706658 -7.106457) (xy 30.67939 -7.10692)
			(xy 29.81579 -7.10692) (xy 29.788518 -7.106517) (xy 29.73453 -7.098753) (xy 29.682196 -7.083385)
			(xy 29.632581 -7.060726) (xy 29.586697 -7.031237) (xy 29.545476 -6.995517) (xy 29.509757 -6.954295)
			(xy 29.480269 -6.90841) (xy 29.457611 -6.858795) (xy 29.442245 -6.806461) (xy 29.434483 -6.752472)
			(xy 27.460456 -6.752472) (xy 27.452695 -6.80645) (xy 27.43733 -6.858777) (xy 27.414675 -6.908385)
			(xy 27.38519 -6.954264) (xy 27.349476 -6.99548) (xy 27.308259 -7.031193) (xy 27.26238 -7.060678)
			(xy 27.212772 -7.083332) (xy 27.160444 -7.098696) (xy 27.106462 -7.106457) (xy 27.079194 -7.10692)
			(xy 26.215594 -7.10692) (xy 26.188322 -7.106517) (xy 26.134333 -7.098754) (xy 26.081998 -7.083386)
			(xy 26.032384 -7.060727) (xy 25.986498 -7.031238) (xy 25.945277 -6.995519) (xy 25.909558 -6.954297)
			(xy 25.88007 -6.908411) (xy 25.857412 -6.858796) (xy 25.842045 -6.806461) (xy 25.834283 -6.752472)
			(xy 23.860518 -6.752472) (xy 23.852762 -6.806412) (xy 23.837397 -6.858741) (xy 23.814741 -6.908351)
			(xy 23.785255 -6.954232) (xy 23.749541 -6.995449) (xy 23.708323 -7.031164) (xy 23.662443 -7.06065)
			(xy 23.612833 -7.083306) (xy 23.560504 -7.098672) (xy 23.506521 -7.106433) (xy 23.479252 -7.10692)
			(xy 22.615652 -7.10692) (xy 22.588381 -7.106461) (xy 22.534393 -7.098699) (xy 22.48206 -7.083333)
			(xy 22.432447 -7.060675) (xy 22.386562 -7.031187) (xy 22.345342 -6.99547) (xy 22.309624 -6.954249)
			(xy 22.280136 -6.908365) (xy 22.257478 -6.858752) (xy 22.242112 -6.806419) (xy 22.234349 -6.752431)
			(xy 20.260584 -6.752431) (xy 20.252822 -6.806413) (xy 20.237457 -6.858742) (xy 20.214801 -6.908352)
			(xy 20.185315 -6.954232) (xy 20.1496 -6.99545) (xy 20.108382 -7.031165) (xy 20.062502 -7.060651)
			(xy 20.012892 -7.083307) (xy 19.960563 -7.098672) (xy 19.906579 -7.106434) (xy 19.87931 -7.10692)
			(xy 19.01571 -7.10692) (xy 18.98844 -7.106438) (xy 18.934457 -7.098676) (xy 18.882127 -7.08331) (xy 18.832516 -7.060654)
			(xy 18.786635 -7.031168) (xy 18.745417 -6.995453) (xy 18.709702 -6.954235) (xy 18.680216 -6.908354)
			(xy 18.65756 -6.858743) (xy 18.642194 -6.806413) (xy 18.634432 -6.75243) (xy 13.611098 -6.75243)
			(xy 13.611098 -9.780016) (xy 13.610604 -9.850398) (xy 13.602711 -9.990941) (xy 13.58695 -10.13082)
			(xy 13.563371 -10.269596) (xy 13.532048 -10.406831) (xy 13.493079 -10.542094) (xy 13.446587 -10.674959)
			(xy 13.392719 -10.805008) (xy 13.331643 -10.931832) (xy 13.263553 -11.055033) (xy 13.188662 -11.174221)
			(xy 13.107205 -11.289023) (xy 13.01944 -11.399077) (xy 12.925642 -11.504037) (xy 12.826107 -11.603572)
			(xy 12.721147 -11.69737) (xy 12.611093 -11.785135) (xy 12.496291 -11.866592) (xy 12.377103 -11.941483)
			(xy 12.253902 -12.009573) (xy 12.127078 -12.070649) (xy 11.997029 -12.124517) (xy 11.864164 -12.171009)
			(xy 11.728901 -12.209978) (xy 11.591666 -12.241301) (xy 11.45289 -12.26488) (xy 11.313011 -12.280641)
			(xy 11.172468 -12.288534) (xy 11.102086 -12.289028) (xy 1.999996 -12.289028) (xy 1.944227 -12.289537)
			(xy 1.833 -12.297872) (xy 1.722707 -12.314497) (xy 1.613965 -12.339317) (xy 1.507382 -12.372193)
			(xy 1.403554 -12.412943) (xy 1.353372 -12.43711) (xy 62.309756 -12.43711) (xy 62.310222 -12.396003)
			(xy 62.317806 -12.314139) (xy 62.332909 -12.233324) (xy 62.355404 -12.154247) (xy 62.385098 -12.077583)
			(xy 62.421737 -12.003984) (xy 62.46501 -11.93408) (xy 62.514548 -11.868466) (xy 62.569927 -11.807701)
			(xy 62.630676 -11.752305) (xy 62.696277 -11.70275) (xy 62.766169 -11.659457) (xy 62.839757 -11.622797)
			(xy 62.916414 -11.593082) (xy 62.995485 -11.570566) (xy 63.076295 -11.55544) (xy 63.158157 -11.547833)
			(xy 63.199264 -11.547348) (xy 63.243059 -11.547873) (xy 63.330225 -11.556491) (xy 63.416121 -11.573637)
			(xy 63.499915 -11.599145) (xy 63.580795 -11.632768) (xy 63.619634 -11.653012) (xy 63.6311 -11.65843)
			(xy 63.656428 -11.65843) (xy 63.667894 -11.653012) (xy 63.706738 -11.632781) (xy 63.787623 -11.599174)
			(xy 63.871416 -11.573672) (xy 63.957309 -11.556521) (xy 64.04447 -11.547888) (xy 64.088264 -11.547348)
			(xy 64.132059 -11.547873) (xy 64.219225 -11.556491) (xy 64.305121 -11.573637) (xy 64.388915 -11.599145)
			(xy 64.469795 -11.632768) (xy 64.508634 -11.653012) (xy 64.5201 -11.65843) (xy 64.545428 -11.65843)
			(xy 64.556894 -11.653012) (xy 64.595738 -11.632781) (xy 64.676623 -11.599174) (xy 64.760416 -11.573672)
			(xy 64.846309 -11.556521) (xy 64.93347 -11.547888) (xy 64.977264 -11.547348) (xy 65.021059 -11.547873)
			(xy 65.108225 -11.556491) (xy 65.194121 -11.573637) (xy 65.277915 -11.599145) (xy 65.358795 -11.632768)
			(xy 65.397634 -11.653012) (xy 65.4091 -11.65843) (xy 65.434428 -11.65843) (xy 65.445894 -11.653012)
			(xy 65.484738 -11.632781) (xy 65.565623 -11.599174) (xy 65.649416 -11.573672) (xy 65.735309 -11.556521)
			(xy 65.82247 -11.547888) (xy 65.866264 -11.547348) (xy 65.904554 -11.547763) (xy 65.980848 -11.554368)
			(xy 66.05629 -11.567515) (xy 66.130321 -11.587105) (xy 66.166492 -11.599672) (xy 66.174929 -11.602323)
			(xy 66.192599 -11.602323) (xy 66.201036 -11.599672) (xy 66.237216 -11.587135) (xy 66.311248 -11.56756)
			(xy 66.386687 -11.554411) (xy 66.462976 -11.547785) (xy 66.501264 -11.547348) (xy 66.54268 -11.547848)
			(xy 66.625149 -11.555593) (xy 66.706543 -11.570964) (xy 66.786158 -11.593827) (xy 66.863305 -11.623986)
			(xy 66.937318 -11.661178) (xy 66.972688 -11.68273) (xy 66.980074 -11.686987) (xy 66.996689 -11.690769)
			(xy 67.013625 -11.688896) (xy 67.021456 -11.685524) (xy 67.057233 -11.668994) (xy 67.131154 -11.641645)
			(xy 67.207206 -11.620946) (xy 67.284791 -11.607058) (xy 67.363301 -11.600092) (xy 67.40271 -11.599672)
			(xy 67.443826 -11.600089) (xy 67.525707 -11.607677) (xy 67.606539 -11.622789) (xy 67.685632 -11.645294)
			(xy 67.76231 -11.675001) (xy 67.835921 -11.711656) (xy 67.905835 -11.754947) (xy 67.971457 -11.804505)
			(xy 68.032226 -11.859906) (xy 68.087623 -11.920677) (xy 68.137178 -11.986301) (xy 68.180465 -12.056218)
			(xy 68.217117 -12.12983) (xy 68.24682 -12.20651) (xy 68.269321 -12.285604) (xy 68.284429 -12.366436)
			(xy 68.292013 -12.448318) (xy 68.292472 -12.489434) (xy 68.291907 -12.533047) (xy 68.283357 -12.619854)
			(xy 68.266352 -12.705408) (xy 68.241056 -12.788886) (xy 68.207711 -12.869488) (xy 68.195659 -12.892068)
			(xy 70.948547 -12.892068) (xy 70.948547 -12.837532) (xy 70.956309 -12.783551) (xy 70.971673 -12.731225)
			(xy 70.994328 -12.681617) (xy 71.023813 -12.635739) (xy 71.059526 -12.594524) (xy 71.100742 -12.558811)
			(xy 71.146621 -12.529327) (xy 71.196228 -12.506672) (xy 71.248555 -12.491308) (xy 71.302536 -12.483547)
			(xy 71.329804 -12.483084) (xy 72.193404 -12.483084) (xy 72.220676 -12.483479) (xy 72.274666 -12.491242)
			(xy 72.327001 -12.506609) (xy 72.376617 -12.529269) (xy 72.422503 -12.558758) (xy 72.463725 -12.594478)
			(xy 72.499444 -12.6357) (xy 72.528933 -12.681586) (xy 72.551592 -12.731202) (xy 72.566959 -12.783538)
			(xy 72.574721 -12.837528) (xy 72.574721 -12.892072) (xy 72.566959 -12.946062) (xy 72.551592 -12.998398)
			(xy 72.528933 -13.048014) (xy 72.499444 -13.0939) (xy 72.488173 -13.106908) (xy 191.037972 -13.106908)
			(xy 191.03849 -13.065179) (xy 191.046314 -12.98209) (xy 191.061883 -12.900098) (xy 191.085062 -12.819924)
			(xy 191.115646 -12.742273) (xy 191.153367 -12.667827) (xy 191.197893 -12.59724) (xy 191.248833 -12.531132)
			(xy 191.305739 -12.470085) (xy 191.368112 -12.414635) (xy 191.435403 -12.365269) (xy 191.507021 -12.32242)
			(xy 191.582336 -12.286466) (xy 191.660687 -12.257723) (xy 191.700912 -12.24661) (xy 191.713612 -12.243308)
			(xy 191.732408 -12.225274) (xy 191.765936 -12.117578) (xy 191.760348 -12.091924) (xy 191.751712 -12.082018)
			(xy 191.723476 -12.048682) (xy 191.672486 -11.977736) (xy 191.628113 -11.902474) (xy 191.590718 -11.823512)
			(xy 191.560607 -11.741496) (xy 191.538028 -11.657095) (xy 191.523163 -11.571) (xy 191.516135 -11.483915)
			(xy 191.517001 -11.39655) (xy 191.525753 -11.309621) (xy 191.542322 -11.223837) (xy 191.56657 -11.139901)
			(xy 191.5983 -11.058497) (xy 191.637253 -10.980292) (xy 191.683109 -10.905925) (xy 191.735495 -10.836003)
			(xy 191.793982 -10.771099) (xy 191.858092 -10.711742) (xy 191.927301 -10.658417) (xy 192.001043 -10.611562)
			(xy 192.078715 -10.571558) (xy 192.159684 -10.538733) (xy 192.243285 -10.513355) (xy 192.328838 -10.495631)
			(xy 192.415641 -10.485707) (xy 192.502986 -10.483662) (xy 192.590159 -10.489515) (xy 192.676446 -10.503218)
			(xy 192.761144 -10.524657) (xy 192.843559 -10.553659) (xy 192.923018 -10.589985) (xy 192.998871 -10.63334)
			(xy 193.070499 -10.683368) (xy 193.137315 -10.739661) (xy 193.198774 -10.801758) (xy 193.254374 -10.869153)
			(xy 193.303659 -10.941294) (xy 193.346227 -11.017591) (xy 193.381731 -11.097421) (xy 193.409879 -11.180131)
			(xy 193.430442 -11.265046) (xy 193.443252 -11.35147) (xy 193.448204 -11.438699) (xy 193.445257 -11.526018)
			(xy 193.434436 -11.612714) (xy 193.415829 -11.698079) (xy 193.389589 -11.781414) (xy 193.355929 -11.862038)
			(xy 193.315124 -11.939293) (xy 193.267509 -12.012547) (xy 193.213473 -12.081201) (xy 193.153457 -12.144694)
			(xy 193.121026 -12.173966) (xy 193.112347 -12.182457) (xy 193.103466 -12.205016) (xy 193.104008 -12.217146)
			(xy 193.112136 -12.298934) (xy 193.113935 -12.310868) (xy 193.126948 -12.331156) (xy 193.137028 -12.337796)
			(xy 193.137282 -12.33805) (xy 193.173525 -12.359702) (xy 193.242152 -12.408882) (xy 193.305811 -12.464344)
			(xy 193.363928 -12.525589) (xy 193.415979 -12.592065) (xy 193.461498 -12.663174) (xy 193.500073 -12.738277)
			(xy 193.531358 -12.816697) (xy 193.555071 -12.897729) (xy 193.570999 -12.980643) (xy 193.578999 -13.064693)
			(xy 193.579496 -13.106908) (xy 193.579055 -13.148019) (xy 193.571467 -13.22989) (xy 193.556355 -13.310712)
			(xy 193.533849 -13.389794) (xy 193.504141 -13.466462) (xy 193.467484 -13.540061) (xy 193.424192 -13.609963)
			(xy 193.374634 -13.675571) (xy 193.319232 -13.736326) (xy 193.25846 -13.791709) (xy 193.192836 -13.841247)
			(xy 193.122921 -13.884518) (xy 193.049311 -13.921151) (xy 192.972634 -13.950836) (xy 192.893545 -13.973317)
			(xy 192.812719 -13.988404) (xy 192.730845 -13.995968) (xy 192.689734 -13.996416) (xy 192.643339 -13.99582)
			(xy 192.551051 -13.986179) (xy 192.460267 -13.966987) (xy 192.371973 -13.938452) (xy 192.329308 -13.920216)
			(xy 192.319366 -13.91641) (xy 192.298102 -13.91641) (xy 192.28816 -13.920216) (xy 192.245553 -13.938427)
			(xy 192.157387 -13.966948) (xy 192.066733 -13.986143) (xy 191.974574 -13.995806) (xy 191.928242 -13.996416)
			(xy 191.927734 -13.996416) (xy 191.886626 -13.995955) (xy 191.804762 -13.988373) (xy 191.723946 -13.973271)
			(xy 191.644867 -13.950778) (xy 191.568202 -13.921085) (xy 191.494602 -13.884445) (xy 191.424697 -13.841172)
			(xy 191.359082 -13.791634) (xy 191.298317 -13.736254) (xy 191.24292 -13.675504) (xy 191.193365 -13.609903)
			(xy 191.150073 -13.540009) (xy 191.113413 -13.46642) (xy 191.083699 -13.389762) (xy 191.061184 -13.31069)
			(xy 191.04606 -13.229878) (xy 191.038456 -13.148015) (xy 191.037972 -13.106908) (xy 72.488173 -13.106908)
			(xy 72.463725 -13.135122) (xy 72.422503 -13.170842) (xy 72.376617 -13.200331) (xy 72.327001 -13.222991)
			(xy 72.274666 -13.238358) (xy 72.220676 -13.246121) (xy 72.193404 -13.246608) (xy 71.329804 -13.246608)
			(xy 71.302536 -13.246053) (xy 71.248555 -13.238292) (xy 71.196228 -13.222928) (xy 71.146621 -13.200273)
			(xy 71.100742 -13.170789) (xy 71.059526 -13.135076) (xy 71.023813 -13.093861) (xy 70.994328 -13.047983)
			(xy 70.971673 -12.998375) (xy 70.956309 -12.946049) (xy 70.948547 -12.892068) (xy 68.195659 -12.892068)
			(xy 68.166638 -12.946439) (xy 68.118231 -13.019001) (xy 68.062955 -13.086478) (xy 68.00134 -13.14822)
			(xy 67.933978 -13.203636) (xy 67.861516 -13.252193) (xy 67.823334 -13.273278) (xy 67.814055 -13.278811)
			(xy 67.800889 -13.295908) (xy 67.797934 -13.306298) (xy 67.787525 -13.3474) (xy 67.759881 -13.427561)
			(xy 67.724737 -13.504728) (xy 67.682409 -13.578201) (xy 67.633283 -13.647314) (xy 67.577804 -13.711439)
			(xy 67.516475 -13.769995) (xy 67.449854 -13.82245) (xy 67.378544 -13.868328) (xy 67.303192 -13.907213)
			(xy 67.224482 -13.938753) (xy 67.143129 -13.96266) (xy 67.05987 -13.978719) (xy 66.975461 -13.986784)
			(xy 66.933064 -13.987272) (xy 66.894775 -13.986847) (xy 66.818481 -13.980245) (xy 66.743038 -13.967101)
			(xy 66.669007 -13.947513) (xy 66.632836 -13.934948) (xy 66.624399 -13.932297) (xy 66.606729 -13.932297)
			(xy 66.598292 -13.934948) (xy 66.56211 -13.947478) (xy 66.488079 -13.967055) (xy 66.41264 -13.980205)
			(xy 66.336352 -13.986834) (xy 66.298064 -13.987272) (xy 66.254269 -13.986733) (xy 66.167104 -13.978118)
			(xy 66.081208 -13.960975) (xy 65.997414 -13.93547) (xy 65.916534 -13.90185) (xy 65.877694 -13.881608)
			(xy 65.866228 -13.87619) (xy 65.8409 -13.87619) (xy 65.829434 -13.881608) (xy 65.790581 -13.901822)
			(xy 65.709699 -13.935433) (xy 65.625908 -13.96094) (xy 65.540018 -13.978094) (xy 65.452857 -13.986731)
			(xy 65.409064 -13.987272) (xy 65.365269 -13.986733) (xy 65.278104 -13.978118) (xy 65.192208 -13.960975)
			(xy 65.108414 -13.93547) (xy 65.027534 -13.90185) (xy 64.988694 -13.881608) (xy 64.977228 -13.87619)
			(xy 64.9519 -13.87619) (xy 64.940434 -13.881608) (xy 64.901581 -13.901822) (xy 64.820699 -13.935433)
			(xy 64.736908 -13.96094) (xy 64.651018 -13.978094) (xy 64.563857 -13.986731) (xy 64.520064 -13.987272)
			(xy 64.476269 -13.986733) (xy 64.389104 -13.978118) (xy 64.303208 -13.960975) (xy 64.219414 -13.93547)
			(xy 64.138534 -13.90185) (xy 64.099694 -13.881608) (xy 64.088228 -13.87619) (xy 64.0629 -13.87619)
			(xy 64.051434 -13.881608) (xy 64.012581 -13.901822) (xy 63.931699 -13.935433) (xy 63.847908 -13.96094)
			(xy 63.762018 -13.978094) (xy 63.674857 -13.986731) (xy 63.631064 -13.987272) (xy 63.588804 -13.98679)
			(xy 63.504665 -13.978779) (xy 63.421665 -13.962822) (xy 63.340553 -13.939064) (xy 63.26206 -13.907718)
			(xy 63.186895 -13.869068) (xy 63.115735 -13.823463) (xy 63.049222 -13.771312) (xy 62.987956 -13.713088)
			(xy 62.93249 -13.649314) (xy 62.883323 -13.580566) (xy 62.840899 -13.507464) (xy 62.805601 -13.430668)
			(xy 62.777747 -13.35087) (xy 62.757589 -13.268789) (xy 62.750954 -13.22705) (xy 62.748768 -13.216225)
			(xy 62.736658 -13.197787) (xy 62.727586 -13.19149) (xy 62.693115 -13.169417) (xy 62.628004 -13.119803)
			(xy 62.567725 -13.064419) (xy 62.512788 -13.003732) (xy 62.463657 -12.938255) (xy 62.420747 -12.868543)
			(xy 62.384422 -12.795185) (xy 62.354987 -12.7188) (xy 62.332693 -12.640034) (xy 62.317728 -12.559554)
			(xy 62.310218 -12.47804) (xy 62.309756 -12.43711) (xy 1.353372 -12.43711) (xy 1.303061 -12.461339)
			(xy 1.206466 -12.517108) (xy 1.114309 -12.579941) (xy 1.027105 -12.649484) (xy 0.945341 -12.72535)
			(xy 0.869476 -12.807114) (xy 0.801731 -12.892064) (xy 56.95347 -12.892064) (xy 56.95347 -12.837536)
			(xy 56.96123 -12.783562) (xy 56.976591 -12.731243) (xy 56.999242 -12.681641) (xy 57.02872 -12.635768)
			(xy 57.064426 -12.594556) (xy 57.105634 -12.558845) (xy 57.151504 -12.529362) (xy 57.201103 -12.506706)
			(xy 57.253421 -12.491339) (xy 57.307394 -12.483573) (xy 57.334658 -12.483084) (xy 58.198258 -12.483084)
			(xy 58.225534 -12.483453) (xy 58.279532 -12.491211) (xy 58.331876 -12.506575) (xy 58.381501 -12.529233)
			(xy 58.427395 -12.558723) (xy 58.468625 -12.594445) (xy 58.504351 -12.635671) (xy 58.533847 -12.681562)
			(xy 58.55651 -12.731184) (xy 58.57188 -12.783527) (xy 58.579644 -12.837524) (xy 58.579644 -12.892076)
			(xy 58.57188 -12.946073) (xy 58.55651 -12.998416) (xy 58.533847 -13.048037) (xy 58.504351 -13.093929)
			(xy 58.468625 -13.135155) (xy 58.427395 -13.170877) (xy 58.381501 -13.200367) (xy 58.331876 -13.223025)
			(xy 58.279532 -13.238389) (xy 58.225534 -13.246147) (xy 58.198258 -13.246608) (xy 57.334658 -13.246608)
			(xy 57.307394 -13.246027) (xy 57.253421 -13.238261) (xy 57.201103 -13.222894) (xy 57.151504 -13.200238)
			(xy 57.105634 -13.170755) (xy 57.064426 -13.135044) (xy 57.02872 -13.093832) (xy 56.999242 -13.047959)
			(xy 56.976591 -12.998357) (xy 56.96123 -12.946038) (xy 56.95347 -12.892064) (xy 0.801731 -12.892064)
			(xy 0.799933 -12.894318) (xy 0.737102 -12.986476) (xy 0.681333 -13.083072) (xy 0.632939 -13.183565)
			(xy 0.59219 -13.287393) (xy 0.559313 -13.393977) (xy 0.534494 -13.502719) (xy 0.517871 -13.613012)
			(xy 0.509536 -13.724239) (xy 0.509016 -13.780008) (xy 0.509016 -16.5207) (xy 76.28834 -16.5207) (xy 76.29237 -16.436094)
			(xy 76.304425 -16.352254) (xy 76.324394 -16.26994) (xy 76.352098 -16.189896) (xy 76.387284 -16.112849)
			(xy 76.429635 -16.039495) (xy 76.478768 -15.970499) (xy 76.534236 -15.906485) (xy 76.595538 -15.848035)
			(xy 76.662118 -15.795676) (xy 76.733375 -15.749883) (xy 76.808661 -15.711071) (xy 76.887296 -15.679591)
			(xy 76.968567 -15.655728) (xy 77.051738 -15.639698) (xy 77.136057 -15.631648) (xy 77.178408 -15.63116)
			(xy 77.178916 -15.63116) (xy 77.224101 -15.631724) (xy 77.314005 -15.640873) (xy 77.402518 -15.659097)
			(xy 77.488725 -15.686205) (xy 77.530452 -15.70355) (xy 77.539034 -15.706862) (xy 77.557395 -15.707764)
			(xy 77.566266 -15.705328) (xy 77.610936 -15.69133) (xy 77.702468 -15.671687) (xy 77.795557 -15.661772)
			(xy 77.842364 -15.661132) (xy 77.84338 -15.661132) (xy 77.885732 -15.661539) (xy 77.970052 -15.669589)
			(xy 78.053225 -15.685618) (xy 78.134498 -15.70948) (xy 78.213134 -15.74096) (xy 78.288422 -15.779772)
			(xy 78.35968 -15.825565) (xy 78.426262 -15.877924) (xy 78.487566 -15.936376) (xy 78.543035 -16.00039)
			(xy 78.592169 -16.069387) (xy 78.634521 -16.142742) (xy 78.669709 -16.219791) (xy 78.697413 -16.299835)
			(xy 78.717383 -16.382151) (xy 78.722326 -16.416528) (xy 191.571372 -16.416528) (xy 191.571784 -16.378238)
			(xy 191.57839 -16.301944) (xy 191.591537 -16.226502) (xy 191.611129 -16.152471) (xy 191.623696 -16.1163)
			(xy 191.626331 -16.10786) (xy 191.62634 -16.090193) (xy 191.623696 -16.081756) (xy 191.611158 -16.045577)
			(xy 191.591583 -15.971544) (xy 191.578434 -15.896105) (xy 191.571809 -15.819816) (xy 191.571372 -15.781528)
			(xy 191.571879 -15.740418) (xy 191.579464 -15.65855) (xy 191.594572 -15.577731) (xy 191.617074 -15.498651)
			(xy 191.646778 -15.421985) (xy 191.68343 -15.348387) (xy 191.726718 -15.278486) (xy 191.776272 -15.212878)
			(xy 191.831669 -15.152124) (xy 191.892437 -15.096741) (xy 191.958056 -15.047202) (xy 192.027967 -15.00393)
			(xy 192.101573 -14.967295) (xy 192.178246 -14.937609) (xy 192.257331 -14.915125) (xy 192.338154 -14.900036)
			(xy 192.420024 -14.89247) (xy 192.461134 -14.89202) (xy 192.499451 -14.892376) (xy 192.575804 -14.898912)
			(xy 192.651311 -14.912) (xy 192.72541 -14.931543) (xy 192.761616 -14.94409) (xy 192.769932 -14.946676)
			(xy 192.787336 -14.946676) (xy 192.795652 -14.94409) (xy 192.831863 -14.931562) (xy 192.905965 -14.912041)
			(xy 192.981469 -14.898959) (xy 193.057819 -14.892413) (xy 193.096134 -14.89202) (xy 193.134451 -14.892376)
			(xy 193.210804 -14.898912) (xy 193.286311 -14.912) (xy 193.36041 -14.931543) (xy 193.396616 -14.94409)
			(xy 193.404932 -14.946676) (xy 193.422336 -14.946676) (xy 193.430652 -14.94409) (xy 193.466772 -14.93159)
			(xy 193.540685 -14.912102) (xy 193.615997 -14.899021) (xy 193.692153 -14.892442) (xy 193.730372 -14.89202)
			(xy 193.731134 -14.89202) (xy 193.772241 -14.89248) (xy 193.854104 -14.900067) (xy 193.934917 -14.915174)
			(xy 194.013993 -14.937671) (xy 194.090656 -14.967367) (xy 194.164253 -15.004008) (xy 194.234156 -15.047282)
			(xy 194.299769 -15.09682) (xy 194.360532 -15.152199) (xy 194.415928 -15.212948) (xy 194.465484 -15.278547)
			(xy 194.508776 -15.348439) (xy 194.545437 -15.422026) (xy 194.575153 -15.498681) (xy 194.597672 -15.577751)
			(xy 194.6128 -15.658561) (xy 194.620409 -15.740421) (xy 194.620896 -15.781528) (xy 194.620451 -15.819809)
			(xy 194.613795 -15.896082) (xy 194.600605 -15.971499) (xy 194.591178 -16.008604) (xy 194.588893 -16.019174)
			(xy 194.592456 -16.040487) (xy 194.598036 -16.049752) (xy 194.621836 -16.08633) (xy 194.662956 -16.163308)
			(xy 194.696348 -16.24394) (xy 194.721691 -16.327453) (xy 194.738741 -16.413043) (xy 194.747336 -16.499892)
			(xy 194.747896 -16.543528) (xy 194.747474 -16.584639) (xy 194.739884 -16.666511) (xy 194.72477 -16.747333)
			(xy 194.702263 -16.826416) (xy 194.672553 -16.903083) (xy 194.635895 -16.976682) (xy 194.592602 -17.046584)
			(xy 194.543042 -17.112192) (xy 194.487639 -17.172947) (xy 194.426866 -17.22833) (xy 194.361241 -17.277868)
			(xy 194.291325 -17.321138) (xy 194.217714 -17.357772) (xy 194.141037 -17.387456) (xy 194.061947 -17.409938)
			(xy 193.98112 -17.425024) (xy 193.899246 -17.432588) (xy 193.858134 -17.433036) (xy 193.814503 -17.432505)
			(xy 193.727659 -17.42397) (xy 193.642069 -17.40697) (xy 193.558556 -17.381667) (xy 193.477923 -17.348306)
			(xy 193.400945 -17.307207) (xy 193.364358 -17.28343) (xy 193.355108 -17.277824) (xy 193.333785 -17.274289)
			(xy 193.32321 -17.276572) (xy 193.286097 -17.285942) (xy 193.210677 -17.299046) (xy 193.134409 -17.305624)
			(xy 193.096134 -17.306036) (xy 193.057818 -17.305656) (xy 192.981465 -17.299127) (xy 192.905958 -17.286046)
			(xy 192.831859 -17.26651) (xy 192.795652 -17.253966) (xy 192.787336 -17.25138) (xy 192.769932 -17.25138)
			(xy 192.761616 -17.253966) (xy 192.725489 -17.266445) (xy 192.651578 -17.285939) (xy 192.576269 -17.299026)
			(xy 192.500115 -17.305611) (xy 192.461896 -17.306036) (xy 192.461134 -17.306036) (xy 192.420027 -17.305555)
			(xy 192.338163 -17.297973) (xy 192.257348 -17.282872) (xy 192.178271 -17.260379) (xy 192.101606 -17.230687)
			(xy 192.028008 -17.194048) (xy 191.958103 -17.150776) (xy 191.892489 -17.10124) (xy 191.831724 -17.045861)
			(xy 191.776328 -16.985113) (xy 191.726772 -16.919513) (xy 191.683479 -16.849621) (xy 191.646819 -16.776033)
			(xy 191.617104 -16.699377) (xy 191.594588 -16.620307) (xy 191.579463 -16.539496) (xy 191.571857 -16.457635)
			(xy 191.571372 -16.416528) (xy 78.722326 -16.416528) (xy 78.729438 -16.465992) (xy 78.733468 -16.5506)
			(xy 78.729438 -16.635208) (xy 78.717383 -16.719049) (xy 78.697413 -16.801365) (xy 78.669709 -16.881409)
			(xy 78.634521 -16.958458) (xy 78.592169 -17.031813) (xy 78.543035 -17.10081) (xy 78.487566 -17.164824)
			(xy 78.426262 -17.223276) (xy 78.35968 -17.275635) (xy 78.288422 -17.321428) (xy 78.213134 -17.36024)
			(xy 78.134498 -17.39172) (xy 78.053225 -17.415582) (xy 77.970052 -17.431611) (xy 77.885732 -17.439661)
			(xy 77.84338 -17.440148) (xy 77.842872 -17.440148) (xy 77.797687 -17.439588) (xy 77.707782 -17.430437)
			(xy 77.61927 -17.412213) (xy 77.533063 -17.385103) (xy 77.491336 -17.367758) (xy 77.482756 -17.36444)
			(xy 77.464393 -17.363542) (xy 77.455522 -17.36598) (xy 77.410853 -17.379982) (xy 77.319321 -17.399623)
			(xy 77.226231 -17.409537) (xy 77.179424 -17.410176) (xy 77.178408 -17.410176) (xy 77.136057 -17.409752)
			(xy 77.051738 -17.401702) (xy 76.968567 -17.385672) (xy 76.887296 -17.361809) (xy 76.808661 -17.330329)
			(xy 76.733375 -17.291517) (xy 76.662118 -17.245724) (xy 76.595538 -17.193365) (xy 76.534236 -17.134915)
			(xy 76.478768 -17.070901) (xy 76.429635 -17.001905) (xy 76.387284 -16.928551) (xy 76.352098 -16.851504)
			(xy 76.324394 -16.77146) (xy 76.304425 -16.689146) (xy 76.29237 -16.605306) (xy 76.28834 -16.5207)
			(xy 0.509016 -16.5207) (xy 0.509016 -17.639611) (xy 15.152858 -17.639611) (xy 15.152858 -17.585109)
			(xy 15.160614 -17.531161) (xy 15.175969 -17.478867) (xy 15.19861 -17.42929) (xy 15.228076 -17.383439)
			(xy 15.263768 -17.342249) (xy 15.304958 -17.306558) (xy 15.350808 -17.277091) (xy 15.400385 -17.25445)
			(xy 15.452679 -17.239095) (xy 15.506627 -17.231338) (xy 15.533878 -17.230852) (xy 16.397478 -17.230852)
			(xy 16.424731 -17.231315) (xy 16.478682 -17.239072) (xy 16.53098 -17.254428) (xy 16.580561 -17.27707)
			(xy 16.626414 -17.306538) (xy 16.667607 -17.342232) (xy 16.703301 -17.383424) (xy 16.732769 -17.429278)
			(xy 16.755412 -17.478858) (xy 16.770768 -17.531156) (xy 16.778525 -17.585107) (xy 16.778525 -17.639611)
			(xy 20.740858 -17.639611) (xy 20.740858 -17.585109) (xy 20.748614 -17.531161) (xy 20.763969 -17.478867)
			(xy 20.78661 -17.42929) (xy 20.816076 -17.383439) (xy 20.851768 -17.342249) (xy 20.892958 -17.306558)
			(xy 20.938808 -17.277091) (xy 20.988385 -17.25445) (xy 21.040679 -17.239095) (xy 21.094627 -17.231338)
			(xy 21.121878 -17.230852) (xy 21.985478 -17.230852) (xy 22.012729 -17.231394) (xy 22.066677 -17.239147)
			(xy 22.118972 -17.2545) (xy 22.168549 -17.277139) (xy 22.2144 -17.306603) (xy 22.255591 -17.342293)
			(xy 22.291284 -17.383482) (xy 22.320751 -17.429331) (xy 22.343392 -17.478908) (xy 22.358748 -17.531202)
			(xy 22.366505 -17.585149) (xy 22.366505 -17.639651) (xy 22.366505 -17.639653) (xy 26.328838 -17.639653)
			(xy 26.328838 -17.585147) (xy 26.336595 -17.531195) (xy 26.35195 -17.478897) (xy 26.374592 -17.429316)
			(xy 26.404059 -17.383462) (xy 26.439752 -17.342268) (xy 26.480944 -17.306573) (xy 26.526797 -17.277103)
			(xy 26.576376 -17.254458) (xy 26.628674 -17.239099) (xy 26.682625 -17.231339) (xy 26.709878 -17.230852)
			(xy 27.573478 -17.230852) (xy 27.600729 -17.231394) (xy 27.654677 -17.239147) (xy 27.706972 -17.2545)
			(xy 27.756549 -17.277139) (xy 27.8024 -17.306603) (xy 27.843591 -17.342293) (xy 27.879284 -17.383482)
			(xy 27.908751 -17.429331) (xy 27.931392 -17.478908) (xy 27.946748 -17.531202) (xy 27.954505 -17.585149)
			(xy 27.954505 -17.639651) (xy 27.954402 -17.640366) (xy 31.915646 -17.640366) (xy 31.915646 -17.585834)
			(xy 31.923406 -17.531857) (xy 31.938769 -17.479533) (xy 31.961421 -17.429928) (xy 31.990902 -17.384052)
			(xy 32.026611 -17.342838) (xy 32.067822 -17.307125) (xy 32.113695 -17.277639) (xy 32.163298 -17.254982)
			(xy 32.21562 -17.239615) (xy 32.269596 -17.231849) (xy 32.296862 -17.23136) (xy 33.160462 -17.23136)
			(xy 33.187736 -17.231777) (xy 33.24173 -17.239535) (xy 33.294071 -17.254899) (xy 33.343691 -17.277556)
			(xy 33.389583 -17.307044) (xy 33.43081 -17.342764) (xy 33.466533 -17.383987) (xy 33.496026 -17.429875)
			(xy 33.518688 -17.479494) (xy 33.534057 -17.531832) (xy 33.54182 -17.585826) (xy 33.54182 -17.640366)
			(xy 37.503646 -17.640366) (xy 37.503646 -17.585834) (xy 37.511406 -17.531857) (xy 37.526769 -17.479533)
			(xy 37.549421 -17.429928) (xy 37.578902 -17.384052) (xy 37.614611 -17.342838) (xy 37.655822 -17.307125)
			(xy 37.701695 -17.277639) (xy 37.751298 -17.254982) (xy 37.80362 -17.239615) (xy 37.857596 -17.231849)
			(xy 37.884862 -17.23136) (xy 38.748462 -17.23136) (xy 38.775736 -17.231777) (xy 38.82973 -17.239535)
			(xy 38.882071 -17.254899) (xy 38.931691 -17.277556) (xy 38.977583 -17.307044) (xy 39.01881 -17.342764)
			(xy 39.054533 -17.383987) (xy 39.084026 -17.429875) (xy 39.106688 -17.479494) (xy 39.122057 -17.531832)
			(xy 39.12982 -17.585826) (xy 39.12982 -17.639654) (xy 43.398638 -17.639654) (xy 43.398638 -17.585146)
			(xy 43.406395 -17.531193) (xy 43.421751 -17.478894) (xy 43.444395 -17.429312) (xy 43.473863 -17.383457)
			(xy 43.509558 -17.342262) (xy 43.550752 -17.306567) (xy 43.596606 -17.277097) (xy 43.646188 -17.254454)
			(xy 43.698487 -17.239096) (xy 43.75244 -17.231338) (xy 43.779694 -17.230852) (xy 44.643294 -17.230852)
			(xy 44.670544 -17.231395) (xy 44.72449 -17.23915) (xy 44.776783 -17.254504) (xy 44.826359 -17.277144)
			(xy 44.872208 -17.306609) (xy 44.913397 -17.342299) (xy 44.949088 -17.383487) (xy 44.978553 -17.429336)
			(xy 45.001194 -17.478911) (xy 45.016548 -17.531204) (xy 45.024305 -17.58515) (xy 45.024305 -17.63965)
			(xy 45.024304 -17.639654) (xy 48.986638 -17.639654) (xy 48.986638 -17.585146) (xy 48.994395 -17.531193)
			(xy 49.009751 -17.478894) (xy 49.032395 -17.429312) (xy 49.061863 -17.383457) (xy 49.097558 -17.342262)
			(xy 49.138752 -17.306567) (xy 49.184606 -17.277097) (xy 49.234188 -17.254454) (xy 49.286487 -17.239096)
			(xy 49.34044 -17.231338) (xy 49.367694 -17.230852) (xy 50.231294 -17.230852) (xy 50.258544 -17.231395)
			(xy 50.31249 -17.23915) (xy 50.364783 -17.254504) (xy 50.414359 -17.277144) (xy 50.460208 -17.306609)
			(xy 50.501397 -17.342299) (xy 50.537088 -17.383487) (xy 50.566553 -17.429336) (xy 50.589194 -17.478911)
			(xy 50.604548 -17.531204) (xy 50.612305 -17.58515) (xy 50.612305 -17.63965) (xy 50.612201 -17.64037)
			(xy 54.607423 -17.64037) (xy 54.607423 -17.58583) (xy 54.615186 -17.531845) (xy 54.630552 -17.479514)
			(xy 54.653209 -17.429903) (xy 54.682696 -17.384021) (xy 54.718413 -17.342803) (xy 54.759632 -17.307088)
			(xy 54.805515 -17.277602) (xy 54.855127 -17.254947) (xy 54.907459 -17.239583) (xy 54.961444 -17.231822)
			(xy 54.988714 -17.23136) (xy 55.852314 -17.23136) (xy 55.879584 -17.231803) (xy 55.933569 -17.239567)
			(xy 55.9859 -17.254935) (xy 56.035512 -17.277593) (xy 56.081393 -17.307081) (xy 56.122612 -17.342798)
			(xy 56.158328 -17.384018) (xy 56.187814 -17.429901) (xy 56.21047 -17.479513) (xy 56.225836 -17.531844)
			(xy 56.233598 -17.58583) (xy 56.233598 -17.64037) (xy 56.225836 -17.694356) (xy 56.21047 -17.746687)
			(xy 56.187814 -17.796299) (xy 56.158328 -17.842182) (xy 56.122612 -17.883402) (xy 56.081393 -17.919119)
			(xy 56.035512 -17.948607) (xy 55.9859 -17.971265) (xy 55.933569 -17.986633) (xy 55.879584 -17.994397)
			(xy 55.852314 -17.994884) (xy 54.988714 -17.994884) (xy 54.961444 -17.994378) (xy 54.907459 -17.986617)
			(xy 54.855127 -17.971253) (xy 54.805515 -17.948598) (xy 54.759632 -17.919112) (xy 54.718413 -17.883397)
			(xy 54.682696 -17.842179) (xy 54.653209 -17.796297) (xy 54.630552 -17.746686) (xy 54.615186 -17.694355)
			(xy 54.607423 -17.64037) (xy 50.612201 -17.64037) (xy 50.604548 -17.693596) (xy 50.589194 -17.745889)
			(xy 50.566553 -17.795464) (xy 50.537088 -17.841313) (xy 50.501397 -17.882501) (xy 50.460208 -17.918191)
			(xy 50.414359 -17.947656) (xy 50.364783 -17.970296) (xy 50.31249 -17.98565) (xy 50.258544 -17.993405)
			(xy 50.231294 -17.993868) (xy 49.367694 -17.993868) (xy 49.34044 -17.993462) (xy 49.286487 -17.985704)
			(xy 49.234188 -17.970346) (xy 49.184606 -17.947703) (xy 49.138752 -17.918233) (xy 49.097558 -17.882538)
			(xy 49.061863 -17.841343) (xy 49.032395 -17.795488) (xy 49.009751 -17.745906) (xy 48.994395 -17.693607)
			(xy 48.986638 -17.639654) (xy 45.024304 -17.639654) (xy 45.016548 -17.693596) (xy 45.001194 -17.745889)
			(xy 44.978553 -17.795464) (xy 44.949088 -17.841313) (xy 44.913397 -17.882501) (xy 44.872208 -17.918191)
			(xy 44.826359 -17.947656) (xy 44.776783 -17.970296) (xy 44.72449 -17.98565) (xy 44.670544 -17.993405)
			(xy 44.643294 -17.993868) (xy 43.779694 -17.993868) (xy 43.75244 -17.993462) (xy 43.698487 -17.985704)
			(xy 43.646188 -17.970346) (xy 43.596606 -17.947703) (xy 43.550752 -17.918233) (xy 43.509558 -17.882538)
			(xy 43.473863 -17.841343) (xy 43.444395 -17.795488) (xy 43.421751 -17.745906) (xy 43.406395 -17.693607)
			(xy 43.398638 -17.639654) (xy 39.12982 -17.639654) (xy 39.12982 -17.640374) (xy 39.122057 -17.694368)
			(xy 39.106688 -17.746706) (xy 39.084026 -17.796325) (xy 39.054533 -17.842213) (xy 39.01881 -17.883436)
			(xy 38.977583 -17.919156) (xy 38.931691 -17.948644) (xy 38.882071 -17.971301) (xy 38.82973 -17.986665)
			(xy 38.775736 -17.994423) (xy 38.748462 -17.994884) (xy 37.884862 -17.994884) (xy 37.857596 -17.994351)
			(xy 37.80362 -17.986585) (xy 37.751298 -17.971218) (xy 37.701695 -17.948561) (xy 37.655822 -17.919075)
			(xy 37.614611 -17.883362) (xy 37.578902 -17.842148) (xy 37.549421 -17.796272) (xy 37.526769 -17.746667)
			(xy 37.511406 -17.694343) (xy 37.503646 -17.640366) (xy 33.54182 -17.640366) (xy 33.54182 -17.640374)
			(xy 33.534057 -17.694368) (xy 33.518688 -17.746706) (xy 33.496026 -17.796325) (xy 33.466533 -17.842213)
			(xy 33.43081 -17.883436) (xy 33.389583 -17.919156) (xy 33.343691 -17.948644) (xy 33.294071 -17.971301)
			(xy 33.24173 -17.986665) (xy 33.187736 -17.994423) (xy 33.160462 -17.994884) (xy 32.296862 -17.994884)
			(xy 32.269596 -17.994351) (xy 32.21562 -17.986585) (xy 32.163298 -17.971218) (xy 32.113695 -17.948561)
			(xy 32.067822 -17.919075) (xy 32.026611 -17.883362) (xy 31.990902 -17.842148) (xy 31.961421 -17.796272)
			(xy 31.938769 -17.746667) (xy 31.923406 -17.694343) (xy 31.915646 -17.640366) (xy 27.954402 -17.640366)
			(xy 27.946748 -17.693598) (xy 27.931392 -17.745892) (xy 27.908751 -17.795469) (xy 27.879284 -17.841318)
			(xy 27.843591 -17.882507) (xy 27.8024 -17.918197) (xy 27.756549 -17.947661) (xy 27.706972 -17.9703)
			(xy 27.654677 -17.985653) (xy 27.600729 -17.993406) (xy 27.573478 -17.993868) (xy 26.709878 -17.993868)
			(xy 26.682625 -17.993461) (xy 26.628674 -17.985701) (xy 26.576376 -17.970342) (xy 26.526797 -17.947697)
			(xy 26.480944 -17.918227) (xy 26.439752 -17.882532) (xy 26.404059 -17.841338) (xy 26.374592 -17.795484)
			(xy 26.35195 -17.745903) (xy 26.336595 -17.693605) (xy 26.328838 -17.639653) (xy 22.366505 -17.639653)
			(xy 22.358748 -17.693598) (xy 22.343392 -17.745892) (xy 22.320751 -17.795469) (xy 22.291284 -17.841318)
			(xy 22.255591 -17.882507) (xy 22.2144 -17.918197) (xy 22.168549 -17.947661) (xy 22.118972 -17.9703)
			(xy 22.066677 -17.985653) (xy 22.012729 -17.993406) (xy 21.985478 -17.993868) (xy 21.121878 -17.993868)
			(xy 21.094627 -17.993382) (xy 21.040679 -17.985625) (xy 20.988385 -17.97027) (xy 20.938808 -17.947629)
			(xy 20.892958 -17.918162) (xy 20.851768 -17.882471) (xy 20.816076 -17.841281) (xy 20.78661 -17.79543)
			(xy 20.763969 -17.745853) (xy 20.748614 -17.693559) (xy 20.740858 -17.639611) (xy 16.778525 -17.639611)
			(xy 16.778525 -17.639613) (xy 16.770768 -17.693564) (xy 16.755412 -17.745862) (xy 16.732769 -17.795442)
			(xy 16.703301 -17.841296) (xy 16.667607 -17.882488) (xy 16.626414 -17.918182) (xy 16.580561 -17.94765)
			(xy 16.53098 -17.970292) (xy 16.478682 -17.985648) (xy 16.424731 -17.993405) (xy 16.397478 -17.993868)
			(xy 15.533878 -17.993868) (xy 15.506627 -17.993382) (xy 15.452679 -17.985625) (xy 15.400385 -17.97027)
			(xy 15.350808 -17.947629) (xy 15.304958 -17.918162) (xy 15.263768 -17.882471) (xy 15.228076 -17.841281)
			(xy 15.19861 -17.79543) (xy 15.175969 -17.745853) (xy 15.160614 -17.693559) (xy 15.152858 -17.639611)
			(xy 0.509016 -17.639611) (xy 0.509016 -19.164391) (xy 17.945563 -19.164391) (xy 17.945563 -19.109849)
			(xy 17.953326 -19.055862) (xy 17.968692 -19.00353) (xy 17.99135 -18.953917) (xy 18.020837 -18.908033)
			(xy 18.056555 -18.866813) (xy 18.097775 -18.831096) (xy 18.143658 -18.801609) (xy 18.193272 -18.778951)
			(xy 18.245604 -18.763585) (xy 18.299591 -18.755823) (xy 18.326862 -18.75536) (xy 19.190462 -18.75536)
			(xy 19.217731 -18.755843) (xy 19.271715 -18.763605) (xy 19.324045 -18.77897) (xy 19.373655 -18.801627)
			(xy 19.419536 -18.831113) (xy 19.460753 -18.866828) (xy 19.496469 -18.908046) (xy 19.525954 -18.953927)
			(xy 19.548611 -19.003537) (xy 19.563976 -19.055867) (xy 19.571738 -19.109851) (xy 19.571738 -19.163653)
			(xy 23.534838 -19.163653) (xy 23.534838 -19.109147) (xy 23.542595 -19.055195) (xy 23.55795 -19.002897)
			(xy 23.580592 -18.953316) (xy 23.610059 -18.907462) (xy 23.645752 -18.866268) (xy 23.686944 -18.830573)
			(xy 23.732797 -18.801103) (xy 23.782376 -18.778458) (xy 23.834674 -18.763099) (xy 23.888625 -18.755339)
			(xy 23.915878 -18.754852) (xy 24.779478 -18.754852) (xy 24.806729 -18.755394) (xy 24.860677 -18.763147)
			(xy 24.912972 -18.7785) (xy 24.962549 -18.801139) (xy 25.0084 -18.830603) (xy 25.049591 -18.866293)
			(xy 25.085284 -18.907482) (xy 25.114751 -18.953331) (xy 25.137392 -19.002908) (xy 25.152748 -19.055202)
			(xy 25.160505 -19.109149) (xy 25.160505 -19.163651) (xy 25.160505 -19.163653) (xy 29.122838 -19.163653)
			(xy 29.122838 -19.109147) (xy 29.130595 -19.055195) (xy 29.14595 -19.002897) (xy 29.168592 -18.953316)
			(xy 29.198059 -18.907462) (xy 29.233752 -18.866268) (xy 29.274944 -18.830573) (xy 29.320797 -18.801103)
			(xy 29.370376 -18.778458) (xy 29.422674 -18.763099) (xy 29.476625 -18.755339) (xy 29.503878 -18.754852)
			(xy 30.367478 -18.754852) (xy 30.394729 -18.755394) (xy 30.448677 -18.763147) (xy 30.500972 -18.7785)
			(xy 30.550549 -18.801139) (xy 30.5964 -18.830603) (xy 30.637591 -18.866293) (xy 30.673284 -18.907482)
			(xy 30.702751 -18.953331) (xy 30.725392 -19.002908) (xy 30.740748 -19.055202) (xy 30.748505 -19.109149)
			(xy 30.748505 -19.163651) (xy 30.748505 -19.163653) (xy 34.710838 -19.163653) (xy 34.710838 -19.109147)
			(xy 34.718595 -19.055195) (xy 34.73395 -19.002897) (xy 34.756592 -18.953316) (xy 34.786059 -18.907462)
			(xy 34.821752 -18.866268) (xy 34.862944 -18.830573) (xy 34.908797 -18.801103) (xy 34.958376 -18.778458)
			(xy 35.010674 -18.763099) (xy 35.064625 -18.755339) (xy 35.091878 -18.754852) (xy 35.955478 -18.754852)
			(xy 35.982729 -18.755394) (xy 36.036677 -18.763147) (xy 36.088972 -18.7785) (xy 36.138549 -18.801139)
			(xy 36.1844 -18.830603) (xy 36.225591 -18.866293) (xy 36.261284 -18.907482) (xy 36.290751 -18.953331)
			(xy 36.313392 -19.002908) (xy 36.328748 -19.055202) (xy 36.336505 -19.109149) (xy 36.336505 -19.163651)
			(xy 36.336505 -19.163654) (xy 40.604638 -19.163654) (xy 40.604638 -19.109146) (xy 40.612395 -19.055193)
			(xy 40.627751 -19.002894) (xy 40.650395 -18.953312) (xy 40.679863 -18.907457) (xy 40.715558 -18.866262)
			(xy 40.756752 -18.830567) (xy 40.802606 -18.801097) (xy 40.852188 -18.778454) (xy 40.904487 -18.763096)
			(xy 40.95844 -18.755338) (xy 40.985694 -18.754852) (xy 41.849294 -18.754852) (xy 41.876544 -18.755395)
			(xy 41.93049 -18.76315) (xy 41.982783 -18.778504) (xy 42.032359 -18.801144) (xy 42.078208 -18.830609)
			(xy 42.119397 -18.866299) (xy 42.155088 -18.907487) (xy 42.184553 -18.953336) (xy 42.207194 -19.002911)
			(xy 42.222548 -19.055204) (xy 42.230305 -19.10915) (xy 42.230305 -19.16365) (xy 42.230202 -19.164367)
			(xy 46.191446 -19.164367) (xy 46.191446 -19.109833) (xy 46.199207 -19.055855) (xy 46.21457 -19.00353)
			(xy 46.237224 -18.953924) (xy 46.266706 -18.908047) (xy 46.302417 -18.866832) (xy 46.343629 -18.831119)
			(xy 46.389505 -18.801634) (xy 46.439109 -18.778978) (xy 46.491433 -18.763612) (xy 46.545411 -18.755848)
			(xy 46.572678 -18.75536) (xy 47.436278 -18.75536) (xy 47.463552 -18.755778) (xy 47.517544 -18.763538)
			(xy 47.569882 -18.778903) (xy 47.619501 -18.801561) (xy 47.66539 -18.83105) (xy 47.706615 -18.866769)
			(xy 47.742337 -18.907992) (xy 47.771828 -18.95388) (xy 47.794489 -19.003497) (xy 47.809857 -19.055835)
			(xy 47.81762 -19.109826) (xy 47.81762 -19.163657) (xy 51.814615 -19.163657) (xy 51.814615 -19.109143)
			(xy 51.822374 -19.055184) (xy 51.837733 -19.002878) (xy 51.86038 -18.95329) (xy 51.889854 -18.907431)
			(xy 51.925554 -18.866233) (xy 51.966755 -18.830536) (xy 52.012617 -18.801065) (xy 52.062206 -18.778422)
			(xy 52.114513 -18.763067) (xy 52.168473 -18.755313) (xy 52.19573 -18.754852) (xy 53.05933 -18.754852)
			(xy 53.086577 -18.75542) (xy 53.140516 -18.763179) (xy 53.192801 -18.778535) (xy 53.24237 -18.801176)
			(xy 53.288211 -18.83064) (xy 53.329394 -18.866328) (xy 53.365078 -18.907513) (xy 53.394538 -18.953357)
			(xy 53.417175 -19.002927) (xy 53.432527 -19.055214) (xy 53.440282 -19.109153) (xy 53.440282 -19.163647)
			(xy 53.440281 -19.163657) (xy 57.402615 -19.163657) (xy 57.402615 -19.109143) (xy 57.410374 -19.055184)
			(xy 57.425733 -19.002878) (xy 57.44838 -18.95329) (xy 57.477854 -18.907431) (xy 57.513554 -18.866233)
			(xy 57.554755 -18.830536) (xy 57.600617 -18.801065) (xy 57.650206 -18.778422) (xy 57.702513 -18.763067)
			(xy 57.756473 -18.755313) (xy 57.78373 -18.754852) (xy 58.64733 -18.754852) (xy 58.674577 -18.75542)
			(xy 58.728516 -18.763179) (xy 58.780801 -18.778535) (xy 58.83037 -18.801176) (xy 58.876211 -18.83064)
			(xy 58.917394 -18.866328) (xy 58.953078 -18.907513) (xy 58.982538 -18.953357) (xy 59.005175 -19.002927)
			(xy 59.020527 -19.055214) (xy 59.028282 -19.109153) (xy 59.028282 -19.163647) (xy 59.020527 -19.217586)
			(xy 59.005175 -19.269873) (xy 58.982538 -19.319443) (xy 58.953078 -19.365287) (xy 58.917394 -19.406472)
			(xy 58.876211 -19.44216) (xy 58.83037 -19.471624) (xy 58.780801 -19.494265) (xy 58.728516 -19.509621)
			(xy 58.674577 -19.51738) (xy 58.64733 -19.517868) (xy 57.78373 -19.517868) (xy 57.756473 -19.517487)
			(xy 57.702513 -19.509733) (xy 57.650206 -19.494378) (xy 57.600617 -19.471735) (xy 57.554755 -19.442264)
			(xy 57.513554 -19.406567) (xy 57.477854 -19.365369) (xy 57.44838 -19.31951) (xy 57.425733 -19.269922)
			(xy 57.410374 -19.217616) (xy 57.402615 -19.163657) (xy 53.440281 -19.163657) (xy 53.432527 -19.217586)
			(xy 53.417175 -19.269873) (xy 53.394538 -19.319443) (xy 53.365078 -19.365287) (xy 53.329394 -19.406472)
			(xy 53.288211 -19.44216) (xy 53.24237 -19.471624) (xy 53.192801 -19.494265) (xy 53.140516 -19.509621)
			(xy 53.086577 -19.51738) (xy 53.05933 -19.517868) (xy 52.19573 -19.517868) (xy 52.168473 -19.517487)
			(xy 52.114513 -19.509733) (xy 52.062206 -19.494378) (xy 52.012617 -19.471735) (xy 51.966755 -19.442264)
			(xy 51.925554 -19.406567) (xy 51.889854 -19.365369) (xy 51.86038 -19.31951) (xy 51.837733 -19.269922)
			(xy 51.822374 -19.217616) (xy 51.814615 -19.163657) (xy 47.81762 -19.163657) (xy 47.81762 -19.164374)
			(xy 47.809857 -19.218365) (xy 47.794489 -19.270703) (xy 47.771828 -19.32032) (xy 47.742337 -19.366208)
			(xy 47.706615 -19.407431) (xy 47.66539 -19.44315) (xy 47.619501 -19.472639) (xy 47.569882 -19.495297)
			(xy 47.517544 -19.510662) (xy 47.463552 -19.518422) (xy 47.436278 -19.518884) (xy 46.572678 -19.518884)
			(xy 46.545411 -19.518352) (xy 46.491433 -19.510588) (xy 46.439109 -19.495222) (xy 46.389505 -19.472566)
			(xy 46.343629 -19.443081) (xy 46.302417 -19.407368) (xy 46.266706 -19.366153) (xy 46.237224 -19.320276)
			(xy 46.21457 -19.27067) (xy 46.199207 -19.218345) (xy 46.191446 -19.164367) (xy 42.230202 -19.164367)
			(xy 42.222548 -19.217596) (xy 42.207194 -19.269889) (xy 42.184553 -19.319464) (xy 42.155088 -19.365313)
			(xy 42.119397 -19.406501) (xy 42.078208 -19.442191) (xy 42.032359 -19.471656) (xy 41.982783 -19.494296)
			(xy 41.93049 -19.50965) (xy 41.876544 -19.517405) (xy 41.849294 -19.517868) (xy 40.985694 -19.517868)
			(xy 40.95844 -19.517462) (xy 40.904487 -19.509704) (xy 40.852188 -19.494346) (xy 40.802606 -19.471703)
			(xy 40.756752 -19.442233) (xy 40.715558 -19.406538) (xy 40.679863 -19.365343) (xy 40.650395 -19.319488)
			(xy 40.627751 -19.269906) (xy 40.612395 -19.217607) (xy 40.604638 -19.163654) (xy 36.336505 -19.163654)
			(xy 36.328748 -19.217598) (xy 36.313392 -19.269892) (xy 36.290751 -19.319469) (xy 36.261284 -19.365318)
			(xy 36.225591 -19.406507) (xy 36.1844 -19.442197) (xy 36.138549 -19.471661) (xy 36.088972 -19.4943)
			(xy 36.036677 -19.509653) (xy 35.982729 -19.517406) (xy 35.955478 -19.517868) (xy 35.091878 -19.517868)
			(xy 35.064625 -19.517461) (xy 35.010674 -19.509701) (xy 34.958376 -19.494342) (xy 34.908797 -19.471697)
			(xy 34.862944 -19.442227) (xy 34.821752 -19.406532) (xy 34.786059 -19.365338) (xy 34.756592 -19.319484)
			(xy 34.73395 -19.269903) (xy 34.718595 -19.217605) (xy 34.710838 -19.163653) (xy 30.748505 -19.163653)
			(xy 30.740748 -19.217598) (xy 30.725392 -19.269892) (xy 30.702751 -19.319469) (xy 30.673284 -19.365318)
			(xy 30.637591 -19.406507) (xy 30.5964 -19.442197) (xy 30.550549 -19.471661) (xy 30.500972 -19.4943)
			(xy 30.448677 -19.509653) (xy 30.394729 -19.517406) (xy 30.367478 -19.517868) (xy 29.503878 -19.517868)
			(xy 29.476625 -19.517461) (xy 29.422674 -19.509701) (xy 29.370376 -19.494342) (xy 29.320797 -19.471697)
			(xy 29.274944 -19.442227) (xy 29.233752 -19.406532) (xy 29.198059 -19.365338) (xy 29.168592 -19.319484)
			(xy 29.14595 -19.269903) (xy 29.130595 -19.217605) (xy 29.122838 -19.163653) (xy 25.160505 -19.163653)
			(xy 25.152748 -19.217598) (xy 25.137392 -19.269892) (xy 25.114751 -19.319469) (xy 25.085284 -19.365318)
			(xy 25.049591 -19.406507) (xy 25.0084 -19.442197) (xy 24.962549 -19.471661) (xy 24.912972 -19.4943)
			(xy 24.860677 -19.509653) (xy 24.806729 -19.517406) (xy 24.779478 -19.517868) (xy 23.915878 -19.517868)
			(xy 23.888625 -19.517461) (xy 23.834674 -19.509701) (xy 23.782376 -19.494342) (xy 23.732797 -19.471697)
			(xy 23.686944 -19.442227) (xy 23.645752 -19.406532) (xy 23.610059 -19.365338) (xy 23.580592 -19.319484)
			(xy 23.55795 -19.269903) (xy 23.542595 -19.217605) (xy 23.534838 -19.163653) (xy 19.571738 -19.163653)
			(xy 19.571738 -19.164389) (xy 19.563976 -19.218373) (xy 19.548611 -19.270703) (xy 19.525954 -19.320313)
			(xy 19.496469 -19.366194) (xy 19.460753 -19.407412) (xy 19.419536 -19.443127) (xy 19.373655 -19.472613)
			(xy 19.324045 -19.49527) (xy 19.271715 -19.510635) (xy 19.217731 -19.518397) (xy 19.190462 -19.518884)
			(xy 18.326862 -19.518884) (xy 18.299591 -19.518417) (xy 18.245604 -19.510655) (xy 18.193272 -19.495289)
			(xy 18.143658 -19.472631) (xy 18.097775 -19.443144) (xy 18.056555 -19.407427) (xy 18.020837 -19.366207)
			(xy 17.99135 -19.320323) (xy 17.968692 -19.27071) (xy 17.953326 -19.218378) (xy 17.945563 -19.164391)
			(xy 0.509016 -19.164391) (xy 0.509016 -20.327366) (xy 65.88506 -20.327366) (xy 65.885484 -20.289077)
			(xy 65.892086 -20.212783) (xy 65.90523 -20.13734) (xy 65.924819 -20.063309) (xy 65.937384 -20.027138)
			(xy 65.940051 -20.018705) (xy 65.94004 -20.001031) (xy 65.937384 -19.992594) (xy 65.924856 -19.956411)
			(xy 65.905279 -19.88238) (xy 65.892127 -19.806942) (xy 65.885498 -19.730654) (xy 65.88506 -19.692366)
			(xy 65.885582 -19.650174) (xy 65.893576 -19.56617) (xy 65.909488 -19.483301) (xy 65.933176 -19.402311)
			(xy 65.964427 -19.323927) (xy 66.00296 -19.248856) (xy 66.048429 -19.17777) (xy 66.074036 -19.144234)
			(xy 66.079883 -19.13601) (xy 66.085128 -19.116537) (xy 66.082515 -19.096539) (xy 66.077846 -19.087592)
			(xy 66.058798 -19.053767) (xy 66.026006 -18.983399) (xy 65.999468 -18.910441) (xy 65.979384 -18.83545)
			(xy 65.965909 -18.758994) (xy 65.959144 -18.681655) (xy 65.95872 -18.642838) (xy 65.95872 -18.642584)
			(xy 65.959137 -18.60148) (xy 65.966724 -18.519622) (xy 65.981831 -18.438814) (xy 66.00433 -18.359744)
			(xy 66.034029 -18.283087) (xy 66.070674 -18.209498) (xy 66.113953 -18.139604) (xy 66.163496 -18.074001)
			(xy 66.218881 -18.01325) (xy 66.279635 -17.957868) (xy 66.34524 -17.908328) (xy 66.415137 -17.865053)
			(xy 66.488728 -17.828411) (xy 66.565386 -17.798716) (xy 66.644456 -17.776221) (xy 66.725266 -17.761118)
			(xy 66.807124 -17.753535) (xy 66.848228 -17.753076) (xy 66.889911 -17.753577) (xy 66.972911 -17.761363)
			(xy 67.054819 -17.776882) (xy 67.134915 -17.799999) (xy 67.212496 -17.830511) (xy 67.286881 -17.868149)
			(xy 67.357417 -17.912584) (xy 67.423485 -17.963425) (xy 67.484504 -18.020226) (xy 67.53994 -18.082488)
			(xy 67.565016 -18.115788) (xy 67.56527 -18.116042) (xy 67.570757 -18.122776) (xy 67.585223 -18.132372)
			(xy 67.602063 -18.136587) (xy 67.610736 -18.136108) (xy 67.697858 -18.127726) (xy 67.706567 -18.126584)
			(xy 67.722478 -18.119178) (xy 67.734922 -18.1068) (xy 67.739006 -18.099024) (xy 67.739006 -18.098516)
			(xy 67.757258 -18.060702) (xy 67.799884 -17.988356) (xy 67.849141 -17.920351) (xy 67.90459 -17.857291)
			(xy 67.965736 -17.79974) (xy 68.032035 -17.748209) (xy 68.102897 -17.703158) (xy 68.17769 -17.664987)
			(xy 68.255748 -17.634037) (xy 68.336377 -17.610583) (xy 68.418857 -17.594835) (xy 68.502455 -17.586933)
			(xy 68.54444 -17.586452) (xy 68.5868 -17.58693) (xy 68.671136 -17.594986) (xy 68.754325 -17.611023)
			(xy 68.835612 -17.634895) (xy 68.914262 -17.666384) (xy 68.989563 -17.705208) (xy 69.060833 -17.751013)
			(xy 69.127426 -17.803385) (xy 69.18874 -17.86185) (xy 69.244218 -17.925878) (xy 69.293359 -17.99489)
			(xy 69.335718 -18.068261) (xy 69.370911 -18.145325) (xy 69.39862 -18.225386) (xy 69.401856 -18.238724)
			(xy 79.0321 -18.238724) (xy 79.032651 -18.193954) (xy 79.041664 -18.104869) (xy 79.059573 -18.017137)
			(xy 79.086195 -17.931647) (xy 79.10322 -17.890236) (xy 79.106772 -17.880641) (xy 79.106781 -17.860202)
			(xy 79.10322 -17.850612) (xy 79.086184 -17.809205) (xy 79.059551 -17.723717) (xy 79.041646 -17.635983)
			(xy 79.032653 -17.546895) (xy 79.0321 -17.502124) (xy 79.032604 -17.459763) (xy 79.040657 -17.375426)
			(xy 79.056691 -17.292236) (xy 79.080559 -17.210946) (xy 79.112047 -17.132294) (xy 79.150869 -17.056991)
			(xy 79.196672 -16.985719) (xy 79.249043 -16.919123) (xy 79.307508 -16.857808) (xy 79.371536 -16.802327)
			(xy 79.440548 -16.753184) (xy 79.513918 -16.710824) (xy 79.590983 -16.675629) (xy 79.671045 -16.64792)
			(xy 79.753378 -16.627946) (xy 79.837237 -16.615889) (xy 79.921862 -16.611858) (xy 80.006487 -16.615889)
			(xy 80.090346 -16.627946) (xy 80.172679 -16.64792) (xy 80.252741 -16.675629) (xy 80.329806 -16.710824)
			(xy 80.403176 -16.753184) (xy 80.472188 -16.802327) (xy 80.536216 -16.857808) (xy 80.594681 -16.919123)
			(xy 80.647052 -16.985719) (xy 80.692855 -17.056991) (xy 80.731677 -17.132294) (xy 80.763165 -17.210946)
			(xy 80.787033 -17.292236) (xy 80.803067 -17.375426) (xy 80.81112 -17.459763) (xy 80.811624 -17.502124)
			(xy 80.811054 -17.546893) (xy 80.802046 -17.635978) (xy 80.784143 -17.723709) (xy 80.757526 -17.809201)
			(xy 80.740504 -17.850612) (xy 80.736924 -17.860198) (xy 80.736933 -17.880645) (xy 80.740504 -17.890236)
			(xy 80.757551 -17.931638) (xy 80.784182 -18.017129) (xy 80.802084 -18.104863) (xy 80.808854 -18.171951)
			(xy 131.633699 -18.171951) (xy 131.633699 -18.117449) (xy 131.641456 -18.063503) (xy 131.656811 -18.011209)
			(xy 131.679453 -17.961633) (xy 131.708919 -17.915784) (xy 131.744611 -17.874596) (xy 131.785802 -17.838906)
			(xy 131.831653 -17.809442) (xy 131.88123 -17.786804) (xy 131.933524 -17.771451) (xy 131.987471 -17.763698)
			(xy 132.014722 -17.763236) (xy 132.878322 -17.763236) (xy 132.905575 -17.763635) (xy 132.959527 -17.771395)
			(xy 133.011825 -17.786754) (xy 133.061405 -17.809399) (xy 133.107258 -17.838869) (xy 133.148451 -17.874565)
			(xy 133.184144 -17.915759) (xy 133.213611 -17.961614) (xy 133.236254 -18.011196) (xy 133.251609 -18.063495)
			(xy 133.259366 -18.117447) (xy 133.259366 -18.171946) (xy 137.033822 -18.171946) (xy 137.033822 -18.117454)
			(xy 137.041577 -18.063516) (xy 137.056928 -18.01123) (xy 137.079564 -17.961661) (xy 137.109023 -17.915818)
			(xy 137.144706 -17.874633) (xy 137.185887 -17.838946) (xy 137.231728 -17.809482) (xy 137.281294 -17.786841)
			(xy 137.333578 -17.771485) (xy 137.387516 -17.763725) (xy 137.414762 -17.763236) (xy 138.278362 -17.763236)
			(xy 138.30562 -17.763608) (xy 138.359581 -17.771362) (xy 138.41189 -17.786716) (xy 138.46148 -17.809359)
			(xy 138.507344 -17.83883) (xy 138.548546 -17.874528) (xy 138.584247 -17.915726) (xy 138.613722 -17.961586)
			(xy 138.63637 -18.011175) (xy 138.65173 -18.063482) (xy 138.659489 -18.117442) (xy 138.659489 -18.17195)
			(xy 140.633699 -18.17195) (xy 140.633699 -18.11745) (xy 140.641455 -18.063505) (xy 140.65681 -18.011213)
			(xy 140.67945 -17.961638) (xy 140.708915 -17.91579) (xy 140.744605 -17.874602) (xy 140.785793 -17.838913)
			(xy 140.831642 -17.809448) (xy 140.881217 -17.786808) (xy 140.933509 -17.771455) (xy 140.987454 -17.763699)
			(xy 141.014704 -17.763236) (xy 141.878304 -17.763236) (xy 141.905558 -17.763634) (xy 141.959512 -17.771392)
			(xy 142.011812 -17.786749) (xy 142.061394 -17.809393) (xy 142.10725 -17.838863) (xy 142.148444 -17.874559)
			(xy 142.184139 -17.915754) (xy 142.213609 -17.961609) (xy 142.236252 -18.011192) (xy 142.251609 -18.063492)
			(xy 142.259366 -18.117446) (xy 142.259366 -18.171954) (xy 142.251609 -18.225908) (xy 142.236252 -18.278208)
			(xy 142.213609 -18.327791) (xy 142.184139 -18.373646) (xy 142.148444 -18.414841) (xy 142.10725 -18.450537)
			(xy 142.061394 -18.480007) (xy 142.011812 -18.502651) (xy 141.959512 -18.518008) (xy 141.905558 -18.525766)
			(xy 141.878304 -18.526252) (xy 141.014704 -18.526252) (xy 140.987454 -18.525701) (xy 140.933509 -18.517945)
			(xy 140.881217 -18.502592) (xy 140.831642 -18.479952) (xy 140.785793 -18.450487) (xy 140.744605 -18.414798)
			(xy 140.708915 -18.37361) (xy 140.67945 -18.327762) (xy 140.65681 -18.278187) (xy 140.641455 -18.225895)
			(xy 140.633699 -18.17195) (xy 138.659489 -18.17195) (xy 138.659489 -18.171958) (xy 138.65173 -18.225918)
			(xy 138.63637 -18.278225) (xy 138.613722 -18.327814) (xy 138.584247 -18.373674) (xy 138.548546 -18.414872)
			(xy 138.507344 -18.45057) (xy 138.46148 -18.480041) (xy 138.41189 -18.502684) (xy 138.359581 -18.518038)
			(xy 138.30562 -18.525792) (xy 138.278362 -18.526252) (xy 137.414762 -18.526252) (xy 137.387516 -18.525675)
			(xy 137.333578 -18.517915) (xy 137.281294 -18.502559) (xy 137.231728 -18.479918) (xy 137.185887 -18.450454)
			(xy 137.144706 -18.414767) (xy 137.109023 -18.373582) (xy 137.079564 -18.327739) (xy 137.056928 -18.27817)
			(xy 137.041577 -18.225884) (xy 137.033822 -18.171946) (xy 133.259366 -18.171946) (xy 133.259366 -18.171953)
			(xy 133.251609 -18.225905) (xy 133.236254 -18.278204) (xy 133.213611 -18.327786) (xy 133.184144 -18.373641)
			(xy 133.148451 -18.414835) (xy 133.107258 -18.450531) (xy 133.061405 -18.480001) (xy 133.011825 -18.502646)
			(xy 132.959527 -18.518005) (xy 132.905575 -18.525765) (xy 132.878322 -18.526252) (xy 132.014722 -18.526252)
			(xy 131.987471 -18.525702) (xy 131.933524 -18.517949) (xy 131.88123 -18.502596) (xy 131.831653 -18.479958)
			(xy 131.785802 -18.450494) (xy 131.744611 -18.414804) (xy 131.708919 -18.373616) (xy 131.679453 -18.327767)
			(xy 131.656811 -18.278191) (xy 131.641456 -18.225897) (xy 131.633699 -18.171951) (xy 80.808854 -18.171951)
			(xy 80.811074 -18.193953) (xy 80.811624 -18.238724) (xy 80.81112 -18.281085) (xy 80.803067 -18.365422)
			(xy 80.787033 -18.448612) (xy 80.763165 -18.529902) (xy 80.731677 -18.608554) (xy 80.692855 -18.683857)
			(xy 80.647052 -18.755129) (xy 80.594681 -18.821725) (xy 80.536216 -18.88304) (xy 80.472188 -18.938521)
			(xy 80.403176 -18.987664) (xy 80.329806 -19.030024) (xy 80.252741 -19.065219) (xy 80.172679 -19.092928)
			(xy 80.090346 -19.112902) (xy 80.006487 -19.124959) (xy 79.921862 -19.128991) (xy 79.837237 -19.124959)
			(xy 79.753378 -19.112902) (xy 79.671045 -19.092928) (xy 79.590983 -19.065219) (xy 79.513918 -19.030024)
			(xy 79.440548 -18.987664) (xy 79.371536 -18.938521) (xy 79.307508 -18.88304) (xy 79.249043 -18.821725)
			(xy 79.196672 -18.755129) (xy 79.150869 -18.683857) (xy 79.112047 -18.608554) (xy 79.080559 -18.529902)
			(xy 79.056691 -18.448612) (xy 79.040657 -18.365422) (xy 79.032604 -18.281085) (xy 79.0321 -18.238724)
			(xy 69.401856 -18.238724) (xy 69.418593 -18.307718) (xy 69.430649 -18.391576) (xy 69.434681 -18.4762)
			(xy 69.430649 -18.560824) (xy 69.418593 -18.644682) (xy 69.39862 -18.727014) (xy 69.370911 -18.807075)
			(xy 69.335718 -18.884139) (xy 69.293359 -18.95751) (xy 69.244218 -19.026522) (xy 69.18874 -19.09055)
			(xy 69.127426 -19.149015) (xy 69.060833 -19.201387) (xy 68.989563 -19.247192) (xy 68.914262 -19.286016)
			(xy 68.835612 -19.317505) (xy 68.754325 -19.341377) (xy 68.671136 -19.357414) (xy 68.5868 -19.36547)
			(xy 68.54444 -19.365976) (xy 68.502753 -19.365468) (xy 68.419745 -19.357644) (xy 68.337834 -19.342089)
			(xy 68.257737 -19.31894) (xy 68.180157 -19.288398) (xy 68.105774 -19.250734) (xy 68.035242 -19.206275)
			(xy 67.969177 -19.155414) (xy 67.90816 -19.098595) (xy 67.852727 -19.036317) (xy 67.827652 -19.00301)
			(xy 67.827398 -19.002756) (xy 67.821873 -18.996058) (xy 67.807425 -18.986454) (xy 67.790601 -18.982223)
			(xy 67.781932 -18.98269) (xy 67.69481 -18.991072) (xy 67.686098 -18.992195) (xy 67.670187 -18.999611)
			(xy 67.657745 -19.011995) (xy 67.653662 -19.019774) (xy 67.653662 -19.020282) (xy 67.63179 -19.065383)
			(xy 67.579339 -19.150805) (xy 67.549014 -19.190716) (xy 67.543272 -19.198996) (xy 67.538026 -19.218428)
			(xy 67.540615 -19.238388) (xy 67.545204 -19.247358) (xy 67.564269 -19.281203) (xy 67.597117 -19.351604)
			(xy 67.623706 -19.424598) (xy 67.643834 -19.499632) (xy 67.657349 -19.576134) (xy 67.664146 -19.653523)
			(xy 67.664584 -19.692366) (xy 67.664167 -19.730656) (xy 67.657563 -19.806949) (xy 67.644416 -19.882392)
			(xy 67.624826 -19.956423) (xy 67.61226 -19.992594) (xy 67.609626 -20.001035) (xy 67.609615 -20.018702)
			(xy 67.61226 -20.027138) (xy 67.624799 -20.063317) (xy 67.644373 -20.13735) (xy 67.653158 -20.187755)
			(xy 138.765443 -20.187755) (xy 138.765443 -20.133245) (xy 138.773201 -20.079289) (xy 138.788559 -20.026987)
			(xy 138.811205 -19.977403) (xy 138.840677 -19.931547) (xy 138.876376 -19.890352) (xy 138.917574 -19.854657)
			(xy 138.963433 -19.825189) (xy 139.013019 -19.802547) (xy 139.065322 -19.787194) (xy 139.119279 -19.779441)
			(xy 139.146534 -19.77898) (xy 140.137134 -19.77898) (xy 140.164383 -19.779493) (xy 140.218325 -19.787253)
			(xy 140.270614 -19.80261) (xy 140.320185 -19.825253) (xy 140.36603 -19.854719) (xy 140.407215 -19.890409)
			(xy 140.442901 -19.931597) (xy 140.449617 -19.942048) (xy 175.988472 -19.942048) (xy 175.988976 -19.899687)
			(xy 175.997029 -19.81535) (xy 176.013063 -19.73216) (xy 176.036931 -19.65087) (xy 176.068419 -19.572218)
			(xy 176.107241 -19.496915) (xy 176.153044 -19.425643) (xy 176.205415 -19.359047) (xy 176.26388 -19.297732)
			(xy 176.327908 -19.242251) (xy 176.39692 -19.193108) (xy 176.47029 -19.150748) (xy 176.547355 -19.115553)
			(xy 176.627417 -19.087844) (xy 176.70975 -19.06787) (xy 176.793609 -19.055813) (xy 176.878234 -19.051782)
			(xy 176.962859 -19.055813) (xy 177.046718 -19.06787) (xy 177.129051 -19.087844) (xy 177.209113 -19.115553)
			(xy 177.286178 -19.150748) (xy 177.359548 -19.193108) (xy 177.42856 -19.242251) (xy 177.492588 -19.297732)
			(xy 177.551053 -19.359047) (xy 177.603424 -19.425643) (xy 177.649227 -19.496915) (xy 177.688049 -19.572218)
			(xy 177.719537 -19.65087) (xy 177.743405 -19.73216) (xy 177.759439 -19.81535) (xy 177.767492 -19.899687)
			(xy 177.767996 -19.942048) (xy 177.767398 -19.98792) (xy 177.757891 -20.079169) (xy 177.739034 -20.168954)
			(xy 177.725578 -20.212812) (xy 177.722752 -20.223379) (xy 177.72523 -20.245087) (xy 177.730404 -20.254722)
			(xy 177.750836 -20.289402) (xy 177.786035 -20.361795) (xy 177.814552 -20.437071) (xy 177.836153 -20.514616)
			(xy 177.850661 -20.593794) (xy 177.857958 -20.67396) (xy 177.85842 -20.714208) (xy 177.85842 -20.715224)
			(xy 177.857839 -20.760561) (xy 177.84856 -20.850758) (xy 177.830152 -20.939544) (xy 177.817018 -20.98294)
			(xy 177.81462 -20.991841) (xy 177.815621 -21.010233) (xy 177.823067 -21.02708) (xy 177.835994 -21.040201)
			(xy 177.844196 -21.044408) (xy 177.8824 -21.062505) (xy 177.955518 -21.104946) (xy 178.024281 -21.15413)
			(xy 178.088069 -21.209614) (xy 178.146306 -21.270898) (xy 178.198469 -21.337429) (xy 178.244087 -21.408608)
			(xy 178.282748 -21.483792) (xy 178.314103 -21.562305) (xy 178.337871 -21.643437) (xy 178.353837 -21.726458)
			(xy 178.361856 -21.810619) (xy 178.362356 -21.85289) (xy 178.361892 -21.894005) (xy 178.354306 -21.975884)
			(xy 178.339197 -22.056714) (xy 178.316694 -22.135805) (xy 178.28699 -22.212482) (xy 178.250337 -22.286091)
			(xy 178.207049 -22.356005) (xy 178.157495 -22.421626) (xy 178.102097 -22.482394) (xy 178.041329 -22.537792)
			(xy 177.975708 -22.587347) (xy 177.905795 -22.630635) (xy 177.832186 -22.667288) (xy 177.755509 -22.696993)
			(xy 177.676418 -22.719496) (xy 177.595588 -22.734605) (xy 177.513709 -22.742192) (xy 177.472594 -22.742652)
			(xy 177.429071 -22.742084) (xy 177.34244 -22.73358) (xy 177.257055 -22.716655) (xy 177.173731 -22.69147)
			(xy 177.093266 -22.658267) (xy 177.016429 -22.617362) (xy 176.943956 -22.569146) (xy 176.876538 -22.514083)
			(xy 176.814822 -22.452697) (xy 176.759398 -22.385575) (xy 176.710795 -22.313361) (xy 176.669479 -22.236745)
			(xy 176.652174 -22.196806) (xy 176.647921 -22.187866) (xy 176.633936 -22.17388) (xy 176.624996 -22.169628)
			(xy 176.585068 -22.152314) (xy 176.508472 -22.110985) (xy 176.436278 -22.062372) (xy 176.369178 -22.006941)
			(xy 176.307813 -21.945221) (xy 176.252769 -21.877802) (xy 176.204574 -21.80533) (xy 176.163687 -21.728496)
			(xy 176.1305 -21.648037) (xy 176.105331 -21.564721) (xy 176.088419 -21.479345) (xy 176.079928 -21.392725)
			(xy 176.079404 -21.349208) (xy 176.079404 -21.348446) (xy 176.079814 -21.310226) (xy 176.086378 -21.234067)
			(xy 176.099462 -21.158755) (xy 176.118968 -21.084845) (xy 176.131474 -21.048726) (xy 176.134055 -21.040409)
			(xy 176.134058 -21.023006) (xy 176.131474 -21.01469) (xy 176.118957 -20.978475) (xy 176.099434 -20.904375)
			(xy 176.086349 -20.828871) (xy 176.079799 -20.752523) (xy 176.079404 -20.714208) (xy 176.07999 -20.668344)
			(xy 176.089425 -20.577104) (xy 176.108186 -20.487316) (xy 176.121568 -20.443444) (xy 176.124428 -20.432883)
			(xy 176.121929 -20.411168) (xy 176.116742 -20.401534) (xy 176.096312 -20.366847) (xy 176.06107 -20.294464)
			(xy 176.032509 -20.219194) (xy 176.010862 -20.141652) (xy 175.996306 -20.062472) (xy 175.988959 -19.982301)
			(xy 175.988472 -19.942048) (xy 140.449617 -19.942048) (xy 140.472364 -19.977445) (xy 140.495002 -20.027018)
			(xy 140.510354 -20.079308) (xy 140.51811 -20.133251) (xy 140.51811 -20.187749) (xy 140.510354 -20.241692)
			(xy 140.495002 -20.293982) (xy 140.472364 -20.343555) (xy 140.442901 -20.389403) (xy 140.407215 -20.430591)
			(xy 140.36603 -20.466281) (xy 140.320185 -20.495747) (xy 140.270614 -20.51839) (xy 140.218325 -20.533747)
			(xy 140.164383 -20.541507) (xy 140.137134 -20.541996) (xy 139.146534 -20.541996) (xy 139.119279 -20.541559)
			(xy 139.065322 -20.533806) (xy 139.013019 -20.518453) (xy 138.963433 -20.495811) (xy 138.917574 -20.466343)
			(xy 138.876376 -20.430648) (xy 138.840677 -20.389453) (xy 138.811205 -20.343597) (xy 138.788559 -20.294013)
			(xy 138.773201 -20.241711) (xy 138.765443 -20.187755) (xy 67.653158 -20.187755) (xy 67.657521 -20.212789)
			(xy 67.664147 -20.289078) (xy 67.664584 -20.327366) (xy 67.66408 -20.369727) (xy 67.656027 -20.454064)
			(xy 67.639993 -20.537254) (xy 67.616125 -20.618544) (xy 67.584637 -20.697196) (xy 67.545815 -20.772499)
			(xy 67.500012 -20.843771) (xy 67.447641 -20.910367) (xy 67.389176 -20.971682) (xy 67.325148 -21.027163)
			(xy 67.256136 -21.076306) (xy 67.182766 -21.118666) (xy 67.105701 -21.153861) (xy 67.025639 -21.18157)
			(xy 66.943306 -21.201544) (xy 66.859447 -21.213601) (xy 66.774822 -21.217633) (xy 66.690197 -21.213601)
			(xy 66.606338 -21.201544) (xy 66.524005 -21.18157) (xy 66.443943 -21.153861) (xy 66.366878 -21.118666)
			(xy 66.293508 -21.076306) (xy 66.224496 -21.027163) (xy 66.160468 -20.971682) (xy 66.102003 -20.910367)
			(xy 66.049632 -20.843771) (xy 66.003829 -20.772499) (xy 65.965007 -20.697196) (xy 65.933519 -20.618544)
			(xy 65.909651 -20.537254) (xy 65.893617 -20.454064) (xy 65.885564 -20.369727) (xy 65.88506 -20.327366)
			(xy 0.509016 -20.327366) (xy 0.509016 -22.309271) (xy 65.993006 -22.309271) (xy 65.993006 -22.224549)
			(xy 66.001059 -22.140212) (xy 66.017093 -22.057022) (xy 66.040961 -21.975732) (xy 66.072449 -21.89708)
			(xy 66.111271 -21.821777) (xy 66.157074 -21.750505) (xy 66.209445 -21.683909) (xy 66.26791 -21.622594)
			(xy 66.331938 -21.567113) (xy 66.40095 -21.51797) (xy 66.47432 -21.47561) (xy 66.551385 -21.440415)
			(xy 66.631447 -21.412706) (xy 66.71378 -21.392732) (xy 66.797639 -21.380675) (xy 66.882264 -21.376644)
			(xy 66.966889 -21.380675) (xy 67.050748 -21.392732) (xy 67.133081 -21.412706) (xy 67.213143 -21.440415)
			(xy 67.290208 -21.47561) (xy 67.363578 -21.51797) (xy 67.43259 -21.567113) (xy 67.496618 -21.622594)
			(xy 67.555083 -21.683909) (xy 67.607454 -21.750505) (xy 67.653257 -21.821777) (xy 67.692079 -21.89708)
			(xy 67.723567 -21.975732) (xy 67.747435 -22.057022) (xy 67.763469 -22.140212) (xy 67.771522 -22.224549)
			(xy 67.772026 -22.26691) (xy 67.771522 -22.309271) (xy 67.763469 -22.393608) (xy 67.747435 -22.476798)
			(xy 67.723567 -22.558088) (xy 67.722853 -22.559872) (xy 114.452596 -22.559872) (xy 114.452596 -22.505328)
			(xy 114.460358 -22.45134) (xy 114.475725 -22.399006) (xy 114.498383 -22.349391) (xy 114.527872 -22.303506)
			(xy 114.563591 -22.262285) (xy 114.604813 -22.226567) (xy 114.650698 -22.19708) (xy 114.700313 -22.174422)
			(xy 114.752648 -22.159056) (xy 114.806636 -22.151295) (xy 114.833908 -22.150832) (xy 115.697508 -22.150832)
			(xy 115.724777 -22.151331) (xy 115.778758 -22.159093) (xy 115.831086 -22.174459) (xy 115.880695 -22.197116)
			(xy 115.926574 -22.226601) (xy 115.96779 -22.262316) (xy 116.003504 -22.303533) (xy 116.032988 -22.349412)
			(xy 116.055644 -22.399021) (xy 116.071008 -22.451349) (xy 116.07877 -22.505331) (xy 116.07877 -22.559869)
			(xy 116.071008 -22.613851) (xy 116.055644 -22.666179) (xy 116.032988 -22.715788) (xy 116.003504 -22.761667)
			(xy 115.96779 -22.802884) (xy 115.926574 -22.838599) (xy 115.880695 -22.868084) (xy 115.831086 -22.890741)
			(xy 115.778758 -22.906107) (xy 115.724777 -22.913869) (xy 115.697508 -22.914356) (xy 114.833908 -22.914356)
			(xy 114.806636 -22.913905) (xy 114.752648 -22.906144) (xy 114.700313 -22.890778) (xy 114.650698 -22.86812)
			(xy 114.604813 -22.838633) (xy 114.563591 -22.802915) (xy 114.527872 -22.761694) (xy 114.498383 -22.715809)
			(xy 114.475725 -22.666194) (xy 114.460358 -22.61386) (xy 114.452596 -22.559872) (xy 67.722853 -22.559872)
			(xy 67.692079 -22.63674) (xy 67.653257 -22.712043) (xy 67.607454 -22.783315) (xy 67.555083 -22.849911)
			(xy 67.496618 -22.911226) (xy 67.43259 -22.966707) (xy 67.363578 -23.01585) (xy 67.361784 -23.016886)
			(xy 136.323137 -23.016886) (xy 136.327046 -22.962479) (xy 136.338661 -22.909183) (xy 136.357746 -22.858084)
			(xy 136.383911 -22.810221) (xy 136.416623 -22.766572) (xy 136.435592 -22.74697) (xy 137.046208 -22.1361)
			(xy 137.06783 -22.115331) (xy 137.116345 -22.080114) (xy 137.169764 -22.052902) (xy 137.226775 -22.034363)
			(xy 137.285982 -22.024951) (xy 137.315956 -22.02434) (xy 137.31621 -22.02434) (xy 137.34348 -22.024815)
			(xy 137.397464 -22.032578) (xy 137.449794 -22.047945) (xy 137.499404 -22.070602) (xy 137.545285 -22.10009)
			(xy 137.586503 -22.135806) (xy 137.622218 -22.177025) (xy 137.651703 -22.222907) (xy 137.674359 -22.272518)
			(xy 137.689724 -22.324848) (xy 137.697486 -22.378832) (xy 137.697972 -22.406102) (xy 137.697972 -22.406356)
			(xy 137.6974 -22.436336) (xy 137.688023 -22.495559) (xy 137.669494 -22.552585) (xy 137.64227 -22.606009)
			(xy 137.60702 -22.654514) (xy 137.586212 -22.676104) (xy 136.975342 -23.28672) (xy 136.955728 -23.305677)
			(xy 136.912079 -23.338389) (xy 136.864216 -23.364554) (xy 136.813117 -23.383639) (xy 136.759821 -23.395254)
			(xy 136.705414 -23.399163) (xy 136.651005 -23.395286) (xy 136.597702 -23.383703) (xy 136.546591 -23.364649)
			(xy 136.498713 -23.338513) (xy 136.455044 -23.305826) (xy 136.416474 -23.267256) (xy 136.383787 -23.223587)
			(xy 136.357651 -23.175709) (xy 136.338597 -23.124598) (xy 136.327014 -23.071295) (xy 136.323137 -23.016886)
			(xy 67.361784 -23.016886) (xy 67.290208 -23.05821) (xy 67.213143 -23.093405) (xy 67.133081 -23.121114)
			(xy 67.050748 -23.141088) (xy 66.966889 -23.153145) (xy 66.882264 -23.157177) (xy 66.797639 -23.153145)
			(xy 66.71378 -23.141088) (xy 66.631447 -23.121114) (xy 66.551385 -23.093405) (xy 66.47432 -23.05821)
			(xy 66.40095 -23.01585) (xy 66.331938 -22.966707) (xy 66.26791 -22.911226) (xy 66.209445 -22.849911)
			(xy 66.157074 -22.783315) (xy 66.111271 -22.712043) (xy 66.072449 -22.63674) (xy 66.040961 -22.558088)
			(xy 66.017093 -22.476798) (xy 66.001059 -22.393608) (xy 65.993006 -22.309271) (xy 0.509016 -22.309271)
			(xy 0.509016 -23.593552) (xy 189.619128 -23.593552) (xy 189.619128 -23.593298) (xy 189.619711 -23.54856)
			(xy 189.628722 -23.459539) (xy 189.646623 -23.371871) (xy 189.673232 -23.286444) (xy 189.690248 -23.245064)
			(xy 189.69384 -23.235481) (xy 189.693822 -23.215031) (xy 189.690248 -23.20544) (xy 189.673222 -23.164064)
			(xy 189.646604 -23.078637) (xy 189.6287 -22.990968) (xy 189.619692 -22.901945) (xy 189.619128 -22.857206)
			(xy 189.619128 -22.856952) (xy 189.619632 -22.814604) (xy 189.627683 -22.73029) (xy 189.643712 -22.647124)
			(xy 189.667573 -22.565857) (xy 189.699052 -22.487227) (xy 189.737863 -22.411946) (xy 189.783653 -22.340694)
			(xy 189.836009 -22.274118) (xy 189.894457 -22.21282) (xy 189.958467 -22.157355) (xy 190.027459 -22.108226)
			(xy 190.100809 -22.065877) (xy 190.177852 -22.030693) (xy 190.257891 -22.002991) (xy 190.3402 -21.983023)
			(xy 190.424035 -21.97097) (xy 190.508636 -21.96694) (xy 190.593237 -21.97097) (xy 190.677072 -21.983023)
			(xy 190.759381 -22.002991) (xy 190.83942 -22.030693) (xy 190.916463 -22.065877) (xy 190.989813 -22.108226)
			(xy 191.058805 -22.157355) (xy 191.122815 -22.21282) (xy 191.181263 -22.274118) (xy 191.233619 -22.340694)
			(xy 191.279409 -22.411946) (xy 191.31822 -22.487227) (xy 191.349699 -22.565857) (xy 191.37356 -22.647124)
			(xy 191.389589 -22.73029) (xy 191.39764 -22.814604) (xy 191.398144 -22.856952) (xy 191.398144 -22.857206)
			(xy 191.397557 -22.901944) (xy 191.388547 -22.990965) (xy 191.370647 -23.078632) (xy 191.344039 -23.16406)
			(xy 191.327024 -23.20544) (xy 191.323489 -23.215039) (xy 191.323471 -23.235473) (xy 191.327024 -23.245064)
			(xy 191.344055 -23.286438) (xy 191.370671 -23.371866) (xy 191.388573 -23.459535) (xy 191.39758 -23.548559)
			(xy 191.398144 -23.593298) (xy 191.398144 -23.593552) (xy 191.39764 -23.6359) (xy 191.389589 -23.720214)
			(xy 191.37356 -23.80338) (xy 191.349699 -23.884647) (xy 191.31822 -23.963277) (xy 191.279409 -24.038558)
			(xy 191.233619 -24.10981) (xy 191.181263 -24.176386) (xy 191.122815 -24.237684) (xy 191.058805 -24.293149)
			(xy 190.989813 -24.342278) (xy 190.916463 -24.384627) (xy 190.83942 -24.419811) (xy 190.759381 -24.447513)
			(xy 190.677072 -24.467481) (xy 190.593237 -24.479534) (xy 190.508636 -24.483565) (xy 190.424035 -24.479534)
			(xy 190.3402 -24.467481) (xy 190.257891 -24.447513) (xy 190.177852 -24.419811) (xy 190.100809 -24.384627)
			(xy 190.027459 -24.342278) (xy 189.958467 -24.293149) (xy 189.894457 -24.237684) (xy 189.836009 -24.176386)
			(xy 189.783653 -24.10981) (xy 189.737863 -24.038558) (xy 189.699052 -23.963277) (xy 189.667573 -23.884647)
			(xy 189.643712 -23.80338) (xy 189.627683 -23.720214) (xy 189.619632 -23.6359) (xy 189.619128 -23.593552)
			(xy 0.509016 -23.593552) (xy 0.509016 -25.56891) (xy 65.510156 -25.56891) (xy 65.510621 -25.527206)
			(xy 65.518403 -25.444163) (xy 65.533928 -25.362214) (xy 65.557059 -25.282079) (xy 65.587593 -25.204462)
			(xy 65.625262 -25.130046) (xy 65.669734 -25.059485) (xy 65.720619 -24.993398) (xy 65.777469 -24.932368)
			(xy 65.839786 -24.876929) (xy 65.873122 -24.851868) (xy 65.88167 -24.844931) (xy 65.892346 -24.825708)
			(xy 65.893696 -24.814784) (xy 65.897332 -24.773398) (xy 65.911399 -24.69151) (xy 65.933041 -24.611291)
			(xy 65.962067 -24.53344) (xy 65.998226 -24.458634) (xy 66.041203 -24.387525) (xy 66.090622 -24.320733)
			(xy 66.146054 -24.25884) (xy 66.207015 -24.202385) (xy 66.272974 -24.15186) (xy 66.343357 -24.107705)
			(xy 66.41755 -24.070304) (xy 66.494907 -24.039985) (xy 66.574755 -24.01701) (xy 66.656396 -24.00158)
			(xy 66.739121 -23.99383) (xy 66.780664 -23.993348) (xy 66.824459 -23.993873) (xy 66.911625 -24.002491)
			(xy 66.997521 -24.019637) (xy 67.081315 -24.045145) (xy 67.162195 -24.078768) (xy 67.201034 -24.099012)
			(xy 67.2125 -24.10443) (xy 67.237828 -24.10443) (xy 67.249294 -24.099012) (xy 67.288138 -24.078781)
			(xy 67.369023 -24.045174) (xy 67.452816 -24.019672) (xy 67.538709 -24.002521) (xy 67.62587 -23.993888)
			(xy 67.669664 -23.993348) (xy 67.713459 -23.993873) (xy 67.800625 -24.002491) (xy 67.886521 -24.019637)
			(xy 67.970315 -24.045145) (xy 68.051195 -24.078768) (xy 68.090034 -24.099012) (xy 68.1015 -24.10443)
			(xy 68.126828 -24.10443) (xy 68.138294 -24.099012) (xy 68.177138 -24.078781) (xy 68.258023 -24.045174)
			(xy 68.341816 -24.019672) (xy 68.427709 -24.002521) (xy 68.51487 -23.993888) (xy 68.558664 -23.993348)
			(xy 68.607651 -23.994055) (xy 68.705028 -24.00487) (xy 68.752974 -24.014938) (xy 68.762324 -24.016604)
			(xy 68.781086 -24.013776) (xy 68.797533 -24.004314) (xy 68.803774 -23.997158) (xy 68.831851 -23.962886)
			(xy 68.893786 -23.899527) (xy 68.961714 -23.842641) (xy 69.034963 -23.792791) (xy 69.112805 -23.750472)
			(xy 69.19447 -23.716104) (xy 69.279148 -23.690027) (xy 69.365999 -23.672499) (xy 69.454163 -23.663695)
			(xy 69.498464 -23.663148) (xy 69.540827 -23.663615) (xy 69.625169 -23.671665) (xy 69.708365 -23.687697)
			(xy 69.789659 -23.711564) (xy 69.868317 -23.743051) (xy 69.943625 -23.781873) (xy 70.014902 -23.827677)
			(xy 70.081502 -23.880049) (xy 70.142823 -23.938516) (xy 70.198307 -24.002546) (xy 70.247454 -24.071561)
			(xy 70.250564 -24.076947) (xy 112.652614 -24.076947) (xy 112.652614 -24.022453) (xy 112.660369 -23.968515)
			(xy 112.67572 -23.916228) (xy 112.698356 -23.866659) (xy 112.727815 -23.820815) (xy 112.763499 -23.77963)
			(xy 112.80468 -23.743942) (xy 112.85052 -23.714477) (xy 112.900087 -23.691836) (xy 112.952372 -23.676478)
			(xy 113.006309 -23.668717) (xy 113.033556 -23.668228) (xy 113.897156 -23.668228) (xy 113.924413 -23.668616)
			(xy 113.978374 -23.676369) (xy 114.030682 -23.691722) (xy 114.080273 -23.714364) (xy 114.126136 -23.743834)
			(xy 114.167338 -23.779531) (xy 114.20304 -23.820729) (xy 114.232514 -23.866588) (xy 114.255162 -23.916176)
			(xy 114.270522 -23.968483) (xy 114.278281 -24.022443) (xy 114.278281 -24.076957) (xy 114.270522 -24.130917)
			(xy 114.255235 -24.182975) (xy 116.218856 -24.182975) (xy 116.218856 -24.128425) (xy 116.226619 -24.074429)
			(xy 116.241989 -24.022088) (xy 116.264651 -23.972468) (xy 116.294144 -23.926577) (xy 116.329868 -23.885352)
			(xy 116.371096 -23.84963) (xy 116.416989 -23.820139) (xy 116.466611 -23.79748) (xy 116.518953 -23.782114)
			(xy 116.572949 -23.774354) (xy 116.600224 -23.773892) (xy 117.463824 -23.773892) (xy 117.491089 -23.774472)
			(xy 117.545063 -23.782235) (xy 117.597384 -23.797601) (xy 117.646985 -23.820256) (xy 117.692857 -23.849739)
			(xy 117.734067 -23.88545) (xy 117.769776 -23.926662) (xy 117.799256 -23.972536) (xy 117.821907 -24.022139)
			(xy 117.83727 -24.07446) (xy 117.84503 -24.128435) (xy 117.84503 -24.182965) (xy 117.83727 -24.23694)
			(xy 117.821907 -24.289261) (xy 117.799256 -24.338864) (xy 117.769776 -24.384738) (xy 117.734067 -24.42595)
			(xy 117.692857 -24.461661) (xy 117.646985 -24.491144) (xy 117.597384 -24.513799) (xy 117.545063 -24.529165)
			(xy 117.491089 -24.536928) (xy 117.463824 -24.537416) (xy 116.600224 -24.537416) (xy 116.572949 -24.537046)
			(xy 116.518953 -24.529286) (xy 116.466611 -24.51392) (xy 116.416989 -24.491261) (xy 116.371096 -24.46177)
			(xy 116.329868 -24.426049) (xy 116.294144 -24.384823) (xy 116.264651 -24.338932) (xy 116.241989 -24.289312)
			(xy 116.226619 -24.236971) (xy 116.218856 -24.182975) (xy 114.255235 -24.182975) (xy 114.255162 -24.183224)
			(xy 114.232514 -24.232812) (xy 114.20304 -24.278671) (xy 114.167338 -24.319869) (xy 114.126136 -24.355566)
			(xy 114.080273 -24.385036) (xy 114.030682 -24.407678) (xy 113.978374 -24.423031) (xy 113.924414 -24.430784)
			(xy 113.897156 -24.431244) (xy 113.033556 -24.431244) (xy 113.006309 -24.430683) (xy 112.952372 -24.422922)
			(xy 112.900087 -24.407564) (xy 112.85052 -24.384923) (xy 112.80468 -24.355458) (xy 112.763499 -24.31977)
			(xy 112.727815 -24.278585) (xy 112.698356 -24.232741) (xy 112.67572 -24.183172) (xy 112.660369 -24.130885)
			(xy 112.652614 -24.076947) (xy 70.250564 -24.076947) (xy 70.289818 -24.144935) (xy 70.325015 -24.222004)
			(xy 70.352727 -24.302069) (xy 70.372702 -24.384407) (xy 70.38476 -24.46827) (xy 70.388792 -24.5529)
			(xy 70.38476 -24.63753) (xy 70.37544 -24.702351) (xy 130.235962 -24.702351) (xy 130.235962 -24.647849)
			(xy 130.243717 -24.593903) (xy 130.259071 -24.541609) (xy 130.28171 -24.492033) (xy 130.311174 -24.446182)
			(xy 130.346863 -24.404991) (xy 130.38805 -24.369298) (xy 130.433897 -24.33983) (xy 130.483472 -24.317185)
			(xy 130.535764 -24.301826) (xy 130.589709 -24.294065) (xy 130.61696 -24.293576) (xy 131.48056 -24.293576)
			(xy 131.507814 -24.294069) (xy 131.561767 -24.301821) (xy 131.614067 -24.317173) (xy 131.66365 -24.339812)
			(xy 131.709506 -24.369277) (xy 131.750702 -24.40497) (xy 131.786399 -24.446162) (xy 131.815869 -24.492015)
			(xy 131.838513 -24.541595) (xy 131.853871 -24.593894) (xy 131.861629 -24.647846) (xy 131.861629 -24.702354)
			(xy 131.853871 -24.756306) (xy 131.838513 -24.808605) (xy 131.815869 -24.858185) (xy 131.786399 -24.904038)
			(xy 131.750702 -24.94523) (xy 131.709506 -24.980923) (xy 131.66365 -25.010388) (xy 131.614067 -25.033027)
			(xy 131.561767 -25.048379) (xy 131.507814 -25.056131) (xy 131.48056 -25.056592) (xy 130.61696 -25.056592)
			(xy 130.589709 -25.056135) (xy 130.535764 -25.048374) (xy 130.483472 -25.033015) (xy 130.433897 -25.01037)
			(xy 130.38805 -24.980902) (xy 130.346863 -24.945209) (xy 130.311174 -24.904018) (xy 130.28171 -24.858167)
			(xy 130.259071 -24.808591) (xy 130.243717 -24.756297) (xy 130.235962 -24.702351) (xy 70.37544 -24.702351)
			(xy 70.372702 -24.721393) (xy 70.352727 -24.803731) (xy 70.325015 -24.883796) (xy 70.289818 -24.960865)
			(xy 70.247454 -25.034239) (xy 70.198307 -25.103254) (xy 70.142823 -25.167284) (xy 70.081502 -25.225751)
			(xy 70.014902 -25.278123) (xy 69.943625 -25.323927) (xy 69.868317 -25.362749) (xy 69.789659 -25.394236)
			(xy 69.708365 -25.418103) (xy 69.625169 -25.434135) (xy 69.540827 -25.442185) (xy 69.498464 -25.442672)
			(xy 69.449476 -25.441976) (xy 69.3521 -25.431154) (xy 69.304154 -25.421082) (xy 69.294812 -25.41935)
			(xy 69.276039 -25.422204) (xy 69.259591 -25.431693) (xy 69.253354 -25.438862) (xy 69.228687 -25.46901)
			(xy 69.174875 -25.52534) (xy 69.116354 -25.57676) (xy 69.085206 -25.600152) (xy 69.076637 -25.607067)
			(xy 69.065975 -25.626306) (xy 69.065849 -25.62733) (xy 133.339332 -25.62733) (xy 133.339332 -24.76373)
			(xy 133.339818 -24.736479) (xy 133.347574 -24.682531) (xy 133.362929 -24.630236) (xy 133.385571 -24.580659)
			(xy 133.415037 -24.534809) (xy 133.450728 -24.493618) (xy 133.491919 -24.457927) (xy 133.537769 -24.428461)
			(xy 133.587346 -24.405819) (xy 133.639641 -24.390464) (xy 133.693589 -24.382708) (xy 133.748091 -24.382708)
			(xy 133.802039 -24.390464) (xy 133.854334 -24.405819) (xy 133.903911 -24.428461) (xy 133.949761 -24.457927)
			(xy 133.990952 -24.493618) (xy 134.026643 -24.534809) (xy 134.056109 -24.580659) (xy 134.078751 -24.630236)
			(xy 134.094106 -24.682531) (xy 134.101862 -24.736479) (xy 134.102348 -24.76373) (xy 134.102348 -25.62733)
			(xy 134.101862 -25.654581) (xy 134.094106 -25.708529) (xy 134.078751 -25.760824) (xy 134.056109 -25.810401)
			(xy 134.026643 -25.856251) (xy 133.990952 -25.897442) (xy 133.949761 -25.933133) (xy 133.903911 -25.962599)
			(xy 133.854334 -25.985241) (xy 133.802039 -26.000596) (xy 133.748091 -26.008352) (xy 133.693589 -26.008352)
			(xy 133.639641 -26.000596) (xy 133.587346 -25.985241) (xy 133.537769 -25.962599) (xy 133.491919 -25.933133)
			(xy 133.450728 -25.897442) (xy 133.415037 -25.856251) (xy 133.385571 -25.810401) (xy 133.362929 -25.760824)
			(xy 133.347574 -25.708529) (xy 133.339818 -25.654581) (xy 133.339332 -25.62733) (xy 69.065849 -25.62733)
			(xy 69.064632 -25.637236) (xy 69.060986 -25.678621) (xy 69.046917 -25.760507) (xy 69.025275 -25.840725)
			(xy 68.996248 -25.918575) (xy 68.960089 -25.99338) (xy 68.917113 -26.064488) (xy 68.867694 -26.131279)
			(xy 68.812263 -26.193171) (xy 68.751303 -26.249626) (xy 68.685345 -26.300151) (xy 68.614964 -26.344307)
			(xy 68.540772 -26.381708) (xy 68.463416 -26.412028) (xy 68.38357 -26.435004) (xy 68.30193 -26.450436)
			(xy 68.219207 -26.458189) (xy 68.177664 -26.458672) (xy 68.133869 -26.458133) (xy 68.046704 -26.449518)
			(xy 67.960808 -26.432375) (xy 67.877014 -26.40687) (xy 67.796134 -26.37325) (xy 67.757294 -26.353008)
			(xy 67.745828 -26.34759) (xy 67.7205 -26.34759) (xy 67.709034 -26.353008) (xy 67.670181 -26.373222)
			(xy 67.589299 -26.406833) (xy 67.505508 -26.43234) (xy 67.419618 -26.449494) (xy 67.332457 -26.458131)
			(xy 67.288664 -26.458672) (xy 67.244869 -26.458133) (xy 67.157704 -26.449518) (xy 67.071808 -26.432375)
			(xy 66.988014 -26.40687) (xy 66.907134 -26.37325) (xy 66.868294 -26.353008) (xy 66.856828 -26.34759)
			(xy 66.8315 -26.34759) (xy 66.820034 -26.353008) (xy 66.781181 -26.373222) (xy 66.700299 -26.406833)
			(xy 66.616508 -26.43234) (xy 66.530618 -26.449494) (xy 66.443457 -26.458131) (xy 66.399664 -26.458672)
			(xy 66.358552 -26.458282) (xy 66.276678 -26.45069) (xy 66.195855 -26.435576) (xy 66.116771 -26.413067)
			(xy 66.040102 -26.383356) (xy 65.966502 -26.346696) (xy 65.8966 -26.3034) (xy 65.830991 -26.253838)
			(xy 65.770236 -26.198433) (xy 65.714853 -26.137658) (xy 65.665316 -26.072031) (xy 65.622046 -26.002113)
			(xy 65.585413 -25.928499) (xy 65.55573 -25.85182) (xy 65.53325 -25.772728) (xy 65.518165 -25.691899)
			(xy 65.510603 -25.610022) (xy 65.510156 -25.56891) (xy 0.509016 -25.56891) (xy 0.509016 -29.026161)
			(xy 11.140205 -29.026161) (xy 11.147539 -28.866724) (xy 11.162812 -28.70785) (xy 11.185984 -28.549934)
			(xy 11.216999 -28.39337) (xy 11.255779 -28.238547) (xy 11.302228 -28.085849) (xy 11.35623 -27.935656)
			(xy 11.417652 -27.788341) (xy 11.48634 -27.644271) (xy 11.562123 -27.503804) (xy 11.644814 -27.367289)
			(xy 11.734207 -27.235065) (xy 11.830079 -27.107461) (xy 11.932193 -26.984794) (xy 12.040293 -26.86737)
			(xy 12.154112 -26.75548) (xy 12.273367 -26.649402) (xy 12.397761 -26.5494) (xy 12.526985 -26.455723)
			(xy 12.660717 -26.368604) (xy 12.798626 -26.288258) (xy 12.940368 -26.214886) (xy 13.085591 -26.148671)
			(xy 13.233934 -26.089776) (xy 13.385028 -26.038349) (xy 13.538498 -25.994517) (xy 13.693962 -25.958388)
			(xy 13.851033 -25.930054) (xy 14.009321 -25.909584) (xy 14.168433 -25.897029) (xy 14.327973 -25.892421)
			(xy 14.487544 -25.895771) (xy 14.64675 -25.90707) (xy 14.805195 -25.92629) (xy 14.962485 -25.953385)
			(xy 15.118229 -25.988285) (xy 15.272039 -26.030905) (xy 15.423535 -26.081139) (xy 15.572338 -26.138862)
			(xy 15.718078 -26.203929) (xy 15.860395 -26.27618) (xy 15.998933 -26.355436) (xy 16.133349 -26.441497)
			(xy 16.263308 -26.534152) (xy 16.388487 -26.633169) (xy 16.508575 -26.738303) (xy 16.623273 -26.849292)
			(xy 16.678148 -26.907236) (xy 17.470427 -27.75458) (xy 130.687572 -27.75458) (xy 130.687572 -26.76398)
			(xy 130.688058 -26.736729) (xy 130.695814 -26.682781) (xy 130.711169 -26.630486) (xy 130.733811 -26.580909)
			(xy 130.763277 -26.535059) (xy 130.798968 -26.493868) (xy 130.840159 -26.458177) (xy 130.886009 -26.428711)
			(xy 130.935586 -26.406069) (xy 130.987881 -26.390714) (xy 131.041829 -26.382958) (xy 131.096331 -26.382958)
			(xy 131.150279 -26.390714) (xy 131.202574 -26.406069) (xy 131.252151 -26.428711) (xy 131.298001 -26.458177)
			(xy 131.339192 -26.493868) (xy 131.374883 -26.535059) (xy 131.404349 -26.580909) (xy 131.426991 -26.630486)
			(xy 131.442346 -26.682781) (xy 131.450102 -26.736729) (xy 131.450588 -26.76398) (xy 131.450588 -26.76779)
			(xy 141.621764 -26.76779) (xy 141.621764 -25.90419) (xy 141.62225 -25.876921) (xy 141.630012 -25.822937)
			(xy 141.645377 -25.770607) (xy 141.668034 -25.720997) (xy 141.69752 -25.675116) (xy 141.733235 -25.633899)
			(xy 141.774452 -25.598184) (xy 141.820333 -25.568698) (xy 141.869943 -25.546041) (xy 141.922273 -25.530676)
			(xy 141.976257 -25.522914) (xy 142.030795 -25.522914) (xy 142.084779 -25.530676) (xy 142.137109 -25.546041)
			(xy 142.186719 -25.568698) (xy 142.2326 -25.598184) (xy 142.273817 -25.633899) (xy 142.309532 -25.675116)
			(xy 142.339018 -25.720997) (xy 142.361675 -25.770607) (xy 142.37704 -25.822937) (xy 142.384802 -25.876921)
			(xy 142.385288 -25.90419) (xy 142.385288 -26.634948) (xy 175.442372 -26.634948) (xy 175.442817 -26.593237)
			(xy 175.450618 -26.510181) (xy 175.466165 -26.428221) (xy 175.489321 -26.348077) (xy 175.519883 -26.270455)
			(xy 175.557582 -26.196038) (xy 175.602086 -26.125479) (xy 175.653004 -26.059399) (xy 175.709888 -25.99838)
			(xy 175.772239 -25.942957) (xy 175.805592 -25.917906) (xy 175.814178 -25.911009) (xy 175.82483 -25.891756)
			(xy 175.826166 -25.880822) (xy 175.829855 -25.839448) (xy 175.843941 -25.757582) (xy 175.865598 -25.677385)
			(xy 175.894637 -25.599556) (xy 175.930804 -25.524774) (xy 175.973785 -25.453688) (xy 176.023205 -25.386918)
			(xy 176.078634 -25.325046) (xy 176.13959 -25.268611) (xy 176.205541 -25.218103) (xy 176.275913 -25.173964)
			(xy 176.350094 -25.136576) (xy 176.427436 -25.106267) (xy 176.507267 -25.083299) (xy 176.588892 -25.067873)
			(xy 176.671599 -25.060123) (xy 176.713134 -25.05964) (xy 176.713642 -25.05964) (xy 176.757406 -25.060139)
			(xy 176.844513 -25.068717) (xy 176.930355 -25.085818) (xy 177.0141 -25.111273) (xy 177.094937 -25.144838)
			(xy 177.133758 -25.16505) (xy 177.145111 -25.170377) (xy 177.170157 -25.170377) (xy 177.18151 -25.16505)
			(xy 177.22038 -25.144826) (xy 177.301322 -25.111257) (xy 177.38517 -25.085803) (xy 177.471113 -25.068709)
			(xy 177.55832 -25.060143) (xy 177.602134 -25.05964) (xy 177.645949 -25.060116) (xy 177.733161 -25.068665)
			(xy 177.819109 -25.085756) (xy 177.902957 -25.111222) (xy 177.983891 -25.144816) (xy 178.022758 -25.16505)
			(xy 178.034111 -25.170377) (xy 178.059157 -25.170377) (xy 178.07051 -25.16505) (xy 178.10938 -25.144826)
			(xy 178.190322 -25.111257) (xy 178.27417 -25.085803) (xy 178.360113 -25.068709) (xy 178.44732 -25.060143)
			(xy 178.491134 -25.05964) (xy 178.541288 -25.060291) (xy 178.640969 -25.071493) (xy 178.690016 -25.081992)
			(xy 178.700529 -25.083816) (xy 178.72144 -25.079687) (xy 178.7389 -25.067462) (xy 178.74488 -25.058624)
			(xy 178.766746 -25.023211) (xy 178.816155 -24.956227) (xy 178.871604 -24.894151) (xy 178.932608 -24.837525)
			(xy 178.998633 -24.786843) (xy 179.069104 -24.742549) (xy 179.143403 -24.705031) (xy 179.220882 -24.674615)
			(xy 179.300862 -24.651569) (xy 179.382645 -24.636093) (xy 179.465517 -24.628322) (xy 179.507134 -24.62784)
			(xy 179.549484 -24.628249) (xy 179.633799 -24.636303) (xy 179.716968 -24.652336) (xy 179.798236 -24.676201)
			(xy 179.876867 -24.707683) (xy 179.95215 -24.746496) (xy 180.023403 -24.79229) (xy 180.08998 -24.844649)
			(xy 180.151278 -24.9031) (xy 180.206744 -24.967112) (xy 180.255873 -25.036107) (xy 180.298222 -25.10946)
			(xy 180.333407 -25.186506) (xy 180.361109 -25.266547) (xy 180.381077 -25.348859) (xy 180.39313 -25.432696)
			(xy 180.397161 -25.5173) (xy 180.39313 -25.601904) (xy 180.381077 -25.685741) (xy 180.361109 -25.768053)
			(xy 180.333407 -25.848094) (xy 180.298222 -25.92514) (xy 180.255873 -25.998493) (xy 180.206744 -26.067488)
			(xy 180.151278 -26.1315) (xy 180.08998 -26.189951) (xy 180.023403 -26.24231) (xy 179.95215 -26.288104)
			(xy 179.876867 -26.326917) (xy 179.798236 -26.358399) (xy 179.716968 -26.382264) (xy 179.633799 -26.398297)
			(xy 179.549484 -26.406351) (xy 179.507134 -26.406856) (xy 179.505864 -26.406856) (xy 179.456029 -26.406131)
			(xy 179.35699 -26.394927) (xy 179.308252 -26.384504) (xy 179.297742 -26.382653) (xy 179.276827 -26.386794)
			(xy 179.259367 -26.39903) (xy 179.253388 -26.407872) (xy 179.230217 -26.445289) (xy 179.177598 -26.515842)
			(xy 179.118275 -26.58086) (xy 179.052827 -26.639708) (xy 179.017676 -26.66619) (xy 179.009104 -26.673102)
			(xy 178.998441 -26.692343) (xy 178.997102 -26.703274) (xy 178.993441 -26.744651) (xy 178.979354 -26.826519)
			(xy 178.957697 -26.906717) (xy 178.928657 -26.984547) (xy 178.892489 -27.059331) (xy 178.849506 -27.130418)
			(xy 178.835198 -27.149749) (xy 180.032656 -27.149749) (xy 180.032656 -27.065027) (xy 180.040709 -26.98069)
			(xy 180.056743 -26.8975) (xy 180.080611 -26.81621) (xy 180.112099 -26.737558) (xy 180.150921 -26.662255)
			(xy 180.196724 -26.590983) (xy 180.249095 -26.524387) (xy 180.30756 -26.463072) (xy 180.371588 -26.407591)
			(xy 180.4406 -26.358448) (xy 180.51397 -26.316088) (xy 180.591035 -26.280893) (xy 180.671097 -26.253184)
			(xy 180.75343 -26.23321) (xy 180.837289 -26.221153) (xy 180.921914 -26.217122) (xy 181.006539 -26.221153)
			(xy 181.090398 -26.23321) (xy 181.172731 -26.253184) (xy 181.252793 -26.280893) (xy 181.329858 -26.316088)
			(xy 181.403228 -26.358448) (xy 181.47224 -26.407591) (xy 181.536268 -26.463072) (xy 181.594733 -26.524387)
			(xy 181.647104 -26.590983) (xy 181.692907 -26.662255) (xy 181.731729 -26.737558) (xy 181.763217 -26.81621)
			(xy 181.787085 -26.8975) (xy 181.803119 -26.98069) (xy 181.811172 -27.065027) (xy 181.811676 -27.107388)
			(xy 181.811172 -27.149749) (xy 181.803119 -27.234086) (xy 181.787085 -27.317276) (xy 181.763217 -27.398566)
			(xy 181.731729 -27.477218) (xy 181.692907 -27.552521) (xy 181.647104 -27.623793) (xy 181.594733 -27.690389)
			(xy 181.536268 -27.751704) (xy 181.47224 -27.807185) (xy 181.403228 -27.856328) (xy 181.329858 -27.898688)
			(xy 181.252793 -27.933883) (xy 181.172731 -27.961592) (xy 181.090398 -27.981566) (xy 181.006539 -27.993623)
			(xy 180.921914 -27.997655) (xy 180.837289 -27.993623) (xy 180.75343 -27.981566) (xy 180.671097 -27.961592)
			(xy 180.591035 -27.933883) (xy 180.51397 -27.898688) (xy 180.4406 -27.856328) (xy 180.371588 -27.807185)
			(xy 180.30756 -27.751704) (xy 180.249095 -27.690389) (xy 180.196724 -27.623793) (xy 180.150921 -27.552521)
			(xy 180.112099 -27.477218) (xy 180.080611 -27.398566) (xy 180.056743 -27.317276) (xy 180.040709 -27.234086)
			(xy 180.032656 -27.149749) (xy 178.835198 -27.149749) (xy 178.800084 -27.197189) (xy 178.744653 -27.259061)
			(xy 178.683695 -27.315497) (xy 178.617742 -27.366004) (xy 178.547367 -27.410143) (xy 178.473184 -27.447529)
			(xy 178.395839 -27.477837) (xy 178.316006 -27.500803) (xy 178.234379 -27.516227) (xy 178.15167 -27.523974)
			(xy 178.110134 -27.524456) (xy 178.109626 -27.524456) (xy 178.065862 -27.523929) (xy 177.978756 -27.515357)
			(xy 177.892915 -27.498263) (xy 177.809169 -27.472814) (xy 177.728331 -27.439255) (xy 177.68951 -27.419046)
			(xy 177.678157 -27.413719) (xy 177.653111 -27.413719) (xy 177.641758 -27.419046) (xy 177.602894 -27.439282)
			(xy 177.521951 -27.472849) (xy 177.438101 -27.498301) (xy 177.352156 -27.515391) (xy 177.264948 -27.523955)
			(xy 177.221134 -27.524456) (xy 177.177318 -27.523994) (xy 177.090106 -27.515442) (xy 177.004158 -27.498348)
			(xy 176.920311 -27.472879) (xy 176.839376 -27.439281) (xy 176.80051 -27.419046) (xy 176.789157 -27.413719)
			(xy 176.764111 -27.413719) (xy 176.752758 -27.419046) (xy 176.713921 -27.439222) (xy 176.633081 -27.472767)
			(xy 176.549339 -27.498216) (xy 176.463504 -27.515325) (xy 176.376404 -27.523927) (xy 176.332642 -27.524456)
			(xy 176.332134 -27.524456) (xy 176.291028 -27.523955) (xy 176.209165 -27.516374) (xy 176.128351 -27.501273)
			(xy 176.049275 -27.47878) (xy 175.972611 -27.449089) (xy 175.899013 -27.412452) (xy 175.829109 -27.369181)
			(xy 175.763495 -27.319646) (xy 175.702731 -27.264268) (xy 175.647335 -27.203522) (xy 175.597779 -27.137923)
			(xy 175.554486 -27.068033) (xy 175.517825 -26.994447) (xy 175.488109 -26.917792) (xy 175.465592 -26.838723)
			(xy 175.450465 -26.757914) (xy 175.442858 -26.676054) (xy 175.442372 -26.634948) (xy 142.385288 -26.634948)
			(xy 142.385288 -26.76779) (xy 142.384802 -26.795059) (xy 142.37704 -26.849043) (xy 142.361675 -26.901373)
			(xy 142.339018 -26.950983) (xy 142.309532 -26.996864) (xy 142.273817 -27.038081) (xy 142.2326 -27.073796)
			(xy 142.186719 -27.103282) (xy 142.137109 -27.125939) (xy 142.084779 -27.141304) (xy 142.030795 -27.149066)
			(xy 141.976257 -27.149066) (xy 141.922273 -27.141304) (xy 141.869943 -27.125939) (xy 141.820333 -27.103282)
			(xy 141.774452 -27.073796) (xy 141.733235 -27.038081) (xy 141.69752 -26.996864) (xy 141.668034 -26.950983)
			(xy 141.645377 -26.901373) (xy 141.630012 -26.849043) (xy 141.62225 -26.795059) (xy 141.621764 -26.76779)
			(xy 131.450588 -26.76779) (xy 131.450588 -27.75458) (xy 131.450102 -27.781831) (xy 131.442346 -27.835779)
			(xy 131.426991 -27.888074) (xy 131.404349 -27.937651) (xy 131.374883 -27.983501) (xy 131.339192 -28.024692)
			(xy 131.298001 -28.060383) (xy 131.252151 -28.089849) (xy 131.202574 -28.112491) (xy 131.150279 -28.127846)
			(xy 131.096331 -28.135602) (xy 131.041829 -28.135602) (xy 130.987881 -28.127846) (xy 130.935586 -28.112491)
			(xy 130.886009 -28.089849) (xy 130.840159 -28.060383) (xy 130.798968 -28.024692) (xy 130.763277 -27.983501)
			(xy 130.733811 -27.937651) (xy 130.711169 -27.888074) (xy 130.695814 -27.835779) (xy 130.688058 -27.781831)
			(xy 130.687572 -27.75458) (xy 17.470427 -27.75458) (xy 17.770856 -28.07589) (xy 17.824996 -28.134528)
			(xy 17.928078 -28.256394) (xy 18.024957 -28.383247) (xy 18.115392 -28.514772) (xy 18.199158 -28.650641)
			(xy 18.276047 -28.790516) (xy 18.345869 -28.934051) (xy 18.408448 -29.080887) (xy 18.463631 -29.230661)
			(xy 18.511279 -29.382999) (xy 18.546379 -29.51861) (xy 101.326696 -29.51861) (xy 101.326696 -28.65501)
			(xy 101.327182 -28.627759) (xy 101.334938 -28.573811) (xy 101.350293 -28.521516) (xy 101.372935 -28.471939)
			(xy 101.402401 -28.426089) (xy 101.438092 -28.384898) (xy 101.479283 -28.349207) (xy 101.525133 -28.319741)
			(xy 101.57471 -28.297099) (xy 101.627005 -28.281744) (xy 101.680953 -28.273988) (xy 101.735455 -28.273988)
			(xy 101.789403 -28.281744) (xy 101.841698 -28.297099) (xy 101.891275 -28.319741) (xy 101.937125 -28.349207)
			(xy 101.978316 -28.384898) (xy 102.014007 -28.426089) (xy 102.043473 -28.471939) (xy 102.066115 -28.521516)
			(xy 102.08147 -28.573811) (xy 102.089226 -28.627759) (xy 102.089712 -28.65501) (xy 102.089712 -29.24302)
			(xy 135.551672 -29.24302) (xy 135.551672 -28.25242) (xy 135.552158 -28.225169) (xy 135.559914 -28.171221)
			(xy 135.575269 -28.118926) (xy 135.597911 -28.069349) (xy 135.627377 -28.023499) (xy 135.663068 -27.982308)
			(xy 135.704259 -27.946617) (xy 135.750109 -27.917151) (xy 135.799686 -27.894509) (xy 135.851981 -27.879154)
			(xy 135.905929 -27.871398) (xy 135.960431 -27.871398) (xy 136.014379 -27.879154) (xy 136.066674 -27.894509)
			(xy 136.116251 -27.917151) (xy 136.162101 -27.946617) (xy 136.203292 -27.982308) (xy 136.238983 -28.023499)
			(xy 136.268449 -28.069349) (xy 136.291091 -28.118926) (xy 136.306446 -28.171221) (xy 136.314202 -28.225169)
			(xy 136.314688 -28.25242) (xy 136.314688 -28.526871) (xy 139.853386 -28.526871) (xy 139.853386 -28.472329)
			(xy 139.861148 -28.418343) (xy 139.876513 -28.366011) (xy 139.89917 -28.316397) (xy 139.928656 -28.270513)
			(xy 139.964371 -28.229293) (xy 140.005589 -28.193574) (xy 140.051471 -28.164084) (xy 140.101082 -28.141424)
			(xy 140.153414 -28.126054) (xy 140.207399 -28.118289) (xy 140.23467 -28.1178) (xy 141.09827 -28.1178)
			(xy 141.12554 -28.118337) (xy 141.179524 -28.126095) (xy 141.231856 -28.141457) (xy 141.281468 -28.164111)
			(xy 141.32735 -28.193595) (xy 141.36857 -28.229309) (xy 141.404287 -28.270526) (xy 141.433775 -28.316406)
			(xy 141.456432 -28.366016) (xy 141.471798 -28.418346) (xy 141.479561 -28.47233) (xy 141.479561 -28.52687)
			(xy 141.471798 -28.580854) (xy 141.456432 -28.633184) (xy 141.433775 -28.682794) (xy 141.404287 -28.728674)
			(xy 141.36857 -28.769891) (xy 141.32735 -28.805605) (xy 141.281468 -28.835089) (xy 141.231856 -28.857743)
			(xy 141.179524 -28.873105) (xy 141.12554 -28.880863) (xy 141.09827 -28.881324) (xy 140.23467 -28.881324)
			(xy 140.207399 -28.880911) (xy 140.153414 -28.873146) (xy 140.101082 -28.857776) (xy 140.051471 -28.835116)
			(xy 140.005589 -28.805626) (xy 139.964371 -28.769907) (xy 139.928656 -28.728687) (xy 139.89917 -28.682803)
			(xy 139.876513 -28.633189) (xy 139.861148 -28.580857) (xy 139.853386 -28.526871) (xy 136.314688 -28.526871)
			(xy 136.314688 -29.24302) (xy 136.314202 -29.270271) (xy 136.306446 -29.324219) (xy 136.291091 -29.376514)
			(xy 136.268449 -29.426091) (xy 136.238983 -29.471941) (xy 136.203292 -29.513132) (xy 136.162101 -29.548823)
			(xy 136.116251 -29.578289) (xy 136.066674 -29.600931) (xy 136.014379 -29.616286) (xy 135.960431 -29.624042)
			(xy 135.905929 -29.624042) (xy 135.851981 -29.616286) (xy 135.799686 -29.600931) (xy 135.750109 -29.578289)
			(xy 135.704259 -29.548823) (xy 135.663068 -29.513132) (xy 135.627377 -29.471941) (xy 135.597911 -29.426091)
			(xy 135.575269 -29.376514) (xy 135.559914 -29.324219) (xy 135.552158 -29.270271) (xy 135.551672 -29.24302)
			(xy 102.089712 -29.24302) (xy 102.089712 -29.51861) (xy 102.089226 -29.545861) (xy 102.08147 -29.599809)
			(xy 102.066115 -29.652104) (xy 102.043473 -29.701681) (xy 102.014007 -29.747531) (xy 101.978316 -29.788722)
			(xy 101.937125 -29.824413) (xy 101.891275 -29.853879) (xy 101.841698 -29.876521) (xy 101.789403 -29.891876)
			(xy 101.735455 -29.899632) (xy 101.680953 -29.899632) (xy 101.627005 -29.891876) (xy 101.57471 -29.876521)
			(xy 101.525133 -29.853879) (xy 101.479283 -29.824413) (xy 101.438092 -29.788722) (xy 101.402401 -29.747531)
			(xy 101.372935 -29.701681) (xy 101.350293 -29.652104) (xy 101.334938 -29.599809) (xy 101.327182 -29.545861)
			(xy 101.326696 -29.51861) (xy 18.546379 -29.51861) (xy 18.551274 -29.537523) (xy 18.583516 -29.693848)
			(xy 18.607926 -29.851586) (xy 18.624443 -30.010345) (xy 18.63109 -30.1338) (xy 197.595716 -30.1338)
			(xy 197.599747 -30.049172) (xy 197.611805 -29.965311) (xy 197.631779 -29.882976) (xy 197.65949 -29.802912)
			(xy 197.694686 -29.725844) (xy 197.737048 -29.652472) (xy 197.786193 -29.583458) (xy 197.841676 -29.519429)
			(xy 197.902994 -29.460963) (xy 197.969592 -29.408591) (xy 198.040866 -29.362787) (xy 198.116172 -29.323965)
			(xy 198.194827 -29.292477) (xy 198.276119 -29.268609) (xy 198.359312 -29.252576) (xy 198.443652 -29.244524)
			(xy 198.486014 -29.244036) (xy 198.524304 -29.244437) (xy 198.600598 -29.251046) (xy 198.676041 -29.264197)
			(xy 198.750071 -29.283791) (xy 198.786242 -29.29636) (xy 198.794679 -29.299011) (xy 198.812349 -29.299011)
			(xy 198.820786 -29.29636) (xy 198.856961 -29.283808) (xy 198.930995 -29.264238) (xy 199.006435 -29.251093)
			(xy 199.082726 -29.244471) (xy 199.121014 -29.244036) (xy 199.159304 -29.244437) (xy 199.235598 -29.251046)
			(xy 199.311041 -29.264197) (xy 199.385071 -29.283791) (xy 199.421242 -29.29636) (xy 199.429679 -29.299011)
			(xy 199.447349 -29.299011) (xy 199.455786 -29.29636) (xy 199.491961 -29.283808) (xy 199.565995 -29.264238)
			(xy 199.641435 -29.251093) (xy 199.717726 -29.244471) (xy 199.756014 -29.244036) (xy 199.794304 -29.244437)
			(xy 199.870598 -29.251046) (xy 199.946041 -29.264197) (xy 200.020071 -29.283791) (xy 200.056242 -29.29636)
			(xy 200.064679 -29.299011) (xy 200.082349 -29.299011) (xy 200.090786 -29.29636) (xy 200.126961 -29.283808)
			(xy 200.200995 -29.264238) (xy 200.276435 -29.251093) (xy 200.352726 -29.244471) (xy 200.391014 -29.244036)
			(xy 200.431702 -29.244422) (xy 200.512738 -29.251848) (xy 200.592757 -29.266645) (xy 200.67109 -29.288689)
			(xy 200.747082 -29.317797) (xy 200.820096 -29.353725) (xy 200.889524 -29.396173) (xy 200.954784 -29.444785)
			(xy 201.015331 -29.499155) (xy 201.070657 -29.558829) (xy 201.120302 -29.623307) (xy 201.163849 -29.69205)
			(xy 201.200934 -29.764484) (xy 201.216514 -29.802074) (xy 201.22098 -29.811942) (xy 201.236608 -29.826918)
			(xy 201.256995 -29.83419) (xy 201.267822 -29.833824) (xy 201.286077 -29.832403) (xy 201.322664 -29.83088)
			(xy 201.340974 -29.830776) (xy 201.383338 -29.831187) (xy 201.467682 -29.839239) (xy 201.550879 -29.855272)
			(xy 201.632176 -29.87914) (xy 201.710835 -29.910629) (xy 201.786145 -29.949452) (xy 201.857423 -29.995258)
			(xy 201.924025 -30.047632) (xy 201.985346 -30.1061) (xy 202.040832 -30.170132) (xy 202.08998 -30.239149)
			(xy 202.132344 -30.312525) (xy 202.167542 -30.389596) (xy 202.195254 -30.469663) (xy 202.21523 -30.552003)
			(xy 202.227288 -30.635868) (xy 202.23132 -30.7205) (xy 202.227288 -30.805132) (xy 202.21523 -30.888997)
			(xy 202.195254 -30.971337) (xy 202.167542 -31.051404) (xy 202.132344 -31.128475) (xy 202.08998 -31.201851)
			(xy 202.040832 -31.270868) (xy 201.985346 -31.3349) (xy 201.924025 -31.393368) (xy 201.857423 -31.445742)
			(xy 201.786145 -31.491548) (xy 201.710835 -31.530371) (xy 201.632176 -31.56186) (xy 201.550879 -31.585728)
			(xy 201.467682 -31.601761) (xy 201.383338 -31.609813) (xy 201.340974 -31.6103) (xy 201.302684 -31.609905)
			(xy 201.226389 -31.603295) (xy 201.150947 -31.590142) (xy 201.076917 -31.570546) (xy 201.040746 -31.557976)
			(xy 201.032309 -31.555325) (xy 201.014639 -31.555325) (xy 201.006202 -31.557976) (xy 200.970027 -31.570528)
			(xy 200.895993 -31.590099) (xy 200.820553 -31.603244) (xy 200.744262 -31.609866) (xy 200.705974 -31.6103)
			(xy 200.667684 -31.609905) (xy 200.591389 -31.603295) (xy 200.515947 -31.590142) (xy 200.441917 -31.570546)
			(xy 200.405746 -31.557976) (xy 200.397309 -31.555325) (xy 200.379639 -31.555325) (xy 200.371202 -31.557976)
			(xy 200.335027 -31.570528) (xy 200.260993 -31.590099) (xy 200.185553 -31.603244) (xy 200.109262 -31.609866)
			(xy 200.070974 -31.6103) (xy 200.032684 -31.609905) (xy 199.956389 -31.603295) (xy 199.880947 -31.590142)
			(xy 199.806917 -31.570546) (xy 199.770746 -31.557976) (xy 199.762309 -31.555325) (xy 199.744639 -31.555325)
			(xy 199.736202 -31.557976) (xy 199.700027 -31.570528) (xy 199.625993 -31.590099) (xy 199.550553 -31.603244)
			(xy 199.474262 -31.609866) (xy 199.435974 -31.6103) (xy 199.395288 -31.609814) (xy 199.314256 -31.602396)
			(xy 199.23424 -31.587608) (xy 199.15591 -31.565572) (xy 199.07992 -31.536472) (xy 199.006906 -31.500553)
			(xy 198.937478 -31.458114) (xy 198.872217 -31.40951) (xy 198.81167 -31.355148) (xy 198.756341 -31.295482)
			(xy 198.706694 -31.231012) (xy 198.663144 -31.162275) (xy 198.626056 -31.089848) (xy 198.610474 -31.052262)
			(xy 198.605924 -31.042441) (xy 198.590335 -31.027459) (xy 198.569982 -31.020164) (xy 198.559166 -31.020512)
			(xy 198.540911 -31.021927) (xy 198.504324 -31.023454) (xy 198.486014 -31.02356) (xy 198.443652 -31.023076)
			(xy 198.359312 -31.015024) (xy 198.276119 -30.998991) (xy 198.194827 -30.975123) (xy 198.116172 -30.943635)
			(xy 198.040866 -30.904813) (xy 197.969592 -30.859009) (xy 197.902994 -30.806637) (xy 197.841676 -30.748171)
			(xy 197.786193 -30.684142) (xy 197.737048 -30.615128) (xy 197.694686 -30.541756) (xy 197.65949 -30.464688)
			(xy 197.631779 -30.384624) (xy 197.611805 -30.302289) (xy 197.599747 -30.218428) (xy 197.595716 -30.1338)
			(xy 18.63109 -30.1338) (xy 18.633025 -30.16973) (xy 18.633652 -30.329344) (xy 18.626321 -30.488792)
			(xy 18.611051 -30.647675) (xy 18.587881 -30.8056) (xy 18.556867 -30.962174) (xy 18.518086 -31.117007)
			(xy 18.471636 -31.269714) (xy 18.417631 -31.419917) (xy 18.356206 -31.56724) (xy 18.287514 -31.711318)
			(xy 18.211725 -31.851793) (xy 18.129028 -31.988316) (xy 18.039629 -32.120546) (xy 17.943749 -32.248156)
			(xy 17.841627 -32.370828) (xy 17.733517 -32.488256) (xy 17.619688 -32.60015) (xy 17.500423 -32.70623)
			(xy 17.376019 -32.806234) (xy 17.246784 -32.899911) (xy 17.173557 -32.94761) (xy 102.642416 -32.94761)
			(xy 102.642416 -31.95701) (xy 102.642902 -31.929759) (xy 102.650658 -31.875811) (xy 102.666013 -31.823516)
			(xy 102.688655 -31.773939) (xy 102.718121 -31.728089) (xy 102.753812 -31.686898) (xy 102.795003 -31.651207)
			(xy 102.840853 -31.621741) (xy 102.89043 -31.599099) (xy 102.942725 -31.583744) (xy 102.996673 -31.575988)
			(xy 103.051175 -31.575988) (xy 103.105123 -31.583744) (xy 103.157418 -31.599099) (xy 103.206995 -31.621741)
			(xy 103.252845 -31.651207) (xy 103.294036 -31.686898) (xy 103.329727 -31.728089) (xy 103.359193 -31.773939)
			(xy 103.381835 -31.823516) (xy 103.39719 -31.875811) (xy 103.404946 -31.929759) (xy 103.405432 -31.95701)
			(xy 103.405432 -32.405066) (xy 105.659936 -32.405066) (xy 105.659936 -31.541466) (xy 105.660422 -31.514215)
			(xy 105.668178 -31.460267) (xy 105.683533 -31.407972) (xy 105.706175 -31.358395) (xy 105.735641 -31.312545)
			(xy 105.771332 -31.271354) (xy 105.812523 -31.235663) (xy 105.858373 -31.206197) (xy 105.90795 -31.183555)
			(xy 105.960245 -31.1682) (xy 106.014193 -31.160444) (xy 106.068695 -31.160444) (xy 106.122643 -31.1682)
			(xy 106.174938 -31.183555) (xy 106.224515 -31.206197) (xy 106.270365 -31.235663) (xy 106.311556 -31.271354)
			(xy 106.347247 -31.312545) (xy 106.376713 -31.358395) (xy 106.399355 -31.407972) (xy 106.41471 -31.460267)
			(xy 106.422466 -31.514215) (xy 106.422952 -31.541466) (xy 106.422952 -31.65856) (xy 140.278612 -31.65856)
			(xy 140.278612 -30.79496) (xy 140.279098 -30.767709) (xy 140.286854 -30.713761) (xy 140.302209 -30.661466)
			(xy 140.324851 -30.611889) (xy 140.354317 -30.566039) (xy 140.390008 -30.524848) (xy 140.431199 -30.489157)
			(xy 140.477049 -30.459691) (xy 140.526626 -30.437049) (xy 140.578921 -30.421694) (xy 140.632869 -30.413938)
			(xy 140.687371 -30.413938) (xy 140.741319 -30.421694) (xy 140.793614 -30.437049) (xy 140.843191 -30.459691)
			(xy 140.889041 -30.489157) (xy 140.930232 -30.524848) (xy 140.965923 -30.566039) (xy 140.995389 -30.611889)
			(xy 141.018031 -30.661466) (xy 141.033386 -30.713761) (xy 141.041142 -30.767709) (xy 141.041628 -30.79496)
			(xy 141.041628 -31.65856) (xy 141.041311 -31.67634) (xy 144.616932 -31.67634) (xy 144.616932 -30.81274)
			(xy 144.617418 -30.785489) (xy 144.625174 -30.731541) (xy 144.640529 -30.679246) (xy 144.663171 -30.629669)
			(xy 144.692637 -30.583819) (xy 144.728328 -30.542628) (xy 144.769519 -30.506937) (xy 144.815369 -30.477471)
			(xy 144.864946 -30.454829) (xy 144.917241 -30.439474) (xy 144.971189 -30.431718) (xy 145.025691 -30.431718)
			(xy 145.079639 -30.439474) (xy 145.131934 -30.454829) (xy 145.181511 -30.477471) (xy 145.227361 -30.506937)
			(xy 145.268552 -30.542628) (xy 145.304243 -30.583819) (xy 145.333709 -30.629669) (xy 145.356351 -30.679246)
			(xy 145.371706 -30.731541) (xy 145.379462 -30.785489) (xy 145.379948 -30.81274) (xy 145.379948 -31.67634)
			(xy 145.379462 -31.703591) (xy 145.371706 -31.757539) (xy 145.356351 -31.809834) (xy 145.333709 -31.859411)
			(xy 145.304243 -31.905261) (xy 145.268552 -31.946452) (xy 145.227361 -31.982143) (xy 145.181511 -32.011609)
			(xy 145.131934 -32.034251) (xy 145.079639 -32.049606) (xy 145.025691 -32.057362) (xy 144.971189 -32.057362)
			(xy 144.917241 -32.049606) (xy 144.864946 -32.034251) (xy 144.815369 -32.011609) (xy 144.769519 -31.982143)
			(xy 144.728328 -31.946452) (xy 144.692637 -31.905261) (xy 144.663171 -31.859411) (xy 144.640529 -31.809834)
			(xy 144.625174 -31.757539) (xy 144.617418 -31.703591) (xy 144.616932 -31.67634) (xy 141.041311 -31.67634)
			(xy 141.041142 -31.685811) (xy 141.033386 -31.739759) (xy 141.018031 -31.792054) (xy 140.995389 -31.841631)
			(xy 140.965923 -31.887481) (xy 140.930232 -31.928672) (xy 140.889041 -31.964363) (xy 140.843191 -31.993829)
			(xy 140.793614 -32.016471) (xy 140.741319 -32.031826) (xy 140.687371 -32.039582) (xy 140.632869 -32.039582)
			(xy 140.578921 -32.031826) (xy 140.526626 -32.016471) (xy 140.477049 -31.993829) (xy 140.431199 -31.964363)
			(xy 140.390008 -31.928672) (xy 140.354317 -31.887481) (xy 140.324851 -31.841631) (xy 140.302209 -31.792054)
			(xy 140.286854 -31.739759) (xy 140.279098 -31.685811) (xy 140.278612 -31.65856) (xy 106.422952 -31.65856)
			(xy 106.422952 -32.405066) (xy 106.422466 -32.432317) (xy 106.41471 -32.486265) (xy 106.399355 -32.53856)
			(xy 106.376713 -32.588137) (xy 106.347247 -32.633987) (xy 106.311556 -32.675178) (xy 106.270365 -32.710869)
			(xy 106.224515 -32.740335) (xy 106.174938 -32.762977) (xy 106.122643 -32.778332) (xy 106.068695 -32.786088)
			(xy 106.014193 -32.786088) (xy 105.960245 -32.778332) (xy 105.90795 -32.762977) (xy 105.858373 -32.740335)
			(xy 105.812523 -32.710869) (xy 105.771332 -32.675178) (xy 105.735641 -32.633987) (xy 105.706175 -32.588137)
			(xy 105.683533 -32.53856) (xy 105.668178 -32.486265) (xy 105.660422 -32.432317) (xy 105.659936 -32.405066)
			(xy 103.405432 -32.405066) (xy 103.405432 -32.94761) (xy 103.404946 -32.974861) (xy 103.39719 -33.028809)
			(xy 103.390276 -33.052356) (xy 119.734235 -33.052356) (xy 119.734235 -32.997844) (xy 119.741993 -32.943888)
			(xy 119.757352 -32.891585) (xy 119.779997 -32.842) (xy 119.80947 -32.796143) (xy 119.845169 -32.754947)
			(xy 119.886367 -32.719252) (xy 119.932226 -32.689783) (xy 119.981813 -32.667141) (xy 120.034117 -32.651787)
			(xy 120.088074 -32.644033) (xy 120.11533 -32.643572) (xy 120.97893 -32.643572) (xy 121.006178 -32.6441)
			(xy 121.06012 -32.65186) (xy 121.112408 -32.667217) (xy 121.161979 -32.689858) (xy 121.207823 -32.719324)
			(xy 121.249008 -32.755014) (xy 121.284694 -32.796201) (xy 121.314156 -32.842047) (xy 121.336794 -32.89162)
			(xy 121.352147 -32.943909) (xy 121.359902 -32.997852) (xy 121.359902 -33.052348) (xy 121.352147 -33.106291)
			(xy 121.336794 -33.15858) (xy 121.314156 -33.208153) (xy 121.284694 -33.253999) (xy 121.249008 -33.295186)
			(xy 121.207823 -33.330876) (xy 121.161979 -33.360342) (xy 121.112408 -33.382983) (xy 121.06012 -33.39834)
			(xy 121.006178 -33.4061) (xy 120.97893 -33.406588) (xy 120.11533 -33.406588) (xy 120.088074 -33.406167)
			(xy 120.034117 -33.398413) (xy 119.981813 -33.383059) (xy 119.932226 -33.360417) (xy 119.886367 -33.330948)
			(xy 119.845169 -33.295253) (xy 119.80947 -33.254057) (xy 119.779997 -33.2082) (xy 119.757352 -33.158615)
			(xy 119.741993 -33.106312) (xy 119.734235 -33.052356) (xy 103.390276 -33.052356) (xy 103.381835 -33.081104)
			(xy 103.359193 -33.130681) (xy 103.329727 -33.176531) (xy 103.294036 -33.217722) (xy 103.252845 -33.253413)
			(xy 103.206995 -33.282879) (xy 103.157418 -33.305521) (xy 103.105123 -33.320876) (xy 103.051175 -33.328632)
			(xy 102.996673 -33.328632) (xy 102.942725 -33.320876) (xy 102.89043 -33.305521) (xy 102.840853 -33.282879)
			(xy 102.795003 -33.253413) (xy 102.753812 -33.217722) (xy 102.718121 -33.176531) (xy 102.688655 -33.130681)
			(xy 102.666013 -33.081104) (xy 102.650658 -33.028809) (xy 102.642902 -32.974861) (xy 102.642416 -32.94761)
			(xy 17.173557 -32.94761) (xy 17.11304 -32.98703) (xy 16.975119 -33.067374) (xy 16.833366 -33.140743)
			(xy 16.688131 -33.206955) (xy 16.539776 -33.265845) (xy 16.38867 -33.317266) (xy 16.235188 -33.361091)
			(xy 16.079713 -33.397211) (xy 15.922631 -33.425536) (xy 15.764332 -33.445995) (xy 15.605209 -33.458538)
			(xy 15.44566 -33.463134) (xy 15.286079 -33.459771) (xy 15.126865 -33.448457) (xy 14.968413 -33.42922)
			(xy 14.811116 -33.402109) (xy 14.655367 -33.367191) (xy 14.501552 -33.324553) (xy 14.350053 -33.2743)
			(xy 14.201248 -33.216557) (xy 14.055506 -33.151469) (xy 13.91319 -33.079197) (xy 13.774653 -32.999921)
			(xy 13.64024 -32.913837) (xy 13.510286 -32.82116) (xy 13.385112 -32.72212) (xy 13.265032 -32.616964)
			(xy 13.150342 -32.505953) (xy 13.095478 -32.447992) (xy 12.00277 -31.279592) (xy 11.948692 -31.220903)
			(xy 11.845626 -31.099035) (xy 11.748763 -30.972182) (xy 11.658343 -30.840658) (xy 11.574591 -30.704792)
			(xy 11.497716 -30.564919) (xy 11.427907 -30.421388) (xy 11.36534 -30.274557) (xy 11.310169 -30.124789)
			(xy 11.262532 -29.972457) (xy 11.222547 -29.81794) (xy 11.190314 -29.661623) (xy 11.165912 -29.503893)
			(xy 11.149402 -29.345143) (xy 11.140826 -29.185767) (xy 11.140205 -29.026161) (xy 0.509016 -29.026161)
			(xy 0.509016 -33.838388) (xy 122.111008 -33.838388) (xy 122.111008 -32.974788) (xy 122.111494 -32.947519)
			(xy 122.119256 -32.893535) (xy 122.134621 -32.841205) (xy 122.157278 -32.791595) (xy 122.186764 -32.745714)
			(xy 122.222479 -32.704497) (xy 122.263696 -32.668782) (xy 122.309577 -32.639296) (xy 122.359187 -32.616639)
			(xy 122.411517 -32.601274) (xy 122.465501 -32.593512) (xy 122.520039 -32.593512) (xy 122.574023 -32.601274)
			(xy 122.626353 -32.616639) (xy 122.675963 -32.639296) (xy 122.721844 -32.668782) (xy 122.763061 -32.704497)
			(xy 122.798776 -32.745714) (xy 122.828262 -32.791595) (xy 122.850919 -32.841205) (xy 122.866284 -32.893535)
			(xy 122.874046 -32.947519) (xy 122.874532 -32.974788) (xy 122.874532 -33.413556) (xy 124.175423 -33.413556)
			(xy 124.175423 -33.359044) (xy 124.183181 -33.305087) (xy 124.198539 -33.252783) (xy 124.221185 -33.203197)
			(xy 124.250658 -33.157339) (xy 124.286357 -33.116142) (xy 124.327555 -33.080446) (xy 124.373415 -33.050976)
			(xy 124.423002 -33.028332) (xy 124.475306 -33.012977) (xy 124.529264 -33.005222) (xy 124.55652 -33.00476)
			(xy 125.42012 -33.00476) (xy 125.447368 -33.005312) (xy 125.501309 -33.01307) (xy 125.553597 -33.028425)
			(xy 125.603167 -33.051066) (xy 125.649011 -33.08053) (xy 125.690196 -33.116218) (xy 125.725882 -33.157405)
			(xy 125.755344 -33.20325) (xy 125.777982 -33.252822) (xy 125.793335 -33.305111) (xy 125.80109 -33.359052)
			(xy 125.80109 -33.413548) (xy 125.793335 -33.467489) (xy 125.777982 -33.519778) (xy 125.755344 -33.56935)
			(xy 125.725882 -33.615195) (xy 125.690196 -33.656382) (xy 125.649011 -33.69207) (xy 125.603167 -33.721534)
			(xy 125.553597 -33.744175) (xy 125.501309 -33.75953) (xy 125.447368 -33.767288) (xy 125.42012 -33.767776)
			(xy 124.55652 -33.767776) (xy 124.529264 -33.767378) (xy 124.475306 -33.759623) (xy 124.423002 -33.744268)
			(xy 124.373415 -33.721624) (xy 124.327555 -33.692154) (xy 124.286357 -33.656458) (xy 124.250658 -33.615261)
			(xy 124.221185 -33.569403) (xy 124.198539 -33.519817) (xy 124.183181 -33.467513) (xy 124.175423 -33.413556)
			(xy 122.874532 -33.413556) (xy 122.874532 -33.838388) (xy 122.874046 -33.865657) (xy 122.866284 -33.919641)
			(xy 122.850919 -33.971971) (xy 122.828262 -34.021581) (xy 122.798776 -34.067462) (xy 122.763061 -34.108679)
			(xy 122.721844 -34.144394) (xy 122.675963 -34.17388) (xy 122.626353 -34.196537) (xy 122.574023 -34.211902)
			(xy 122.520039 -34.219664) (xy 122.465501 -34.219664) (xy 122.411517 -34.211902) (xy 122.359187 -34.196537)
			(xy 122.309577 -34.17388) (xy 122.263696 -34.144394) (xy 122.222479 -34.108679) (xy 122.186764 -34.067462)
			(xy 122.157278 -34.021581) (xy 122.134621 -33.971971) (xy 122.119256 -33.919641) (xy 122.111494 -33.865657)
			(xy 122.111008 -33.838388) (xy 0.509016 -33.838388) (xy 0.509016 -36.080556) (xy 122.143423 -36.080556)
			(xy 122.143423 -36.026044) (xy 122.151181 -35.972087) (xy 122.166539 -35.919783) (xy 122.189185 -35.870197)
			(xy 122.218658 -35.824339) (xy 122.254357 -35.783142) (xy 122.295555 -35.747446) (xy 122.341415 -35.717976)
			(xy 122.391002 -35.695332) (xy 122.443306 -35.679977) (xy 122.497264 -35.672222) (xy 122.52452 -35.67176)
			(xy 123.38812 -35.67176) (xy 123.415368 -35.672312) (xy 123.469309 -35.68007) (xy 123.521597 -35.695425)
			(xy 123.571167 -35.718066) (xy 123.617011 -35.74753) (xy 123.658196 -35.783218) (xy 123.693882 -35.824405)
			(xy 123.723344 -35.87025) (xy 123.745982 -35.919822) (xy 123.761335 -35.972111) (xy 123.76909 -36.026052)
			(xy 123.76909 -36.080548) (xy 123.761335 -36.134489) (xy 123.745982 -36.186778) (xy 123.723344 -36.23635)
			(xy 123.693882 -36.282195) (xy 123.658196 -36.323382) (xy 123.617011 -36.35907) (xy 123.571167 -36.388534)
			(xy 123.521597 -36.411175) (xy 123.469309 -36.42653) (xy 123.415368 -36.434288) (xy 123.38812 -36.434776)
			(xy 122.52452 -36.434776) (xy 122.497264 -36.434378) (xy 122.443306 -36.426623) (xy 122.391002 -36.411268)
			(xy 122.341415 -36.388624) (xy 122.295555 -36.359154) (xy 122.254357 -36.323458) (xy 122.218658 -36.282261)
			(xy 122.189185 -36.236403) (xy 122.166539 -36.186817) (xy 122.151181 -36.134513) (xy 122.143423 -36.080556)
			(xy 0.509016 -36.080556) (xy 0.509016 -39.23137) (xy 9.080235 -39.23137) (xy 9.080235 -39.10223)
			(xy 9.088185 -38.973335) (xy 9.104055 -38.845175) (xy 9.127784 -38.718234) (xy 9.159283 -38.592995)
			(xy 9.198432 -38.469932) (xy 9.245083 -38.349513) (xy 9.299058 -38.232194) (xy 9.360153 -38.11842)
			(xy 9.428136 -38.008623) (xy 9.50275 -37.90322) (xy 9.583711 -37.80261) (xy 9.670711 -37.707175)
			(xy 9.763422 -37.617276) (xy 9.861492 -37.533255) (xy 9.964547 -37.455431) (xy 10.072198 -37.384099)
			(xy 10.184037 -37.319529) (xy 10.299638 -37.261967) (xy 10.418563 -37.21163) (xy 10.540362 -37.16871)
			(xy 10.664572 -37.133369) (xy 10.790721 -37.105742) (xy 10.918333 -37.085933) (xy 11.046922 -37.074017)
			(xy 11.176 -37.070041) (xy 11.305078 -37.074017) (xy 11.433667 -37.085933) (xy 11.521898 -37.099629)
			(xy 170.60087 -37.099629) (xy 170.60087 -37.000299) (xy 170.608862 -36.901292) (xy 170.624796 -36.803249)
			(xy 170.648567 -36.706806) (xy 170.680022 -36.612588) (xy 170.718955 -36.521208) (xy 170.765116 -36.433256)
			(xy 170.818204 -36.349304) (xy 170.877875 -36.269895) (xy 170.943743 -36.195546) (xy 171.01538 -36.126738)
			(xy 171.092321 -36.063918) (xy 171.174067 -36.007493) (xy 171.260089 -35.957828) (xy 171.349828 -35.915246)
			(xy 171.442702 -35.880024) (xy 171.53811 -35.852388) (xy 171.635432 -35.83252) (xy 171.734037 -35.820547)
			(xy 171.833286 -35.816548) (xy 171.932535 -35.820547) (xy 172.03114 -35.83252) (xy 172.128462 -35.852388)
			(xy 172.22387 -35.880024) (xy 172.316744 -35.915246) (xy 172.406483 -35.957828) (xy 172.492505 -36.007493)
			(xy 172.574251 -36.063918) (xy 172.651192 -36.126738) (xy 172.722829 -36.195546) (xy 172.788697 -36.269895)
			(xy 172.848368 -36.349304) (xy 172.901456 -36.433256) (xy 172.947617 -36.521208) (xy 172.98655 -36.612588)
			(xy 173.018005 -36.706806) (xy 173.041776 -36.803249) (xy 173.05771 -36.901292) (xy 173.065702 -37.000299)
			(xy 173.066202 -37.049964) (xy 173.065702 -37.099629) (xy 173.05771 -37.198636) (xy 173.041776 -37.296679)
			(xy 173.034033 -37.328094) (xy 197.270624 -37.328094) (xy 197.271107 -37.28698) (xy 197.278695 -37.205103)
			(xy 197.293804 -37.124275) (xy 197.316307 -37.045187) (xy 197.346011 -36.968512) (xy 197.382664 -36.894904)
			(xy 197.425951 -36.824993) (xy 197.475504 -36.759373) (xy 197.5309 -36.698606) (xy 197.591667 -36.643209)
			(xy 197.657286 -36.593655) (xy 197.727197 -36.550367) (xy 197.800804 -36.513715) (xy 197.877479 -36.48401)
			(xy 197.956568 -36.461506) (xy 198.037395 -36.446396) (xy 198.119272 -36.438808) (xy 198.160386 -36.438332)
			(xy 198.203952 -36.438853) (xy 198.290667 -36.447372) (xy 198.376134 -36.464329) (xy 198.459533 -36.489562)
			(xy 198.540065 -36.522829) (xy 198.616958 -36.563811) (xy 198.689475 -36.612116) (xy 198.756921 -36.66728)
			(xy 198.81865 -36.728775) (xy 198.87407 -36.796011) (xy 198.922649 -36.868345) (xy 198.963923 -36.945081)
			(xy 198.997496 -37.025486) (xy 199.010778 -37.066982) (xy 199.013703 -37.075249) (xy 199.024271 -37.089233)
			(xy 199.038923 -37.098854) (xy 199.047354 -37.101272) (xy 199.088321 -37.111837) (xy 199.168226 -37.13965)
			(xy 199.24513 -37.174922) (xy 199.318339 -37.217334) (xy 199.387193 -37.266504) (xy 199.451068 -37.321986)
			(xy 199.509389 -37.383281) (xy 199.529427 -37.408809) (xy 207.619596 -37.408809) (xy 207.619596 -37.324087)
			(xy 207.627649 -37.23975) (xy 207.643683 -37.15656) (xy 207.667551 -37.07527) (xy 207.699039 -36.996618)
			(xy 207.737861 -36.921315) (xy 207.783664 -36.850043) (xy 207.836035 -36.783447) (xy 207.8945 -36.722132)
			(xy 207.958528 -36.666651) (xy 208.02754 -36.617508) (xy 208.10091 -36.575148) (xy 208.177975 -36.539953)
			(xy 208.258037 -36.512244) (xy 208.34037 -36.49227) (xy 208.424229 -36.480213) (xy 208.508854 -36.476182)
			(xy 208.593479 -36.480213) (xy 208.677338 -36.49227) (xy 208.759671 -36.512244) (xy 208.839733 -36.539953)
			(xy 208.916798 -36.575148) (xy 208.990168 -36.617508) (xy 209.05918 -36.666651) (xy 209.123208 -36.722132)
			(xy 209.181673 -36.783447) (xy 209.234044 -36.850043) (xy 209.279847 -36.921315) (xy 209.318669 -36.996618)
			(xy 209.350157 -37.07527) (xy 209.374025 -37.15656) (xy 209.390059 -37.23975) (xy 209.398112 -37.324087)
			(xy 209.398616 -37.366448) (xy 209.398112 -37.408809) (xy 209.390059 -37.493146) (xy 209.374025 -37.576336)
			(xy 209.350157 -37.657626) (xy 209.318669 -37.736278) (xy 209.279847 -37.811581) (xy 209.234044 -37.882853)
			(xy 209.181673 -37.949449) (xy 209.123208 -38.010764) (xy 209.05918 -38.066245) (xy 208.990168 -38.115388)
			(xy 208.916798 -38.157748) (xy 208.839733 -38.192943) (xy 208.759671 -38.220652) (xy 208.677338 -38.240626)
			(xy 208.593479 -38.252683) (xy 208.508854 -38.256715) (xy 208.424229 -38.252683) (xy 208.34037 -38.240626)
			(xy 208.258037 -38.220652) (xy 208.177975 -38.192943) (xy 208.10091 -38.157748) (xy 208.02754 -38.115388)
			(xy 207.958528 -38.066245) (xy 207.8945 -38.010764) (xy 207.836035 -37.949449) (xy 207.783664 -37.882853)
			(xy 207.737861 -37.811581) (xy 207.699039 -37.736278) (xy 207.667551 -37.657626) (xy 207.643683 -37.576336)
			(xy 207.627649 -37.493146) (xy 207.619596 -37.408809) (xy 199.529427 -37.408809) (xy 199.561629 -37.449835)
			(xy 199.607316 -37.521047) (xy 199.646037 -37.596273) (xy 199.677444 -37.674835) (xy 199.701252 -37.756024)
			(xy 199.717247 -37.839106) (xy 199.725284 -37.92333) (xy 199.725788 -37.965634) (xy 199.72532 -38.006748)
			(xy 199.71773 -38.088625) (xy 199.702618 -38.169453) (xy 199.680113 -38.248541) (xy 199.650407 -38.325216)
			(xy 199.613754 -38.398823) (xy 199.570465 -38.468734) (xy 199.520911 -38.534353) (xy 199.465514 -38.595119)
			(xy 199.404746 -38.650516) (xy 199.339127 -38.70007) (xy 199.269216 -38.743357) (xy 199.195608 -38.78001)
			(xy 199.118933 -38.809716) (xy 199.039845 -38.83222) (xy 198.959017 -38.847331) (xy 198.87714 -38.85492)
			(xy 198.836026 -38.855396) (xy 198.792461 -38.854844) (xy 198.705747 -38.846327) (xy 198.620282 -38.829372)
			(xy 198.536884 -38.804141) (xy 198.456353 -38.770876) (xy 198.379461 -38.729896) (xy 198.306944 -38.681594)
			(xy 198.239498 -38.626432) (xy 198.177769 -38.56494) (xy 198.122348 -38.497707) (xy 198.073767 -38.425377)
			(xy 198.032492 -38.348643) (xy 197.998917 -38.26824) (xy 197.985634 -38.226746) (xy 197.982688 -38.218487)
			(xy 197.97213 -38.204501) (xy 197.957486 -38.194877) (xy 197.949058 -38.192456) (xy 197.908101 -38.181857)
			(xy 197.828197 -38.154046) (xy 197.751293 -38.118776) (xy 197.678085 -38.076367) (xy 197.609232 -38.0272)
			(xy 197.545356 -37.97172) (xy 197.487035 -37.910428) (xy 197.434795 -37.843877) (xy 197.389107 -37.772668)
			(xy 197.350384 -37.697444) (xy 197.318976 -37.618885) (xy 197.295165 -37.537699) (xy 197.279169 -37.454619)
			(xy 197.271129 -37.370397) (xy 197.270624 -37.328094) (xy 173.034033 -37.328094) (xy 173.018005 -37.393122)
			(xy 172.98655 -37.48734) (xy 172.947617 -37.57872) (xy 172.901456 -37.666672) (xy 172.848368 -37.750624)
			(xy 172.788697 -37.830033) (xy 172.722829 -37.904382) (xy 172.651192 -37.97319) (xy 172.574251 -38.03601)
			(xy 172.492505 -38.092435) (xy 172.406483 -38.1421) (xy 172.316744 -38.184682) (xy 172.22387 -38.219904)
			(xy 172.128462 -38.24754) (xy 172.03114 -38.267408) (xy 171.932535 -38.279381) (xy 171.833286 -38.283381)
			(xy 171.734037 -38.279381) (xy 171.635432 -38.267408) (xy 171.53811 -38.24754) (xy 171.442702 -38.219904)
			(xy 171.349828 -38.184682) (xy 171.260089 -38.1421) (xy 171.174067 -38.092435) (xy 171.092321 -38.03601)
			(xy 171.01538 -37.97319) (xy 170.943743 -37.904382) (xy 170.877875 -37.830033) (xy 170.818204 -37.750624)
			(xy 170.765116 -37.666672) (xy 170.718955 -37.57872) (xy 170.680022 -37.48734) (xy 170.648567 -37.393122)
			(xy 170.624796 -37.296679) (xy 170.608862 -37.198636) (xy 170.60087 -37.099629) (xy 11.521898 -37.099629)
			(xy 11.561279 -37.105742) (xy 11.687428 -37.133369) (xy 11.811638 -37.16871) (xy 11.933437 -37.21163)
			(xy 12.052362 -37.261967) (xy 12.167963 -37.319529) (xy 12.279802 -37.384099) (xy 12.387453 -37.455431)
			(xy 12.490508 -37.533255) (xy 12.588578 -37.617276) (xy 12.681289 -37.707175) (xy 12.768289 -37.80261)
			(xy 12.84925 -37.90322) (xy 12.923864 -38.008623) (xy 12.991847 -38.11842) (xy 13.052942 -38.232194)
			(xy 13.106917 -38.349513) (xy 13.153568 -38.469932) (xy 13.192717 -38.592995) (xy 13.224216 -38.718234)
			(xy 13.247945 -38.845175) (xy 13.263815 -38.973335) (xy 13.271765 -39.10223) (xy 13.272262 -39.1668)
			(xy 13.271765 -39.23137) (xy 13.263815 -39.360265) (xy 13.256012 -39.423283) (xy 254.45872 -39.423283)
			(xy 254.45872 -39.338561) (xy 254.466773 -39.254224) (xy 254.482807 -39.171034) (xy 254.506675 -39.089744)
			(xy 254.538163 -39.011092) (xy 254.576985 -38.935789) (xy 254.622788 -38.864517) (xy 254.675159 -38.797921)
			(xy 254.733624 -38.736606) (xy 254.797652 -38.681125) (xy 254.866664 -38.631982) (xy 254.940034 -38.589622)
			(xy 255.017099 -38.554427) (xy 255.097161 -38.526718) (xy 255.179494 -38.506744) (xy 255.263353 -38.494687)
			(xy 255.347978 -38.490656) (xy 255.432603 -38.494687) (xy 255.516462 -38.506744) (xy 255.598795 -38.526718)
			(xy 255.678857 -38.554427) (xy 255.755922 -38.589622) (xy 255.829292 -38.631982) (xy 255.898304 -38.681125)
			(xy 255.962332 -38.736606) (xy 256.020797 -38.797921) (xy 256.073168 -38.864517) (xy 256.118971 -38.935789)
			(xy 256.157793 -39.011092) (xy 256.189281 -39.089744) (xy 256.213149 -39.171034) (xy 256.229183 -39.254224)
			(xy 256.237236 -39.338561) (xy 256.23774 -39.380922) (xy 256.237236 -39.423283) (xy 256.229183 -39.50762)
			(xy 256.213149 -39.59081) (xy 256.189281 -39.6721) (xy 256.157793 -39.750752) (xy 256.118971 -39.826055)
			(xy 256.073168 -39.897327) (xy 256.020797 -39.963923) (xy 255.962332 -40.025238) (xy 255.898304 -40.080719)
			(xy 255.829292 -40.129862) (xy 255.755922 -40.172222) (xy 255.678857 -40.207417) (xy 255.598795 -40.235126)
			(xy 255.516462 -40.2551) (xy 255.432603 -40.267157) (xy 255.347978 -40.271189) (xy 255.263353 -40.267157)
			(xy 255.179494 -40.2551) (xy 255.097161 -40.235126) (xy 255.017099 -40.207417) (xy 254.940034 -40.172222)
			(xy 254.866664 -40.129862) (xy 254.797652 -40.080719) (xy 254.733624 -40.025238) (xy 254.675159 -39.963923)
			(xy 254.622788 -39.897327) (xy 254.576985 -39.826055) (xy 254.538163 -39.750752) (xy 254.506675 -39.6721)
			(xy 254.482807 -39.59081) (xy 254.466773 -39.50762) (xy 254.45872 -39.423283) (xy 13.256012 -39.423283)
			(xy 13.247945 -39.488425) (xy 13.224216 -39.615366) (xy 13.192717 -39.740605) (xy 13.153568 -39.863668)
			(xy 13.106917 -39.984087) (xy 13.052942 -40.101406) (xy 12.991847 -40.21518) (xy 12.923864 -40.324977)
			(xy 12.84925 -40.43038) (xy 12.768289 -40.53099) (xy 12.681289 -40.626425) (xy 12.588578 -40.716324)
			(xy 12.490508 -40.800345) (xy 12.413317 -40.858637) (xy 24.936192 -40.858637) (xy 24.936192 -40.773915)
			(xy 24.944245 -40.689578) (xy 24.960279 -40.606388) (xy 24.984147 -40.525098) (xy 25.015635 -40.446446)
			(xy 25.054457 -40.371143) (xy 25.10026 -40.299871) (xy 25.152631 -40.233275) (xy 25.211096 -40.17196)
			(xy 25.275124 -40.116479) (xy 25.344136 -40.067336) (xy 25.417506 -40.024976) (xy 25.494571 -39.989781)
			(xy 25.574633 -39.962072) (xy 25.656966 -39.942098) (xy 25.740825 -39.930041) (xy 25.82545 -39.92601)
			(xy 25.910075 -39.930041) (xy 25.993934 -39.942098) (xy 26.076267 -39.962072) (xy 26.156329 -39.989781)
			(xy 26.233394 -40.024976) (xy 26.306764 -40.067336) (xy 26.375776 -40.116479) (xy 26.439804 -40.17196)
			(xy 26.498269 -40.233275) (xy 26.55064 -40.299871) (xy 26.596443 -40.371143) (xy 26.635265 -40.446446)
			(xy 26.666753 -40.525098) (xy 26.690621 -40.606388) (xy 26.706655 -40.689578) (xy 26.711938 -40.744902)
			(xy 235.083357 -40.744902) (xy 235.087362 -40.656994) (xy 235.099345 -40.569814) (xy 235.119205 -40.484085)
			(xy 235.14678 -40.400517) (xy 235.181839 -40.319803) (xy 235.224092 -40.242611) (xy 235.27319 -40.169582)
			(xy 235.328726 -40.10132) (xy 235.390238 -40.03839) (xy 235.457219 -39.981316) (xy 235.529112 -39.930568)
			(xy 235.605321 -39.886568) (xy 235.685216 -39.849681) (xy 235.768135 -39.820212) (xy 235.85339 -39.798405)
			(xy 235.940274 -39.784441) (xy 236.028068 -39.778435) (xy 236.116045 -39.780439) (xy 236.203475 -39.790434)
			(xy 236.289634 -39.808338) (xy 236.373808 -39.834002) (xy 236.455299 -39.867215) (xy 236.533433 -39.907701)
			(xy 236.607561 -39.955123) (xy 236.677069 -40.00909) (xy 236.741383 -40.069155) (xy 236.799967 -40.134819)
			(xy 236.852338 -40.205538) (xy 236.898061 -40.280726) (xy 236.936758 -40.359761) (xy 236.968107 -40.441987)
			(xy 236.991849 -40.526723) (xy 237.007787 -40.613267) (xy 237.015789 -40.700902) (xy 237.01629 -40.744902)
			(xy 237.015789 -40.788902) (xy 237.007787 -40.876537) (xy 236.994276 -40.9499) (xy 246.935452 -40.9499)
			(xy 246.939482 -40.865295) (xy 246.951537 -40.781456) (xy 246.971506 -40.699142) (xy 246.999209 -40.619099)
			(xy 247.034396 -40.542053) (xy 247.076747 -40.468699) (xy 247.125879 -40.399704) (xy 247.181347 -40.335692)
			(xy 247.242648 -40.277242) (xy 247.309228 -40.224883) (xy 247.380484 -40.179091) (xy 247.45577 -40.14028)
			(xy 247.534404 -40.1088) (xy 247.615675 -40.084938) (xy 247.698846 -40.06891) (xy 247.783163 -40.060859)
			(xy 247.825514 -40.060372) (xy 247.868043 -40.060872) (xy 247.952713 -40.068982) (xy 248.036223 -40.085137)
			(xy 248.11781 -40.109189) (xy 248.196728 -40.140918) (xy 248.272258 -40.180035) (xy 248.343709 -40.226182)
			(xy 248.41043 -40.278938) (xy 248.441464 -40.308022) (xy 248.441718 -40.308276) (xy 248.44904 -40.314652)
			(xy 248.467069 -40.321822) (xy 248.47677 -40.322246) (xy 248.557288 -40.321992) (xy 248.575576 -40.314626)
			(xy 248.582688 -40.307514) (xy 248.613778 -40.278057) (xy 248.680689 -40.224588) (xy 248.752429 -40.177798)
			(xy 248.828335 -40.13812) (xy 248.907704 -40.105923) (xy 248.9898 -40.081504) (xy 249.073863 -40.065089)
			(xy 249.159115 -40.056831) (xy 249.20194 -40.056308) (xy 249.202448 -40.056308) (xy 249.244796 -40.056782)
			(xy 249.329107 -40.064837) (xy 249.412272 -40.08087) (xy 249.493536 -40.104735) (xy 249.572163 -40.136216)
			(xy 249.647442 -40.175029) (xy 249.718691 -40.220821) (xy 249.785265 -40.273178) (xy 249.84656 -40.331627)
			(xy 249.902022 -40.395637) (xy 249.951149 -40.464629) (xy 249.993496 -40.537978) (xy 250.028678 -40.615021)
			(xy 250.056379 -40.695058) (xy 250.076346 -40.777367) (xy 250.088399 -40.8612) (xy 250.092429 -40.9458)
			(xy 250.088399 -41.0304) (xy 250.076346 -41.114233) (xy 250.056379 -41.196542) (xy 250.028678 -41.276579)
			(xy 249.993496 -41.353622) (xy 249.951149 -41.426971) (xy 249.902022 -41.495963) (xy 249.84656 -41.559973)
			(xy 249.785265 -41.618422) (xy 249.718691 -41.670779) (xy 249.647442 -41.716571) (xy 249.572163 -41.755384)
			(xy 249.493536 -41.786865) (xy 249.412272 -41.81073) (xy 249.329107 -41.826763) (xy 249.244796 -41.834818)
			(xy 249.202448 -41.835324) (xy 249.159919 -41.834822) (xy 249.07525 -41.826709) (xy 248.991741 -41.810552)
			(xy 248.910155 -41.7865) (xy 248.831237 -41.754771) (xy 248.755707 -41.715655) (xy 248.684255 -41.66951)
			(xy 248.617533 -41.616756) (xy 248.586498 -41.587674) (xy 248.586244 -41.58742) (xy 248.578903 -41.58107)
			(xy 248.560888 -41.573885) (xy 248.551192 -41.57345) (xy 248.470674 -41.573704) (xy 248.452386 -41.58107)
			(xy 248.445274 -41.588182) (xy 248.414201 -41.617657) (xy 248.347287 -41.671125) (xy 248.275544 -41.717913)
			(xy 248.199635 -41.757589) (xy 248.120264 -41.789784) (xy 248.038166 -41.8142) (xy 247.954101 -41.830612)
			(xy 247.868848 -41.838866) (xy 247.826022 -41.839388) (xy 247.825514 -41.839388) (xy 247.783163 -41.838941)
			(xy 247.698846 -41.83089) (xy 247.615675 -41.814862) (xy 247.534404 -41.791) (xy 247.45577 -41.75952)
			(xy 247.380484 -41.720709) (xy 247.309228 -41.674917) (xy 247.242648 -41.622558) (xy 247.181347 -41.564108)
			(xy 247.125879 -41.500096) (xy 247.076747 -41.431101) (xy 247.034396 -41.357747) (xy 246.999209 -41.280701)
			(xy 246.971506 -41.200658) (xy 246.951537 -41.118344) (xy 246.939482 -41.034505) (xy 246.935452 -40.9499)
			(xy 236.994276 -40.9499) (xy 236.991849 -40.963081) (xy 236.968107 -41.047817) (xy 236.936758 -41.130043)
			(xy 236.898061 -41.209078) (xy 236.852338 -41.284266) (xy 236.799967 -41.354985) (xy 236.741383 -41.420649)
			(xy 236.677069 -41.480714) (xy 236.607561 -41.534681) (xy 236.533433 -41.582103) (xy 236.455299 -41.622589)
			(xy 236.373808 -41.655802) (xy 236.289634 -41.681466) (xy 236.203475 -41.69937) (xy 236.116045 -41.709365)
			(xy 236.028068 -41.711369) (xy 235.940274 -41.705363) (xy 235.85339 -41.691399) (xy 235.768135 -41.669592)
			(xy 235.685216 -41.640123) (xy 235.605321 -41.603236) (xy 235.529112 -41.559236) (xy 235.457219 -41.508488)
			(xy 235.390238 -41.451414) (xy 235.328726 -41.388484) (xy 235.27319 -41.320222) (xy 235.224092 -41.247193)
			(xy 235.181839 -41.170001) (xy 235.14678 -41.089287) (xy 235.119205 -41.005719) (xy 235.099345 -40.91999)
			(xy 235.087362 -40.83281) (xy 235.083357 -40.744902) (xy 26.711938 -40.744902) (xy 26.714708 -40.773915)
			(xy 26.715212 -40.816276) (xy 26.714708 -40.858637) (xy 26.706655 -40.942974) (xy 26.690621 -41.026164)
			(xy 26.666753 -41.107454) (xy 26.635265 -41.186106) (xy 26.596443 -41.261409) (xy 26.55064 -41.332681)
			(xy 26.498269 -41.399277) (xy 26.439804 -41.460592) (xy 26.375776 -41.516073) (xy 26.306764 -41.565216)
			(xy 26.233394 -41.607576) (xy 26.156329 -41.642771) (xy 26.076267 -41.67048) (xy 25.993934 -41.690454)
			(xy 25.910075 -41.702511) (xy 25.82545 -41.706543) (xy 25.740825 -41.702511) (xy 25.656966 -41.690454)
			(xy 25.574633 -41.67048) (xy 25.494571 -41.642771) (xy 25.417506 -41.607576) (xy 25.344136 -41.565216)
			(xy 25.275124 -41.516073) (xy 25.211096 -41.460592) (xy 25.152631 -41.399277) (xy 25.10026 -41.332681)
			(xy 25.054457 -41.261409) (xy 25.015635 -41.186106) (xy 24.984147 -41.107454) (xy 24.960279 -41.026164)
			(xy 24.944245 -40.942974) (xy 24.936192 -40.858637) (xy 12.413317 -40.858637) (xy 12.387453 -40.878169)
			(xy 12.279802 -40.949501) (xy 12.167963 -41.014071) (xy 12.052362 -41.071633) (xy 11.933437 -41.12197)
			(xy 11.811638 -41.16489) (xy 11.687428 -41.200231) (xy 11.561279 -41.227858) (xy 11.433667 -41.247667)
			(xy 11.305078 -41.259583) (xy 11.176 -41.26356) (xy 11.046922 -41.259583) (xy 10.918333 -41.247667)
			(xy 10.790721 -41.227858) (xy 10.664572 -41.200231) (xy 10.540362 -41.16489) (xy 10.418563 -41.12197)
			(xy 10.299638 -41.071633) (xy 10.184037 -41.014071) (xy 10.072198 -40.949501) (xy 9.964547 -40.878169)
			(xy 9.861492 -40.800345) (xy 9.763422 -40.716324) (xy 9.670711 -40.626425) (xy 9.583711 -40.53099)
			(xy 9.50275 -40.43038) (xy 9.428136 -40.324977) (xy 9.360153 -40.21518) (xy 9.299058 -40.101406)
			(xy 9.245083 -39.984087) (xy 9.198432 -39.863668) (xy 9.159283 -39.740605) (xy 9.127784 -39.615366)
			(xy 9.104055 -39.488425) (xy 9.088185 -39.360265) (xy 9.080235 -39.23137) (xy 0.509016 -39.23137)
			(xy 0.509016 -43.481752) (xy 178.630072 -43.481752) (xy 178.630072 -42.618152) (xy 178.630558 -42.590883)
			(xy 178.63832 -42.536899) (xy 178.653685 -42.484569) (xy 178.676342 -42.434959) (xy 178.705828 -42.389078)
			(xy 178.741543 -42.347861) (xy 178.78276 -42.312146) (xy 178.828641 -42.28266) (xy 178.878251 -42.260003)
			(xy 178.930581 -42.244638) (xy 178.984565 -42.236876) (xy 179.039103 -42.236876) (xy 179.093087 -42.244638)
			(xy 179.145417 -42.260003) (xy 179.195027 -42.28266) (xy 179.240908 -42.312146) (xy 179.282125 -42.347861)
			(xy 179.31784 -42.389078) (xy 179.347326 -42.434959) (xy 179.369983 -42.484569) (xy 179.385348 -42.536899)
			(xy 179.39311 -42.590883) (xy 179.393596 -42.618152) (xy 179.393596 -43.481752) (xy 179.39311 -43.509021)
			(xy 179.385348 -43.563005) (xy 179.369983 -43.615335) (xy 179.347326 -43.664945) (xy 179.31784 -43.710826)
			(xy 179.282125 -43.752043) (xy 179.240908 -43.787758) (xy 179.195027 -43.817244) (xy 179.145417 -43.839901)
			(xy 179.093087 -43.855266) (xy 179.039103 -43.863028) (xy 178.984565 -43.863028) (xy 178.930581 -43.855266)
			(xy 178.878251 -43.839901) (xy 178.828641 -43.817244) (xy 178.78276 -43.787758) (xy 178.741543 -43.752043)
			(xy 178.705828 -43.710826) (xy 178.676342 -43.664945) (xy 178.653685 -43.615335) (xy 178.63832 -43.563005)
			(xy 178.630558 -43.509021) (xy 178.630072 -43.481752) (xy 0.509016 -43.481752) (xy 0.509016 -47.04994)
			(xy 59.582066 -47.04994) (xy 59.586045 -46.890389) (xy 59.597972 -46.731234) (xy 59.617818 -46.572872)
			(xy 59.645532 -46.415696) (xy 59.681047 -46.260096) (xy 59.724273 -46.10646) (xy 59.775104 -45.95517)
			(xy 59.833413 -45.806602) (xy 59.899054 -45.661125) (xy 59.971866 -45.519101) (xy 60.051666 -45.380882)
			(xy 60.138257 -45.246813) (xy 60.231423 -45.117227) (xy 60.330933 -44.992446) (xy 60.436538 -44.87278)
			(xy 60.547978 -44.758527) (xy 60.664973 -44.649971) (xy 60.787235 -44.547381) (xy 60.914458 -44.451014)
			(xy 61.046326 -44.361107) (xy 61.182512 -44.277886) (xy 61.322677 -44.201556) (xy 61.466472 -44.132307)
			(xy 61.613541 -44.070313) (xy 61.763517 -44.015726) (xy 61.916027 -43.968683) (xy 62.070693 -43.9293)
			(xy 62.227129 -43.897676) (xy 62.384947 -43.873888) (xy 62.543755 -43.857997) (xy 62.703158 -43.850041)
			(xy 62.782958 -43.849544) (xy 64.382904 -43.849544) (xy 64.462705 -43.850033) (xy 64.622107 -43.857989)
			(xy 64.780916 -43.87388) (xy 64.938734 -43.897668) (xy 65.095171 -43.929293) (xy 65.249837 -43.968675)
			(xy 65.402347 -44.015719) (xy 65.552323 -44.070306) (xy 65.699392 -44.132301) (xy 65.843188 -44.201549)
			(xy 65.983353 -44.277879) (xy 66.119539 -44.361101) (xy 66.251408 -44.451008) (xy 66.378631 -44.547376)
			(xy 66.500893 -44.649966) (xy 66.617889 -44.758522) (xy 66.729328 -44.872775) (xy 66.834934 -44.992442)
			(xy 66.934444 -45.117223) (xy 67.02761 -45.246809) (xy 67.114201 -45.380878) (xy 67.194001 -45.519097)
			(xy 67.266813 -45.661122) (xy 67.332455 -45.806599) (xy 67.390764 -45.955168) (xy 67.441595 -46.106458)
			(xy 67.484821 -46.260094) (xy 67.520336 -46.415694) (xy 67.54805 -46.572871) (xy 67.567896 -46.731233)
			(xy 67.579823 -46.890388) (xy 67.583802 -47.04994) (xy 89.78165 -47.04994) (xy 89.78563 -46.895439)
			(xy 89.797557 -46.741349) (xy 89.817402 -46.588076) (xy 89.84511 -46.436028) (xy 89.880608 -46.285609)
			(xy 89.923803 -46.137216) (xy 89.97458 -45.991243) (xy 90.032804 -45.848078) (xy 90.098321 -45.708101)
			(xy 90.170957 -45.571681) (xy 90.250519 -45.439181) (xy 90.336796 -45.310953) (xy 90.42956 -45.187337)
			(xy 90.528565 -45.068659) (xy 90.633548 -44.955236) (xy 90.74423 -44.847368) (xy 90.860319 -44.74534)
			(xy 90.981506 -44.649424) (xy 91.10747 -44.559873) (xy 91.237877 -44.476926) (xy 91.372381 -44.400801)
			(xy 91.510626 -44.331702) (xy 91.652244 -44.269811) (xy 91.796861 -44.215293) (xy 91.944092 -44.168291)
			(xy 92.093548 -44.128931) (xy 92.244832 -44.097317) (xy 92.397543 -44.073533) (xy 92.551275 -44.057642)
			(xy 92.705622 -44.049686) (xy 92.782898 -44.049188) (xy 94.383098 -44.049188) (xy 94.460374 -44.049669)
			(xy 94.614722 -44.057625) (xy 94.768456 -44.073516) (xy 94.921168 -44.0973) (xy 95.072452 -44.128914)
			(xy 95.221909 -44.168274) (xy 95.369142 -44.215276) (xy 95.513759 -44.269795) (xy 95.655379 -44.331686)
			(xy 95.793624 -44.400785) (xy 95.928129 -44.47691) (xy 96.058537 -44.559858) (xy 96.184502 -44.649409)
			(xy 96.30569 -44.745326) (xy 96.421779 -44.847354) (xy 96.532463 -44.955223) (xy 96.555487 -44.980098)
			(xy 181.659784 -44.980098) (xy 181.659784 -44.116498) (xy 181.66027 -44.089229) (xy 181.668032 -44.035245)
			(xy 181.683397 -43.982915) (xy 181.706054 -43.933305) (xy 181.73554 -43.887424) (xy 181.771255 -43.846207)
			(xy 181.812472 -43.810492) (xy 181.858353 -43.781006) (xy 181.907963 -43.758349) (xy 181.960293 -43.742984)
			(xy 182.014277 -43.735222) (xy 182.068815 -43.735222) (xy 182.122799 -43.742984) (xy 182.175129 -43.758349)
			(xy 182.224739 -43.781006) (xy 182.27062 -43.810492) (xy 182.311837 -43.846207) (xy 182.347552 -43.887424)
			(xy 182.377038 -43.933305) (xy 182.399695 -43.982915) (xy 182.412218 -44.025566) (xy 236.740192 -44.025566)
			(xy 236.74068 -43.984453) (xy 236.74827 -43.902577) (xy 236.763381 -43.82175) (xy 236.785886 -43.742663)
			(xy 236.815591 -43.665989) (xy 236.852243 -43.592383) (xy 236.895531 -43.522473) (xy 236.945083 -43.456854)
			(xy 237.000479 -43.396088) (xy 237.061245 -43.340691) (xy 237.126863 -43.291137) (xy 237.196773 -43.247849)
			(xy 237.270378 -43.211196) (xy 237.347052 -43.181489) (xy 237.426139 -43.158984) (xy 237.506965 -43.143872)
			(xy 237.588841 -43.136281) (xy 237.629954 -43.135804) (xy 237.672596 -43.136331) (xy 237.757484 -43.144543)
			(xy 237.841197 -43.160838) (xy 237.922968 -43.185068) (xy 237.962694 -43.200574) (xy 237.971356 -43.203655)
			(xy 237.989722 -43.204046) (xy 237.998508 -43.201336) (xy 238.034032 -43.189272) (xy 238.106663 -43.170452)
			(xy 238.18062 -43.157817) (xy 238.25538 -43.151455) (xy 238.292894 -43.151044) (xy 238.332166 -43.151496)
			(xy 238.410399 -43.158477) (xy 238.487712 -43.172332) (xy 238.563501 -43.192954) (xy 238.600488 -43.206162)
			(xy 238.609037 -43.208926) (xy 238.626991 -43.208926) (xy 238.63554 -43.206162) (xy 238.672533 -43.192975)
			(xy 238.748323 -43.172363) (xy 238.825633 -43.158506) (xy 238.903863 -43.151512) (xy 238.943134 -43.151044)
			(xy 238.981423 -43.151469) (xy 239.057717 -43.158071) (xy 239.133159 -43.171215) (xy 239.207191 -43.190803)
			(xy 239.243362 -43.203368) (xy 239.251799 -43.206019) (xy 239.269469 -43.206019) (xy 239.277906 -43.203368)
			(xy 239.314089 -43.190839) (xy 239.38812 -43.171262) (xy 239.463558 -43.158111) (xy 239.539846 -43.151482)
			(xy 239.578134 -43.151044) (xy 239.616423 -43.151469) (xy 239.692717 -43.158071) (xy 239.768159 -43.171215)
			(xy 239.842191 -43.190803) (xy 239.878362 -43.203368) (xy 239.886799 -43.206019) (xy 239.904469 -43.206019)
			(xy 239.912906 -43.203368) (xy 239.949089 -43.190839) (xy 240.02312 -43.171262) (xy 240.098558 -43.158111)
			(xy 240.174846 -43.151482) (xy 240.213134 -43.151044) (xy 240.25606 -43.151581) (xy 240.341511 -43.159862)
			(xy 240.425768 -43.176335) (xy 240.508046 -43.200846) (xy 240.587581 -43.233168) (xy 240.613613 -43.246802)
			(xy 243.62918 -43.246802) (xy 243.629584 -43.208512) (xy 243.636192 -43.132218) (xy 243.649342 -43.056775)
			(xy 243.668936 -42.982745) (xy 243.681504 -42.946574) (xy 243.684156 -42.938137) (xy 243.684156 -42.920466)
			(xy 243.681504 -42.91203) (xy 243.668959 -42.875853) (xy 243.649386 -42.80182) (xy 243.636239 -42.72638)
			(xy 243.629616 -42.65009) (xy 243.62918 -42.611802) (xy 243.629684 -42.569441) (xy 243.637737 -42.485104)
			(xy 243.653771 -42.401914) (xy 243.677639 -42.320624) (xy 243.709127 -42.241972) (xy 243.747949 -42.166669)
			(xy 243.793752 -42.095397) (xy 243.846123 -42.028801) (xy 243.904588 -41.967486) (xy 243.968616 -41.912005)
			(xy 244.037628 -41.862862) (xy 244.110998 -41.820502) (xy 244.188063 -41.785307) (xy 244.268125 -41.757598)
			(xy 244.350458 -41.737624) (xy 244.434317 -41.725567) (xy 244.518942 -41.721536) (xy 244.603567 -41.725567)
			(xy 244.687426 -41.737624) (xy 244.769759 -41.757598) (xy 244.849821 -41.785307) (xy 244.926886 -41.820502)
			(xy 245.000256 -41.862862) (xy 245.069268 -41.912005) (xy 245.133296 -41.967486) (xy 245.191761 -42.028801)
			(xy 245.244132 -42.095397) (xy 245.289935 -42.166669) (xy 245.328757 -42.241972) (xy 245.360245 -42.320624)
			(xy 245.384113 -42.401914) (xy 245.400147 -42.485104) (xy 245.4082 -42.569441) (xy 245.408704 -42.611802)
			(xy 245.408302 -42.650092) (xy 245.401694 -42.726386) (xy 245.388543 -42.801829) (xy 245.368949 -42.875859)
			(xy 245.35638 -42.91203) (xy 245.353727 -42.920466) (xy 245.353728 -42.938137) (xy 245.35638 -42.946574)
			(xy 245.368926 -42.982751) (xy 245.388499 -43.056784) (xy 245.401645 -43.132224) (xy 245.408269 -43.208514)
			(xy 245.408704 -43.246802) (xy 245.4082 -43.289163) (xy 245.400147 -43.3735) (xy 245.384113 -43.45669)
			(xy 245.360245 -43.53798) (xy 245.328757 -43.616632) (xy 245.289935 -43.691935) (xy 245.244132 -43.763207)
			(xy 245.191761 -43.829803) (xy 245.133296 -43.891118) (xy 245.069268 -43.946599) (xy 245.000256 -43.995742)
			(xy 244.926886 -44.038102) (xy 244.849821 -44.073297) (xy 244.769759 -44.101006) (xy 244.687426 -44.12098)
			(xy 244.603567 -44.133037) (xy 244.518942 -44.137069) (xy 244.434317 -44.133037) (xy 244.350458 -44.12098)
			(xy 244.268125 -44.101006) (xy 244.188063 -44.073297) (xy 244.110998 -44.038102) (xy 244.037628 -43.995742)
			(xy 243.968616 -43.946599) (xy 243.904588 -43.891118) (xy 243.846123 -43.829803) (xy 243.793752 -43.763207)
			(xy 243.747949 -43.691935) (xy 243.709127 -43.616632) (xy 243.677639 -43.53798) (xy 243.653771 -43.45669)
			(xy 243.637737 -43.3735) (xy 243.629684 -43.289163) (xy 243.62918 -43.246802) (xy 240.613613 -43.246802)
			(xy 240.663633 -43.272999) (xy 240.735496 -43.31997) (xy 240.802501 -43.373643) (xy 240.864025 -43.433521)
			(xy 240.919496 -43.499046) (xy 240.968398 -43.569608) (xy 241.010277 -43.644552) (xy 241.044744 -43.723182)
			(xy 241.071477 -43.804765) (xy 241.090229 -43.888544) (xy 241.096038 -43.931078) (xy 241.097792 -43.94092)
			(xy 241.107661 -43.958279) (xy 241.123386 -43.970587) (xy 241.132868 -43.97375) (xy 241.172506 -43.985287)
			(xy 241.249638 -44.014728) (xy 241.32371 -44.051189) (xy 241.394086 -44.094356) (xy 241.460159 -44.143858)
			(xy 241.521362 -44.199269) (xy 241.577167 -44.260112) (xy 241.627095 -44.325864) (xy 241.670716 -44.395959)
			(xy 241.707655 -44.469795) (xy 241.737594 -44.546735) (xy 241.760276 -44.626118) (xy 241.775505 -44.707261)
			(xy 241.78315 -44.789466) (xy 241.783616 -44.830746) (xy 241.783231 -44.871862) (xy 241.775639 -44.953744)
			(xy 241.760525 -45.034576) (xy 241.738017 -45.113668) (xy 241.708307 -45.190346) (xy 241.671649 -45.263956)
			(xy 241.628355 -45.333869) (xy 241.578796 -45.39949) (xy 241.523393 -45.460258) (xy 241.462619 -45.515654)
			(xy 241.396993 -45.565207) (xy 241.327075 -45.608494) (xy 241.253462 -45.645144) (xy 241.176781 -45.674846)
			(xy 241.097686 -45.697346) (xy 241.016853 -45.712452) (xy 240.93497 -45.720035) (xy 240.893854 -45.720508)
			(xy 240.848047 -45.719908) (xy 240.756919 -45.710469) (xy 240.667241 -45.691726) (xy 240.579961 -45.663878)
			(xy 240.537746 -45.646086) (xy 240.528923 -45.642621) (xy 240.509997 -45.641842) (xy 240.500916 -45.644562)
			(xy 240.454475 -45.659757) (xy 240.359116 -45.681105) (xy 240.261993 -45.691873) (xy 240.213134 -45.692568)
			(xy 240.174844 -45.692152) (xy 240.09855 -45.685547) (xy 240.023108 -45.672401) (xy 239.949077 -45.652811)
			(xy 239.912906 -45.640244) (xy 239.904469 -45.637593) (xy 239.886799 -45.637593) (xy 239.878362 -45.640244)
			(xy 239.842183 -45.652782) (xy 239.76815 -45.672357) (xy 239.692711 -45.685505) (xy 239.616422 -45.692131)
			(xy 239.578134 -45.692568) (xy 239.539844 -45.692152) (xy 239.46355 -45.685547) (xy 239.388108 -45.672401)
			(xy 239.314077 -45.652811) (xy 239.277906 -45.640244) (xy 239.269469 -45.637593) (xy 239.251799 -45.637593)
			(xy 239.243362 -45.640244) (xy 239.207183 -45.652782) (xy 239.13315 -45.672357) (xy 239.057711 -45.685505)
			(xy 238.981422 -45.692131) (xy 238.943134 -45.692568) (xy 238.903862 -45.692107) (xy 238.825629 -45.685129)
			(xy 238.748316 -45.671276) (xy 238.672527 -45.650657) (xy 238.63554 -45.63745) (xy 238.626991 -45.634686)
			(xy 238.609037 -45.634686) (xy 238.600488 -45.63745) (xy 238.563502 -45.650659) (xy 238.48771 -45.671265)
			(xy 238.410397 -45.685115) (xy 238.332165 -45.692103) (xy 238.292894 -45.692568) (xy 238.24936 -45.692039)
			(xy 238.16271 -45.683524) (xy 238.077306 -45.666586) (xy 237.993965 -45.641387) (xy 237.913484 -45.608168)
			(xy 237.87481 -45.588174) (xy 237.86657 -45.584248) (xy 237.848476 -45.581916) (xy 237.839504 -45.583602)
			(xy 237.790399 -45.594167) (xy 237.690592 -45.6055) (xy 237.640368 -45.606208) (xy 237.640114 -45.606208)
			(xy 237.599001 -45.605674) (xy 237.517127 -45.598088) (xy 237.436301 -45.582981) (xy 237.357214 -45.560481)
			(xy 237.280541 -45.53078) (xy 237.206935 -45.494131) (xy 237.137024 -45.450847) (xy 237.071406 -45.401297)
			(xy 237.010639 -45.345904) (xy 236.955242 -45.285141) (xy 236.905687 -45.219525) (xy 236.862399 -45.149618)
			(xy 236.825745 -45.076014) (xy 236.796038 -44.999343) (xy 236.773533 -44.920257) (xy 236.75842 -44.839433)
			(xy 236.750829 -44.757559) (xy 236.750352 -44.716446) (xy 236.750814 -44.676228) (xy 236.758123 -44.596123)
			(xy 236.772622 -44.517004) (xy 236.794193 -44.439513) (xy 236.80801 -44.40174) (xy 236.811025 -44.392621)
			(xy 236.810769 -44.373433) (xy 236.807502 -44.364402) (xy 236.791394 -44.324025) (xy 236.766206 -44.240819)
			(xy 236.749266 -44.15555) (xy 236.740738 -44.069034) (xy 236.740192 -44.025566) (xy 182.412218 -44.025566)
			(xy 182.41506 -44.035245) (xy 182.422822 -44.089229) (xy 182.423308 -44.116498) (xy 182.423308 -44.980098)
			(xy 182.422822 -45.007367) (xy 182.41506 -45.061351) (xy 182.399695 -45.113681) (xy 182.377038 -45.163291)
			(xy 182.347552 -45.209172) (xy 182.311837 -45.250389) (xy 182.27062 -45.286104) (xy 182.224739 -45.31559)
			(xy 182.175129 -45.338247) (xy 182.122799 -45.353612) (xy 182.068815 -45.361374) (xy 182.014277 -45.361374)
			(xy 181.960293 -45.353612) (xy 181.907963 -45.338247) (xy 181.858353 -45.31559) (xy 181.812472 -45.286104)
			(xy 181.771255 -45.250389) (xy 181.73554 -45.209172) (xy 181.706054 -45.163291) (xy 181.683397 -45.113681)
			(xy 181.668032 -45.061351) (xy 181.66027 -45.007367) (xy 181.659784 -44.980098) (xy 96.555487 -44.980098)
			(xy 96.637446 -45.068647) (xy 96.736452 -45.187325) (xy 96.829216 -45.310943) (xy 96.915495 -45.439171)
			(xy 96.995057 -45.571672) (xy 97.067693 -45.708092) (xy 97.133211 -45.848071) (xy 97.191435 -45.991237)
			(xy 97.242212 -46.13721) (xy 97.285407 -46.285604) (xy 97.320906 -46.436025) (xy 97.329238 -46.481746)
			(xy 178.630072 -46.481746) (xy 178.630072 -45.618146) (xy 178.630558 -45.590877) (xy 178.63832 -45.536893)
			(xy 178.653685 -45.484563) (xy 178.676342 -45.434953) (xy 178.705828 -45.389072) (xy 178.741543 -45.347855)
			(xy 178.78276 -45.31214) (xy 178.828641 -45.282654) (xy 178.878251 -45.259997) (xy 178.930581 -45.244632)
			(xy 178.984565 -45.23687) (xy 179.039103 -45.23687) (xy 179.093087 -45.244632) (xy 179.145417 -45.259997)
			(xy 179.195027 -45.282654) (xy 179.240908 -45.31214) (xy 179.282125 -45.347855) (xy 179.31784 -45.389072)
			(xy 179.347326 -45.434953) (xy 179.369983 -45.484563) (xy 179.385348 -45.536893) (xy 179.39311 -45.590877)
			(xy 179.393596 -45.618146) (xy 179.393596 -46.481746) (xy 179.39311 -46.509015) (xy 179.385348 -46.562999)
			(xy 179.369983 -46.615329) (xy 179.347326 -46.664939) (xy 179.31784 -46.71082) (xy 179.282125 -46.752037)
			(xy 179.240908 -46.787752) (xy 179.195027 -46.817238) (xy 179.145417 -46.839895) (xy 179.093087 -46.85526)
			(xy 179.039103 -46.863022) (xy 178.984565 -46.863022) (xy 178.930581 -46.85526) (xy 178.878251 -46.839895)
			(xy 178.828641 -46.817238) (xy 178.78276 -46.787752) (xy 178.741543 -46.752037) (xy 178.705828 -46.71082)
			(xy 178.676342 -46.664939) (xy 178.653685 -46.615329) (xy 178.63832 -46.562999) (xy 178.630558 -46.509015)
			(xy 178.630072 -46.481746) (xy 97.329238 -46.481746) (xy 97.348615 -46.588073) (xy 97.368459 -46.741347)
			(xy 97.380387 -46.895438) (xy 97.384366 -47.04994) (xy 97.380387 -47.204442) (xy 97.368459 -47.358533)
			(xy 97.348615 -47.511807) (xy 97.320906 -47.663855) (xy 97.285407 -47.814276) (xy 97.242212 -47.96267)
			(xy 97.219453 -48.028098) (xy 181.659784 -48.028098) (xy 181.659784 -47.164498) (xy 181.66027 -47.137229)
			(xy 181.668032 -47.083245) (xy 181.683397 -47.030915) (xy 181.706054 -46.981305) (xy 181.73554 -46.935424)
			(xy 181.771255 -46.894207) (xy 181.812472 -46.858492) (xy 181.858353 -46.829006) (xy 181.907963 -46.806349)
			(xy 181.960293 -46.790984) (xy 182.014277 -46.783222) (xy 182.068815 -46.783222) (xy 182.122799 -46.790984)
			(xy 182.175129 -46.806349) (xy 182.224739 -46.829006) (xy 182.27062 -46.858492) (xy 182.311837 -46.894207)
			(xy 182.347552 -46.935424) (xy 182.377038 -46.981305) (xy 182.399695 -47.030915) (xy 182.41506 -47.083245)
			(xy 182.422822 -47.137229) (xy 182.423308 -47.164498) (xy 182.423308 -48.028098) (xy 182.422822 -48.055367)
			(xy 182.41506 -48.109351) (xy 182.399695 -48.161681) (xy 182.377038 -48.211291) (xy 182.347552 -48.257172)
			(xy 182.311837 -48.298389) (xy 182.27062 -48.334104) (xy 182.224739 -48.36359) (xy 182.175129 -48.386247)
			(xy 182.122799 -48.401612) (xy 182.068815 -48.409374) (xy 182.014277 -48.409374) (xy 181.960293 -48.401612)
			(xy 181.907963 -48.386247) (xy 181.858353 -48.36359) (xy 181.812472 -48.334104) (xy 181.771255 -48.298389)
			(xy 181.73554 -48.257172) (xy 181.706054 -48.211291) (xy 181.683397 -48.161681) (xy 181.668032 -48.109351)
			(xy 181.66027 -48.055367) (xy 181.659784 -48.028098) (xy 97.219453 -48.028098) (xy 97.191435 -48.108643)
			(xy 97.133211 -48.251809) (xy 97.067693 -48.391788) (xy 96.995057 -48.528208) (xy 96.915495 -48.660709)
			(xy 96.829216 -48.788937) (xy 96.736452 -48.912555) (xy 96.637446 -49.031233) (xy 96.532463 -49.144657)
			(xy 96.421779 -49.252526) (xy 96.30569 -49.354554) (xy 96.184502 -49.450471) (xy 96.140518 -49.48174)
			(xy 178.630072 -49.48174) (xy 178.630072 -48.61814) (xy 178.630558 -48.590871) (xy 178.63832 -48.536887)
			(xy 178.653685 -48.484557) (xy 178.676342 -48.434947) (xy 178.705828 -48.389066) (xy 178.741543 -48.347849)
			(xy 178.78276 -48.312134) (xy 178.828641 -48.282648) (xy 178.878251 -48.259991) (xy 178.930581 -48.244626)
			(xy 178.984565 -48.236864) (xy 179.039103 -48.236864) (xy 179.093087 -48.244626) (xy 179.145417 -48.259991)
			(xy 179.195027 -48.282648) (xy 179.240908 -48.312134) (xy 179.282125 -48.347849) (xy 179.31784 -48.389066)
			(xy 179.347326 -48.434947) (xy 179.369983 -48.484557) (xy 179.385348 -48.536887) (xy 179.39311 -48.590871)
			(xy 179.393596 -48.61814) (xy 179.393596 -49.48174) (xy 179.39311 -49.509009) (xy 179.385348 -49.562993)
			(xy 179.369983 -49.615323) (xy 179.347326 -49.664933) (xy 179.31784 -49.710814) (xy 179.282125 -49.752031)
			(xy 179.240908 -49.787746) (xy 179.195027 -49.817232) (xy 179.145417 -49.839889) (xy 179.093087 -49.855254)
			(xy 179.039103 -49.863016) (xy 178.984565 -49.863016) (xy 178.930581 -49.855254) (xy 178.878251 -49.839889)
			(xy 178.828641 -49.817232) (xy 178.78276 -49.787746) (xy 178.741543 -49.752031) (xy 178.705828 -49.710814)
			(xy 178.676342 -49.664933) (xy 178.653685 -49.615323) (xy 178.63832 -49.562993) (xy 178.630558 -49.509009)
			(xy 178.630072 -49.48174) (xy 96.140518 -49.48174) (xy 96.058537 -49.540022) (xy 95.928129 -49.62297)
			(xy 95.793624 -49.699095) (xy 95.655379 -49.768194) (xy 95.513759 -49.830085) (xy 95.369142 -49.884604)
			(xy 95.221909 -49.931606) (xy 95.072452 -49.970966) (xy 94.921168 -50.00258) (xy 94.768456 -50.026364)
			(xy 94.614722 -50.042255) (xy 94.460374 -50.050211) (xy 94.383098 -50.0507) (xy 92.782898 -50.0507)
			(xy 92.705622 -50.050194) (xy 92.551275 -50.042238) (xy 92.397543 -50.026347) (xy 92.244832 -50.002563)
			(xy 92.093548 -49.970949) (xy 91.944092 -49.931589) (xy 91.796861 -49.884587) (xy 91.652244 -49.830069)
			(xy 91.510626 -49.768178) (xy 91.372381 -49.699079) (xy 91.237877 -49.622954) (xy 91.10747 -49.540007)
			(xy 90.981506 -49.450456) (xy 90.860319 -49.35454) (xy 90.74423 -49.252512) (xy 90.633548 -49.144644)
			(xy 90.528565 -49.031221) (xy 90.42956 -48.912543) (xy 90.336796 -48.788927) (xy 90.250519 -48.660699)
			(xy 90.170957 -48.528199) (xy 90.098321 -48.391779) (xy 90.032804 -48.251802) (xy 89.97458 -48.108637)
			(xy 89.923803 -47.962664) (xy 89.880608 -47.814271) (xy 89.84511 -47.663852) (xy 89.817402 -47.511804)
			(xy 89.797557 -47.358531) (xy 89.78563 -47.204441) (xy 89.78165 -47.04994) (xy 67.583802 -47.04994)
			(xy 67.579823 -47.209492) (xy 67.567896 -47.368647) (xy 67.54805 -47.527009) (xy 67.520336 -47.684186)
			(xy 67.484821 -47.839786) (xy 67.441595 -47.993422) (xy 67.390764 -48.144712) (xy 67.332455 -48.293281)
			(xy 67.266813 -48.438758) (xy 67.194001 -48.580783) (xy 67.114201 -48.719002) (xy 67.02761 -48.853071)
			(xy 66.934444 -48.982657) (xy 66.834934 -49.107438) (xy 66.729328 -49.227105) (xy 66.617889 -49.341358)
			(xy 66.500893 -49.449914) (xy 66.378631 -49.552504) (xy 66.251408 -49.648872) (xy 66.119539 -49.738779)
			(xy 65.983353 -49.822001) (xy 65.843188 -49.898331) (xy 65.699392 -49.967579) (xy 65.552323 -50.029574)
			(xy 65.402347 -50.084161) (xy 65.249837 -50.131205) (xy 65.095171 -50.170587) (xy 64.938734 -50.202212)
			(xy 64.780916 -50.226) (xy 64.622107 -50.241891) (xy 64.462705 -50.249847) (xy 64.382904 -50.250344)
			(xy 62.782958 -50.250344) (xy 62.703158 -50.249839) (xy 62.543755 -50.241883) (xy 62.384947 -50.225992)
			(xy 62.227129 -50.202204) (xy 62.070693 -50.17058) (xy 61.916027 -50.131197) (xy 61.763517 -50.084154)
			(xy 61.613541 -50.029567) (xy 61.466472 -49.967573) (xy 61.322677 -49.898324) (xy 61.182512 -49.821994)
			(xy 61.046326 -49.738773) (xy 60.914458 -49.648866) (xy 60.787235 -49.552499) (xy 60.664973 -49.449909)
			(xy 60.547978 -49.341353) (xy 60.436538 -49.2271) (xy 60.330933 -49.107434) (xy 60.231423 -48.982653)
			(xy 60.138257 -48.853067) (xy 60.051666 -48.718998) (xy 59.971866 -48.580779) (xy 59.899054 -48.438755)
			(xy 59.833413 -48.293278) (xy 59.775104 -48.14471) (xy 59.724273 -47.99342) (xy 59.681047 -47.839784)
			(xy 59.645532 -47.684184) (xy 59.617818 -47.527008) (xy 59.597972 -47.368646) (xy 59.586045 -47.209491)
			(xy 59.582066 -47.04994) (xy 0.509016 -47.04994) (xy 0.509016 -50.949098) (xy 181.659784 -50.949098)
			(xy 181.659784 -50.085498) (xy 181.66027 -50.058229) (xy 181.668032 -50.004245) (xy 181.683397 -49.951915)
			(xy 181.706054 -49.902305) (xy 181.73554 -49.856424) (xy 181.771255 -49.815207) (xy 181.812472 -49.779492)
			(xy 181.858353 -49.750006) (xy 181.907963 -49.727349) (xy 181.960293 -49.711984) (xy 182.014277 -49.704222)
			(xy 182.068815 -49.704222) (xy 182.122799 -49.711984) (xy 182.175129 -49.727349) (xy 182.224739 -49.750006)
			(xy 182.27062 -49.779492) (xy 182.311837 -49.815207) (xy 182.347552 -49.856424) (xy 182.377038 -49.902305)
			(xy 182.399695 -49.951915) (xy 182.41506 -50.004245) (xy 182.422822 -50.058229) (xy 182.423308 -50.085498)
			(xy 182.423308 -50.949098) (xy 182.422822 -50.976367) (xy 182.41506 -51.030351) (xy 182.399695 -51.082681)
			(xy 182.377038 -51.132291) (xy 182.347552 -51.178172) (xy 182.311837 -51.219389) (xy 182.27062 -51.255104)
			(xy 182.224739 -51.28459) (xy 182.175129 -51.307247) (xy 182.122799 -51.322612) (xy 182.068815 -51.330374)
			(xy 182.014277 -51.330374) (xy 181.960293 -51.322612) (xy 181.907963 -51.307247) (xy 181.858353 -51.28459)
			(xy 181.812472 -51.255104) (xy 181.771255 -51.219389) (xy 181.73554 -51.178172) (xy 181.706054 -51.132291)
			(xy 181.683397 -51.082681) (xy 181.668032 -51.030351) (xy 181.66027 -50.976367) (xy 181.659784 -50.949098)
			(xy 0.509016 -50.949098) (xy 0.509016 -52.481734) (xy 178.630072 -52.481734) (xy 178.630072 -51.618134)
			(xy 178.630558 -51.590865) (xy 178.63832 -51.536881) (xy 178.653685 -51.484551) (xy 178.676342 -51.434941)
			(xy 178.705828 -51.38906) (xy 178.741543 -51.347843) (xy 178.78276 -51.312128) (xy 178.828641 -51.282642)
			(xy 178.878251 -51.259985) (xy 178.930581 -51.24462) (xy 178.984565 -51.236858) (xy 179.039103 -51.236858)
			(xy 179.093087 -51.24462) (xy 179.145417 -51.259985) (xy 179.195027 -51.282642) (xy 179.240908 -51.312128)
			(xy 179.282125 -51.347843) (xy 179.31784 -51.38906) (xy 179.347326 -51.434941) (xy 179.369983 -51.484551)
			(xy 179.385348 -51.536881) (xy 179.39311 -51.590865) (xy 179.393596 -51.618134) (xy 179.393596 -51.999896)
			(xy 201.367397 -51.999896) (xy 201.371407 -51.837793) (xy 201.38343 -51.676088) (xy 201.403434 -51.515174)
			(xy 201.431372 -51.355447) (xy 201.467175 -51.197297) (xy 201.510755 -51.041111) (xy 201.562006 -50.887271)
			(xy 201.620802 -50.736154) (xy 201.687 -50.58813) (xy 201.760436 -50.44356) (xy 201.840933 -50.302799)
			(xy 201.928292 -50.166191) (xy 202.0223 -50.034071) (xy 202.122727 -49.906761) (xy 202.229327 -49.784573)
			(xy 202.341839 -49.667807) (xy 202.459987 -49.556748) (xy 202.583484 -49.451667) (xy 202.712026 -49.352823)
			(xy 202.845299 -49.260456) (xy 202.982977 -49.174793) (xy 203.124723 -49.096044) (xy 203.27019 -49.024401)
			(xy 203.419022 -48.960039) (xy 203.570854 -48.903117) (xy 203.725316 -48.853773) (xy 203.882029 -48.812128)
			(xy 204.04061 -48.778283) (xy 204.200671 -48.752323) (xy 204.361819 -48.73431) (xy 204.523661 -48.724289)
			(xy 204.685801 -48.722283) (xy 204.847842 -48.728299) (xy 205.009386 -48.74232) (xy 205.17004 -48.764313)
			(xy 205.32941 -48.794225) (xy 205.487105 -48.831981) (xy 205.64274 -48.877489) (xy 205.795934 -48.930639)
			(xy 205.946312 -48.9913) (xy 206.093507 -49.059323) (xy 206.237157 -49.134542) (xy 206.376912 -49.216773)
			(xy 206.512428 -49.305815) (xy 206.643376 -49.40145) (xy 206.769434 -49.503444) (xy 206.890294 -49.611547)
			(xy 207.00566 -49.725494) (xy 207.115249 -49.845008) (xy 207.218794 -49.969795) (xy 207.316041 -50.09955)
			(xy 207.406753 -50.233955) (xy 207.490706 -50.372682) (xy 207.567696 -50.515391) (xy 207.637535 -50.661732)
			(xy 207.70005 -50.811349) (xy 207.755091 -50.963874) (xy 207.802521 -51.118934) (xy 207.842224 -51.27615)
			(xy 207.874105 -51.435138) (xy 207.898083 -51.595507) (xy 207.914102 -51.756866) (xy 207.922121 -51.91882)
			(xy 207.922622 -51.999896) (xy 207.922121 -52.080972) (xy 207.921092 -52.10175) (xy 244.67947 -52.10175)
			(xy 244.679975 -52.075243) (xy 244.687334 -52.022743) (xy 244.701889 -51.971767) (xy 244.723361 -51.923297)
			(xy 244.751335 -51.878265) (xy 244.785274 -51.837539) (xy 244.824523 -51.801903) (xy 244.868327 -51.772043)
			(xy 244.915843 -51.748534) (xy 244.966156 -51.731829) (xy 244.992144 -51.726592) (xy 245.000543 -51.724726)
			(xy 245.015476 -51.716197) (xy 245.026755 -51.703216) (xy 245.030244 -51.69535) (xy 245.045663 -51.657494)
			(xy 245.082559 -51.584546) (xy 245.125992 -51.515291) (xy 245.175596 -51.450313) (xy 245.230952 -51.39016)
			(xy 245.291595 -51.335341) (xy 245.357011 -51.286316) (xy 245.426649 -51.2435) (xy 245.499922 -51.207254)
			(xy 245.576211 -51.177884) (xy 245.654873 -51.155637) (xy 245.735245 -51.140701) (xy 245.816648 -51.133203)
			(xy 245.857522 -51.13274) (xy 245.899843 -51.133258) (xy 245.984099 -51.14133) (xy 246.067208 -51.157371)
			(xy 246.148416 -51.181236) (xy 246.226989 -51.212708) (xy 246.302217 -51.251503) (xy 246.33809 -51.273964)
			(xy 246.346484 -51.278827) (xy 246.365522 -51.28248) (xy 246.38456 -51.278827) (xy 246.392954 -51.273964)
			(xy 246.42883 -51.25151) (xy 246.504063 -51.212731) (xy 246.582638 -51.181268) (xy 246.663845 -51.157405)
			(xy 246.74695 -51.141356) (xy 246.831202 -51.133268) (xy 246.873522 -51.13274) (xy 246.926862 -51.134518)
			(xy 246.938638 -51.134618) (xy 246.960306 -51.125466) (xy 246.975671 -51.107657) (xy 246.979186 -51.096418)
			(xy 246.990138 -51.056039) (xy 247.018713 -50.977397) (xy 247.054545 -50.901785) (xy 247.097317 -50.829872)
			(xy 247.146653 -50.762292) (xy 247.202115 -50.699642) (xy 247.263214 -50.642477) (xy 247.329411 -50.5913)
			(xy 247.40012 -50.546564) (xy 247.474717 -50.508665) (xy 247.552542 -50.477936) (xy 247.632909 -50.45465)
			(xy 247.715107 -50.439012) (xy 247.79841 -50.431161) (xy 247.840246 -50.430684) (xy 247.883752 -50.431235)
			(xy 247.970347 -50.439729) (xy 248.055699 -50.456641) (xy 248.138991 -50.481809) (xy 248.219426 -50.514992)
			(xy 248.296235 -50.555874) (xy 248.332752 -50.579528) (xy 248.341308 -50.584744) (xy 248.360946 -50.588653)
			(xy 248.380584 -50.584744) (xy 248.38914 -50.579528) (xy 248.425663 -50.555885) (xy 248.50248 -50.515022)
			(xy 248.582916 -50.481847) (xy 248.666204 -50.456676) (xy 248.751551 -50.439749) (xy 248.838142 -50.431227)
			(xy 248.881646 -50.430684) (xy 248.926403 -50.431259) (xy 249.015462 -50.440266) (xy 249.103167 -50.458165)
			(xy 249.188634 -50.484775) (xy 249.270999 -50.519828) (xy 249.349431 -50.562968) (xy 249.386598 -50.58791)
			(xy 249.394939 -50.593062) (xy 249.414052 -50.597328) (xy 249.433374 -50.594144) (xy 249.44197 -50.589434)
			(xy 249.4758 -50.569354) (xy 249.546346 -50.534523) (xy 249.619688 -50.506051) (xy 249.695257 -50.484158)
			(xy 249.772462 -50.469016) (xy 249.850701 -50.460742) (xy 249.890026 -50.45964) (xy 249.889772 -50.4444)
			(xy 249.889772 -50.443892) (xy 249.89024 -50.405527) (xy 249.896983 -50.329093) (xy 249.903234 -50.291238)
			(xy 249.904413 -50.282319) (xy 249.901131 -50.26464) (xy 249.891952 -50.249179) (xy 249.8852 -50.243232)
			(xy 249.851748 -50.215094) (xy 249.789907 -50.153305) (xy 249.734424 -50.08575) (xy 249.685833 -50.01308)
			(xy 249.644603 -49.935995) (xy 249.61113 -49.855239) (xy 249.585738 -49.771589) (xy 249.568671 -49.685852)
			(xy 249.560094 -49.598855) (xy 249.559572 -49.555146) (xy 249.560076 -49.512785) (xy 249.568129 -49.428448)
			(xy 249.584163 -49.345258) (xy 249.608031 -49.263968) (xy 249.639519 -49.185316) (xy 249.678341 -49.110013)
			(xy 249.724144 -49.038741) (xy 249.776515 -48.972145) (xy 249.83498 -48.91083) (xy 249.899008 -48.855349)
			(xy 249.96802 -48.806206) (xy 250.04139 -48.763846) (xy 250.118455 -48.728651) (xy 250.198517 -48.700942)
			(xy 250.28085 -48.680968) (xy 250.364709 -48.668911) (xy 250.449334 -48.66488) (xy 250.533959 -48.668911)
			(xy 250.617818 -48.680968) (xy 250.700151 -48.700942) (xy 250.780213 -48.728651) (xy 250.857278 -48.763846)
			(xy 250.930648 -48.806206) (xy 250.99966 -48.855349) (xy 251.063688 -48.91083) (xy 251.122153 -48.972145)
			(xy 251.174524 -49.038741) (xy 251.220327 -49.110013) (xy 251.259149 -49.185316) (xy 251.290637 -49.263968)
			(xy 251.314505 -49.345258) (xy 251.330539 -49.428448) (xy 251.338592 -49.512785) (xy 251.339096 -49.555146)
			(xy 251.338636 -49.593574) (xy 251.331894 -49.670136) (xy 251.325634 -49.708054) (xy 251.324473 -49.716974)
			(xy 251.32775 -49.73465) (xy 251.336921 -49.750111) (xy 251.343668 -49.75606) (xy 251.362142 -49.771471)
			(xy 251.397596 -49.803999) (xy 251.414534 -49.821084) (xy 251.422676 -49.828571) (xy 251.443355 -49.836348)
			(xy 251.454412 -49.83607) (xy 251.469822 -49.835031) (xy 251.50069 -49.833886) (xy 251.516134 -49.833784)
			(xy 251.557251 -49.834166) (xy 251.639133 -49.841757) (xy 251.719966 -49.85687) (xy 251.79906 -49.879378)
			(xy 251.875739 -49.909087) (xy 251.94935 -49.945745) (xy 252.019265 -49.989039) (xy 252.084886 -50.038598)
			(xy 252.145655 -50.094001) (xy 252.201053 -50.154775) (xy 252.250607 -50.220401) (xy 252.293894 -50.29032)
			(xy 252.330545 -50.363934) (xy 252.360248 -50.440616) (xy 252.382748 -50.519712) (xy 252.397854 -50.600546)
			(xy 252.405438 -50.682429) (xy 252.405896 -50.723546) (xy 252.405358 -50.767341) (xy 252.396743 -50.854506)
			(xy 252.379599 -50.940401) (xy 252.354094 -51.024196) (xy 252.320474 -51.105076) (xy 252.300232 -51.143916)
			(xy 252.29478 -51.15537) (xy 252.2948 -51.18071) (xy 252.300232 -51.192176) (xy 252.320452 -51.231026)
			(xy 252.354062 -51.311909) (xy 252.379567 -51.3957) (xy 252.39672 -51.481592) (xy 252.405355 -51.568752)
			(xy 252.405896 -51.612546) (xy 252.405358 -51.656341) (xy 252.396743 -51.743506) (xy 252.379599 -51.829401)
			(xy 252.354094 -51.913196) (xy 252.320474 -51.994076) (xy 252.317441 -51.999896) (xy 265.367523 -51.999896)
			(xy 265.371533 -51.837793) (xy 265.383556 -51.676088) (xy 265.40356 -51.515174) (xy 265.431498 -51.355447)
			(xy 265.467301 -51.197297) (xy 265.510881 -51.041111) (xy 265.562132 -50.887271) (xy 265.620928 -50.736154)
			(xy 265.687126 -50.58813) (xy 265.760562 -50.44356) (xy 265.841059 -50.302799) (xy 265.928418 -50.166191)
			(xy 266.022426 -50.034071) (xy 266.122853 -49.906761) (xy 266.229453 -49.784573) (xy 266.341965 -49.667807)
			(xy 266.460113 -49.556748) (xy 266.58361 -49.451667) (xy 266.712152 -49.352823) (xy 266.845425 -49.260456)
			(xy 266.983103 -49.174793) (xy 267.124849 -49.096044) (xy 267.270316 -49.024401) (xy 267.419148 -48.960039)
			(xy 267.57098 -48.903117) (xy 267.725442 -48.853773) (xy 267.882155 -48.812128) (xy 268.040736 -48.778283)
			(xy 268.200797 -48.752323) (xy 268.361945 -48.73431) (xy 268.523787 -48.724289) (xy 268.685927 -48.722283)
			(xy 268.847968 -48.728299) (xy 269.009512 -48.74232) (xy 269.170166 -48.764313) (xy 269.329536 -48.794225)
			(xy 269.487231 -48.831981) (xy 269.642866 -48.877489) (xy 269.79606 -48.930639) (xy 269.946438 -48.9913)
			(xy 270.093633 -49.059323) (xy 270.237283 -49.134542) (xy 270.377038 -49.216773) (xy 270.512554 -49.305815)
			(xy 270.643502 -49.40145) (xy 270.76956 -49.503444) (xy 270.89042 -49.611547) (xy 271.005786 -49.725494)
			(xy 271.115375 -49.845008) (xy 271.21892 -49.969795) (xy 271.316167 -50.09955) (xy 271.406879 -50.233955)
			(xy 271.490832 -50.372682) (xy 271.567822 -50.515391) (xy 271.637661 -50.661732) (xy 271.700176 -50.811349)
			(xy 271.755217 -50.963874) (xy 271.802647 -51.118934) (xy 271.84235 -51.27615) (xy 271.874231 -51.435138)
			(xy 271.898209 -51.595507) (xy 271.914228 -51.756866) (xy 271.922247 -51.91882) (xy 271.922748 -51.999896)
			(xy 271.922247 -52.080972) (xy 271.914228 -52.242926) (xy 271.898209 -52.404285) (xy 271.874231 -52.564654)
			(xy 271.84235 -52.723642) (xy 271.802647 -52.880858) (xy 271.755217 -53.035918) (xy 271.700176 -53.188443)
			(xy 271.637661 -53.33806) (xy 271.567822 -53.484401) (xy 271.490832 -53.62711) (xy 271.406879 -53.765837)
			(xy 271.316167 -53.900242) (xy 271.21892 -54.029997) (xy 271.115375 -54.154784) (xy 271.005786 -54.274298)
			(xy 270.89042 -54.388245) (xy 270.76956 -54.496348) (xy 270.643502 -54.598342) (xy 270.512554 -54.693977)
			(xy 270.377038 -54.783019) (xy 270.237283 -54.86525) (xy 270.093633 -54.940469) (xy 269.946438 -55.008492)
			(xy 269.79606 -55.069153) (xy 269.642866 -55.122303) (xy 269.487231 -55.167811) (xy 269.329536 -55.205567)
			(xy 269.170166 -55.235479) (xy 269.009512 -55.257472) (xy 268.847968 -55.271493) (xy 268.685927 -55.277509)
			(xy 268.523787 -55.275503) (xy 268.361945 -55.265482) (xy 268.200797 -55.247469) (xy 268.040736 -55.221509)
			(xy 267.882155 -55.187664) (xy 267.725442 -55.146019) (xy 267.57098 -55.096675) (xy 267.419148 -55.039753)
			(xy 267.270316 -54.975391) (xy 267.124849 -54.903748) (xy 266.983103 -54.824999) (xy 266.845425 -54.739336)
			(xy 266.712152 -54.646969) (xy 266.58361 -54.548125) (xy 266.460113 -54.443044) (xy 266.341965 -54.331985)
			(xy 266.229453 -54.215219) (xy 266.122853 -54.093031) (xy 266.022426 -53.965721) (xy 265.928418 -53.833601)
			(xy 265.841059 -53.696993) (xy 265.760562 -53.556232) (xy 265.687126 -53.411662) (xy 265.620928 -53.263638)
			(xy 265.562132 -53.112521) (xy 265.510881 -52.958681) (xy 265.467301 -52.802495) (xy 265.431498 -52.644345)
			(xy 265.40356 -52.484618) (xy 265.383556 -52.323704) (xy 265.371533 -52.161999) (xy 265.367523 -51.999896)
			(xy 252.317441 -51.999896) (xy 252.300232 -52.032916) (xy 252.29478 -52.04437) (xy 252.2948 -52.06971)
			(xy 252.300232 -52.081176) (xy 252.320452 -52.120026) (xy 252.354062 -52.200909) (xy 252.379567 -52.2847)
			(xy 252.39672 -52.370592) (xy 252.405355 -52.457752) (xy 252.405896 -52.501546) (xy 252.405431 -52.54266)
			(xy 252.39784 -52.624537) (xy 252.382728 -52.705364) (xy 252.360222 -52.784452) (xy 252.330515 -52.861127)
			(xy 252.293861 -52.934733) (xy 252.250573 -53.004644) (xy 252.201018 -53.070263) (xy 252.145621 -53.131029)
			(xy 252.084853 -53.186426) (xy 252.019234 -53.235979) (xy 251.949323 -53.279267) (xy 251.875716 -53.31592)
			(xy 251.799041 -53.345626) (xy 251.719952 -53.36813) (xy 251.639125 -53.383242) (xy 251.557248 -53.390832)
			(xy 251.516134 -53.391308) (xy 251.471924 -53.390745) (xy 251.383942 -53.381965) (xy 251.297264 -53.3645)
			(xy 251.212747 -53.33852) (xy 251.131225 -53.304282) (xy 251.053503 -53.262125) (xy 250.980346 -53.212465)
			(xy 250.912478 -53.15579) (xy 250.881134 -53.124608) (xy 250.873005 -53.117104) (xy 250.852316 -53.109337)
			(xy 250.841256 -53.109622) (xy 250.825846 -53.110663) (xy 250.794978 -53.111806) (xy 250.779534 -53.111908)
			(xy 250.737779 -53.111492) (xy 250.654637 -53.103677) (xy 250.572592 -53.088104) (xy 250.492369 -53.064909)
			(xy 250.414673 -53.034297) (xy 250.340188 -52.996537) (xy 250.269571 -52.951961) (xy 250.203442 -52.900963)
			(xy 250.142385 -52.843991) (xy 250.086937 -52.781547) (xy 250.037585 -52.714181) (xy 249.994765 -52.642486)
			(xy 249.958854 -52.567092) (xy 249.930167 -52.488665) (xy 249.908958 -52.407894) (xy 249.895413 -52.32549)
			(xy 249.892058 -52.283868) (xy 249.891061 -52.274773) (xy 249.88348 -52.258135) (xy 249.870549 -52.245209)
			(xy 249.853908 -52.237634) (xy 249.844814 -52.236624) (xy 249.805225 -52.23352) (xy 249.726783 -52.221122)
			(xy 249.649759 -52.201775) (xy 249.574769 -52.175634) (xy 249.50241 -52.142907) (xy 249.433259 -52.103855)
			(xy 249.400314 -52.081684) (xy 249.392012 -52.076461) (xy 249.372875 -52.072218) (xy 249.353539 -52.075433)
			(xy 249.344942 -52.08016) (xy 249.312459 -52.099495) (xy 249.244799 -52.133223) (xy 249.174522 -52.161088)
			(xy 249.13844 -52.172362) (xy 249.128616 -52.175851) (xy 249.112727 -52.189319) (xy 249.103444 -52.207965)
			(xy 249.102372 -52.218336) (xy 249.099675 -52.260463) (xy 249.087279 -52.34397) (xy 249.067027 -52.425926)
			(xy 249.039099 -52.505595) (xy 249.003748 -52.582258) (xy 248.961291 -52.655227) (xy 248.912112 -52.723845)
			(xy 248.856651 -52.787493) (xy 248.795409 -52.8456) (xy 248.728936 -52.897642) (xy 248.657831 -52.943151)
			(xy 248.582733 -52.981717) (xy 248.504319 -53.012994) (xy 248.423294 -53.036699) (xy 248.340387 -53.052621)
			(xy 248.256345 -53.060614) (xy 248.214134 -53.061108) (xy 248.171669 -53.060607) (xy 248.087125 -53.052507)
			(xy 248.003739 -53.036385) (xy 247.922268 -53.01239) (xy 247.843456 -52.98074) (xy 247.768018 -52.941722)
			(xy 247.696643 -52.895693) (xy 247.629979 -52.84307) (xy 247.568634 -52.784334) (xy 247.540526 -52.752498)
			(xy 247.534176 -52.745132) (xy 247.517412 -52.736496) (xy 247.429274 -52.726336) (xy 247.410986 -52.731416)
			(xy 247.403112 -52.737258) (xy 247.370277 -52.761024) (xy 247.301045 -52.803187) (xy 247.228263 -52.838875)
			(xy 247.152535 -52.867791) (xy 247.07449 -52.889697) (xy 246.994775 -52.904409) (xy 246.914052 -52.911805)
			(xy 246.873522 -52.912264) (xy 246.831202 -52.911724) (xy 246.746946 -52.903656) (xy 246.663838 -52.887619)
			(xy 246.58263 -52.863758) (xy 246.504056 -52.83229) (xy 246.428827 -52.793499) (xy 246.392954 -52.77104)
			(xy 246.38456 -52.766177) (xy 246.365522 -52.762524) (xy 246.346484 -52.766177) (xy 246.33809 -52.77104)
			(xy 246.302222 -52.793507) (xy 246.226987 -52.832285) (xy 246.148411 -52.863747) (xy 246.067203 -52.887609)
			(xy 245.984096 -52.903654) (xy 245.899842 -52.911738) (xy 245.857522 -52.912264) (xy 245.813221 -52.911666)
			(xy 245.725058 -52.90285) (xy 245.638208 -52.885314) (xy 245.553531 -52.85923) (xy 245.471867 -52.824858)
			(xy 245.394025 -52.782538) (xy 245.320775 -52.732689) (xy 245.252843 -52.675806) (xy 245.190903 -52.61245)
			(xy 245.135568 -52.543252) (xy 245.111016 -52.506372) (xy 245.106055 -52.499361) (xy 245.092457 -52.488884)
			(xy 245.076169 -52.483465) (xy 245.067582 -52.483258) (xy 245.060978 -52.483258) (xy 245.033722 -52.482865)
			(xy 244.979766 -52.475104) (xy 244.927464 -52.459743) (xy 244.87788 -52.437094) (xy 244.832025 -52.407619)
			(xy 244.790831 -52.371918) (xy 244.755138 -52.330717) (xy 244.725671 -52.284856) (xy 244.703032 -52.235269)
			(xy 244.68768 -52.182963) (xy 244.679929 -52.129006) (xy 244.67947 -52.10175) (xy 207.921092 -52.10175)
			(xy 207.914102 -52.242926) (xy 207.898083 -52.404285) (xy 207.874105 -52.564654) (xy 207.842224 -52.723642)
			(xy 207.802521 -52.880858) (xy 207.755091 -53.035918) (xy 207.70005 -53.188443) (xy 207.637535 -53.33806)
			(xy 207.567696 -53.484401) (xy 207.490706 -53.62711) (xy 207.406753 -53.765837) (xy 207.316041 -53.900242)
			(xy 207.218794 -54.029997) (xy 207.115249 -54.154784) (xy 207.00566 -54.274298) (xy 206.890294 -54.388245)
			(xy 206.769434 -54.496348) (xy 206.643376 -54.598342) (xy 206.512428 -54.693977) (xy 206.376912 -54.783019)
			(xy 206.237157 -54.86525) (xy 206.093507 -54.940469) (xy 205.946312 -55.008492) (xy 205.795934 -55.069153)
			(xy 205.64274 -55.122303) (xy 205.487105 -55.167811) (xy 205.32941 -55.205567) (xy 205.17004 -55.235479)
			(xy 205.009386 -55.257472) (xy 204.847842 -55.271493) (xy 204.685801 -55.277509) (xy 204.523661 -55.275503)
			(xy 204.361819 -55.265482) (xy 204.200671 -55.247469) (xy 204.04061 -55.221509) (xy 203.882029 -55.187664)
			(xy 203.725316 -55.146019) (xy 203.570854 -55.096675) (xy 203.419022 -55.039753) (xy 203.27019 -54.975391)
			(xy 203.124723 -54.903748) (xy 202.982977 -54.824999) (xy 202.845299 -54.739336) (xy 202.712026 -54.646969)
			(xy 202.583484 -54.548125) (xy 202.459987 -54.443044) (xy 202.341839 -54.331985) (xy 202.229327 -54.215219)
			(xy 202.122727 -54.093031) (xy 202.0223 -53.965721) (xy 201.928292 -53.833601) (xy 201.840933 -53.696993)
			(xy 201.760436 -53.556232) (xy 201.687 -53.411662) (xy 201.620802 -53.263638) (xy 201.562006 -53.112521)
			(xy 201.510755 -52.958681) (xy 201.467175 -52.802495) (xy 201.431372 -52.644345) (xy 201.403434 -52.484618)
			(xy 201.38343 -52.323704) (xy 201.371407 -52.161999) (xy 201.367397 -51.999896) (xy 179.393596 -51.999896)
			(xy 179.393596 -52.481734) (xy 179.39311 -52.509003) (xy 179.385348 -52.562987) (xy 179.369983 -52.615317)
			(xy 179.347326 -52.664927) (xy 179.31784 -52.710808) (xy 179.282125 -52.752025) (xy 179.240908 -52.78774)
			(xy 179.195027 -52.817226) (xy 179.145417 -52.839883) (xy 179.093087 -52.855248) (xy 179.039103 -52.86301)
			(xy 178.984565 -52.86301) (xy 178.930581 -52.855248) (xy 178.878251 -52.839883) (xy 178.828641 -52.817226)
			(xy 178.78276 -52.78774) (xy 178.741543 -52.752025) (xy 178.705828 -52.710808) (xy 178.676342 -52.664927)
			(xy 178.653685 -52.615317) (xy 178.63832 -52.562987) (xy 178.630558 -52.509003) (xy 178.630072 -52.481734)
			(xy 0.509016 -52.481734) (xy 0.509016 -53.954934) (xy 181.659784 -53.954934) (xy 181.659784 -53.091334)
			(xy 181.66027 -53.064065) (xy 181.668032 -53.010081) (xy 181.683397 -52.957751) (xy 181.706054 -52.908141)
			(xy 181.73554 -52.86226) (xy 181.771255 -52.821043) (xy 181.812472 -52.785328) (xy 181.858353 -52.755842)
			(xy 181.907963 -52.733185) (xy 181.960293 -52.71782) (xy 182.014277 -52.710058) (xy 182.068815 -52.710058)
			(xy 182.122799 -52.71782) (xy 182.175129 -52.733185) (xy 182.224739 -52.755842) (xy 182.27062 -52.785328)
			(xy 182.311837 -52.821043) (xy 182.347552 -52.86226) (xy 182.377038 -52.908141) (xy 182.399695 -52.957751)
			(xy 182.41506 -53.010081) (xy 182.422822 -53.064065) (xy 182.423308 -53.091334) (xy 182.423308 -53.954934)
			(xy 182.422822 -53.982203) (xy 182.41506 -54.036187) (xy 182.399695 -54.088517) (xy 182.377038 -54.138127)
			(xy 182.347552 -54.184008) (xy 182.311837 -54.225225) (xy 182.27062 -54.26094) (xy 182.224739 -54.290426)
			(xy 182.175129 -54.313083) (xy 182.122799 -54.328448) (xy 182.068815 -54.33621) (xy 182.014277 -54.33621)
			(xy 181.960293 -54.328448) (xy 181.907963 -54.313083) (xy 181.858353 -54.290426) (xy 181.812472 -54.26094)
			(xy 181.771255 -54.225225) (xy 181.73554 -54.184008) (xy 181.706054 -54.138127) (xy 181.683397 -54.088517)
			(xy 181.668032 -54.036187) (xy 181.66027 -53.982203) (xy 181.659784 -53.954934) (xy 0.509016 -53.954934)
			(xy 0.509016 -55.481728) (xy 178.630072 -55.481728) (xy 178.630072 -54.618128) (xy 178.630558 -54.590859)
			(xy 178.63832 -54.536875) (xy 178.653685 -54.484545) (xy 178.676342 -54.434935) (xy 178.705828 -54.389054)
			(xy 178.741543 -54.347837) (xy 178.78276 -54.312122) (xy 178.828641 -54.282636) (xy 178.878251 -54.259979)
			(xy 178.930581 -54.244614) (xy 178.984565 -54.236852) (xy 179.039103 -54.236852) (xy 179.093087 -54.244614)
			(xy 179.145417 -54.259979) (xy 179.195027 -54.282636) (xy 179.240908 -54.312122) (xy 179.282125 -54.347837)
			(xy 179.31784 -54.389054) (xy 179.347326 -54.434935) (xy 179.369983 -54.484545) (xy 179.385348 -54.536875)
			(xy 179.39311 -54.590859) (xy 179.393596 -54.618128) (xy 179.393596 -55.481728) (xy 179.39311 -55.508997)
			(xy 179.385348 -55.562981) (xy 179.369983 -55.615311) (xy 179.347326 -55.664921) (xy 179.31784 -55.710802)
			(xy 179.282125 -55.752019) (xy 179.240908 -55.787734) (xy 179.195027 -55.81722) (xy 179.145417 -55.839877)
			(xy 179.093087 -55.855242) (xy 179.039103 -55.863004) (xy 178.984565 -55.863004) (xy 178.930581 -55.855242)
			(xy 178.878251 -55.839877) (xy 178.828641 -55.81722) (xy 178.78276 -55.787734) (xy 178.741543 -55.752019)
			(xy 178.705828 -55.710802) (xy 178.676342 -55.664921) (xy 178.653685 -55.615311) (xy 178.63832 -55.562981)
			(xy 178.630558 -55.508997) (xy 178.630072 -55.481728) (xy 0.509016 -55.481728) (xy 0.509016 -57.094435)
			(xy 170.842169 -57.094435) (xy 170.842169 -57.005413) (xy 170.850149 -56.916749) (xy 170.866045 -56.829158)
			(xy 170.889728 -56.743343) (xy 170.921008 -56.659998) (xy 170.959634 -56.579792) (xy 171.005293 -56.503371)
			(xy 171.057619 -56.43135) (xy 171.11619 -56.36431) (xy 171.180535 -56.30279) (xy 171.250135 -56.247286)
			(xy 171.324431 -56.198244) (xy 171.402823 -56.156059) (xy 171.484682 -56.121071) (xy 171.569347 -56.093562)
			(xy 171.656137 -56.073752) (xy 171.744353 -56.061802) (xy 171.833286 -56.057809) (xy 171.922219 -56.061802)
			(xy 172.010435 -56.073752) (xy 172.097225 -56.093562) (xy 172.18189 -56.121071) (xy 172.263749 -56.156059)
			(xy 172.342141 -56.198244) (xy 172.416437 -56.247286) (xy 172.486037 -56.30279) (xy 172.550382 -56.36431)
			(xy 172.608953 -56.43135) (xy 172.661279 -56.503371) (xy 172.706938 -56.579792) (xy 172.745564 -56.659998)
			(xy 172.776844 -56.743343) (xy 172.800527 -56.829158) (xy 172.816423 -56.916749) (xy 172.824403 -57.005413)
			(xy 172.824902 -57.049924) (xy 172.824403 -57.094435) (xy 172.816423 -57.183099) (xy 172.800527 -57.27069)
			(xy 172.776844 -57.356505) (xy 172.745564 -57.43985) (xy 172.706938 -57.520056) (xy 172.661279 -57.596477)
			(xy 172.608953 -57.668498) (xy 172.550382 -57.735538) (xy 172.486037 -57.797058) (xy 172.416437 -57.852562)
			(xy 172.342141 -57.901604) (xy 172.263749 -57.943789) (xy 172.18189 -57.978777) (xy 172.097225 -58.006286)
			(xy 172.010435 -58.026096) (xy 171.922219 -58.038046) (xy 171.833286 -58.04204) (xy 171.744353 -58.038046)
			(xy 171.656137 -58.026096) (xy 171.569347 -58.006286) (xy 171.484682 -57.978777) (xy 171.402823 -57.943789)
			(xy 171.324431 -57.901604) (xy 171.250135 -57.852562) (xy 171.180535 -57.797058) (xy 171.11619 -57.735538)
			(xy 171.057619 -57.668498) (xy 171.005293 -57.596477) (xy 170.959634 -57.520056) (xy 170.921008 -57.43985)
			(xy 170.889728 -57.356505) (xy 170.866045 -57.27069) (xy 170.850149 -57.183099) (xy 170.842169 -57.094435)
			(xy 0.509016 -57.094435) (xy 0.509016 -60.375038) (xy 233.333297 -60.375038) (xy 233.337302 -60.28713)
			(xy 233.349285 -60.19995) (xy 233.369145 -60.114221) (xy 233.39672 -60.030653) (xy 233.431779 -59.949939)
			(xy 233.474032 -59.872747) (xy 233.52313 -59.799718) (xy 233.578666 -59.731456) (xy 233.640178 -59.668526)
			(xy 233.707159 -59.611452) (xy 233.779052 -59.560704) (xy 233.855261 -59.516704) (xy 233.935156 -59.479817)
			(xy 234.018075 -59.450348) (xy 234.10333 -59.428541) (xy 234.190214 -59.414577) (xy 234.278008 -59.408571)
			(xy 234.365985 -59.410575) (xy 234.453415 -59.42057) (xy 234.539574 -59.438474) (xy 234.623748 -59.464138)
			(xy 234.705239 -59.497351) (xy 234.783373 -59.537837) (xy 234.857501 -59.585259) (xy 234.927009 -59.639226)
			(xy 234.991323 -59.699291) (xy 235.049907 -59.764955) (xy 235.102278 -59.835674) (xy 235.148001 -59.910862)
			(xy 235.186698 -59.989897) (xy 235.218047 -60.072123) (xy 235.241789 -60.156859) (xy 235.257727 -60.243403)
			(xy 235.265729 -60.331038) (xy 235.26623 -60.375038) (xy 235.265729 -60.419038) (xy 235.257727 -60.506673)
			(xy 235.241789 -60.593217) (xy 235.218047 -60.677953) (xy 235.186698 -60.760179) (xy 235.148001 -60.839214)
			(xy 235.102278 -60.914402) (xy 235.049907 -60.985121) (xy 234.991323 -61.050785) (xy 234.927009 -61.11085)
			(xy 234.857501 -61.164817) (xy 234.783373 -61.212239) (xy 234.705239 -61.252725) (xy 234.623748 -61.285938)
			(xy 234.539574 -61.311602) (xy 234.453415 -61.329506) (xy 234.365985 -61.339501) (xy 234.278008 -61.341505)
			(xy 234.190214 -61.335499) (xy 234.10333 -61.321535) (xy 234.018075 -61.299728) (xy 233.935156 -61.270259)
			(xy 233.855261 -61.233372) (xy 233.779052 -61.189372) (xy 233.707159 -61.138624) (xy 233.640178 -61.08155)
			(xy 233.578666 -61.01862) (xy 233.52313 -60.950358) (xy 233.474032 -60.877329) (xy 233.431779 -60.800137)
			(xy 233.39672 -60.719423) (xy 233.369145 -60.635855) (xy 233.349285 -60.550126) (xy 233.337302 -60.462946)
			(xy 233.333297 -60.375038) (xy 0.509016 -60.375038) (xy 0.509016 -74.760836) (xy 39.554404 -74.760836)
			(xy 39.554404 -66.060828) (xy 39.554909 -65.955304) (xy 39.562993 -65.74441) (xy 39.579149 -65.533981)
			(xy 39.603352 -65.324324) (xy 39.635569 -65.115749) (xy 39.675751 -64.908561) (xy 39.723839 -64.703064)
			(xy 39.779763 -64.49956) (xy 39.84344 -64.298347) (xy 39.914778 -64.09972) (xy 39.993672 -63.903972)
			(xy 40.080005 -63.71139) (xy 40.173652 -63.522255) (xy 40.274474 -63.336846) (xy 40.382324 -63.155435)
			(xy 40.497043 -62.978288) (xy 40.618463 -62.805666) (xy 40.746406 -62.63782) (xy 40.880684 -62.474998)
			(xy 41.0211 -62.317439) (xy 41.167448 -62.165374) (xy 41.319513 -62.019026) (xy 41.477072 -61.87861)
			(xy 41.639894 -61.744332) (xy 41.80774 -61.616389) (xy 41.980362 -61.494969) (xy 42.157509 -61.38025)
			(xy 42.33892 -61.2724) (xy 42.524329 -61.171578) (xy 42.713464 -61.077931) (xy 42.906046 -60.991598)
			(xy 43.101794 -60.912704) (xy 43.300421 -60.841366) (xy 43.501634 -60.777689) (xy 43.705138 -60.721765)
			(xy 43.910635 -60.673677) (xy 44.117823 -60.633495) (xy 44.326398 -60.601278) (xy 44.536055 -60.577075)
			(xy 44.746484 -60.560919) (xy 44.957378 -60.552835) (xy 45.168426 -60.552835) (xy 45.37932 -60.560919)
			(xy 45.589749 -60.577075) (xy 45.799406 -60.601278) (xy 46.007981 -60.633495) (xy 46.215169 -60.673677)
			(xy 46.420666 -60.721765) (xy 46.62417 -60.777689) (xy 46.825383 -60.841366) (xy 47.02401 -60.912704)
			(xy 47.219758 -60.991598) (xy 47.41234 -61.077931) (xy 47.601475 -61.171578) (xy 47.786884 -61.2724)
			(xy 47.968295 -61.38025) (xy 48.145442 -61.494969) (xy 48.318064 -61.616389) (xy 48.48591 -61.744332)
			(xy 48.648732 -61.87861) (xy 48.806291 -62.019026) (xy 48.958356 -62.165374) (xy 49.104704 -62.317439)
			(xy 49.24512 -62.474998) (xy 49.379398 -62.63782) (xy 49.507341 -62.805666) (xy 49.628761 -62.978288)
			(xy 49.74348 -63.155435) (xy 49.85133 -63.336846) (xy 49.952152 -63.522255) (xy 50.045799 -63.71139)
			(xy 50.132132 -63.903972) (xy 50.211026 -64.09972) (xy 50.282364 -64.298347) (xy 50.346041 -64.49956)
			(xy 50.401965 -64.703064) (xy 50.450053 -64.908561) (xy 50.490235 -65.115749) (xy 50.522452 -65.324324)
			(xy 50.546655 -65.533981) (xy 50.562811 -65.74441) (xy 50.570895 -65.955304) (xy 50.5714 -66.060828)
			(xy 50.5714 -74.760836) (xy 50.571366 -74.767948) (xy 173.354492 -74.767948) (xy 173.354492 -66.06794)
			(xy 173.354997 -65.962416) (xy 173.363081 -65.751522) (xy 173.379237 -65.541093) (xy 173.40344 -65.331436)
			(xy 173.435657 -65.122861) (xy 173.475839 -64.915673) (xy 173.523927 -64.710176) (xy 173.579851 -64.506672)
			(xy 173.643528 -64.305459) (xy 173.714866 -64.106832) (xy 173.79376 -63.911084) (xy 173.880093 -63.718502)
			(xy 173.97374 -63.529367) (xy 174.074562 -63.343958) (xy 174.182412 -63.162547) (xy 174.297131 -62.9854)
			(xy 174.418551 -62.812778) (xy 174.546494 -62.644932) (xy 174.680772 -62.48211) (xy 174.821188 -62.324551)
			(xy 174.967536 -62.172486) (xy 175.119601 -62.026138) (xy 175.27716 -61.885722) (xy 175.439982 -61.751444)
			(xy 175.607828 -61.623501) (xy 175.78045 -61.502081) (xy 175.957597 -61.387362) (xy 176.139008 -61.279512)
			(xy 176.324417 -61.17869) (xy 176.513552 -61.085043) (xy 176.706134 -60.99871) (xy 176.901882 -60.919816)
			(xy 177.100509 -60.848478) (xy 177.301722 -60.784801) (xy 177.505226 -60.728877) (xy 177.710723 -60.680789)
			(xy 177.917911 -60.640607) (xy 178.126486 -60.60839) (xy 178.336143 -60.584187) (xy 178.546572 -60.568031)
			(xy 178.757466 -60.559947) (xy 178.968514 -60.559947) (xy 179.179408 -60.568031) (xy 179.389837 -60.584187)
			(xy 179.599494 -60.60839) (xy 179.808069 -60.640607) (xy 180.015257 -60.680789) (xy 180.220754 -60.728877)
			(xy 180.424258 -60.784801) (xy 180.625471 -60.848478) (xy 180.824098 -60.919816) (xy 181.019846 -60.99871)
			(xy 181.212428 -61.085043) (xy 181.401563 -61.17869) (xy 181.586972 -61.279512) (xy 181.768383 -61.387362)
			(xy 181.94553 -61.502081) (xy 182.118152 -61.623501) (xy 182.285998 -61.751444) (xy 182.44882 -61.885722)
			(xy 182.606379 -62.026138) (xy 182.758444 -62.172486) (xy 182.904792 -62.324551) (xy 183.045208 -62.48211)
			(xy 183.179486 -62.644932) (xy 183.307429 -62.812778) (xy 183.428849 -62.9854) (xy 183.543568 -63.162547)
			(xy 183.651418 -63.343958) (xy 183.75224 -63.529367) (xy 183.845887 -63.718502) (xy 183.93222 -63.911084)
			(xy 184.011114 -64.106832) (xy 184.082452 -64.305459) (xy 184.146129 -64.506672) (xy 184.202053 -64.710176)
			(xy 184.250141 -64.915673) (xy 184.290323 -65.122861) (xy 184.32254 -65.331436) (xy 184.346743 -65.541093)
			(xy 184.362899 -65.751522) (xy 184.370983 -65.962416) (xy 184.371488 -66.06794) (xy 184.371488 -74.760836)
			(xy 287.494472 -74.760836) (xy 287.494472 -66.060828) (xy 287.494977 -65.955304) (xy 287.503061 -65.74441)
			(xy 287.519217 -65.533981) (xy 287.54342 -65.324324) (xy 287.575637 -65.115749) (xy 287.615819 -64.908561)
			(xy 287.663907 -64.703064) (xy 287.719831 -64.49956) (xy 287.783508 -64.298347) (xy 287.854846 -64.09972)
			(xy 287.93374 -63.903972) (xy 288.020073 -63.71139) (xy 288.11372 -63.522255) (xy 288.214542 -63.336846)
			(xy 288.322392 -63.155435) (xy 288.437111 -62.978288) (xy 288.558531 -62.805666) (xy 288.686474 -62.63782)
			(xy 288.820752 -62.474998) (xy 288.961168 -62.317439) (xy 289.107516 -62.165374) (xy 289.259581 -62.019026)
			(xy 289.41714 -61.87861) (xy 289.579962 -61.744332) (xy 289.747808 -61.616389) (xy 289.92043 -61.494969)
			(xy 290.097577 -61.38025) (xy 290.278988 -61.2724) (xy 290.464397 -61.171578) (xy 290.653532 -61.077931)
			(xy 290.846114 -60.991598) (xy 291.041862 -60.912704) (xy 291.240489 -60.841366) (xy 291.441702 -60.777689)
			(xy 291.645206 -60.721765) (xy 291.850703 -60.673677) (xy 292.057891 -60.633495) (xy 292.266466 -60.601278)
			(xy 292.476123 -60.577075) (xy 292.686552 -60.560919) (xy 292.897446 -60.552835) (xy 293.108494 -60.552835)
			(xy 293.319388 -60.560919) (xy 293.529817 -60.577075) (xy 293.739474 -60.601278) (xy 293.948049 -60.633495)
			(xy 294.155237 -60.673677) (xy 294.360734 -60.721765) (xy 294.564238 -60.777689) (xy 294.765451 -60.841366)
			(xy 294.964078 -60.912704) (xy 295.159826 -60.991598) (xy 295.352408 -61.077931) (xy 295.541543 -61.171578)
			(xy 295.726952 -61.2724) (xy 295.908363 -61.38025) (xy 296.08551 -61.494969) (xy 296.258132 -61.616389)
			(xy 296.425978 -61.744332) (xy 296.5888 -61.87861) (xy 296.746359 -62.019026) (xy 296.898424 -62.165374)
			(xy 297.044772 -62.317439) (xy 297.185188 -62.474998) (xy 297.319466 -62.63782) (xy 297.447409 -62.805666)
			(xy 297.568829 -62.978288) (xy 297.683548 -63.155435) (xy 297.791398 -63.336846) (xy 297.89222 -63.522255)
			(xy 297.985867 -63.71139) (xy 298.0722 -63.903972) (xy 298.151094 -64.09972) (xy 298.222432 -64.298347)
			(xy 298.286109 -64.49956) (xy 298.342033 -64.703064) (xy 298.390121 -64.908561) (xy 298.430303 -65.115749)
			(xy 298.46252 -65.324324) (xy 298.486723 -65.533981) (xy 298.502879 -65.74441) (xy 298.510963 -65.955304)
			(xy 298.511468 -66.060828) (xy 298.511468 -74.760836) (xy 298.511434 -74.767948) (xy 421.29456 -74.767948)
			(xy 421.29456 -66.06794) (xy 421.295065 -65.962416) (xy 421.303149 -65.751522) (xy 421.319305 -65.541093)
			(xy 421.343508 -65.331436) (xy 421.375725 -65.122861) (xy 421.415907 -64.915673) (xy 421.463995 -64.710176)
			(xy 421.519919 -64.506672) (xy 421.583596 -64.305459) (xy 421.654934 -64.106832) (xy 421.733828 -63.911084)
			(xy 421.820161 -63.718502) (xy 421.913808 -63.529367) (xy 422.01463 -63.343958) (xy 422.12248 -63.162547)
			(xy 422.237199 -62.9854) (xy 422.358619 -62.812778) (xy 422.486562 -62.644932) (xy 422.62084 -62.48211)
			(xy 422.761256 -62.324551) (xy 422.907604 -62.172486) (xy 423.059669 -62.026138) (xy 423.217228 -61.885722)
			(xy 423.38005 -61.751444) (xy 423.547896 -61.623501) (xy 423.720518 -61.502081) (xy 423.897665 -61.387362)
			(xy 424.079076 -61.279512) (xy 424.264485 -61.17869) (xy 424.45362 -61.085043) (xy 424.646202 -60.99871)
			(xy 424.84195 -60.919816) (xy 425.040577 -60.848478) (xy 425.24179 -60.784801) (xy 425.445294 -60.728877)
			(xy 425.650791 -60.680789) (xy 425.857979 -60.640607) (xy 426.066554 -60.60839) (xy 426.276211 -60.584187)
			(xy 426.48664 -60.568031) (xy 426.697534 -60.559947) (xy 426.908582 -60.559947) (xy 427.119476 -60.568031)
			(xy 427.329905 -60.584187) (xy 427.539562 -60.60839) (xy 427.748137 -60.640607) (xy 427.955325 -60.680789)
			(xy 428.160822 -60.728877) (xy 428.364326 -60.784801) (xy 428.565539 -60.848478) (xy 428.764166 -60.919816)
			(xy 428.959914 -60.99871) (xy 429.152496 -61.085043) (xy 429.341631 -61.17869) (xy 429.52704 -61.279512)
			(xy 429.708451 -61.387362) (xy 429.885598 -61.502081) (xy 430.05822 -61.623501) (xy 430.226066 -61.751444)
			(xy 430.388888 -61.885722) (xy 430.546447 -62.026138) (xy 430.698512 -62.172486) (xy 430.84486 -62.324551)
			(xy 430.985276 -62.48211) (xy 431.119554 -62.644932) (xy 431.247497 -62.812778) (xy 431.368917 -62.9854)
			(xy 431.483636 -63.162547) (xy 431.591486 -63.343958) (xy 431.692308 -63.529367) (xy 431.785955 -63.718502)
			(xy 431.872288 -63.911084) (xy 431.951182 -64.106832) (xy 432.02252 -64.305459) (xy 432.086197 -64.506672)
			(xy 432.142121 -64.710176) (xy 432.190209 -64.915673) (xy 432.230391 -65.122861) (xy 432.262608 -65.331436)
			(xy 432.286811 -65.541093) (xy 432.302967 -65.751522) (xy 432.311051 -65.962416) (xy 432.311556 -66.06794)
			(xy 432.311556 -74.767948) (xy 432.311051 -74.873472) (xy 432.302967 -75.084366) (xy 432.286811 -75.294795)
			(xy 432.262608 -75.504452) (xy 432.230391 -75.713027) (xy 432.190209 -75.920215) (xy 432.142121 -76.125712)
			(xy 432.086197 -76.329216) (xy 432.02252 -76.530429) (xy 431.951182 -76.729056) (xy 431.872288 -76.924804)
			(xy 431.785955 -77.117386) (xy 431.692308 -77.306521) (xy 431.591486 -77.49193) (xy 431.483636 -77.673341)
			(xy 431.368917 -77.850488) (xy 431.247497 -78.02311) (xy 431.119554 -78.190956) (xy 430.985276 -78.353778)
			(xy 430.84486 -78.511337) (xy 430.698512 -78.663402) (xy 430.546447 -78.80975) (xy 430.388888 -78.950166)
			(xy 430.226066 -79.084444) (xy 430.05822 -79.212387) (xy 429.885598 -79.333807) (xy 429.708451 -79.448526)
			(xy 429.52704 -79.556376) (xy 429.341631 -79.657198) (xy 429.152496 -79.750845) (xy 428.959914 -79.837178)
			(xy 428.764166 -79.916072) (xy 428.565539 -79.98741) (xy 428.364326 -80.051087) (xy 428.160822 -80.107011)
			(xy 427.955325 -80.155099) (xy 427.748137 -80.195281) (xy 427.539562 -80.227498) (xy 427.329905 -80.251701)
			(xy 427.119476 -80.267857) (xy 426.908582 -80.275941) (xy 426.697534 -80.275941) (xy 426.48664 -80.267857)
			(xy 426.276211 -80.251701) (xy 426.066554 -80.227498) (xy 425.857979 -80.195281) (xy 425.650791 -80.155099)
			(xy 425.445294 -80.107011) (xy 425.24179 -80.051087) (xy 425.040577 -79.98741) (xy 424.84195 -79.916072)
			(xy 424.646202 -79.837178) (xy 424.45362 -79.750845) (xy 424.264485 -79.657198) (xy 424.079076 -79.556376)
			(xy 423.897665 -79.448526) (xy 423.720518 -79.333807) (xy 423.547896 -79.212387) (xy 423.38005 -79.084444)
			(xy 423.217228 -78.950166) (xy 423.059669 -78.80975) (xy 422.907604 -78.663402) (xy 422.761256 -78.511337)
			(xy 422.62084 -78.353778) (xy 422.486562 -78.190956) (xy 422.358619 -78.02311) (xy 422.237199 -77.850488)
			(xy 422.12248 -77.673341) (xy 422.01463 -77.49193) (xy 421.913808 -77.306521) (xy 421.820161 -77.117386)
			(xy 421.733828 -76.924804) (xy 421.654934 -76.729056) (xy 421.583596 -76.530429) (xy 421.519919 -76.329216)
			(xy 421.463995 -76.125712) (xy 421.415907 -75.920215) (xy 421.375725 -75.713027) (xy 421.343508 -75.504452)
			(xy 421.319305 -75.294795) (xy 421.303149 -75.084366) (xy 421.295065 -74.873472) (xy 421.29456 -74.767948)
			(xy 298.511434 -74.767948) (xy 298.510963 -74.86636) (xy 298.502879 -75.077254) (xy 298.486723 -75.287683)
			(xy 298.46252 -75.49734) (xy 298.430303 -75.705915) (xy 298.390121 -75.913103) (xy 298.342033 -76.1186)
			(xy 298.286109 -76.322104) (xy 298.222432 -76.523317) (xy 298.151094 -76.721944) (xy 298.0722 -76.917692)
			(xy 297.985867 -77.110274) (xy 297.89222 -77.299409) (xy 297.791398 -77.484818) (xy 297.683548 -77.666229)
			(xy 297.568829 -77.843376) (xy 297.447409 -78.015998) (xy 297.319466 -78.183844) (xy 297.185188 -78.346666)
			(xy 297.044772 -78.504225) (xy 296.898424 -78.65629) (xy 296.746359 -78.802638) (xy 296.5888 -78.943054)
			(xy 296.425978 -79.077332) (xy 296.258132 -79.205275) (xy 296.08551 -79.326695) (xy 295.908363 -79.441414)
			(xy 295.726952 -79.549264) (xy 295.541543 -79.650086) (xy 295.352408 -79.743733) (xy 295.159826 -79.830066)
			(xy 294.964078 -79.90896) (xy 294.765451 -79.980298) (xy 294.564238 -80.043975) (xy 294.360734 -80.099899)
			(xy 294.155237 -80.147987) (xy 293.948049 -80.188169) (xy 293.739474 -80.220386) (xy 293.529817 -80.244589)
			(xy 293.319388 -80.260745) (xy 293.108494 -80.268829) (xy 292.897446 -80.268829) (xy 292.686552 -80.260745)
			(xy 292.476123 -80.244589) (xy 292.266466 -80.220386) (xy 292.057891 -80.188169) (xy 291.850703 -80.147987)
			(xy 291.645206 -80.099899) (xy 291.441702 -80.043975) (xy 291.240489 -79.980298) (xy 291.041862 -79.90896)
			(xy 290.846114 -79.830066) (xy 290.653532 -79.743733) (xy 290.464397 -79.650086) (xy 290.278988 -79.549264)
			(xy 290.097577 -79.441414) (xy 289.92043 -79.326695) (xy 289.747808 -79.205275) (xy 289.579962 -79.077332)
			(xy 289.41714 -78.943054) (xy 289.259581 -78.802638) (xy 289.107516 -78.65629) (xy 288.961168 -78.504225)
			(xy 288.820752 -78.346666) (xy 288.686474 -78.183844) (xy 288.558531 -78.015998) (xy 288.437111 -77.843376)
			(xy 288.322392 -77.666229) (xy 288.214542 -77.484818) (xy 288.11372 -77.299409) (xy 288.020073 -77.110274)
			(xy 287.93374 -76.917692) (xy 287.854846 -76.721944) (xy 287.783508 -76.523317) (xy 287.719831 -76.322104)
			(xy 287.663907 -76.1186) (xy 287.615819 -75.913103) (xy 287.575637 -75.705915) (xy 287.54342 -75.49734)
			(xy 287.519217 -75.287683) (xy 287.503061 -75.077254) (xy 287.494977 -74.86636) (xy 287.494472 -74.760836)
			(xy 184.371488 -74.760836) (xy 184.371488 -74.767948) (xy 184.370983 -74.873472) (xy 184.362899 -75.084366)
			(xy 184.346743 -75.294795) (xy 184.32254 -75.504452) (xy 184.290323 -75.713027) (xy 184.250141 -75.920215)
			(xy 184.202053 -76.125712) (xy 184.146129 -76.329216) (xy 184.082452 -76.530429) (xy 184.011114 -76.729056)
			(xy 183.93222 -76.924804) (xy 183.845887 -77.117386) (xy 183.75224 -77.306521) (xy 183.651418 -77.49193)
			(xy 183.543568 -77.673341) (xy 183.428849 -77.850488) (xy 183.307429 -78.02311) (xy 183.179486 -78.190956)
			(xy 183.045208 -78.353778) (xy 182.904792 -78.511337) (xy 182.758444 -78.663402) (xy 182.606379 -78.80975)
			(xy 182.44882 -78.950166) (xy 182.285998 -79.084444) (xy 182.118152 -79.212387) (xy 181.94553 -79.333807)
			(xy 181.768383 -79.448526) (xy 181.586972 -79.556376) (xy 181.401563 -79.657198) (xy 181.212428 -79.750845)
			(xy 181.019846 -79.837178) (xy 180.824098 -79.916072) (xy 180.625471 -79.98741) (xy 180.424258 -80.051087)
			(xy 180.220754 -80.107011) (xy 180.015257 -80.155099) (xy 179.808069 -80.195281) (xy 179.599494 -80.227498)
			(xy 179.389837 -80.251701) (xy 179.179408 -80.267857) (xy 178.968514 -80.275941) (xy 178.757466 -80.275941)
			(xy 178.546572 -80.267857) (xy 178.336143 -80.251701) (xy 178.126486 -80.227498) (xy 177.917911 -80.195281)
			(xy 177.710723 -80.155099) (xy 177.505226 -80.107011) (xy 177.301722 -80.051087) (xy 177.100509 -79.98741)
			(xy 176.901882 -79.916072) (xy 176.706134 -79.837178) (xy 176.513552 -79.750845) (xy 176.324417 -79.657198)
			(xy 176.139008 -79.556376) (xy 175.957597 -79.448526) (xy 175.78045 -79.333807) (xy 175.607828 -79.212387)
			(xy 175.439982 -79.084444) (xy 175.27716 -78.950166) (xy 175.119601 -78.80975) (xy 174.967536 -78.663402)
			(xy 174.821188 -78.511337) (xy 174.680772 -78.353778) (xy 174.546494 -78.190956) (xy 174.418551 -78.02311)
			(xy 174.297131 -77.850488) (xy 174.182412 -77.673341) (xy 174.074562 -77.49193) (xy 173.97374 -77.306521)
			(xy 173.880093 -77.117386) (xy 173.79376 -76.924804) (xy 173.714866 -76.729056) (xy 173.643528 -76.530429)
			(xy 173.579851 -76.329216) (xy 173.523927 -76.125712) (xy 173.475839 -75.920215) (xy 173.435657 -75.713027)
			(xy 173.40344 -75.504452) (xy 173.379237 -75.294795) (xy 173.363081 -75.084366) (xy 173.354997 -74.873472)
			(xy 173.354492 -74.767948) (xy 50.571366 -74.767948) (xy 50.570895 -74.86636) (xy 50.562811 -75.077254)
			(xy 50.546655 -75.287683) (xy 50.522452 -75.49734) (xy 50.490235 -75.705915) (xy 50.450053 -75.913103)
			(xy 50.401965 -76.1186) (xy 50.346041 -76.322104) (xy 50.282364 -76.523317) (xy 50.211026 -76.721944)
			(xy 50.132132 -76.917692) (xy 50.045799 -77.110274) (xy 49.952152 -77.299409) (xy 49.85133 -77.484818)
			(xy 49.74348 -77.666229) (xy 49.628761 -77.843376) (xy 49.507341 -78.015998) (xy 49.379398 -78.183844)
			(xy 49.24512 -78.346666) (xy 49.104704 -78.504225) (xy 48.958356 -78.65629) (xy 48.806291 -78.802638)
			(xy 48.648732 -78.943054) (xy 48.48591 -79.077332) (xy 48.318064 -79.205275) (xy 48.145442 -79.326695)
			(xy 47.968295 -79.441414) (xy 47.786884 -79.549264) (xy 47.601475 -79.650086) (xy 47.41234 -79.743733)
			(xy 47.219758 -79.830066) (xy 47.02401 -79.90896) (xy 46.825383 -79.980298) (xy 46.62417 -80.043975)
			(xy 46.420666 -80.099899) (xy 46.215169 -80.147987) (xy 46.007981 -80.188169) (xy 45.799406 -80.220386)
			(xy 45.589749 -80.244589) (xy 45.37932 -80.260745) (xy 45.168426 -80.268829) (xy 44.957378 -80.268829)
			(xy 44.746484 -80.260745) (xy 44.536055 -80.244589) (xy 44.326398 -80.220386) (xy 44.117823 -80.188169)
			(xy 43.910635 -80.147987) (xy 43.705138 -80.099899) (xy 43.501634 -80.043975) (xy 43.300421 -79.980298)
			(xy 43.101794 -79.90896) (xy 42.906046 -79.830066) (xy 42.713464 -79.743733) (xy 42.524329 -79.650086)
			(xy 42.33892 -79.549264) (xy 42.157509 -79.441414) (xy 41.980362 -79.326695) (xy 41.80774 -79.205275)
			(xy 41.639894 -79.077332) (xy 41.477072 -78.943054) (xy 41.319513 -78.802638) (xy 41.167448 -78.65629)
			(xy 41.0211 -78.504225) (xy 40.880684 -78.346666) (xy 40.746406 -78.183844) (xy 40.618463 -78.015998)
			(xy 40.497043 -77.843376) (xy 40.382324 -77.666229) (xy 40.274474 -77.484818) (xy 40.173652 -77.299409)
			(xy 40.080005 -77.110274) (xy 39.993672 -76.917692) (xy 39.914778 -76.721944) (xy 39.84344 -76.523317)
			(xy 39.779763 -76.322104) (xy 39.723839 -76.1186) (xy 39.675751 -75.913103) (xy 39.635569 -75.705915)
			(xy 39.603352 -75.49734) (xy 39.579149 -75.287683) (xy 39.562993 -75.077254) (xy 39.554909 -74.86636)
			(xy 39.554404 -74.760836) (xy 0.509016 -74.760836) (xy 0.509016 -77.67193) (xy 0.5095 -77.725143)
			(xy 0.517108 -77.831296) (xy 0.532269 -77.936637) (xy 0.554904 -78.040627) (xy 0.584899 -78.142739)
			(xy 0.622101 -78.242451) (xy 0.666319 -78.339256) (xy 0.71733 -78.43266) (xy 0.774873 -78.522188)
			(xy 0.838654 -78.607384) (xy 0.90835 -78.687813) (xy 0.945642 -78.725776) (xy 1.77419 -79.554324)
			(xy 1.823612 -79.604428) (xy 1.917404 -79.709374) (xy 2.005163 -79.819414) (xy 2.086614 -79.934202)
			(xy 2.161501 -80.053377) (xy 2.229587 -80.176563) (xy 2.290658 -80.303374) (xy 2.344523 -80.433409)
			(xy 2.391012 -80.56626) (xy 2.429978 -80.701509) (xy 2.461299 -80.83873) (xy 2.484876 -80.977491)
			(xy 2.500635 -81.117356) (xy 2.508527 -81.257885) (xy 2.509012 -81.32826) (xy 2.509012 -81.691972)
			(xy 232.140715 -81.691972) (xy 232.145114 -81.518126) (xy 232.157548 -81.34467) (xy 232.177991 -81.171975)
			(xy 232.206398 -81.00041) (xy 232.242709 -80.830342) (xy 232.286847 -80.662135) (xy 232.338717 -80.49615)
			(xy 232.398207 -80.332741) (xy 232.465191 -80.172258) (xy 232.539525 -80.015044) (xy 232.62105 -79.861437)
			(xy 232.709592 -79.711764) (xy 232.804961 -79.566346) (xy 232.906953 -79.425495) (xy 233.015351 -79.289511)
			(xy 233.129921 -79.158685) (xy 233.250418 -79.033298) (xy 233.376586 -78.913618) (xy 233.508153 -78.799901)
			(xy 233.644839 -78.69239) (xy 233.715306 -78.641448) (xy 238.084614 -78.641448) (xy 238.155081 -78.69239)
			(xy 238.291767 -78.799901) (xy 238.423334 -78.913618) (xy 238.549502 -79.033298) (xy 238.669999 -79.158685)
			(xy 238.784569 -79.289511) (xy 238.892967 -79.425495) (xy 238.994959 -79.566346) (xy 239.090328 -79.711764)
			(xy 239.17887 -79.861437) (xy 239.260395 -80.015044) (xy 239.334729 -80.172258) (xy 239.401713 -80.332741)
			(xy 239.461203 -80.49615) (xy 239.513073 -80.662135) (xy 239.557211 -80.830342) (xy 239.593522 -81.00041)
			(xy 239.608937 -81.093507) (xy 398.275806 -81.093507) (xy 398.275806 -81.008785) (xy 398.283859 -80.924448)
			(xy 398.299893 -80.841258) (xy 398.323761 -80.759968) (xy 398.355249 -80.681316) (xy 398.394071 -80.606013)
			(xy 398.439874 -80.534741) (xy 398.492245 -80.468145) (xy 398.55071 -80.40683) (xy 398.614738 -80.351349)
			(xy 398.68375 -80.302206) (xy 398.75712 -80.259846) (xy 398.834185 -80.224651) (xy 398.914247 -80.196942)
			(xy 398.99658 -80.176968) (xy 399.080439 -80.164911) (xy 399.165064 -80.16088) (xy 399.249689 -80.164911)
			(xy 399.333548 -80.176968) (xy 399.415881 -80.196942) (xy 399.495943 -80.224651) (xy 399.573008 -80.259846)
			(xy 399.646378 -80.302206) (xy 399.71539 -80.351349) (xy 399.779418 -80.40683) (xy 399.837883 -80.468145)
			(xy 399.890254 -80.534741) (xy 399.936057 -80.606013) (xy 399.974879 -80.681316) (xy 400.006367 -80.759968)
			(xy 400.030235 -80.841258) (xy 400.046269 -80.924448) (xy 400.054322 -81.008785) (xy 400.054826 -81.051146)
			(xy 400.054322 -81.093507) (xy 400.046269 -81.177844) (xy 400.030235 -81.261034) (xy 400.006367 -81.342324)
			(xy 399.974879 -81.420976) (xy 399.936057 -81.496279) (xy 399.890254 -81.567551) (xy 399.837883 -81.634147)
			(xy 399.779418 -81.695462) (xy 399.71539 -81.750943) (xy 399.646378 -81.800086) (xy 399.573008 -81.842446)
			(xy 399.495943 -81.877641) (xy 399.415881 -81.90535) (xy 399.333548 -81.925324) (xy 399.249689 -81.937381)
			(xy 399.165064 -81.941413) (xy 399.080439 -81.937381) (xy 398.99658 -81.925324) (xy 398.914247 -81.90535)
			(xy 398.834185 -81.877641) (xy 398.75712 -81.842446) (xy 398.68375 -81.800086) (xy 398.614738 -81.750943)
			(xy 398.55071 -81.695462) (xy 398.492245 -81.634147) (xy 398.439874 -81.567551) (xy 398.394071 -81.496279)
			(xy 398.355249 -81.420976) (xy 398.323761 -81.342324) (xy 398.299893 -81.261034) (xy 398.283859 -81.177844)
			(xy 398.275806 -81.093507) (xy 239.608937 -81.093507) (xy 239.621929 -81.171975) (xy 239.642372 -81.34467)
			(xy 239.654806 -81.518126) (xy 239.659205 -81.691972) (xy 239.655559 -81.865835) (xy 239.643877 -82.039343)
			(xy 239.624183 -82.212126) (xy 239.596519 -82.383812) (xy 239.560945 -82.554036) (xy 239.517536 -82.722432)
			(xy 239.466387 -82.888641) (xy 239.407605 -83.052306) (xy 239.341317 -83.213078) (xy 239.267665 -83.370612)
			(xy 239.186806 -83.524571) (xy 239.098913 -83.674626) (xy 239.004175 -83.820455) (xy 238.902794 -83.961748)
			(xy 238.794987 -84.0982) (xy 238.680985 -84.229521) (xy 238.561032 -84.355429) (xy 238.435384 -84.475655)
			(xy 238.30431 -84.589941) (xy 238.168092 -84.698043) (xy 238.027019 -84.79973) (xy 237.881395 -84.894784)
			(xy 237.731531 -84.983001) (xy 237.577747 -85.064194) (xy 237.420373 -85.138187) (xy 237.259746 -85.204823)
			(xy 237.096208 -85.263959) (xy 236.930111 -85.315469) (xy 236.761809 -85.359242) (xy 236.591663 -85.395185)
			(xy 236.420037 -85.423221) (xy 236.247297 -85.443289) (xy 236.073815 -85.455348) (xy 235.89996 -85.45937)
			(xy 235.726105 -85.455348) (xy 235.552623 -85.443289) (xy 235.379883 -85.423221) (xy 235.208257 -85.395185)
			(xy 235.038111 -85.359242) (xy 234.869809 -85.315469) (xy 234.703712 -85.263959) (xy 234.540174 -85.204823)
			(xy 234.379547 -85.138187) (xy 234.222173 -85.064194) (xy 234.068389 -84.983001) (xy 233.918525 -84.894784)
			(xy 233.772901 -84.79973) (xy 233.631828 -84.698043) (xy 233.49561 -84.589941) (xy 233.364536 -84.475655)
			(xy 233.238888 -84.355429) (xy 233.118935 -84.229521) (xy 233.004933 -84.0982) (xy 232.897126 -83.961748)
			(xy 232.795745 -83.820455) (xy 232.701007 -83.674626) (xy 232.613114 -83.524571) (xy 232.532255 -83.370612)
			(xy 232.458603 -83.213078) (xy 232.392315 -83.052306) (xy 232.333533 -82.888641) (xy 232.282384 -82.722432)
			(xy 232.238975 -82.554036) (xy 232.203401 -82.383812) (xy 232.175737 -82.212126) (xy 232.156043 -82.039343)
			(xy 232.144361 -81.865835) (xy 232.140715 -81.691972) (xy 2.509012 -81.691972) (xy 2.509012 -84.065147)
			(xy 218.29831 -84.065147) (xy 218.29831 -84.010653) (xy 218.306065 -83.956712) (xy 218.321417 -83.904424)
			(xy 218.344054 -83.854854) (xy 218.373515 -83.809009) (xy 218.4092 -83.767823) (xy 218.450383 -83.732134)
			(xy 218.496225 -83.70267) (xy 218.545794 -83.680029) (xy 218.598081 -83.664672) (xy 218.652021 -83.656912)
			(xy 218.679268 -83.656424) (xy 219.542868 -83.656424) (xy 219.570125 -83.656821) (xy 219.624084 -83.664575)
			(xy 219.67639 -83.679929) (xy 219.725978 -83.702572) (xy 219.771839 -83.732041) (xy 219.813039 -83.767738)
			(xy 219.848739 -83.808935) (xy 219.878213 -83.854794) (xy 219.90086 -83.90438) (xy 219.916219 -83.956685)
			(xy 219.923977 -84.010643) (xy 219.923977 -84.065157) (xy 219.916219 -84.119115) (xy 219.90086 -84.17142)
			(xy 219.878213 -84.221006) (xy 219.848739 -84.266865) (xy 219.813039 -84.308062) (xy 219.771839 -84.343759)
			(xy 219.725978 -84.373228) (xy 219.67639 -84.395871) (xy 219.624084 -84.411225) (xy 219.570125 -84.418979)
			(xy 219.542868 -84.41944) (xy 218.679268 -84.41944) (xy 218.652021 -84.418888) (xy 218.598081 -84.411128)
			(xy 218.545794 -84.395771) (xy 218.496225 -84.37313) (xy 218.450383 -84.343666) (xy 218.4092 -84.307977)
			(xy 218.373515 -84.266791) (xy 218.344054 -84.220946) (xy 218.321417 -84.171376) (xy 218.306065 -84.119088)
			(xy 218.29831 -84.065147) (xy 2.509012 -84.065147) (xy 2.509012 -86.948548) (xy 217.344518 -86.948548)
			(xy 217.344518 -86.894052) (xy 217.352274 -86.84011) (xy 217.367627 -86.787821) (xy 217.390266 -86.738249)
			(xy 217.419729 -86.692404) (xy 217.455416 -86.651218) (xy 217.496602 -86.61553) (xy 217.542447 -86.586067)
			(xy 217.592019 -86.563428) (xy 217.644308 -86.548074) (xy 217.69825 -86.540318) (xy 217.725498 -86.539832)
			(xy 218.589098 -86.539832) (xy 218.616354 -86.540215) (xy 218.670311 -86.547972) (xy 218.722614 -86.56333)
			(xy 218.7722 -86.585975) (xy 218.818058 -86.615446) (xy 218.859255 -86.651143) (xy 218.894953 -86.69234)
			(xy 218.924424 -86.738198) (xy 218.947069 -86.787784) (xy 218.962427 -86.840087) (xy 218.970185 -86.894044)
			(xy 218.970185 -86.948556) (xy 218.962427 -87.002513) (xy 218.947069 -87.054816) (xy 218.924424 -87.104402)
			(xy 218.894953 -87.15026) (xy 218.859255 -87.191457) (xy 218.818058 -87.227154) (xy 218.7722 -87.256625)
			(xy 218.722614 -87.27927) (xy 218.670311 -87.294628) (xy 218.616354 -87.302385) (xy 218.589098 -87.302848)
			(xy 217.725498 -87.302848) (xy 217.69825 -87.302282) (xy 217.644308 -87.294526) (xy 217.592019 -87.279172)
			(xy 217.542447 -87.256533) (xy 217.496602 -87.22707) (xy 217.455416 -87.191382) (xy 217.419729 -87.150196)
			(xy 217.390266 -87.104351) (xy 217.367627 -87.054779) (xy 217.352274 -87.00249) (xy 217.344518 -86.948548)
			(xy 2.509012 -86.948548) (xy 2.509012 -106.447336) (xy 11.713464 -106.447336) (xy 11.713464 -105.456736)
			(xy 11.71395 -105.429467) (xy 11.721712 -105.375483) (xy 11.737077 -105.323153) (xy 11.759734 -105.273543)
			(xy 11.78922 -105.227662) (xy 11.824935 -105.186445) (xy 11.866152 -105.15073) (xy 11.912033 -105.121244)
			(xy 11.961643 -105.098587) (xy 12.013973 -105.083222) (xy 12.067957 -105.07546) (xy 12.122495 -105.07546)
			(xy 12.176479 -105.083222) (xy 12.228809 -105.098587) (xy 12.278419 -105.121244) (xy 12.3243 -105.15073)
			(xy 12.365517 -105.186445) (xy 12.401232 -105.227662) (xy 12.430718 -105.273543) (xy 12.453375 -105.323153)
			(xy 12.46874 -105.375483) (xy 12.476502 -105.429467) (xy 12.476988 -105.456736) (xy 12.476988 -105.664)
			(xy 15.57274 -105.664) (xy 15.57274 -104.6734) (xy 15.573226 -104.646131) (xy 15.580988 -104.592147)
			(xy 15.596353 -104.539817) (xy 15.61901 -104.490207) (xy 15.648496 -104.444326) (xy 15.684211 -104.403109)
			(xy 15.725428 -104.367394) (xy 15.771309 -104.337908) (xy 15.820919 -104.315251) (xy 15.873249 -104.299886)
			(xy 15.927233 -104.292124) (xy 15.981771 -104.292124) (xy 16.035755 -104.299886) (xy 16.088085 -104.315251)
			(xy 16.137695 -104.337908) (xy 16.146631 -104.343651) (xy 326.803 -104.343651) (xy 326.803 -104.258929)
			(xy 326.811053 -104.174592) (xy 326.827087 -104.091402) (xy 326.850955 -104.010112) (xy 326.882443 -103.93146)
			(xy 326.921265 -103.856157) (xy 326.967068 -103.784885) (xy 327.019439 -103.718289) (xy 327.077904 -103.656974)
			(xy 327.141932 -103.601493) (xy 327.210944 -103.55235) (xy 327.284314 -103.50999) (xy 327.361379 -103.474795)
			(xy 327.441441 -103.447086) (xy 327.523774 -103.427112) (xy 327.607633 -103.415055) (xy 327.692258 -103.411024)
			(xy 327.776883 -103.415055) (xy 327.860742 -103.427112) (xy 327.943075 -103.447086) (xy 328.023137 -103.474795)
			(xy 328.100202 -103.50999) (xy 328.173572 -103.55235) (xy 328.242584 -103.601493) (xy 328.306612 -103.656974)
			(xy 328.365077 -103.718289) (xy 328.417448 -103.784885) (xy 328.463251 -103.856157) (xy 328.502073 -103.93146)
			(xy 328.533561 -104.010112) (xy 328.557429 -104.091402) (xy 328.573463 -104.174592) (xy 328.581516 -104.258929)
			(xy 328.58202 -104.30129) (xy 328.581516 -104.343651) (xy 328.573463 -104.427988) (xy 328.557429 -104.511178)
			(xy 328.533561 -104.592468) (xy 328.502073 -104.67112) (xy 328.463251 -104.746423) (xy 328.417448 -104.817695)
			(xy 328.365077 -104.884291) (xy 328.306612 -104.945606) (xy 328.242584 -105.001087) (xy 328.173572 -105.05023)
			(xy 328.100202 -105.09259) (xy 328.023137 -105.127785) (xy 327.943075 -105.155494) (xy 327.860742 -105.175468)
			(xy 327.776883 -105.187525) (xy 327.692258 -105.191557) (xy 327.607633 -105.187525) (xy 327.523774 -105.175468)
			(xy 327.441441 -105.155494) (xy 327.361379 -105.127785) (xy 327.284314 -105.09259) (xy 327.210944 -105.05023)
			(xy 327.141932 -105.001087) (xy 327.077904 -104.945606) (xy 327.019439 -104.884291) (xy 326.967068 -104.817695)
			(xy 326.921265 -104.746423) (xy 326.882443 -104.67112) (xy 326.850955 -104.592468) (xy 326.827087 -104.511178)
			(xy 326.811053 -104.427988) (xy 326.803 -104.343651) (xy 16.146631 -104.343651) (xy 16.183576 -104.367394)
			(xy 16.224793 -104.403109) (xy 16.260508 -104.444326) (xy 16.289994 -104.490207) (xy 16.312651 -104.539817)
			(xy 16.328016 -104.592147) (xy 16.335778 -104.646131) (xy 16.336264 -104.6734) (xy 16.336264 -105.664)
			(xy 16.335778 -105.691269) (xy 16.328016 -105.745253) (xy 16.312651 -105.797583) (xy 16.289994 -105.847193)
			(xy 16.260508 -105.893074) (xy 16.224793 -105.934291) (xy 16.183576 -105.970006) (xy 16.137695 -105.999492)
			(xy 16.088085 -106.022149) (xy 16.035755 -106.037514) (xy 15.981771 -106.045276) (xy 15.927233 -106.045276)
			(xy 15.873249 -106.037514) (xy 15.820919 -106.022149) (xy 15.771309 -105.999492) (xy 15.725428 -105.970006)
			(xy 15.684211 -105.934291) (xy 15.648496 -105.893074) (xy 15.61901 -105.847193) (xy 15.596353 -105.797583)
			(xy 15.580988 -105.745253) (xy 15.573226 -105.691269) (xy 15.57274 -105.664) (xy 12.476988 -105.664)
			(xy 12.476988 -106.447336) (xy 12.476502 -106.474605) (xy 12.46874 -106.528589) (xy 12.453375 -106.580919)
			(xy 12.430718 -106.630529) (xy 12.401232 -106.67641) (xy 12.365517 -106.717627) (xy 12.3243 -106.753342)
			(xy 12.278419 -106.782828) (xy 12.228809 -106.805485) (xy 12.176479 -106.82085) (xy 12.122495 -106.828612)
			(xy 12.067957 -106.828612) (xy 12.013973 -106.82085) (xy 11.961643 -106.805485) (xy 11.912033 -106.782828)
			(xy 11.866152 -106.753342) (xy 11.824935 -106.717627) (xy 11.78922 -106.67641) (xy 11.759734 -106.630529)
			(xy 11.737077 -106.580919) (xy 11.721712 -106.528589) (xy 11.71395 -106.474605) (xy 11.713464 -106.447336)
			(xy 2.509012 -106.447336) (xy 2.509012 -108.943971) (xy 11.292822 -108.943971) (xy 11.292822 -108.889469)
			(xy 11.300578 -108.835522) (xy 11.315933 -108.783228) (xy 11.338574 -108.733651) (xy 11.36804 -108.687801)
			(xy 11.403731 -108.646611) (xy 11.444921 -108.61092) (xy 11.490771 -108.581454) (xy 11.540348 -108.558813)
			(xy 11.592642 -108.543458) (xy 11.646589 -108.535702) (xy 11.67384 -108.535216) (xy 12.53744 -108.535216)
			(xy 12.564692 -108.535694) (xy 12.61864 -108.54345) (xy 12.670935 -108.558806) (xy 12.720513 -108.581447)
			(xy 12.766364 -108.610914) (xy 12.807554 -108.646606) (xy 12.843246 -108.687796) (xy 12.872713 -108.733647)
			(xy 12.895354 -108.783225) (xy 12.91071 -108.83552) (xy 12.918466 -108.889468) (xy 12.918466 -108.943972)
			(xy 12.91071 -108.99792) (xy 12.895354 -109.050215) (xy 12.872713 -109.099793) (xy 12.843246 -109.145644)
			(xy 12.807554 -109.186834) (xy 12.766364 -109.222526) (xy 12.720513 -109.251993) (xy 12.670935 -109.274634)
			(xy 12.61864 -109.28999) (xy 12.564692 -109.297746) (xy 12.53744 -109.298232) (xy 11.67384 -109.298232)
			(xy 11.646589 -109.297738) (xy 11.592642 -109.289982) (xy 11.540348 -109.274627) (xy 11.490771 -109.251986)
			(xy 11.444921 -109.22252) (xy 11.403731 -109.186829) (xy 11.36804 -109.145639) (xy 11.338574 -109.099789)
			(xy 11.315933 -109.050212) (xy 11.300578 -108.997918) (xy 11.292822 -108.943971) (xy 2.509012 -108.943971)
			(xy 2.509012 -109.451973) (xy 15.092889 -109.451973) (xy 15.092889 -109.397467) (xy 15.100646 -109.343517)
			(xy 15.116002 -109.291219) (xy 15.138645 -109.241639) (xy 15.168113 -109.195786) (xy 15.203807 -109.154594)
			(xy 15.244999 -109.118901) (xy 15.290853 -109.089433) (xy 15.340433 -109.066791) (xy 15.39273 -109.051435)
			(xy 15.446681 -109.043679) (xy 15.473934 -109.043216) (xy 16.464534 -109.043216) (xy 16.491785 -109.043694)
			(xy 16.545733 -109.051451) (xy 16.598028 -109.066807) (xy 16.647605 -109.089448) (xy 16.693456 -109.118915)
			(xy 16.734646 -109.154607) (xy 16.770337 -109.195798) (xy 16.799804 -109.241648) (xy 16.822445 -109.291226)
			(xy 16.8378 -109.343521) (xy 16.845556 -109.397469) (xy 16.845556 -109.451971) (xy 16.8378 -109.505919)
			(xy 16.822445 -109.558214) (xy 16.799804 -109.607792) (xy 16.770337 -109.653642) (xy 16.734646 -109.694833)
			(xy 16.693456 -109.730525) (xy 16.647605 -109.759992) (xy 16.598028 -109.782633) (xy 16.545733 -109.797989)
			(xy 16.491785 -109.805746) (xy 16.464534 -109.806232) (xy 15.473934 -109.806232) (xy 15.446681 -109.805761)
			(xy 15.39273 -109.798005) (xy 15.340433 -109.782649) (xy 15.290853 -109.760007) (xy 15.244999 -109.730539)
			(xy 15.203807 -109.694846) (xy 15.168113 -109.653654) (xy 15.138645 -109.607801) (xy 15.116002 -109.558221)
			(xy 15.100646 -109.505923) (xy 15.092889 -109.451973) (xy 2.509012 -109.451973) (xy 2.509012 -114.734161)
			(xy 11.255226 -114.734161) (xy 11.255226 -114.679659) (xy 11.262982 -114.625711) (xy 11.278337 -114.573416)
			(xy 11.300979 -114.523839) (xy 11.330445 -114.477988) (xy 11.366136 -114.436798) (xy 11.407326 -114.401106)
			(xy 11.453177 -114.371639) (xy 11.502754 -114.348998) (xy 11.555049 -114.333643) (xy 11.608997 -114.325886)
			(xy 11.636248 -114.3254) (xy 12.499848 -114.3254) (xy 12.527101 -114.325867) (xy 12.581052 -114.333624)
			(xy 12.633349 -114.34898) (xy 12.68293 -114.371622) (xy 12.728783 -114.40109) (xy 12.769975 -114.436783)
			(xy 12.805669 -114.477976) (xy 12.835137 -114.523829) (xy 12.85778 -114.573409) (xy 12.873136 -114.625706)
			(xy 12.880893 -114.679657) (xy 12.880893 -114.734163) (xy 12.873136 -114.788114) (xy 12.85778 -114.840411)
			(xy 12.835137 -114.889991) (xy 12.805669 -114.935844) (xy 12.769975 -114.977037) (xy 12.728783 -115.01273)
			(xy 12.68293 -115.042198) (xy 12.633349 -115.06484) (xy 12.581052 -115.080196) (xy 12.527101 -115.087953)
			(xy 12.499848 -115.088416) (xy 11.636248 -115.088416) (xy 11.608997 -115.087934) (xy 11.555049 -115.080177)
			(xy 11.502754 -115.064822) (xy 11.453177 -115.042181) (xy 11.407326 -115.012714) (xy 11.366136 -114.977022)
			(xy 11.330445 -114.935832) (xy 11.300979 -114.889981) (xy 11.278337 -114.840404) (xy 11.262982 -114.788109)
			(xy 11.255226 -114.734161) (xy 2.509012 -114.734161) (xy 2.509012 -133.480302) (xy 20.179284 -133.480302)
			(xy 20.179284 -132.489702) (xy 20.17977 -132.462451) (xy 20.187526 -132.408503) (xy 20.202881 -132.356208)
			(xy 20.225523 -132.306631) (xy 20.254989 -132.260781) (xy 20.29068 -132.21959) (xy 20.331871 -132.183899)
			(xy 20.377721 -132.154433) (xy 20.427298 -132.131791) (xy 20.479593 -132.116436) (xy 20.533541 -132.10868)
			(xy 20.588043 -132.10868) (xy 20.641991 -132.116436) (xy 20.694286 -132.131791) (xy 20.743863 -132.154433)
			(xy 20.789713 -132.183899) (xy 20.830904 -132.21959) (xy 20.866595 -132.260781) (xy 20.896061 -132.306631)
			(xy 20.918703 -132.356208) (xy 20.934058 -132.408503) (xy 20.941814 -132.462451) (xy 20.9423 -132.489702)
			(xy 20.9423 -133.480302) (xy 20.941814 -133.507553) (xy 20.934058 -133.561501) (xy 20.918703 -133.613796)
			(xy 20.896061 -133.663373) (xy 20.866595 -133.709223) (xy 20.830904 -133.750414) (xy 20.789713 -133.786105)
			(xy 20.743863 -133.815571) (xy 20.694286 -133.838213) (xy 20.641991 -133.853568) (xy 20.588043 -133.861324)
			(xy 20.533541 -133.861324) (xy 20.479593 -133.853568) (xy 20.427298 -133.838213) (xy 20.377721 -133.815571)
			(xy 20.331871 -133.786105) (xy 20.29068 -133.750414) (xy 20.254989 -133.709223) (xy 20.225523 -133.663373)
			(xy 20.202881 -133.613796) (xy 20.187526 -133.561501) (xy 20.17977 -133.507553) (xy 20.179284 -133.480302)
			(xy 2.509012 -133.480302) (xy 2.509012 -138.001502) (xy 20.019264 -138.001502) (xy 20.019264 -137.010902)
			(xy 20.01975 -136.983651) (xy 20.027506 -136.929703) (xy 20.042861 -136.877408) (xy 20.065503 -136.827831)
			(xy 20.094969 -136.781981) (xy 20.13066 -136.74079) (xy 20.171851 -136.705099) (xy 20.217701 -136.675633)
			(xy 20.267278 -136.652991) (xy 20.319573 -136.637636) (xy 20.373521 -136.62988) (xy 20.428023 -136.62988)
			(xy 20.481971 -136.637636) (xy 20.534266 -136.652991) (xy 20.583843 -136.675633) (xy 20.629693 -136.705099)
			(xy 20.670884 -136.74079) (xy 20.706575 -136.781981) (xy 20.736041 -136.827831) (xy 20.758683 -136.877408)
			(xy 20.774038 -136.929703) (xy 20.781794 -136.983651) (xy 20.78228 -137.010902) (xy 20.78228 -138.001502)
			(xy 20.781794 -138.028753) (xy 20.774038 -138.082701) (xy 20.758683 -138.134996) (xy 20.736041 -138.184573)
			(xy 20.706575 -138.230423) (xy 20.670884 -138.271614) (xy 20.629693 -138.307305) (xy 20.583843 -138.336771)
			(xy 20.534266 -138.359413) (xy 20.481971 -138.374768) (xy 20.428023 -138.382524) (xy 20.373521 -138.382524)
			(xy 20.319573 -138.374768) (xy 20.267278 -138.359413) (xy 20.217701 -138.336771) (xy 20.171851 -138.307305)
			(xy 20.13066 -138.271614) (xy 20.094969 -138.230423) (xy 20.065503 -138.184573) (xy 20.042861 -138.134996)
			(xy 20.027506 -138.082701) (xy 20.01975 -138.028753) (xy 20.019264 -138.001502) (xy 2.509012 -138.001502)
			(xy 2.509012 -145.104166) (xy 163.29995 -145.104166) (xy 163.29995 -145.049634) (xy 163.30771 -144.995658)
			(xy 163.323072 -144.943336) (xy 163.345724 -144.893732) (xy 163.375204 -144.847856) (xy 163.410912 -144.806643)
			(xy 163.452121 -144.77093) (xy 163.497993 -144.741445) (xy 163.547595 -144.718788) (xy 163.599915 -144.70342)
			(xy 163.653891 -144.695653) (xy 163.681156 -144.695164) (xy 164.671756 -144.695164) (xy 164.699031 -144.695573)
			(xy 164.753026 -144.70333) (xy 164.805368 -144.718694) (xy 164.85499 -144.74135) (xy 164.900882 -144.770839)
			(xy 164.94211 -144.806559) (xy 164.977835 -144.847783) (xy 165.007329 -144.893672) (xy 165.029991 -144.943291)
			(xy 165.045361 -144.995631) (xy 165.053124 -145.049625) (xy 165.053124 -145.104175) (xy 165.045361 -145.158169)
			(xy 165.029991 -145.210509) (xy 165.007329 -145.260128) (xy 164.977835 -145.306017) (xy 164.94211 -145.347241)
			(xy 164.900882 -145.382961) (xy 164.85499 -145.41245) (xy 164.805368 -145.435106) (xy 164.753026 -145.45047)
			(xy 164.699031 -145.458227) (xy 164.671756 -145.458688) (xy 163.681156 -145.458688) (xy 163.653891 -145.458147)
			(xy 163.599915 -145.45038) (xy 163.547595 -145.435012) (xy 163.497993 -145.412355) (xy 163.452121 -145.38287)
			(xy 163.410912 -145.347157) (xy 163.375204 -145.305944) (xy 163.345724 -145.260068) (xy 163.323072 -145.210464)
			(xy 163.30771 -145.158142) (xy 163.29995 -145.104166) (xy 2.509012 -145.104166) (xy 2.509012 -153.765504)
			(xy 24.441921 -153.765504) (xy 24.445917 -153.555618) (xy 24.457902 -153.346036) (xy 24.477856 -153.137062)
			(xy 24.505752 -152.929) (xy 24.541549 -152.72215) (xy 24.585194 -152.516813) (xy 24.636626 -152.313287)
			(xy 24.695768 -152.111866) (xy 24.762536 -151.912843) (xy 24.836832 -151.716506) (xy 24.91855 -151.52314)
			(xy 25.007569 -151.333025) (xy 25.103762 -151.146437) (xy 25.206989 -150.963646) (xy 25.3171 -150.784918)
			(xy 25.433935 -150.610511) (xy 25.557325 -150.440679) (xy 25.687092 -150.275667) (xy 25.823046 -150.115716)
			(xy 25.964992 -149.961056) (xy 26.112722 -149.811912) (xy 26.266024 -149.668501) (xy 26.424674 -149.53103)
			(xy 26.588443 -149.399698) (xy 26.757093 -149.274697) (xy 26.930379 -149.156206) (xy 27.108051 -149.044399)
			(xy 27.289851 -148.939437) (xy 27.475515 -148.841472) (xy 27.664773 -148.750647) (xy 27.857353 -148.667093)
			(xy 28.052974 -148.59093) (xy 28.251352 -148.522271) (xy 28.452201 -148.461214) (xy 28.655228 -148.407847)
			(xy 28.860141 -148.362249) (xy 29.06664 -148.324484) (xy 29.274427 -148.294609) (xy 29.483202 -148.272666)
			(xy 29.69266 -148.258687) (xy 29.902499 -148.252692) (xy 30.112413 -148.254691) (xy 30.3221 -148.264679)
			(xy 30.531254 -148.282644) (xy 30.739572 -148.308558) (xy 30.946753 -148.342383) (xy 31.152497 -148.384072)
			(xy 31.356503 -148.433564) (xy 31.558478 -148.490786) (xy 31.758128 -148.555656) (xy 31.955163 -148.62808)
			(xy 32.149299 -148.707953) (xy 32.340252 -148.795159) (xy 32.527748 -148.889571) (xy 32.711513 -148.991053)
			(xy 32.891281 -149.099457) (xy 33.066792 -149.214627) (xy 33.237791 -149.336395) (xy 33.404031 -149.464584)
			(xy 33.56527 -149.59901) (xy 33.721274 -149.739477) (xy 33.871817 -149.885781) (xy 34.016681 -150.03771)
			(xy 34.155656 -150.195044) (xy 34.288541 -150.357555) (xy 34.415142 -150.525008) (xy 34.535277 -150.697158)
			(xy 34.648771 -150.873758) (xy 34.688915 -150.941786) (xy 108.742233 -150.941786) (xy 108.746238 -150.836037)
			(xy 108.758228 -150.730894) (xy 108.778137 -150.626959) (xy 108.805848 -150.524827) (xy 108.841205 -150.425083)
			(xy 108.884003 -150.328299) (xy 108.933999 -150.235029) (xy 108.990906 -150.145808) (xy 109.054397 -150.061145)
			(xy 109.124109 -149.981527) (xy 109.199643 -149.907409) (xy 109.280566 -149.839216) (xy 109.366415 -149.777338)
			(xy 109.456698 -149.722131) (xy 109.550897 -149.673909) (xy 109.648474 -149.632949) (xy 109.748869 -149.599487)
			(xy 109.851507 -149.573713) (xy 109.9558 -149.555775) (xy 110.061151 -149.545776) (xy 110.166957 -149.543773)
			(xy 110.272611 -149.549778) (xy 110.377508 -149.563757) (xy 110.481048 -149.585628) (xy 110.582637 -149.615268)
			(xy 110.681694 -149.652506) (xy 110.777651 -149.697128) (xy 110.869958 -149.74888) (xy 110.958087 -149.807465)
			(xy 111.041533 -149.872547) (xy 111.119817 -149.943753) (xy 111.187365 -150.015249) (xy 160.856694 -150.015249)
			(xy 160.856694 -149.960751) (xy 160.86445 -149.906808) (xy 160.879803 -149.854517) (xy 160.902441 -149.804944)
			(xy 160.931904 -149.759096) (xy 160.967592 -149.717909) (xy 161.008777 -149.682219) (xy 161.054623 -149.652753)
			(xy 161.104195 -149.630111) (xy 161.156484 -149.614755) (xy 161.210427 -149.606996) (xy 161.237676 -149.606508)
			(xy 162.228276 -149.606508) (xy 162.255531 -149.606937) (xy 162.309487 -149.614692) (xy 162.36179 -149.630046)
			(xy 162.411375 -149.652688) (xy 162.457233 -149.682157) (xy 162.498431 -149.717852) (xy 162.534128 -149.759047)
			(xy 162.5636 -149.804904) (xy 162.586245 -149.854488) (xy 162.601603 -149.90679) (xy 162.609361 -149.960745)
			(xy 162.609361 -149.967557) (xy 163.793819 -149.967557) (xy 163.793819 -149.913043) (xy 163.801578 -149.859084)
			(xy 163.816937 -149.806779) (xy 163.839584 -149.757192) (xy 163.869057 -149.711333) (xy 163.904758 -149.670135)
			(xy 163.945958 -149.634438) (xy 163.99182 -149.604968) (xy 164.041409 -149.582325) (xy 164.093716 -149.566971)
			(xy 164.147675 -149.559217) (xy 164.174932 -149.558756) (xy 165.165532 -149.558756) (xy 165.192779 -149.559316)
			(xy 165.246718 -149.567076) (xy 165.299004 -149.582432) (xy 165.348573 -149.605073) (xy 165.394415 -149.634537)
			(xy 165.435597 -149.670226) (xy 165.471282 -149.711411) (xy 165.500742 -149.757255) (xy 165.523379 -149.806826)
			(xy 165.538731 -149.859113) (xy 165.546486 -149.913053) (xy 165.546486 -149.967547) (xy 165.538731 -150.021487)
			(xy 165.523379 -150.073774) (xy 165.500742 -150.123345) (xy 165.471282 -150.169189) (xy 165.435597 -150.210374)
			(xy 165.394415 -150.246063) (xy 165.348573 -150.275527) (xy 165.299004 -150.298168) (xy 165.246718 -150.313524)
			(xy 165.192779 -150.321284) (xy 165.165532 -150.321772) (xy 164.174932 -150.321772) (xy 164.147675 -150.321383)
			(xy 164.093716 -150.313629) (xy 164.041409 -150.298275) (xy 163.99182 -150.275632) (xy 163.945958 -150.246162)
			(xy 163.904758 -150.210465) (xy 163.869057 -150.169267) (xy 163.839584 -150.123408) (xy 163.816937 -150.073821)
			(xy 163.801578 -150.021516) (xy 163.793819 -149.967557) (xy 162.609361 -149.967557) (xy 162.609361 -150.015255)
			(xy 162.601603 -150.06921) (xy 162.586245 -150.121512) (xy 162.5636 -150.171096) (xy 162.534128 -150.216953)
			(xy 162.498431 -150.258148) (xy 162.457233 -150.293843) (xy 162.411375 -150.323312) (xy 162.36179 -150.345954)
			(xy 162.309487 -150.361308) (xy 162.255531 -150.369063) (xy 162.228276 -150.369524) (xy 161.237676 -150.369524)
			(xy 161.210427 -150.369004) (xy 161.156484 -150.361245) (xy 161.104195 -150.345889) (xy 161.054623 -150.323247)
			(xy 161.008777 -150.293781) (xy 160.967592 -150.258091) (xy 160.931904 -150.216904) (xy 160.902441 -150.171056)
			(xy 160.879803 -150.121483) (xy 160.86445 -150.069192) (xy 160.856694 -150.015249) (xy 111.187365 -150.015249)
			(xy 111.192492 -150.020676) (xy 111.259142 -150.102876) (xy 111.319384 -150.18988) (xy 111.372873 -150.281191)
			(xy 111.419304 -150.376286) (xy 111.458409 -150.47462) (xy 111.489966 -150.575631) (xy 111.513793 -150.678738)
			(xy 111.529754 -150.783352) (xy 111.537758 -150.888874) (xy 111.538258 -150.941786) (xy 111.537758 -150.994698)
			(xy 111.529754 -151.10022) (xy 111.513793 -151.204834) (xy 111.489966 -151.307941) (xy 111.458409 -151.408952)
			(xy 111.419304 -151.507286) (xy 111.372873 -151.602381) (xy 111.319384 -151.693692) (xy 111.259142 -151.780696)
			(xy 111.192492 -151.862896) (xy 111.119817 -151.939819) (xy 111.041533 -152.011025) (xy 110.958087 -152.076107)
			(xy 110.869958 -152.134692) (xy 110.777651 -152.186444) (xy 110.681694 -152.231066) (xy 110.582637 -152.268304)
			(xy 110.481048 -152.297944) (xy 110.377508 -152.319815) (xy 110.272611 -152.333794) (xy 110.166957 -152.339799)
			(xy 110.061151 -152.337796) (xy 109.9558 -152.327797) (xy 109.851507 -152.309859) (xy 109.748869 -152.284085)
			(xy 109.648474 -152.250623) (xy 109.550897 -152.209663) (xy 109.456698 -152.161441) (xy 109.366415 -152.106234)
			(xy 109.280566 -152.044356) (xy 109.199643 -151.976163) (xy 109.124109 -151.902045) (xy 109.054397 -151.822427)
			(xy 108.990906 -151.737764) (xy 108.933999 -151.648543) (xy 108.884003 -151.555273) (xy 108.841205 -151.458489)
			(xy 108.805848 -151.358745) (xy 108.778137 -151.256613) (xy 108.758228 -151.152678) (xy 108.746238 -151.047535)
			(xy 108.742233 -150.941786) (xy 34.688915 -150.941786) (xy 34.755459 -151.05455) (xy 34.855186 -151.239273)
			(xy 34.947809 -151.427659) (xy 35.033193 -151.619434) (xy 35.111214 -151.814321) (xy 35.181759 -152.012037)
			(xy 35.244726 -152.212295) (xy 35.300023 -152.414805) (xy 35.34757 -152.619274) (xy 35.354948 -152.657556)
			(xy 115.368832 -152.657556) (xy 115.369254 -152.619267) (xy 115.375857 -152.542973) (xy 115.389002 -152.46753)
			(xy 115.40859 -152.393499) (xy 115.421156 -152.357328) (xy 115.423829 -152.348897) (xy 115.423815 -152.331221)
			(xy 115.421156 -152.322784) (xy 115.408624 -152.286603) (xy 115.389048 -152.212571) (xy 115.375898 -152.137132)
			(xy 115.36927 -152.060844) (xy 115.368832 -152.022556) (xy 115.369211 -151.981443) (xy 115.376803 -151.89957)
			(xy 115.391918 -151.818746) (xy 115.414428 -151.739662) (xy 115.44414 -151.662993) (xy 115.480801 -151.589393)
			(xy 115.524097 -151.51949) (xy 115.573659 -151.453881) (xy 115.629065 -151.393126) (xy 115.689841 -151.337743)
			(xy 115.755469 -151.288206) (xy 115.825388 -151.244936) (xy 115.899002 -151.208303) (xy 115.975683 -151.178621)
			(xy 116.054775 -151.156141) (xy 116.135605 -151.141056) (xy 116.217481 -151.133495) (xy 116.258594 -151.133048)
			(xy 116.29691 -151.133415) (xy 116.373264 -151.139947) (xy 116.448771 -151.153032) (xy 116.52287 -151.172572)
			(xy 116.559076 -151.185118) (xy 116.567392 -151.187704) (xy 116.584796 -151.187704) (xy 116.593112 -151.185118)
			(xy 116.629327 -151.172602) (xy 116.703427 -151.153078) (xy 116.778931 -151.139993) (xy 116.855279 -151.133443)
			(xy 116.893594 -151.133048) (xy 116.933808 -151.133478) (xy 117.01391 -151.140701) (xy 117.093031 -151.155132)
			(xy 117.170525 -151.176654) (xy 117.2083 -151.190452) (xy 117.217087 -151.193359) (xy 117.235581 -151.193359)
			(xy 117.244368 -151.190452) (xy 117.282145 -151.176662) (xy 117.359642 -151.155155) (xy 117.438762 -151.140723)
			(xy 117.518861 -151.133486) (xy 117.559074 -151.133048) (xy 117.59739 -151.133421) (xy 117.673744 -151.139951)
			(xy 117.74925 -151.153034) (xy 117.82335 -151.172573) (xy 117.859556 -151.185118) (xy 117.867872 -151.187704)
			(xy 117.885276 -151.187704) (xy 117.893592 -151.185118) (xy 117.929809 -151.172608) (xy 118.003908 -151.153082)
			(xy 118.079411 -151.139995) (xy 118.155759 -151.133444) (xy 118.194074 -151.133048) (xy 118.23239 -151.133421)
			(xy 118.308744 -151.139951) (xy 118.38425 -151.153034) (xy 118.45835 -151.172573) (xy 118.494556 -151.185118)
			(xy 118.502872 -151.187704) (xy 118.520276 -151.187704) (xy 118.528592 -151.185118) (xy 118.564809 -151.172608)
			(xy 118.638908 -151.153082) (xy 118.714411 -151.139995) (xy 118.790759 -151.133444) (xy 118.829074 -151.133048)
			(xy 118.86739 -151.133421) (xy 118.943744 -151.139951) (xy 119.01925 -151.153034) (xy 119.09335 -151.172573)
			(xy 119.129556 -151.185118) (xy 119.137872 -151.187704) (xy 119.155276 -151.187704) (xy 119.163592 -151.185118)
			(xy 119.199718 -151.172636) (xy 119.273629 -151.153143) (xy 119.348939 -151.140056) (xy 119.425093 -151.133472)
			(xy 119.463312 -151.133048) (xy 119.464074 -151.133048) (xy 119.505181 -151.133537) (xy 119.587043 -151.141119)
			(xy 119.667858 -151.156221) (xy 119.746934 -151.178714) (xy 119.823598 -151.208407) (xy 119.897196 -151.245045)
			(xy 119.9671 -151.288316) (xy 120.032714 -151.337852) (xy 120.093479 -151.39323) (xy 120.148875 -151.453978)
			(xy 120.198431 -151.519577) (xy 120.241724 -151.589468) (xy 120.278384 -151.663055) (xy 120.3081 -151.73971)
			(xy 120.330617 -151.818779) (xy 120.345743 -151.899589) (xy 120.35335 -151.98145) (xy 120.353836 -152.022556)
			(xy 120.353419 -152.060846) (xy 120.346814 -152.137139) (xy 120.333668 -152.212582) (xy 120.314078 -152.286613)
			(xy 120.301512 -152.322784) (xy 120.298884 -152.331226) (xy 120.29887 -152.348891) (xy 120.301512 -152.357328)
			(xy 120.314046 -152.393509) (xy 120.333622 -152.467541) (xy 120.346772 -152.542979) (xy 120.353399 -152.619268)
			(xy 120.353836 -152.657556) (xy 120.353306 -152.698665) (xy 120.345722 -152.780533) (xy 120.330616 -152.861351)
			(xy 120.308115 -152.940431) (xy 120.278413 -153.017096) (xy 120.241762 -153.090693) (xy 120.198476 -153.160594)
			(xy 120.148923 -153.226202) (xy 120.093528 -153.286957) (xy 120.032762 -153.34234) (xy 119.967144 -153.391879)
			(xy 119.897234 -153.435151) (xy 119.823629 -153.471786) (xy 119.746958 -153.501473) (xy 119.667874 -153.523957)
			(xy 119.587052 -153.539047) (xy 119.505183 -153.546614) (xy 119.464074 -153.547064) (xy 119.425757 -153.546706)
			(xy 119.349404 -153.540171) (xy 119.273897 -153.527084) (xy 119.199798 -153.507541) (xy 119.163592 -153.494994)
			(xy 119.155276 -153.492408) (xy 119.137872 -153.492408) (xy 119.129556 -153.494994) (xy 119.093344 -153.507519)
			(xy 119.019243 -153.527041) (xy 118.943738 -153.540123) (xy 118.867389 -153.546671) (xy 118.829074 -153.547064)
			(xy 118.790757 -153.546706) (xy 118.714404 -153.540171) (xy 118.638897 -153.527084) (xy 118.564798 -153.507541)
			(xy 118.528592 -153.494994) (xy 118.520276 -153.492408) (xy 118.502872 -153.492408) (xy 118.494556 -153.494994)
			(xy 118.458344 -153.507519) (xy 118.384243 -153.527041) (xy 118.308738 -153.540123) (xy 118.232389 -153.546671)
			(xy 118.194074 -153.547064) (xy 118.155757 -153.546706) (xy 118.079404 -153.540171) (xy 118.003897 -153.527084)
			(xy 117.929798 -153.507541) (xy 117.893592 -153.494994) (xy 117.885276 -153.492408) (xy 117.867872 -153.492408)
			(xy 117.859556 -153.494994) (xy 117.823344 -153.507519) (xy 117.749243 -153.527041) (xy 117.673738 -153.540123)
			(xy 117.597389 -153.546671) (xy 117.559074 -153.547064) (xy 117.51886 -153.546643) (xy 117.438758 -153.539418)
			(xy 117.359636 -153.524984) (xy 117.282143 -153.50346) (xy 117.244368 -153.48966) (xy 117.235581 -153.486753)
			(xy 117.217087 -153.486753) (xy 117.2083 -153.48966) (xy 117.170526 -153.50346) (xy 117.093029 -153.524965)
			(xy 117.013907 -153.539393) (xy 116.933807 -153.546627) (xy 116.893594 -153.547064) (xy 116.855277 -153.5467)
			(xy 116.778924 -153.540167) (xy 116.703417 -153.527082) (xy 116.629318 -153.50754) (xy 116.593112 -153.494994)
			(xy 116.584796 -153.492408) (xy 116.567392 -153.492408) (xy 116.559076 -153.494994) (xy 116.522953 -153.507485)
			(xy 116.449041 -153.526976) (xy 116.37373 -153.54006) (xy 116.297575 -153.546641) (xy 116.259356 -153.547064)
			(xy 116.258594 -153.547064) (xy 116.217487 -153.546593) (xy 116.135624 -153.539008) (xy 116.05481 -153.523904)
			(xy 115.975734 -153.501409) (xy 115.89907 -153.471714) (xy 115.825473 -153.435075) (xy 115.755569 -153.391802)
			(xy 115.689955 -153.342264) (xy 115.629192 -153.286885) (xy 115.573796 -153.226137) (xy 115.52424 -153.160537)
			(xy 115.480947 -153.090646) (xy 115.444287 -153.017059) (xy 115.414571 -152.940403) (xy 115.392053 -152.861333)
			(xy 115.376926 -152.780524) (xy 115.369318 -152.698663) (xy 115.368832 -152.657556) (xy 35.354948 -152.657556)
			(xy 35.387298 -152.825405) (xy 35.41915 -153.032898) (xy 35.44308 -153.241454) (xy 35.459052 -153.45077)
			(xy 35.467044 -153.660542) (xy 35.467544 -153.765504) (xy 35.467044 -153.870466) (xy 35.459052 -154.080238)
			(xy 35.44308 -154.289554) (xy 35.422918 -154.465274) (xy 127.823468 -154.465274) (xy 127.824038 -154.420505)
			(xy 127.833047 -154.33142) (xy 127.850949 -154.243689) (xy 127.877566 -154.158197) (xy 127.894588 -154.116786)
			(xy 127.89817 -154.1072) (xy 127.89816 -154.086753) (xy 127.894588 -154.077162) (xy 127.87754 -154.03576)
			(xy 127.850909 -153.95027) (xy 127.833008 -153.862535) (xy 127.824018 -153.773445) (xy 127.823468 -153.728674)
			(xy 127.824038 -153.683905) (xy 127.833047 -153.59482) (xy 127.850949 -153.507089) (xy 127.877566 -153.421597)
			(xy 127.894588 -153.380186) (xy 127.89817 -153.3706) (xy 127.89816 -153.350153) (xy 127.894588 -153.340562)
			(xy 127.87754 -153.29916) (xy 127.850909 -153.21367) (xy 127.833008 -153.125935) (xy 127.824018 -153.036845)
			(xy 127.823468 -152.992074) (xy 127.823874 -152.950958) (xy 127.831464 -152.869076) (xy 127.846576 -152.788245)
			(xy 127.869082 -152.709152) (xy 127.898791 -152.632473) (xy 127.935447 -152.558863) (xy 127.978739 -152.488949)
			(xy 128.028297 -152.423328) (xy 128.083699 -152.362559) (xy 128.144471 -152.307161) (xy 128.210095 -152.257607)
			(xy 128.280012 -152.21432) (xy 128.353625 -152.177668) (xy 128.430305 -152.147965) (xy 128.509399 -152.125463)
			(xy 128.590232 -152.110356) (xy 128.672114 -152.102771) (xy 128.71323 -152.102312) (xy 128.754841 -152.102773)
			(xy 128.837698 -152.110553) (xy 128.919467 -152.126031) (xy 128.999435 -152.149074) (xy 129.076903 -152.179479)
			(xy 129.151195 -152.216982) (xy 129.186686 -152.23871) (xy 129.195829 -152.243863) (xy 129.216542 -152.24708)
			(xy 129.236814 -152.241752) (xy 129.24536 -152.235662) (xy 129.278989 -152.209671) (xy 129.350383 -152.163546)
			(xy 129.425854 -152.124445) (xy 129.504712 -152.092724) (xy 129.586237 -152.068675) (xy 129.669685 -152.052515)
			(xy 129.754295 -152.044393) (xy 129.796794 -152.043892) (xy 129.837907 -152.044419) (xy 129.919782 -152.052005)
			(xy 130.000607 -152.067113) (xy 130.079694 -152.089613) (xy 130.156368 -152.119315) (xy 130.229974 -152.155965)
			(xy 130.299884 -152.19925) (xy 130.365503 -152.2488) (xy 130.42627 -152.304193) (xy 130.481667 -152.364957)
			(xy 130.531221 -152.430573) (xy 130.57451 -152.500481) (xy 130.611164 -152.574085) (xy 130.64087 -152.650756)
			(xy 130.663376 -152.729842) (xy 130.678488 -152.810667) (xy 130.686079 -152.892541) (xy 130.686556 -152.933654)
			(xy 130.685993 -152.978424) (xy 130.676983 -153.067509) (xy 130.659077 -153.15524) (xy 130.632459 -153.240731)
			(xy 130.615436 -153.282142) (xy 130.611899 -153.291741) (xy 130.611882 -153.312176) (xy 130.615436 -153.321766)
			(xy 130.63244 -153.363117) (xy 130.659051 -153.448479) (xy 130.676958 -153.536082) (xy 130.68598 -153.625039)
			(xy 130.686556 -153.669746) (xy 130.686556 -153.670762) (xy 130.686302 -153.682192) (xy 130.712781 -153.688138)
			(xy 130.765016 -153.702881) (xy 130.790696 -153.711656) (xy 130.798893 -153.71417) (xy 130.816027 -153.71417)
			(xy 130.824224 -153.711656) (xy 130.85944 -153.699695) (xy 130.931444 -153.681041) (xy 131.004765 -153.668532)
			(xy 131.07888 -153.662259) (xy 131.11607 -153.661872) (xy 131.153259 -153.662271) (xy 131.227372 -153.668558)
			(xy 131.300692 -153.681065) (xy 131.372698 -153.699703) (xy 131.407916 -153.711656) (xy 131.416113 -153.71417)
			(xy 131.433247 -153.71417) (xy 131.441444 -153.711656) (xy 131.476659 -153.699689) (xy 131.548662 -153.681037)
			(xy 131.621984 -153.66853) (xy 131.6961 -153.662258) (xy 131.73329 -153.661872) (xy 131.77523 -153.662267)
			(xy 131.858732 -153.670239) (xy 131.941097 -153.686113) (xy 132.02158 -153.709744) (xy 132.099453 -153.740919)
			(xy 132.165372 -153.774902) (xy 188.441847 -153.774902) (xy 188.445843 -153.565016) (xy 188.457828 -153.355434)
			(xy 188.477782 -153.14646) (xy 188.505678 -152.938398) (xy 188.541475 -152.731548) (xy 188.58512 -152.526211)
			(xy 188.636552 -152.322685) (xy 188.695694 -152.121264) (xy 188.762462 -151.922241) (xy 188.836758 -151.725904)
			(xy 188.918476 -151.532538) (xy 189.007495 -151.342423) (xy 189.103688 -151.155835) (xy 189.206915 -150.973044)
			(xy 189.317026 -150.794316) (xy 189.433861 -150.619909) (xy 189.557251 -150.450077) (xy 189.687018 -150.285065)
			(xy 189.822972 -150.125114) (xy 189.964918 -149.970454) (xy 190.112648 -149.82131) (xy 190.26595 -149.677899)
			(xy 190.4246 -149.540428) (xy 190.588369 -149.409096) (xy 190.757019 -149.284095) (xy 190.930305 -149.165604)
			(xy 191.107977 -149.053797) (xy 191.289777 -148.948835) (xy 191.475441 -148.85087) (xy 191.664699 -148.760045)
			(xy 191.857279 -148.676491) (xy 192.0529 -148.600328) (xy 192.251278 -148.531669) (xy 192.452127 -148.470612)
			(xy 192.655154 -148.417245) (xy 192.860067 -148.371647) (xy 193.066566 -148.333882) (xy 193.274353 -148.304007)
			(xy 193.483128 -148.282064) (xy 193.692586 -148.268085) (xy 193.902425 -148.26209) (xy 194.112339 -148.264089)
			(xy 194.322026 -148.274077) (xy 194.53118 -148.292042) (xy 194.739498 -148.317956) (xy 194.946679 -148.351781)
			(xy 195.152423 -148.39347) (xy 195.356429 -148.442962) (xy 195.558404 -148.500184) (xy 195.758054 -148.565054)
			(xy 195.955089 -148.637478) (xy 196.149225 -148.717351) (xy 196.340178 -148.804557) (xy 196.527674 -148.898969)
			(xy 196.711439 -149.000451) (xy 196.891207 -149.108855) (xy 197.066718 -149.224025) (xy 197.237717 -149.345793)
			(xy 197.403957 -149.473982) (xy 197.565196 -149.608408) (xy 197.7212 -149.748875) (xy 197.871743 -149.895179)
			(xy 198.016607 -150.047108) (xy 198.155582 -150.204442) (xy 198.288467 -150.366953) (xy 198.415068 -150.534406)
			(xy 198.535203 -150.706556) (xy 198.648697 -150.883156) (xy 198.755385 -151.063948) (xy 198.855112 -151.248671)
			(xy 198.947735 -151.437057) (xy 199.033119 -151.628832) (xy 199.11114 -151.823719) (xy 199.181685 -152.021435)
			(xy 199.244652 -152.221693) (xy 199.299949 -152.424203) (xy 199.347496 -152.628672) (xy 199.387224 -152.834803)
			(xy 199.419076 -153.042296) (xy 199.443006 -153.250852) (xy 199.458978 -153.460168) (xy 199.46697 -153.66994)
			(xy 199.467428 -153.766012) (xy 272.382243 -153.766012) (xy 272.386239 -153.556126) (xy 272.398224 -153.346544)
			(xy 272.418178 -153.13757) (xy 272.446074 -152.929508) (xy 272.481871 -152.722658) (xy 272.525516 -152.517321)
			(xy 272.576948 -152.313795) (xy 272.63609 -152.112374) (xy 272.702858 -151.913351) (xy 272.777154 -151.717014)
			(xy 272.858872 -151.523648) (xy 272.947891 -151.333533) (xy 273.044084 -151.146945) (xy 273.147311 -150.964154)
			(xy 273.257422 -150.785426) (xy 273.374257 -150.611019) (xy 273.497647 -150.441187) (xy 273.627414 -150.276175)
			(xy 273.763368 -150.116224) (xy 273.905314 -149.961564) (xy 274.053044 -149.81242) (xy 274.206346 -149.669009)
			(xy 274.364996 -149.531538) (xy 274.528765 -149.400206) (xy 274.697415 -149.275205) (xy 274.870701 -149.156714)
			(xy 275.048373 -149.044907) (xy 275.230173 -148.939945) (xy 275.415837 -148.84198) (xy 275.605095 -148.751155)
			(xy 275.797675 -148.667601) (xy 275.993296 -148.591438) (xy 276.191674 -148.522779) (xy 276.392523 -148.461722)
			(xy 276.59555 -148.408355) (xy 276.800463 -148.362757) (xy 277.006962 -148.324992) (xy 277.214749 -148.295117)
			(xy 277.423524 -148.273174) (xy 277.632982 -148.259195) (xy 277.842821 -148.2532) (xy 278.052735 -148.255199)
			(xy 278.262422 -148.265187) (xy 278.471576 -148.283152) (xy 278.679894 -148.309066) (xy 278.887075 -148.342891)
			(xy 279.092819 -148.38458) (xy 279.296825 -148.434072) (xy 279.4988 -148.491294) (xy 279.69845 -148.556164)
			(xy 279.895485 -148.628588) (xy 280.089621 -148.708461) (xy 280.280574 -148.795667) (xy 280.46807 -148.890079)
			(xy 280.651835 -148.991561) (xy 280.831603 -149.099965) (xy 281.007114 -149.215135) (xy 281.178113 -149.336903)
			(xy 281.344353 -149.465092) (xy 281.505592 -149.599518) (xy 281.661596 -149.739985) (xy 281.812139 -149.886289)
			(xy 281.957003 -150.038218) (xy 282.095978 -150.195552) (xy 282.228863 -150.358063) (xy 282.355464 -150.525516)
			(xy 282.475599 -150.697666) (xy 282.589093 -150.874266) (xy 282.695781 -151.055058) (xy 282.795508 -151.239781)
			(xy 282.888131 -151.428167) (xy 282.973515 -151.619942) (xy 283.051536 -151.814829) (xy 283.122081 -152.012545)
			(xy 283.185048 -152.212803) (xy 283.240345 -152.415313) (xy 283.287892 -152.619782) (xy 283.305746 -152.71242)
			(xy 358.186997 -152.71242) (xy 358.191002 -152.606671) (xy 358.202992 -152.501528) (xy 358.222901 -152.397593)
			(xy 358.250612 -152.295461) (xy 358.285969 -152.195717) (xy 358.328767 -152.098933) (xy 358.378763 -152.005663)
			(xy 358.43567 -151.916442) (xy 358.499161 -151.831779) (xy 358.568873 -151.752161) (xy 358.644407 -151.678043)
			(xy 358.72533 -151.60985) (xy 358.811179 -151.547972) (xy 358.901462 -151.492765) (xy 358.995661 -151.444543)
			(xy 359.093238 -151.403583) (xy 359.193633 -151.370121) (xy 359.296271 -151.344347) (xy 359.400564 -151.326409)
			(xy 359.505915 -151.31641) (xy 359.611721 -151.314407) (xy 359.717375 -151.320412) (xy 359.822272 -151.334391)
			(xy 359.925812 -151.356262) (xy 360.027401 -151.385902) (xy 360.126458 -151.42314) (xy 360.222415 -151.467762)
			(xy 360.314722 -151.519514) (xy 360.402851 -151.578099) (xy 360.486297 -151.643181) (xy 360.564581 -151.714387)
			(xy 360.637256 -151.79131) (xy 360.703906 -151.87351) (xy 360.764148 -151.960514) (xy 360.817637 -152.051825)
			(xy 360.864068 -152.14692) (xy 360.903173 -152.245254) (xy 360.93473 -152.346265) (xy 360.958557 -152.449372)
			(xy 360.974518 -152.553986) (xy 360.982522 -152.659508) (xy 360.983022 -152.71242) (xy 360.982522 -152.765332)
			(xy 360.974518 -152.870854) (xy 360.958557 -152.975468) (xy 360.93473 -153.078575) (xy 360.903173 -153.179586)
			(xy 360.864068 -153.27792) (xy 360.817637 -153.373015) (xy 360.764148 -153.464326) (xy 360.703906 -153.55133)
			(xy 360.637256 -153.63353) (xy 360.564581 -153.710453) (xy 360.486297 -153.781659) (xy 360.402851 -153.846741)
			(xy 360.314722 -153.905326) (xy 360.222415 -153.957078) (xy 360.126458 -154.0017) (xy 360.027401 -154.038938)
			(xy 359.925812 -154.068578) (xy 359.822272 -154.090449) (xy 359.717375 -154.104428) (xy 359.611721 -154.110433)
			(xy 359.505915 -154.10843) (xy 359.400564 -154.098431) (xy 359.296271 -154.080493) (xy 359.193633 -154.054719)
			(xy 359.093238 -154.021257) (xy 358.995661 -153.980297) (xy 358.901462 -153.932075) (xy 358.811179 -153.876868)
			(xy 358.72533 -153.81499) (xy 358.644407 -153.746797) (xy 358.568873 -153.672679) (xy 358.499161 -153.593061)
			(xy 358.43567 -153.508398) (xy 358.378763 -153.419177) (xy 358.328767 -153.325907) (xy 358.285969 -153.229123)
			(xy 358.250612 -153.129379) (xy 358.222901 -153.027247) (xy 358.202992 -152.923312) (xy 358.191002 -152.818169)
			(xy 358.186997 -152.71242) (xy 283.305746 -152.71242) (xy 283.32762 -152.825913) (xy 283.359472 -153.033406)
			(xy 283.383402 -153.241962) (xy 283.399374 -153.451278) (xy 283.407366 -153.66105) (xy 283.407866 -153.766012)
			(xy 283.407366 -153.870974) (xy 283.399374 -154.080746) (xy 283.383402 -154.290062) (xy 283.359472 -154.498618)
			(xy 283.32762 -154.706111) (xy 283.287892 -154.912242) (xy 283.240345 -155.116711) (xy 283.185048 -155.319221)
			(xy 283.122081 -155.519479) (xy 283.051536 -155.717195) (xy 282.973515 -155.912082) (xy 282.888131 -156.103857)
			(xy 282.795508 -156.292243) (xy 282.695781 -156.476966) (xy 282.589093 -156.657758) (xy 282.475599 -156.834358)
			(xy 282.355464 -157.006508) (xy 282.228863 -157.173961) (xy 282.095978 -157.336472) (xy 281.957003 -157.493806)
			(xy 281.812139 -157.645735) (xy 281.661596 -157.792039) (xy 281.505592 -157.932506) (xy 281.344353 -158.066932)
			(xy 281.178113 -158.195121) (xy 281.007114 -158.316889) (xy 280.831603 -158.432059) (xy 280.651835 -158.540463)
			(xy 280.46807 -158.641945) (xy 280.280574 -158.736357) (xy 280.089621 -158.823563) (xy 279.895485 -158.903436)
			(xy 279.69845 -158.97586) (xy 279.4988 -159.04073) (xy 279.382794 -159.073596) (xy 343.127076 -159.073596)
			(xy 343.127653 -159.028827) (xy 343.136659 -158.939742) (xy 343.15456 -158.852011) (xy 343.181175 -158.766519)
			(xy 343.198196 -158.725108) (xy 343.201765 -158.715518) (xy 343.201764 -158.695074) (xy 343.198196 -158.685484)
			(xy 343.181156 -158.644079) (xy 343.154522 -158.55859) (xy 343.136619 -158.470856) (xy 343.127627 -158.381767)
			(xy 343.127076 -158.336996) (xy 343.127653 -158.292227) (xy 343.136659 -158.203142) (xy 343.15456 -158.115411)
			(xy 343.181175 -158.029919) (xy 343.198196 -157.988508) (xy 343.201765 -157.978918) (xy 343.201764 -157.958474)
			(xy 343.198196 -157.948884) (xy 343.181156 -157.907479) (xy 343.154522 -157.82199) (xy 343.136619 -157.734256)
			(xy 343.127627 -157.645167) (xy 343.127076 -157.600396) (xy 343.127549 -157.559286) (xy 343.135137 -157.477416)
			(xy 343.150247 -157.396596) (xy 343.172752 -157.317516) (xy 343.202459 -157.240849) (xy 343.239114 -157.167252)
			(xy 343.282404 -157.097351) (xy 343.33196 -157.031743) (xy 343.387359 -156.970988) (xy 343.448129 -156.915605)
			(xy 343.51375 -156.866067) (xy 343.583663 -156.822796) (xy 343.657271 -156.786161) (xy 343.733945 -156.756475)
			(xy 343.813032 -156.733992) (xy 343.893856 -156.718903) (xy 343.975728 -156.711337) (xy 344.016838 -156.710888)
			(xy 344.058442 -156.711362) (xy 344.14129 -156.719094) (xy 344.223055 -156.734524) (xy 344.303022 -156.757517)
			(xy 344.380495 -156.787874) (xy 344.454797 -156.825328) (xy 344.490294 -156.847032) (xy 344.499434 -156.852189)
			(xy 344.520149 -156.855402) (xy 344.540422 -156.850073) (xy 344.548968 -156.843984) (xy 344.582592 -156.818029)
			(xy 344.653971 -156.771973) (xy 344.729414 -156.73293) (xy 344.808235 -156.701255) (xy 344.889716 -156.677237)
			(xy 344.973116 -156.661094) (xy 345.057674 -156.652974) (xy 345.100148 -156.652468) (xy 345.100402 -156.652468)
			(xy 345.14151 -156.652911) (xy 345.223374 -156.660496) (xy 345.30419 -156.6756) (xy 345.383268 -156.698096)
			(xy 345.459933 -156.727791) (xy 345.533532 -156.764433) (xy 345.603437 -156.807707) (xy 345.669051 -156.857246)
			(xy 345.729816 -156.912627) (xy 345.785212 -156.973378) (xy 345.806812 -157.001972) (xy 386.403596 -157.001972)
			(xy 386.40399 -156.963682) (xy 386.410601 -156.887387) (xy 386.423753 -156.811945) (xy 386.44335 -156.737915)
			(xy 386.45592 -156.701744) (xy 386.458586 -156.693311) (xy 386.458577 -156.675637) (xy 386.45592 -156.6672)
			(xy 386.443367 -156.631026) (xy 386.423796 -156.556991) (xy 386.410652 -156.481551) (xy 386.40403 -156.40526)
			(xy 386.403596 -156.366972) (xy 386.404015 -156.328179) (xy 386.410791 -156.25089) (xy 386.424264 -156.174482)
			(xy 386.44433 -156.099536) (xy 386.45719 -156.062934) (xy 386.459858 -156.054502) (xy 386.459846 -156.036827)
			(xy 386.45719 -156.02839) (xy 386.444324 -155.991789) (xy 386.424239 -155.916847) (xy 386.410766 -155.840438)
			(xy 386.404005 -155.763146) (xy 386.403596 -155.724352) (xy 386.404014 -155.686062) (xy 386.410618 -155.609769)
			(xy 386.423763 -155.534326) (xy 386.443354 -155.460295) (xy 386.45592 -155.424124) (xy 386.458596 -155.415693)
			(xy 386.45858 -155.398017) (xy 386.45592 -155.38958) (xy 386.443389 -155.353398) (xy 386.423812 -155.279367)
			(xy 386.410662 -155.203928) (xy 386.404034 -155.12764) (xy 386.403596 -155.089352) (xy 386.40407 -155.049438)
			(xy 386.411294 -154.969935) (xy 386.425601 -154.891398) (xy 386.446874 -154.814455) (xy 386.460492 -154.776932)
			(xy 386.463345 -154.768269) (xy 386.463329 -154.750041) (xy 386.460492 -154.741372) (xy 386.44684 -154.70386)
			(xy 386.425547 -154.626919) (xy 386.411244 -154.548377) (xy 386.404048 -154.468869) (xy 386.403596 -154.428952)
			(xy 386.404014 -154.390662) (xy 386.410618 -154.314369) (xy 386.423763 -154.238926) (xy 386.443354 -154.164895)
			(xy 386.45592 -154.128724) (xy 386.458596 -154.120293) (xy 386.45858 -154.102617) (xy 386.45592 -154.09418)
			(xy 386.443389 -154.057998) (xy 386.423812 -153.983967) (xy 386.410662 -153.908528) (xy 386.404034 -153.83224)
			(xy 386.403596 -153.793952) (xy 386.404007 -153.75284) (xy 386.411599 -153.670969) (xy 386.426714 -153.590147)
			(xy 386.449223 -153.511065) (xy 386.478934 -153.434397) (xy 386.515593 -153.360799) (xy 386.558887 -153.290897)
			(xy 386.608448 -153.225289) (xy 386.663851 -153.164535) (xy 386.724625 -153.109152) (xy 386.79025 -153.059614)
			(xy 386.860166 -153.016344) (xy 386.933777 -152.97971) (xy 387.010455 -152.950026) (xy 387.089545 -152.927544)
			(xy 387.170372 -152.912457) (xy 387.252246 -152.904893) (xy 387.293358 -152.904444) (xy 387.331674 -152.904822)
			(xy 387.408027 -152.91135) (xy 387.483534 -152.924432) (xy 387.557634 -152.94397) (xy 387.59384 -152.956514)
			(xy 387.602156 -152.9591) (xy 387.61956 -152.9591) (xy 387.627876 -152.956514) (xy 387.663994 -152.944008)
			(xy 387.737908 -152.924522) (xy 387.81322 -152.911442) (xy 387.889376 -152.904865) (xy 387.927596 -152.904444)
			(xy 387.928358 -152.904444) (xy 387.969464 -152.904953) (xy 388.051326 -152.912533) (xy 388.13214 -152.927634)
			(xy 388.211216 -152.950125) (xy 388.28788 -152.979816) (xy 388.361478 -153.016453) (xy 388.431382 -153.059723)
			(xy 388.496996 -153.109258) (xy 388.55776 -153.164634) (xy 388.613157 -153.225381) (xy 388.662713 -153.290979)
			(xy 388.706006 -153.360869) (xy 388.742667 -153.434454) (xy 388.772383 -153.511109) (xy 388.7949 -153.590177)
			(xy 388.810027 -153.670986) (xy 388.817634 -153.752846) (xy 388.817889 -153.774394) (xy 436.382169 -153.774394)
			(xy 436.386165 -153.564508) (xy 436.39815 -153.354926) (xy 436.418104 -153.145952) (xy 436.446 -152.93789)
			(xy 436.481797 -152.73104) (xy 436.525442 -152.525703) (xy 436.576874 -152.322177) (xy 436.636016 -152.120756)
			(xy 436.702784 -151.921733) (xy 436.77708 -151.725396) (xy 436.858798 -151.53203) (xy 436.947817 -151.341915)
			(xy 437.04401 -151.155327) (xy 437.147237 -150.972536) (xy 437.257348 -150.793808) (xy 437.374183 -150.619401)
			(xy 437.497573 -150.449569) (xy 437.62734 -150.284557) (xy 437.763294 -150.124606) (xy 437.90524 -149.969946)
			(xy 438.05297 -149.820802) (xy 438.206272 -149.677391) (xy 438.364922 -149.53992) (xy 438.528691 -149.408588)
			(xy 438.697341 -149.283587) (xy 438.870627 -149.165096) (xy 439.048299 -149.053289) (xy 439.230099 -148.948327)
			(xy 439.415763 -148.850362) (xy 439.605021 -148.759537) (xy 439.797601 -148.675983) (xy 439.993222 -148.59982)
			(xy 440.1916 -148.531161) (xy 440.392449 -148.470104) (xy 440.595476 -148.416737) (xy 440.800389 -148.371139)
			(xy 441.006888 -148.333374) (xy 441.214675 -148.303499) (xy 441.42345 -148.281556) (xy 441.632908 -148.267577)
			(xy 441.842747 -148.261582) (xy 442.052661 -148.263581) (xy 442.262348 -148.273569) (xy 442.471502 -148.291534)
			(xy 442.67982 -148.317448) (xy 442.887001 -148.351273) (xy 443.092745 -148.392962) (xy 443.296751 -148.442454)
			(xy 443.498726 -148.499676) (xy 443.698376 -148.564546) (xy 443.895411 -148.63697) (xy 444.089547 -148.716843)
			(xy 444.2805 -148.804049) (xy 444.467996 -148.898461) (xy 444.651761 -148.999943) (xy 444.831529 -149.108347)
			(xy 445.00704 -149.223517) (xy 445.178039 -149.345285) (xy 445.344279 -149.473474) (xy 445.505518 -149.6079)
			(xy 445.661522 -149.748367) (xy 445.812065 -149.894671) (xy 445.956929 -150.0466) (xy 446.095904 -150.203934)
			(xy 446.228789 -150.366445) (xy 446.35539 -150.533898) (xy 446.475525 -150.706048) (xy 446.589019 -150.882648)
			(xy 446.695707 -151.06344) (xy 446.795434 -151.248163) (xy 446.888057 -151.436549) (xy 446.973441 -151.628324)
			(xy 447.051462 -151.823211) (xy 447.122007 -152.020927) (xy 447.184974 -152.221185) (xy 447.240271 -152.423695)
			(xy 447.287818 -152.628164) (xy 447.327546 -152.834295) (xy 447.359398 -153.041788) (xy 447.383328 -153.250344)
			(xy 447.3993 -153.45966) (xy 447.407292 -153.669432) (xy 447.407792 -153.774394) (xy 447.407292 -153.879356)
			(xy 447.3993 -154.089128) (xy 447.383328 -154.298444) (xy 447.359398 -154.507) (xy 447.327546 -154.714493)
			(xy 447.287818 -154.920624) (xy 447.240271 -155.125093) (xy 447.184974 -155.327603) (xy 447.122007 -155.527861)
			(xy 447.051462 -155.725577) (xy 446.973441 -155.920464) (xy 446.888057 -156.112239) (xy 446.795434 -156.300625)
			(xy 446.695707 -156.485348) (xy 446.589019 -156.66614) (xy 446.475525 -156.84274) (xy 446.35539 -157.01489)
			(xy 446.228789 -157.182343) (xy 446.095904 -157.344854) (xy 445.956929 -157.502188) (xy 445.812065 -157.654117)
			(xy 445.661522 -157.800421) (xy 445.505518 -157.940888) (xy 445.344279 -158.075314) (xy 445.178039 -158.203503)
			(xy 445.00704 -158.325271) (xy 444.831529 -158.440441) (xy 444.651761 -158.548845) (xy 444.467996 -158.650327)
			(xy 444.2805 -158.744739) (xy 444.089547 -158.831945) (xy 443.895411 -158.911818) (xy 443.698376 -158.984242)
			(xy 443.498726 -159.049112) (xy 443.296751 -159.106334) (xy 443.092745 -159.155826) (xy 442.887001 -159.197515)
			(xy 442.67982 -159.23134) (xy 442.471502 -159.257254) (xy 442.262348 -159.275219) (xy 442.052661 -159.285207)
			(xy 441.842747 -159.287206) (xy 441.632908 -159.281211) (xy 441.42345 -159.267232) (xy 441.214675 -159.245289)
			(xy 441.006888 -159.215414) (xy 440.800389 -159.177649) (xy 440.595476 -159.132051) (xy 440.392449 -159.078684)
			(xy 440.1916 -159.017627) (xy 439.993222 -158.948968) (xy 439.797601 -158.872805) (xy 439.605021 -158.789251)
			(xy 439.415763 -158.698426) (xy 439.230099 -158.600461) (xy 439.048299 -158.495499) (xy 438.870627 -158.383692)
			(xy 438.697341 -158.265201) (xy 438.528691 -158.1402) (xy 438.364922 -158.008868) (xy 438.206272 -157.871397)
			(xy 438.05297 -157.727986) (xy 437.90524 -157.578842) (xy 437.763294 -157.424182) (xy 437.62734 -157.264231)
			(xy 437.497573 -157.099219) (xy 437.374183 -156.929387) (xy 437.257348 -156.75498) (xy 437.147237 -156.576252)
			(xy 437.04401 -156.393461) (xy 436.947817 -156.206873) (xy 436.858798 -156.016758) (xy 436.77708 -155.823392)
			(xy 436.702784 -155.627055) (xy 436.636016 -155.428032) (xy 436.576874 -155.226611) (xy 436.525442 -155.023085)
			(xy 436.481797 -154.817748) (xy 436.446 -154.610898) (xy 436.418104 -154.402836) (xy 436.39815 -154.193862)
			(xy 436.386165 -153.98428) (xy 436.382169 -153.774394) (xy 388.817889 -153.774394) (xy 388.81812 -153.793952)
			(xy 388.817702 -153.832242) (xy 388.811098 -153.908535) (xy 388.797953 -153.983978) (xy 388.778362 -154.058009)
			(xy 388.765796 -154.09418) (xy 388.763168 -154.102623) (xy 388.763152 -154.120288) (xy 388.765796 -154.128724)
			(xy 388.778328 -154.164905) (xy 388.797905 -154.238937) (xy 388.811055 -154.314375) (xy 388.817683 -154.390664)
			(xy 388.81812 -154.428952) (xy 388.817646 -154.468866) (xy 388.810422 -154.548369) (xy 388.796115 -154.626906)
			(xy 388.774842 -154.703849) (xy 388.761224 -154.741372) (xy 388.758419 -154.750047) (xy 388.758403 -154.768264)
			(xy 388.761224 -154.776932) (xy 388.774878 -154.814443) (xy 388.79617 -154.891385) (xy 388.810472 -154.969927)
			(xy 388.817668 -155.049435) (xy 388.81812 -155.089352) (xy 388.817702 -155.127642) (xy 388.811098 -155.203935)
			(xy 388.797953 -155.279378) (xy 388.778362 -155.353409) (xy 388.765796 -155.38958) (xy 388.763168 -155.398023)
			(xy 388.763152 -155.415688) (xy 388.765796 -155.424124) (xy 388.778328 -155.460305) (xy 388.797905 -155.534337)
			(xy 388.811055 -155.609775) (xy 388.817683 -155.686064) (xy 388.81812 -155.724352) (xy 388.817677 -155.763144)
			(xy 388.810908 -155.840433) (xy 388.797442 -155.916841) (xy 388.777382 -155.991787) (xy 388.764526 -156.02839)
			(xy 388.761895 -156.036832) (xy 388.761883 -156.054497) (xy 388.764526 -156.062934) (xy 388.7774 -156.099532)
			(xy 388.797482 -156.174476) (xy 388.810953 -156.250885) (xy 388.817712 -156.328178) (xy 388.81812 -156.366972)
			(xy 388.817708 -156.405262) (xy 388.811103 -156.481556) (xy 388.797955 -156.556998) (xy 388.778363 -156.631029)
			(xy 388.765796 -156.6672) (xy 388.763157 -156.67564) (xy 388.763148 -156.693308) (xy 388.765796 -156.701744)
			(xy 388.778334 -156.737923) (xy 388.797909 -156.811956) (xy 388.811058 -156.887395) (xy 388.817683 -156.963684)
			(xy 388.81812 -157.001972) (xy 388.817621 -157.043082) (xy 388.810036 -157.124951) (xy 388.794928 -157.20577)
			(xy 388.772425 -157.284851) (xy 388.742721 -157.361517) (xy 388.706068 -157.435115) (xy 388.66278 -157.505016)
			(xy 388.613226 -157.570624) (xy 388.557828 -157.631379) (xy 388.49706 -157.686762) (xy 388.43144 -157.736301)
			(xy 388.361528 -157.779573) (xy 388.287921 -157.816208) (xy 388.211248 -157.845893) (xy 388.132162 -157.868377)
			(xy 388.051339 -157.883465) (xy 387.969468 -157.891031) (xy 387.928358 -157.89148) (xy 387.890041 -157.891126)
			(xy 387.813688 -157.88459) (xy 387.738181 -157.871501) (xy 387.664082 -157.851957) (xy 387.627876 -157.83941)
			(xy 387.61956 -157.836824) (xy 387.602156 -157.836824) (xy 387.59384 -157.83941) (xy 387.557721 -157.851912)
			(xy 387.483807 -157.871399) (xy 387.408495 -157.88448) (xy 387.33234 -157.891059) (xy 387.29412 -157.89148)
			(xy 387.293358 -157.89148) (xy 387.252251 -157.891028) (xy 387.170388 -157.88344) (xy 387.089574 -157.868332)
			(xy 387.010498 -157.845835) (xy 386.933835 -157.816138) (xy 386.860238 -157.779497) (xy 386.790335 -157.736222)
			(xy 386.724722 -157.686684) (xy 386.663959 -157.631304) (xy 386.608563 -157.570555) (xy 386.559008 -157.504955)
			(xy 386.515715 -157.435063) (xy 386.479055 -157.361475) (xy 386.449338 -157.28482) (xy 386.42682 -157.20575)
			(xy 386.411692 -157.12494) (xy 386.404083 -157.043079) (xy 386.403596 -157.001972) (xy 345.806812 -157.001972)
			(xy 345.834767 -157.03898) (xy 345.878059 -157.108874) (xy 345.914719 -157.182463) (xy 345.944433 -157.259121)
			(xy 345.966949 -157.338193) (xy 345.982074 -157.419006) (xy 345.989679 -157.500868) (xy 345.990164 -157.541976)
			(xy 345.989609 -157.586746) (xy 345.980596 -157.675831) (xy 345.962689 -157.763562) (xy 345.936068 -157.849053)
			(xy 345.919044 -157.890464) (xy 345.915494 -157.900059) (xy 345.915485 -157.920497) (xy 345.919044 -157.930088)
			(xy 345.936056 -157.971436) (xy 345.962665 -158.056799) (xy 345.980569 -158.144403) (xy 345.989589 -158.233361)
			(xy 345.990164 -158.278068) (xy 345.990164 -158.279084) (xy 345.98991 -158.290514) (xy 346.016389 -158.296459)
			(xy 346.068624 -158.311202) (xy 346.094304 -158.319978) (xy 346.102501 -158.322492) (xy 346.119635 -158.322492)
			(xy 346.127832 -158.319978) (xy 346.163048 -158.308033) (xy 346.235059 -158.289446) (xy 346.308381 -158.277006)
			(xy 346.382492 -158.2708) (xy 346.419678 -158.270448) (xy 346.456862 -158.27082) (xy 346.53097 -158.277041)
			(xy 346.60429 -158.289483) (xy 346.676301 -158.308056) (xy 346.711524 -158.319978) (xy 346.719721 -158.322492)
			(xy 346.736855 -158.322492) (xy 346.745052 -158.319978) (xy 346.780146 -158.308069) (xy 346.851906 -158.289524)
			(xy 346.924971 -158.277084) (xy 346.998824 -158.270837) (xy 347.035882 -158.270448) (xy 347.036898 -158.270448)
			(xy 347.078822 -158.270999) (xy 347.162292 -158.278969) (xy 347.244625 -158.294837) (xy 347.325078 -158.31846)
			(xy 347.40292 -158.349624) (xy 347.477448 -158.388045) (xy 347.547987 -158.433377) (xy 347.613896 -158.485209)
			(xy 347.674581 -158.543071) (xy 347.72949 -158.60644) (xy 347.778127 -158.674741) (xy 347.820052 -158.747357)
			(xy 347.854884 -158.823628) (xy 347.882308 -158.902865) (xy 347.902076 -158.984351) (xy 347.914009 -159.067346)
			(xy 347.917999 -159.1511) (xy 347.914009 -159.234854) (xy 347.902076 -159.317849) (xy 347.882308 -159.399335)
			(xy 347.854884 -159.478572) (xy 347.820052 -159.554843) (xy 347.778127 -159.627459) (xy 347.72949 -159.69576)
			(xy 347.674581 -159.759129) (xy 347.613896 -159.816991) (xy 347.547987 -159.868823) (xy 347.477448 -159.914155)
			(xy 347.40292 -159.952576) (xy 347.325078 -159.98374) (xy 347.244625 -160.007363) (xy 347.162292 -160.023231)
			(xy 347.078822 -160.031201) (xy 347.036898 -160.031684) (xy 347.035882 -160.031684) (xy 346.998825 -160.031285)
			(xy 346.924976 -160.025019) (xy 346.851913 -160.012575) (xy 346.780153 -159.994041) (xy 346.745052 -159.982154)
			(xy 346.736855 -159.97964) (xy 346.719721 -159.97964) (xy 346.711524 -159.982154) (xy 346.684116 -159.991499)
			(xy 346.628318 -160.007008) (xy 346.600018 -160.013142) (xy 346.590235 -160.015622) (xy 346.573598 -160.027019)
			(xy 346.562626 -160.04394) (xy 346.560394 -160.053782) (xy 346.550929 -160.102889) (xy 346.522417 -160.19875)
			(xy 346.503498 -160.245044) (xy 346.499892 -160.254619) (xy 346.499745 -160.275056) (xy 346.503244 -160.284668)
			(xy 346.520278 -160.326041) (xy 346.546893 -160.41147) (xy 346.564794 -160.499139) (xy 346.5738 -160.588163)
			(xy 346.574364 -160.632902) (xy 346.574364 -160.633156) (xy 346.57386 -160.675504) (xy 346.565809 -160.759818)
			(xy 346.54978 -160.842984) (xy 346.525919 -160.924251) (xy 346.49444 -161.002881) (xy 346.455629 -161.078162)
			(xy 346.409839 -161.149414) (xy 346.357483 -161.21599) (xy 346.299035 -161.277288) (xy 346.235025 -161.332753)
			(xy 346.166033 -161.381882) (xy 346.092683 -161.424231) (xy 346.01564 -161.459415) (xy 345.935601 -161.487117)
			(xy 345.853292 -161.507085) (xy 345.769457 -161.519138) (xy 345.684856 -161.523169) (xy 345.600255 -161.519138)
			(xy 345.51642 -161.507085) (xy 345.434111 -161.487117) (xy 345.354072 -161.459415) (xy 345.277029 -161.424231)
			(xy 345.203679 -161.381882) (xy 345.134687 -161.332753) (xy 345.070677 -161.277288) (xy 345.012229 -161.21599)
			(xy 344.959873 -161.149414) (xy 344.914083 -161.078162) (xy 344.875272 -161.002881) (xy 344.843793 -160.924251)
			(xy 344.819932 -160.842984) (xy 344.803903 -160.759818) (xy 344.795852 -160.675504) (xy 344.795348 -160.633156)
			(xy 344.795348 -160.632902) (xy 344.795938 -160.588164) (xy 344.804948 -160.499143) (xy 344.822847 -160.411476)
			(xy 344.849453 -160.326048) (xy 344.866468 -160.284668) (xy 344.870056 -160.275084) (xy 344.87004 -160.254635)
			(xy 344.866468 -160.245044) (xy 344.849433 -160.203637) (xy 344.822801 -160.118148) (xy 344.804897 -160.030415)
			(xy 344.795901 -159.941327) (xy 344.795348 -159.896556) (xy 344.795678 -159.859467) (xy 344.801776 -159.78554)
			(xy 344.814009 -159.712377) (xy 344.82278 -159.676338) (xy 344.824538 -159.668008) (xy 344.823098 -159.651057)
			(xy 344.816174 -159.635517) (xy 344.810588 -159.629094) (xy 344.770202 -159.586168) (xy 344.758264 -159.588708)
			(xy 344.749364 -159.591023) (xy 344.733871 -159.600904) (xy 344.728038 -159.608012) (xy 344.702891 -159.640664)
			(xy 344.647483 -159.701681) (xy 344.586669 -159.757312) (xy 344.520971 -159.807081) (xy 344.450952 -159.850561)
			(xy 344.377213 -159.887379) (xy 344.300384 -159.917221) (xy 344.221125 -159.93983) (xy 344.140115 -159.955012)
			(xy 344.058048 -159.962637) (xy 344.016838 -159.963104) (xy 343.975733 -159.962551) (xy 343.893874 -159.954971)
			(xy 343.813062 -159.939871) (xy 343.733989 -159.917381) (xy 343.657327 -159.887692) (xy 343.583731 -159.851057)
			(xy 343.513829 -159.807789) (xy 343.448216 -159.758257) (xy 343.387452 -159.702884) (xy 343.332056 -159.642141)
			(xy 343.2825 -159.576547) (xy 343.239206 -159.506661) (xy 343.202543 -159.433078) (xy 343.172826 -159.356428)
			(xy 343.150306 -159.277363) (xy 343.135175 -159.196557) (xy 343.127564 -159.114701) (xy 343.127076 -159.073596)
			(xy 279.382794 -159.073596) (xy 279.296825 -159.097952) (xy 279.092819 -159.147444) (xy 278.887075 -159.189133)
			(xy 278.679894 -159.222958) (xy 278.471576 -159.248872) (xy 278.262422 -159.266837) (xy 278.052735 -159.276825)
			(xy 277.842821 -159.278824) (xy 277.632982 -159.272829) (xy 277.423524 -159.25885) (xy 277.214749 -159.236907)
			(xy 277.006962 -159.207032) (xy 276.800463 -159.169267) (xy 276.59555 -159.123669) (xy 276.392523 -159.070302)
			(xy 276.191674 -159.009245) (xy 275.993296 -158.940586) (xy 275.797675 -158.864423) (xy 275.605095 -158.780869)
			(xy 275.415837 -158.690044) (xy 275.230173 -158.592079) (xy 275.048373 -158.487117) (xy 274.870701 -158.37531)
			(xy 274.697415 -158.256819) (xy 274.528765 -158.131818) (xy 274.364996 -158.000486) (xy 274.206346 -157.863015)
			(xy 274.053044 -157.719604) (xy 273.905314 -157.57046) (xy 273.763368 -157.4158) (xy 273.627414 -157.255849)
			(xy 273.497647 -157.090837) (xy 273.374257 -156.921005) (xy 273.257422 -156.746598) (xy 273.147311 -156.56787)
			(xy 273.044084 -156.385079) (xy 272.947891 -156.198491) (xy 272.858872 -156.008376) (xy 272.777154 -155.81501)
			(xy 272.702858 -155.618673) (xy 272.63609 -155.41965) (xy 272.576948 -155.218229) (xy 272.525516 -155.014703)
			(xy 272.481871 -154.809366) (xy 272.446074 -154.602516) (xy 272.418178 -154.394454) (xy 272.398224 -154.18548)
			(xy 272.386239 -153.975898) (xy 272.382243 -153.766012) (xy 199.467428 -153.766012) (xy 199.46747 -153.774902)
			(xy 199.46697 -153.879864) (xy 199.458978 -154.089636) (xy 199.443006 -154.298952) (xy 199.419076 -154.507508)
			(xy 199.387224 -154.715001) (xy 199.347496 -154.921132) (xy 199.299949 -155.125601) (xy 199.244652 -155.328111)
			(xy 199.181685 -155.528369) (xy 199.11114 -155.726085) (xy 199.033119 -155.920972) (xy 198.947735 -156.112747)
			(xy 198.855112 -156.301133) (xy 198.755385 -156.485856) (xy 198.648697 -156.666648) (xy 198.535203 -156.843248)
			(xy 198.415068 -157.015398) (xy 198.288467 -157.182851) (xy 198.155582 -157.345362) (xy 198.016607 -157.502696)
			(xy 197.871743 -157.654625) (xy 197.7212 -157.800929) (xy 197.565196 -157.941396) (xy 197.403957 -158.075822)
			(xy 197.237717 -158.204011) (xy 197.066718 -158.325779) (xy 196.891207 -158.440949) (xy 196.711439 -158.549353)
			(xy 196.527674 -158.650835) (xy 196.340178 -158.745247) (xy 196.149225 -158.832453) (xy 195.955089 -158.912326)
			(xy 195.758054 -158.98475) (xy 195.558404 -159.04962) (xy 195.356429 -159.106842) (xy 195.152423 -159.156334)
			(xy 194.946679 -159.198023) (xy 194.739498 -159.231848) (xy 194.53118 -159.257762) (xy 194.322026 -159.275727)
			(xy 194.112339 -159.285715) (xy 193.902425 -159.287714) (xy 193.692586 -159.281719) (xy 193.483128 -159.26774)
			(xy 193.274353 -159.245797) (xy 193.066566 -159.215922) (xy 192.860067 -159.178157) (xy 192.655154 -159.132559)
			(xy 192.452127 -159.079192) (xy 192.251278 -159.018135) (xy 192.0529 -158.949476) (xy 191.857279 -158.873313)
			(xy 191.664699 -158.789759) (xy 191.475441 -158.698934) (xy 191.289777 -158.600969) (xy 191.107977 -158.496007)
			(xy 190.930305 -158.3842) (xy 190.757019 -158.265709) (xy 190.588369 -158.140708) (xy 190.4246 -158.009376)
			(xy 190.26595 -157.871905) (xy 190.112648 -157.728494) (xy 189.964918 -157.57935) (xy 189.822972 -157.42469)
			(xy 189.687018 -157.264739) (xy 189.557251 -157.099727) (xy 189.433861 -156.929895) (xy 189.317026 -156.755488)
			(xy 189.206915 -156.57676) (xy 189.103688 -156.393969) (xy 189.007495 -156.207381) (xy 188.918476 -156.017266)
			(xy 188.836758 -155.8239) (xy 188.762462 -155.627563) (xy 188.695694 -155.42854) (xy 188.636552 -155.227119)
			(xy 188.58512 -155.023593) (xy 188.541475 -154.818256) (xy 188.505678 -154.611406) (xy 188.477782 -154.403344)
			(xy 188.457828 -154.19437) (xy 188.445843 -153.984788) (xy 188.441847 -153.774902) (xy 132.165372 -153.774902)
			(xy 132.17401 -153.779355) (xy 132.244575 -153.824704) (xy 132.31051 -153.876555) (xy 132.371218 -153.934439)
			(xy 132.426149 -153.997832) (xy 132.474805 -154.066159) (xy 132.516746 -154.138802) (xy 132.551591 -154.215103)
			(xy 132.579026 -154.29437) (xy 132.598802 -154.375887) (xy 132.61074 -154.458914) (xy 132.614731 -154.5427)
			(xy 132.61074 -154.626486) (xy 132.598802 -154.709513) (xy 132.579026 -154.79103) (xy 132.551591 -154.870297)
			(xy 132.516746 -154.946598) (xy 132.474805 -155.019241) (xy 132.426149 -155.087568) (xy 132.371218 -155.150961)
			(xy 132.31051 -155.208845) (xy 132.244575 -155.260696) (xy 132.17401 -155.306045) (xy 132.099453 -155.344481)
			(xy 132.02158 -155.375656) (xy 131.941097 -155.399287) (xy 131.858732 -155.415161) (xy 131.77523 -155.423133)
			(xy 131.73329 -155.423616) (xy 131.6961 -155.423229) (xy 131.621987 -155.416939) (xy 131.548668 -155.404428)
			(xy 131.476662 -155.385787) (xy 131.441444 -155.373832) (xy 131.433247 -155.371318) (xy 131.416113 -155.371318)
			(xy 131.407916 -155.373832) (xy 131.374578 -155.385154) (xy 131.306486 -155.403082) (xy 131.237181 -155.41552)
			(xy 131.202176 -155.419298) (xy 131.192163 -155.420682) (xy 131.174401 -155.43031) (xy 131.161723 -155.446041)
			(xy 131.158488 -155.45562) (xy 131.151035 -155.480306) (xy 131.133624 -155.528851) (xy 131.12369 -155.552648)
			(xy 131.120082 -155.562222) (xy 131.119936 -155.58266) (xy 131.123436 -155.592272) (xy 131.140471 -155.633645)
			(xy 131.167086 -155.719073) (xy 131.184987 -155.806743) (xy 131.193992 -155.895767) (xy 131.194556 -155.940506)
			(xy 131.194556 -155.94076) (xy 131.194052 -155.983108) (xy 131.186001 -156.067422) (xy 131.169972 -156.150588)
			(xy 131.146111 -156.231855) (xy 131.114632 -156.310485) (xy 131.075821 -156.385766) (xy 131.030031 -156.457018)
			(xy 130.977675 -156.523594) (xy 130.919227 -156.584892) (xy 130.855217 -156.640357) (xy 130.786225 -156.689486)
			(xy 130.712875 -156.731835) (xy 130.635832 -156.767019) (xy 130.555793 -156.794721) (xy 130.473484 -156.814689)
			(xy 130.389649 -156.826742) (xy 130.305048 -156.830773) (xy 130.220447 -156.826742) (xy 130.136612 -156.814689)
			(xy 130.054303 -156.794721) (xy 129.974264 -156.767019) (xy 129.897221 -156.731835) (xy 129.823871 -156.689486)
			(xy 129.754879 -156.640357) (xy 129.690869 -156.584892) (xy 129.632421 -156.523594) (xy 129.580065 -156.457018)
			(xy 129.534275 -156.385766) (xy 129.495464 -156.310485) (xy 129.463985 -156.231855) (xy 129.440124 -156.150588)
			(xy 129.424095 -156.067422) (xy 129.416044 -155.983108) (xy 129.41554 -155.94076) (xy 129.41554 -155.940506)
			(xy 129.416091 -155.895767) (xy 129.425111 -155.806745) (xy 129.443021 -155.719078) (xy 129.46964 -155.633651)
			(xy 129.48666 -155.592272) (xy 129.490247 -155.582688) (xy 129.490232 -155.562239) (xy 129.48666 -155.552648)
			(xy 129.471663 -155.516314) (xy 129.447353 -155.441557) (xy 129.429731 -155.364948) (xy 129.418932 -155.287083)
			(xy 129.416556 -155.247848) (xy 129.415794 -155.233878) (xy 129.400046 -155.21051) (xy 129.29235 -155.160472)
			(xy 129.264664 -155.16352) (xy 129.253234 -155.172156) (xy 129.220015 -155.196974) (xy 129.149739 -155.241)
			(xy 129.075668 -155.27829) (xy 128.998447 -155.308521) (xy 128.918747 -155.33143) (xy 128.83726 -155.346818)
			(xy 128.754694 -155.354552) (xy 128.71323 -155.355036) (xy 128.672115 -155.354573) (xy 128.590235 -155.346988)
			(xy 128.509404 -155.33188) (xy 128.430313 -155.309379) (xy 128.353635 -155.279675) (xy 128.280025 -155.243023)
			(xy 128.210111 -155.199735) (xy 128.144489 -155.150181) (xy 128.08372 -155.094783) (xy 128.028322 -155.034014)
			(xy 127.978767 -154.968393) (xy 127.935479 -154.898479) (xy 127.898826 -154.824869) (xy 127.869122 -154.748191)
			(xy 127.84662 -154.669099) (xy 127.831512 -154.588269) (xy 127.823927 -154.506389) (xy 127.823468 -154.465274)
			(xy 35.422918 -154.465274) (xy 35.41915 -154.49811) (xy 35.387298 -154.705603) (xy 35.34757 -154.911734)
			(xy 35.300023 -155.116203) (xy 35.244726 -155.318713) (xy 35.181759 -155.518971) (xy 35.111214 -155.716687)
			(xy 35.033193 -155.911574) (xy 34.947809 -156.103349) (xy 34.855186 -156.291735) (xy 34.755459 -156.476458)
			(xy 34.648771 -156.65725) (xy 34.535277 -156.83385) (xy 34.415142 -157.006) (xy 34.288541 -157.173453)
			(xy 34.155656 -157.335964) (xy 34.016681 -157.493298) (xy 33.871817 -157.645227) (xy 33.721274 -157.791531)
			(xy 33.56527 -157.931998) (xy 33.404031 -158.066424) (xy 33.237791 -158.194613) (xy 33.066792 -158.316381)
			(xy 32.891281 -158.431551) (xy 32.711513 -158.539955) (xy 32.527748 -158.641437) (xy 32.340252 -158.735849)
			(xy 32.149299 -158.823055) (xy 31.955163 -158.902928) (xy 31.758128 -158.975352) (xy 31.558478 -159.040222)
			(xy 31.356503 -159.097444) (xy 31.152497 -159.146936) (xy 30.946753 -159.188625) (xy 30.739572 -159.22245)
			(xy 30.531254 -159.248364) (xy 30.3221 -159.266329) (xy 30.112413 -159.276317) (xy 29.902499 -159.278316)
			(xy 29.69266 -159.272321) (xy 29.483202 -159.258342) (xy 29.274427 -159.236399) (xy 29.06664 -159.206524)
			(xy 28.860141 -159.168759) (xy 28.655228 -159.123161) (xy 28.452201 -159.069794) (xy 28.251352 -159.008737)
			(xy 28.052974 -158.940078) (xy 27.857353 -158.863915) (xy 27.664773 -158.780361) (xy 27.475515 -158.689536)
			(xy 27.289851 -158.591571) (xy 27.108051 -158.486609) (xy 26.930379 -158.374802) (xy 26.757093 -158.256311)
			(xy 26.588443 -158.13131) (xy 26.424674 -157.999978) (xy 26.266024 -157.862507) (xy 26.112722 -157.719096)
			(xy 25.964992 -157.569952) (xy 25.823046 -157.415292) (xy 25.687092 -157.255341) (xy 25.557325 -157.090329)
			(xy 25.433935 -156.920497) (xy 25.3171 -156.74609) (xy 25.206989 -156.567362) (xy 25.103762 -156.384571)
			(xy 25.007569 -156.197983) (xy 24.91855 -156.007868) (xy 24.836832 -155.814502) (xy 24.762536 -155.618165)
			(xy 24.695768 -155.419142) (xy 24.636626 -155.217721) (xy 24.585194 -155.014195) (xy 24.541549 -154.808858)
			(xy 24.505752 -154.602008) (xy 24.477856 -154.393946) (xy 24.457902 -154.184972) (xy 24.445917 -153.97539)
			(xy 24.441921 -153.765504) (xy 2.509012 -153.765504) (xy 2.509012 -164.097716) (xy 86.129368 -164.097716)
			(xy 86.129877 -164.05494) (xy 86.138089 -163.969783) (xy 86.154448 -163.88581) (xy 86.178803 -163.803797)
			(xy 86.194392 -163.76396) (xy 86.19746 -163.755511) (xy 86.19811 -163.737557) (xy 86.195662 -163.728908)
			(xy 86.181097 -163.683434) (xy 86.160666 -163.590154) (xy 86.150355 -163.495221) (xy 86.149688 -163.447476)
			(xy 86.150084 -163.409186) (xy 86.156694 -163.332892) (xy 86.169846 -163.257449) (xy 86.189443 -163.183419)
			(xy 86.202012 -163.147248) (xy 86.204676 -163.138815) (xy 86.204669 -163.121141) (xy 86.202012 -163.112704)
			(xy 86.18946 -163.076529) (xy 86.169889 -163.002495) (xy 86.156744 -162.927055) (xy 86.150122 -162.850764)
			(xy 86.149688 -162.812476) (xy 86.15013 -162.771365) (xy 86.157719 -162.689494) (xy 86.172832 -162.608673)
			(xy 86.195339 -162.529592) (xy 86.225048 -162.452925) (xy 86.261705 -162.379327) (xy 86.304997 -162.309425)
			(xy 86.354555 -162.243817) (xy 86.409957 -162.183063) (xy 86.470728 -162.12768) (xy 86.536351 -162.078142)
			(xy 86.606266 -162.034871) (xy 86.679876 -161.998237) (xy 86.756552 -161.968552) (xy 86.83564 -161.94607)
			(xy 86.916466 -161.930982) (xy 86.998339 -161.923417) (xy 87.03945 -161.922968) (xy 87.077766 -161.923352)
			(xy 87.154119 -161.92988) (xy 87.229626 -161.94296) (xy 87.303725 -161.962495) (xy 87.339932 -161.975038)
			(xy 87.348248 -161.977624) (xy 87.365652 -161.977624) (xy 87.373968 -161.975038) (xy 87.410177 -161.962503)
			(xy 87.484279 -161.942985) (xy 87.559785 -161.929905) (xy 87.636135 -161.92336) (xy 87.67445 -161.922968)
			(xy 87.712766 -161.923352) (xy 87.789119 -161.92988) (xy 87.864626 -161.94296) (xy 87.938725 -161.962495)
			(xy 87.974932 -161.975038) (xy 87.983248 -161.977624) (xy 88.000652 -161.977624) (xy 88.008968 -161.975038)
			(xy 88.045177 -161.962503) (xy 88.119279 -161.942985) (xy 88.194785 -161.929905) (xy 88.271135 -161.92336)
			(xy 88.30945 -161.922968) (xy 88.347766 -161.923352) (xy 88.424119 -161.92988) (xy 88.499626 -161.94296)
			(xy 88.573725 -161.962495) (xy 88.609932 -161.975038) (xy 88.618248 -161.977624) (xy 88.635652 -161.977624)
			(xy 88.643968 -161.975038) (xy 88.680177 -161.962503) (xy 88.754279 -161.942985) (xy 88.829785 -161.929905)
			(xy 88.906135 -161.92336) (xy 88.94445 -161.922968) (xy 88.982766 -161.923352) (xy 89.059119 -161.92988)
			(xy 89.134626 -161.94296) (xy 89.208725 -161.962495) (xy 89.244932 -161.975038) (xy 89.253248 -161.977624)
			(xy 89.270652 -161.977624) (xy 89.278968 -161.975038) (xy 89.315177 -161.962503) (xy 89.389279 -161.942985)
			(xy 89.464785 -161.929905) (xy 89.541135 -161.92336) (xy 89.57945 -161.922968) (xy 89.62106 -161.923438)
			(xy 89.703917 -161.931201) (xy 89.785687 -161.946663) (xy 89.865658 -161.96969) (xy 89.90457 -161.984436)
			(xy 89.913248 -161.987466) (xy 89.931617 -161.98771) (xy 89.940384 -161.984944) (xy 89.976385 -161.972506)
			(xy 90.050053 -161.953122) (xy 90.125108 -161.940106) (xy 90.201001 -161.933552) (xy 90.239088 -161.933128)
			(xy 90.23985 -161.933128) (xy 90.280956 -161.93366) (xy 90.362817 -161.94124) (xy 90.443629 -161.956339)
			(xy 90.522705 -161.97883) (xy 90.599368 -162.008519) (xy 90.672965 -162.045155) (xy 90.742868 -162.088423)
			(xy 90.808482 -162.137957) (xy 90.869246 -162.193332) (xy 90.924643 -162.254076) (xy 90.974199 -162.319673)
			(xy 91.017492 -162.389561) (xy 91.054154 -162.463145) (xy 91.08387 -162.539798) (xy 91.106389 -162.618865)
			(xy 91.121517 -162.699672) (xy 91.129125 -162.781531) (xy 91.129612 -162.822636) (xy 91.12919 -162.860925)
			(xy 91.122588 -162.937219) (xy 91.109443 -163.012662) (xy 91.089854 -163.086693) (xy 91.077288 -163.122864)
			(xy 91.076082 -163.126674) (xy 119.365268 -163.126674) (xy 119.365838 -163.081905) (xy 119.374847 -162.99282)
			(xy 119.392749 -162.905089) (xy 119.419366 -162.819597) (xy 119.436388 -162.778186) (xy 119.43997 -162.7686)
			(xy 119.43996 -162.748153) (xy 119.436388 -162.738562) (xy 119.41934 -162.69716) (xy 119.392709 -162.61167)
			(xy 119.374808 -162.523935) (xy 119.365818 -162.434845) (xy 119.365268 -162.390074) (xy 119.365838 -162.345305)
			(xy 119.374847 -162.25622) (xy 119.392749 -162.168489) (xy 119.419366 -162.082997) (xy 119.436388 -162.041586)
			(xy 119.43997 -162.032) (xy 119.43996 -162.011553) (xy 119.436388 -162.001962) (xy 119.41934 -161.96056)
			(xy 119.392709 -161.87507) (xy 119.374808 -161.787335) (xy 119.365818 -161.698245) (xy 119.365268 -161.653474)
			(xy 119.365674 -161.612358) (xy 119.373264 -161.530476) (xy 119.388376 -161.449645) (xy 119.410882 -161.370552)
			(xy 119.440591 -161.293873) (xy 119.477247 -161.220263) (xy 119.520539 -161.150349) (xy 119.570097 -161.084728)
			(xy 119.625499 -161.023959) (xy 119.686271 -160.968561) (xy 119.751895 -160.919007) (xy 119.821812 -160.87572)
			(xy 119.895425 -160.839068) (xy 119.972105 -160.809365) (xy 120.051199 -160.786863) (xy 120.132032 -160.771756)
			(xy 120.213914 -160.764171) (xy 120.25503 -160.763712) (xy 120.296641 -160.764173) (xy 120.379498 -160.771953)
			(xy 120.461267 -160.787431) (xy 120.541235 -160.810474) (xy 120.618703 -160.840879) (xy 120.692995 -160.878382)
			(xy 120.728486 -160.90011) (xy 120.737629 -160.905263) (xy 120.758342 -160.90848) (xy 120.778614 -160.903152)
			(xy 120.78716 -160.897062) (xy 120.820789 -160.871071) (xy 120.892183 -160.824946) (xy 120.967654 -160.785845)
			(xy 121.046512 -160.754124) (xy 121.128037 -160.730075) (xy 121.211485 -160.713915) (xy 121.296095 -160.705793)
			(xy 121.338594 -160.705292) (xy 121.379707 -160.705819) (xy 121.461582 -160.713405) (xy 121.542407 -160.728513)
			(xy 121.621494 -160.751013) (xy 121.698168 -160.780715) (xy 121.771774 -160.817365) (xy 121.841684 -160.86065)
			(xy 121.907303 -160.9102) (xy 121.96807 -160.965593) (xy 122.023467 -161.026357) (xy 122.073021 -161.091973)
			(xy 122.11631 -161.161881) (xy 122.152964 -161.235485) (xy 122.18267 -161.312156) (xy 122.205176 -161.391242)
			(xy 122.220288 -161.472067) (xy 122.227879 -161.553941) (xy 122.228356 -161.595054) (xy 122.227793 -161.639824)
			(xy 122.218783 -161.728909) (xy 122.200877 -161.81664) (xy 122.174259 -161.902131) (xy 122.157236 -161.943542)
			(xy 122.153699 -161.953141) (xy 122.153682 -161.973576) (xy 122.157236 -161.983166) (xy 122.17424 -162.024517)
			(xy 122.200851 -162.109879) (xy 122.218758 -162.197482) (xy 122.22778 -162.286439) (xy 122.228356 -162.331146)
			(xy 122.228356 -162.332162) (xy 122.228102 -162.343592) (xy 122.254581 -162.349538) (xy 122.306816 -162.364281)
			(xy 122.332496 -162.373056) (xy 122.340693 -162.37557) (xy 122.357827 -162.37557) (xy 122.366024 -162.373056)
			(xy 122.40124 -162.361095) (xy 122.473244 -162.342441) (xy 122.546565 -162.329932) (xy 122.62068 -162.323659)
			(xy 122.65787 -162.323272) (xy 122.695059 -162.323671) (xy 122.769172 -162.329958) (xy 122.842492 -162.342465)
			(xy 122.914498 -162.361103) (xy 122.949716 -162.373056) (xy 122.957913 -162.37557) (xy 122.975047 -162.37557)
			(xy 122.983244 -162.373056) (xy 123.018459 -162.361089) (xy 123.090462 -162.342437) (xy 123.163784 -162.32993)
			(xy 123.2379 -162.323658) (xy 123.27509 -162.323272) (xy 123.31703 -162.323667) (xy 123.400532 -162.331639)
			(xy 123.482897 -162.347513) (xy 123.56338 -162.371144) (xy 123.641253 -162.402319) (xy 123.71581 -162.440755)
			(xy 123.786375 -162.486104) (xy 123.85231 -162.537955) (xy 123.913018 -162.595839) (xy 123.913877 -162.59683)
			(xy 376.471695 -162.59683) (xy 376.4757 -162.491081) (xy 376.48769 -162.385938) (xy 376.507599 -162.282003)
			(xy 376.53531 -162.179871) (xy 376.570667 -162.080127) (xy 376.613465 -161.983343) (xy 376.663461 -161.890073)
			(xy 376.720368 -161.800852) (xy 376.783859 -161.716189) (xy 376.853571 -161.636571) (xy 376.929105 -161.562453)
			(xy 377.010028 -161.49426) (xy 377.095877 -161.432382) (xy 377.18616 -161.377175) (xy 377.280359 -161.328953)
			(xy 377.377936 -161.287993) (xy 377.478331 -161.254531) (xy 377.580969 -161.228757) (xy 377.685262 -161.210819)
			(xy 377.790613 -161.20082) (xy 377.896419 -161.198817) (xy 378.002073 -161.204822) (xy 378.10697 -161.218801)
			(xy 378.21051 -161.240672) (xy 378.312099 -161.270312) (xy 378.411156 -161.30755) (xy 378.507113 -161.352172)
			(xy 378.59942 -161.403924) (xy 378.687549 -161.462509) (xy 378.770995 -161.527591) (xy 378.849279 -161.598797)
			(xy 378.921954 -161.67572) (xy 378.988604 -161.75792) (xy 379.048846 -161.844924) (xy 379.102335 -161.936235)
			(xy 379.148766 -162.03133) (xy 379.187871 -162.129664) (xy 379.219428 -162.230675) (xy 379.243255 -162.333782)
			(xy 379.259216 -162.438396) (xy 379.26722 -162.543918) (xy 379.26772 -162.59683) (xy 379.26722 -162.649742)
			(xy 379.266995 -162.65271) (xy 385.808735 -162.65271) (xy 385.81274 -162.546961) (xy 385.82473 -162.441818)
			(xy 385.844639 -162.337883) (xy 385.87235 -162.235751) (xy 385.907707 -162.136007) (xy 385.950505 -162.039223)
			(xy 386.000501 -161.945953) (xy 386.057408 -161.856732) (xy 386.120899 -161.772069) (xy 386.190611 -161.692451)
			(xy 386.266145 -161.618333) (xy 386.347068 -161.55014) (xy 386.432917 -161.488262) (xy 386.5232 -161.433055)
			(xy 386.617399 -161.384833) (xy 386.714976 -161.343873) (xy 386.815371 -161.310411) (xy 386.918009 -161.284637)
			(xy 387.022302 -161.266699) (xy 387.127653 -161.2567) (xy 387.233459 -161.254697) (xy 387.339113 -161.260702)
			(xy 387.44401 -161.274681) (xy 387.54755 -161.296552) (xy 387.649139 -161.326192) (xy 387.748196 -161.36343)
			(xy 387.844153 -161.408052) (xy 387.93646 -161.459804) (xy 388.024589 -161.518389) (xy 388.108035 -161.583471)
			(xy 388.186319 -161.654677) (xy 388.231017 -161.701988) (xy 409.929076 -161.701988) (xy 409.92965 -161.657219)
			(xy 409.938657 -161.568134) (xy 409.956559 -161.480403) (xy 409.983175 -161.394911) (xy 410.000196 -161.3535)
			(xy 410.00377 -161.343912) (xy 410.003765 -161.323466) (xy 410.000196 -161.313876) (xy 409.983153 -161.272472)
			(xy 409.956521 -161.186983) (xy 409.938618 -161.099248) (xy 409.929627 -161.010159) (xy 409.929076 -160.965388)
			(xy 409.92965 -160.920619) (xy 409.938657 -160.831534) (xy 409.956559 -160.743803) (xy 409.983175 -160.658311)
			(xy 410.000196 -160.6169) (xy 410.00377 -160.607312) (xy 410.003765 -160.586866) (xy 410.000196 -160.577276)
			(xy 409.983153 -160.535872) (xy 409.956521 -160.450383) (xy 409.938618 -160.362648) (xy 409.929627 -160.273559)
			(xy 409.929076 -160.228788) (xy 409.929541 -160.187678) (xy 409.93713 -160.105808) (xy 409.952241 -160.024988)
			(xy 409.974747 -159.945907) (xy 410.004454 -159.869241) (xy 410.041109 -159.795643) (xy 410.0844 -159.725742)
			(xy 410.133957 -159.660134) (xy 410.189357 -159.59938) (xy 410.250127 -159.543997) (xy 410.315748 -159.494459)
			(xy 410.385662 -159.451187) (xy 410.45927 -159.414553) (xy 410.535944 -159.384867) (xy 410.615031 -159.362384)
			(xy 410.695856 -159.347295) (xy 410.777728 -159.339729) (xy 410.818838 -159.33928) (xy 410.860442 -159.339755)
			(xy 410.94329 -159.347487) (xy 411.025054 -159.362917) (xy 411.105022 -159.38591) (xy 411.182495 -159.416266)
			(xy 411.256796 -159.45372) (xy 411.292294 -159.475424) (xy 411.301434 -159.480582) (xy 411.322149 -159.483796)
			(xy 411.342422 -159.478466) (xy 411.350968 -159.472376) (xy 411.384591 -159.44642) (xy 411.45597 -159.400364)
			(xy 411.531414 -159.361321) (xy 411.610235 -159.329647) (xy 411.691716 -159.305629) (xy 411.775116 -159.289486)
			(xy 411.859674 -159.281366) (xy 411.902148 -159.28086) (xy 411.902402 -159.28086) (xy 411.943509 -159.281311)
			(xy 412.025374 -159.288895) (xy 412.106189 -159.304) (xy 412.185267 -159.326496) (xy 412.261931 -159.356191)
			(xy 412.33553 -159.392831) (xy 412.405434 -159.436106) (xy 412.471048 -159.485644) (xy 412.531813 -159.541025)
			(xy 412.587209 -159.601775) (xy 412.636764 -159.667376) (xy 412.680057 -159.737269) (xy 412.716716 -159.810858)
			(xy 412.746431 -159.887515) (xy 412.768947 -159.966587) (xy 412.784073 -160.047398) (xy 412.791679 -160.129261)
			(xy 412.792164 -160.170368) (xy 412.791606 -160.215138) (xy 412.782594 -160.304223) (xy 412.764688 -160.391954)
			(xy 412.738068 -160.477445) (xy 412.721044 -160.518856) (xy 412.717498 -160.528452) (xy 412.717487 -160.548889)
			(xy 412.721044 -160.55848) (xy 412.738053 -160.599829) (xy 412.764663 -160.685192) (xy 412.782568 -160.772795)
			(xy 412.791589 -160.861753) (xy 412.792164 -160.90646) (xy 412.792164 -160.907476) (xy 412.79191 -160.918906)
			(xy 412.818389 -160.924851) (xy 412.870624 -160.939594) (xy 412.896304 -160.94837) (xy 412.904501 -160.950884)
			(xy 412.921635 -160.950884) (xy 412.929832 -160.94837) (xy 412.96505 -160.936429) (xy 413.037059 -160.91784)
			(xy 413.110382 -160.905398) (xy 413.184492 -160.899192) (xy 413.221678 -160.89884) (xy 413.258862 -160.899213)
			(xy 413.33297 -160.905434) (xy 413.40629 -160.917875) (xy 413.478301 -160.936448) (xy 413.513524 -160.94837)
			(xy 413.521721 -160.950884) (xy 413.538855 -160.950884) (xy 413.547052 -160.94837) (xy 413.582146 -160.93646)
			(xy 413.653906 -160.917916) (xy 413.726971 -160.905476) (xy 413.800824 -160.899229) (xy 413.837882 -160.89884)
			(xy 413.838898 -160.89884) (xy 413.880822 -160.899407) (xy 413.964291 -160.907377) (xy 414.046623 -160.923245)
			(xy 414.127075 -160.946868) (xy 414.204917 -160.978031) (xy 414.279444 -161.016452) (xy 414.349982 -161.061784)
			(xy 414.415891 -161.113615) (xy 414.476575 -161.171477) (xy 414.531484 -161.234845) (xy 414.580121 -161.303146)
			(xy 414.622045 -161.37576) (xy 414.656876 -161.452031) (xy 414.684301 -161.531268) (xy 414.704068 -161.612752)
			(xy 414.716001 -161.695747) (xy 414.719991 -161.7795) (xy 414.716001 -161.863253) (xy 414.704068 -161.946248)
			(xy 414.684301 -162.027732) (xy 414.656876 -162.106969) (xy 414.622045 -162.18324) (xy 414.580121 -162.255854)
			(xy 414.531484 -162.324155) (xy 414.476575 -162.387523) (xy 414.415891 -162.445385) (xy 414.349982 -162.497216)
			(xy 414.279444 -162.542548) (xy 414.204917 -162.580969) (xy 414.127075 -162.612132) (xy 414.046623 -162.635755)
			(xy 413.964291 -162.651623) (xy 413.880822 -162.659593) (xy 413.838898 -162.660076) (xy 413.837882 -162.660076)
			(xy 413.800825 -162.659672) (xy 413.726976 -162.653407) (xy 413.653913 -162.640964) (xy 413.582153 -162.622432)
			(xy 413.547052 -162.610546) (xy 413.538855 -162.608032) (xy 413.521721 -162.608032) (xy 413.513524 -162.610546)
			(xy 413.484638 -162.620383) (xy 413.425785 -162.636529) (xy 413.395922 -162.642804) (xy 413.386334 -162.645159)
			(xy 413.369889 -162.656054) (xy 413.358796 -162.672367) (xy 413.356298 -162.68192) (xy 413.34617 -162.726275)
			(xy 413.318046 -162.812805) (xy 413.300164 -162.85464) (xy 413.296347 -162.864579) (xy 413.296353 -162.885846)
			(xy 413.300164 -162.895788) (xy 413.318394 -162.938388) (xy 413.346909 -163.026556) (xy 413.366099 -163.117213)
			(xy 413.375757 -163.209373) (xy 413.376364 -163.255706) (xy 413.376364 -163.256214) (xy 413.37586 -163.298562)
			(xy 413.367809 -163.382876) (xy 413.35178 -163.466042) (xy 413.327919 -163.547309) (xy 413.29644 -163.625939)
			(xy 413.257629 -163.70122) (xy 413.230169 -163.74395) (xy 431.840894 -163.74395) (xy 431.840894 -163.68945)
			(xy 431.84865 -163.635505) (xy 431.864004 -163.583213) (xy 431.886644 -163.533639) (xy 431.916109 -163.48779)
			(xy 431.951798 -163.446602) (xy 431.992986 -163.410912) (xy 432.038833 -163.381447) (xy 432.088408 -163.358807)
			(xy 432.140699 -163.343452) (xy 432.194644 -163.335695) (xy 432.221894 -163.335208) (xy 433.212494 -163.335208)
			(xy 433.239748 -163.335638) (xy 433.293702 -163.343395) (xy 433.346003 -163.358751) (xy 433.395586 -163.381394)
			(xy 433.441442 -163.410863) (xy 433.482637 -163.446559) (xy 433.518333 -163.487753) (xy 433.547803 -163.533609)
			(xy 433.570447 -163.583191) (xy 433.585804 -163.635492) (xy 433.593561 -163.689446) (xy 433.593561 -163.743954)
			(xy 433.585804 -163.797908) (xy 433.570447 -163.850209) (xy 433.547803 -163.899791) (xy 433.518333 -163.945647)
			(xy 433.482637 -163.986841) (xy 433.441442 -164.022537) (xy 433.395586 -164.052006) (xy 433.346003 -164.074649)
			(xy 433.293702 -164.090005) (xy 433.239748 -164.097762) (xy 433.212494 -164.098224) (xy 432.221894 -164.098224)
			(xy 432.194644 -164.097705) (xy 432.140699 -164.089948) (xy 432.088408 -164.074593) (xy 432.038833 -164.051953)
			(xy 431.992986 -164.022488) (xy 431.951798 -163.986798) (xy 431.916109 -163.94561) (xy 431.886644 -163.899761)
			(xy 431.864004 -163.850187) (xy 431.84865 -163.797895) (xy 431.840894 -163.74395) (xy 413.230169 -163.74395)
			(xy 413.211839 -163.772472) (xy 413.159483 -163.839048) (xy 413.101035 -163.900346) (xy 413.037025 -163.955811)
			(xy 412.968033 -164.00494) (xy 412.894683 -164.047289) (xy 412.81764 -164.082473) (xy 412.737601 -164.110175)
			(xy 412.655292 -164.130143) (xy 412.571457 -164.142196) (xy 412.486856 -164.146227) (xy 412.402255 -164.142196)
			(xy 412.31842 -164.130143) (xy 412.236111 -164.110175) (xy 412.156072 -164.082473) (xy 412.079029 -164.047289)
			(xy 412.005679 -164.00494) (xy 411.936687 -163.955811) (xy 411.872677 -163.900346) (xy 411.814229 -163.839048)
			(xy 411.761873 -163.772472) (xy 411.716083 -163.70122) (xy 411.677272 -163.625939) (xy 411.645793 -163.547309)
			(xy 411.621932 -163.466042) (xy 411.605903 -163.382876) (xy 411.597852 -163.298562) (xy 411.597348 -163.256214)
			(xy 411.597348 -163.255706) (xy 411.597963 -163.209374) (xy 411.607632 -163.117217) (xy 411.626825 -163.026563)
			(xy 411.655334 -162.938394) (xy 411.673548 -162.895788) (xy 411.677348 -162.885844) (xy 411.677353 -162.864582)
			(xy 411.673548 -162.85464) (xy 411.655311 -162.811974) (xy 411.626764 -162.723684) (xy 411.607569 -162.632899)
			(xy 411.597934 -162.54061) (xy 411.597348 -162.494214) (xy 411.597953 -162.446404) (xy 411.608131 -162.351329)
			(xy 411.617668 -162.304476) (xy 411.61964 -162.292071) (xy 411.612727 -162.267957) (xy 411.60446 -162.258502)
			(xy 411.56382 -162.216338) (xy 411.560264 -162.2171) (xy 411.551416 -162.219411) (xy 411.536053 -162.229303)
			(xy 411.530292 -162.236404) (xy 411.505145 -162.269057) (xy 411.449744 -162.330083) (xy 411.388935 -162.385722)
			(xy 411.323239 -162.435497) (xy 411.253221 -162.478981) (xy 411.17948 -162.515801) (xy 411.102649 -162.545642)
			(xy 411.023387 -162.568246) (xy 410.942373 -162.583421) (xy 410.860303 -162.591036) (xy 410.819092 -162.591496)
			(xy 410.818838 -162.591496) (xy 410.777733 -162.590951) (xy 410.695873 -162.583371) (xy 410.615061 -162.568271)
			(xy 410.535987 -162.54578) (xy 410.459325 -162.516091) (xy 410.385729 -162.479456) (xy 410.315826 -162.436187)
			(xy 410.250213 -162.386655) (xy 410.18945 -162.331281) (xy 410.134053 -162.270538) (xy 410.084497 -162.204943)
			(xy 410.041203 -162.135056) (xy 410.004541 -162.061473) (xy 409.974824 -161.984822) (xy 409.952304 -161.905756)
			(xy 409.937174 -161.82495) (xy 409.929564 -161.743093) (xy 409.929076 -161.701988) (xy 388.231017 -161.701988)
			(xy 388.258994 -161.7316) (xy 388.325644 -161.8138) (xy 388.385886 -161.900804) (xy 388.439375 -161.992115)
			(xy 388.485806 -162.08721) (xy 388.524911 -162.185544) (xy 388.556468 -162.286555) (xy 388.580295 -162.389662)
			(xy 388.596256 -162.494276) (xy 388.60426 -162.599798) (xy 388.60476 -162.65271) (xy 388.60426 -162.705622)
			(xy 388.596256 -162.811144) (xy 388.580295 -162.915758) (xy 388.556468 -163.018865) (xy 388.524911 -163.119876)
			(xy 388.485806 -163.21821) (xy 388.439375 -163.313305) (xy 388.385886 -163.404616) (xy 388.325644 -163.49162)
			(xy 388.258994 -163.57382) (xy 388.186319 -163.650743) (xy 388.108035 -163.721949) (xy 388.024589 -163.787031)
			(xy 387.93646 -163.845616) (xy 387.844153 -163.897368) (xy 387.748196 -163.94199) (xy 387.649139 -163.979228)
			(xy 387.54755 -164.008868) (xy 387.44401 -164.030739) (xy 387.339113 -164.044718) (xy 387.233459 -164.050723)
			(xy 387.127653 -164.04872) (xy 387.022302 -164.038721) (xy 386.918009 -164.020783) (xy 386.815371 -163.995009)
			(xy 386.714976 -163.961547) (xy 386.617399 -163.920587) (xy 386.5232 -163.872365) (xy 386.432917 -163.817158)
			(xy 386.347068 -163.75528) (xy 386.266145 -163.687087) (xy 386.190611 -163.612969) (xy 386.120899 -163.533351)
			(xy 386.057408 -163.448688) (xy 386.000501 -163.359467) (xy 385.950505 -163.266197) (xy 385.907707 -163.169413)
			(xy 385.87235 -163.069669) (xy 385.844639 -162.967537) (xy 385.82473 -162.863602) (xy 385.81274 -162.758459)
			(xy 385.808735 -162.65271) (xy 379.266995 -162.65271) (xy 379.259216 -162.755264) (xy 379.243255 -162.859878)
			(xy 379.219428 -162.962985) (xy 379.187871 -163.063996) (xy 379.148766 -163.16233) (xy 379.102335 -163.257425)
			(xy 379.048846 -163.348736) (xy 378.988604 -163.43574) (xy 378.921954 -163.51794) (xy 378.849279 -163.594863)
			(xy 378.770995 -163.666069) (xy 378.687549 -163.731151) (xy 378.59942 -163.789736) (xy 378.507113 -163.841488)
			(xy 378.411156 -163.88611) (xy 378.312099 -163.923348) (xy 378.21051 -163.952988) (xy 378.10697 -163.974859)
			(xy 378.002073 -163.988838) (xy 377.896419 -163.994843) (xy 377.790613 -163.99284) (xy 377.685262 -163.982841)
			(xy 377.580969 -163.964903) (xy 377.478331 -163.939129) (xy 377.377936 -163.905667) (xy 377.280359 -163.864707)
			(xy 377.18616 -163.816485) (xy 377.095877 -163.761278) (xy 377.010028 -163.6994) (xy 376.929105 -163.631207)
			(xy 376.853571 -163.557089) (xy 376.783859 -163.477471) (xy 376.720368 -163.392808) (xy 376.663461 -163.303587)
			(xy 376.613465 -163.210317) (xy 376.570667 -163.113533) (xy 376.53531 -163.013789) (xy 376.507599 -162.911657)
			(xy 376.48769 -162.807722) (xy 376.4757 -162.702579) (xy 376.471695 -162.59683) (xy 123.913877 -162.59683)
			(xy 123.967949 -162.659232) (xy 124.016605 -162.727559) (xy 124.058546 -162.800202) (xy 124.093391 -162.876503)
			(xy 124.120826 -162.95577) (xy 124.140602 -163.037287) (xy 124.15254 -163.120314) (xy 124.156531 -163.2041)
			(xy 124.15254 -163.287886) (xy 124.140602 -163.370913) (xy 124.120826 -163.45243) (xy 124.093391 -163.531697)
			(xy 124.058546 -163.607998) (xy 124.016605 -163.680641) (xy 123.967949 -163.748968) (xy 123.913018 -163.812361)
			(xy 123.85231 -163.870245) (xy 123.786375 -163.922096) (xy 123.71581 -163.967445) (xy 123.641253 -164.005881)
			(xy 123.56338 -164.037056) (xy 123.482897 -164.060687) (xy 123.400532 -164.076561) (xy 123.31703 -164.084533)
			(xy 123.27509 -164.085016) (xy 123.2379 -164.084629) (xy 123.163787 -164.078339) (xy 123.090468 -164.065828)
			(xy 123.018462 -164.047187) (xy 122.983244 -164.035232) (xy 122.975047 -164.032718) (xy 122.957913 -164.032718)
			(xy 122.949716 -164.035232) (xy 122.907233 -164.049509) (xy 122.820068 -164.070379) (xy 122.775726 -164.076888)
			(xy 122.765804 -164.078672) (xy 122.748385 -164.088778) (xy 122.736231 -164.104835) (xy 122.733308 -164.11448)
			(xy 122.724748 -164.14638) (xy 122.70352 -164.20893) (xy 122.69089 -164.239448) (xy 122.687282 -164.249022)
			(xy 122.687136 -164.26946) (xy 122.690636 -164.279072) (xy 122.707671 -164.320445) (xy 122.734286 -164.405873)
			(xy 122.752187 -164.493543) (xy 122.756237 -164.53358) (xy 365.854996 -164.53358) (xy 365.855358 -164.495263)
			(xy 365.861892 -164.41891) (xy 365.874978 -164.343403) (xy 365.89452 -164.269304) (xy 365.907066 -164.233098)
			(xy 365.909662 -164.224784) (xy 365.909655 -164.207378) (xy 365.907066 -164.199062) (xy 365.894569 -164.162941)
			(xy 365.875081 -164.089028) (xy 365.861998 -164.013717) (xy 365.855418 -163.937561) (xy 365.854996 -163.899342)
			(xy 365.854996 -163.89858) (xy 365.855448 -163.857477) (xy 365.863034 -163.775622) (xy 365.878141 -163.694816)
			(xy 365.900639 -163.615749) (xy 365.930337 -163.539095) (xy 365.966981 -163.465508) (xy 366.010258 -163.395615)
			(xy 366.059799 -163.330014) (xy 366.115181 -163.269264) (xy 366.175933 -163.213883) (xy 366.241535 -163.164344)
			(xy 366.311429 -163.121069) (xy 366.385017 -163.084427) (xy 366.461672 -163.054732) (xy 366.54074 -163.032236)
			(xy 366.621546 -163.017131) (xy 366.703401 -163.009546) (xy 366.744504 -163.009072) (xy 366.745266 -163.009072)
			(xy 366.783487 -163.009474) (xy 366.859645 -163.01604) (xy 366.934958 -163.029126) (xy 367.008868 -163.048635)
			(xy 367.044986 -163.061142) (xy 367.053302 -163.063728) (xy 367.070706 -163.063728) (xy 367.079022 -163.061142)
			(xy 367.115235 -163.04862) (xy 367.189336 -163.029098) (xy 367.26484 -163.016015) (xy 367.341189 -163.009466)
			(xy 367.379504 -163.009072) (xy 367.419718 -163.009498) (xy 367.49982 -163.016721) (xy 367.578942 -163.031153)
			(xy 367.656435 -163.052677) (xy 367.69421 -163.066476) (xy 367.702997 -163.069383) (xy 367.721491 -163.069383)
			(xy 367.730278 -163.066476) (xy 367.768054 -163.052684) (xy 367.845551 -163.031177) (xy 367.924672 -163.016746)
			(xy 368.004771 -163.00951) (xy 368.044984 -163.009072) (xy 368.0833 -163.009446) (xy 368.159653 -163.015977)
			(xy 368.23516 -163.029059) (xy 368.309259 -163.048598) (xy 368.345466 -163.061142) (xy 368.353782 -163.063728)
			(xy 368.371186 -163.063728) (xy 368.379502 -163.061142) (xy 368.415717 -163.048626) (xy 368.489817 -163.029103)
			(xy 368.565321 -163.016017) (xy 368.641669 -163.009467) (xy 368.679984 -163.009072) (xy 368.7183 -163.009446)
			(xy 368.794653 -163.015977) (xy 368.87016 -163.029059) (xy 368.944259 -163.048598) (xy 368.980466 -163.061142)
			(xy 368.988782 -163.063728) (xy 369.006186 -163.063728) (xy 369.014502 -163.061142) (xy 369.050717 -163.048626)
			(xy 369.124817 -163.029103) (xy 369.200321 -163.016017) (xy 369.276669 -163.009467) (xy 369.314984 -163.009072)
			(xy 369.3533 -163.009446) (xy 369.429653 -163.015977) (xy 369.50516 -163.029059) (xy 369.579259 -163.048598)
			(xy 369.615466 -163.061142) (xy 369.623782 -163.063728) (xy 369.641186 -163.063728) (xy 369.649502 -163.061142)
			(xy 369.685565 -163.048673) (xy 369.759352 -163.029204) (xy 369.834533 -163.016119) (xy 369.910559 -163.009515)
			(xy 369.948714 -163.009072) (xy 369.949984 -163.009072) (xy 369.994754 -163.009635) (xy 370.083841 -163.018637)
			(xy 370.171573 -163.03654) (xy 370.257063 -163.063164) (xy 370.298472 -163.080192) (xy 370.308063 -163.083757)
			(xy 370.328505 -163.083757) (xy 370.338096 -163.080192) (xy 370.379479 -163.063183) (xy 370.464904 -163.036561)
			(xy 370.55257 -163.018653) (xy 370.641592 -163.00964) (xy 370.68633 -163.009072) (xy 370.686584 -163.009072)
			(xy 370.727686 -163.009582) (xy 370.809538 -163.017165) (xy 370.890342 -163.032268) (xy 370.969408 -163.054763)
			(xy 371.046061 -163.084457) (xy 371.119647 -163.121096) (xy 371.189538 -163.16437) (xy 371.255139 -163.213907)
			(xy 371.315889 -163.269286) (xy 371.37127 -163.330033) (xy 371.42081 -163.395632) (xy 371.464086 -163.465522)
			(xy 371.500729 -163.539106) (xy 371.530426 -163.615758) (xy 371.552923 -163.694823) (xy 371.56803 -163.775626)
			(xy 371.575616 -163.857478) (xy 371.576092 -163.89858) (xy 371.576092 -163.899342) (xy 371.575679 -163.937562)
			(xy 371.569116 -164.013721) (xy 371.556033 -164.089033) (xy 371.536527 -164.162943) (xy 371.524022 -164.199062)
			(xy 371.521447 -164.207381) (xy 371.52144 -164.224782) (xy 371.524022 -164.233098) (xy 371.536535 -164.269314)
			(xy 371.55606 -164.343414) (xy 371.569146 -164.418917) (xy 371.575697 -164.495265) (xy 371.576092 -164.53358)
			(xy 371.575734 -164.571323) (xy 371.569392 -164.646543) (xy 371.556692 -164.720953) (xy 371.537726 -164.794018)
			(xy 371.525546 -164.829744) (xy 371.522818 -164.838516) (xy 371.52307 -164.85687) (xy 371.526054 -164.865558)
			(xy 371.541045 -164.904681) (xy 371.564495 -164.985121) (xy 371.58028 -165.067409) (xy 371.588259 -165.150817)
			(xy 371.588792 -165.19271) (xy 371.588792 -165.19398) (xy 371.588329 -165.235083) (xy 371.580745 -165.316939)
			(xy 371.565641 -165.397747) (xy 371.543146 -165.476815) (xy 371.51345 -165.553471) (xy 371.476808 -165.62706)
			(xy 371.433533 -165.696954) (xy 371.383993 -165.762556) (xy 371.328611 -165.823308) (xy 371.267859 -165.87869)
			(xy 371.202257 -165.92823) (xy 371.132363 -165.971506) (xy 371.058775 -166.008149) (xy 370.982119 -166.037844)
			(xy 370.90305 -166.06034) (xy 370.822243 -166.075445) (xy 370.740387 -166.083029) (xy 370.699284 -166.083488)
			(xy 370.69903 -166.083488) (xy 370.654291 -166.082927) (xy 370.56527 -166.07391) (xy 370.477602 -166.056003)
			(xy 370.392175 -166.029387) (xy 370.350796 -166.012368) (xy 370.341205 -166.008803) (xy 370.320763 -166.008803)
			(xy 370.311172 -166.012368) (xy 370.269762 -166.029396) (xy 370.184274 -166.056029) (xy 370.096542 -166.073935)
			(xy 370.007454 -166.082933) (xy 369.962684 -166.083488) (xy 369.961414 -166.083488) (xy 369.923257 -166.083067)
			(xy 369.847228 -166.076479) (xy 369.772044 -166.063393) (xy 369.69826 -166.043906) (xy 369.662202 -166.031418)
			(xy 369.653886 -166.028832) (xy 369.636482 -166.028832) (xy 369.628166 -166.031418) (xy 369.591953 -166.043941)
			(xy 369.517852 -166.063463) (xy 369.442348 -166.076546) (xy 369.365999 -166.083094) (xy 369.327684 -166.083488)
			(xy 369.289367 -166.083126) (xy 369.213014 -166.076592) (xy 369.137507 -166.063506) (xy 369.063408 -166.043964)
			(xy 369.027202 -166.031418) (xy 369.018886 -166.028832) (xy 369.001482 -166.028832) (xy 368.993166 -166.031418)
			(xy 368.956953 -166.043941) (xy 368.882852 -166.063463) (xy 368.807348 -166.076546) (xy 368.730999 -166.083094)
			(xy 368.692684 -166.083488) (xy 368.654367 -166.083126) (xy 368.578014 -166.076592) (xy 368.502507 -166.063506)
			(xy 368.428408 -166.043964) (xy 368.392202 -166.031418) (xy 368.383886 -166.028832) (xy 368.366482 -166.028832)
			(xy 368.358166 -166.031418) (xy 368.321953 -166.043941) (xy 368.247852 -166.063463) (xy 368.172348 -166.076546)
			(xy 368.095999 -166.083094) (xy 368.057684 -166.083488) (xy 368.01747 -166.083062) (xy 367.937368 -166.075838)
			(xy 367.858246 -166.061406) (xy 367.780753 -166.039883) (xy 367.742978 -166.026084) (xy 367.734191 -166.023177)
			(xy 367.715697 -166.023177) (xy 367.70691 -166.026084) (xy 367.669134 -166.039877) (xy 367.591637 -166.061385)
			(xy 367.512517 -166.075815) (xy 367.432417 -166.083051) (xy 367.392204 -166.083488) (xy 367.353888 -166.08312)
			(xy 367.277534 -166.076588) (xy 367.202027 -166.063503) (xy 367.127928 -166.043963) (xy 367.091722 -166.031418)
			(xy 367.083406 -166.028832) (xy 367.066002 -166.028832) (xy 367.057686 -166.031418) (xy 367.021563 -166.043908)
			(xy 366.947651 -166.063398) (xy 366.87234 -166.076483) (xy 366.796185 -166.083065) (xy 366.757966 -166.083488)
			(xy 366.757204 -166.083488) (xy 366.7161 -166.083044) (xy 366.634244 -166.075459) (xy 366.553436 -166.060354)
			(xy 366.474367 -166.037857) (xy 366.397711 -166.00816) (xy 366.324122 -165.971516) (xy 366.254228 -165.928239)
			(xy 366.188625 -165.878698) (xy 366.127874 -165.823315) (xy 366.072492 -165.762562) (xy 366.022951 -165.696959)
			(xy 365.979676 -165.627064) (xy 365.943034 -165.553475) (xy 365.913338 -165.476818) (xy 365.890843 -165.397748)
			(xy 365.875739 -165.316941) (xy 365.868155 -165.235084) (xy 365.867696 -165.19398) (xy 365.867696 -165.192964)
			(xy 365.868115 -165.155349) (xy 365.874496 -165.080389) (xy 365.887191 -165.006237) (xy 365.906111 -164.933424)
			(xy 365.918242 -164.897816) (xy 365.920992 -164.889049) (xy 365.920727 -164.87069) (xy 365.917734 -164.862002)
			(xy 365.902679 -164.822733) (xy 365.879172 -164.741978) (xy 365.863391 -164.659366) (xy 365.855475 -164.575633)
			(xy 365.854996 -164.53358) (xy 122.756237 -164.53358) (xy 122.761192 -164.582567) (xy 122.761756 -164.627306)
			(xy 122.761756 -164.62756) (xy 122.761252 -164.669908) (xy 122.753201 -164.754222) (xy 122.737172 -164.837388)
			(xy 122.713311 -164.918655) (xy 122.681832 -164.997285) (xy 122.643021 -165.072566) (xy 122.597231 -165.143818)
			(xy 122.544875 -165.210394) (xy 122.486427 -165.271692) (xy 122.422417 -165.327157) (xy 122.353425 -165.376286)
			(xy 122.280075 -165.418635) (xy 122.203032 -165.453819) (xy 122.122993 -165.481521) (xy 122.040684 -165.501489)
			(xy 121.956849 -165.513542) (xy 121.872248 -165.517573) (xy 121.787647 -165.513542) (xy 121.703812 -165.501489)
			(xy 121.621503 -165.481521) (xy 121.541464 -165.453819) (xy 121.464421 -165.418635) (xy 121.391071 -165.376286)
			(xy 121.322079 -165.327157) (xy 121.258069 -165.271692) (xy 121.199621 -165.210394) (xy 121.147265 -165.143818)
			(xy 121.101475 -165.072566) (xy 121.062664 -164.997285) (xy 121.031185 -164.918655) (xy 121.007324 -164.837388)
			(xy 120.991295 -164.754222) (xy 120.983244 -164.669908) (xy 120.98274 -164.62756) (xy 120.98274 -164.627306)
			(xy 120.983291 -164.582567) (xy 120.992311 -164.493545) (xy 121.010221 -164.405878) (xy 121.03684 -164.320451)
			(xy 121.05386 -164.279072) (xy 121.057447 -164.269488) (xy 121.057432 -164.249039) (xy 121.05386 -164.239448)
			(xy 121.037012 -164.19848) (xy 121.010567 -164.113931) (xy 120.992664 -164.027171) (xy 120.983478 -163.939061)
			(xy 120.98274 -163.89477) (xy 120.982373 -163.885212) (xy 120.975335 -163.867438) (xy 120.962255 -163.853496)
			(xy 120.953784 -163.84905) (xy 120.870726 -163.809934) (xy 120.861899 -163.806187) (xy 120.842781 -163.804911)
			(xy 120.824539 -163.810771) (xy 120.816878 -163.816538) (xy 120.782853 -163.843559) (xy 120.710459 -163.891613)
			(xy 120.633724 -163.93238) (xy 120.55338 -163.965469) (xy 120.470192 -163.990568) (xy 120.384953 -164.007435)
			(xy 120.298476 -164.01591) (xy 120.25503 -164.016436) (xy 120.213915 -164.015973) (xy 120.132035 -164.008388)
			(xy 120.051204 -163.99328) (xy 119.972113 -163.970779) (xy 119.895435 -163.941075) (xy 119.821825 -163.904423)
			(xy 119.751911 -163.861135) (xy 119.686289 -163.811581) (xy 119.62552 -163.756183) (xy 119.570122 -163.695414)
			(xy 119.520567 -163.629793) (xy 119.477279 -163.559879) (xy 119.440626 -163.486269) (xy 119.410922 -163.409591)
			(xy 119.38842 -163.330499) (xy 119.373312 -163.249669) (xy 119.365727 -163.167789) (xy 119.365268 -163.126674)
			(xy 91.076082 -163.126674) (xy 91.074618 -163.131296) (xy 91.074629 -163.148971) (xy 91.077288 -163.157408)
			(xy 91.089816 -163.193591) (xy 91.109393 -163.267622) (xy 91.122545 -163.34306) (xy 91.129174 -163.419348)
			(xy 91.129612 -163.457636) (xy 91.129114 -163.500412) (xy 91.120898 -163.585569) (xy 91.104536 -163.669543)
			(xy 91.080178 -163.751555) (xy 91.064588 -163.791392) (xy 91.061544 -163.799848) (xy 91.060879 -163.817795)
			(xy 91.063318 -163.826444) (xy 91.07787 -163.871922) (xy 91.098306 -163.9652) (xy 91.108623 -164.060131)
			(xy 91.109292 -164.107876) (xy 91.108825 -164.148987) (xy 91.101239 -164.230857) (xy 91.08613 -164.311679)
			(xy 91.063626 -164.390761) (xy 91.033921 -164.467428) (xy 90.997266 -164.541027) (xy 90.953976 -164.610929)
			(xy 90.904419 -164.676538) (xy 90.849019 -164.737293) (xy 90.788249 -164.792677) (xy 90.722626 -164.842215)
			(xy 90.652712 -164.885486) (xy 90.579103 -164.92212) (xy 90.502427 -164.951804) (xy 90.423339 -164.974286)
			(xy 90.342514 -164.989373) (xy 90.260641 -164.996936) (xy 90.21953 -164.997384) (xy 90.177921 -164.996892)
			(xy 90.095064 -164.989136) (xy 90.013294 -164.97368) (xy 89.933323 -164.950659) (xy 89.89441 -164.935916)
			(xy 89.88572 -164.932926) (xy 89.867362 -164.932654) (xy 89.858596 -164.935408) (xy 89.822497 -164.947854)
			(xy 89.748643 -164.967275) (xy 89.673397 -164.980297) (xy 89.597312 -164.986825) (xy 89.55913 -164.987224)
			(xy 89.520814 -164.986846) (xy 89.444461 -164.980317) (xy 89.368954 -164.967235) (xy 89.294855 -164.947698)
			(xy 89.258648 -164.935154) (xy 89.250332 -164.932568) (xy 89.232928 -164.932568) (xy 89.224612 -164.935154)
			(xy 89.188396 -164.947666) (xy 89.114296 -164.96719) (xy 89.038793 -164.980277) (xy 88.962445 -164.986828)
			(xy 88.92413 -164.987224) (xy 88.885814 -164.986846) (xy 88.809461 -164.980317) (xy 88.733954 -164.967235)
			(xy 88.659855 -164.947698) (xy 88.623648 -164.935154) (xy 88.615332 -164.932568) (xy 88.597928 -164.932568)
			(xy 88.589612 -164.935154) (xy 88.553396 -164.947666) (xy 88.479296 -164.96719) (xy 88.403793 -164.980277)
			(xy 88.327445 -164.986828) (xy 88.28913 -164.987224) (xy 88.250814 -164.986846) (xy 88.174461 -164.980317)
			(xy 88.098954 -164.967235) (xy 88.024855 -164.947698) (xy 87.988648 -164.935154) (xy 87.980332 -164.932568)
			(xy 87.962928 -164.932568) (xy 87.954612 -164.935154) (xy 87.918396 -164.947666) (xy 87.844296 -164.96719)
			(xy 87.768793 -164.980277) (xy 87.692445 -164.986828) (xy 87.65413 -164.987224) (xy 87.615814 -164.986846)
			(xy 87.539461 -164.980317) (xy 87.463954 -164.967235) (xy 87.389855 -164.947698) (xy 87.353648 -164.935154)
			(xy 87.345332 -164.932568) (xy 87.327928 -164.932568) (xy 87.319612 -164.935154) (xy 87.283487 -164.947638)
			(xy 87.209575 -164.96713) (xy 87.134265 -164.980216) (xy 87.058111 -164.9868) (xy 87.019892 -164.987224)
			(xy 87.01913 -164.987224) (xy 86.978023 -164.986759) (xy 86.896158 -164.979177) (xy 86.815342 -164.964075)
			(xy 86.736265 -164.941581) (xy 86.659599 -164.911888) (xy 86.586 -164.875249) (xy 86.516095 -164.831976)
			(xy 86.45048 -164.782438) (xy 86.389716 -164.727058) (xy 86.334319 -164.666309) (xy 86.284763 -164.600708)
			(xy 86.241471 -164.530815) (xy 86.204811 -164.457226) (xy 86.175097 -164.380569) (xy 86.152582 -164.301497)
			(xy 86.137457 -164.220686) (xy 86.129853 -164.138823) (xy 86.129368 -164.097716) (xy 2.509012 -164.097716)
			(xy 2.509012 -166.86276) (xy 61.046868 -166.86276) (xy 61.047433 -166.81799) (xy 61.056443 -166.728905)
			(xy 61.074347 -166.641174) (xy 61.100966 -166.555683) (xy 61.117988 -166.514272) (xy 61.121578 -166.504688)
			(xy 61.121563 -166.484239) (xy 61.117988 -166.474648) (xy 61.100968 -166.433235) (xy 61.074329 -166.347749)
			(xy 61.05642 -166.260018) (xy 61.047422 -166.17093) (xy 61.046868 -166.12616) (xy 61.047433 -166.08139)
			(xy 61.056443 -165.992305) (xy 61.074347 -165.904574) (xy 61.100966 -165.819083) (xy 61.117988 -165.777672)
			(xy 61.121578 -165.768088) (xy 61.121563 -165.747639) (xy 61.117988 -165.738048) (xy 61.100968 -165.696635)
			(xy 61.074329 -165.611149) (xy 61.05642 -165.523418) (xy 61.047422 -165.43433) (xy 61.046868 -165.38956)
			(xy 61.047314 -165.348449) (xy 61.054905 -165.266579) (xy 61.070019 -165.185759) (xy 61.092527 -165.106679)
			(xy 61.122236 -165.030013) (xy 61.158893 -164.956415) (xy 61.202185 -164.886514) (xy 61.251743 -164.820907)
			(xy 61.307144 -164.760153) (xy 61.367915 -164.70477) (xy 61.433537 -164.655232) (xy 61.503451 -164.611961)
			(xy 61.57706 -164.575327) (xy 61.653735 -164.545641) (xy 61.732822 -164.523157) (xy 61.813647 -164.508068)
			(xy 61.895519 -164.500502) (xy 61.93663 -164.500052) (xy 61.978234 -164.500535) (xy 62.061081 -164.508266)
			(xy 62.142846 -164.523695) (xy 62.222813 -164.546687) (xy 62.300286 -164.577041) (xy 62.374588 -164.614493)
			(xy 62.410086 -164.636196) (xy 62.419228 -164.641351) (xy 62.439942 -164.644569) (xy 62.460215 -164.639239)
			(xy 62.46876 -164.633148) (xy 62.502383 -164.607191) (xy 62.573762 -164.561136) (xy 62.649206 -164.522094)
			(xy 62.728027 -164.49042) (xy 62.809509 -164.466402) (xy 62.892908 -164.450259) (xy 62.977466 -164.442138)
			(xy 63.01994 -164.441632) (xy 63.020194 -164.441632) (xy 63.0613 -164.442118) (xy 63.143163 -164.449702)
			(xy 63.223977 -164.464805) (xy 63.303052 -164.487299) (xy 63.379716 -164.516993) (xy 63.453313 -164.553631)
			(xy 63.523217 -164.596903) (xy 63.58883 -164.64644) (xy 63.649594 -164.701818) (xy 63.70499 -164.762565)
			(xy 63.754546 -164.828164) (xy 63.797839 -164.898054) (xy 63.8345 -164.971641) (xy 63.864216 -165.048295)
			(xy 63.886734 -165.127364) (xy 63.901861 -165.208173) (xy 63.909469 -165.290034) (xy 63.909956 -165.33114)
			(xy 63.909389 -165.375909) (xy 63.900379 -165.464994) (xy 63.882475 -165.552725) (xy 63.855858 -165.638217)
			(xy 63.838836 -165.679628) (xy 63.83525 -165.689212) (xy 63.835264 -165.709661) (xy 63.838836 -165.719252)
			(xy 63.855836 -165.760605) (xy 63.882448 -165.845966) (xy 63.900356 -165.933568) (xy 63.903248 -165.962076)
			(xy 81.591411 -165.962076) (xy 81.595416 -165.856327) (xy 81.607406 -165.751184) (xy 81.627315 -165.647249)
			(xy 81.655026 -165.545117) (xy 81.690383 -165.445373) (xy 81.733181 -165.348589) (xy 81.783177 -165.255319)
			(xy 81.840084 -165.166098) (xy 81.903575 -165.081435) (xy 81.973287 -165.001817) (xy 82.048821 -164.927699)
			(xy 82.129744 -164.859506) (xy 82.215593 -164.797628) (xy 82.305876 -164.742421) (xy 82.400075 -164.694199)
			(xy 82.497652 -164.653239) (xy 82.598047 -164.619777) (xy 82.700685 -164.594003) (xy 82.804978 -164.576065)
			(xy 82.910329 -164.566066) (xy 83.016135 -164.564063) (xy 83.121789 -164.570068) (xy 83.226686 -164.584047)
			(xy 83.330226 -164.605918) (xy 83.431815 -164.635558) (xy 83.530872 -164.672796) (xy 83.626829 -164.717418)
			(xy 83.719136 -164.76917) (xy 83.807265 -164.827755) (xy 83.890711 -164.892837) (xy 83.968995 -164.964043)
			(xy 84.04167 -165.040966) (xy 84.10832 -165.123166) (xy 84.168562 -165.21017) (xy 84.222051 -165.301481)
			(xy 84.268482 -165.396576) (xy 84.307587 -165.49491) (xy 84.339144 -165.595921) (xy 84.362971 -165.699028)
			(xy 84.378932 -165.803642) (xy 84.386936 -165.909164) (xy 84.387436 -165.962076) (xy 90.989411 -165.962076)
			(xy 90.993416 -165.856327) (xy 91.005406 -165.751184) (xy 91.025315 -165.647249) (xy 91.053026 -165.545117)
			(xy 91.088383 -165.445373) (xy 91.131181 -165.348589) (xy 91.181177 -165.255319) (xy 91.238084 -165.166098)
			(xy 91.301575 -165.081435) (xy 91.371287 -165.001817) (xy 91.446821 -164.927699) (xy 91.527744 -164.859506)
			(xy 91.613593 -164.797628) (xy 91.703876 -164.742421) (xy 91.798075 -164.694199) (xy 91.895652 -164.653239)
			(xy 91.996047 -164.619777) (xy 92.098685 -164.594003) (xy 92.202978 -164.576065) (xy 92.308329 -164.566066)
			(xy 92.414135 -164.564063) (xy 92.519789 -164.570068) (xy 92.624686 -164.584047) (xy 92.728226 -164.605918)
			(xy 92.829815 -164.635558) (xy 92.928872 -164.672796) (xy 93.024829 -164.717418) (xy 93.117136 -164.76917)
			(xy 93.205265 -164.827755) (xy 93.288711 -164.892837) (xy 93.366995 -164.964043) (xy 93.43967 -165.040966)
			(xy 93.50632 -165.123166) (xy 93.566562 -165.21017) (xy 93.620051 -165.301481) (xy 93.666482 -165.396576)
			(xy 93.705587 -165.49491) (xy 93.737144 -165.595921) (xy 93.760971 -165.699028) (xy 93.776932 -165.803642)
			(xy 93.784936 -165.909164) (xy 93.785436 -165.962076) (xy 93.784936 -166.014988) (xy 93.776932 -166.12051)
			(xy 93.760971 -166.225124) (xy 93.737144 -166.328231) (xy 93.705587 -166.429242) (xy 93.666482 -166.527576)
			(xy 93.620051 -166.622671) (xy 93.566562 -166.713982) (xy 93.50632 -166.800986) (xy 93.43967 -166.883186)
			(xy 93.366995 -166.960109) (xy 93.288711 -167.031315) (xy 93.205265 -167.096397) (xy 93.117136 -167.154982)
			(xy 93.024829 -167.206734) (xy 92.928872 -167.251356) (xy 92.829815 -167.288594) (xy 92.728226 -167.318234)
			(xy 92.624686 -167.340105) (xy 92.519789 -167.354084) (xy 92.414135 -167.360089) (xy 92.308329 -167.358086)
			(xy 92.202978 -167.348087) (xy 92.098685 -167.330149) (xy 91.996047 -167.304375) (xy 91.895652 -167.270913)
			(xy 91.798075 -167.229953) (xy 91.703876 -167.181731) (xy 91.613593 -167.126524) (xy 91.527744 -167.064646)
			(xy 91.446821 -166.996453) (xy 91.371287 -166.922335) (xy 91.301575 -166.842717) (xy 91.238084 -166.758054)
			(xy 91.181177 -166.668833) (xy 91.131181 -166.575563) (xy 91.088383 -166.478779) (xy 91.053026 -166.379035)
			(xy 91.025315 -166.276903) (xy 91.005406 -166.172968) (xy 90.993416 -166.067825) (xy 90.989411 -165.962076)
			(xy 84.387436 -165.962076) (xy 84.386936 -166.014988) (xy 84.378932 -166.12051) (xy 84.362971 -166.225124)
			(xy 84.339144 -166.328231) (xy 84.307587 -166.429242) (xy 84.268482 -166.527576) (xy 84.222051 -166.622671)
			(xy 84.168562 -166.713982) (xy 84.10832 -166.800986) (xy 84.04167 -166.883186) (xy 83.968995 -166.960109)
			(xy 83.890711 -167.031315) (xy 83.807265 -167.096397) (xy 83.719136 -167.154982) (xy 83.626829 -167.206734)
			(xy 83.530872 -167.251356) (xy 83.431815 -167.288594) (xy 83.330226 -167.318234) (xy 83.226686 -167.340105)
			(xy 83.121789 -167.354084) (xy 83.016135 -167.360089) (xy 82.910329 -167.358086) (xy 82.804978 -167.348087)
			(xy 82.700685 -167.330149) (xy 82.598047 -167.304375) (xy 82.497652 -167.270913) (xy 82.400075 -167.229953)
			(xy 82.305876 -167.181731) (xy 82.215593 -167.126524) (xy 82.129744 -167.064646) (xy 82.048821 -166.996453)
			(xy 81.973287 -166.922335) (xy 81.903575 -166.842717) (xy 81.840084 -166.758054) (xy 81.783177 -166.668833)
			(xy 81.733181 -166.575563) (xy 81.690383 -166.478779) (xy 81.655026 -166.379035) (xy 81.627315 -166.276903)
			(xy 81.607406 -166.172968) (xy 81.595416 -166.067825) (xy 81.591411 -165.962076) (xy 63.903248 -165.962076)
			(xy 63.909379 -166.022525) (xy 63.909956 -166.067232) (xy 63.909956 -166.068248) (xy 63.909702 -166.079678)
			(xy 63.936181 -166.085625) (xy 63.988416 -166.100367) (xy 64.014096 -166.109142) (xy 64.022293 -166.111656)
			(xy 64.039427 -166.111656) (xy 64.047624 -166.109142) (xy 64.082842 -166.097202) (xy 64.154852 -166.078613)
			(xy 64.228174 -166.066171) (xy 64.302285 -166.059965) (xy 64.33947 -166.059612) (xy 64.376654 -166.059989)
			(xy 64.450761 -166.066209) (xy 64.524081 -166.078649) (xy 64.596093 -166.097221) (xy 64.631316 -166.109142)
			(xy 64.639513 -166.111656) (xy 64.656647 -166.111656) (xy 64.664844 -166.109142) (xy 64.699939 -166.097233)
			(xy 64.771698 -166.078689) (xy 64.844763 -166.066249) (xy 64.918616 -166.060001) (xy 64.955674 -166.059612)
			(xy 64.95669 -166.059612) (xy 64.998618 -166.060035) (xy 65.082094 -166.068005) (xy 65.164434 -166.083874)
			(xy 65.244893 -166.107498) (xy 65.322742 -166.138663) (xy 65.397276 -166.177087) (xy 65.46782 -166.222422)
			(xy 65.533735 -166.274258) (xy 65.594424 -166.332124) (xy 65.649338 -166.395498) (xy 65.69798 -166.463804)
			(xy 65.739908 -166.536425) (xy 65.774743 -166.612703) (xy 65.802169 -166.691946) (xy 65.821939 -166.773438)
			(xy 65.833873 -166.85644) (xy 65.837863 -166.9402) (xy 65.833873 -167.02396) (xy 65.821939 -167.106962)
			(xy 65.802169 -167.188454) (xy 65.774743 -167.267697) (xy 65.739908 -167.343975) (xy 65.69798 -167.416596)
			(xy 65.688295 -167.430196) (xy 351.432876 -167.430196) (xy 351.433453 -167.385427) (xy 351.442459 -167.296342)
			(xy 351.46036 -167.208611) (xy 351.486975 -167.123119) (xy 351.503996 -167.081708) (xy 351.507565 -167.072118)
			(xy 351.507564 -167.051674) (xy 351.503996 -167.042084) (xy 351.486956 -167.000679) (xy 351.460322 -166.91519)
			(xy 351.442419 -166.827456) (xy 351.433427 -166.738367) (xy 351.432876 -166.693596) (xy 351.433453 -166.648827)
			(xy 351.442459 -166.559742) (xy 351.46036 -166.472011) (xy 351.486975 -166.386519) (xy 351.503996 -166.345108)
			(xy 351.507565 -166.335518) (xy 351.507564 -166.315074) (xy 351.503996 -166.305484) (xy 351.486956 -166.264079)
			(xy 351.460322 -166.17859) (xy 351.442419 -166.090856) (xy 351.433427 -166.001767) (xy 351.432876 -165.956996)
			(xy 351.433349 -165.915886) (xy 351.440937 -165.834016) (xy 351.456047 -165.753196) (xy 351.478552 -165.674116)
			(xy 351.508259 -165.597449) (xy 351.544914 -165.523852) (xy 351.588204 -165.453951) (xy 351.63776 -165.388343)
			(xy 351.693159 -165.327588) (xy 351.753929 -165.272205) (xy 351.81955 -165.222667) (xy 351.889463 -165.179396)
			(xy 351.963071 -165.142761) (xy 352.039745 -165.113075) (xy 352.118832 -165.090592) (xy 352.199656 -165.075503)
			(xy 352.281528 -165.067937) (xy 352.322638 -165.067488) (xy 352.364242 -165.067962) (xy 352.44709 -165.075694)
			(xy 352.528855 -165.091124) (xy 352.608822 -165.114117) (xy 352.686295 -165.144474) (xy 352.760597 -165.181928)
			(xy 352.796094 -165.203632) (xy 352.805234 -165.208789) (xy 352.825949 -165.212002) (xy 352.846222 -165.206673)
			(xy 352.854768 -165.200584) (xy 352.888392 -165.174629) (xy 352.959771 -165.128573) (xy 353.035214 -165.08953)
			(xy 353.114035 -165.057855) (xy 353.195516 -165.033837) (xy 353.278916 -165.017694) (xy 353.363474 -165.009574)
			(xy 353.405948 -165.009068) (xy 353.406202 -165.009068) (xy 353.44731 -165.009511) (xy 353.529174 -165.017096)
			(xy 353.60999 -165.0322) (xy 353.689068 -165.054696) (xy 353.765733 -165.084391) (xy 353.839332 -165.121033)
			(xy 353.909237 -165.164307) (xy 353.974851 -165.213846) (xy 354.035616 -165.269227) (xy 354.091012 -165.329978)
			(xy 354.140567 -165.39558) (xy 354.183859 -165.465474) (xy 354.220519 -165.539063) (xy 354.250233 -165.615721)
			(xy 354.272749 -165.694793) (xy 354.287874 -165.775606) (xy 354.295479 -165.857468) (xy 354.295964 -165.898576)
			(xy 354.295409 -165.943346) (xy 354.286396 -166.032431) (xy 354.268489 -166.120162) (xy 354.241868 -166.205653)
			(xy 354.224844 -166.247064) (xy 354.221294 -166.256659) (xy 354.221285 -166.277097) (xy 354.224844 -166.286688)
			(xy 354.241856 -166.328036) (xy 354.268465 -166.413399) (xy 354.286369 -166.501003) (xy 354.289105 -166.527988)
			(xy 401.547076 -166.527988) (xy 401.54765 -166.483219) (xy 401.556657 -166.394134) (xy 401.574559 -166.306403)
			(xy 401.601175 -166.220911) (xy 401.618196 -166.1795) (xy 401.62177 -166.169912) (xy 401.621765 -166.149466)
			(xy 401.618196 -166.139876) (xy 401.601153 -166.098472) (xy 401.574521 -166.012983) (xy 401.556618 -165.925248)
			(xy 401.547627 -165.836159) (xy 401.547076 -165.791388) (xy 401.54765 -165.746619) (xy 401.556657 -165.657534)
			(xy 401.574559 -165.569803) (xy 401.601175 -165.484311) (xy 401.618196 -165.4429) (xy 401.62177 -165.433312)
			(xy 401.621765 -165.412866) (xy 401.618196 -165.403276) (xy 401.601153 -165.361872) (xy 401.574521 -165.276383)
			(xy 401.556618 -165.188648) (xy 401.547627 -165.099559) (xy 401.547076 -165.054788) (xy 401.547541 -165.013678)
			(xy 401.55513 -164.931808) (xy 401.570241 -164.850988) (xy 401.592747 -164.771907) (xy 401.622454 -164.695241)
			(xy 401.659109 -164.621643) (xy 401.7024 -164.551742) (xy 401.751957 -164.486134) (xy 401.807357 -164.42538)
			(xy 401.868127 -164.369997) (xy 401.933748 -164.320459) (xy 402.003662 -164.277187) (xy 402.07727 -164.240553)
			(xy 402.153944 -164.210867) (xy 402.233031 -164.188384) (xy 402.313856 -164.173295) (xy 402.395728 -164.165729)
			(xy 402.436838 -164.16528) (xy 402.478442 -164.165755) (xy 402.56129 -164.173487) (xy 402.643054 -164.188917)
			(xy 402.723022 -164.21191) (xy 402.800495 -164.242266) (xy 402.874796 -164.27972) (xy 402.910294 -164.301424)
			(xy 402.919434 -164.306582) (xy 402.940149 -164.309796) (xy 402.960422 -164.304466) (xy 402.968968 -164.298376)
			(xy 403.002591 -164.27242) (xy 403.07397 -164.226364) (xy 403.149414 -164.187321) (xy 403.228235 -164.155647)
			(xy 403.309716 -164.131629) (xy 403.393116 -164.115486) (xy 403.477674 -164.107366) (xy 403.520148 -164.10686)
			(xy 403.520402 -164.10686) (xy 403.561509 -164.107311) (xy 403.643374 -164.114895) (xy 403.724189 -164.13)
			(xy 403.803267 -164.152496) (xy 403.879931 -164.182191) (xy 403.95353 -164.218831) (xy 404.023434 -164.262106)
			(xy 404.089048 -164.311644) (xy 404.149813 -164.367025) (xy 404.205209 -164.427775) (xy 404.254764 -164.493376)
			(xy 404.298057 -164.563269) (xy 404.334716 -164.636858) (xy 404.364431 -164.713515) (xy 404.386947 -164.792587)
			(xy 404.402073 -164.873398) (xy 404.409679 -164.955261) (xy 404.410164 -164.996368) (xy 404.409606 -165.041138)
			(xy 404.400594 -165.130223) (xy 404.382688 -165.217954) (xy 404.356068 -165.303445) (xy 404.339044 -165.344856)
			(xy 404.335498 -165.354452) (xy 404.335487 -165.374889) (xy 404.339044 -165.38448) (xy 404.356053 -165.425829)
			(xy 404.382663 -165.511192) (xy 404.400568 -165.598795) (xy 404.409589 -165.687753) (xy 404.410164 -165.73246)
			(xy 404.410164 -165.733476) (xy 404.40991 -165.744906) (xy 404.436389 -165.750851) (xy 404.488624 -165.765594)
			(xy 404.514304 -165.77437) (xy 404.522501 -165.776884) (xy 404.539635 -165.776884) (xy 404.547832 -165.77437)
			(xy 404.58305 -165.762429) (xy 404.655059 -165.74384) (xy 404.728382 -165.731398) (xy 404.802492 -165.725192)
			(xy 404.839678 -165.72484) (xy 404.876862 -165.725213) (xy 404.95097 -165.731434) (xy 405.02429 -165.743875)
			(xy 405.096301 -165.762448) (xy 405.131524 -165.77437) (xy 405.139721 -165.776884) (xy 405.156855 -165.776884)
			(xy 405.165052 -165.77437) (xy 405.200146 -165.76246) (xy 405.271906 -165.743916) (xy 405.344971 -165.731476)
			(xy 405.418824 -165.725229) (xy 405.455882 -165.72484) (xy 405.456898 -165.72484) (xy 405.498822 -165.725407)
			(xy 405.582291 -165.733377) (xy 405.664623 -165.749245) (xy 405.745075 -165.772868) (xy 405.822917 -165.804031)
			(xy 405.897444 -165.842452) (xy 405.967982 -165.887784) (xy 406.033891 -165.939615) (xy 406.094575 -165.997477)
			(xy 406.149484 -166.060845) (xy 406.198121 -166.129146) (xy 406.240045 -166.20176) (xy 406.274876 -166.278031)
			(xy 406.302301 -166.357268) (xy 406.322068 -166.438752) (xy 406.334001 -166.521747) (xy 406.337991 -166.6055)
			(xy 406.334001 -166.689253) (xy 406.322068 -166.772248) (xy 406.302301 -166.853732) (xy 406.274876 -166.932969)
			(xy 406.240045 -167.00924) (xy 406.198121 -167.081854) (xy 406.149484 -167.150155) (xy 406.094575 -167.213523)
			(xy 406.033891 -167.271385) (xy 405.967982 -167.323216) (xy 405.897444 -167.368548) (xy 405.822917 -167.406969)
			(xy 405.745075 -167.438132) (xy 405.664623 -167.461755) (xy 405.582291 -167.477623) (xy 405.498822 -167.485593)
			(xy 405.456898 -167.486076) (xy 405.455882 -167.486076) (xy 405.418825 -167.485672) (xy 405.344976 -167.479407)
			(xy 405.271913 -167.466964) (xy 405.200153 -167.448432) (xy 405.165052 -167.436546) (xy 405.156855 -167.434032)
			(xy 405.139721 -167.434032) (xy 405.131524 -167.436546) (xy 405.102638 -167.446383) (xy 405.043785 -167.462529)
			(xy 405.013922 -167.468804) (xy 405.004334 -167.471159) (xy 404.987889 -167.482054) (xy 404.976796 -167.498367)
			(xy 404.974298 -167.50792) (xy 404.96417 -167.552275) (xy 404.936046 -167.638805) (xy 404.918164 -167.68064)
			(xy 404.914347 -167.690579) (xy 404.914353 -167.711846) (xy 404.918164 -167.721788) (xy 404.936394 -167.764388)
			(xy 404.964909 -167.852556) (xy 404.984099 -167.943213) (xy 404.993757 -168.035373) (xy 404.994364 -168.081706)
			(xy 404.994364 -168.082214) (xy 404.99386 -168.124562) (xy 404.985809 -168.208876) (xy 404.96978 -168.292042)
			(xy 404.945919 -168.373309) (xy 404.91444 -168.451939) (xy 404.875629 -168.52722) (xy 404.829839 -168.598472)
			(xy 404.777483 -168.665048) (xy 404.719035 -168.726346) (xy 404.655025 -168.781811) (xy 404.586033 -168.83094)
			(xy 404.512683 -168.873289) (xy 404.43564 -168.908473) (xy 404.355601 -168.936175) (xy 404.273292 -168.956143)
			(xy 404.189457 -168.968196) (xy 404.104856 -168.972227) (xy 404.020255 -168.968196) (xy 403.93642 -168.956143)
			(xy 403.854111 -168.936175) (xy 403.774072 -168.908473) (xy 403.697029 -168.873289) (xy 403.623679 -168.83094)
			(xy 403.554687 -168.781811) (xy 403.490677 -168.726346) (xy 403.432229 -168.665048) (xy 403.379873 -168.598472)
			(xy 403.334083 -168.52722) (xy 403.295272 -168.451939) (xy 403.263793 -168.373309) (xy 403.239932 -168.292042)
			(xy 403.223903 -168.208876) (xy 403.215852 -168.124562) (xy 403.215348 -168.082214) (xy 403.215348 -168.081706)
			(xy 403.215963 -168.035374) (xy 403.225632 -167.943217) (xy 403.244825 -167.852563) (xy 403.273334 -167.764394)
			(xy 403.291548 -167.721788) (xy 403.295348 -167.711844) (xy 403.295353 -167.690582) (xy 403.291548 -167.68064)
			(xy 403.273311 -167.637974) (xy 403.244764 -167.549684) (xy 403.225569 -167.458899) (xy 403.215934 -167.36661)
			(xy 403.215348 -167.320214) (xy 403.215953 -167.272404) (xy 403.226131 -167.177329) (xy 403.235668 -167.130476)
			(xy 403.23764 -167.118071) (xy 403.230727 -167.093957) (xy 403.22246 -167.084502) (xy 403.18182 -167.042338)
			(xy 403.178264 -167.0431) (xy 403.169416 -167.045411) (xy 403.154053 -167.055303) (xy 403.148292 -167.062404)
			(xy 403.123145 -167.095057) (xy 403.067744 -167.156083) (xy 403.006935 -167.211722) (xy 402.941239 -167.261497)
			(xy 402.871221 -167.304981) (xy 402.79748 -167.341801) (xy 402.720649 -167.371642) (xy 402.641387 -167.394246)
			(xy 402.560373 -167.409421) (xy 402.478303 -167.417036) (xy 402.437092 -167.417496) (xy 402.436838 -167.417496)
			(xy 402.395733 -167.416951) (xy 402.313873 -167.409371) (xy 402.233061 -167.394271) (xy 402.153987 -167.37178)
			(xy 402.077325 -167.342091) (xy 402.003729 -167.305456) (xy 401.933826 -167.262187) (xy 401.868213 -167.212655)
			(xy 401.80745 -167.157281) (xy 401.752053 -167.096538) (xy 401.702497 -167.030943) (xy 401.659203 -166.961056)
			(xy 401.622541 -166.887473) (xy 401.592824 -166.810822) (xy 401.570304 -166.731756) (xy 401.555174 -166.65095)
			(xy 401.547564 -166.569093) (xy 401.547076 -166.527988) (xy 354.289105 -166.527988) (xy 354.295389 -166.589961)
			(xy 354.295964 -166.634668) (xy 354.295964 -166.635684) (xy 354.29571 -166.647114) (xy 354.322189 -166.653059)
			(xy 354.374424 -166.667802) (xy 354.400104 -166.676578) (xy 354.408301 -166.679092) (xy 354.425435 -166.679092)
			(xy 354.433632 -166.676578) (xy 354.468848 -166.664633) (xy 354.540859 -166.646046) (xy 354.614181 -166.633606)
			(xy 354.688292 -166.6274) (xy 354.725478 -166.627048) (xy 354.762662 -166.62742) (xy 354.83677 -166.633641)
			(xy 354.91009 -166.646083) (xy 354.982101 -166.664656) (xy 355.017324 -166.676578) (xy 355.025521 -166.679092)
			(xy 355.042655 -166.679092) (xy 355.050852 -166.676578) (xy 355.085946 -166.664669) (xy 355.157706 -166.646124)
			(xy 355.230771 -166.633684) (xy 355.304624 -166.627437) (xy 355.341682 -166.627048) (xy 355.342698 -166.627048)
			(xy 355.384622 -166.627599) (xy 355.468092 -166.635569) (xy 355.550425 -166.651437) (xy 355.630878 -166.67506)
			(xy 355.70872 -166.706224) (xy 355.783248 -166.744645) (xy 355.853787 -166.789977) (xy 355.919696 -166.841809)
			(xy 355.980381 -166.899671) (xy 356.03529 -166.96304) (xy 356.083927 -167.031341) (xy 356.125852 -167.103957)
			(xy 356.160684 -167.180228) (xy 356.188108 -167.259465) (xy 356.207876 -167.340951) (xy 356.219809 -167.423946)
			(xy 356.223799 -167.5077) (xy 356.219809 -167.591454) (xy 356.207876 -167.674449) (xy 356.188108 -167.755935)
			(xy 356.160684 -167.835172) (xy 356.125852 -167.911443) (xy 356.083927 -167.984059) (xy 356.03529 -168.05236)
			(xy 355.980381 -168.115729) (xy 355.919696 -168.173591) (xy 355.853787 -168.225423) (xy 355.783248 -168.270755)
			(xy 355.70872 -168.309176) (xy 355.630878 -168.34034) (xy 355.550425 -168.363963) (xy 355.468092 -168.379831)
			(xy 355.384622 -168.387801) (xy 355.342698 -168.388284) (xy 355.341682 -168.388284) (xy 355.304625 -168.387885)
			(xy 355.230776 -168.381619) (xy 355.157713 -168.369175) (xy 355.085953 -168.350641) (xy 355.050852 -168.338754)
			(xy 355.042655 -168.33624) (xy 355.025521 -168.33624) (xy 355.017324 -168.338754) (xy 354.989546 -168.348208)
			(xy 354.932984 -168.363843) (xy 354.904294 -168.369996) (xy 354.894532 -168.372423) (xy 354.877923 -168.383747)
			(xy 354.866932 -168.400579) (xy 354.86467 -168.410382) (xy 354.855142 -168.457509) (xy 354.827269 -168.549532)
			(xy 354.809044 -168.594024) (xy 354.805459 -168.603609) (xy 354.805473 -168.624057) (xy 354.809044 -168.633648)
			(xy 354.826071 -168.675024) (xy 354.852688 -168.760451) (xy 354.870591 -168.84812) (xy 354.879599 -168.937143)
			(xy 354.880164 -168.981882) (xy 354.880164 -168.982136) (xy 354.87966 -169.024484) (xy 354.871609 -169.108798)
			(xy 354.85558 -169.191964) (xy 354.831719 -169.273231) (xy 354.80024 -169.351861) (xy 354.761429 -169.427142)
			(xy 354.715639 -169.498394) (xy 354.663283 -169.56497) (xy 354.604835 -169.626268) (xy 354.540825 -169.681733)
			(xy 354.471833 -169.730862) (xy 354.398483 -169.773211) (xy 354.32144 -169.808395) (xy 354.241401 -169.836097)
			(xy 354.159092 -169.856065) (xy 354.075257 -169.868118) (xy 353.990656 -169.872149) (xy 353.906055 -169.868118)
			(xy 353.82222 -169.856065) (xy 353.739911 -169.836097) (xy 353.659872 -169.808395) (xy 353.582829 -169.773211)
			(xy 353.509479 -169.730862) (xy 353.440487 -169.681733) (xy 353.376477 -169.626268) (xy 353.318029 -169.56497)
			(xy 353.265673 -169.498394) (xy 353.219883 -169.427142) (xy 353.181072 -169.351861) (xy 353.149593 -169.273231)
			(xy 353.125732 -169.191964) (xy 353.109703 -169.108798) (xy 353.101652 -169.024484) (xy 353.101148 -168.982136)
			(xy 353.101148 -168.981882) (xy 353.101731 -168.937144) (xy 353.110743 -168.848123) (xy 353.128644 -168.760456)
			(xy 353.155252 -168.675028) (xy 353.172268 -168.633648) (xy 353.175811 -168.624051) (xy 353.175824 -168.603615)
			(xy 353.172268 -168.594024) (xy 353.155227 -168.55262) (xy 353.128597 -168.46713) (xy 353.110694 -168.379396)
			(xy 353.1017 -168.290307) (xy 353.101148 -168.245536) (xy 353.101148 -168.24452) (xy 353.101526 -168.208908)
			(xy 353.107261 -168.137915) (xy 353.118654 -168.067607) (xy 353.126802 -168.032938) (xy 353.128529 -168.024629)
			(xy 353.126997 -168.007741) (xy 353.119979 -167.992303) (xy 353.114356 -167.985948) (xy 353.07397 -167.943276)
			(xy 353.064064 -167.945308) (xy 353.055164 -167.947623) (xy 353.039671 -167.957504) (xy 353.033838 -167.964612)
			(xy 353.008691 -167.997264) (xy 352.953283 -168.058281) (xy 352.892469 -168.113912) (xy 352.826771 -168.163681)
			(xy 352.756752 -168.207161) (xy 352.683013 -168.243979) (xy 352.606184 -168.273821) (xy 352.526925 -168.29643)
			(xy 352.445915 -168.311612) (xy 352.363848 -168.319237) (xy 352.322638 -168.319704) (xy 352.281533 -168.319151)
			(xy 352.199674 -168.311571) (xy 352.118862 -168.296471) (xy 352.039789 -168.273981) (xy 351.963127 -168.244292)
			(xy 351.889531 -168.207657) (xy 351.819629 -168.164389) (xy 351.754016 -168.114857) (xy 351.693252 -168.059484)
			(xy 351.637856 -167.998741) (xy 351.5883 -167.933147) (xy 351.545006 -167.863261) (xy 351.508343 -167.789678)
			(xy 351.478626 -167.713028) (xy 351.456106 -167.633963) (xy 351.440975 -167.553157) (xy 351.433364 -167.471301)
			(xy 351.432876 -167.430196) (xy 65.688295 -167.430196) (xy 65.649338 -167.484902) (xy 65.594424 -167.548276)
			(xy 65.533735 -167.606142) (xy 65.46782 -167.657978) (xy 65.397276 -167.703313) (xy 65.322742 -167.741737)
			(xy 65.244893 -167.772902) (xy 65.164434 -167.796526) (xy 65.082094 -167.812395) (xy 64.998618 -167.820365)
			(xy 64.95669 -167.820848) (xy 64.955674 -167.820848) (xy 64.918617 -167.820448) (xy 64.844768 -167.814181)
			(xy 64.771705 -167.801738) (xy 64.699945 -167.783204) (xy 64.664844 -167.771318) (xy 64.656647 -167.768804)
			(xy 64.639513 -167.768804) (xy 64.631316 -167.771318) (xy 64.597889 -167.782662) (xy 64.529607 -167.80059)
			(xy 64.494918 -167.807132) (xy 64.484907 -167.809437) (xy 64.467748 -167.820693) (xy 64.456372 -167.837772)
			(xy 64.454024 -167.847772) (xy 64.44452 -167.895628) (xy 64.416383 -167.989057) (xy 64.39789 -168.034208)
			(xy 64.394248 -168.043772) (xy 64.394124 -168.064219) (xy 64.397636 -168.073832) (xy 64.414658 -168.11521)
			(xy 64.441276 -168.200636) (xy 64.459181 -168.288304) (xy 64.46819 -168.377327) (xy 64.468756 -168.422066)
			(xy 64.468756 -168.42232) (xy 64.468252 -168.464668) (xy 64.460201 -168.548982) (xy 64.444172 -168.632148)
			(xy 64.420311 -168.713415) (xy 64.388832 -168.792045) (xy 64.350021 -168.867326) (xy 64.304231 -168.938578)
			(xy 64.251875 -169.005154) (xy 64.193427 -169.066452) (xy 64.129417 -169.121917) (xy 64.060425 -169.171046)
			(xy 63.987075 -169.213395) (xy 63.910032 -169.248579) (xy 63.829993 -169.276281) (xy 63.747684 -169.296249)
			(xy 63.663849 -169.308302) (xy 63.579248 -169.312333) (xy 63.494647 -169.308302) (xy 63.410812 -169.296249)
			(xy 63.328503 -169.276281) (xy 63.248464 -169.248579) (xy 63.171421 -169.213395) (xy 63.098071 -169.171046)
			(xy 63.029079 -169.121917) (xy 62.965069 -169.066452) (xy 62.906621 -169.005154) (xy 62.854265 -168.938578)
			(xy 62.808475 -168.867326) (xy 62.769664 -168.792045) (xy 62.738185 -168.713415) (xy 62.714324 -168.632148)
			(xy 62.698295 -168.548982) (xy 62.690244 -168.464668) (xy 62.68974 -168.42232) (xy 62.68974 -168.422066)
			(xy 62.690311 -168.377328) (xy 62.699325 -168.288306) (xy 62.71723 -168.200639) (xy 62.743842 -168.115211)
			(xy 62.76086 -168.073832) (xy 62.764412 -168.064238) (xy 62.76442 -168.043799) (xy 62.76086 -168.034208)
			(xy 62.743813 -167.992806) (xy 62.717185 -167.907315) (xy 62.699284 -167.81958) (xy 62.690292 -167.730491)
			(xy 62.68974 -167.68572) (xy 62.68974 -167.685466) (xy 62.689833 -167.667858) (xy 62.691229 -167.632668)
			(xy 62.692534 -167.615108) (xy 62.692907 -167.605036) (xy 62.68662 -167.585904) (xy 62.673425 -167.57069)
			(xy 62.664594 -167.565832) (xy 62.566296 -167.516556) (xy 62.535816 -167.520366) (xy 62.524132 -167.53078)
			(xy 62.493735 -167.556935) (xy 62.428993 -167.604263) (xy 62.360251 -167.645567) (xy 62.288069 -167.680512)
			(xy 62.213032 -167.708812) (xy 62.135751 -167.730238) (xy 62.056854 -167.744617) (xy 61.976982 -167.75183)
			(xy 61.936884 -167.752268) (xy 61.93663 -167.752268) (xy 61.895524 -167.751759) (xy 61.813662 -167.744177)
			(xy 61.732849 -167.729076) (xy 61.653773 -167.706584) (xy 61.57711 -167.676893) (xy 61.503513 -167.640256)
			(xy 61.433609 -167.596985) (xy 61.367995 -167.547451) (xy 61.307231 -167.492074) (xy 61.251835 -167.431328)
			(xy 61.202279 -167.36573) (xy 61.158986 -167.295841) (xy 61.122325 -167.222256) (xy 61.092608 -167.145602)
			(xy 61.07009 -167.066534) (xy 61.054963 -166.985725) (xy 61.047355 -166.903866) (xy 61.046868 -166.86276)
			(xy 2.509012 -166.86276) (xy 2.509012 -170.29303) (xy 8.7249 -170.29303) (xy 8.7249 -169.42943) (xy 8.725386 -169.402179)
			(xy 8.733142 -169.348231) (xy 8.748497 -169.295936) (xy 8.771139 -169.246359) (xy 8.800605 -169.200509)
			(xy 8.836296 -169.159318) (xy 8.877487 -169.123627) (xy 8.923337 -169.094161) (xy 8.972914 -169.071519)
			(xy 9.025209 -169.056164) (xy 9.079157 -169.048408) (xy 9.133659 -169.048408) (xy 9.187607 -169.056164)
			(xy 9.239902 -169.071519) (xy 9.289479 -169.094161) (xy 9.335329 -169.123627) (xy 9.37652 -169.159318)
			(xy 9.412211 -169.200509) (xy 9.441677 -169.246359) (xy 9.464319 -169.295936) (xy 9.479674 -169.348231)
			(xy 9.48743 -169.402179) (xy 9.487916 -169.42943) (xy 9.487916 -169.857674) (xy 111.084868 -169.857674)
			(xy 111.085438 -169.812905) (xy 111.094447 -169.72382) (xy 111.112349 -169.636089) (xy 111.138966 -169.550597)
			(xy 111.155988 -169.509186) (xy 111.15957 -169.4996) (xy 111.15956 -169.479153) (xy 111.155988 -169.469562)
			(xy 111.13894 -169.42816) (xy 111.112309 -169.34267) (xy 111.094408 -169.254935) (xy 111.085418 -169.165845)
			(xy 111.084868 -169.121074) (xy 111.085438 -169.076305) (xy 111.094447 -168.98722) (xy 111.112349 -168.899489)
			(xy 111.138966 -168.813997) (xy 111.155988 -168.772586) (xy 111.15957 -168.763) (xy 111.15956 -168.742553)
			(xy 111.155988 -168.732962) (xy 111.13894 -168.69156) (xy 111.112309 -168.60607) (xy 111.094408 -168.518335)
			(xy 111.085418 -168.429245) (xy 111.084868 -168.384474) (xy 111.085274 -168.343358) (xy 111.092864 -168.261476)
			(xy 111.107976 -168.180645) (xy 111.130482 -168.101552) (xy 111.160191 -168.024873) (xy 111.196847 -167.951263)
			(xy 111.240139 -167.881349) (xy 111.289697 -167.815728) (xy 111.345099 -167.754959) (xy 111.405871 -167.699561)
			(xy 111.471495 -167.650007) (xy 111.541412 -167.60672) (xy 111.615025 -167.570068) (xy 111.691705 -167.540365)
			(xy 111.770799 -167.517863) (xy 111.851632 -167.502756) (xy 111.933514 -167.495171) (xy 111.97463 -167.494712)
			(xy 112.016241 -167.495173) (xy 112.099098 -167.502953) (xy 112.180867 -167.518431) (xy 112.260835 -167.541474)
			(xy 112.338303 -167.571879) (xy 112.412595 -167.609382) (xy 112.448086 -167.63111) (xy 112.457229 -167.636263)
			(xy 112.477942 -167.63948) (xy 112.498214 -167.634152) (xy 112.50676 -167.628062) (xy 112.540389 -167.602071)
			(xy 112.611783 -167.555946) (xy 112.687254 -167.516845) (xy 112.766112 -167.485124) (xy 112.847637 -167.461075)
			(xy 112.931085 -167.444915) (xy 113.015695 -167.436793) (xy 113.058194 -167.436292) (xy 113.099307 -167.436819)
			(xy 113.181182 -167.444405) (xy 113.262007 -167.459513) (xy 113.341094 -167.482013) (xy 113.417768 -167.511715)
			(xy 113.491374 -167.548365) (xy 113.561284 -167.59165) (xy 113.626903 -167.6412) (xy 113.68767 -167.696593)
			(xy 113.743067 -167.757357) (xy 113.792621 -167.822973) (xy 113.83591 -167.892881) (xy 113.872564 -167.966485)
			(xy 113.90227 -168.043156) (xy 113.924776 -168.122242) (xy 113.939888 -168.203067) (xy 113.947479 -168.284941)
			(xy 113.947956 -168.326054) (xy 113.947393 -168.370824) (xy 113.938383 -168.459909) (xy 113.920477 -168.54764)
			(xy 113.893859 -168.633131) (xy 113.876836 -168.674542) (xy 113.873299 -168.684141) (xy 113.873282 -168.704576)
			(xy 113.876836 -168.714166) (xy 113.89384 -168.755517) (xy 113.920451 -168.840879) (xy 113.938358 -168.928482)
			(xy 113.94738 -169.017439) (xy 113.947956 -169.062146) (xy 113.947956 -169.063162) (xy 113.947702 -169.074592)
			(xy 113.974181 -169.080538) (xy 114.026416 -169.095281) (xy 114.052096 -169.104056) (xy 114.060293 -169.10657)
			(xy 114.077427 -169.10657) (xy 114.085624 -169.104056) (xy 114.12084 -169.092095) (xy 114.192844 -169.073441)
			(xy 114.266165 -169.060932) (xy 114.34028 -169.054659) (xy 114.37747 -169.054272) (xy 114.414659 -169.054671)
			(xy 114.488772 -169.060958) (xy 114.562092 -169.073465) (xy 114.634098 -169.092103) (xy 114.669316 -169.104056)
			(xy 114.677513 -169.10657) (xy 114.694647 -169.10657) (xy 114.702844 -169.104056) (xy 114.738059 -169.092089)
			(xy 114.810062 -169.073437) (xy 114.883384 -169.06093) (xy 114.9575 -169.054658) (xy 114.99469 -169.054272)
			(xy 115.03663 -169.054667) (xy 115.120132 -169.062639) (xy 115.202497 -169.078513) (xy 115.28298 -169.102144)
			(xy 115.360853 -169.133319) (xy 115.43541 -169.171755) (xy 115.505975 -169.217104) (xy 115.57191 -169.268955)
			(xy 115.632618 -169.326839) (xy 115.687549 -169.390232) (xy 115.736205 -169.458559) (xy 115.778146 -169.531202)
			(xy 115.812991 -169.607503) (xy 115.840426 -169.68677) (xy 115.860202 -169.768287) (xy 115.87214 -169.851314)
			(xy 115.876131 -169.9351) (xy 115.87214 -170.018886) (xy 115.860202 -170.101913) (xy 115.840426 -170.18343)
			(xy 115.812991 -170.262697) (xy 115.778146 -170.338998) (xy 115.736205 -170.411641) (xy 115.687549 -170.479968)
			(xy 115.632618 -170.543361) (xy 115.57191 -170.601245) (xy 115.505975 -170.653096) (xy 115.498571 -170.657854)
			(xy 161.052951 -170.657854) (xy 161.052951 -170.603346) (xy 161.060709 -170.549393) (xy 161.076066 -170.497093)
			(xy 161.09871 -170.447511) (xy 161.12818 -170.401657) (xy 161.163876 -170.360463) (xy 161.205071 -170.324769)
			(xy 161.250927 -170.295301) (xy 161.30051 -170.27266) (xy 161.352811 -170.257305) (xy 161.406764 -170.24955)
			(xy 161.434018 -170.249088) (xy 162.297618 -170.249088) (xy 162.324868 -170.249583) (xy 162.378813 -170.257342)
			(xy 162.431105 -170.272698) (xy 162.48068 -170.29534) (xy 162.526528 -170.324806) (xy 162.567715 -170.360498)
			(xy 162.603404 -170.401687) (xy 162.632869 -170.447536) (xy 162.655508 -170.497111) (xy 162.670862 -170.549404)
			(xy 162.678618 -170.60335) (xy 162.678618 -170.65785) (xy 162.670862 -170.711796) (xy 162.655508 -170.764089)
			(xy 162.632869 -170.813664) (xy 162.603404 -170.859513) (xy 162.567715 -170.900702) (xy 162.526528 -170.936394)
			(xy 162.48068 -170.96586) (xy 162.431105 -170.988502) (xy 162.378813 -171.003858) (xy 162.324868 -171.011617)
			(xy 162.297618 -171.012104) (xy 161.434018 -171.012104) (xy 161.406764 -171.01165) (xy 161.352811 -171.003895)
			(xy 161.30051 -170.98854) (xy 161.250927 -170.965899) (xy 161.205071 -170.936431) (xy 161.163876 -170.900737)
			(xy 161.12818 -170.859543) (xy 161.09871 -170.813689) (xy 161.076066 -170.764107) (xy 161.060709 -170.711807)
			(xy 161.052951 -170.657854) (xy 115.498571 -170.657854) (xy 115.43541 -170.698445) (xy 115.360853 -170.736881)
			(xy 115.28298 -170.768056) (xy 115.202497 -170.791687) (xy 115.120132 -170.807561) (xy 115.03663 -170.815533)
			(xy 114.99469 -170.816016) (xy 114.9575 -170.815629) (xy 114.883387 -170.809339) (xy 114.810068 -170.796828)
			(xy 114.738062 -170.778187) (xy 114.702844 -170.766232) (xy 114.694647 -170.763718) (xy 114.677513 -170.763718)
			(xy 114.669316 -170.766232) (xy 114.625188 -170.781068) (xy 114.534574 -170.80245) (xy 114.488468 -170.808904)
			(xy 114.478735 -170.810567) (xy 114.461516 -170.820188) (xy 114.449244 -170.83563) (xy 114.44605 -170.844972)
			(xy 114.43848 -170.870441) (xy 114.420685 -170.920512) (xy 114.41049 -170.945048) (xy 114.406882 -170.954622)
			(xy 114.406736 -170.97506) (xy 114.410236 -170.984672) (xy 114.427271 -171.026045) (xy 114.453886 -171.111473)
			(xy 114.471787 -171.199143) (xy 114.480792 -171.288167) (xy 114.481356 -171.332906) (xy 114.481356 -171.33316)
			(xy 114.480852 -171.375508) (xy 114.472801 -171.459822) (xy 114.456772 -171.542988) (xy 114.432911 -171.624255)
			(xy 114.401432 -171.702885) (xy 114.362621 -171.778166) (xy 114.316831 -171.849418) (xy 114.264475 -171.915994)
			(xy 114.206027 -171.977292) (xy 114.142017 -172.032757) (xy 114.073025 -172.081886) (xy 113.999675 -172.124235)
			(xy 113.922632 -172.159419) (xy 113.842593 -172.187121) (xy 113.760284 -172.207089) (xy 113.676449 -172.219142)
			(xy 113.591848 -172.223173) (xy 113.507247 -172.219142) (xy 113.423412 -172.207089) (xy 113.341103 -172.187121)
			(xy 113.261064 -172.159419) (xy 113.184021 -172.124235) (xy 113.110671 -172.081886) (xy 113.041679 -172.032757)
			(xy 112.977669 -171.977292) (xy 112.919221 -171.915994) (xy 112.866865 -171.849418) (xy 112.821075 -171.778166)
			(xy 112.782264 -171.702885) (xy 112.750785 -171.624255) (xy 112.726924 -171.542988) (xy 112.710895 -171.459822)
			(xy 112.702844 -171.375508) (xy 112.70234 -171.33316) (xy 112.70234 -171.332906) (xy 112.702891 -171.288167)
			(xy 112.711911 -171.199145) (xy 112.729821 -171.111478) (xy 112.75644 -171.026051) (xy 112.77346 -170.984672)
			(xy 112.777047 -170.975088) (xy 112.777032 -170.954639) (xy 112.77346 -170.945048) (xy 112.757652 -170.906707)
			(xy 112.732373 -170.827716) (xy 112.714548 -170.746717) (xy 112.70433 -170.664411) (xy 112.702594 -170.622976)
			(xy 112.702594 -170.622722) (xy 112.701955 -170.613271) (xy 112.694549 -170.595846) (xy 112.681333 -170.582289)
			(xy 112.672876 -170.578018) (xy 112.589818 -170.540172) (xy 112.581121 -170.536666) (xy 112.562416 -170.535564)
			(xy 112.544562 -170.541248) (xy 112.536986 -170.546776) (xy 112.536986 -170.54703) (xy 112.536478 -170.54703)
			(xy 112.502475 -170.574102) (xy 112.430107 -170.622247) (xy 112.353386 -170.663099) (xy 112.273043 -170.696267)
			(xy 112.189846 -170.721435) (xy 112.104591 -170.738363) (xy 112.01809 -170.746889) (xy 111.97463 -170.747436)
			(xy 111.933515 -170.746973) (xy 111.851635 -170.739388) (xy 111.770804 -170.72428) (xy 111.691713 -170.701779)
			(xy 111.615035 -170.672075) (xy 111.541425 -170.635423) (xy 111.471511 -170.592135) (xy 111.405889 -170.542581)
			(xy 111.34512 -170.487183) (xy 111.289722 -170.426414) (xy 111.240167 -170.360793) (xy 111.196879 -170.290879)
			(xy 111.160226 -170.217269) (xy 111.130522 -170.140591) (xy 111.10802 -170.061499) (xy 111.092912 -169.980669)
			(xy 111.085327 -169.898789) (xy 111.084868 -169.857674) (xy 9.487916 -169.857674) (xy 9.487916 -170.29303)
			(xy 9.48743 -170.320281) (xy 9.479674 -170.374229) (xy 9.464319 -170.426524) (xy 9.441677 -170.476101)
			(xy 9.412211 -170.521951) (xy 9.37652 -170.563142) (xy 9.335329 -170.598833) (xy 9.289479 -170.628299)
			(xy 9.239902 -170.650941) (xy 9.187607 -170.666296) (xy 9.133659 -170.674052) (xy 9.079157 -170.674052)
			(xy 9.025209 -170.666296) (xy 8.972914 -170.650941) (xy 8.923337 -170.628299) (xy 8.877487 -170.598833)
			(xy 8.836296 -170.563142) (xy 8.800605 -170.521951) (xy 8.771139 -170.476101) (xy 8.748497 -170.426524)
			(xy 8.733142 -170.374229) (xy 8.725386 -170.320281) (xy 8.7249 -170.29303) (xy 2.509012 -170.29303)
			(xy 2.509012 -173.07814) (xy 8.7249 -173.07814) (xy 8.7249 -172.21454) (xy 8.725386 -172.187289)
			(xy 8.733142 -172.133341) (xy 8.748497 -172.081046) (xy 8.771139 -172.031469) (xy 8.800605 -171.985619)
			(xy 8.836296 -171.944428) (xy 8.877487 -171.908737) (xy 8.923337 -171.879271) (xy 8.972914 -171.856629)
			(xy 9.025209 -171.841274) (xy 9.079157 -171.833518) (xy 9.133659 -171.833518) (xy 9.187607 -171.841274)
			(xy 9.239902 -171.856629) (xy 9.289479 -171.879271) (xy 9.335329 -171.908737) (xy 9.37652 -171.944428)
			(xy 9.412211 -171.985619) (xy 9.441677 -172.031469) (xy 9.464319 -172.081046) (xy 9.479674 -172.133341)
			(xy 9.48743 -172.187289) (xy 9.487916 -172.21454) (xy 9.487916 -173.07814) (xy 9.48743 -173.105391)
			(xy 9.479674 -173.159339) (xy 9.464319 -173.211634) (xy 9.441677 -173.261211) (xy 9.412211 -173.307061)
			(xy 9.37652 -173.348252) (xy 9.335329 -173.383943) (xy 9.289479 -173.413409) (xy 9.239902 -173.436051)
			(xy 9.187607 -173.451406) (xy 9.133659 -173.459162) (xy 9.079157 -173.459162) (xy 9.025209 -173.451406)
			(xy 8.972914 -173.436051) (xy 8.923337 -173.413409) (xy 8.877487 -173.383943) (xy 8.836296 -173.348252)
			(xy 8.800605 -173.307061) (xy 8.771139 -173.261211) (xy 8.748497 -173.211634) (xy 8.733142 -173.159339)
			(xy 8.725386 -173.105391) (xy 8.7249 -173.07814) (xy 2.509012 -173.07814) (xy 2.509012 -175.848264)
			(xy 8.7249 -175.848264) (xy 8.7249 -174.984664) (xy 8.725386 -174.957413) (xy 8.733142 -174.903465)
			(xy 8.748497 -174.85117) (xy 8.771139 -174.801593) (xy 8.800605 -174.755743) (xy 8.836296 -174.714552)
			(xy 8.877487 -174.678861) (xy 8.923337 -174.649395) (xy 8.972914 -174.626753) (xy 9.025209 -174.611398)
			(xy 9.079157 -174.603642) (xy 9.133659 -174.603642) (xy 9.187607 -174.611398) (xy 9.239902 -174.626753)
			(xy 9.289479 -174.649395) (xy 9.335329 -174.678861) (xy 9.37652 -174.714552) (xy 9.412211 -174.755743)
			(xy 9.441677 -174.801593) (xy 9.464319 -174.85117) (xy 9.479674 -174.903465) (xy 9.48743 -174.957413)
			(xy 9.487916 -174.984664) (xy 9.487916 -175.559974) (xy 69.360288 -175.559974) (xy 69.360857 -175.515205)
			(xy 69.369865 -175.42612) (xy 69.387768 -175.338388) (xy 69.414386 -175.252897) (xy 69.431408 -175.211486)
			(xy 69.434989 -175.2019) (xy 69.43498 -175.181453) (xy 69.431408 -175.171862) (xy 69.414355 -175.130462)
			(xy 69.387726 -175.044971) (xy 69.369827 -174.957236) (xy 69.360838 -174.868145) (xy 69.360288 -174.823374)
			(xy 69.360857 -174.778605) (xy 69.369865 -174.68952) (xy 69.387768 -174.601788) (xy 69.414386 -174.516297)
			(xy 69.431408 -174.474886) (xy 69.434989 -174.4653) (xy 69.43498 -174.444853) (xy 69.431408 -174.435262)
			(xy 69.414355 -174.393862) (xy 69.387726 -174.308371) (xy 69.369827 -174.220636) (xy 69.360838 -174.131545)
			(xy 69.360288 -174.086774) (xy 69.360674 -174.045657) (xy 69.368264 -173.963775) (xy 69.383377 -173.882942)
			(xy 69.405884 -173.803848) (xy 69.435593 -173.727169) (xy 69.47225 -173.653557) (xy 69.515543 -173.583643)
			(xy 69.565103 -173.518021) (xy 69.620506 -173.457252) (xy 69.681279 -173.401854) (xy 69.746905 -173.3523)
			(xy 69.816824 -173.309013) (xy 69.890438 -173.272362) (xy 69.96712 -173.24266) (xy 70.046216 -173.220159)
			(xy 70.12705 -173.205053) (xy 70.208933 -173.19747) (xy 70.25005 -173.197012) (xy 70.29166 -173.197513)
			(xy 70.374516 -173.205285) (xy 70.456284 -173.220756) (xy 70.536252 -173.243791) (xy 70.613721 -173.274189)
			(xy 70.688014 -173.311686) (xy 70.723506 -173.33341) (xy 70.73264 -173.338581) (xy 70.753359 -173.341792)
			(xy 70.773635 -173.336456) (xy 70.78218 -173.330362) (xy 70.815836 -173.304408) (xy 70.887226 -173.258279)
			(xy 70.962691 -173.219173) (xy 71.041544 -173.187448) (xy 71.123065 -173.163392) (xy 71.20651 -173.147226)
			(xy 71.291116 -173.139097) (xy 71.333614 -173.138592) (xy 71.374727 -173.139099) (xy 71.456602 -173.146687)
			(xy 71.537428 -173.161797) (xy 71.616516 -173.1843) (xy 71.693189 -173.214003) (xy 71.703445 -173.21911)
			(xy 393.739116 -173.21911) (xy 393.739743 -173.172708) (xy 393.749432 -173.08041) (xy 393.768686 -172.989625)
			(xy 393.797294 -172.90134) (xy 393.81557 -172.858684) (xy 393.819371 -172.84874) (xy 393.819374 -172.827478)
			(xy 393.81557 -172.817536) (xy 393.797307 -172.774875) (xy 393.768715 -172.686587) (xy 393.749458 -172.595804)
			(xy 393.739745 -172.503511) (xy 393.739116 -172.45711) (xy 393.739622 -172.415997) (xy 393.747208 -172.33412)
			(xy 393.762316 -172.253293) (xy 393.784818 -172.174205) (xy 393.81452 -172.097531) (xy 393.851171 -172.023924)
			(xy 393.894457 -171.954012) (xy 393.944008 -171.888393) (xy 393.999403 -171.827626) (xy 394.060168 -171.772229)
			(xy 394.125786 -171.722675) (xy 394.195696 -171.679387) (xy 394.269301 -171.642733) (xy 394.345975 -171.613028)
			(xy 394.425062 -171.590524) (xy 394.505889 -171.575413) (xy 394.587765 -171.567824) (xy 394.628878 -171.567348)
			(xy 394.670013 -171.567796) (xy 394.75193 -171.575416) (xy 394.832794 -171.590566) (xy 394.911913 -171.613115)
			(xy 394.988614 -171.642872) (xy 395.06224 -171.679583) (xy 395.132163 -171.722933) (xy 395.197785 -171.772553)
			(xy 395.258547 -171.828019) (xy 395.313929 -171.888856) (xy 395.339062 -171.921424) (xy 395.345281 -171.928954)
			(xy 395.36201 -171.939002) (xy 395.371574 -171.940982) (xy 395.41286 -171.948033) (xy 395.493962 -171.968978)
			(xy 395.572736 -171.997455) (xy 395.648484 -172.033212) (xy 395.720535 -172.075931) (xy 395.78825 -172.125234)
			(xy 395.851031 -172.180685) (xy 395.908321 -172.241793) (xy 395.959613 -172.308015) (xy 396.004452 -172.378766)
			(xy 396.042441 -172.453419) (xy 396.073244 -172.531313) (xy 396.096588 -172.611757) (xy 396.112266 -172.69404)
			(xy 396.120139 -172.777432) (xy 396.12062 -172.819314) (xy 396.120152 -172.860082) (xy 396.112652 -172.941273)
			(xy 396.097752 -173.021436) (xy 396.075577 -173.099899) (xy 396.046313 -173.176003) (xy 396.028672 -173.21276)
			(xy 396.024359 -173.222451) (xy 396.023438 -173.243625) (xy 396.026894 -173.253654) (xy 396.041217 -173.292003)
			(xy 396.063564 -173.370761) (xy 396.07857 -173.451241) (xy 396.086111 -173.53276) (xy 396.086584 -173.573694)
			(xy 396.086007 -173.618463) (xy 396.077001 -173.707548) (xy 396.0591 -173.795279) (xy 396.032485 -173.880771)
			(xy 396.015464 -173.922182) (xy 396.011903 -173.931774) (xy 396.0119 -173.952215) (xy 396.015464 -173.961806)
			(xy 396.032477 -174.003153) (xy 396.059087 -174.088517) (xy 396.076991 -174.17612) (xy 396.08601 -174.265079)
			(xy 396.086584 -174.309786) (xy 396.086584 -174.310802) (xy 396.08633 -174.322232) (xy 396.112809 -174.328178)
			(xy 396.165044 -174.342921) (xy 396.190724 -174.351696) (xy 396.198921 -174.35421) (xy 396.216055 -174.35421)
			(xy 396.224252 -174.351696) (xy 396.259466 -174.339729) (xy 396.33147 -174.321076) (xy 396.404792 -174.308569)
			(xy 396.478908 -174.302297) (xy 396.516098 -174.301912) (xy 396.553288 -174.302301) (xy 396.627401 -174.30859)
			(xy 396.70072 -174.3211) (xy 396.772726 -174.339741) (xy 396.807944 -174.351696) (xy 396.816141 -174.35421)
			(xy 396.833275 -174.35421) (xy 396.841472 -174.351696) (xy 396.876685 -174.339723) (xy 396.948689 -174.321072)
			(xy 397.022011 -174.308567) (xy 397.096127 -174.302297) (xy 397.133318 -174.301912) (xy 397.175254 -174.302444)
			(xy 397.258746 -174.310418) (xy 397.341102 -174.326292) (xy 397.421577 -174.349923) (xy 397.49944 -174.381096)
			(xy 397.573988 -174.41953) (xy 397.644545 -174.464875) (xy 397.710473 -174.516722) (xy 397.771173 -174.574601)
			(xy 397.826097 -174.637988) (xy 397.874747 -174.706309) (xy 397.916683 -174.778944) (xy 397.951524 -174.855237)
			(xy 397.978955 -174.934497) (xy 397.998729 -175.016005) (xy 398.010665 -175.099023) (xy 398.014656 -175.1828)
			(xy 398.010665 -175.266577) (xy 397.998729 -175.349595) (xy 397.978955 -175.431103) (xy 397.951524 -175.510363)
			(xy 397.916683 -175.586656) (xy 397.874747 -175.659291) (xy 397.826097 -175.727612) (xy 397.771173 -175.790999)
			(xy 397.710473 -175.848878) (xy 397.644545 -175.900725) (xy 397.573988 -175.94607) (xy 397.49944 -175.984504)
			(xy 397.421577 -176.015677) (xy 397.341102 -176.039308) (xy 397.258746 -176.055182) (xy 397.175254 -176.063156)
			(xy 397.133318 -176.063656) (xy 397.096129 -176.063259) (xy 397.022016 -176.056971) (xy 396.948696 -176.044464)
			(xy 396.87669 -176.025825) (xy 396.841472 -176.013872) (xy 396.833275 -176.011358) (xy 396.816141 -176.011358)
			(xy 396.807944 -176.013872) (xy 396.778999 -176.023726) (xy 396.720017 -176.039869) (xy 396.690088 -176.04613)
			(xy 396.680511 -176.048515) (xy 396.664071 -176.059402) (xy 396.652972 -176.0757) (xy 396.650464 -176.085246)
			(xy 396.640294 -176.12901) (xy 396.612299 -176.21439) (xy 396.594584 -176.25568) (xy 396.590807 -176.265631)
			(xy 396.590789 -176.286886) (xy 396.594584 -176.296828) (xy 396.612789 -176.339438) (xy 396.641312 -176.427603)
			(xy 396.660509 -176.518256) (xy 396.670174 -176.610414) (xy 396.670784 -176.656746) (xy 396.670784 -176.657254)
			(xy 396.67028 -176.699602) (xy 396.662229 -176.783916) (xy 396.6462 -176.867082) (xy 396.622339 -176.948349)
			(xy 396.59086 -177.026979) (xy 396.552049 -177.10226) (xy 396.506259 -177.173512) (xy 396.453903 -177.240088)
			(xy 396.395455 -177.301386) (xy 396.331445 -177.356851) (xy 396.262453 -177.40598) (xy 396.189103 -177.448329)
			(xy 396.11206 -177.483513) (xy 396.032021 -177.511215) (xy 395.949712 -177.531183) (xy 395.865877 -177.543236)
			(xy 395.781276 -177.547267) (xy 395.696675 -177.543236) (xy 395.61284 -177.531183) (xy 395.530531 -177.511215)
			(xy 395.450492 -177.483513) (xy 395.373449 -177.448329) (xy 395.300099 -177.40598) (xy 395.231107 -177.356851)
			(xy 395.167097 -177.301386) (xy 395.108649 -177.240088) (xy 395.056293 -177.173512) (xy 395.010503 -177.10226)
			(xy 394.971692 -177.026979) (xy 394.940213 -176.948349) (xy 394.916352 -176.867082) (xy 394.900323 -176.783916)
			(xy 394.892272 -176.699602) (xy 394.891768 -176.657254) (xy 394.891768 -176.656746) (xy 394.892395 -176.610415)
			(xy 394.902061 -176.518257) (xy 394.92125 -176.427603) (xy 394.949756 -176.339434) (xy 394.967968 -176.296828)
			(xy 394.971802 -176.286894) (xy 394.971784 -176.265622) (xy 394.967968 -176.25568) (xy 394.949707 -176.213025)
			(xy 394.921167 -176.12473) (xy 394.901979 -176.033943) (xy 394.89235 -175.941651) (xy 394.891768 -175.895254)
			(xy 394.89209 -175.858508) (xy 394.898067 -175.785262) (xy 394.903706 -175.74895) (xy 394.905149 -175.737024)
			(xy 394.898112 -175.714088) (xy 394.890244 -175.705008) (xy 394.824966 -175.637698) (xy 394.80236 -175.629824)
			(xy 394.790168 -175.631602) (xy 394.760779 -175.635286) (xy 394.701676 -175.63923) (xy 394.672058 -175.639476)
			(xy 394.630944 -175.639027) (xy 394.549066 -175.631436) (xy 394.468237 -175.616324) (xy 394.389148 -175.593818)
			(xy 394.312473 -175.564111) (xy 394.238865 -175.527456) (xy 394.168954 -175.484166) (xy 394.103335 -175.434611)
			(xy 394.042568 -175.379212) (xy 393.987171 -175.318444) (xy 393.937618 -175.252823) (xy 393.89433 -175.18291)
			(xy 393.857678 -175.109302) (xy 393.827973 -175.032625) (xy 393.80547 -174.953535) (xy 393.79036 -174.872707)
			(xy 393.782772 -174.790829) (xy 393.782296 -174.749714) (xy 393.782296 -174.749206) (xy 393.782815 -174.706532)
			(xy 393.791014 -174.621579) (xy 393.807309 -174.537801) (xy 393.83155 -174.455968) (xy 393.847066 -174.416212)
			(xy 393.850705 -174.406179) (xy 393.85003 -174.384863) (xy 393.845796 -174.375064) (xy 393.828734 -174.338786)
			(xy 393.800425 -174.263775) (xy 393.778984 -174.18652) (xy 393.764586 -174.107649) (xy 393.757348 -174.027801)
			(xy 393.756896 -173.987714) (xy 393.757452 -173.943459) (xy 393.766275 -173.855391) (xy 393.783795 -173.768633)
			(xy 393.809839 -173.684042) (xy 393.826492 -173.643036) (xy 393.830085 -173.632871) (xy 393.829579 -173.611348)
			(xy 393.825476 -173.60138) (xy 393.808875 -173.565511) (xy 393.781358 -173.491412) (xy 393.760529 -173.415162)
			(xy 393.746554 -173.337364) (xy 393.739543 -173.258632) (xy 393.739116 -173.21911) (xy 71.703445 -173.21911)
			(xy 71.766795 -173.250654) (xy 71.836706 -173.29394) (xy 71.902324 -173.343492) (xy 71.963091 -173.398886)
			(xy 72.018488 -173.459651) (xy 72.068042 -173.525268) (xy 72.11133 -173.595177) (xy 72.147984 -173.668781)
			(xy 72.17769 -173.745454) (xy 72.200196 -173.82454) (xy 72.215308 -173.905366) (xy 72.222899 -173.987241)
			(xy 72.223376 -174.028354) (xy 72.22282 -174.073124) (xy 72.213808 -174.162209) (xy 72.195901 -174.24994)
			(xy 72.16928 -174.335431) (xy 72.152256 -174.376842) (xy 72.148718 -174.38644) (xy 72.148701 -174.406876)
			(xy 72.152256 -174.416466) (xy 72.169272 -174.457846) (xy 72.195896 -174.543271) (xy 72.213802 -174.630939)
			(xy 72.222811 -174.719961) (xy 72.223376 -174.7647) (xy 72.223376 -174.765208) (xy 72.223122 -174.77867)
			(xy 72.249601 -174.784615) (xy 72.301836 -174.799358) (xy 72.327516 -174.808134) (xy 72.335713 -174.810648)
			(xy 72.352847 -174.810648) (xy 72.361044 -174.808134) (xy 72.39626 -174.796188) (xy 72.46827 -174.777601)
			(xy 72.541593 -174.765161) (xy 72.615704 -174.758956) (xy 72.65289 -174.758604) (xy 72.690074 -174.75897)
			(xy 72.764182 -174.765192) (xy 72.837502 -174.777635) (xy 72.909513 -174.796211) (xy 72.944736 -174.808134)
			(xy 72.952933 -174.810648) (xy 72.970067 -174.810648) (xy 72.978264 -174.808134) (xy 73.013366 -174.796247)
			(xy 73.085122 -174.777697) (xy 73.158185 -174.765251) (xy 73.232036 -174.758997) (xy 73.269094 -174.758604)
			(xy 73.27011 -174.758604) (xy 73.312036 -174.759059) (xy 73.395508 -174.767031) (xy 73.477845 -174.7829)
			(xy 73.5583 -174.806525) (xy 73.636145 -174.83769) (xy 73.710676 -174.876114) (xy 73.781216 -174.921448)
			(xy 73.847128 -174.973283) (xy 73.907814 -175.031148) (xy 73.962725 -175.094519) (xy 74.011364 -175.162823)
			(xy 74.053289 -175.235441) (xy 74.088123 -175.311716) (xy 74.115548 -175.390956) (xy 74.135316 -175.472444)
			(xy 74.14725 -175.555443) (xy 74.15124 -175.6392) (xy 74.14725 -175.722957) (xy 74.135316 -175.805956)
			(xy 74.115548 -175.887444) (xy 74.088123 -175.966684) (xy 74.053289 -176.042959) (xy 74.01685 -176.106074)
			(xy 102.855268 -176.106074) (xy 102.855838 -176.061305) (xy 102.864847 -175.97222) (xy 102.882749 -175.884489)
			(xy 102.909366 -175.798997) (xy 102.926388 -175.757586) (xy 102.92997 -175.748) (xy 102.92996 -175.727553)
			(xy 102.926388 -175.717962) (xy 102.90934 -175.67656) (xy 102.882709 -175.59107) (xy 102.864808 -175.503335)
			(xy 102.855818 -175.414245) (xy 102.855268 -175.369474) (xy 102.855838 -175.324705) (xy 102.864847 -175.23562)
			(xy 102.882749 -175.147889) (xy 102.909366 -175.062397) (xy 102.926388 -175.020986) (xy 102.92997 -175.0114)
			(xy 102.92996 -174.990953) (xy 102.926388 -174.981362) (xy 102.90934 -174.93996) (xy 102.882709 -174.85447)
			(xy 102.864808 -174.766735) (xy 102.855818 -174.677645) (xy 102.855268 -174.632874) (xy 102.855674 -174.591758)
			(xy 102.863264 -174.509876) (xy 102.878376 -174.429045) (xy 102.900882 -174.349952) (xy 102.930591 -174.273273)
			(xy 102.967247 -174.199663) (xy 103.010539 -174.129749) (xy 103.060097 -174.064128) (xy 103.115499 -174.003359)
			(xy 103.176271 -173.947961) (xy 103.241895 -173.898407) (xy 103.311812 -173.85512) (xy 103.385425 -173.818468)
			(xy 103.462105 -173.788765) (xy 103.541199 -173.766263) (xy 103.622032 -173.751156) (xy 103.703914 -173.743571)
			(xy 103.74503 -173.743112) (xy 103.786641 -173.743573) (xy 103.869498 -173.751353) (xy 103.951267 -173.766831)
			(xy 104.031235 -173.789874) (xy 104.108703 -173.820279) (xy 104.182995 -173.857782) (xy 104.218486 -173.87951)
			(xy 104.227629 -173.884663) (xy 104.248342 -173.88788) (xy 104.268614 -173.882552) (xy 104.27716 -173.876462)
			(xy 104.310789 -173.850471) (xy 104.382183 -173.804346) (xy 104.457654 -173.765245) (xy 104.536512 -173.733524)
			(xy 104.618037 -173.709475) (xy 104.701485 -173.693315) (xy 104.786095 -173.685193) (xy 104.828594 -173.684692)
			(xy 104.869707 -173.685219) (xy 104.951582 -173.692805) (xy 105.032407 -173.707913) (xy 105.111494 -173.730413)
			(xy 105.188168 -173.760115) (xy 105.261774 -173.796765) (xy 105.331684 -173.84005) (xy 105.397303 -173.8896)
			(xy 105.45807 -173.944993) (xy 105.513467 -174.005757) (xy 105.563021 -174.071373) (xy 105.60631 -174.141281)
			(xy 105.642964 -174.214885) (xy 105.67267 -174.291556) (xy 105.695176 -174.370642) (xy 105.710288 -174.451467)
			(xy 105.717879 -174.533341) (xy 105.718356 -174.574454) (xy 105.717793 -174.619224) (xy 105.708783 -174.708309)
			(xy 105.690877 -174.79604) (xy 105.664259 -174.881531) (xy 105.647236 -174.922942) (xy 105.643699 -174.932541)
			(xy 105.643682 -174.952976) (xy 105.647236 -174.962566) (xy 105.66424 -175.003917) (xy 105.690851 -175.089279)
			(xy 105.708758 -175.176882) (xy 105.71778 -175.265839) (xy 105.718356 -175.310546) (xy 105.718356 -175.311562)
			(xy 105.718102 -175.322992) (xy 105.744581 -175.328938) (xy 105.796816 -175.343681) (xy 105.822496 -175.352456)
			(xy 105.830693 -175.35497) (xy 105.847827 -175.35497) (xy 105.856024 -175.352456) (xy 105.89124 -175.340495)
			(xy 105.963244 -175.321841) (xy 106.036565 -175.309332) (xy 106.11068 -175.303059) (xy 106.14787 -175.302672)
			(xy 106.185059 -175.303071) (xy 106.259172 -175.309358) (xy 106.332492 -175.321865) (xy 106.404498 -175.340503)
			(xy 106.439716 -175.352456) (xy 106.447913 -175.35497) (xy 106.465047 -175.35497) (xy 106.473244 -175.352456)
			(xy 106.508459 -175.340489) (xy 106.580462 -175.321837) (xy 106.653784 -175.30933) (xy 106.7279 -175.303058)
			(xy 106.76509 -175.302672) (xy 106.80703 -175.303067) (xy 106.890532 -175.311039) (xy 106.972897 -175.326913)
			(xy 107.05338 -175.350544) (xy 107.131253 -175.381719) (xy 107.20581 -175.420155) (xy 107.276375 -175.465504)
			(xy 107.34231 -175.517355) (xy 107.403018 -175.575239) (xy 107.457949 -175.638632) (xy 107.505577 -175.705516)
			(xy 359.713276 -175.705516) (xy 359.713826 -175.660746) (xy 359.72284 -175.571661) (xy 359.740749 -175.48393)
			(xy 359.767371 -175.398439) (xy 359.784396 -175.357028) (xy 359.787954 -175.347435) (xy 359.78796 -175.326994)
			(xy 359.784396 -175.317404) (xy 359.767362 -175.275997) (xy 359.740727 -175.190508) (xy 359.722822 -175.102775)
			(xy 359.713828 -175.013687) (xy 359.713276 -174.968916) (xy 359.713826 -174.924146) (xy 359.72284 -174.835061)
			(xy 359.740749 -174.74733) (xy 359.767371 -174.661839) (xy 359.784396 -174.620428) (xy 359.787954 -174.610835)
			(xy 359.78796 -174.590394) (xy 359.784396 -174.580804) (xy 359.767362 -174.539397) (xy 359.740727 -174.453908)
			(xy 359.722822 -174.366175) (xy 359.713828 -174.277087) (xy 359.713276 -174.232316) (xy 359.713768 -174.191206)
			(xy 359.721354 -174.109337) (xy 359.736463 -174.028517) (xy 359.758966 -173.949437) (xy 359.788671 -173.872771)
			(xy 359.825324 -173.799173) (xy 359.868613 -173.729272) (xy 359.918168 -173.663664) (xy 359.973567 -173.602909)
			(xy 360.034335 -173.547526) (xy 360.099955 -173.497988) (xy 360.169867 -173.454716) (xy 360.243474 -173.418081)
			(xy 360.320148 -173.388396) (xy 360.399234 -173.365912) (xy 360.480057 -173.350823) (xy 360.561928 -173.343257)
			(xy 360.603038 -173.342808) (xy 360.644642 -173.343279) (xy 360.72749 -173.351011) (xy 360.809255 -173.366441)
			(xy 360.889223 -173.389435) (xy 360.966695 -173.419793) (xy 361.040997 -173.457248) (xy 361.076494 -173.478952)
			(xy 361.08563 -173.48412) (xy 361.106349 -173.487339) (xy 361.126625 -173.482001) (xy 361.135168 -173.475904)
			(xy 361.168794 -173.449952) (xy 361.240172 -173.403895) (xy 361.315615 -173.364851) (xy 361.394436 -173.333176)
			(xy 361.475917 -173.309157) (xy 361.559316 -173.293014) (xy 361.643874 -173.284894) (xy 361.686348 -173.284388)
			(xy 361.686602 -173.284388) (xy 361.72771 -173.284811) (xy 361.809576 -173.292396) (xy 361.890393 -173.307501)
			(xy 361.969472 -173.329998) (xy 362.046138 -173.359694) (xy 362.119738 -173.396336) (xy 362.189643 -173.439612)
			(xy 362.255258 -173.489152) (xy 362.316023 -173.544534) (xy 362.371419 -173.605287) (xy 362.420974 -173.67089)
			(xy 362.464266 -173.740786) (xy 362.500925 -173.814377) (xy 362.530638 -173.891036) (xy 362.553153 -173.97011)
			(xy 362.568276 -174.050924) (xy 362.57588 -174.132788) (xy 362.576364 -174.173896) (xy 362.575781 -174.218665)
			(xy 362.566776 -174.307749) (xy 362.548877 -174.395481) (xy 362.522264 -174.480972) (xy 362.505244 -174.522384)
			(xy 362.501683 -174.531976) (xy 362.501681 -174.552417) (xy 362.505244 -174.562008) (xy 362.522284 -174.603413)
			(xy 362.548917 -174.688902) (xy 362.56682 -174.776636) (xy 362.575812 -174.865725) (xy 362.576364 -174.910496)
			(xy 362.575094 -174.953676) (xy 362.575044 -174.965402) (xy 362.584373 -174.986895) (xy 362.602231 -175.002063)
			(xy 362.613448 -175.005492) (xy 362.632331 -175.010413) (xy 362.669682 -175.021721) (xy 362.688124 -175.028098)
			(xy 362.696321 -175.030612) (xy 362.713455 -175.030612) (xy 362.721652 -175.028098) (xy 362.756876 -175.016176)
			(xy 362.828883 -174.997583) (xy 362.902204 -174.985136) (xy 362.976313 -174.978924) (xy 363.013498 -174.978568)
			(xy 363.050682 -174.978934) (xy 363.12479 -174.985156) (xy 363.19811 -174.997599) (xy 363.270121 -175.016175)
			(xy 363.305344 -175.028098) (xy 363.313541 -175.030612) (xy 363.330675 -175.030612) (xy 363.338872 -175.028098)
			(xy 363.373974 -175.016212) (xy 363.44573 -174.997661) (xy 363.518793 -174.985214) (xy 363.592644 -174.978961)
			(xy 363.629702 -174.978568) (xy 363.630718 -174.978568) (xy 363.672642 -174.979095) (xy 363.75611 -174.987067)
			(xy 363.838443 -175.002937) (xy 363.918894 -175.026561) (xy 363.996736 -175.057726) (xy 364.071262 -175.096148)
			(xy 364.141799 -175.141481) (xy 364.207708 -175.193313) (xy 364.268391 -175.251175) (xy 364.323299 -175.314544)
			(xy 364.371935 -175.382845) (xy 364.413859 -175.45546) (xy 364.44869 -175.531731) (xy 364.476114 -175.610968)
			(xy 364.495881 -175.692452) (xy 364.507814 -175.775447) (xy 364.511804 -175.8592) (xy 364.507814 -175.942953)
			(xy 364.495881 -176.025948) (xy 364.476114 -176.107432) (xy 364.44869 -176.186669) (xy 364.413859 -176.26294)
			(xy 364.371935 -176.335555) (xy 364.323299 -176.403856) (xy 364.268391 -176.467225) (xy 364.207708 -176.525087)
			(xy 364.141799 -176.576919) (xy 364.071262 -176.622252) (xy 363.996736 -176.660674) (xy 363.918894 -176.691839)
			(xy 363.838443 -176.715463) (xy 363.75611 -176.731333) (xy 363.672642 -176.739305) (xy 363.630718 -176.739804)
			(xy 363.629702 -176.739804) (xy 363.592645 -176.739398) (xy 363.518796 -176.733134) (xy 363.445733 -176.720692)
			(xy 363.373973 -176.70216) (xy 363.338872 -176.690274) (xy 363.330675 -176.68776) (xy 363.313541 -176.68776)
			(xy 363.305344 -176.690274) (xy 363.271298 -176.701763) (xy 363.201741 -176.719817) (xy 363.166406 -176.726342)
			(xy 363.157048 -176.728326) (xy 363.140733 -176.738296) (xy 363.129218 -176.75356) (xy 363.126274 -176.762664)
			(xy 363.118487 -176.78918) (xy 363.100057 -176.841287) (xy 363.089444 -176.866804) (xy 363.085871 -176.876392)
			(xy 363.085877 -176.896837) (xy 363.089444 -176.906428) (xy 363.106465 -176.947806) (xy 363.133084 -177.033233)
			(xy 363.150988 -177.120901) (xy 363.159998 -177.209923) (xy 363.160564 -177.254662) (xy 363.160564 -177.254916)
			(xy 363.16006 -177.297264) (xy 363.152009 -177.381578) (xy 363.13598 -177.464744) (xy 363.112119 -177.546011)
			(xy 363.08064 -177.624641) (xy 363.041829 -177.699922) (xy 362.996039 -177.771174) (xy 362.943683 -177.83775)
			(xy 362.885235 -177.899048) (xy 362.821225 -177.954513) (xy 362.752233 -178.003642) (xy 362.678883 -178.045991)
			(xy 362.60184 -178.081175) (xy 362.521801 -178.108877) (xy 362.439492 -178.128845) (xy 362.355657 -178.140898)
			(xy 362.271056 -178.144929) (xy 362.186455 -178.140898) (xy 362.10262 -178.128845) (xy 362.020311 -178.108877)
			(xy 361.940272 -178.081175) (xy 361.863229 -178.045991) (xy 361.789879 -178.003642) (xy 361.720887 -177.954513)
			(xy 361.656877 -177.899048) (xy 361.598429 -177.83775) (xy 361.546073 -177.771174) (xy 361.500283 -177.699922)
			(xy 361.461472 -177.624641) (xy 361.429993 -177.546011) (xy 361.406132 -177.464744) (xy 361.390103 -177.381578)
			(xy 361.382052 -177.297264) (xy 361.381548 -177.254916) (xy 361.381548 -177.254662) (xy 361.382124 -177.209924)
			(xy 361.391138 -177.120903) (xy 361.409041 -177.033235) (xy 361.435651 -176.947807) (xy 361.452668 -176.906428)
			(xy 361.456222 -176.896834) (xy 361.456228 -176.876395) (xy 361.452668 -176.866804) (xy 361.435658 -176.825422)
			(xy 361.409036 -176.739997) (xy 361.391129 -176.65233) (xy 361.382115 -176.563308) (xy 361.381548 -176.51857)
			(xy 361.381548 -176.518316) (xy 361.38189 -176.482968) (xy 361.387504 -176.412495) (xy 361.39869 -176.34269)
			(xy 361.406694 -176.308258) (xy 361.409002 -176.295757) (xy 361.402463 -176.271224) (xy 361.394248 -176.261522)
			(xy 361.353608 -176.218596) (xy 361.34421 -176.220628) (xy 361.335443 -176.222892) (xy 361.32021 -176.232657)
			(xy 361.314492 -176.239678) (xy 361.289344 -176.272353) (xy 361.233931 -176.333418) (xy 361.173106 -176.389094)
			(xy 361.10739 -176.438902) (xy 361.037347 -176.482416) (xy 360.963578 -176.519263) (xy 360.886716 -176.549126)
			(xy 360.807421 -176.571748) (xy 360.726373 -176.586937) (xy 360.644268 -176.594561) (xy 360.603038 -176.595024)
			(xy 360.561931 -176.594551) (xy 360.480067 -176.58697) (xy 360.399251 -176.571868) (xy 360.320173 -176.549375)
			(xy 360.243508 -176.519683) (xy 360.169909 -176.483044) (xy 360.100004 -176.439772) (xy 360.034389 -176.390235)
			(xy 359.973624 -176.334856) (xy 359.918228 -176.274107) (xy 359.868672 -176.208506) (xy 359.825379 -176.138613)
			(xy 359.78872 -176.065025) (xy 359.759005 -175.988368) (xy 359.73649 -175.909296) (xy 359.721365 -175.828485)
			(xy 359.713761 -175.746623) (xy 359.713276 -175.705516) (xy 107.505577 -175.705516) (xy 107.506605 -175.706959)
			(xy 107.548546 -175.779602) (xy 107.583391 -175.855903) (xy 107.610826 -175.93517) (xy 107.630602 -176.016687)
			(xy 107.64254 -176.099714) (xy 107.646531 -176.1835) (xy 107.64254 -176.267286) (xy 107.630602 -176.350313)
			(xy 107.610826 -176.43183) (xy 107.583391 -176.511097) (xy 107.548546 -176.587398) (xy 107.506605 -176.660041)
			(xy 107.457949 -176.728368) (xy 107.403018 -176.791761) (xy 107.34231 -176.849645) (xy 107.276375 -176.901496)
			(xy 107.20581 -176.946845) (xy 107.131253 -176.985281) (xy 107.05338 -177.016456) (xy 106.972897 -177.040087)
			(xy 106.890532 -177.055961) (xy 106.80703 -177.063933) (xy 106.76509 -177.064416) (xy 106.7279 -177.064029)
			(xy 106.653787 -177.057739) (xy 106.580468 -177.045228) (xy 106.508462 -177.026587) (xy 106.473244 -177.014632)
			(xy 106.465047 -177.012118) (xy 106.447913 -177.012118) (xy 106.439716 -177.014632) (xy 106.394061 -177.029945)
			(xy 106.300252 -177.051713) (xy 106.252518 -177.058066) (xy 106.242041 -177.059824) (xy 106.223772 -177.070618)
			(xy 106.211473 -177.087908) (xy 106.20883 -177.098198) (xy 106.199325 -177.142161) (xy 106.1726 -177.22805)
			(xy 106.15549 -177.269648) (xy 106.151882 -177.279222) (xy 106.151736 -177.29966) (xy 106.155236 -177.309272)
			(xy 106.172271 -177.350645) (xy 106.198886 -177.436073) (xy 106.216787 -177.523743) (xy 106.225792 -177.612767)
			(xy 106.226356 -177.657506) (xy 106.226356 -177.65776) (xy 106.225852 -177.700108) (xy 106.217801 -177.784422)
			(xy 106.201772 -177.867588) (xy 106.177911 -177.948855) (xy 106.146432 -178.027485) (xy 106.107621 -178.102766)
			(xy 106.061831 -178.174018) (xy 106.009475 -178.240594) (xy 105.951027 -178.301892) (xy 105.887017 -178.357357)
			(xy 105.818025 -178.406486) (xy 105.744675 -178.448835) (xy 105.667632 -178.484019) (xy 105.587593 -178.511721)
			(xy 105.505284 -178.531689) (xy 105.421449 -178.543742) (xy 105.336848 -178.547773) (xy 105.252247 -178.543742)
			(xy 105.168412 -178.531689) (xy 105.086103 -178.511721) (xy 105.006064 -178.484019) (xy 104.929021 -178.448835)
			(xy 104.855671 -178.406486) (xy 104.786679 -178.357357) (xy 104.722669 -178.301892) (xy 104.664221 -178.240594)
			(xy 104.611865 -178.174018) (xy 104.566075 -178.102766) (xy 104.527264 -178.027485) (xy 104.495785 -177.948855)
			(xy 104.471924 -177.867588) (xy 104.455895 -177.784422) (xy 104.447844 -177.700108) (xy 104.44734 -177.65776)
			(xy 104.44734 -177.657506) (xy 104.447891 -177.612767) (xy 104.456911 -177.523745) (xy 104.474821 -177.436078)
			(xy 104.50144 -177.350651) (xy 104.51846 -177.309272) (xy 104.522047 -177.299688) (xy 104.522032 -177.279239)
			(xy 104.51846 -177.269648) (xy 104.501426 -177.228241) (xy 104.474794 -177.142752) (xy 104.456889 -177.055019)
			(xy 104.447894 -176.965931) (xy 104.44734 -176.92116) (xy 104.447594 -176.89703) (xy 104.44745 -176.887477)
			(xy 104.440882 -176.869548) (xy 104.428227 -176.855249) (xy 104.419908 -176.850548) (xy 104.33812 -176.808638)
			(xy 104.329507 -176.804642) (xy 104.310627 -176.802733) (xy 104.292347 -176.807824) (xy 104.284526 -176.81321)
			(xy 104.284526 -176.813464) (xy 104.284018 -176.813464) (xy 104.250823 -176.838169) (xy 104.180649 -176.882028)
			(xy 104.106709 -176.919187) (xy 104.029639 -176.949324) (xy 103.950105 -176.97218) (xy 103.868793 -176.987556)
			(xy 103.786406 -176.995321) (xy 103.74503 -176.995836) (xy 103.703915 -176.995373) (xy 103.622035 -176.987788)
			(xy 103.541204 -176.97268) (xy 103.462113 -176.950179) (xy 103.385435 -176.920475) (xy 103.311825 -176.883823)
			(xy 103.241911 -176.840535) (xy 103.176289 -176.790981) (xy 103.11552 -176.735583) (xy 103.060122 -176.674814)
			(xy 103.010567 -176.609193) (xy 102.967279 -176.539279) (xy 102.930626 -176.465669) (xy 102.900922 -176.388991)
			(xy 102.87842 -176.309899) (xy 102.863312 -176.229069) (xy 102.855727 -176.147189) (xy 102.855268 -176.106074)
			(xy 74.01685 -176.106074) (xy 74.011364 -176.115577) (xy 73.962725 -176.183881) (xy 73.907814 -176.247252)
			(xy 73.847128 -176.305117) (xy 73.781216 -176.356952) (xy 73.710676 -176.402286) (xy 73.636145 -176.44071)
			(xy 73.5583 -176.471875) (xy 73.477845 -176.4955) (xy 73.395508 -176.511369) (xy 73.312036 -176.519341)
			(xy 73.27011 -176.51984) (xy 73.269094 -176.51984) (xy 73.232037 -176.519434) (xy 73.158188 -176.51317)
			(xy 73.085125 -176.500728) (xy 73.013365 -176.482196) (xy 72.978264 -176.47031) (xy 72.970067 -176.467796)
			(xy 72.952933 -176.467796) (xy 72.944736 -176.47031) (xy 72.910756 -176.481853) (xy 72.841327 -176.500034)
			(xy 72.806052 -176.506632) (xy 72.796116 -176.508916) (xy 72.779041 -176.520017) (xy 72.767603 -176.536869)
			(xy 72.765158 -176.546764) (xy 72.755578 -176.591455) (xy 72.728473 -176.67875) (xy 72.711056 -176.721008)
			(xy 72.70748 -176.730595) (xy 72.707488 -176.751041) (xy 72.711056 -176.760632) (xy 72.728073 -176.802012)
			(xy 72.754694 -176.887437) (xy 72.7726 -176.975105) (xy 72.78161 -177.064127) (xy 72.782176 -177.108866)
			(xy 72.782176 -177.10912) (xy 72.781672 -177.151468) (xy 72.773621 -177.235782) (xy 72.757592 -177.318948)
			(xy 72.733731 -177.400215) (xy 72.702252 -177.478845) (xy 72.663441 -177.554126) (xy 72.617651 -177.625378)
			(xy 72.565295 -177.691954) (xy 72.506847 -177.753252) (xy 72.442837 -177.808717) (xy 72.373845 -177.857846)
			(xy 72.300495 -177.900195) (xy 72.223452 -177.935379) (xy 72.143413 -177.963081) (xy 72.061104 -177.983049)
			(xy 71.977269 -177.995102) (xy 71.892668 -177.999133) (xy 71.808067 -177.995102) (xy 71.724232 -177.983049)
			(xy 71.641923 -177.963081) (xy 71.561884 -177.935379) (xy 71.484841 -177.900195) (xy 71.411491 -177.857846)
			(xy 71.342499 -177.808717) (xy 71.278489 -177.753252) (xy 71.220041 -177.691954) (xy 71.167685 -177.625378)
			(xy 71.121895 -177.554126) (xy 71.083084 -177.478845) (xy 71.051605 -177.400215) (xy 71.027744 -177.318948)
			(xy 71.011715 -177.235782) (xy 71.003664 -177.151468) (xy 71.00316 -177.10912) (xy 71.00316 -177.108866)
			(xy 71.003737 -177.064128) (xy 71.01275 -176.975107) (xy 71.030653 -176.887439) (xy 71.057263 -176.802011)
			(xy 71.07428 -176.760632) (xy 71.077831 -176.751038) (xy 71.077839 -176.730599) (xy 71.07428 -176.721008)
			(xy 71.057235 -176.679605) (xy 71.030605 -176.594115) (xy 71.012704 -176.50638) (xy 71.003712 -176.417291)
			(xy 71.00316 -176.37252) (xy 71.00316 -176.371758) (xy 71.003227 -176.356824) (xy 71.004242 -176.326972)
			(xy 71.005192 -176.312068) (xy 71.005427 -176.302019) (xy 70.999034 -176.282984) (xy 70.985815 -176.267867)
			(xy 70.976998 -176.263046) (xy 70.8787 -176.214532) (xy 70.84822 -176.218596) (xy 70.83679 -176.228756)
			(xy 70.806403 -176.254854) (xy 70.741691 -176.302073) (xy 70.672994 -176.343279) (xy 70.60087 -176.378141)
			(xy 70.525902 -176.406374) (xy 70.4487 -176.427751) (xy 70.369887 -176.442098) (xy 70.290104 -176.449298)
			(xy 70.25005 -176.449736) (xy 70.208935 -176.449254) (xy 70.127056 -176.441671) (xy 70.046226 -176.426565)
			(xy 69.967134 -176.404065) (xy 69.890456 -176.374363) (xy 69.816846 -176.337712) (xy 69.746932 -176.294426)
			(xy 69.68131 -176.244873) (xy 69.620541 -176.189476) (xy 69.565143 -176.128708) (xy 69.515588 -176.063088)
			(xy 69.472299 -175.993175) (xy 69.435647 -175.919566) (xy 69.405943 -175.842889) (xy 69.383441 -175.763798)
			(xy 69.368332 -175.682968) (xy 69.360747 -175.601089) (xy 69.360288 -175.559974) (xy 9.487916 -175.559974)
			(xy 9.487916 -175.848264) (xy 9.48743 -175.875515) (xy 9.479674 -175.929463) (xy 9.464319 -175.981758)
			(xy 9.441677 -176.031335) (xy 9.412211 -176.077185) (xy 9.37652 -176.118376) (xy 9.335329 -176.154067)
			(xy 9.289479 -176.183533) (xy 9.239902 -176.206175) (xy 9.187607 -176.22153) (xy 9.133659 -176.229286)
			(xy 9.079157 -176.229286) (xy 9.025209 -176.22153) (xy 8.972914 -176.206175) (xy 8.923337 -176.183533)
			(xy 8.877487 -176.154067) (xy 8.836296 -176.118376) (xy 8.800605 -176.077185) (xy 8.771139 -176.031335)
			(xy 8.748497 -175.981758) (xy 8.733142 -175.929463) (xy 8.725386 -175.875515) (xy 8.7249 -175.848264)
			(xy 2.509012 -175.848264) (xy 2.509012 -178.618388) (xy 8.7249 -178.618388) (xy 8.7249 -177.754788)
			(xy 8.725386 -177.727537) (xy 8.733142 -177.673589) (xy 8.748497 -177.621294) (xy 8.771139 -177.571717)
			(xy 8.800605 -177.525867) (xy 8.836296 -177.484676) (xy 8.877487 -177.448985) (xy 8.923337 -177.419519)
			(xy 8.972914 -177.396877) (xy 9.025209 -177.381522) (xy 9.079157 -177.373766) (xy 9.133659 -177.373766)
			(xy 9.187607 -177.381522) (xy 9.239902 -177.396877) (xy 9.289479 -177.419519) (xy 9.335329 -177.448985)
			(xy 9.37652 -177.484676) (xy 9.412211 -177.525867) (xy 9.441677 -177.571717) (xy 9.464319 -177.621294)
			(xy 9.479674 -177.673589) (xy 9.48743 -177.727537) (xy 9.487916 -177.754788) (xy 9.487916 -178.618388)
			(xy 9.48743 -178.645639) (xy 9.479674 -178.699587) (xy 9.464319 -178.751882) (xy 9.44304 -178.798474)
			(xy 77.963268 -178.798474) (xy 77.963886 -178.752072) (xy 77.973579 -178.659774) (xy 77.992835 -178.568989)
			(xy 78.021445 -178.480704) (xy 78.039722 -178.438048) (xy 78.043541 -178.42811) (xy 78.043531 -178.406843)
			(xy 78.039722 -178.3969) (xy 78.021451 -178.354243) (xy 77.99286 -178.265953) (xy 77.973605 -178.175169)
			(xy 77.963896 -178.082875) (xy 77.963268 -178.036474) (xy 77.963674 -177.995358) (xy 77.971264 -177.913476)
			(xy 77.986376 -177.832645) (xy 78.008882 -177.753552) (xy 78.038591 -177.676873) (xy 78.075247 -177.603263)
			(xy 78.118539 -177.533349) (xy 78.168097 -177.467728) (xy 78.223499 -177.406959) (xy 78.284271 -177.351561)
			(xy 78.349895 -177.302007) (xy 78.419812 -177.25872) (xy 78.493425 -177.222068) (xy 78.570105 -177.192365)
			(xy 78.649199 -177.169863) (xy 78.730032 -177.154756) (xy 78.811914 -177.147171) (xy 78.85303 -177.146712)
			(xy 78.893848 -177.147168) (xy 78.975141 -177.154659) (xy 79.055405 -177.169568) (xy 79.133966 -177.191768)
			(xy 79.210162 -177.221072) (xy 79.283352 -177.257234) (xy 79.352922 -177.29995) (xy 79.418285 -177.348861)
			(xy 79.478892 -177.403555) (xy 79.534233 -177.463571) (xy 79.559404 -177.495708) (xy 79.565179 -177.502627)
			(xy 79.580393 -177.512264) (xy 79.589122 -177.514504) (xy 79.631283 -177.524073) (xy 79.713687 -177.550242)
			(xy 79.793163 -177.584282) (xy 79.868962 -177.625872) (xy 79.940368 -177.67462) (xy 80.006708 -177.730066)
			(xy 80.067355 -177.791686) (xy 80.121738 -177.8589) (xy 80.169343 -177.931073) (xy 80.209721 -178.007525)
			(xy 80.242492 -178.087533) (xy 80.267345 -178.170343) (xy 80.284047 -178.255173) (xy 80.29244 -178.341224)
			(xy 80.292956 -178.384454) (xy 80.292766 -178.411062) (xy 80.289588 -178.464184) (xy 80.286606 -178.490626)
			(xy 80.285833 -178.501873) (xy 80.292962 -178.523233) (xy 80.300322 -178.531774) (xy 80.329261 -178.562798)
			(xy 80.381784 -178.629432) (xy 80.427728 -178.700761) (xy 80.466676 -178.776139) (xy 80.498274 -178.854881)
			(xy 80.522235 -178.936272) (xy 80.538342 -179.019574) (xy 80.546449 -179.104032) (xy 80.546956 -179.146454)
			(xy 80.546393 -179.191224) (xy 80.537383 -179.280309) (xy 80.519477 -179.36804) (xy 80.492859 -179.453531)
			(xy 80.475836 -179.494942) (xy 80.472299 -179.504541) (xy 80.472282 -179.524976) (xy 80.475836 -179.534566)
			(xy 80.49284 -179.575917) (xy 80.519451 -179.661279) (xy 80.537358 -179.748882) (xy 80.54638 -179.837839)
			(xy 80.546956 -179.882546) (xy 80.546956 -179.883562) (xy 80.546702 -179.894992) (xy 80.573181 -179.900938)
			(xy 80.625416 -179.915681) (xy 80.651096 -179.924456) (xy 80.659293 -179.92697) (xy 80.676427 -179.92697)
			(xy 80.684624 -179.924456) (xy 80.71984 -179.912495) (xy 80.791844 -179.893841) (xy 80.865165 -179.881332)
			(xy 80.93928 -179.875059) (xy 80.97647 -179.874672) (xy 81.013659 -179.875071) (xy 81.087772 -179.881358)
			(xy 81.161092 -179.893865) (xy 81.233098 -179.912503) (xy 81.268316 -179.924456) (xy 81.276513 -179.92697)
			(xy 81.293647 -179.92697) (xy 81.301844 -179.924456) (xy 81.337059 -179.912489) (xy 81.409062 -179.893837)
			(xy 81.482384 -179.88133) (xy 81.5565 -179.875058) (xy 81.59369 -179.874672) (xy 81.63563 -179.875067)
			(xy 81.719132 -179.883039) (xy 81.801497 -179.898913) (xy 81.88198 -179.922544) (xy 81.959853 -179.953719)
			(xy 82.03441 -179.992155) (xy 82.104975 -180.037504) (xy 82.17091 -180.089355) (xy 82.231618 -180.147239)
			(xy 82.286549 -180.210632) (xy 82.335205 -180.278959) (xy 82.377146 -180.351602) (xy 82.411991 -180.427903)
			(xy 82.439426 -180.50717) (xy 82.459202 -180.588687) (xy 82.462267 -180.610002) (xy 86.081108 -180.610002)
			(xy 86.081685 -180.565233) (xy 86.090691 -180.476148) (xy 86.108592 -180.388417) (xy 86.135207 -180.302925)
			(xy 86.152228 -180.261514) (xy 86.155792 -180.251923) (xy 86.155793 -180.231481) (xy 86.152228 -180.22189)
			(xy 86.135186 -180.180486) (xy 86.108554 -180.094996) (xy 86.090651 -180.007262) (xy 86.081659 -179.918173)
			(xy 86.081108 -179.873402) (xy 86.081685 -179.828633) (xy 86.090691 -179.739548) (xy 86.108592 -179.651817)
			(xy 86.135207 -179.566325) (xy 86.152228 -179.524914) (xy 86.155792 -179.515323) (xy 86.155793 -179.494881)
			(xy 86.152228 -179.48529) (xy 86.135186 -179.443886) (xy 86.108554 -179.358396) (xy 86.090651 -179.270662)
			(xy 86.081659 -179.181573) (xy 86.081108 -179.136802) (xy 86.081615 -179.095689) (xy 86.089201 -179.013813)
			(xy 86.10431 -178.932986) (xy 86.126812 -178.853898) (xy 86.156515 -178.777224) (xy 86.193165 -178.703617)
			(xy 86.236451 -178.633706) (xy 86.286003 -178.568087) (xy 86.341397 -178.50732) (xy 86.402163 -178.451923)
			(xy 86.46778 -178.402369) (xy 86.537689 -178.359081) (xy 86.611295 -178.322428) (xy 86.687968 -178.292722)
			(xy 86.767055 -178.270217) (xy 86.847881 -178.255106) (xy 86.929757 -178.247516) (xy 86.97087 -178.24704)
			(xy 87.01248 -178.247527) (xy 87.095336 -178.255301) (xy 87.177105 -178.270774) (xy 87.257073 -178.293812)
			(xy 87.334542 -178.324213) (xy 87.408835 -178.361712) (xy 87.444326 -178.383438) (xy 87.453453 -178.388623)
			(xy 87.474176 -178.391826) (xy 87.494454 -178.386485) (xy 87.503 -178.38039) (xy 87.536641 -178.354416)
			(xy 87.608034 -178.30829) (xy 87.683503 -178.269188) (xy 87.762359 -178.237466) (xy 87.843882 -178.213414)
			(xy 87.927328 -178.19725) (xy 88.011936 -178.189124) (xy 88.054434 -178.18862) (xy 88.095548 -178.18908)
			(xy 88.177426 -178.19667) (xy 88.258254 -178.211782) (xy 88.337343 -178.234287) (xy 88.414018 -178.263994)
			(xy 88.487625 -178.300648) (xy 88.557536 -178.343937) (xy 88.623155 -178.393491) (xy 88.683922 -178.448889)
			(xy 88.739319 -178.509657) (xy 88.788872 -178.575277) (xy 88.83216 -178.645189) (xy 88.868813 -178.718797)
			(xy 88.898518 -178.795473) (xy 88.921021 -178.874562) (xy 88.936132 -178.95539) (xy 88.94372 -179.037268)
			(xy 88.944196 -179.078382) (xy 88.943648 -179.123152) (xy 88.934633 -179.212238) (xy 88.916724 -179.299969)
			(xy 88.890101 -179.38546) (xy 88.873076 -179.42687) (xy 88.869521 -179.436464) (xy 88.869514 -179.456904)
			(xy 88.873076 -179.466494) (xy 88.890086 -179.507843) (xy 88.916696 -179.593206) (xy 88.934602 -179.680809)
			(xy 88.943621 -179.769767) (xy 88.944196 -179.814474) (xy 88.944196 -179.81549) (xy 88.943942 -179.82692)
			(xy 88.970422 -179.832862) (xy 89.022656 -179.847607) (xy 89.048336 -179.856384) (xy 89.056533 -179.858898)
			(xy 89.073667 -179.858898) (xy 89.081864 -179.856384) (xy 89.117077 -179.844413) (xy 89.189082 -179.825761)
			(xy 89.262404 -179.813256) (xy 89.33652 -179.806985) (xy 89.37371 -179.8066) (xy 89.4109 -179.806986)
			(xy 89.485013 -179.813277) (xy 89.558333 -179.825787) (xy 89.630338 -179.844429) (xy 89.665556 -179.856384)
			(xy 89.673753 -179.858898) (xy 89.690887 -179.858898) (xy 89.699084 -179.856384) (xy 89.734295 -179.844408)
			(xy 89.8063 -179.825757) (xy 89.879623 -179.813253) (xy 89.953739 -179.806984) (xy 89.99093 -179.8066)
			(xy 90.032865 -179.807156) (xy 90.116355 -179.815131) (xy 90.198709 -179.831006) (xy 90.279182 -179.854637)
			(xy 90.357043 -179.885811) (xy 90.431589 -179.924244) (xy 90.502144 -179.969589) (xy 90.56807 -180.021436)
			(xy 90.628768 -180.079314) (xy 90.683691 -180.1427) (xy 90.732339 -180.211019) (xy 90.774274 -180.283653)
			(xy 90.809114 -180.359944) (xy 90.836544 -180.439202) (xy 90.856317 -180.520708) (xy 90.868253 -180.603725)
			(xy 90.869375 -180.627274) (xy 94.473268 -180.627274) (xy 94.473838 -180.582505) (xy 94.482847 -180.49342)
			(xy 94.500749 -180.405689) (xy 94.527366 -180.320197) (xy 94.544388 -180.278786) (xy 94.54797 -180.2692)
			(xy 94.54796 -180.248753) (xy 94.544388 -180.239162) (xy 94.52734 -180.19776) (xy 94.500709 -180.11227)
			(xy 94.482808 -180.024535) (xy 94.473818 -179.935445) (xy 94.473268 -179.890674) (xy 94.473838 -179.845905)
			(xy 94.482847 -179.75682) (xy 94.500749 -179.669089) (xy 94.527366 -179.583597) (xy 94.544388 -179.542186)
			(xy 94.54797 -179.5326) (xy 94.54796 -179.512153) (xy 94.544388 -179.502562) (xy 94.52734 -179.46116)
			(xy 94.500709 -179.37567) (xy 94.482808 -179.287935) (xy 94.473818 -179.198845) (xy 94.473268 -179.154074)
			(xy 94.473674 -179.112958) (xy 94.481264 -179.031076) (xy 94.496376 -178.950245) (xy 94.518882 -178.871152)
			(xy 94.548591 -178.794473) (xy 94.585247 -178.720863) (xy 94.628539 -178.650949) (xy 94.678097 -178.585328)
			(xy 94.733499 -178.524559) (xy 94.794271 -178.469161) (xy 94.859895 -178.419607) (xy 94.929812 -178.37632)
			(xy 95.003425 -178.339668) (xy 95.080105 -178.309965) (xy 95.159199 -178.287463) (xy 95.240032 -178.272356)
			(xy 95.321914 -178.264771) (xy 95.36303 -178.264312) (xy 95.404641 -178.264773) (xy 95.487498 -178.272553)
			(xy 95.569267 -178.288031) (xy 95.649235 -178.311074) (xy 95.726703 -178.341479) (xy 95.800995 -178.378982)
			(xy 95.836486 -178.40071) (xy 95.845629 -178.405863) (xy 95.866342 -178.40908) (xy 95.886614 -178.403752)
			(xy 95.89516 -178.397662) (xy 95.928789 -178.371671) (xy 96.000183 -178.325546) (xy 96.075654 -178.286445)
			(xy 96.154512 -178.254724) (xy 96.236037 -178.230675) (xy 96.319485 -178.214515) (xy 96.404095 -178.206393)
			(xy 96.446594 -178.205892) (xy 96.487707 -178.206419) (xy 96.569582 -178.214005) (xy 96.650407 -178.229113)
			(xy 96.729494 -178.251613) (xy 96.806168 -178.281315) (xy 96.879774 -178.317965) (xy 96.949684 -178.36125)
			(xy 97.015303 -178.4108) (xy 97.07607 -178.466193) (xy 97.131467 -178.526957) (xy 97.181021 -178.592573)
			(xy 97.22431 -178.662481) (xy 97.260964 -178.736085) (xy 97.29067 -178.812756) (xy 97.313176 -178.891842)
			(xy 97.328288 -178.972667) (xy 97.335879 -179.054541) (xy 97.336356 -179.095654) (xy 97.335793 -179.140424)
			(xy 97.329275 -179.204874) (xy 368.074448 -179.204874) (xy 368.075006 -179.161932) (xy 368.083288 -179.076448)
			(xy 368.099773 -178.99216) (xy 368.124306 -178.909855) (xy 368.15666 -178.830297) (xy 368.196533 -178.75423)
			(xy 368.243554 -178.682361) (xy 368.297284 -178.615359) (xy 368.357224 -178.55385) (xy 368.422813 -178.498405)
			(xy 368.493443 -178.449542) (xy 368.568454 -178.407716) (xy 368.607594 -178.390042) (xy 368.615999 -178.385919)
			(xy 368.629281 -178.372745) (xy 368.633502 -178.364388) (xy 368.645948 -178.33721) (xy 368.64947 -178.328554)
			(xy 368.650638 -178.309919) (xy 368.648234 -178.300888) (xy 368.635415 -178.257999) (xy 368.617464 -178.170297)
			(xy 368.608423 -178.081234) (xy 368.607848 -178.036474) (xy 368.608352 -177.994113) (xy 368.616405 -177.909776)
			(xy 368.632439 -177.826586) (xy 368.656307 -177.745296) (xy 368.687795 -177.666644) (xy 368.726617 -177.591341)
			(xy 368.77242 -177.520069) (xy 368.824791 -177.453473) (xy 368.883256 -177.392158) (xy 368.947284 -177.336677)
			(xy 369.016296 -177.287534) (xy 369.089666 -177.245174) (xy 369.166731 -177.209979) (xy 369.246793 -177.18227)
			(xy 369.329126 -177.162296) (xy 369.412985 -177.150239) (xy 369.49761 -177.146208) (xy 369.582235 -177.150239)
			(xy 369.666094 -177.162296) (xy 369.748427 -177.18227) (xy 369.828489 -177.209979) (xy 369.905554 -177.245174)
			(xy 369.978924 -177.287534) (xy 370.047936 -177.336677) (xy 370.111964 -177.392158) (xy 370.170429 -177.453473)
			(xy 370.2228 -177.520069) (xy 370.268603 -177.591341) (xy 370.307425 -177.666644) (xy 370.338913 -177.745296)
			(xy 370.362781 -177.826586) (xy 370.378815 -177.909776) (xy 370.386868 -177.994113) (xy 370.387372 -178.036474)
			(xy 370.387372 -178.036728) (xy 370.386948 -178.075094) (xy 370.380306 -178.151538) (xy 370.367099 -178.227125)
			(xy 370.357654 -178.264312) (xy 370.35562 -178.273261) (xy 370.357441 -178.291512) (xy 370.365595 -178.307941)
			(xy 370.37903 -178.320427) (xy 370.387372 -178.324256) (xy 370.427603 -178.341379) (xy 370.50477 -178.382506)
			(xy 370.577528 -178.431007) (xy 370.645175 -178.486413) (xy 370.707059 -178.548191) (xy 370.762582 -178.615743)
			(xy 370.811207 -178.688417) (xy 370.852467 -178.765513) (xy 370.885962 -178.846285) (xy 370.911369 -178.929954)
			(xy 370.928442 -179.015713) (xy 370.937018 -179.102733) (xy 370.937536 -179.146454) (xy 370.936975 -179.191224)
			(xy 370.927964 -179.280309) (xy 370.910058 -179.36804) (xy 370.883439 -179.453531) (xy 370.866416 -179.494942)
			(xy 370.86288 -179.504541) (xy 370.862862 -179.524975) (xy 370.866416 -179.534566) (xy 370.883441 -179.575977)
			(xy 370.910078 -179.661464) (xy 370.927986 -179.749196) (xy 370.936982 -179.838284) (xy 370.937536 -179.883054)
			(xy 370.937282 -179.903882) (xy 370.937631 -179.91519) (xy 370.946776 -179.935848) (xy 370.963889 -179.950596)
			(xy 370.97462 -179.954174) (xy 370.989618 -179.95835) (xy 371.019344 -179.967623) (xy 371.034056 -179.972716)
			(xy 371.042253 -179.97523) (xy 371.059387 -179.97523) (xy 371.067584 -179.972716) (xy 371.102796 -179.960741)
			(xy 371.174801 -179.94209) (xy 371.248123 -179.929585) (xy 371.322239 -179.923316) (xy 371.35943 -179.922932)
			(xy 371.396619 -179.923339) (xy 371.470732 -179.929623) (xy 371.544052 -179.942128) (xy 371.616058 -179.960764)
			(xy 371.651276 -179.972716) (xy 371.659473 -179.97523) (xy 371.676607 -179.97523) (xy 371.684804 -179.972716)
			(xy 371.720023 -179.960763) (xy 371.792025 -179.942106) (xy 371.865345 -179.929595) (xy 371.93946 -179.923319)
			(xy 371.97665 -179.922932) (xy 372.01859 -179.923405) (xy 372.10209 -179.931374) (xy 372.184455 -179.947244)
			(xy 372.264938 -179.970872) (xy 372.34281 -180.002043) (xy 372.417367 -180.040476) (xy 372.487932 -180.085822)
			(xy 372.553868 -180.137671) (xy 372.614576 -180.195553) (xy 372.669507 -180.258944) (xy 372.718163 -180.327269)
			(xy 372.760105 -180.39991) (xy 372.794951 -180.476209) (xy 372.822386 -180.555475) (xy 372.842162 -180.63699)
			(xy 372.848069 -180.678074) (xy 376.477276 -180.678074) (xy 376.477846 -180.633305) (xy 376.486854 -180.54422)
			(xy 376.504757 -180.456489) (xy 376.531374 -180.370997) (xy 376.548396 -180.329586) (xy 376.551978 -180.32)
			(xy 376.551968 -180.299553) (xy 376.548396 -180.289962) (xy 376.531349 -180.24856) (xy 376.504717 -180.16307)
			(xy 376.486816 -180.075335) (xy 376.477826 -179.986245) (xy 376.477276 -179.941474) (xy 376.477846 -179.896705)
			(xy 376.486854 -179.80762) (xy 376.504757 -179.719889) (xy 376.531374 -179.634397) (xy 376.548396 -179.592986)
			(xy 376.551978 -179.5834) (xy 376.551968 -179.562953) (xy 376.548396 -179.553362) (xy 376.531349 -179.51196)
			(xy 376.504717 -179.42647) (xy 376.486816 -179.338735) (xy 376.477826 -179.249645) (xy 376.477276 -179.204874)
			(xy 376.477674 -179.163758) (xy 376.485264 -179.081876) (xy 376.500376 -179.001043) (xy 376.522883 -178.92195)
			(xy 376.552591 -178.845272) (xy 376.589248 -178.771661) (xy 376.632541 -178.701747) (xy 376.682099 -178.636125)
			(xy 376.737501 -178.575356) (xy 376.798274 -178.519958) (xy 376.863899 -178.470404) (xy 376.933817 -178.427117)
			(xy 377.00743 -178.390466) (xy 377.084111 -178.360763) (xy 377.163206 -178.338262) (xy 377.244039 -178.323155)
			(xy 377.325922 -178.315571) (xy 377.367038 -178.315112) (xy 377.408648 -178.315619) (xy 377.491503 -178.323389)
			(xy 377.573272 -178.338859) (xy 377.65324 -178.361894) (xy 377.730709 -178.392291) (xy 377.805002 -178.429786)
			(xy 377.840494 -178.45151) (xy 377.849633 -178.45667) (xy 377.870349 -178.459885) (xy 377.890623 -178.454554)
			(xy 377.899168 -178.448462) (xy 377.932829 -178.422514) (xy 378.004217 -178.376384) (xy 378.079682 -178.337278)
			(xy 378.158534 -178.305551) (xy 378.240054 -178.281495) (xy 378.323498 -178.265328) (xy 378.408104 -178.257198)
			(xy 378.450602 -178.256692) (xy 378.491715 -178.257211) (xy 378.57359 -178.264798) (xy 378.654416 -178.279906)
			(xy 378.733503 -178.302408) (xy 378.810176 -178.33211) (xy 378.883782 -178.368761) (xy 378.953693 -178.412046)
			(xy 379.019312 -178.461597) (xy 379.080078 -178.51699) (xy 379.135475 -178.577755) (xy 379.185029 -178.643371)
			(xy 379.228318 -178.713279) (xy 379.264972 -178.786883) (xy 379.294678 -178.863555) (xy 379.317184 -178.942641)
			(xy 379.332296 -179.023466) (xy 379.339887 -179.105341) (xy 379.340364 -179.146454) (xy 379.339801 -179.191224)
			(xy 379.330791 -179.280309) (xy 379.312886 -179.36804) (xy 379.286267 -179.453531) (xy 379.269244 -179.494942)
			(xy 379.265706 -179.50454) (xy 379.265689 -179.524976) (xy 379.269244 -179.534566) (xy 379.286249 -179.575917)
			(xy 379.31286 -179.661279) (xy 379.330766 -179.748882) (xy 379.339788 -179.837839) (xy 379.340364 -179.882546)
			(xy 379.340364 -179.883562) (xy 379.34011 -179.894992) (xy 379.366589 -179.900938) (xy 379.418824 -179.915681)
			(xy 379.444504 -179.924456) (xy 379.452701 -179.92697) (xy 379.469835 -179.92697) (xy 379.478032 -179.924456)
			(xy 379.513248 -179.912493) (xy 379.585251 -179.893839) (xy 379.658572 -179.881331) (xy 379.732688 -179.875058)
			(xy 379.769878 -179.874672) (xy 379.807067 -179.875069) (xy 379.88118 -179.881356) (xy 379.9545 -179.893864)
			(xy 380.026506 -179.912502) (xy 380.061724 -179.924456) (xy 380.069921 -179.92697) (xy 380.087055 -179.92697)
			(xy 380.095252 -179.924456) (xy 380.130466 -179.912487) (xy 380.20247 -179.893835) (xy 380.275792 -179.881329)
			(xy 380.349908 -179.875057) (xy 380.387098 -179.874672) (xy 380.429038 -179.875067) (xy 380.512539 -179.88304)
			(xy 380.594904 -179.898915) (xy 380.675386 -179.922546) (xy 380.753258 -179.953722) (xy 380.827814 -179.992158)
			(xy 380.898379 -180.037507) (xy 380.964314 -180.089358) (xy 381.025021 -180.147242) (xy 381.079951 -180.210635)
			(xy 381.128607 -180.278962) (xy 381.170547 -180.351604) (xy 381.205392 -180.427905) (xy 381.232827 -180.507172)
			(xy 381.252602 -180.588688) (xy 381.26454 -180.671715) (xy 381.264843 -180.678074) (xy 384.808476 -180.678074)
			(xy 384.809046 -180.633305) (xy 384.818054 -180.54422) (xy 384.835957 -180.456489) (xy 384.862574 -180.370997)
			(xy 384.879596 -180.329586) (xy 384.883178 -180.32) (xy 384.883168 -180.299553) (xy 384.879596 -180.289962)
			(xy 384.862549 -180.24856) (xy 384.835917 -180.16307) (xy 384.818016 -180.075335) (xy 384.809026 -179.986245)
			(xy 384.808476 -179.941474) (xy 384.809046 -179.896705) (xy 384.818054 -179.80762) (xy 384.835957 -179.719889)
			(xy 384.862574 -179.634397) (xy 384.879596 -179.592986) (xy 384.883178 -179.5834) (xy 384.883168 -179.562953)
			(xy 384.879596 -179.553362) (xy 384.862549 -179.51196) (xy 384.835917 -179.42647) (xy 384.818016 -179.338735)
			(xy 384.809026 -179.249645) (xy 384.808476 -179.204874) (xy 384.808874 -179.163758) (xy 384.816464 -179.081876)
			(xy 384.831576 -179.001043) (xy 384.854083 -178.92195) (xy 384.883791 -178.845272) (xy 384.920448 -178.771661)
			(xy 384.963741 -178.701747) (xy 385.013299 -178.636125) (xy 385.068701 -178.575356) (xy 385.129474 -178.519958)
			(xy 385.195099 -178.470404) (xy 385.265017 -178.427117) (xy 385.33863 -178.390466) (xy 385.415311 -178.360763)
			(xy 385.494406 -178.338262) (xy 385.575239 -178.323155) (xy 385.657122 -178.315571) (xy 385.698238 -178.315112)
			(xy 385.739848 -178.315619) (xy 385.822703 -178.323389) (xy 385.904472 -178.338859) (xy 385.98444 -178.361894)
			(xy 386.061909 -178.392291) (xy 386.136202 -178.429786) (xy 386.171694 -178.45151) (xy 386.180833 -178.45667)
			(xy 386.201549 -178.459885) (xy 386.221823 -178.454554) (xy 386.230368 -178.448462) (xy 386.264029 -178.422514)
			(xy 386.335417 -178.376384) (xy 386.410882 -178.337278) (xy 386.489734 -178.305551) (xy 386.571254 -178.281495)
			(xy 386.654698 -178.265328) (xy 386.739304 -178.257198) (xy 386.781802 -178.256692) (xy 386.822915 -178.257211)
			(xy 386.90479 -178.264798) (xy 386.985616 -178.279906) (xy 387.064703 -178.302408) (xy 387.141376 -178.33211)
			(xy 387.214982 -178.368761) (xy 387.284893 -178.412046) (xy 387.350512 -178.461597) (xy 387.411278 -178.51699)
			(xy 387.466675 -178.577755) (xy 387.516229 -178.643371) (xy 387.559518 -178.713279) (xy 387.596172 -178.786883)
			(xy 387.625878 -178.863555) (xy 387.648384 -178.942641) (xy 387.663496 -179.023466) (xy 387.671087 -179.105341)
			(xy 387.671564 -179.146454) (xy 387.671001 -179.191224) (xy 387.661991 -179.280309) (xy 387.644086 -179.36804)
			(xy 387.617467 -179.453531) (xy 387.600444 -179.494942) (xy 387.596906 -179.50454) (xy 387.596889 -179.524976)
			(xy 387.600444 -179.534566) (xy 387.617449 -179.575917) (xy 387.64406 -179.661279) (xy 387.661966 -179.748882)
			(xy 387.670988 -179.837839) (xy 387.671564 -179.882546) (xy 387.671564 -179.883562) (xy 387.67131 -179.894992)
			(xy 387.697789 -179.900938) (xy 387.750024 -179.915681) (xy 387.775704 -179.924456) (xy 387.783901 -179.92697)
			(xy 387.801035 -179.92697) (xy 387.809232 -179.924456) (xy 387.844448 -179.912493) (xy 387.916451 -179.893839)
			(xy 387.989772 -179.881331) (xy 388.063888 -179.875058) (xy 388.101078 -179.874672) (xy 388.138267 -179.875069)
			(xy 388.21238 -179.881356) (xy 388.2857 -179.893864) (xy 388.357706 -179.912502) (xy 388.392924 -179.924456)
			(xy 388.401121 -179.92697) (xy 388.418255 -179.92697) (xy 388.426452 -179.924456) (xy 388.461666 -179.912487)
			(xy 388.53367 -179.893835) (xy 388.606992 -179.881329) (xy 388.681108 -179.875057) (xy 388.718298 -179.874672)
			(xy 388.760238 -179.875067) (xy 388.843739 -179.88304) (xy 388.926104 -179.898915) (xy 389.006586 -179.922546)
			(xy 389.084458 -179.953722) (xy 389.159014 -179.992158) (xy 389.229579 -180.037507) (xy 389.295514 -180.089358)
			(xy 389.356221 -180.147242) (xy 389.411151 -180.210635) (xy 389.459807 -180.278962) (xy 389.501747 -180.351604)
			(xy 389.536592 -180.427905) (xy 389.564027 -180.507172) (xy 389.583802 -180.588688) (xy 389.59574 -180.671715)
			(xy 389.599731 -180.7555) (xy 389.59574 -180.839285) (xy 389.583802 -180.922312) (xy 389.564027 -181.003828)
			(xy 389.536592 -181.083095) (xy 389.501747 -181.159396) (xy 389.459807 -181.232038) (xy 389.411151 -181.300365)
			(xy 389.356221 -181.363758) (xy 389.295514 -181.421642) (xy 389.229579 -181.473493) (xy 389.159014 -181.518842)
			(xy 389.084458 -181.557278) (xy 389.006586 -181.588454) (xy 388.926104 -181.612085) (xy 388.843739 -181.62796)
			(xy 388.760238 -181.635933) (xy 388.718298 -181.636416) (xy 388.681108 -181.636027) (xy 388.606996 -181.629737)
			(xy 388.533676 -181.617227) (xy 388.46167 -181.598587) (xy 388.426452 -181.586632) (xy 388.418255 -181.584118)
			(xy 388.401121 -181.584118) (xy 388.392924 -181.586632) (xy 388.365208 -181.596078) (xy 388.308773 -181.611711)
			(xy 388.280148 -181.617874) (xy 388.270401 -181.620348) (xy 388.25379 -181.63165) (xy 388.242792 -181.648464)
			(xy 388.240524 -181.65826) (xy 388.231054 -181.705587) (xy 388.203179 -181.797995) (xy 388.184898 -181.842664)
			(xy 388.181281 -181.852235) (xy 388.18114 -181.872676) (xy 388.184644 -181.882288) (xy 388.201684 -181.923659)
			(xy 388.228298 -182.009088) (xy 388.246197 -182.096758) (xy 388.255201 -182.185783) (xy 388.255764 -182.230522)
			(xy 388.255764 -182.230776) (xy 388.25526 -182.273124) (xy 388.247209 -182.357438) (xy 388.23118 -182.440604)
			(xy 388.207319 -182.521871) (xy 388.17584 -182.600501) (xy 388.137029 -182.675782) (xy 388.091239 -182.747034)
			(xy 388.038883 -182.81361) (xy 387.980435 -182.874908) (xy 387.916425 -182.930373) (xy 387.847433 -182.979502)
			(xy 387.774083 -183.021851) (xy 387.69704 -183.057035) (xy 387.617001 -183.084737) (xy 387.534692 -183.104705)
			(xy 387.450857 -183.116758) (xy 387.366256 -183.120789) (xy 387.281655 -183.116758) (xy 387.19782 -183.104705)
			(xy 387.115511 -183.084737) (xy 387.035472 -183.057035) (xy 386.958429 -183.021851) (xy 386.885079 -182.979502)
			(xy 386.816087 -182.930373) (xy 386.752077 -182.874908) (xy 386.693629 -182.81361) (xy 386.641273 -182.747034)
			(xy 386.595483 -182.675782) (xy 386.556672 -182.600501) (xy 386.525193 -182.521871) (xy 386.501332 -182.440604)
			(xy 386.485303 -182.357438) (xy 386.477252 -182.273124) (xy 386.476748 -182.230776) (xy 386.476748 -182.230522)
			(xy 386.477311 -182.185784) (xy 386.486329 -182.096762) (xy 386.504235 -182.009095) (xy 386.53085 -181.923667)
			(xy 386.547868 -181.882288) (xy 386.551445 -181.872701) (xy 386.551436 -181.852255) (xy 386.547868 -181.842664)
			(xy 386.53084 -181.801254) (xy 386.504206 -181.715766) (xy 386.4863 -181.628034) (xy 386.477302 -181.538946)
			(xy 386.476748 -181.494176) (xy 386.476748 -181.493668) (xy 386.47711 -181.457839) (xy 386.482902 -181.386415)
			(xy 386.49442 -181.315688) (xy 386.502656 -181.280816) (xy 386.504356 -181.272508) (xy 386.502799 -181.255633)
			(xy 386.495808 -181.240195) (xy 386.49021 -181.233826) (xy 386.44957 -181.1909) (xy 386.43941 -181.193186)
			(xy 386.430637 -181.195432) (xy 386.415405 -181.205208) (xy 386.409692 -181.212236) (xy 386.384552 -181.244927)
			(xy 386.329156 -181.306026) (xy 386.268343 -181.361734) (xy 386.202634 -181.411575) (xy 386.132593 -181.455119)
			(xy 386.058822 -181.491993) (xy 385.981955 -181.521881) (xy 385.902652 -181.544524) (xy 385.821593 -181.55973)
			(xy 385.739474 -181.567368) (xy 385.698238 -181.567836) (xy 385.657123 -181.567365) (xy 385.575243 -181.559781)
			(xy 385.494413 -181.544674) (xy 385.415321 -181.522173) (xy 385.338643 -181.49247) (xy 385.265033 -181.455819)
			(xy 385.195119 -181.412532) (xy 385.129497 -181.362978) (xy 385.068728 -181.30758) (xy 385.01333 -181.246812)
			(xy 384.963775 -181.181191) (xy 384.920487 -181.111277) (xy 384.883834 -181.037668) (xy 384.854131 -180.96099)
			(xy 384.831629 -180.881899) (xy 384.81652 -180.801068) (xy 384.808935 -180.719189) (xy 384.808476 -180.678074)
			(xy 381.264843 -180.678074) (xy 381.268531 -180.7555) (xy 381.26454 -180.839285) (xy 381.252602 -180.922312)
			(xy 381.232827 -181.003828) (xy 381.205392 -181.083095) (xy 381.170547 -181.159396) (xy 381.128607 -181.232038)
			(xy 381.079951 -181.300365) (xy 381.025021 -181.363758) (xy 380.964314 -181.421642) (xy 380.898379 -181.473493)
			(xy 380.827814 -181.518842) (xy 380.753258 -181.557278) (xy 380.675386 -181.588454) (xy 380.594904 -181.612085)
			(xy 380.512539 -181.62796) (xy 380.429038 -181.635933) (xy 380.387098 -181.636416) (xy 380.349908 -181.636027)
			(xy 380.275796 -181.629737) (xy 380.202476 -181.617227) (xy 380.13047 -181.598587) (xy 380.095252 -181.586632)
			(xy 380.087055 -181.584118) (xy 380.069921 -181.584118) (xy 380.061724 -181.586632) (xy 380.034008 -181.596078)
			(xy 379.977573 -181.611711) (xy 379.948948 -181.617874) (xy 379.939201 -181.620348) (xy 379.92259 -181.63165)
			(xy 379.911592 -181.648464) (xy 379.909324 -181.65826) (xy 379.899854 -181.705587) (xy 379.871979 -181.797995)
			(xy 379.853698 -181.842664) (xy 379.850081 -181.852235) (xy 379.84994 -181.872676) (xy 379.853444 -181.882288)
			(xy 379.870484 -181.923659) (xy 379.897098 -182.009088) (xy 379.914997 -182.096758) (xy 379.924001 -182.185783)
			(xy 379.924564 -182.230522) (xy 379.924564 -182.230776) (xy 379.92406 -182.273124) (xy 379.916009 -182.357438)
			(xy 379.89998 -182.440604) (xy 379.876119 -182.521871) (xy 379.84464 -182.600501) (xy 379.805829 -182.675782)
			(xy 379.760039 -182.747034) (xy 379.707683 -182.81361) (xy 379.649235 -182.874908) (xy 379.585225 -182.930373)
			(xy 379.516233 -182.979502) (xy 379.442883 -183.021851) (xy 379.36584 -183.057035) (xy 379.285801 -183.084737)
			(xy 379.203492 -183.104705) (xy 379.119657 -183.116758) (xy 379.035056 -183.120789) (xy 378.950455 -183.116758)
			(xy 378.86662 -183.104705) (xy 378.784311 -183.084737) (xy 378.704272 -183.057035) (xy 378.627229 -183.021851)
			(xy 378.553879 -182.979502) (xy 378.484887 -182.930373) (xy 378.420877 -182.874908) (xy 378.362429 -182.81361)
			(xy 378.310073 -182.747034) (xy 378.264283 -182.675782) (xy 378.225472 -182.600501) (xy 378.193993 -182.521871)
			(xy 378.170132 -182.440604) (xy 378.154103 -182.357438) (xy 378.146052 -182.273124) (xy 378.145548 -182.230776)
			(xy 378.145548 -182.230522) (xy 378.146111 -182.185784) (xy 378.155129 -182.096762) (xy 378.173035 -182.009095)
			(xy 378.19965 -181.923667) (xy 378.216668 -181.882288) (xy 378.220245 -181.872701) (xy 378.220236 -181.852255)
			(xy 378.216668 -181.842664) (xy 378.19964 -181.801254) (xy 378.173006 -181.715766) (xy 378.1551 -181.628034)
			(xy 378.146102 -181.538946) (xy 378.145548 -181.494176) (xy 378.145548 -181.493668) (xy 378.14591 -181.457839)
			(xy 378.151702 -181.386415) (xy 378.16322 -181.315688) (xy 378.171456 -181.280816) (xy 378.173156 -181.272508)
			(xy 378.171599 -181.255633) (xy 378.164608 -181.240195) (xy 378.15901 -181.233826) (xy 378.11837 -181.1909)
			(xy 378.10821 -181.193186) (xy 378.099437 -181.195432) (xy 378.084205 -181.205208) (xy 378.078492 -181.212236)
			(xy 378.053352 -181.244927) (xy 377.997956 -181.306026) (xy 377.937143 -181.361734) (xy 377.871434 -181.411575)
			(xy 377.801393 -181.455119) (xy 377.727622 -181.491993) (xy 377.650755 -181.521881) (xy 377.571452 -181.544524)
			(xy 377.490393 -181.55973) (xy 377.408274 -181.567368) (xy 377.367038 -181.567836) (xy 377.325923 -181.567365)
			(xy 377.244043 -181.559781) (xy 377.163213 -181.544674) (xy 377.084121 -181.522173) (xy 377.007443 -181.49247)
			(xy 376.933833 -181.455819) (xy 376.863919 -181.412532) (xy 376.798297 -181.362978) (xy 376.737528 -181.30758)
			(xy 376.68213 -181.246812) (xy 376.632575 -181.181191) (xy 376.589287 -181.111277) (xy 376.552634 -181.037668)
			(xy 376.522931 -180.96099) (xy 376.500429 -180.881899) (xy 376.48532 -180.801068) (xy 376.477735 -180.719189)
			(xy 376.477276 -180.678074) (xy 372.848069 -180.678074) (xy 372.8541 -180.720015) (xy 372.858091 -180.8038)
			(xy 372.8541 -180.887585) (xy 372.842162 -180.97061) (xy 372.822386 -181.052125) (xy 372.794951 -181.131391)
			(xy 372.760105 -181.20769) (xy 372.718163 -181.280331) (xy 372.669507 -181.348656) (xy 372.614576 -181.412047)
			(xy 372.553868 -181.469929) (xy 372.487932 -181.521778) (xy 372.417367 -181.567124) (xy 372.34281 -181.605557)
			(xy 372.264938 -181.636728) (xy 372.184455 -181.660356) (xy 372.10209 -181.676226) (xy 372.01859 -181.684195)
			(xy 371.97665 -181.684676) (xy 371.939461 -181.684274) (xy 371.865348 -181.677988) (xy 371.792028 -181.665482)
			(xy 371.720022 -181.646845) (xy 371.684804 -181.634892) (xy 371.676607 -181.632378) (xy 371.659473 -181.632378)
			(xy 371.651276 -181.634892) (xy 371.611916 -181.648156) (xy 371.531285 -181.66812) (xy 371.449135 -181.680416)
			(xy 371.40769 -181.683152) (xy 371.397889 -181.684131) (xy 371.380113 -181.692579) (xy 371.36683 -181.707102)
			(xy 371.362986 -181.716172) (xy 371.348 -181.753764) (xy 371.344428 -181.763418) (xy 371.344429 -181.783987)
			(xy 371.348 -181.793642) (xy 371.365038 -181.835014) (xy 371.391656 -181.920442) (xy 371.409557 -182.008112)
			(xy 371.418559 -182.097137) (xy 371.41912 -182.141876) (xy 371.418616 -182.184237) (xy 371.410563 -182.268574)
			(xy 371.394529 -182.351764) (xy 371.370661 -182.433054) (xy 371.339173 -182.511706) (xy 371.300351 -182.587009)
			(xy 371.254548 -182.658281) (xy 371.202177 -182.724877) (xy 371.143712 -182.786192) (xy 371.079684 -182.841673)
			(xy 371.010672 -182.890816) (xy 370.937302 -182.933176) (xy 370.860237 -182.968371) (xy 370.780175 -182.99608)
			(xy 370.697842 -183.016054) (xy 370.613983 -183.028111) (xy 370.529358 -183.032143) (xy 370.444733 -183.028111)
			(xy 370.360874 -183.016054) (xy 370.278541 -182.99608) (xy 370.198479 -182.968371) (xy 370.121414 -182.933176)
			(xy 370.048044 -182.890816) (xy 369.979032 -182.841673) (xy 369.915004 -182.786192) (xy 369.856539 -182.724877)
			(xy 369.804168 -182.658281) (xy 369.758365 -182.587009) (xy 369.719543 -182.511706) (xy 369.688055 -182.433054)
			(xy 369.664187 -182.351764) (xy 369.648153 -182.268574) (xy 369.6401 -182.184237) (xy 369.639596 -182.141876)
			(xy 369.640165 -182.097107) (xy 369.649173 -182.008022) (xy 369.667076 -181.92029) (xy 369.693694 -181.834799)
			(xy 369.710716 -181.793388) (xy 369.714296 -181.783802) (xy 369.714287 -181.763355) (xy 369.710716 -181.753764)
			(xy 369.693665 -181.712364) (xy 369.667035 -181.626872) (xy 369.649135 -181.539137) (xy 369.640146 -181.450047)
			(xy 369.639596 -181.405276) (xy 369.639771 -181.384669) (xy 369.641804 -181.343504) (xy 369.64366 -181.32298)
			(xy 369.644023 -181.312283) (xy 369.63707 -181.292069) (xy 369.630198 -181.283864) (xy 369.57127 -181.22011)
			(xy 369.551204 -181.211728) (xy 369.540282 -181.211982) (xy 369.523264 -181.212236) (xy 369.522756 -181.212236)
			(xy 369.481649 -181.211766) (xy 369.399787 -181.204159) (xy 369.318976 -181.189032) (xy 369.239905 -181.166515)
			(xy 369.163248 -181.136799) (xy 369.08966 -181.100138) (xy 369.019768 -181.056844) (xy 368.954168 -181.007287)
			(xy 368.893419 -180.95189) (xy 368.83804 -180.891125) (xy 368.788503 -180.825509) (xy 368.745231 -180.755604)
			(xy 368.708592 -180.682005) (xy 368.678899 -180.605339) (xy 368.656406 -180.526261) (xy 368.641304 -180.445446)
			(xy 368.633721 -180.363581) (xy 368.633248 -180.322474) (xy 368.6337 -180.283493) (xy 368.640575 -180.205835)
			(xy 368.654226 -180.129077) (xy 368.663982 -180.091334) (xy 368.666037 -180.082278) (xy 368.664208 -180.063813)
			(xy 368.655908 -180.047218) (xy 368.642231 -180.034679) (xy 368.633756 -180.030882) (xy 368.596114 -180.015301)
			(xy 368.523548 -179.97826) (xy 368.454673 -179.934739) (xy 368.390066 -179.885102) (xy 368.330268 -179.829767)
			(xy 368.27578 -179.769195) (xy 368.227059 -179.703896) (xy 368.184512 -179.634415) (xy 368.148496 -179.561335)
			(xy 368.119314 -179.485268) (xy 368.097208 -179.406851) (xy 368.082365 -179.326741) (xy 368.074909 -179.24561)
			(xy 368.074448 -179.204874) (xy 97.329275 -179.204874) (xy 97.326783 -179.229509) (xy 97.308877 -179.31724)
			(xy 97.282259 -179.402731) (xy 97.265236 -179.444142) (xy 97.261699 -179.453741) (xy 97.261682 -179.474176)
			(xy 97.265236 -179.483766) (xy 97.28224 -179.525117) (xy 97.308851 -179.610479) (xy 97.326758 -179.698082)
			(xy 97.33578 -179.787039) (xy 97.336356 -179.831746) (xy 97.336356 -179.832762) (xy 97.336102 -179.844192)
			(xy 97.362581 -179.850138) (xy 97.414816 -179.864881) (xy 97.440496 -179.873656) (xy 97.448693 -179.87617)
			(xy 97.465827 -179.87617) (xy 97.474024 -179.873656) (xy 97.50924 -179.861695) (xy 97.581244 -179.843041)
			(xy 97.654565 -179.830532) (xy 97.72868 -179.824259) (xy 97.76587 -179.823872) (xy 97.803059 -179.824271)
			(xy 97.877172 -179.830558) (xy 97.950492 -179.843065) (xy 98.022498 -179.861703) (xy 98.057716 -179.873656)
			(xy 98.065913 -179.87617) (xy 98.083047 -179.87617) (xy 98.091244 -179.873656) (xy 98.126459 -179.861689)
			(xy 98.198462 -179.843037) (xy 98.271784 -179.83053) (xy 98.3459 -179.824258) (xy 98.38309 -179.823872)
			(xy 98.42503 -179.824267) (xy 98.508532 -179.832239) (xy 98.590897 -179.848113) (xy 98.67138 -179.871744)
			(xy 98.749253 -179.902919) (xy 98.82381 -179.941355) (xy 98.894375 -179.986704) (xy 98.96031 -180.038555)
			(xy 99.021018 -180.096439) (xy 99.075949 -180.159832) (xy 99.124605 -180.228159) (xy 99.166546 -180.300802)
			(xy 99.201391 -180.377103) (xy 99.228826 -180.45637) (xy 99.248602 -180.537887) (xy 99.26054 -180.620914)
			(xy 99.264531 -180.7047) (xy 99.26054 -180.788486) (xy 99.248602 -180.871513) (xy 99.228826 -180.95303)
			(xy 99.201391 -181.032297) (xy 99.166546 -181.108598) (xy 99.124605 -181.181241) (xy 99.075949 -181.249568)
			(xy 99.021018 -181.312961) (xy 98.96031 -181.370845) (xy 98.894375 -181.422696) (xy 98.82381 -181.468045)
			(xy 98.749253 -181.506481) (xy 98.67138 -181.537656) (xy 98.590897 -181.561287) (xy 98.508532 -181.577161)
			(xy 98.42503 -181.585133) (xy 98.38309 -181.585616) (xy 98.3459 -181.585229) (xy 98.271787 -181.578939)
			(xy 98.198468 -181.566428) (xy 98.126462 -181.547787) (xy 98.091244 -181.535832) (xy 98.083047 -181.533318)
			(xy 98.065913 -181.533318) (xy 98.057716 -181.535832) (xy 98.015534 -181.549982) (xy 97.929009 -181.570726)
			(xy 97.884996 -181.577234) (xy 97.875031 -181.57898) (xy 97.85759 -181.589205) (xy 97.845466 -181.605383)
			(xy 97.842578 -181.61508) (xy 97.833805 -181.648299) (xy 97.811813 -181.713397) (xy 97.798636 -181.745128)
			(xy 97.79505 -181.754712) (xy 97.795064 -181.775161) (xy 97.798636 -181.784752) (xy 97.815664 -181.826127)
			(xy 97.842281 -181.911555) (xy 97.860184 -181.999224) (xy 97.869191 -182.088247) (xy 97.869756 -182.132986)
			(xy 97.869756 -182.13324) (xy 97.869252 -182.175588) (xy 97.861201 -182.259902) (xy 97.845172 -182.343068)
			(xy 97.821311 -182.424335) (xy 97.789832 -182.502965) (xy 97.751021 -182.578246) (xy 97.705231 -182.649498)
			(xy 97.652875 -182.716074) (xy 97.594427 -182.777372) (xy 97.530417 -182.832837) (xy 97.461425 -182.881966)
			(xy 97.388075 -182.924315) (xy 97.311032 -182.959499) (xy 97.230993 -182.987201) (xy 97.148684 -183.007169)
			(xy 97.064849 -183.019222) (xy 96.980248 -183.023253) (xy 96.895647 -183.019222) (xy 96.811812 -183.007169)
			(xy 96.729503 -182.987201) (xy 96.649464 -182.959499) (xy 96.572421 -182.924315) (xy 96.499071 -182.881966)
			(xy 96.430079 -182.832837) (xy 96.366069 -182.777372) (xy 96.307621 -182.716074) (xy 96.255265 -182.649498)
			(xy 96.209475 -182.578246) (xy 96.170664 -182.502965) (xy 96.139185 -182.424335) (xy 96.115324 -182.343068)
			(xy 96.099295 -182.259902) (xy 96.091244 -182.175588) (xy 96.09074 -182.13324) (xy 96.09074 -182.132986)
			(xy 96.091318 -182.088248) (xy 96.10033 -181.999226) (xy 96.118232 -181.911559) (xy 96.144843 -181.826131)
			(xy 96.16186 -181.784752) (xy 96.165401 -181.775154) (xy 96.165416 -181.754718) (xy 96.16186 -181.745128)
			(xy 96.144825 -181.703755) (xy 96.11821 -181.618327) (xy 96.100309 -181.530657) (xy 96.091304 -181.441633)
			(xy 96.09074 -181.396894) (xy 96.09074 -181.395878) (xy 96.090368 -181.38632) (xy 96.083332 -181.368547)
			(xy 96.070254 -181.354605) (xy 96.061784 -181.350158) (xy 95.965264 -181.304184) (xy 95.936308 -181.30774)
			(xy 95.924878 -181.317138) (xy 95.890853 -181.344159) (xy 95.818459 -181.392213) (xy 95.741724 -181.43298)
			(xy 95.66138 -181.466069) (xy 95.578192 -181.491168) (xy 95.492953 -181.508035) (xy 95.406476 -181.51651)
			(xy 95.36303 -181.517036) (xy 95.321915 -181.516573) (xy 95.240035 -181.508988) (xy 95.159204 -181.49388)
			(xy 95.080113 -181.471379) (xy 95.003435 -181.441675) (xy 94.929825 -181.405023) (xy 94.859911 -181.361735)
			(xy 94.794289 -181.312181) (xy 94.73352 -181.256783) (xy 94.678122 -181.196014) (xy 94.628567 -181.130393)
			(xy 94.585279 -181.060479) (xy 94.548626 -180.986869) (xy 94.518922 -180.910191) (xy 94.49642 -180.831099)
			(xy 94.481312 -180.750269) (xy 94.473727 -180.668389) (xy 94.473268 -180.627274) (xy 90.869375 -180.627274)
			(xy 90.872244 -180.6875) (xy 90.868253 -180.771275) (xy 90.856317 -180.854292) (xy 90.836544 -180.935798)
			(xy 90.809114 -181.015056) (xy 90.774274 -181.091347) (xy 90.732339 -181.163981) (xy 90.683691 -181.2323)
			(xy 90.628768 -181.295686) (xy 90.56807 -181.353564) (xy 90.502144 -181.405411) (xy 90.431589 -181.450756)
			(xy 90.357043 -181.489189) (xy 90.279182 -181.520363) (xy 90.198709 -181.543994) (xy 90.116355 -181.559869)
			(xy 90.032865 -181.567844) (xy 89.99093 -181.568344) (xy 89.953741 -181.567944) (xy 89.879628 -181.561657)
			(xy 89.806308 -181.54915) (xy 89.734302 -181.530513) (xy 89.699084 -181.51856) (xy 89.690887 -181.516046)
			(xy 89.673753 -181.516046) (xy 89.665556 -181.51856) (xy 89.630433 -181.5305) (xy 89.558617 -181.54912)
			(xy 89.485489 -181.561626) (xy 89.411567 -181.56793) (xy 89.374472 -181.568344) (xy 89.372948 -181.568344)
			(xy 89.365328 -181.56809) (xy 89.355809 -181.6135) (xy 89.328579 -181.702202) (xy 89.310972 -181.745128)
			(xy 89.307384 -181.754712) (xy 89.307399 -181.775161) (xy 89.310972 -181.784752) (xy 89.327996 -181.826163)
			(xy 89.354632 -181.91165) (xy 89.37254 -181.999382) (xy 89.381538 -182.08847) (xy 89.382092 -182.13324)
			(xy 89.381588 -182.175601) (xy 89.373535 -182.259938) (xy 89.357501 -182.343128) (xy 89.333633 -182.424418)
			(xy 89.302145 -182.50307) (xy 89.263323 -182.578373) (xy 89.21752 -182.649645) (xy 89.165149 -182.716241)
			(xy 89.106684 -182.777556) (xy 89.042656 -182.833037) (xy 88.973644 -182.88218) (xy 88.900274 -182.92454)
			(xy 88.823209 -182.959735) (xy 88.743147 -182.987444) (xy 88.660814 -183.007418) (xy 88.576955 -183.019475)
			(xy 88.49233 -183.023507) (xy 88.407705 -183.019475) (xy 88.323846 -183.007418) (xy 88.241513 -182.987444)
			(xy 88.161451 -182.959735) (xy 88.084386 -182.92454) (xy 88.011016 -182.88218) (xy 87.942004 -182.833037)
			(xy 87.877976 -182.777556) (xy 87.819511 -182.716241) (xy 87.76714 -182.649645) (xy 87.721337 -182.578373)
			(xy 87.682515 -182.50307) (xy 87.651027 -182.424418) (xy 87.627159 -182.343128) (xy 87.611125 -182.259938)
			(xy 87.603072 -182.175601) (xy 87.602568 -182.13324) (xy 87.603127 -182.08847) (xy 87.612138 -181.999385)
			(xy 87.630045 -181.911654) (xy 87.656665 -181.826163) (xy 87.673688 -181.784752) (xy 87.677232 -181.775155)
			(xy 87.677247 -181.754718) (xy 87.673688 -181.745128) (xy 87.65877 -181.708939) (xy 87.634581 -181.634489)
			(xy 87.617023 -181.558202) (xy 87.606232 -181.480668) (xy 87.603838 -181.441598) (xy 87.602983 -181.432757)
			(xy 87.596138 -181.416387) (xy 87.58411 -181.403342) (xy 87.576406 -181.398926) (xy 87.486236 -181.352444)
			(xy 87.459312 -181.35346) (xy 87.447882 -181.360826) (xy 87.412209 -181.38294) (xy 87.337447 -181.421096)
			(xy 87.259425 -181.452047) (xy 87.178837 -181.475518) (xy 87.096397 -181.4913) (xy 87.012838 -181.499253)
			(xy 86.97087 -181.499764) (xy 86.929755 -181.499316) (xy 86.847877 -181.491726) (xy 86.767048 -181.476614)
			(xy 86.687959 -181.454109) (xy 86.611283 -181.424402) (xy 86.537675 -181.387748) (xy 86.467763 -181.344458)
			(xy 86.402144 -181.294902) (xy 86.341376 -181.239504) (xy 86.28598 -181.178735) (xy 86.236426 -181.113114)
			(xy 86.193139 -181.043201) (xy 86.156487 -180.969592) (xy 86.126782 -180.892915) (xy 86.10428 -180.813824)
			(xy 86.08917 -180.732995) (xy 86.081583 -180.651117) (xy 86.081108 -180.610002) (xy 82.462267 -180.610002)
			(xy 82.47114 -180.671714) (xy 82.475131 -180.7555) (xy 82.47114 -180.839286) (xy 82.459202 -180.922313)
			(xy 82.439426 -181.00383) (xy 82.411991 -181.083097) (xy 82.377146 -181.159398) (xy 82.335205 -181.232041)
			(xy 82.286549 -181.300368) (xy 82.231618 -181.363761) (xy 82.17091 -181.421645) (xy 82.104975 -181.473496)
			(xy 82.03441 -181.518845) (xy 81.959853 -181.557281) (xy 81.88198 -181.588456) (xy 81.801497 -181.612087)
			(xy 81.719132 -181.627961) (xy 81.63563 -181.635933) (xy 81.59369 -181.636416) (xy 81.5565 -181.636029)
			(xy 81.482387 -181.629739) (xy 81.409068 -181.617228) (xy 81.337062 -181.598587) (xy 81.301844 -181.586632)
			(xy 81.293647 -181.584118) (xy 81.276513 -181.584118) (xy 81.268316 -181.586632) (xy 81.24011 -181.596266)
			(xy 81.182657 -181.612157) (xy 81.153508 -181.618382) (xy 81.143879 -181.620834) (xy 81.127394 -181.631892)
			(xy 81.116335 -181.648377) (xy 81.113884 -181.658006) (xy 81.104396 -181.702491) (xy 81.07755 -181.789404)
			(xy 81.06029 -181.831488) (xy 81.056659 -181.841055) (xy 81.056528 -181.861499) (xy 81.060036 -181.871112)
			(xy 81.077051 -181.912492) (xy 81.103672 -181.997918) (xy 81.121578 -182.085585) (xy 81.130589 -182.174608)
			(xy 81.131156 -182.219346) (xy 81.131156 -182.2196) (xy 81.130652 -182.261948) (xy 81.122601 -182.346262)
			(xy 81.106572 -182.429428) (xy 81.082711 -182.510695) (xy 81.051232 -182.589325) (xy 81.012421 -182.664606)
			(xy 80.966631 -182.735858) (xy 80.914275 -182.802434) (xy 80.855827 -182.863732) (xy 80.791817 -182.919197)
			(xy 80.722825 -182.968326) (xy 80.649475 -183.010675) (xy 80.572432 -183.045859) (xy 80.492393 -183.073561)
			(xy 80.410084 -183.093529) (xy 80.326249 -183.105582) (xy 80.241648 -183.109613) (xy 80.157047 -183.105582)
			(xy 80.073212 -183.093529) (xy 79.990903 -183.073561) (xy 79.910864 -183.045859) (xy 79.833821 -183.010675)
			(xy 79.760471 -182.968326) (xy 79.691479 -182.919197) (xy 79.627469 -182.863732) (xy 79.569021 -182.802434)
			(xy 79.516665 -182.735858) (xy 79.470875 -182.664606) (xy 79.432064 -182.589325) (xy 79.400585 -182.510695)
			(xy 79.376724 -182.429428) (xy 79.360695 -182.346262) (xy 79.352644 -182.261948) (xy 79.35214 -182.2196)
			(xy 79.35214 -182.219346) (xy 79.352704 -182.174608) (xy 79.361721 -182.085586) (xy 79.379627 -181.997918)
			(xy 79.406242 -181.912491) (xy 79.42326 -181.871112) (xy 79.426824 -181.861521) (xy 79.426824 -181.841079)
			(xy 79.42326 -181.831488) (xy 79.406239 -181.790076) (xy 79.379604 -181.704589) (xy 79.361695 -181.616857)
			(xy 79.352696 -181.52777) (xy 79.35214 -181.483) (xy 79.35214 -181.482746) (xy 79.352599 -181.44258)
			(xy 79.359845 -181.362574) (xy 79.366618 -181.32298) (xy 79.366618 -181.322726) (xy 79.368105 -181.310829)
			(xy 79.361202 -181.287898) (xy 79.35341 -181.278784) (xy 79.287878 -181.210204) (xy 79.265018 -181.202076)
			(xy 79.252826 -181.203854) (xy 79.222877 -181.207733) (xy 79.162627 -181.21193) (xy 79.13243 -181.212236)
			(xy 79.091315 -181.211773) (xy 79.009435 -181.204188) (xy 78.928604 -181.18908) (xy 78.849513 -181.166579)
			(xy 78.772835 -181.136875) (xy 78.699225 -181.100223) (xy 78.629311 -181.056935) (xy 78.563689 -181.007381)
			(xy 78.50292 -180.951983) (xy 78.447522 -180.891214) (xy 78.397967 -180.825593) (xy 78.354679 -180.755679)
			(xy 78.318026 -180.682069) (xy 78.288322 -180.605391) (xy 78.26582 -180.526299) (xy 78.250712 -180.445469)
			(xy 78.243127 -180.363589) (xy 78.242668 -180.322474) (xy 78.242668 -180.321966) (xy 78.243175 -180.279292)
			(xy 78.251378 -180.194339) (xy 78.267677 -180.110561) (xy 78.291921 -180.028728) (xy 78.307438 -179.988972)
			(xy 78.311043 -179.978929) (xy 78.310391 -179.957622) (xy 78.306168 -179.947824) (xy 78.289089 -179.911553)
			(xy 78.260784 -179.836541) (xy 78.239347 -179.759284) (xy 78.224953 -179.680411) (xy 78.217719 -179.600562)
			(xy 78.217268 -179.560474) (xy 78.21746 -179.533866) (xy 78.220637 -179.480744) (xy 78.223618 -179.454302)
			(xy 78.224368 -179.443055) (xy 78.217254 -179.421697) (xy 78.209902 -179.413154) (xy 78.180933 -179.382157)
			(xy 78.128411 -179.31552) (xy 78.082469 -179.244186) (xy 78.043525 -179.168805) (xy 78.011931 -179.090059)
			(xy 77.987974 -179.008663) (xy 77.971872 -178.925358) (xy 77.963772 -178.840898) (xy 77.963268 -178.798474)
			(xy 9.44304 -178.798474) (xy 9.441677 -178.801459) (xy 9.412211 -178.847309) (xy 9.37652 -178.8885)
			(xy 9.335329 -178.924191) (xy 9.289479 -178.953657) (xy 9.239902 -178.976299) (xy 9.187607 -178.991654)
			(xy 9.133659 -178.99941) (xy 9.079157 -178.99941) (xy 9.025209 -178.991654) (xy 8.972914 -178.976299)
			(xy 8.923337 -178.953657) (xy 8.877487 -178.924191) (xy 8.836296 -178.8885) (xy 8.800605 -178.847309)
			(xy 8.771139 -178.801459) (xy 8.748497 -178.751882) (xy 8.733142 -178.699587) (xy 8.725386 -178.645639)
			(xy 8.7249 -178.618388) (xy 2.509012 -178.618388) (xy 2.509012 -190.64715) (xy 220.414866 -190.64715)
			(xy 220.414866 -190.59265) (xy 220.422621 -190.538705) (xy 220.437974 -190.486413) (xy 220.460612 -190.436837)
			(xy 220.490075 -190.390988) (xy 220.525762 -190.349798) (xy 220.566948 -190.314105) (xy 220.612793 -190.284636)
			(xy 220.662366 -190.261992) (xy 220.714656 -190.246632) (xy 220.7686 -190.238869) (xy 220.79585 -190.23838)
			(xy 221.78645 -190.23838) (xy 221.813704 -190.238864) (xy 221.867659 -190.246615) (xy 221.919961 -190.261966)
			(xy 221.969546 -190.284605) (xy 222.015404 -190.314071) (xy 222.056601 -190.349763) (xy 222.092299 -190.390956)
			(xy 222.121771 -190.43681) (xy 222.144416 -190.486392) (xy 222.159775 -190.538692) (xy 222.167533 -190.592646)
			(xy 222.167533 -190.647154) (xy 222.159775 -190.701108) (xy 222.144416 -190.753408) (xy 222.121771 -190.80299)
			(xy 222.092299 -190.848844) (xy 222.056601 -190.890037) (xy 222.015404 -190.925729) (xy 221.969546 -190.955195)
			(xy 221.919961 -190.977834) (xy 221.867659 -190.993185) (xy 221.813704 -191.000936) (xy 221.78645 -191.001396)
			(xy 220.79585 -191.001396) (xy 220.7686 -191.000931) (xy 220.714656 -190.993168) (xy 220.662366 -190.977808)
			(xy 220.612793 -190.955164) (xy 220.566948 -190.925695) (xy 220.525762 -190.890002) (xy 220.490075 -190.848812)
			(xy 220.460612 -190.802963) (xy 220.437974 -190.753387) (xy 220.422621 -190.701095) (xy 220.414866 -190.64715)
			(xy 2.509012 -190.64715) (xy 2.509012 -194.296284) (xy 255.545336 -194.296284) (xy 255.545336 -193.432684)
			(xy 255.545822 -193.405415) (xy 255.553584 -193.351431) (xy 255.568949 -193.299101) (xy 255.591606 -193.249491)
			(xy 255.621092 -193.20361) (xy 255.656807 -193.162393) (xy 255.698024 -193.126678) (xy 255.743905 -193.097192)
			(xy 255.793515 -193.074535) (xy 255.845845 -193.05917) (xy 255.899829 -193.051408) (xy 255.954367 -193.051408)
			(xy 256.008351 -193.05917) (xy 256.060681 -193.074535) (xy 256.110291 -193.097192) (xy 256.156172 -193.126678)
			(xy 256.197389 -193.162393) (xy 256.233104 -193.20361) (xy 256.26259 -193.249491) (xy 256.285247 -193.299101)
			(xy 256.300612 -193.351431) (xy 256.308374 -193.405415) (xy 256.30886 -193.432684) (xy 256.30886 -194.296284)
			(xy 256.308374 -194.323553) (xy 256.300612 -194.377537) (xy 256.285247 -194.429867) (xy 256.26259 -194.479477)
			(xy 256.25414 -194.492626) (xy 260.09346 -194.492626) (xy 260.09346 -193.502026) (xy 260.093946 -193.474757)
			(xy 260.101708 -193.420773) (xy 260.117073 -193.368443) (xy 260.13973 -193.318833) (xy 260.169216 -193.272952)
			(xy 260.204931 -193.231735) (xy 260.246148 -193.19602) (xy 260.292029 -193.166534) (xy 260.341639 -193.143877)
			(xy 260.393969 -193.128512) (xy 260.447953 -193.12075) (xy 260.502491 -193.12075) (xy 260.556475 -193.128512)
			(xy 260.608805 -193.143877) (xy 260.658415 -193.166534) (xy 260.704296 -193.19602) (xy 260.745513 -193.231735)
			(xy 260.781228 -193.272952) (xy 260.810714 -193.318833) (xy 260.833371 -193.368443) (xy 260.848736 -193.420773)
			(xy 260.856498 -193.474757) (xy 260.856984 -193.502026) (xy 260.856984 -194.492626) (xy 260.856498 -194.519895)
			(xy 260.848736 -194.573879) (xy 260.833371 -194.626209) (xy 260.810714 -194.675819) (xy 260.781228 -194.7217)
			(xy 260.745513 -194.762917) (xy 260.704296 -194.798632) (xy 260.658415 -194.828118) (xy 260.608805 -194.850775)
			(xy 260.556475 -194.86614) (xy 260.502491 -194.873902) (xy 260.447953 -194.873902) (xy 260.393969 -194.86614)
			(xy 260.341639 -194.850775) (xy 260.292029 -194.828118) (xy 260.246148 -194.798632) (xy 260.204931 -194.762917)
			(xy 260.169216 -194.7217) (xy 260.13973 -194.675819) (xy 260.117073 -194.626209) (xy 260.101708 -194.573879)
			(xy 260.093946 -194.519895) (xy 260.09346 -194.492626) (xy 256.25414 -194.492626) (xy 256.233104 -194.525358)
			(xy 256.197389 -194.566575) (xy 256.156172 -194.60229) (xy 256.110291 -194.631776) (xy 256.060681 -194.654433)
			(xy 256.008351 -194.669798) (xy 255.954367 -194.67756) (xy 255.899829 -194.67756) (xy 255.845845 -194.669798)
			(xy 255.793515 -194.654433) (xy 255.743905 -194.631776) (xy 255.698024 -194.60229) (xy 255.656807 -194.566575)
			(xy 255.621092 -194.525358) (xy 255.591606 -194.479477) (xy 255.568949 -194.429867) (xy 255.553584 -194.377537)
			(xy 255.545822 -194.323553) (xy 255.545336 -194.296284) (xy 2.509012 -194.296284) (xy 2.509012 -197.07352)
			(xy 255.545336 -197.07352) (xy 255.545336 -196.20992) (xy 255.545822 -196.182651) (xy 255.553584 -196.128667)
			(xy 255.568949 -196.076337) (xy 255.591606 -196.026727) (xy 255.621092 -195.980846) (xy 255.656807 -195.939629)
			(xy 255.698024 -195.903914) (xy 255.743905 -195.874428) (xy 255.793515 -195.851771) (xy 255.845845 -195.836406)
			(xy 255.899829 -195.828644) (xy 255.954367 -195.828644) (xy 256.008351 -195.836406) (xy 256.060681 -195.851771)
			(xy 256.110291 -195.874428) (xy 256.156172 -195.903914) (xy 256.197389 -195.939629) (xy 256.233104 -195.980846)
			(xy 256.26259 -196.026727) (xy 256.285247 -196.076337) (xy 256.300612 -196.128667) (xy 256.308374 -196.182651)
			(xy 256.30886 -196.20992) (xy 256.30886 -197.07352) (xy 256.308374 -197.100789) (xy 256.300612 -197.154773)
			(xy 256.285247 -197.207103) (xy 256.26259 -197.256713) (xy 256.233104 -197.302594) (xy 256.197389 -197.343811)
			(xy 256.156172 -197.379526) (xy 256.110291 -197.409012) (xy 256.060681 -197.431669) (xy 256.008351 -197.447034)
			(xy 255.954367 -197.454796) (xy 255.899829 -197.454796) (xy 255.845845 -197.447034) (xy 255.793515 -197.431669)
			(xy 255.743905 -197.409012) (xy 255.698024 -197.379526) (xy 255.656807 -197.343811) (xy 255.621092 -197.302594)
			(xy 255.591606 -197.256713) (xy 255.568949 -197.207103) (xy 255.553584 -197.154773) (xy 255.545822 -197.100789)
			(xy 255.545336 -197.07352) (xy 2.509012 -197.07352) (xy 2.509012 -199.868028) (xy 255.545336 -199.868028)
			(xy 255.545336 -199.004428) (xy 255.545822 -198.977159) (xy 255.553584 -198.923175) (xy 255.568949 -198.870845)
			(xy 255.591606 -198.821235) (xy 255.621092 -198.775354) (xy 255.656807 -198.734137) (xy 255.698024 -198.698422)
			(xy 255.743905 -198.668936) (xy 255.793515 -198.646279) (xy 255.845845 -198.630914) (xy 255.899829 -198.623152)
			(xy 255.954367 -198.623152) (xy 256.008351 -198.630914) (xy 256.060681 -198.646279) (xy 256.110291 -198.668936)
			(xy 256.156172 -198.698422) (xy 256.197389 -198.734137) (xy 256.233104 -198.775354) (xy 256.26259 -198.821235)
			(xy 256.285247 -198.870845) (xy 256.300612 -198.923175) (xy 256.308374 -198.977159) (xy 256.30886 -199.004428)
			(xy 256.30886 -199.868028) (xy 256.308374 -199.895297) (xy 256.300612 -199.949281) (xy 256.285247 -200.001611)
			(xy 256.26259 -200.051221) (xy 256.233104 -200.097102) (xy 256.197389 -200.138319) (xy 256.156172 -200.174034)
			(xy 256.110291 -200.20352) (xy 256.060681 -200.226177) (xy 256.008351 -200.241542) (xy 255.954367 -200.249304)
			(xy 255.899829 -200.249304) (xy 255.845845 -200.241542) (xy 255.793515 -200.226177) (xy 255.743905 -200.20352)
			(xy 255.698024 -200.174034) (xy 255.656807 -200.138319) (xy 255.621092 -200.097102) (xy 255.591606 -200.051221)
			(xy 255.568949 -200.001611) (xy 255.553584 -199.949281) (xy 255.545822 -199.895297) (xy 255.545336 -199.868028)
			(xy 2.509012 -199.868028) (xy 2.509012 -202.662536) (xy 255.545336 -202.662536) (xy 255.545336 -201.798936)
			(xy 255.545822 -201.771667) (xy 255.553584 -201.717683) (xy 255.568949 -201.665353) (xy 255.591606 -201.615743)
			(xy 255.621092 -201.569862) (xy 255.656807 -201.528645) (xy 255.698024 -201.49293) (xy 255.743905 -201.463444)
			(xy 255.793515 -201.440787) (xy 255.845845 -201.425422) (xy 255.899829 -201.41766) (xy 255.954367 -201.41766)
			(xy 256.008351 -201.425422) (xy 256.060681 -201.440787) (xy 256.110291 -201.463444) (xy 256.156172 -201.49293)
			(xy 256.197389 -201.528645) (xy 256.233104 -201.569862) (xy 256.26259 -201.615743) (xy 256.285247 -201.665353)
			(xy 256.300612 -201.717683) (xy 256.308374 -201.771667) (xy 256.30886 -201.798936) (xy 256.30886 -202.662536)
			(xy 256.308374 -202.689805) (xy 256.300612 -202.743789) (xy 256.285247 -202.796119) (xy 256.26259 -202.845729)
			(xy 256.233104 -202.89161) (xy 256.197389 -202.932827) (xy 256.156172 -202.968542) (xy 256.110291 -202.998028)
			(xy 256.060681 -203.020685) (xy 256.008351 -203.03605) (xy 255.954367 -203.043812) (xy 255.899829 -203.043812)
			(xy 255.845845 -203.03605) (xy 255.793515 -203.020685) (xy 255.743905 -202.998028) (xy 255.698024 -202.968542)
			(xy 255.656807 -202.932827) (xy 255.621092 -202.89161) (xy 255.591606 -202.845729) (xy 255.568949 -202.796119)
			(xy 255.553584 -202.743789) (xy 255.545822 -202.689805) (xy 255.545336 -202.662536) (xy 2.509012 -202.662536)
			(xy 2.509012 -205.439772) (xy 255.545336 -205.439772) (xy 255.545336 -204.576172) (xy 255.545822 -204.548903)
			(xy 255.553584 -204.494919) (xy 255.568949 -204.442589) (xy 255.591606 -204.392979) (xy 255.621092 -204.347098)
			(xy 255.656807 -204.305881) (xy 255.698024 -204.270166) (xy 255.743905 -204.24068) (xy 255.793515 -204.218023)
			(xy 255.845845 -204.202658) (xy 255.899829 -204.194896) (xy 255.954367 -204.194896) (xy 256.008351 -204.202658)
			(xy 256.060681 -204.218023) (xy 256.110291 -204.24068) (xy 256.156172 -204.270166) (xy 256.197389 -204.305881)
			(xy 256.233104 -204.347098) (xy 256.26259 -204.392979) (xy 256.285247 -204.442589) (xy 256.300612 -204.494919)
			(xy 256.308374 -204.548903) (xy 256.30886 -204.576172) (xy 256.30886 -205.439772) (xy 256.308374 -205.467041)
			(xy 256.300612 -205.521025) (xy 256.285247 -205.573355) (xy 256.26259 -205.622965) (xy 256.233104 -205.668846)
			(xy 256.197389 -205.710063) (xy 256.156172 -205.745778) (xy 256.110291 -205.775264) (xy 256.060681 -205.797921)
			(xy 256.008351 -205.813286) (xy 255.954367 -205.821048) (xy 255.899829 -205.821048) (xy 255.845845 -205.813286)
			(xy 255.793515 -205.797921) (xy 255.743905 -205.775264) (xy 255.698024 -205.745778) (xy 255.656807 -205.710063)
			(xy 255.621092 -205.668846) (xy 255.591606 -205.622965) (xy 255.568949 -205.573355) (xy 255.553584 -205.521025)
			(xy 255.545822 -205.467041) (xy 255.545336 -205.439772) (xy 2.509012 -205.439772) (xy 2.509012 -207.499458)
			(xy 97.408492 -207.499458) (xy 97.408492 -206.635858) (xy 97.408978 -206.608589) (xy 97.41674 -206.554605)
			(xy 97.432105 -206.502275) (xy 97.454762 -206.452665) (xy 97.484248 -206.406784) (xy 97.519963 -206.365567)
			(xy 97.56118 -206.329852) (xy 97.607061 -206.300366) (xy 97.656671 -206.277709) (xy 97.709001 -206.262344)
			(xy 97.762985 -206.254582) (xy 97.817523 -206.254582) (xy 97.871507 -206.262344) (xy 97.923837 -206.277709)
			(xy 97.973447 -206.300366) (xy 98.019328 -206.329852) (xy 98.060545 -206.365567) (xy 98.09626 -206.406784)
			(xy 98.125746 -206.452665) (xy 98.148403 -206.502275) (xy 98.163768 -206.554605) (xy 98.17153 -206.608589)
			(xy 98.172016 -206.635858) (xy 98.172016 -207.499458) (xy 98.17153 -207.526727) (xy 98.163768 -207.580711)
			(xy 98.148403 -207.633041) (xy 98.125746 -207.682651) (xy 98.09626 -207.728532) (xy 98.060545 -207.769749)
			(xy 98.019328 -207.805464) (xy 97.973447 -207.83495) (xy 97.923837 -207.857607) (xy 97.871507 -207.872972)
			(xy 97.817523 -207.880734) (xy 97.762985 -207.880734) (xy 97.709001 -207.872972) (xy 97.656671 -207.857607)
			(xy 97.607061 -207.83495) (xy 97.56118 -207.805464) (xy 97.519963 -207.769749) (xy 97.484248 -207.728532)
			(xy 97.454762 -207.682651) (xy 97.432105 -207.633041) (xy 97.41674 -207.580711) (xy 97.408978 -207.526727)
			(xy 97.408492 -207.499458) (xy 2.509012 -207.499458) (xy 2.509012 -209.023458) (xy 94.105984 -209.023458)
			(xy 94.105984 -208.159858) (xy 94.10647 -208.132589) (xy 94.114232 -208.078605) (xy 94.129597 -208.026275)
			(xy 94.152254 -207.976665) (xy 94.18174 -207.930784) (xy 94.217455 -207.889567) (xy 94.258672 -207.853852)
			(xy 94.304553 -207.824366) (xy 94.354163 -207.801709) (xy 94.406493 -207.786344) (xy 94.460477 -207.778582)
			(xy 94.515015 -207.778582) (xy 94.568999 -207.786344) (xy 94.621329 -207.801709) (xy 94.670939 -207.824366)
			(xy 94.71682 -207.853852) (xy 94.758037 -207.889567) (xy 94.793752 -207.930784) (xy 94.823238 -207.976665)
			(xy 94.845895 -208.026275) (xy 94.86126 -208.078605) (xy 94.869022 -208.132589) (xy 94.869508 -208.159858)
			(xy 94.869508 -208.217008) (xy 255.545336 -208.217008) (xy 255.545336 -207.353408) (xy 255.545822 -207.326139)
			(xy 255.553584 -207.272155) (xy 255.568949 -207.219825) (xy 255.591606 -207.170215) (xy 255.621092 -207.124334)
			(xy 255.656807 -207.083117) (xy 255.698024 -207.047402) (xy 255.743905 -207.017916) (xy 255.793515 -206.995259)
			(xy 255.845845 -206.979894) (xy 255.899829 -206.972132) (xy 255.954367 -206.972132) (xy 256.008351 -206.979894)
			(xy 256.060681 -206.995259) (xy 256.110291 -207.017916) (xy 256.156172 -207.047402) (xy 256.197389 -207.083117)
			(xy 256.233104 -207.124334) (xy 256.26259 -207.170215) (xy 256.285247 -207.219825) (xy 256.300612 -207.272155)
			(xy 256.308374 -207.326139) (xy 256.30886 -207.353408) (xy 256.30886 -208.217008) (xy 256.308374 -208.244277)
			(xy 256.300612 -208.298261) (xy 256.285247 -208.350591) (xy 256.26259 -208.400201) (xy 256.233104 -208.446082)
			(xy 256.197389 -208.487299) (xy 256.156172 -208.523014) (xy 256.110291 -208.5525) (xy 256.060681 -208.575157)
			(xy 256.008351 -208.590522) (xy 255.954367 -208.598284) (xy 255.899829 -208.598284) (xy 255.845845 -208.590522)
			(xy 255.793515 -208.575157) (xy 255.743905 -208.5525) (xy 255.698024 -208.523014) (xy 255.656807 -208.487299)
			(xy 255.621092 -208.446082) (xy 255.591606 -208.400201) (xy 255.568949 -208.350591) (xy 255.553584 -208.298261)
			(xy 255.545822 -208.244277) (xy 255.545336 -208.217008) (xy 94.869508 -208.217008) (xy 94.869508 -209.023458)
			(xy 94.869022 -209.050727) (xy 94.86126 -209.104711) (xy 94.845895 -209.157041) (xy 94.823238 -209.206651)
			(xy 94.793752 -209.252532) (xy 94.758037 -209.293749) (xy 94.71682 -209.329464) (xy 94.670939 -209.35895)
			(xy 94.621329 -209.381607) (xy 94.568999 -209.396972) (xy 94.515015 -209.404734) (xy 94.460477 -209.404734)
			(xy 94.406493 -209.396972) (xy 94.354163 -209.381607) (xy 94.304553 -209.35895) (xy 94.258672 -209.329464)
			(xy 94.217455 -209.293749) (xy 94.18174 -209.252532) (xy 94.152254 -209.206651) (xy 94.129597 -209.157041)
			(xy 94.114232 -209.104711) (xy 94.10647 -209.050727) (xy 94.105984 -209.023458) (xy 2.509012 -209.023458)
			(xy 2.509012 -212.98027) (xy 78.81214 -212.98027) (xy 78.81617 -212.837935) (xy 78.828245 -212.696055)
			(xy 78.848328 -212.555087) (xy 78.876355 -212.41548) (xy 78.912235 -212.277682) (xy 78.955853 -212.142135)
			(xy 79.00707 -212.009273) (xy 79.065721 -211.879521) (xy 79.131619 -211.753295) (xy 79.204553 -211.630999)
			(xy 79.28429 -211.513026) (xy 79.370572 -211.399753) (xy 79.463125 -211.291542) (xy 79.561652 -211.188741)
			(xy 79.665837 -211.091679) (xy 79.775346 -211.000667) (xy 79.889829 -210.915995) (xy 80.008919 -210.837937)
			(xy 80.132234 -210.766741) (xy 80.25938 -210.702635) (xy 80.389949 -210.645826) (xy 80.523523 -210.596494)
			(xy 80.659674 -210.554798) (xy 80.797965 -210.520872) (xy 80.937955 -210.494824) (xy 81.079194 -210.476738)
			(xy 81.22123 -210.466671) (xy 81.363608 -210.464656) (xy 81.505872 -210.470699) (xy 81.647566 -210.484781)
			(xy 81.788236 -210.506857) (xy 81.927433 -210.536857) (xy 82.064709 -210.574683) (xy 82.199625 -210.620215)
			(xy 82.331749 -210.673306) (xy 82.460658 -210.733788) (xy 82.585939 -210.801466) (xy 82.70719 -210.876123)
			(xy 82.824023 -210.957521) (xy 82.936064 -211.045398) (xy 83.042954 -211.139473) (xy 83.144351 -211.239445)
			(xy 83.239929 -211.344993) (xy 83.329383 -211.455779) (xy 83.412425 -211.571448) (xy 83.488791 -211.691631)
			(xy 83.558235 -211.815941) (xy 83.620535 -211.943982) (xy 83.675491 -212.075341) (xy 83.69835 -212.140038)
			(xy 94.106492 -212.140038) (xy 94.106492 -211.276438) (xy 94.106978 -211.249187) (xy 94.114734 -211.195239)
			(xy 94.130089 -211.142944) (xy 94.152731 -211.093367) (xy 94.182197 -211.047517) (xy 94.217888 -211.006326)
			(xy 94.259079 -210.970635) (xy 94.304929 -210.941169) (xy 94.354506 -210.918527) (xy 94.406801 -210.903172)
			(xy 94.460749 -210.895416) (xy 94.515251 -210.895416) (xy 94.569199 -210.903172) (xy 94.621494 -210.918527)
			(xy 94.671071 -210.941169) (xy 94.716921 -210.970635) (xy 94.758112 -211.006326) (xy 94.793803 -211.047517)
			(xy 94.823269 -211.093367) (xy 94.845911 -211.142944) (xy 94.861266 -211.195239) (xy 94.869022 -211.249187)
			(xy 94.869508 -211.276438) (xy 94.869508 -212.140038) (xy 94.869022 -212.167289) (xy 94.861266 -212.221237)
			(xy 94.845911 -212.273532) (xy 94.823269 -212.323109) (xy 94.793803 -212.368959) (xy 94.758112 -212.41015)
			(xy 94.716921 -212.445841) (xy 94.671071 -212.475307) (xy 94.621494 -212.497949) (xy 94.569199 -212.513304)
			(xy 94.515251 -212.52106) (xy 94.460749 -212.52106) (xy 94.406801 -212.513304) (xy 94.354506 -212.497949)
			(xy 94.304929 -212.475307) (xy 94.259079 -212.445841) (xy 94.217888 -212.41015) (xy 94.182197 -212.368959)
			(xy 94.152731 -212.323109) (xy 94.130089 -212.273532) (xy 94.114734 -212.221237) (xy 94.106978 -212.167289)
			(xy 94.106492 -212.140038) (xy 83.69835 -212.140038) (xy 83.722928 -212.2096) (xy 83.762692 -212.346327)
			(xy 83.794658 -212.485085) (xy 83.818723 -212.625429) (xy 83.834809 -212.76691) (xy 83.842864 -212.909074)
			(xy 83.843368 -212.98027) (xy 140.011408 -212.98027) (xy 140.015438 -212.837906) (xy 140.027516 -212.695998)
			(xy 140.047604 -212.555001) (xy 140.075636 -212.415366) (xy 140.111523 -212.27754) (xy 140.15515 -212.141966)
			(xy 140.206377 -212.009077) (xy 140.26504 -211.879298) (xy 140.330952 -211.753047) (xy 140.403901 -211.630727)
			(xy 140.483653 -211.51273) (xy 140.569953 -211.399434) (xy 140.662525 -211.291201) (xy 140.761071 -211.188379)
			(xy 140.865277 -211.091298) (xy 140.974809 -211.000267) (xy 141.089315 -210.915579) (xy 141.208429 -210.837504)
			(xy 141.331769 -210.766294) (xy 141.45894 -210.702175) (xy 141.589536 -210.645354) (xy 141.723136 -210.596013)
			(xy 141.859315 -210.554308) (xy 141.997634 -210.520375) (xy 142.137652 -210.494322) (xy 142.278919 -210.476232)
			(xy 142.420984 -210.466163) (xy 142.563391 -210.464148) (xy 142.705684 -210.470192) (xy 142.847406 -210.484278)
			(xy 142.988105 -210.506358) (xy 143.12733 -210.536363) (xy 143.264634 -210.574197) (xy 143.399577 -210.619738)
			(xy 143.531728 -210.672841) (xy 143.660663 -210.733335) (xy 143.785969 -210.801026) (xy 143.907245 -210.875699)
			(xy 144.024101 -210.957113) (xy 144.093464 -211.011516) (xy 255.545336 -211.011516) (xy 255.545336 -210.147916)
			(xy 255.545822 -210.120647) (xy 255.553584 -210.066663) (xy 255.568949 -210.014333) (xy 255.591606 -209.964723)
			(xy 255.621092 -209.918842) (xy 255.656807 -209.877625) (xy 255.698024 -209.84191) (xy 255.743905 -209.812424)
			(xy 255.793515 -209.789767) (xy 255.845845 -209.774402) (xy 255.899829 -209.76664) (xy 255.954367 -209.76664)
			(xy 256.008351 -209.774402) (xy 256.060681 -209.789767) (xy 256.110291 -209.812424) (xy 256.156172 -209.84191)
			(xy 256.197389 -209.877625) (xy 256.233104 -209.918842) (xy 256.26259 -209.964723) (xy 256.285247 -210.014333)
			(xy 256.300612 -210.066663) (xy 256.308374 -210.120647) (xy 256.30886 -210.147916) (xy 256.30886 -211.011516)
			(xy 256.308374 -211.038785) (xy 256.300612 -211.092769) (xy 256.285247 -211.145099) (xy 256.26259 -211.194709)
			(xy 256.233104 -211.24059) (xy 256.197389 -211.281807) (xy 256.156172 -211.317522) (xy 256.110291 -211.347008)
			(xy 256.060681 -211.369665) (xy 256.008351 -211.38503) (xy 255.954367 -211.392792) (xy 255.899829 -211.392792)
			(xy 255.845845 -211.38503) (xy 255.793515 -211.369665) (xy 255.743905 -211.347008) (xy 255.698024 -211.317522)
			(xy 255.656807 -211.281807) (xy 255.621092 -211.24059) (xy 255.591606 -211.194709) (xy 255.568949 -211.145099)
			(xy 255.553584 -211.092769) (xy 255.545822 -211.038785) (xy 255.545336 -211.011516) (xy 144.093464 -211.011516)
			(xy 144.136165 -211.045007) (xy 144.243077 -211.139101) (xy 144.344494 -211.239093) (xy 144.440091 -211.344662)
			(xy 144.529563 -211.455471) (xy 144.612622 -211.571164) (xy 144.689003 -211.691371) (xy 144.758461 -211.815706)
			(xy 144.820774 -211.943772) (xy 144.875741 -212.075159) (xy 144.923187 -212.209444) (xy 144.96296 -212.346199)
			(xy 144.994932 -212.484985) (xy 145.019002 -212.625357) (xy 145.035091 -212.766867) (xy 145.043148 -212.909059)
			(xy 145.043652 -212.98027) (xy 145.043148 -213.051481) (xy 145.035091 -213.193673) (xy 145.019002 -213.335183)
			(xy 144.994932 -213.475555) (xy 144.96296 -213.614341) (xy 144.923187 -213.751096) (xy 144.90378 -213.806024)
			(xy 255.545336 -213.806024) (xy 255.545336 -212.942424) (xy 255.545822 -212.915155) (xy 255.553584 -212.861171)
			(xy 255.568949 -212.808841) (xy 255.591606 -212.759231) (xy 255.621092 -212.71335) (xy 255.656807 -212.672133)
			(xy 255.698024 -212.636418) (xy 255.743905 -212.606932) (xy 255.793515 -212.584275) (xy 255.845845 -212.56891)
			(xy 255.899829 -212.561148) (xy 255.954367 -212.561148) (xy 256.008351 -212.56891) (xy 256.060681 -212.584275)
			(xy 256.110291 -212.606932) (xy 256.156172 -212.636418) (xy 256.197389 -212.672133) (xy 256.233104 -212.71335)
			(xy 256.26259 -212.759231) (xy 256.285247 -212.808841) (xy 256.300612 -212.861171) (xy 256.308374 -212.915155)
			(xy 256.30886 -212.942424) (xy 256.30886 -212.980016) (xy 326.752208 -212.980016) (xy 326.756238 -212.837681)
			(xy 326.768313 -212.695801) (xy 326.788396 -212.554833) (xy 326.816423 -212.415226) (xy 326.852303 -212.277428)
			(xy 326.895921 -212.141881) (xy 326.947138 -212.009019) (xy 327.005789 -211.879267) (xy 327.071687 -211.753041)
			(xy 327.144621 -211.630745) (xy 327.224358 -211.512772) (xy 327.31064 -211.399499) (xy 327.403193 -211.291288)
			(xy 327.50172 -211.188487) (xy 327.605905 -211.091425) (xy 327.715414 -211.000413) (xy 327.829897 -210.915741)
			(xy 327.948987 -210.837683) (xy 328.072302 -210.766487) (xy 328.199448 -210.702381) (xy 328.330017 -210.645572)
			(xy 328.463591 -210.59624) (xy 328.599742 -210.554544) (xy 328.738033 -210.520618) (xy 328.878023 -210.49457)
			(xy 329.019262 -210.476484) (xy 329.161298 -210.466417) (xy 329.303676 -210.464402) (xy 329.44594 -210.470445)
			(xy 329.587634 -210.484527) (xy 329.728304 -210.506603) (xy 329.867501 -210.536603) (xy 330.004777 -210.574429)
			(xy 330.139693 -210.619961) (xy 330.271817 -210.673052) (xy 330.400726 -210.733534) (xy 330.526007 -210.801212)
			(xy 330.647258 -210.875869) (xy 330.764091 -210.957267) (xy 330.876132 -211.045144) (xy 330.983022 -211.139219)
			(xy 331.084419 -211.239191) (xy 331.179997 -211.344739) (xy 331.269451 -211.455525) (xy 331.352493 -211.571194)
			(xy 331.428859 -211.691377) (xy 331.498303 -211.815687) (xy 331.560603 -211.943728) (xy 331.615559 -212.075087)
			(xy 331.662996 -212.209346) (xy 331.70276 -212.346073) (xy 331.734726 -212.484831) (xy 331.758791 -212.625175)
			(xy 331.774877 -212.766656) (xy 331.782932 -212.90882) (xy 331.783436 -212.980016) (xy 387.951476 -212.980016)
			(xy 387.955506 -212.837652) (xy 387.967584 -212.695744) (xy 387.987672 -212.554747) (xy 388.015704 -212.415112)
			(xy 388.051591 -212.277286) (xy 388.095218 -212.141712) (xy 388.146445 -212.008823) (xy 388.205108 -211.879044)
			(xy 388.27102 -211.752793) (xy 388.343969 -211.630473) (xy 388.423721 -211.512476) (xy 388.510021 -211.39918)
			(xy 388.602593 -211.290947) (xy 388.701139 -211.188125) (xy 388.805345 -211.091044) (xy 388.914877 -211.000013)
			(xy 389.029383 -210.915325) (xy 389.148497 -210.83725) (xy 389.271837 -210.76604) (xy 389.399008 -210.701921)
			(xy 389.529604 -210.6451) (xy 389.663204 -210.595759) (xy 389.799383 -210.554054) (xy 389.937702 -210.520121)
			(xy 390.07772 -210.494068) (xy 390.218987 -210.475978) (xy 390.361052 -210.465909) (xy 390.503459 -210.463894)
			(xy 390.645752 -210.469938) (xy 390.787474 -210.484024) (xy 390.928173 -210.506104) (xy 391.067398 -210.536109)
			(xy 391.204702 -210.573943) (xy 391.339645 -210.619484) (xy 391.471796 -210.672587) (xy 391.600731 -210.733081)
			(xy 391.726037 -210.800772) (xy 391.847313 -210.875445) (xy 391.964169 -210.956859) (xy 392.076233 -211.044753)
			(xy 392.183145 -211.138847) (xy 392.284562 -211.238839) (xy 392.380159 -211.344408) (xy 392.469631 -211.455217)
			(xy 392.55269 -211.57091) (xy 392.629071 -211.691117) (xy 392.698529 -211.815452) (xy 392.760842 -211.943518)
			(xy 392.815809 -212.074905) (xy 392.863255 -212.20919) (xy 392.903028 -212.345945) (xy 392.935 -212.484731)
			(xy 392.95907 -212.625103) (xy 392.975159 -212.766613) (xy 392.983216 -212.908805) (xy 392.98372 -212.980016)
			(xy 392.983216 -213.051227) (xy 392.975159 -213.193419) (xy 392.95907 -213.334929) (xy 392.935 -213.475301)
			(xy 392.903028 -213.614087) (xy 392.863255 -213.750842) (xy 392.815809 -213.885127) (xy 392.760842 -214.016514)
			(xy 392.698529 -214.14458) (xy 392.629071 -214.268915) (xy 392.55269 -214.389122) (xy 392.469631 -214.504815)
			(xy 392.380159 -214.615624) (xy 392.284562 -214.721193) (xy 392.183145 -214.821185) (xy 392.076233 -214.915279)
			(xy 391.964169 -215.003173) (xy 391.847313 -215.084587) (xy 391.726037 -215.15926) (xy 391.600731 -215.226951)
			(xy 391.471796 -215.287445) (xy 391.339645 -215.340548) (xy 391.204702 -215.386089) (xy 391.067398 -215.423923)
			(xy 390.928173 -215.453928) (xy 390.787474 -215.476008) (xy 390.645752 -215.490094) (xy 390.503459 -215.496138)
			(xy 390.361052 -215.494123) (xy 390.218987 -215.484054) (xy 390.07772 -215.465964) (xy 389.937702 -215.439911)
			(xy 389.799383 -215.405978) (xy 389.663204 -215.364273) (xy 389.529604 -215.314932) (xy 389.399008 -215.258111)
			(xy 389.271837 -215.193992) (xy 389.148497 -215.122782) (xy 389.029383 -215.044707) (xy 388.914877 -214.960019)
			(xy 388.805345 -214.868988) (xy 388.701139 -214.771907) (xy 388.602593 -214.669085) (xy 388.510021 -214.560852)
			(xy 388.423721 -214.447556) (xy 388.343969 -214.329559) (xy 388.27102 -214.207239) (xy 388.205108 -214.080988)
			(xy 388.146445 -213.951209) (xy 388.095218 -213.81832) (xy 388.051591 -213.682746) (xy 388.015704 -213.54492)
			(xy 387.987672 -213.405285) (xy 387.967584 -213.264288) (xy 387.955506 -213.12238) (xy 387.951476 -212.980016)
			(xy 331.783436 -212.980016) (xy 331.782932 -213.051212) (xy 331.774877 -213.193376) (xy 331.758791 -213.334857)
			(xy 331.734726 -213.475201) (xy 331.70276 -213.613959) (xy 331.662996 -213.750686) (xy 331.615559 -213.884945)
			(xy 331.560603 -214.016304) (xy 331.498303 -214.144345) (xy 331.428859 -214.268655) (xy 331.352493 -214.388838)
			(xy 331.269451 -214.504507) (xy 331.179997 -214.615293) (xy 331.084419 -214.720841) (xy 330.983022 -214.820813)
			(xy 330.876132 -214.914888) (xy 330.764091 -215.002765) (xy 330.647258 -215.084163) (xy 330.526007 -215.15882)
			(xy 330.400726 -215.226498) (xy 330.271817 -215.28698) (xy 330.139693 -215.340071) (xy 330.004777 -215.385603)
			(xy 329.867501 -215.423429) (xy 329.728304 -215.453429) (xy 329.587634 -215.475505) (xy 329.44594 -215.489587)
			(xy 329.303676 -215.49563) (xy 329.161298 -215.493615) (xy 329.019262 -215.483548) (xy 328.878023 -215.465462)
			(xy 328.738033 -215.439414) (xy 328.599742 -215.405488) (xy 328.463591 -215.363792) (xy 328.330017 -215.31446)
			(xy 328.199448 -215.257651) (xy 328.072302 -215.193545) (xy 327.948987 -215.122349) (xy 327.829897 -215.044291)
			(xy 327.715414 -214.959619) (xy 327.605905 -214.868607) (xy 327.50172 -214.771545) (xy 327.403193 -214.668744)
			(xy 327.31064 -214.560533) (xy 327.224358 -214.44726) (xy 327.144621 -214.329287) (xy 327.071687 -214.206991)
			(xy 327.005789 -214.080765) (xy 326.947138 -213.951013) (xy 326.895921 -213.818151) (xy 326.852303 -213.682604)
			(xy 326.816423 -213.544806) (xy 326.788396 -213.405199) (xy 326.768313 -213.264231) (xy 326.756238 -213.122351)
			(xy 326.752208 -212.980016) (xy 256.30886 -212.980016) (xy 256.30886 -213.806024) (xy 256.308374 -213.833293)
			(xy 256.300612 -213.887277) (xy 256.285247 -213.939607) (xy 256.26259 -213.989217) (xy 256.233104 -214.035098)
			(xy 256.197389 -214.076315) (xy 256.156172 -214.11203) (xy 256.110291 -214.141516) (xy 256.060681 -214.164173)
			(xy 256.008351 -214.179538) (xy 255.954367 -214.1873) (xy 255.899829 -214.1873) (xy 255.845845 -214.179538)
			(xy 255.793515 -214.164173) (xy 255.743905 -214.141516) (xy 255.698024 -214.11203) (xy 255.656807 -214.076315)
			(xy 255.621092 -214.035098) (xy 255.591606 -213.989217) (xy 255.568949 -213.939607) (xy 255.553584 -213.887277)
			(xy 255.545822 -213.833293) (xy 255.545336 -213.806024) (xy 144.90378 -213.806024) (xy 144.875741 -213.885381)
			(xy 144.820774 -214.016768) (xy 144.758461 -214.144834) (xy 144.689003 -214.269169) (xy 144.612622 -214.389376)
			(xy 144.529563 -214.505069) (xy 144.440091 -214.615878) (xy 144.344494 -214.721447) (xy 144.243077 -214.821439)
			(xy 144.136165 -214.915533) (xy 144.024101 -215.003427) (xy 143.907245 -215.084841) (xy 143.785969 -215.159514)
			(xy 143.660663 -215.227205) (xy 143.531728 -215.287699) (xy 143.399577 -215.340802) (xy 143.264634 -215.386343)
			(xy 143.12733 -215.424177) (xy 142.988105 -215.454182) (xy 142.847406 -215.476262) (xy 142.705684 -215.490348)
			(xy 142.563391 -215.496392) (xy 142.420984 -215.494377) (xy 142.278919 -215.484308) (xy 142.137652 -215.466218)
			(xy 141.997634 -215.440165) (xy 141.859315 -215.406232) (xy 141.723136 -215.364527) (xy 141.589536 -215.315186)
			(xy 141.45894 -215.258365) (xy 141.331769 -215.194246) (xy 141.208429 -215.123036) (xy 141.089315 -215.044961)
			(xy 140.974809 -214.960273) (xy 140.865277 -214.869242) (xy 140.761071 -214.772161) (xy 140.662525 -214.669339)
			(xy 140.569953 -214.561106) (xy 140.483653 -214.44781) (xy 140.403901 -214.329813) (xy 140.330952 -214.207493)
			(xy 140.26504 -214.081242) (xy 140.206377 -213.951463) (xy 140.15515 -213.818574) (xy 140.111523 -213.683)
			(xy 140.075636 -213.545174) (xy 140.047604 -213.405539) (xy 140.027516 -213.264542) (xy 140.015438 -213.122634)
			(xy 140.011408 -212.98027) (xy 83.843368 -212.98027) (xy 83.842864 -213.051466) (xy 83.834809 -213.19363)
			(xy 83.818723 -213.335111) (xy 83.794658 -213.475455) (xy 83.762692 -213.614213) (xy 83.722928 -213.75094)
			(xy 83.675491 -213.885199) (xy 83.620535 -214.016558) (xy 83.558235 -214.144599) (xy 83.488791 -214.268909)
			(xy 83.412425 -214.389092) (xy 83.329383 -214.504761) (xy 83.239929 -214.615547) (xy 83.144351 -214.721095)
			(xy 83.042954 -214.821067) (xy 82.936064 -214.915142) (xy 82.837488 -214.992458) (xy 94.106492 -214.992458)
			(xy 94.106492 -214.128858) (xy 94.106978 -214.101607) (xy 94.114734 -214.047659) (xy 94.130089 -213.995364)
			(xy 94.152731 -213.945787) (xy 94.182197 -213.899937) (xy 94.217888 -213.858746) (xy 94.259079 -213.823055)
			(xy 94.304929 -213.793589) (xy 94.354506 -213.770947) (xy 94.406801 -213.755592) (xy 94.460749 -213.747836)
			(xy 94.515251 -213.747836) (xy 94.569199 -213.755592) (xy 94.621494 -213.770947) (xy 94.671071 -213.793589)
			(xy 94.716921 -213.823055) (xy 94.758112 -213.858746) (xy 94.793803 -213.899937) (xy 94.823269 -213.945787)
			(xy 94.845911 -213.995364) (xy 94.861266 -214.047659) (xy 94.869022 -214.101607) (xy 94.869508 -214.128858)
			(xy 94.869508 -214.992458) (xy 94.869022 -215.019709) (xy 94.861266 -215.073657) (xy 94.845911 -215.125952)
			(xy 94.823269 -215.175529) (xy 94.793803 -215.221379) (xy 94.758112 -215.26257) (xy 94.716921 -215.298261)
			(xy 94.671071 -215.327727) (xy 94.621494 -215.350369) (xy 94.569199 -215.365724) (xy 94.515251 -215.37348)
			(xy 94.460749 -215.37348) (xy 94.406801 -215.365724) (xy 94.354506 -215.350369) (xy 94.304929 -215.327727)
			(xy 94.259079 -215.298261) (xy 94.217888 -215.26257) (xy 94.182197 -215.221379) (xy 94.152731 -215.175529)
			(xy 94.130089 -215.125952) (xy 94.114734 -215.073657) (xy 94.106978 -215.019709) (xy 94.106492 -214.992458)
			(xy 82.837488 -214.992458) (xy 82.824023 -215.003019) (xy 82.70719 -215.084417) (xy 82.585939 -215.159074)
			(xy 82.460658 -215.226752) (xy 82.331749 -215.287234) (xy 82.199625 -215.340325) (xy 82.064709 -215.385857)
			(xy 81.927433 -215.423683) (xy 81.788236 -215.453683) (xy 81.647566 -215.475759) (xy 81.505872 -215.489841)
			(xy 81.363608 -215.495884) (xy 81.22123 -215.493869) (xy 81.079194 -215.483802) (xy 80.937955 -215.465716)
			(xy 80.797965 -215.439668) (xy 80.659674 -215.405742) (xy 80.523523 -215.364046) (xy 80.389949 -215.314714)
			(xy 80.25938 -215.257905) (xy 80.132234 -215.193799) (xy 80.008919 -215.122603) (xy 79.889829 -215.044545)
			(xy 79.775346 -214.959873) (xy 79.665837 -214.868861) (xy 79.561652 -214.771799) (xy 79.463125 -214.668998)
			(xy 79.370572 -214.560787) (xy 79.28429 -214.447514) (xy 79.204553 -214.329541) (xy 79.131619 -214.207245)
			(xy 79.065721 -214.081019) (xy 79.00707 -213.951267) (xy 78.955853 -213.818405) (xy 78.912235 -213.682858)
			(xy 78.876355 -213.54506) (xy 78.848328 -213.405453) (xy 78.828245 -213.264485) (xy 78.81617 -213.122605)
			(xy 78.81214 -212.98027) (xy 2.509012 -212.98027) (xy 2.509012 -217.548574) (xy 338.152884 -217.548574)
			(xy 338.152884 -217.494026) (xy 338.160647 -217.440032) (xy 338.176017 -217.387693) (xy 338.198679 -217.338074)
			(xy 338.228172 -217.292186) (xy 338.263897 -217.250963) (xy 338.305125 -217.215244) (xy 338.351016 -217.185756)
			(xy 338.400638 -217.1631) (xy 338.452979 -217.147737) (xy 338.506973 -217.13998) (xy 338.534248 -217.13952)
			(xy 339.550248 -217.13952) (xy 339.577514 -217.140046) (xy 339.63149 -217.147813) (xy 339.683811 -217.163181)
			(xy 339.733413 -217.185839) (xy 339.779286 -217.215325) (xy 339.820495 -217.251039) (xy 339.856204 -217.292253)
			(xy 339.885684 -217.338129) (xy 339.908336 -217.387734) (xy 339.923698 -217.440057) (xy 339.931458 -217.494034)
			(xy 339.931458 -217.548566) (xy 339.923698 -217.602543) (xy 339.908336 -217.654866) (xy 339.885684 -217.704471)
			(xy 339.856204 -217.750347) (xy 339.820495 -217.791561) (xy 339.779286 -217.827275) (xy 339.733413 -217.856761)
			(xy 339.683811 -217.879419) (xy 339.63149 -217.894787) (xy 339.577514 -217.902554) (xy 339.550248 -217.903044)
			(xy 338.534248 -217.903044) (xy 338.506973 -217.90262) (xy 338.452979 -217.894863) (xy 338.400638 -217.8795)
			(xy 338.351016 -217.856844) (xy 338.305125 -217.827356) (xy 338.263897 -217.791637) (xy 338.228172 -217.750414)
			(xy 338.198679 -217.704526) (xy 338.176017 -217.654907) (xy 338.160647 -217.602568) (xy 338.152884 -217.548574)
			(xy 2.509012 -217.548574) (xy 2.509012 -219.820372) (xy 129.049982 -219.820372) (xy 129.049982 -219.765828)
			(xy 129.057745 -219.71184) (xy 129.073111 -219.659505) (xy 129.095769 -219.609891) (xy 129.125257 -219.564005)
			(xy 129.160975 -219.522783) (xy 129.202196 -219.487064) (xy 129.24808 -219.457575) (xy 129.297694 -219.434915)
			(xy 129.350028 -219.419547) (xy 129.404016 -219.411783) (xy 129.431288 -219.411296) (xy 130.447288 -219.411296)
			(xy 130.474557 -219.411843) (xy 130.528539 -219.419602) (xy 130.580867 -219.434966) (xy 130.630476 -219.45762)
			(xy 130.676357 -219.487104) (xy 130.717574 -219.522818) (xy 130.753288 -219.564034) (xy 130.782774 -219.609913)
			(xy 130.80543 -219.659522) (xy 130.820795 -219.711849) (xy 130.828557 -219.765831) (xy 130.828557 -219.820369)
			(xy 130.820795 -219.874351) (xy 130.80543 -219.926678) (xy 130.782774 -219.976287) (xy 130.753288 -220.022166)
			(xy 130.717574 -220.063382) (xy 130.676357 -220.099096) (xy 130.630476 -220.12858) (xy 130.580867 -220.151234)
			(xy 130.528539 -220.166598) (xy 130.474557 -220.174357) (xy 130.447288 -220.17482) (xy 129.431288 -220.17482)
			(xy 129.404016 -220.174417) (xy 129.350028 -220.166653) (xy 129.297694 -220.151285) (xy 129.24808 -220.128625)
			(xy 129.202196 -220.099136) (xy 129.160975 -220.063417) (xy 129.125257 -220.022195) (xy 129.095769 -219.976309)
			(xy 129.073111 -219.926695) (xy 129.057745 -219.87436) (xy 129.049982 -219.820372) (xy 2.509012 -219.820372)
			(xy 2.509012 -243.6744) (xy 108.185132 -243.6744) (xy 108.189304 -243.624054) (xy 108.201706 -243.575081)
			(xy 108.222 -243.528817) (xy 108.249632 -243.486525) (xy 108.283849 -243.449358) (xy 108.323717 -243.418331)
			(xy 108.368148 -243.394288) (xy 108.41593 -243.377887) (xy 108.465761 -243.369575) (xy 108.49102 -243.369084)
			(xy 109.431074 -243.369084) (xy 109.456332 -243.369591) (xy 109.506161 -243.377902) (xy 109.553942 -243.394301)
			(xy 109.598371 -243.418342) (xy 109.638238 -243.449368) (xy 109.672453 -243.486533) (xy 109.700085 -243.528823)
			(xy 109.720378 -243.575085) (xy 109.73278 -243.624056) (xy 109.736927 -243.6741) (xy 361.758723 -243.6741)
			(xy 361.762898 -243.623721) (xy 361.775308 -243.574716) (xy 361.795615 -243.528421) (xy 361.823265 -243.486101)
			(xy 361.857503 -243.448909) (xy 361.897396 -243.41786) (xy 361.941856 -243.393801) (xy 361.989669 -243.377388)
			(xy 362.039532 -243.369068) (xy 362.064808 -243.368576) (xy 363.004862 -243.368576) (xy 363.030146 -243.36899)
			(xy 363.080025 -243.377308) (xy 363.127854 -243.393722) (xy 363.172329 -243.417786) (xy 363.212237 -243.448843)
			(xy 363.246487 -243.486045) (xy 363.274147 -243.528377) (xy 363.294462 -243.574685) (xy 363.306876 -243.623705)
			(xy 363.311053 -243.6741) (xy 363.306876 -243.724495) (xy 363.294462 -243.773515) (xy 363.274147 -243.819823)
			(xy 363.246487 -243.862155) (xy 363.212237 -243.899357) (xy 363.172329 -243.930414) (xy 363.127854 -243.954478)
			(xy 363.080025 -243.970892) (xy 363.030146 -243.97921) (xy 363.004862 -243.9797) (xy 362.064808 -243.9797)
			(xy 362.039532 -243.979132) (xy 361.989669 -243.970812) (xy 361.941856 -243.954399) (xy 361.897396 -243.93034)
			(xy 361.857503 -243.899291) (xy 361.823265 -243.862099) (xy 361.795615 -243.819779) (xy 361.775308 -243.773484)
			(xy 361.762898 -243.724479) (xy 361.758723 -243.6741) (xy 109.736927 -243.6741) (xy 109.736952 -243.6744)
			(xy 109.73278 -243.724744) (xy 109.720378 -243.773715) (xy 109.700085 -243.819977) (xy 109.672453 -243.862267)
			(xy 109.638238 -243.899432) (xy 109.598371 -243.930458) (xy 109.553942 -243.954499) (xy 109.506161 -243.970898)
			(xy 109.456332 -243.979209) (xy 109.431074 -243.9797) (xy 108.49102 -243.9797) (xy 108.465761 -243.979225)
			(xy 108.41593 -243.970913) (xy 108.368148 -243.954512) (xy 108.323717 -243.930469) (xy 108.283849 -243.899442)
			(xy 108.249632 -243.862275) (xy 108.222 -243.819983) (xy 108.201706 -243.773719) (xy 108.189304 -243.724746)
			(xy 108.185132 -243.6744) (xy 2.509012 -243.6744) (xy 2.509012 -244.4844) (xy 97.374883 -244.4844)
			(xy 97.379059 -244.434011) (xy 97.391472 -244.384997) (xy 97.411784 -244.338695) (xy 97.43944 -244.296368)
			(xy 97.473686 -244.259171) (xy 97.513588 -244.228118) (xy 97.558057 -244.204057) (xy 97.605881 -244.187644)
			(xy 97.655753 -244.179326) (xy 97.681034 -244.178836) (xy 98.621088 -244.178836) (xy 98.646367 -244.179332)
			(xy 98.696236 -244.187652) (xy 98.744056 -244.204067) (xy 98.788521 -244.228129) (xy 98.82842 -244.259181)
			(xy 98.862663 -244.296378) (xy 98.890316 -244.338703) (xy 98.910626 -244.385003) (xy 98.923037 -244.434014)
			(xy 98.927213 -244.4844) (xy 100.194783 -244.4844) (xy 100.198959 -244.434011) (xy 100.211373 -244.384996)
			(xy 100.231685 -244.338693) (xy 100.259342 -244.296365) (xy 100.293589 -244.259168) (xy 100.333492 -244.228115)
			(xy 100.377963 -244.204054) (xy 100.425787 -244.187642) (xy 100.475661 -244.179326) (xy 100.500942 -244.178836)
			(xy 101.440996 -244.178836) (xy 101.466275 -244.179333) (xy 101.516143 -244.187654) (xy 101.563961 -244.204069)
			(xy 101.608426 -244.228131) (xy 101.648323 -244.259184) (xy 101.682565 -244.29638) (xy 101.710217 -244.338705)
			(xy 101.730526 -244.385005) (xy 101.742937 -244.434015) (xy 101.747113 -244.4844) (xy 103.014983 -244.4844)
			(xy 103.019159 -244.434014) (xy 103.03157 -244.385003) (xy 103.051879 -244.338704) (xy 103.079532 -244.296378)
			(xy 103.113774 -244.259181) (xy 103.153672 -244.228128) (xy 103.198137 -244.204065) (xy 103.245956 -244.18765)
			(xy 103.295825 -244.179329) (xy 103.321104 -244.178836) (xy 104.261158 -244.178836) (xy 104.286439 -244.17933)
			(xy 104.336312 -244.187646) (xy 104.384136 -244.204058) (xy 104.428605 -244.228118) (xy 104.468508 -244.259171)
			(xy 104.502755 -244.296368) (xy 104.530412 -244.338695) (xy 104.550724 -244.384997) (xy 104.563137 -244.434011)
			(xy 104.567313 -244.4844) (xy 105.834883 -244.4844) (xy 105.839059 -244.434014) (xy 105.851471 -244.385002)
			(xy 105.87178 -244.338701) (xy 105.899434 -244.296375) (xy 105.933678 -244.259178) (xy 105.973577 -244.228125)
			(xy 106.018043 -244.204063) (xy 106.065863 -244.187648) (xy 106.115732 -244.179328) (xy 106.141012 -244.178836)
			(xy 107.081066 -244.178836) (xy 107.106346 -244.17933) (xy 107.156218 -244.187647) (xy 107.204041 -244.20406)
			(xy 107.24851 -244.228121) (xy 107.288411 -244.259174) (xy 107.322657 -244.29637) (xy 107.350313 -244.338697)
			(xy 107.370624 -244.384999) (xy 107.383037 -244.434012) (xy 107.387188 -244.4841) (xy 364.108984 -244.4841)
			(xy 364.113155 -244.433763) (xy 364.125555 -244.384799) (xy 364.145845 -244.338543) (xy 364.173472 -244.296259)
			(xy 364.207683 -244.259098) (xy 364.247543 -244.228076) (xy 364.291966 -244.204037) (xy 364.33974 -244.187639)
			(xy 364.389561 -244.179327) (xy 364.414816 -244.178836) (xy 365.35487 -244.178836) (xy 365.380133 -244.179238)
			(xy 365.42997 -244.18755) (xy 365.47776 -244.203952) (xy 365.522198 -244.227997) (xy 365.562072 -244.259028)
			(xy 365.596293 -244.2962) (xy 365.62393 -244.338497) (xy 365.644227 -244.384767) (xy 365.656631 -244.433747)
			(xy 365.660804 -244.4841) (xy 366.928884 -244.4841) (xy 366.933055 -244.433762) (xy 366.945456 -244.384797)
			(xy 366.965746 -244.338541) (xy 366.993374 -244.296256) (xy 367.027586 -244.259095) (xy 367.067447 -244.228073)
			(xy 367.111871 -244.204035) (xy 367.159646 -244.187637) (xy 367.209469 -244.179327) (xy 367.234724 -244.178836)
			(xy 368.174778 -244.178836) (xy 368.200041 -244.179239) (xy 368.249877 -244.187552) (xy 368.297665 -244.203955)
			(xy 368.342102 -244.228) (xy 368.381975 -244.259031) (xy 368.416196 -244.296203) (xy 368.443831 -244.3385)
			(xy 368.464128 -244.384769) (xy 368.476531 -244.433748) (xy 368.480704 -244.4841) (xy 369.749113 -244.4841)
			(xy 369.753283 -244.433771) (xy 369.76568 -244.384814) (xy 369.785966 -244.338565) (xy 369.813587 -244.296286)
			(xy 369.847791 -244.25913) (xy 369.887643 -244.22811) (xy 369.932057 -244.204073) (xy 369.979822 -244.187673)
			(xy 370.029635 -244.179359) (xy 370.054886 -244.178836) (xy 370.99494 -244.178836) (xy 371.020197 -244.179272)
			(xy 371.070021 -244.187592) (xy 371.117796 -244.203999) (xy 371.162219 -244.228045) (xy 371.202079 -244.259074)
			(xy 371.236289 -244.296241) (xy 371.263916 -244.33853) (xy 371.284205 -244.38479) (xy 371.296604 -244.433759)
			(xy 371.300776 -244.4841) (xy 372.569013 -244.4841) (xy 372.573183 -244.43377) (xy 372.585581 -244.384812)
			(xy 372.605867 -244.338563) (xy 372.63349 -244.296284) (xy 372.667694 -244.259127) (xy 372.707547 -244.228107)
			(xy 372.751963 -244.20407) (xy 372.799729 -244.187671) (xy 372.849543 -244.179358) (xy 372.874794 -244.178836)
			(xy 373.814848 -244.178836) (xy 373.840104 -244.179273) (xy 373.889927 -244.187594) (xy 373.937701 -244.204002)
			(xy 373.982123 -244.228048) (xy 374.021982 -244.259077) (xy 374.056191 -244.296243) (xy 374.083817 -244.338533)
			(xy 374.104106 -244.384792) (xy 374.116505 -244.43376) (xy 374.120676 -244.4841) (xy 374.116505 -244.53444)
			(xy 374.104106 -244.583408) (xy 374.083817 -244.629667) (xy 374.056191 -244.671957) (xy 374.021982 -244.709123)
			(xy 373.982123 -244.740152) (xy 373.937701 -244.764198) (xy 373.889927 -244.780606) (xy 373.840104 -244.788927)
			(xy 373.814848 -244.789452) (xy 372.874794 -244.789452) (xy 372.849543 -244.788842) (xy 372.799729 -244.780529)
			(xy 372.751963 -244.76413) (xy 372.707547 -244.740093) (xy 372.667694 -244.709073) (xy 372.63349 -244.671916)
			(xy 372.605867 -244.629637) (xy 372.585581 -244.583388) (xy 372.573183 -244.53443) (xy 372.569013 -244.4841)
			(xy 371.300776 -244.4841) (xy 371.296604 -244.534441) (xy 371.284205 -244.58341) (xy 371.263915 -244.62967)
			(xy 371.236289 -244.671959) (xy 371.202079 -244.709126) (xy 371.162219 -244.740155) (xy 371.117796 -244.764201)
			(xy 371.070021 -244.780608) (xy 371.020197 -244.788928) (xy 370.99494 -244.789452) (xy 370.054886 -244.789452)
			(xy 370.029635 -244.788841) (xy 369.979822 -244.780527) (xy 369.932057 -244.764127) (xy 369.887643 -244.74009)
			(xy 369.847791 -244.70907) (xy 369.813587 -244.671914) (xy 369.785966 -244.629635) (xy 369.76568 -244.583386)
			(xy 369.753283 -244.534429) (xy 369.749113 -244.4841) (xy 368.480704 -244.4841) (xy 368.476531 -244.534452)
			(xy 368.464128 -244.583431) (xy 368.443831 -244.6297) (xy 368.416196 -244.671997) (xy 368.381975 -244.709169)
			(xy 368.342102 -244.7402) (xy 368.297665 -244.764245) (xy 368.249877 -244.780648) (xy 368.200041 -244.788961)
			(xy 368.174778 -244.789452) (xy 367.234724 -244.789452) (xy 367.209469 -244.788873) (xy 367.159646 -244.780563)
			(xy 367.111871 -244.764165) (xy 367.067447 -244.740127) (xy 367.027586 -244.709105) (xy 366.993374 -244.671944)
			(xy 366.965746 -244.629659) (xy 366.945456 -244.583403) (xy 366.933055 -244.534438) (xy 366.928884 -244.4841)
			(xy 365.660804 -244.4841) (xy 365.656631 -244.534453) (xy 365.644227 -244.583433) (xy 365.62393 -244.629703)
			(xy 365.596293 -244.672) (xy 365.562072 -244.709172) (xy 365.522198 -244.740203) (xy 365.47776 -244.764248)
			(xy 365.42997 -244.78065) (xy 365.380133 -244.788962) (xy 365.35487 -244.789452) (xy 364.414816 -244.789452)
			(xy 364.389561 -244.788873) (xy 364.33974 -244.780561) (xy 364.291966 -244.764163) (xy 364.247543 -244.740124)
			(xy 364.207683 -244.709102) (xy 364.173472 -244.671941) (xy 364.145845 -244.629657) (xy 364.125555 -244.583401)
			(xy 364.113155 -244.534437) (xy 364.108984 -244.4841) (xy 107.387188 -244.4841) (xy 107.387213 -244.4844)
			(xy 107.383037 -244.534788) (xy 107.370624 -244.583801) (xy 107.350313 -244.630103) (xy 107.322657 -244.67243)
			(xy 107.288411 -244.709626) (xy 107.24851 -244.740679) (xy 107.204041 -244.76474) (xy 107.156218 -244.781153)
			(xy 107.106346 -244.78947) (xy 107.081066 -244.78996) (xy 106.141012 -244.78996) (xy 106.115732 -244.789472)
			(xy 106.065863 -244.781152) (xy 106.018043 -244.764737) (xy 105.973577 -244.740675) (xy 105.933678 -244.709622)
			(xy 105.899434 -244.672425) (xy 105.87178 -244.630099) (xy 105.851471 -244.583798) (xy 105.839059 -244.534786)
			(xy 105.834883 -244.4844) (xy 104.567313 -244.4844) (xy 104.563137 -244.534789) (xy 104.550724 -244.583803)
			(xy 104.530412 -244.630105) (xy 104.502755 -244.672432) (xy 104.468508 -244.709629) (xy 104.428605 -244.740682)
			(xy 104.384136 -244.764742) (xy 104.336312 -244.781154) (xy 104.286439 -244.78947) (xy 104.261158 -244.78996)
			(xy 103.321104 -244.78996) (xy 103.295825 -244.789471) (xy 103.245956 -244.78115) (xy 103.198137 -244.764735)
			(xy 103.153672 -244.740672) (xy 103.113774 -244.709619) (xy 103.079532 -244.672422) (xy 103.051879 -244.630096)
			(xy 103.03157 -244.583797) (xy 103.019159 -244.534786) (xy 103.014983 -244.4844) (xy 101.747113 -244.4844)
			(xy 101.742937 -244.534785) (xy 101.730526 -244.583795) (xy 101.710217 -244.630095) (xy 101.682565 -244.67242)
			(xy 101.648323 -244.709616) (xy 101.608426 -244.740669) (xy 101.563961 -244.764731) (xy 101.516143 -244.781146)
			(xy 101.466275 -244.789467) (xy 101.440996 -244.78996) (xy 100.500942 -244.78996) (xy 100.475661 -244.789474)
			(xy 100.425787 -244.781158) (xy 100.377963 -244.764746) (xy 100.333492 -244.740685) (xy 100.293589 -244.709632)
			(xy 100.259342 -244.672435) (xy 100.231685 -244.630107) (xy 100.211373 -244.583804) (xy 100.198959 -244.534789)
			(xy 100.194783 -244.4844) (xy 98.927213 -244.4844) (xy 98.923037 -244.534786) (xy 98.910626 -244.583797)
			(xy 98.890316 -244.630097) (xy 98.862663 -244.672422) (xy 98.82842 -244.709619) (xy 98.788521 -244.740671)
			(xy 98.744056 -244.764733) (xy 98.696236 -244.781148) (xy 98.646367 -244.789468) (xy 98.621088 -244.78996)
			(xy 97.681034 -244.78996) (xy 97.655753 -244.789474) (xy 97.605881 -244.781156) (xy 97.558057 -244.764743)
			(xy 97.513588 -244.740682) (xy 97.473686 -244.709629) (xy 97.43944 -244.672432) (xy 97.411784 -244.630105)
			(xy 97.391472 -244.583803) (xy 97.379059 -244.534789) (xy 97.374883 -244.4844) (xy 2.509012 -244.4844)
			(xy 2.509012 -245.2944) (xy 108.185144 -245.2944) (xy 108.189316 -245.244056) (xy 108.201717 -245.195085)
			(xy 108.222011 -245.148823) (xy 108.249642 -245.106533) (xy 108.283857 -245.069367) (xy 108.323723 -245.038341)
			(xy 108.368153 -245.014299) (xy 108.415933 -244.997899) (xy 108.465762 -244.989587) (xy 108.49102 -244.989096)
			(xy 109.431074 -244.989096) (xy 109.456333 -244.989579) (xy 109.506164 -244.99789) (xy 109.553947 -245.01429)
			(xy 109.598378 -245.038332) (xy 109.638246 -245.069359) (xy 109.672463 -245.106526) (xy 109.700095 -245.148818)
			(xy 109.72039 -245.195081) (xy 109.732792 -245.244054) (xy 109.736939 -245.2941) (xy 361.758735 -245.2941)
			(xy 361.76291 -245.243723) (xy 361.775319 -245.194719) (xy 361.795626 -245.148427) (xy 361.823274 -245.106109)
			(xy 361.857511 -245.068918) (xy 361.897403 -245.03787) (xy 361.941861 -245.013812) (xy 361.989672 -244.997399)
			(xy 362.039533 -244.98908) (xy 362.064808 -244.988588) (xy 363.004862 -244.988588) (xy 363.030147 -244.988978)
			(xy 363.080028 -244.997296) (xy 363.127859 -245.013711) (xy 363.172336 -245.037776) (xy 363.212245 -245.068834)
			(xy 363.246497 -245.106037) (xy 363.274158 -245.148371) (xy 363.294473 -245.194681) (xy 363.306888 -245.243703)
			(xy 363.311065 -245.2941) (xy 363.306888 -245.344497) (xy 363.294473 -245.393519) (xy 363.274158 -245.439829)
			(xy 363.246497 -245.482163) (xy 363.212245 -245.519366) (xy 363.172336 -245.550424) (xy 363.127859 -245.574489)
			(xy 363.080028 -245.590904) (xy 363.030147 -245.599222) (xy 363.004862 -245.599712) (xy 362.064808 -245.599712)
			(xy 362.039533 -245.59912) (xy 361.989672 -245.590801) (xy 361.941861 -245.574388) (xy 361.897403 -245.55033)
			(xy 361.857511 -245.519282) (xy 361.823274 -245.482091) (xy 361.795626 -245.439773) (xy 361.775319 -245.393481)
			(xy 361.76291 -245.344477) (xy 361.758735 -245.2941) (xy 109.736939 -245.2941) (xy 109.736964 -245.2944)
			(xy 109.732792 -245.344746) (xy 109.72039 -245.393719) (xy 109.700095 -245.439982) (xy 109.672463 -245.482274)
			(xy 109.638246 -245.519441) (xy 109.598378 -245.550468) (xy 109.553947 -245.57451) (xy 109.506164 -245.59091)
			(xy 109.456333 -245.599221) (xy 109.431074 -245.599712) (xy 108.49102 -245.599712) (xy 108.465762 -245.599213)
			(xy 108.415933 -245.590901) (xy 108.368153 -245.574501) (xy 108.323723 -245.550459) (xy 108.283857 -245.519433)
			(xy 108.249642 -245.482267) (xy 108.222011 -245.439977) (xy 108.201717 -245.393715) (xy 108.189316 -245.344744)
			(xy 108.185144 -245.2944) (xy 2.509012 -245.2944) (xy 2.509012 -246.1044) (xy 97.374895 -246.1044)
			(xy 97.379071 -246.054013) (xy 97.391483 -246.005001) (xy 97.411794 -245.958701) (xy 97.439449 -245.916375)
			(xy 97.473694 -245.879179) (xy 97.513595 -245.848128) (xy 97.558062 -245.824068) (xy 97.605884 -245.807655)
			(xy 97.655754 -245.799338) (xy 97.681034 -245.798848) (xy 98.621088 -245.798848) (xy 98.646368 -245.79932)
			(xy 98.696239 -245.80764) (xy 98.744061 -245.824056) (xy 98.788528 -245.848119) (xy 98.828428 -245.879173)
			(xy 98.862672 -245.91637) (xy 98.890327 -245.958698) (xy 98.910637 -246.004999) (xy 98.923049 -246.054012)
			(xy 98.927225 -246.1044) (xy 100.194795 -246.1044) (xy 100.198971 -246.054012) (xy 100.211384 -246.005)
			(xy 100.231695 -245.958699) (xy 100.259351 -245.916373) (xy 100.293597 -245.879177) (xy 100.333499 -245.848125)
			(xy 100.377968 -245.824065) (xy 100.42579 -245.807654) (xy 100.475662 -245.799338) (xy 100.500942 -245.798848)
			(xy 101.440996 -245.798848) (xy 101.466276 -245.799321) (xy 101.516146 -245.807642) (xy 101.563966 -245.824058)
			(xy 101.608432 -245.848121) (xy 101.648331 -245.879175) (xy 101.682574 -245.916373) (xy 101.710228 -245.9587)
			(xy 101.730538 -246.005001) (xy 101.742949 -246.054013) (xy 101.747125 -246.1044) (xy 103.014995 -246.1044)
			(xy 103.01917 -246.054016) (xy 103.031581 -246.005007) (xy 103.05189 -245.958709) (xy 103.079542 -245.916385)
			(xy 103.113783 -245.87919) (xy 103.153679 -245.848138) (xy 103.198142 -245.824076) (xy 103.245959 -245.807661)
			(xy 103.295826 -245.799341) (xy 103.321104 -245.798848) (xy 104.261158 -245.798848) (xy 104.28644 -245.799318)
			(xy 104.336315 -245.807634) (xy 104.38414 -245.824047) (xy 104.428612 -245.848108) (xy 104.468516 -245.879162)
			(xy 104.502764 -245.91636) (xy 104.530422 -245.958689) (xy 104.550735 -246.004993) (xy 104.563149 -246.054009)
			(xy 104.567325 -246.1044) (xy 105.834895 -246.1044) (xy 105.839071 -246.054016) (xy 105.851482 -246.005006)
			(xy 105.871791 -245.958707) (xy 105.899444 -245.916383) (xy 105.933686 -245.879187) (xy 105.973583 -245.848135)
			(xy 106.018047 -245.824074) (xy 106.065866 -245.80766) (xy 106.115733 -245.79934) (xy 106.141012 -245.798848)
			(xy 107.081066 -245.798848) (xy 107.106347 -245.799318) (xy 107.156221 -245.807636) (xy 107.204046 -245.824049)
			(xy 107.248516 -245.848111) (xy 107.288419 -245.879165) (xy 107.322666 -245.916363) (xy 107.350323 -245.958691)
			(xy 107.370636 -246.004995) (xy 107.383049 -246.05401) (xy 107.387208 -246.1042) (xy 364.108896 -246.1042)
			(xy 364.113068 -246.053848) (xy 364.125472 -246.00487) (xy 364.145768 -245.958601) (xy 364.173403 -245.916305)
			(xy 364.207623 -245.879133) (xy 364.247495 -245.848102) (xy 364.291931 -245.824057) (xy 364.339718 -245.807653)
			(xy 364.389554 -245.79934) (xy 364.414816 -245.798848) (xy 365.35487 -245.798848) (xy 365.380126 -245.799426)
			(xy 365.429949 -245.807736) (xy 365.477725 -245.824133) (xy 365.52215 -245.848171) (xy 365.562012 -245.879193)
			(xy 365.596224 -245.916354) (xy 365.623853 -245.958639) (xy 365.644144 -246.004896) (xy 365.656545 -246.053861)
			(xy 365.660716 -246.1042) (xy 366.928796 -246.1042) (xy 366.932969 -246.053847) (xy 366.945372 -246.004868)
			(xy 366.965669 -245.958599) (xy 366.993305 -245.916302) (xy 367.027526 -245.879131) (xy 367.067399 -245.848099)
			(xy 367.111836 -245.824054) (xy 367.159625 -245.807652) (xy 367.209461 -245.799339) (xy 367.234724 -245.798848)
			(xy 368.174778 -245.798848) (xy 368.200033 -245.799427) (xy 368.249855 -245.807737) (xy 368.29763 -245.824135)
			(xy 368.342054 -245.848173) (xy 368.381915 -245.879196) (xy 368.416126 -245.916357) (xy 368.443754 -245.958642)
			(xy 368.464045 -246.004897) (xy 368.476445 -246.053862) (xy 368.480616 -246.1042) (xy 369.749024 -246.1042)
			(xy 369.753196 -246.053856) (xy 369.765597 -246.004885) (xy 369.785888 -245.958623) (xy 369.813518 -245.916332)
			(xy 369.847731 -245.879165) (xy 369.887595 -245.848136) (xy 369.932022 -245.824092) (xy 369.979801 -245.807687)
			(xy 370.029628 -245.79937) (xy 370.054886 -245.798848) (xy 370.99494 -245.798848) (xy 371.02019 -245.799461)
			(xy 371.069999 -245.807778) (xy 371.11776 -245.82418) (xy 371.162171 -245.848219) (xy 371.202019 -245.879239)
			(xy 371.236219 -245.916395) (xy 371.263838 -245.958673) (xy 371.284121 -246.004919) (xy 371.296517 -246.053873)
			(xy 371.300687 -246.1042) (xy 372.568924 -246.1042) (xy 372.573096 -246.053855) (xy 372.585497 -246.004884)
			(xy 372.60579 -245.958621) (xy 372.63342 -245.916329) (xy 372.667634 -245.879162) (xy 372.707499 -245.848133)
			(xy 372.751927 -245.824089) (xy 372.799707 -245.807685) (xy 372.849535 -245.79937) (xy 372.874794 -245.798848)
			(xy 373.814848 -245.798848) (xy 373.840097 -245.799461) (xy 373.889906 -245.80778) (xy 373.937666 -245.824183)
			(xy 373.982075 -245.848222) (xy 374.021923 -245.879242) (xy 374.056121 -245.916398) (xy 374.083739 -245.958675)
			(xy 374.104022 -246.004921) (xy 374.116417 -246.053874) (xy 374.120587 -246.1042) (xy 374.116417 -246.154526)
			(xy 374.104022 -246.203479) (xy 374.083739 -246.249725) (xy 374.056121 -246.292002) (xy 374.021923 -246.329158)
			(xy 373.982075 -246.360178) (xy 373.937666 -246.384217) (xy 373.889906 -246.40062) (xy 373.840097 -246.408939)
			(xy 373.814848 -246.409464) (xy 372.874794 -246.409464) (xy 372.849535 -246.40903) (xy 372.799707 -246.400715)
			(xy 372.751927 -246.384311) (xy 372.707499 -246.360267) (xy 372.667634 -246.329238) (xy 372.63342 -246.292071)
			(xy 372.60579 -246.249779) (xy 372.585497 -246.203516) (xy 372.573096 -246.154545) (xy 372.568924 -246.1042)
			(xy 371.300687 -246.1042) (xy 371.296517 -246.154527) (xy 371.284121 -246.203481) (xy 371.263838 -246.249727)
			(xy 371.236219 -246.292005) (xy 371.202019 -246.329161) (xy 371.162171 -246.360181) (xy 371.11776 -246.38422)
			(xy 371.069999 -246.400622) (xy 371.02019 -246.408939) (xy 370.99494 -246.409464) (xy 370.054886 -246.409464)
			(xy 370.029628 -246.40903) (xy 369.979801 -246.400713) (xy 369.932022 -246.384308) (xy 369.887595 -246.360264)
			(xy 369.847731 -246.329235) (xy 369.813518 -246.292068) (xy 369.785888 -246.249777) (xy 369.765597 -246.203515)
			(xy 369.753196 -246.154544) (xy 369.749024 -246.1042) (xy 368.480616 -246.1042) (xy 368.476445 -246.154538)
			(xy 368.464045 -246.203503) (xy 368.443754 -246.249758) (xy 368.416126 -246.292043) (xy 368.381915 -246.329204)
			(xy 368.342054 -246.360227) (xy 368.29763 -246.384265) (xy 368.249855 -246.400663) (xy 368.200033 -246.408973)
			(xy 368.174778 -246.409464) (xy 367.234724 -246.409464) (xy 367.209461 -246.409061) (xy 367.159625 -246.400748)
			(xy 367.111836 -246.384346) (xy 367.067399 -246.360301) (xy 367.027526 -246.329269) (xy 366.993305 -246.292098)
			(xy 366.965669 -246.249801) (xy 366.945372 -246.203532) (xy 366.932969 -246.154553) (xy 366.928796 -246.1042)
			(xy 365.660716 -246.1042) (xy 365.656545 -246.154539) (xy 365.644144 -246.203504) (xy 365.623853 -246.249761)
			(xy 365.596224 -246.292046) (xy 365.562012 -246.329207) (xy 365.52215 -246.360229) (xy 365.477725 -246.384267)
			(xy 365.429949 -246.400664) (xy 365.380126 -246.408974) (xy 365.35487 -246.409464) (xy 364.414816 -246.409464)
			(xy 364.389554 -246.40906) (xy 364.339718 -246.400747) (xy 364.291931 -246.384343) (xy 364.247495 -246.360298)
			(xy 364.207623 -246.329267) (xy 364.173403 -246.292095) (xy 364.145768 -246.249799) (xy 364.125472 -246.20353)
			(xy 364.113068 -246.154552) (xy 364.108896 -246.1042) (xy 107.387208 -246.1042) (xy 107.387225 -246.1044)
			(xy 107.383049 -246.15479) (xy 107.370636 -246.203805) (xy 107.350323 -246.250109) (xy 107.322666 -246.292437)
			(xy 107.288419 -246.329635) (xy 107.248516 -246.360689) (xy 107.204046 -246.384751) (xy 107.156221 -246.401164)
			(xy 107.106347 -246.409482) (xy 107.081066 -246.409972) (xy 106.141012 -246.409972) (xy 106.115733 -246.40946)
			(xy 106.065866 -246.40114) (xy 106.018047 -246.384726) (xy 105.973583 -246.360665) (xy 105.933686 -246.329613)
			(xy 105.899444 -246.292417) (xy 105.871791 -246.250093) (xy 105.851482 -246.203794) (xy 105.839071 -246.154784)
			(xy 105.834895 -246.1044) (xy 104.567325 -246.1044) (xy 104.563149 -246.154791) (xy 104.550735 -246.203807)
			(xy 104.530422 -246.250111) (xy 104.502764 -246.29244) (xy 104.468516 -246.329638) (xy 104.428612 -246.360692)
			(xy 104.38414 -246.384753) (xy 104.336315 -246.401166) (xy 104.28644 -246.409482) (xy 104.261158 -246.409972)
			(xy 103.321104 -246.409972) (xy 103.295826 -246.409459) (xy 103.245959 -246.401139) (xy 103.198142 -246.384724)
			(xy 103.153679 -246.360662) (xy 103.113783 -246.32961) (xy 103.079542 -246.292415) (xy 103.05189 -246.250091)
			(xy 103.031581 -246.203793) (xy 103.01917 -246.154784) (xy 103.014995 -246.1044) (xy 101.747125 -246.1044)
			(xy 101.742949 -246.154787) (xy 101.730538 -246.203799) (xy 101.710228 -246.2501) (xy 101.682574 -246.292427)
			(xy 101.648331 -246.329625) (xy 101.608432 -246.360679) (xy 101.563966 -246.384742) (xy 101.516146 -246.401158)
			(xy 101.466276 -246.409479) (xy 101.440996 -246.409972) (xy 100.500942 -246.409972) (xy 100.475662 -246.409462)
			(xy 100.42579 -246.401146) (xy 100.377968 -246.384735) (xy 100.333499 -246.360675) (xy 100.293597 -246.329623)
			(xy 100.259351 -246.292427) (xy 100.231695 -246.250101) (xy 100.211384 -246.2038) (xy 100.198971 -246.154788)
			(xy 100.194795 -246.1044) (xy 98.927225 -246.1044) (xy 98.923049 -246.154788) (xy 98.910637 -246.203801)
			(xy 98.890327 -246.250102) (xy 98.862672 -246.29243) (xy 98.828428 -246.329627) (xy 98.788528 -246.360681)
			(xy 98.744061 -246.384744) (xy 98.696239 -246.40116) (xy 98.646368 -246.40948) (xy 98.621088 -246.409972)
			(xy 97.681034 -246.409972) (xy 97.655754 -246.409462) (xy 97.605884 -246.401145) (xy 97.558062 -246.384732)
			(xy 97.513595 -246.360672) (xy 97.473694 -246.329621) (xy 97.439449 -246.292425) (xy 97.411794 -246.250099)
			(xy 97.391483 -246.203799) (xy 97.379071 -246.154787) (xy 97.374895 -246.1044) (xy 2.509012 -246.1044)
			(xy 2.509012 -246.9144) (xy 108.185156 -246.9144) (xy 108.189328 -246.864058) (xy 108.201729 -246.815089)
			(xy 108.222021 -246.768829) (xy 108.249651 -246.72654) (xy 108.283865 -246.689376) (xy 108.32373 -246.658351)
			(xy 108.368157 -246.63431) (xy 108.415936 -246.617911) (xy 108.465763 -246.609599) (xy 108.49102 -246.609108)
			(xy 109.431074 -246.609108) (xy 109.456334 -246.609567) (xy 109.506167 -246.617878) (xy 109.553951 -246.634279)
			(xy 109.598385 -246.658322) (xy 109.638254 -246.68935) (xy 109.672472 -246.726518) (xy 109.700106 -246.768812)
			(xy 109.720401 -246.815077) (xy 109.732804 -246.864052) (xy 109.736959 -246.9142) (xy 361.758647 -246.9142)
			(xy 361.762823 -246.863808) (xy 361.775236 -246.814791) (xy 361.795548 -246.768485) (xy 361.823205 -246.726155)
			(xy 361.857452 -246.688953) (xy 361.897355 -246.657897) (xy 361.941825 -246.633831) (xy 361.989651 -246.617414)
			(xy 362.039526 -246.609093) (xy 362.064808 -246.6086) (xy 363.004862 -246.6086) (xy 363.03014 -246.609166)
			(xy 363.080006 -246.617481) (xy 363.127824 -246.633892) (xy 363.172288 -246.65795) (xy 363.212185 -246.688999)
			(xy 363.246428 -246.726191) (xy 363.274081 -246.768513) (xy 363.29439 -246.81481) (xy 363.306801 -246.863818)
			(xy 363.310977 -246.9142) (xy 363.306801 -246.964582) (xy 363.29439 -247.01359) (xy 363.274081 -247.059887)
			(xy 363.246428 -247.102209) (xy 363.212185 -247.139401) (xy 363.172288 -247.17045) (xy 363.127824 -247.194508)
			(xy 363.080006 -247.210919) (xy 363.03014 -247.219234) (xy 363.004862 -247.219724) (xy 362.064808 -247.219724)
			(xy 362.039526 -247.219307) (xy 361.989651 -247.210986) (xy 361.941825 -247.194569) (xy 361.897355 -247.170503)
			(xy 361.857452 -247.139447) (xy 361.823205 -247.102245) (xy 361.795548 -247.059915) (xy 361.775236 -247.013609)
			(xy 361.762823 -246.964592) (xy 361.758647 -246.9142) (xy 109.736959 -246.9142) (xy 109.736976 -246.9144)
			(xy 109.732804 -246.964748) (xy 109.720401 -247.013723) (xy 109.700106 -247.059988) (xy 109.672472 -247.102282)
			(xy 109.638254 -247.13945) (xy 109.598385 -247.170478) (xy 109.553951 -247.194521) (xy 109.506167 -247.210922)
			(xy 109.456334 -247.219233) (xy 109.431074 -247.219724) (xy 108.49102 -247.219724) (xy 108.465763 -247.219201)
			(xy 108.415936 -247.210889) (xy 108.368157 -247.19449) (xy 108.32373 -247.170449) (xy 108.283865 -247.139424)
			(xy 108.249651 -247.10226) (xy 108.222021 -247.059971) (xy 108.201729 -247.013711) (xy 108.189328 -246.964742)
			(xy 108.185156 -246.9144) (xy 2.509012 -246.9144) (xy 2.509012 -247.7244) (xy 97.374907 -247.7244)
			(xy 97.379083 -247.674015) (xy 97.391495 -247.625005) (xy 97.411805 -247.578707) (xy 97.439459 -247.536383)
			(xy 97.473702 -247.499188) (xy 97.513601 -247.468138) (xy 97.558067 -247.444079) (xy 97.605887 -247.427667)
			(xy 97.655755 -247.41935) (xy 97.681034 -247.41886) (xy 98.621088 -247.41886) (xy 98.646369 -247.419308)
			(xy 98.696242 -247.427629) (xy 98.744066 -247.444045) (xy 98.788534 -247.468109) (xy 98.828436 -247.499164)
			(xy 98.862682 -247.536363) (xy 98.890337 -247.578692) (xy 98.910648 -247.624995) (xy 98.923061 -247.67401)
			(xy 98.927237 -247.7244) (xy 100.194807 -247.7244) (xy 100.198983 -247.674014) (xy 100.211395 -247.625004)
			(xy 100.231706 -247.578704) (xy 100.259361 -247.53638) (xy 100.293605 -247.499185) (xy 100.333506 -247.468135)
			(xy 100.377972 -247.444076) (xy 100.425793 -247.427665) (xy 100.475663 -247.41935) (xy 100.500942 -247.41886)
			(xy 101.440996 -247.41886) (xy 101.466277 -247.419309) (xy 101.516149 -247.42763) (xy 101.563971 -247.444047)
			(xy 101.608439 -247.468111) (xy 101.648339 -247.499167) (xy 101.682584 -247.536366) (xy 101.710238 -247.578694)
			(xy 101.730549 -247.624997) (xy 101.742961 -247.674011) (xy 101.747137 -247.7244) (xy 103.015007 -247.7244)
			(xy 103.019182 -247.674018) (xy 103.031593 -247.625011) (xy 103.0519 -247.578715) (xy 103.079551 -247.536393)
			(xy 103.113791 -247.499199) (xy 103.153685 -247.468148) (xy 103.198147 -247.444087) (xy 103.245962 -247.427673)
			(xy 103.295827 -247.419353) (xy 103.321104 -247.41886) (xy 104.261158 -247.41886) (xy 104.286441 -247.419306)
			(xy 104.336318 -247.427622) (xy 104.384145 -247.444036) (xy 104.428619 -247.468098) (xy 104.468524 -247.499153)
			(xy 104.502774 -247.536353) (xy 104.530433 -247.578683) (xy 104.550746 -247.624989) (xy 104.56316 -247.674007)
			(xy 104.567337 -247.7244) (xy 105.834907 -247.7244) (xy 105.839082 -247.674018) (xy 105.851493 -247.62501)
			(xy 105.871801 -247.578713) (xy 105.899453 -247.53639) (xy 105.933694 -247.499196) (xy 105.97359 -247.468145)
			(xy 106.018052 -247.444085) (xy 106.065869 -247.427671) (xy 106.115734 -247.419352) (xy 106.141012 -247.41886)
			(xy 107.081066 -247.41886) (xy 107.106348 -247.419306) (xy 107.156224 -247.427624) (xy 107.204051 -247.444038)
			(xy 107.248523 -247.468101) (xy 107.288427 -247.499156) (xy 107.322676 -247.536356) (xy 107.350334 -247.578686)
			(xy 107.370647 -247.624991) (xy 107.383061 -247.674008) (xy 107.38722 -247.7242) (xy 364.108908 -247.7242)
			(xy 364.11308 -247.67385) (xy 364.125483 -247.624874) (xy 364.145778 -247.578607) (xy 364.173412 -247.536312)
			(xy 364.207631 -247.499142) (xy 364.247501 -247.468112) (xy 364.291935 -247.444068) (xy 364.339721 -247.427665)
			(xy 364.389555 -247.419352) (xy 364.414816 -247.41886) (xy 365.35487 -247.41886) (xy 365.380127 -247.419414)
			(xy 365.429952 -247.427724) (xy 365.477729 -247.444122) (xy 365.522156 -247.468161) (xy 365.56202 -247.499184)
			(xy 365.596233 -247.536347) (xy 365.623863 -247.578634) (xy 365.644155 -247.624892) (xy 365.656556 -247.673859)
			(xy 365.660728 -247.7242) (xy 366.928808 -247.7242) (xy 366.93298 -247.673849) (xy 366.945384 -247.624872)
			(xy 366.96568 -247.578605) (xy 366.993314 -247.536309) (xy 367.027534 -247.499139) (xy 367.067406 -247.468109)
			(xy 367.111841 -247.444065) (xy 367.159628 -247.427663) (xy 367.209462 -247.419351) (xy 367.234724 -247.41886)
			(xy 368.174778 -247.41886) (xy 368.200034 -247.419415) (xy 368.249858 -247.427726) (xy 368.297635 -247.444124)
			(xy 368.34206 -247.468163) (xy 368.381923 -247.499187) (xy 368.416136 -247.536349) (xy 368.443764 -247.578636)
			(xy 368.464056 -247.624893) (xy 368.476457 -247.67386) (xy 368.480628 -247.7242) (xy 369.749037 -247.7242)
			(xy 369.753208 -247.673858) (xy 369.765609 -247.624889) (xy 369.785899 -247.578629) (xy 369.813527 -247.53634)
			(xy 369.847739 -247.499174) (xy 369.887601 -247.468147) (xy 369.932027 -247.444103) (xy 369.979804 -247.427699)
			(xy 370.029629 -247.419383) (xy 370.054886 -247.41886) (xy 370.99494 -247.41886) (xy 371.020191 -247.419449)
			(xy 371.070002 -247.427767) (xy 371.117765 -247.444169) (xy 371.162177 -247.468209) (xy 371.202028 -247.499231)
			(xy 371.236229 -247.536388) (xy 371.263848 -247.578667) (xy 371.284133 -247.624915) (xy 371.296529 -247.673871)
			(xy 371.300699 -247.7242) (xy 372.568937 -247.7242) (xy 372.573108 -247.673857) (xy 372.585509 -247.624888)
			(xy 372.605801 -247.578627) (xy 372.63343 -247.536337) (xy 372.667642 -247.499171) (xy 372.707506 -247.468144)
			(xy 372.751932 -247.444101) (xy 372.79971 -247.427698) (xy 372.849536 -247.419382) (xy 372.874794 -247.41886)
			(xy 373.814848 -247.41886) (xy 373.840098 -247.419449) (xy 373.889908 -247.427768) (xy 373.93767 -247.444172)
			(xy 373.982082 -247.468212) (xy 374.021931 -247.499233) (xy 374.056131 -247.53639) (xy 374.083749 -247.578669)
			(xy 374.104033 -247.624917) (xy 374.116429 -247.673872) (xy 374.120599 -247.7242) (xy 374.116429 -247.774528)
			(xy 374.104033 -247.823483) (xy 374.083749 -247.869731) (xy 374.056131 -247.91201) (xy 374.021931 -247.949166)
			(xy 373.982082 -247.980188) (xy 373.937671 -248.004228) (xy 373.889908 -248.020632) (xy 373.840098 -248.028951)
			(xy 373.814848 -248.029476) (xy 372.874794 -248.029476) (xy 372.849536 -248.029018) (xy 372.79971 -248.020702)
			(xy 372.751932 -248.004299) (xy 372.707506 -247.980256) (xy 372.667642 -247.949229) (xy 372.63343 -247.912063)
			(xy 372.605801 -247.869773) (xy 372.585509 -247.823512) (xy 372.573108 -247.774543) (xy 372.568937 -247.7242)
			(xy 371.300699 -247.7242) (xy 371.296529 -247.774529) (xy 371.284133 -247.823485) (xy 371.263848 -247.869733)
			(xy 371.236229 -247.912012) (xy 371.202028 -247.949169) (xy 371.162177 -247.980191) (xy 371.117765 -248.004231)
			(xy 371.070002 -248.020633) (xy 371.020191 -248.028951) (xy 370.99494 -248.029476) (xy 370.054886 -248.029476)
			(xy 370.029629 -248.029017) (xy 369.979804 -248.020701) (xy 369.932027 -248.004297) (xy 369.887601 -247.980253)
			(xy 369.847739 -247.949226) (xy 369.813527 -247.91206) (xy 369.785899 -247.869771) (xy 369.765609 -247.823511)
			(xy 369.753208 -247.774542) (xy 369.749037 -247.7242) (xy 368.480628 -247.7242) (xy 368.476457 -247.77454)
			(xy 368.464056 -247.823507) (xy 368.443764 -247.869764) (xy 368.416136 -247.912051) (xy 368.381923 -247.949213)
			(xy 368.34206 -247.980237) (xy 368.297635 -248.004276) (xy 368.249858 -248.020674) (xy 368.200034 -248.028985)
			(xy 368.174778 -248.029476) (xy 367.234724 -248.029476) (xy 367.209462 -248.029049) (xy 367.159628 -248.020737)
			(xy 367.111841 -248.004335) (xy 367.067406 -247.980291) (xy 367.027534 -247.949261) (xy 366.993314 -247.912091)
			(xy 366.96568 -247.869795) (xy 366.945384 -247.823528) (xy 366.93298 -247.774551) (xy 366.928808 -247.7242)
			(xy 365.660728 -247.7242) (xy 365.656556 -247.774541) (xy 365.644155 -247.823508) (xy 365.623863 -247.869766)
			(xy 365.596233 -247.912053) (xy 365.56202 -247.949216) (xy 365.522156 -247.980239) (xy 365.477729 -248.004278)
			(xy 365.429952 -248.020676) (xy 365.380127 -248.028986) (xy 365.35487 -248.029476) (xy 364.414816 -248.029476)
			(xy 364.389555 -248.029048) (xy 364.339721 -248.020735) (xy 364.291935 -248.004332) (xy 364.247501 -247.980288)
			(xy 364.207631 -247.949258) (xy 364.173412 -247.912088) (xy 364.145778 -247.869793) (xy 364.125483 -247.823526)
			(xy 364.11308 -247.77455) (xy 364.108908 -247.7242) (xy 107.38722 -247.7242) (xy 107.387237 -247.7244)
			(xy 107.383061 -247.774792) (xy 107.370647 -247.823809) (xy 107.350334 -247.870114) (xy 107.322676 -247.912444)
			(xy 107.288427 -247.949644) (xy 107.248523 -247.980699) (xy 107.204051 -248.004762) (xy 107.156224 -248.021176)
			(xy 107.106348 -248.029494) (xy 107.081066 -248.029984) (xy 106.141012 -248.029984) (xy 106.115734 -248.029448)
			(xy 106.065869 -248.021129) (xy 106.018052 -248.004715) (xy 105.97359 -247.980655) (xy 105.933694 -247.949604)
			(xy 105.899453 -247.91241) (xy 105.871801 -247.870087) (xy 105.851493 -247.82379) (xy 105.839082 -247.774782)
			(xy 105.834907 -247.7244) (xy 104.567337 -247.7244) (xy 104.56316 -247.774793) (xy 104.550746 -247.823811)
			(xy 104.530433 -247.870117) (xy 104.502774 -247.912447) (xy 104.468524 -247.949647) (xy 104.428619 -247.980702)
			(xy 104.384145 -248.004764) (xy 104.336318 -248.021178) (xy 104.286441 -248.029494) (xy 104.261158 -248.029984)
			(xy 103.321104 -248.029984) (xy 103.295827 -248.029447) (xy 103.245962 -248.021127) (xy 103.198147 -248.004713)
			(xy 103.153685 -247.980652) (xy 103.113791 -247.949601) (xy 103.079551 -247.912407) (xy 103.0519 -247.870085)
			(xy 103.031593 -247.823789) (xy 103.019182 -247.774782) (xy 103.015007 -247.7244) (xy 101.747137 -247.7244)
			(xy 101.742961 -247.774789) (xy 101.730549 -247.823803) (xy 101.710238 -247.870106) (xy 101.682584 -247.912434)
			(xy 101.648339 -247.949633) (xy 101.608439 -247.980689) (xy 101.563971 -248.004753) (xy 101.516149 -248.02117)
			(xy 101.466277 -248.029491) (xy 101.440996 -248.029984) (xy 100.500942 -248.029984) (xy 100.475663 -248.02945)
			(xy 100.425793 -248.021135) (xy 100.377972 -248.004724) (xy 100.333506 -247.980665) (xy 100.293605 -247.949615)
			(xy 100.259361 -247.91242) (xy 100.231706 -247.870096) (xy 100.211395 -247.823796) (xy 100.198983 -247.774786)
			(xy 100.194807 -247.7244) (xy 98.927237 -247.7244) (xy 98.923061 -247.77479) (xy 98.910648 -247.823805)
			(xy 98.890337 -247.870108) (xy 98.862682 -247.912437) (xy 98.828436 -247.949636) (xy 98.788534 -247.980691)
			(xy 98.744066 -248.004755) (xy 98.696242 -248.021171) (xy 98.646369 -248.029492) (xy 98.621088 -248.029984)
			(xy 97.681034 -248.029984) (xy 97.655755 -248.02945) (xy 97.605887 -248.021133) (xy 97.558067 -248.004721)
			(xy 97.513601 -247.980662) (xy 97.473702 -247.949612) (xy 97.439459 -247.912417) (xy 97.411805 -247.870093)
			(xy 97.391495 -247.823795) (xy 97.379083 -247.774785) (xy 97.374907 -247.7244) (xy 2.509012 -247.7244)
			(xy 2.509012 -248.5344) (xy 108.185168 -248.5344) (xy 108.189339 -248.48406) (xy 108.20174 -248.435093)
			(xy 108.222032 -248.388834) (xy 108.249661 -248.346547) (xy 108.283873 -248.309385) (xy 108.323736 -248.278361)
			(xy 108.368162 -248.254321) (xy 108.415939 -248.237922) (xy 108.465764 -248.229611) (xy 108.49102 -248.22912)
			(xy 109.431074 -248.22912) (xy 109.456335 -248.229555) (xy 109.50617 -248.237867) (xy 109.553956 -248.254268)
			(xy 109.598391 -248.278312) (xy 109.638262 -248.309342) (xy 109.672482 -248.346511) (xy 109.700117 -248.388806)
			(xy 109.720412 -248.435073) (xy 109.732816 -248.48405) (xy 109.736971 -248.5342) (xy 361.758659 -248.5342)
			(xy 361.762835 -248.48381) (xy 361.775248 -248.434795) (xy 361.795559 -248.388491) (xy 361.823214 -248.346162)
			(xy 361.85746 -248.308962) (xy 361.897361 -248.277907) (xy 361.94183 -248.253842) (xy 361.989653 -248.237426)
			(xy 362.039527 -248.229104) (xy 362.064808 -248.228612) (xy 363.004862 -248.228612) (xy 363.030141 -248.229154)
			(xy 363.080009 -248.23747) (xy 363.127829 -248.253881) (xy 363.172294 -248.27794) (xy 363.212193 -248.30899)
			(xy 363.246437 -248.346184) (xy 363.274091 -248.388507) (xy 363.294401 -248.434806) (xy 363.306813 -248.483816)
			(xy 363.310989 -248.5342) (xy 363.306813 -248.584584) (xy 363.294401 -248.633594) (xy 363.274091 -248.679893)
			(xy 363.246437 -248.722216) (xy 363.212193 -248.75941) (xy 363.172294 -248.79046) (xy 363.127829 -248.814519)
			(xy 363.080009 -248.83093) (xy 363.030141 -248.839246) (xy 363.004862 -248.839736) (xy 362.064808 -248.839736)
			(xy 362.039527 -248.839296) (xy 361.989653 -248.830974) (xy 361.94183 -248.814558) (xy 361.897361 -248.790493)
			(xy 361.85746 -248.759438) (xy 361.823214 -248.722238) (xy 361.795559 -248.679909) (xy 361.775248 -248.633605)
			(xy 361.762835 -248.58459) (xy 361.758659 -248.5342) (xy 109.736971 -248.5342) (xy 109.736988 -248.5344)
			(xy 109.732816 -248.58475) (xy 109.720412 -248.633727) (xy 109.700117 -248.679994) (xy 109.672482 -248.722289)
			(xy 109.638262 -248.759458) (xy 109.598391 -248.790488) (xy 109.553956 -248.814532) (xy 109.50617 -248.830933)
			(xy 109.456335 -248.839245) (xy 109.431074 -248.839736) (xy 108.49102 -248.839736) (xy 108.465764 -248.839189)
			(xy 108.415939 -248.830878) (xy 108.368162 -248.814479) (xy 108.323736 -248.790439) (xy 108.283873 -248.759415)
			(xy 108.249661 -248.722253) (xy 108.222032 -248.679966) (xy 108.20174 -248.633707) (xy 108.189339 -248.58474)
			(xy 108.185168 -248.5344) (xy 2.509012 -248.5344) (xy 2.509012 -258.880356) (xy 67.312036 -258.880356)
			(xy 67.316066 -258.738021) (xy 67.328141 -258.596141) (xy 67.348224 -258.455173) (xy 67.376251 -258.315566)
			(xy 67.412131 -258.177768) (xy 67.455749 -258.042221) (xy 67.506966 -257.909359) (xy 67.565617 -257.779607)
			(xy 67.631515 -257.653381) (xy 67.704449 -257.531085) (xy 67.784186 -257.413112) (xy 67.870468 -257.299839)
			(xy 67.963021 -257.191628) (xy 68.061548 -257.088827) (xy 68.165733 -256.991765) (xy 68.275242 -256.900753)
			(xy 68.389725 -256.816081) (xy 68.508815 -256.738023) (xy 68.63213 -256.666827) (xy 68.759276 -256.602721)
			(xy 68.889845 -256.545912) (xy 69.023419 -256.49658) (xy 69.15957 -256.454884) (xy 69.297861 -256.420958)
			(xy 69.437851 -256.39491) (xy 69.57909 -256.376824) (xy 69.721126 -256.366757) (xy 69.863504 -256.364742)
			(xy 70.005768 -256.370785) (xy 70.147462 -256.384867) (xy 70.288132 -256.406943) (xy 70.427329 -256.436943)
			(xy 70.564605 -256.474769) (xy 70.699521 -256.520301) (xy 70.831645 -256.573392) (xy 70.960554 -256.633874)
			(xy 71.085835 -256.701552) (xy 71.207086 -256.776209) (xy 71.323919 -256.857607) (xy 71.43596 -256.945484)
			(xy 71.54285 -257.039559) (xy 71.644247 -257.139531) (xy 71.739825 -257.245079) (xy 71.829279 -257.355865)
			(xy 71.912321 -257.471534) (xy 71.988687 -257.591717) (xy 72.058131 -257.716027) (xy 72.120431 -257.844068)
			(xy 72.175387 -257.975427) (xy 72.222824 -258.109686) (xy 72.262588 -258.246413) (xy 72.294554 -258.385171)
			(xy 72.318619 -258.525515) (xy 72.334705 -258.666996) (xy 72.34276 -258.80916) (xy 72.343264 -258.880356)
			(xy 151.51202 -258.880356) (xy 151.51605 -258.738021) (xy 151.528125 -258.596141) (xy 151.548208 -258.455173)
			(xy 151.576235 -258.315566) (xy 151.612115 -258.177768) (xy 151.655733 -258.042221) (xy 151.70695 -257.909359)
			(xy 151.765601 -257.779607) (xy 151.831499 -257.653381) (xy 151.904433 -257.531085) (xy 151.98417 -257.413112)
			(xy 152.070452 -257.299839) (xy 152.163005 -257.191628) (xy 152.261532 -257.088827) (xy 152.365717 -256.991765)
			(xy 152.475226 -256.900753) (xy 152.589709 -256.816081) (xy 152.708799 -256.738023) (xy 152.832114 -256.666827)
			(xy 152.95926 -256.602721) (xy 153.089829 -256.545912) (xy 153.223403 -256.49658) (xy 153.359554 -256.454884)
			(xy 153.497845 -256.420958) (xy 153.637835 -256.39491) (xy 153.779074 -256.376824) (xy 153.92111 -256.366757)
			(xy 154.063488 -256.364742) (xy 154.205752 -256.370785) (xy 154.347446 -256.384867) (xy 154.488116 -256.406943)
			(xy 154.627313 -256.436943) (xy 154.764589 -256.474769) (xy 154.899505 -256.520301) (xy 155.031629 -256.573392)
			(xy 155.160538 -256.633874) (xy 155.285819 -256.701552) (xy 155.40707 -256.776209) (xy 155.523903 -256.857607)
			(xy 155.635944 -256.945484) (xy 155.742834 -257.039559) (xy 155.844231 -257.139531) (xy 155.939809 -257.245079)
			(xy 156.029263 -257.355865) (xy 156.112305 -257.471534) (xy 156.188671 -257.591717) (xy 156.258115 -257.716027)
			(xy 156.320415 -257.844068) (xy 156.375371 -257.975427) (xy 156.422808 -258.109686) (xy 156.462572 -258.246413)
			(xy 156.494538 -258.385171) (xy 156.518603 -258.525515) (xy 156.534689 -258.666996) (xy 156.542744 -258.80916)
			(xy 156.543246 -258.880102) (xy 315.252104 -258.880102) (xy 315.256134 -258.737767) (xy 315.268209 -258.595887)
			(xy 315.288292 -258.454919) (xy 315.316319 -258.315312) (xy 315.352199 -258.177514) (xy 315.395817 -258.041967)
			(xy 315.447034 -257.909105) (xy 315.505685 -257.779353) (xy 315.571583 -257.653127) (xy 315.644517 -257.530831)
			(xy 315.724254 -257.412858) (xy 315.810536 -257.299585) (xy 315.903089 -257.191374) (xy 316.001616 -257.088573)
			(xy 316.105801 -256.991511) (xy 316.21531 -256.900499) (xy 316.329793 -256.815827) (xy 316.448883 -256.737769)
			(xy 316.572198 -256.666573) (xy 316.699344 -256.602467) (xy 316.829913 -256.545658) (xy 316.963487 -256.496326)
			(xy 317.099638 -256.45463) (xy 317.237929 -256.420704) (xy 317.377919 -256.394656) (xy 317.519158 -256.37657)
			(xy 317.661194 -256.366503) (xy 317.803572 -256.364488) (xy 317.945836 -256.370531) (xy 318.08753 -256.384613)
			(xy 318.2282 -256.406689) (xy 318.367397 -256.436689) (xy 318.504673 -256.474515) (xy 318.639589 -256.520047)
			(xy 318.771713 -256.573138) (xy 318.900622 -256.63362) (xy 319.025903 -256.701298) (xy 319.147154 -256.775955)
			(xy 319.263987 -256.857353) (xy 319.376028 -256.94523) (xy 319.482918 -257.039305) (xy 319.584315 -257.139277)
			(xy 319.679893 -257.244825) (xy 319.769347 -257.355611) (xy 319.852389 -257.47128) (xy 319.928755 -257.591463)
			(xy 319.998199 -257.715773) (xy 320.060499 -257.843814) (xy 320.115455 -257.975173) (xy 320.162892 -258.109432)
			(xy 320.202656 -258.246159) (xy 320.234622 -258.384917) (xy 320.258687 -258.525261) (xy 320.274773 -258.666742)
			(xy 320.282828 -258.808906) (xy 320.283332 -258.880102) (xy 399.452088 -258.880102) (xy 399.456118 -258.737767)
			(xy 399.468193 -258.595887) (xy 399.488276 -258.454919) (xy 399.516303 -258.315312) (xy 399.552183 -258.177514)
			(xy 399.595801 -258.041967) (xy 399.647018 -257.909105) (xy 399.705669 -257.779353) (xy 399.771567 -257.653127)
			(xy 399.844501 -257.530831) (xy 399.924238 -257.412858) (xy 400.01052 -257.299585) (xy 400.103073 -257.191374)
			(xy 400.2016 -257.088573) (xy 400.305785 -256.991511) (xy 400.415294 -256.900499) (xy 400.529777 -256.815827)
			(xy 400.648867 -256.737769) (xy 400.772182 -256.666573) (xy 400.899328 -256.602467) (xy 401.029897 -256.545658)
			(xy 401.163471 -256.496326) (xy 401.299622 -256.45463) (xy 401.437913 -256.420704) (xy 401.577903 -256.394656)
			(xy 401.719142 -256.37657) (xy 401.861178 -256.366503) (xy 402.003556 -256.364488) (xy 402.14582 -256.370531)
			(xy 402.287514 -256.384613) (xy 402.428184 -256.406689) (xy 402.567381 -256.436689) (xy 402.704657 -256.474515)
			(xy 402.839573 -256.520047) (xy 402.971697 -256.573138) (xy 403.100606 -256.63362) (xy 403.225887 -256.701298)
			(xy 403.347138 -256.775955) (xy 403.463971 -256.857353) (xy 403.576012 -256.94523) (xy 403.682902 -257.039305)
			(xy 403.784299 -257.139277) (xy 403.879877 -257.244825) (xy 403.969331 -257.355611) (xy 404.052373 -257.47128)
			(xy 404.128739 -257.591463) (xy 404.198183 -257.715773) (xy 404.260483 -257.843814) (xy 404.315439 -257.975173)
			(xy 404.362876 -258.109432) (xy 404.40264 -258.246159) (xy 404.434606 -258.384917) (xy 404.458671 -258.525261)
			(xy 404.474757 -258.666742) (xy 404.482812 -258.808906) (xy 404.483316 -258.880102) (xy 404.482812 -258.951298)
			(xy 404.474757 -259.093462) (xy 404.458671 -259.234943) (xy 404.434606 -259.375287) (xy 404.40264 -259.514045)
			(xy 404.362876 -259.650772) (xy 404.315439 -259.785031) (xy 404.260483 -259.91639) (xy 404.198183 -260.044431)
			(xy 404.128739 -260.168741) (xy 404.052373 -260.288924) (xy 403.969331 -260.404593) (xy 403.879877 -260.515379)
			(xy 403.784299 -260.620927) (xy 403.682902 -260.720899) (xy 403.576012 -260.814974) (xy 403.463971 -260.902851)
			(xy 403.347138 -260.984249) (xy 403.225887 -261.058906) (xy 403.100606 -261.126584) (xy 402.971697 -261.187066)
			(xy 402.839573 -261.240157) (xy 402.704657 -261.285689) (xy 402.567381 -261.323515) (xy 402.428184 -261.353515)
			(xy 402.287514 -261.375591) (xy 402.14582 -261.389673) (xy 402.003556 -261.395716) (xy 401.861178 -261.393701)
			(xy 401.719142 -261.383634) (xy 401.577903 -261.365548) (xy 401.437913 -261.3395) (xy 401.299622 -261.305574)
			(xy 401.163471 -261.263878) (xy 401.029897 -261.214546) (xy 400.899328 -261.157737) (xy 400.772182 -261.093631)
			(xy 400.648867 -261.022435) (xy 400.529777 -260.944377) (xy 400.415294 -260.859705) (xy 400.305785 -260.768693)
			(xy 400.2016 -260.671631) (xy 400.103073 -260.56883) (xy 400.01052 -260.460619) (xy 399.924238 -260.347346)
			(xy 399.844501 -260.229373) (xy 399.771567 -260.107077) (xy 399.705669 -259.980851) (xy 399.647018 -259.851099)
			(xy 399.595801 -259.718237) (xy 399.552183 -259.58269) (xy 399.516303 -259.444892) (xy 399.488276 -259.305285)
			(xy 399.468193 -259.164317) (xy 399.456118 -259.022437) (xy 399.452088 -258.880102) (xy 320.283332 -258.880102)
			(xy 320.282828 -258.951298) (xy 320.274773 -259.093462) (xy 320.258687 -259.234943) (xy 320.234622 -259.375287)
			(xy 320.202656 -259.514045) (xy 320.162892 -259.650772) (xy 320.115455 -259.785031) (xy 320.060499 -259.91639)
			(xy 319.998199 -260.044431) (xy 319.928755 -260.168741) (xy 319.852389 -260.288924) (xy 319.769347 -260.404593)
			(xy 319.679893 -260.515379) (xy 319.584315 -260.620927) (xy 319.482918 -260.720899) (xy 319.376028 -260.814974)
			(xy 319.263987 -260.902851) (xy 319.147154 -260.984249) (xy 319.025903 -261.058906) (xy 318.900622 -261.126584)
			(xy 318.771713 -261.187066) (xy 318.639589 -261.240157) (xy 318.504673 -261.285689) (xy 318.367397 -261.323515)
			(xy 318.2282 -261.353515) (xy 318.08753 -261.375591) (xy 317.945836 -261.389673) (xy 317.803572 -261.395716)
			(xy 317.661194 -261.393701) (xy 317.519158 -261.383634) (xy 317.377919 -261.365548) (xy 317.237929 -261.3395)
			(xy 317.099638 -261.305574) (xy 316.963487 -261.263878) (xy 316.829913 -261.214546) (xy 316.699344 -261.157737)
			(xy 316.572198 -261.093631) (xy 316.448883 -261.022435) (xy 316.329793 -260.944377) (xy 316.21531 -260.859705)
			(xy 316.105801 -260.768693) (xy 316.001616 -260.671631) (xy 315.903089 -260.56883) (xy 315.810536 -260.460619)
			(xy 315.724254 -260.347346) (xy 315.644517 -260.229373) (xy 315.571583 -260.107077) (xy 315.505685 -259.980851)
			(xy 315.447034 -259.851099) (xy 315.395817 -259.718237) (xy 315.352199 -259.58269) (xy 315.316319 -259.444892)
			(xy 315.288292 -259.305285) (xy 315.268209 -259.164317) (xy 315.256134 -259.022437) (xy 315.252104 -258.880102)
			(xy 156.543246 -258.880102) (xy 156.543248 -258.880356) (xy 156.542744 -258.951552) (xy 156.534689 -259.093716)
			(xy 156.518603 -259.235197) (xy 156.494538 -259.375541) (xy 156.462572 -259.514299) (xy 156.422808 -259.651026)
			(xy 156.375371 -259.785285) (xy 156.320415 -259.916644) (xy 156.258115 -260.044685) (xy 156.188671 -260.168995)
			(xy 156.112305 -260.289178) (xy 156.029263 -260.404847) (xy 155.939809 -260.515633) (xy 155.844231 -260.621181)
			(xy 155.742834 -260.721153) (xy 155.635944 -260.815228) (xy 155.523903 -260.903105) (xy 155.40707 -260.984503)
			(xy 155.285819 -261.05916) (xy 155.160538 -261.126838) (xy 155.031629 -261.18732) (xy 154.899505 -261.240411)
			(xy 154.764589 -261.285943) (xy 154.627313 -261.323769) (xy 154.488116 -261.353769) (xy 154.347446 -261.375845)
			(xy 154.205752 -261.389927) (xy 154.063488 -261.39597) (xy 153.92111 -261.393955) (xy 153.779074 -261.383888)
			(xy 153.637835 -261.365802) (xy 153.497845 -261.339754) (xy 153.359554 -261.305828) (xy 153.223403 -261.264132)
			(xy 153.089829 -261.2148) (xy 152.95926 -261.157991) (xy 152.832114 -261.093885) (xy 152.708799 -261.022689)
			(xy 152.589709 -260.944631) (xy 152.475226 -260.859959) (xy 152.365717 -260.768947) (xy 152.261532 -260.671885)
			(xy 152.163005 -260.569084) (xy 152.070452 -260.460873) (xy 151.98417 -260.3476) (xy 151.904433 -260.229627)
			(xy 151.831499 -260.107331) (xy 151.765601 -259.981105) (xy 151.70695 -259.851353) (xy 151.655733 -259.718491)
			(xy 151.612115 -259.582944) (xy 151.576235 -259.445146) (xy 151.548208 -259.305539) (xy 151.528125 -259.164571)
			(xy 151.51605 -259.022691) (xy 151.51202 -258.880356) (xy 72.343264 -258.880356) (xy 72.34276 -258.951552)
			(xy 72.334705 -259.093716) (xy 72.318619 -259.235197) (xy 72.294554 -259.375541) (xy 72.262588 -259.514299)
			(xy 72.222824 -259.651026) (xy 72.175387 -259.785285) (xy 72.120431 -259.916644) (xy 72.058131 -260.044685)
			(xy 71.988687 -260.168995) (xy 71.912321 -260.289178) (xy 71.829279 -260.404847) (xy 71.739825 -260.515633)
			(xy 71.644247 -260.621181) (xy 71.54285 -260.721153) (xy 71.43596 -260.815228) (xy 71.323919 -260.903105)
			(xy 71.207086 -260.984503) (xy 71.085835 -261.05916) (xy 70.960554 -261.126838) (xy 70.831645 -261.18732)
			(xy 70.699521 -261.240411) (xy 70.564605 -261.285943) (xy 70.427329 -261.323769) (xy 70.288132 -261.353769)
			(xy 70.147462 -261.375845) (xy 70.005768 -261.389927) (xy 69.863504 -261.39597) (xy 69.721126 -261.393955)
			(xy 69.57909 -261.383888) (xy 69.437851 -261.365802) (xy 69.297861 -261.339754) (xy 69.15957 -261.305828)
			(xy 69.023419 -261.264132) (xy 68.889845 -261.2148) (xy 68.759276 -261.157991) (xy 68.63213 -261.093885)
			(xy 68.508815 -261.022689) (xy 68.389725 -260.944631) (xy 68.275242 -260.859959) (xy 68.165733 -260.768947)
			(xy 68.061548 -260.671885) (xy 67.963021 -260.569084) (xy 67.870468 -260.460873) (xy 67.784186 -260.3476)
			(xy 67.704449 -260.229627) (xy 67.631515 -260.107331) (xy 67.565617 -259.981105) (xy 67.506966 -259.851353)
			(xy 67.455749 -259.718491) (xy 67.412131 -259.582944) (xy 67.376251 -259.445146) (xy 67.348224 -259.305539)
			(xy 67.328141 -259.164571) (xy 67.316066 -259.022691) (xy 67.312036 -258.880356) (xy 2.509012 -258.880356)
			(xy 2.509012 -269.226284) (xy 108.485698 -269.226284) (xy 108.489652 -269.177311) (xy 108.50141 -269.129607)
			(xy 108.520668 -269.084406) (xy 108.546927 -269.04288) (xy 108.579508 -269.006104) (xy 108.617566 -268.97503)
			(xy 108.660116 -268.950464) (xy 108.706055 -268.933042) (xy 108.754195 -268.923214) (xy 108.803287 -268.921236)
			(xy 108.852061 -268.927158) (xy 108.899253 -268.940827) (xy 108.943642 -268.96189) (xy 108.984077 -268.9898)
			(xy 109.019511 -269.023835) (xy 109.049027 -269.063114) (xy 109.07186 -269.106618) (xy 109.087419 -269.153222)
			(xy 109.0953 -269.201718) (xy 109.095794 -269.226284) (xy 109.425752 -269.226284) (xy 109.429706 -269.177311)
			(xy 109.441464 -269.129607) (xy 109.460722 -269.084406) (xy 109.486981 -269.04288) (xy 109.519562 -269.006104)
			(xy 109.55762 -268.97503) (xy 109.60017 -268.950464) (xy 109.646109 -268.933042) (xy 109.694249 -268.923214)
			(xy 109.743341 -268.921236) (xy 109.792115 -268.927158) (xy 109.839307 -268.940827) (xy 109.883696 -268.96189)
			(xy 109.924131 -268.9898) (xy 109.959565 -269.023835) (xy 109.989081 -269.063114) (xy 110.011914 -269.106618)
			(xy 110.027473 -269.153222) (xy 110.035354 -269.201718) (xy 110.035848 -269.226284) (xy 114.119418 -269.226284)
			(xy 114.123372 -269.177311) (xy 114.13513 -269.129607) (xy 114.154388 -269.084406) (xy 114.180647 -269.04288)
			(xy 114.213228 -269.006104) (xy 114.251286 -268.97503) (xy 114.293836 -268.950464) (xy 114.339775 -268.933042)
			(xy 114.387915 -268.923214) (xy 114.437007 -268.921236) (xy 114.485781 -268.927158) (xy 114.532973 -268.940827)
			(xy 114.577362 -268.96189) (xy 114.617797 -268.9898) (xy 114.653231 -269.023835) (xy 114.682747 -269.063114)
			(xy 114.70558 -269.106618) (xy 114.721139 -269.153222) (xy 114.72902 -269.201718) (xy 114.729514 -269.226284)
			(xy 115.059472 -269.226284) (xy 115.063426 -269.177311) (xy 115.075184 -269.129607) (xy 115.094442 -269.084406)
			(xy 115.120701 -269.04288) (xy 115.153282 -269.006104) (xy 115.19134 -268.97503) (xy 115.23389 -268.950464)
			(xy 115.279829 -268.933042) (xy 115.327969 -268.923214) (xy 115.377061 -268.921236) (xy 115.425835 -268.927158)
			(xy 115.473027 -268.940827) (xy 115.517416 -268.96189) (xy 115.557851 -268.9898) (xy 115.593285 -269.023835)
			(xy 115.622801 -269.063114) (xy 115.645634 -269.106618) (xy 115.661193 -269.153222) (xy 115.669074 -269.201718)
			(xy 115.669563 -269.22603) (xy 356.425766 -269.22603) (xy 356.42972 -269.177057) (xy 356.441478 -269.129353)
			(xy 356.460736 -269.084152) (xy 356.486995 -269.042626) (xy 356.519576 -269.00585) (xy 356.557634 -268.974776)
			(xy 356.600184 -268.95021) (xy 356.646123 -268.932788) (xy 356.694263 -268.92296) (xy 356.743355 -268.920982)
			(xy 356.792129 -268.926904) (xy 356.839321 -268.940573) (xy 356.88371 -268.961636) (xy 356.924145 -268.989546)
			(xy 356.959579 -269.023581) (xy 356.989095 -269.06286) (xy 357.011928 -269.106364) (xy 357.027487 -269.152968)
			(xy 357.035368 -269.201464) (xy 357.035862 -269.22603) (xy 357.36582 -269.22603) (xy 357.369774 -269.177057)
			(xy 357.381532 -269.129353) (xy 357.40079 -269.084152) (xy 357.427049 -269.042626) (xy 357.45963 -269.00585)
			(xy 357.497688 -268.974776) (xy 357.540238 -268.95021) (xy 357.586177 -268.932788) (xy 357.634317 -268.92296)
			(xy 357.683409 -268.920982) (xy 357.732183 -268.926904) (xy 357.779375 -268.940573) (xy 357.823764 -268.961636)
			(xy 357.864199 -268.989546) (xy 357.899633 -269.023581) (xy 357.929149 -269.06286) (xy 357.951982 -269.106364)
			(xy 357.967541 -269.152968) (xy 357.975422 -269.201464) (xy 357.975916 -269.22603) (xy 362.059486 -269.22603)
			(xy 362.06344 -269.177057) (xy 362.075198 -269.129353) (xy 362.094456 -269.084152) (xy 362.120715 -269.042626)
			(xy 362.153296 -269.00585) (xy 362.191354 -268.974776) (xy 362.233904 -268.95021) (xy 362.279843 -268.932788)
			(xy 362.327983 -268.92296) (xy 362.377075 -268.920982) (xy 362.425849 -268.926904) (xy 362.473041 -268.940573)
			(xy 362.51743 -268.961636) (xy 362.557865 -268.989546) (xy 362.593299 -269.023581) (xy 362.622815 -269.06286)
			(xy 362.645648 -269.106364) (xy 362.661207 -269.152968) (xy 362.669088 -269.201464) (xy 362.669582 -269.22603)
			(xy 362.99954 -269.22603) (xy 363.003494 -269.177057) (xy 363.015252 -269.129353) (xy 363.03451 -269.084152)
			(xy 363.060769 -269.042626) (xy 363.09335 -269.00585) (xy 363.131408 -268.974776) (xy 363.173958 -268.95021)
			(xy 363.219897 -268.932788) (xy 363.268037 -268.92296) (xy 363.317129 -268.920982) (xy 363.365903 -268.926904)
			(xy 363.413095 -268.940573) (xy 363.457484 -268.961636) (xy 363.497919 -268.989546) (xy 363.533353 -269.023581)
			(xy 363.562869 -269.06286) (xy 363.585702 -269.106364) (xy 363.601261 -269.152968) (xy 363.609142 -269.201464)
			(xy 363.609636 -269.22603) (xy 363.609142 -269.250596) (xy 363.601261 -269.299092) (xy 363.585702 -269.345696)
			(xy 363.562869 -269.3892) (xy 363.533353 -269.428479) (xy 363.497919 -269.462514) (xy 363.457484 -269.490424)
			(xy 363.413095 -269.511487) (xy 363.365903 -269.525156) (xy 363.317129 -269.531078) (xy 363.268037 -269.5291)
			(xy 363.219897 -269.519272) (xy 363.173958 -269.50185) (xy 363.131408 -269.477284) (xy 363.09335 -269.44621)
			(xy 363.060769 -269.409434) (xy 363.03451 -269.367908) (xy 363.015252 -269.322707) (xy 363.003494 -269.275003)
			(xy 362.99954 -269.22603) (xy 362.669582 -269.22603) (xy 362.669088 -269.250596) (xy 362.661207 -269.299092)
			(xy 362.645648 -269.345696) (xy 362.622815 -269.3892) (xy 362.593299 -269.428479) (xy 362.557865 -269.462514)
			(xy 362.51743 -269.490424) (xy 362.473041 -269.511487) (xy 362.425849 -269.525156) (xy 362.377075 -269.531078)
			(xy 362.327983 -269.5291) (xy 362.279843 -269.519272) (xy 362.233904 -269.50185) (xy 362.191354 -269.477284)
			(xy 362.153296 -269.44621) (xy 362.120715 -269.409434) (xy 362.094456 -269.367908) (xy 362.075198 -269.322707)
			(xy 362.06344 -269.275003) (xy 362.059486 -269.22603) (xy 357.975916 -269.22603) (xy 357.975422 -269.250596)
			(xy 357.967541 -269.299092) (xy 357.951982 -269.345696) (xy 357.929149 -269.3892) (xy 357.899633 -269.428479)
			(xy 357.864199 -269.462514) (xy 357.823764 -269.490424) (xy 357.779375 -269.511487) (xy 357.732183 -269.525156)
			(xy 357.683409 -269.531078) (xy 357.634317 -269.5291) (xy 357.586177 -269.519272) (xy 357.540238 -269.50185)
			(xy 357.497688 -269.477284) (xy 357.45963 -269.44621) (xy 357.427049 -269.409434) (xy 357.40079 -269.367908)
			(xy 357.381532 -269.322707) (xy 357.369774 -269.275003) (xy 357.36582 -269.22603) (xy 357.035862 -269.22603)
			(xy 357.035368 -269.250596) (xy 357.027487 -269.299092) (xy 357.011928 -269.345696) (xy 356.989095 -269.3892)
			(xy 356.959579 -269.428479) (xy 356.924145 -269.462514) (xy 356.88371 -269.490424) (xy 356.839321 -269.511487)
			(xy 356.792129 -269.525156) (xy 356.743355 -269.531078) (xy 356.694263 -269.5291) (xy 356.646123 -269.519272)
			(xy 356.600184 -269.50185) (xy 356.557634 -269.477284) (xy 356.519576 -269.44621) (xy 356.486995 -269.409434)
			(xy 356.460736 -269.367908) (xy 356.441478 -269.322707) (xy 356.42972 -269.275003) (xy 356.425766 -269.22603)
			(xy 115.669563 -269.22603) (xy 115.669568 -269.226284) (xy 115.669074 -269.25085) (xy 115.661193 -269.299346)
			(xy 115.645634 -269.34595) (xy 115.622801 -269.389454) (xy 115.593285 -269.428733) (xy 115.557851 -269.462768)
			(xy 115.517416 -269.490678) (xy 115.473027 -269.511741) (xy 115.425835 -269.52541) (xy 115.377061 -269.531332)
			(xy 115.327969 -269.529354) (xy 115.279829 -269.519526) (xy 115.23389 -269.502104) (xy 115.19134 -269.477538)
			(xy 115.153282 -269.446464) (xy 115.120701 -269.409688) (xy 115.094442 -269.368162) (xy 115.075184 -269.322961)
			(xy 115.063426 -269.275257) (xy 115.059472 -269.226284) (xy 114.729514 -269.226284) (xy 114.72902 -269.25085)
			(xy 114.721139 -269.299346) (xy 114.70558 -269.34595) (xy 114.682747 -269.389454) (xy 114.653231 -269.428733)
			(xy 114.617797 -269.462768) (xy 114.577362 -269.490678) (xy 114.532973 -269.511741) (xy 114.485781 -269.52541)
			(xy 114.437007 -269.531332) (xy 114.387915 -269.529354) (xy 114.339775 -269.519526) (xy 114.293836 -269.502104)
			(xy 114.251286 -269.477538) (xy 114.213228 -269.446464) (xy 114.180647 -269.409688) (xy 114.154388 -269.368162)
			(xy 114.13513 -269.322961) (xy 114.123372 -269.275257) (xy 114.119418 -269.226284) (xy 110.035848 -269.226284)
			(xy 110.035354 -269.25085) (xy 110.027473 -269.299346) (xy 110.011914 -269.34595) (xy 109.989081 -269.389454)
			(xy 109.959565 -269.428733) (xy 109.924131 -269.462768) (xy 109.883696 -269.490678) (xy 109.839307 -269.511741)
			(xy 109.792115 -269.52541) (xy 109.743341 -269.531332) (xy 109.694249 -269.529354) (xy 109.646109 -269.519526)
			(xy 109.60017 -269.502104) (xy 109.55762 -269.477538) (xy 109.519562 -269.446464) (xy 109.486981 -269.409688)
			(xy 109.460722 -269.368162) (xy 109.441464 -269.322961) (xy 109.429706 -269.275257) (xy 109.425752 -269.226284)
			(xy 109.095794 -269.226284) (xy 109.0953 -269.25085) (xy 109.087419 -269.299346) (xy 109.07186 -269.34595)
			(xy 109.049027 -269.389454) (xy 109.019511 -269.428733) (xy 108.984077 -269.462768) (xy 108.943642 -269.490678)
			(xy 108.899253 -269.511741) (xy 108.852061 -269.52541) (xy 108.803287 -269.531332) (xy 108.754195 -269.529354)
			(xy 108.706055 -269.519526) (xy 108.660116 -269.502104) (xy 108.617566 -269.477538) (xy 108.579508 -269.446464)
			(xy 108.546927 -269.409688) (xy 108.520668 -269.368162) (xy 108.50141 -269.322961) (xy 108.489652 -269.275257)
			(xy 108.485698 -269.226284) (xy 2.509012 -269.226284) (xy 2.509012 -270.03629) (xy 97.675712 -270.03629)
			(xy 97.679666 -269.987317) (xy 97.691424 -269.939613) (xy 97.710682 -269.894412) (xy 97.736941 -269.852886)
			(xy 97.769522 -269.81611) (xy 97.80758 -269.785036) (xy 97.85013 -269.76047) (xy 97.896069 -269.743048)
			(xy 97.944209 -269.73322) (xy 97.993301 -269.731242) (xy 98.042075 -269.737164) (xy 98.089267 -269.750833)
			(xy 98.133656 -269.771896) (xy 98.174091 -269.799806) (xy 98.209525 -269.833841) (xy 98.239041 -269.87312)
			(xy 98.261874 -269.916624) (xy 98.277433 -269.963228) (xy 98.285314 -270.011724) (xy 98.285808 -270.03629)
			(xy 98.615766 -270.03629) (xy 98.61972 -269.987317) (xy 98.631478 -269.939613) (xy 98.650736 -269.894412)
			(xy 98.676995 -269.852886) (xy 98.709576 -269.81611) (xy 98.747634 -269.785036) (xy 98.790184 -269.76047)
			(xy 98.836123 -269.743048) (xy 98.884263 -269.73322) (xy 98.933355 -269.731242) (xy 98.982129 -269.737164)
			(xy 99.029321 -269.750833) (xy 99.07371 -269.771896) (xy 99.114145 -269.799806) (xy 99.149579 -269.833841)
			(xy 99.179095 -269.87312) (xy 99.201928 -269.916624) (xy 99.217487 -269.963228) (xy 99.225368 -270.011724)
			(xy 99.225862 -270.03629) (xy 100.49562 -270.03629) (xy 100.499574 -269.987317) (xy 100.511332 -269.939613)
			(xy 100.53059 -269.894412) (xy 100.556849 -269.852886) (xy 100.58943 -269.81611) (xy 100.627488 -269.785036)
			(xy 100.670038 -269.76047) (xy 100.715977 -269.743048) (xy 100.764117 -269.73322) (xy 100.813209 -269.731242)
			(xy 100.861983 -269.737164) (xy 100.909175 -269.750833) (xy 100.953564 -269.771896) (xy 100.993999 -269.799806)
			(xy 101.029433 -269.833841) (xy 101.058949 -269.87312) (xy 101.081782 -269.916624) (xy 101.097341 -269.963228)
			(xy 101.105222 -270.011724) (xy 101.105716 -270.03629) (xy 101.435674 -270.03629) (xy 101.439628 -269.987317)
			(xy 101.451386 -269.939613) (xy 101.470644 -269.894412) (xy 101.496903 -269.852886) (xy 101.529484 -269.81611)
			(xy 101.567542 -269.785036) (xy 101.610092 -269.76047) (xy 101.656031 -269.743048) (xy 101.704171 -269.73322)
			(xy 101.753263 -269.731242) (xy 101.802037 -269.737164) (xy 101.849229 -269.750833) (xy 101.893618 -269.771896)
			(xy 101.934053 -269.799806) (xy 101.969487 -269.833841) (xy 101.999003 -269.87312) (xy 102.021836 -269.916624)
			(xy 102.037395 -269.963228) (xy 102.045276 -270.011724) (xy 102.04577 -270.03629) (xy 103.315782 -270.03629)
			(xy 103.319736 -269.987317) (xy 103.331494 -269.939613) (xy 103.350752 -269.894412) (xy 103.377011 -269.852886)
			(xy 103.409592 -269.81611) (xy 103.44765 -269.785036) (xy 103.4902 -269.76047) (xy 103.536139 -269.743048)
			(xy 103.584279 -269.73322) (xy 103.633371 -269.731242) (xy 103.682145 -269.737164) (xy 103.729337 -269.750833)
			(xy 103.773726 -269.771896) (xy 103.814161 -269.799806) (xy 103.849595 -269.833841) (xy 103.879111 -269.87312)
			(xy 103.901944 -269.916624) (xy 103.917503 -269.963228) (xy 103.925384 -270.011724) (xy 103.925878 -270.03629)
			(xy 104.255836 -270.03629) (xy 104.25979 -269.987317) (xy 104.271548 -269.939613) (xy 104.290806 -269.894412)
			(xy 104.317065 -269.852886) (xy 104.349646 -269.81611) (xy 104.387704 -269.785036) (xy 104.430254 -269.76047)
			(xy 104.476193 -269.743048) (xy 104.524333 -269.73322) (xy 104.573425 -269.731242) (xy 104.622199 -269.737164)
			(xy 104.669391 -269.750833) (xy 104.71378 -269.771896) (xy 104.754215 -269.799806) (xy 104.789649 -269.833841)
			(xy 104.819165 -269.87312) (xy 104.841998 -269.916624) (xy 104.857557 -269.963228) (xy 104.865438 -270.011724)
			(xy 104.865932 -270.03629) (xy 106.13569 -270.03629) (xy 106.139644 -269.987317) (xy 106.151402 -269.939613)
			(xy 106.17066 -269.894412) (xy 106.196919 -269.852886) (xy 106.2295 -269.81611) (xy 106.267558 -269.785036)
			(xy 106.310108 -269.76047) (xy 106.356047 -269.743048) (xy 106.404187 -269.73322) (xy 106.453279 -269.731242)
			(xy 106.502053 -269.737164) (xy 106.549245 -269.750833) (xy 106.593634 -269.771896) (xy 106.634069 -269.799806)
			(xy 106.669503 -269.833841) (xy 106.699019 -269.87312) (xy 106.721852 -269.916624) (xy 106.737411 -269.963228)
			(xy 106.745292 -270.011724) (xy 106.745786 -270.03629) (xy 107.075744 -270.03629) (xy 107.079698 -269.987317)
			(xy 107.091456 -269.939613) (xy 107.110714 -269.894412) (xy 107.136973 -269.852886) (xy 107.169554 -269.81611)
			(xy 107.207612 -269.785036) (xy 107.250162 -269.76047) (xy 107.296101 -269.743048) (xy 107.344241 -269.73322)
			(xy 107.393333 -269.731242) (xy 107.442107 -269.737164) (xy 107.489299 -269.750833) (xy 107.533688 -269.771896)
			(xy 107.574123 -269.799806) (xy 107.609557 -269.833841) (xy 107.639073 -269.87312) (xy 107.661906 -269.916624)
			(xy 107.677465 -269.963228) (xy 107.685346 -270.011724) (xy 107.68584 -270.03629) (xy 116.469426 -270.03629)
			(xy 116.47338 -269.987317) (xy 116.485138 -269.939613) (xy 116.504396 -269.894412) (xy 116.530655 -269.852886)
			(xy 116.563236 -269.81611) (xy 116.601294 -269.785036) (xy 116.643844 -269.76047) (xy 116.689783 -269.743048)
			(xy 116.737923 -269.73322) (xy 116.787015 -269.731242) (xy 116.835789 -269.737164) (xy 116.882981 -269.750833)
			(xy 116.92737 -269.771896) (xy 116.967805 -269.799806) (xy 117.003239 -269.833841) (xy 117.032755 -269.87312)
			(xy 117.055588 -269.916624) (xy 117.071147 -269.963228) (xy 117.079028 -270.011724) (xy 117.079522 -270.03629)
			(xy 117.40948 -270.03629) (xy 117.413434 -269.987317) (xy 117.425192 -269.939613) (xy 117.44445 -269.894412)
			(xy 117.470709 -269.852886) (xy 117.50329 -269.81611) (xy 117.541348 -269.785036) (xy 117.583898 -269.76047)
			(xy 117.629837 -269.743048) (xy 117.677977 -269.73322) (xy 117.727069 -269.731242) (xy 117.775843 -269.737164)
			(xy 117.823035 -269.750833) (xy 117.867424 -269.771896) (xy 117.907859 -269.799806) (xy 117.943293 -269.833841)
			(xy 117.972809 -269.87312) (xy 117.995642 -269.916624) (xy 118.011201 -269.963228) (xy 118.019082 -270.011724)
			(xy 118.019576 -270.03629) (xy 119.289334 -270.03629) (xy 119.293288 -269.987317) (xy 119.305046 -269.939613)
			(xy 119.324304 -269.894412) (xy 119.350563 -269.852886) (xy 119.383144 -269.81611) (xy 119.421202 -269.785036)
			(xy 119.463752 -269.76047) (xy 119.509691 -269.743048) (xy 119.557831 -269.73322) (xy 119.606923 -269.731242)
			(xy 119.655697 -269.737164) (xy 119.702889 -269.750833) (xy 119.747278 -269.771896) (xy 119.787713 -269.799806)
			(xy 119.823147 -269.833841) (xy 119.852663 -269.87312) (xy 119.875496 -269.916624) (xy 119.891055 -269.963228)
			(xy 119.898936 -270.011724) (xy 119.89943 -270.03629) (xy 120.229388 -270.03629) (xy 120.233342 -269.987317)
			(xy 120.2451 -269.939613) (xy 120.264358 -269.894412) (xy 120.290617 -269.852886) (xy 120.323198 -269.81611)
			(xy 120.361256 -269.785036) (xy 120.403806 -269.76047) (xy 120.449745 -269.743048) (xy 120.497885 -269.73322)
			(xy 120.546977 -269.731242) (xy 120.595751 -269.737164) (xy 120.642943 -269.750833) (xy 120.687332 -269.771896)
			(xy 120.727767 -269.799806) (xy 120.763201 -269.833841) (xy 120.792717 -269.87312) (xy 120.81555 -269.916624)
			(xy 120.831109 -269.963228) (xy 120.83899 -270.011724) (xy 120.839484 -270.03629) (xy 122.109242 -270.03629)
			(xy 122.113196 -269.987317) (xy 122.124954 -269.939613) (xy 122.144212 -269.894412) (xy 122.170471 -269.852886)
			(xy 122.203052 -269.81611) (xy 122.24111 -269.785036) (xy 122.28366 -269.76047) (xy 122.329599 -269.743048)
			(xy 122.377739 -269.73322) (xy 122.426831 -269.731242) (xy 122.475605 -269.737164) (xy 122.522797 -269.750833)
			(xy 122.567186 -269.771896) (xy 122.607621 -269.799806) (xy 122.643055 -269.833841) (xy 122.672571 -269.87312)
			(xy 122.695404 -269.916624) (xy 122.710963 -269.963228) (xy 122.718844 -270.011724) (xy 122.719338 -270.03629)
			(xy 123.049296 -270.03629) (xy 123.05325 -269.987317) (xy 123.065008 -269.939613) (xy 123.084266 -269.894412)
			(xy 123.110525 -269.852886) (xy 123.143106 -269.81611) (xy 123.181164 -269.785036) (xy 123.223714 -269.76047)
			(xy 123.269653 -269.743048) (xy 123.317793 -269.73322) (xy 123.366885 -269.731242) (xy 123.415659 -269.737164)
			(xy 123.462851 -269.750833) (xy 123.50724 -269.771896) (xy 123.547675 -269.799806) (xy 123.583109 -269.833841)
			(xy 123.612625 -269.87312) (xy 123.635458 -269.916624) (xy 123.651017 -269.963228) (xy 123.658898 -270.011724)
			(xy 123.659392 -270.03629) (xy 124.929404 -270.03629) (xy 124.933358 -269.987317) (xy 124.945116 -269.939613)
			(xy 124.964374 -269.894412) (xy 124.990633 -269.852886) (xy 125.023214 -269.81611) (xy 125.061272 -269.785036)
			(xy 125.103822 -269.76047) (xy 125.149761 -269.743048) (xy 125.197901 -269.73322) (xy 125.246993 -269.731242)
			(xy 125.295767 -269.737164) (xy 125.342959 -269.750833) (xy 125.387348 -269.771896) (xy 125.427783 -269.799806)
			(xy 125.463217 -269.833841) (xy 125.492733 -269.87312) (xy 125.515566 -269.916624) (xy 125.531125 -269.963228)
			(xy 125.539006 -270.011724) (xy 125.5395 -270.03629) (xy 125.869458 -270.03629) (xy 125.873412 -269.987317)
			(xy 125.88517 -269.939613) (xy 125.904428 -269.894412) (xy 125.930687 -269.852886) (xy 125.963268 -269.81611)
			(xy 126.001326 -269.785036) (xy 126.043876 -269.76047) (xy 126.089815 -269.743048) (xy 126.137955 -269.73322)
			(xy 126.187047 -269.731242) (xy 126.235821 -269.737164) (xy 126.283013 -269.750833) (xy 126.327402 -269.771896)
			(xy 126.367837 -269.799806) (xy 126.403271 -269.833841) (xy 126.432787 -269.87312) (xy 126.45562 -269.916624)
			(xy 126.471179 -269.963228) (xy 126.47906 -270.011724) (xy 126.479549 -270.036036) (xy 345.61578 -270.036036)
			(xy 345.619734 -269.987063) (xy 345.631492 -269.939359) (xy 345.65075 -269.894158) (xy 345.677009 -269.852632)
			(xy 345.70959 -269.815856) (xy 345.747648 -269.784782) (xy 345.790198 -269.760216) (xy 345.836137 -269.742794)
			(xy 345.884277 -269.732966) (xy 345.933369 -269.730988) (xy 345.982143 -269.73691) (xy 346.029335 -269.750579)
			(xy 346.073724 -269.771642) (xy 346.114159 -269.799552) (xy 346.149593 -269.833587) (xy 346.179109 -269.872866)
			(xy 346.201942 -269.91637) (xy 346.217501 -269.962974) (xy 346.225382 -270.01147) (xy 346.225876 -270.036036)
			(xy 346.555834 -270.036036) (xy 346.559788 -269.987063) (xy 346.571546 -269.939359) (xy 346.590804 -269.894158)
			(xy 346.617063 -269.852632) (xy 346.649644 -269.815856) (xy 346.687702 -269.784782) (xy 346.730252 -269.760216)
			(xy 346.776191 -269.742794) (xy 346.824331 -269.732966) (xy 346.873423 -269.730988) (xy 346.922197 -269.73691)
			(xy 346.969389 -269.750579) (xy 347.013778 -269.771642) (xy 347.054213 -269.799552) (xy 347.089647 -269.833587)
			(xy 347.119163 -269.872866) (xy 347.141996 -269.91637) (xy 347.157555 -269.962974) (xy 347.165436 -270.01147)
			(xy 347.16593 -270.036036) (xy 348.435688 -270.036036) (xy 348.439642 -269.987063) (xy 348.4514 -269.939359)
			(xy 348.470658 -269.894158) (xy 348.496917 -269.852632) (xy 348.529498 -269.815856) (xy 348.567556 -269.784782)
			(xy 348.610106 -269.760216) (xy 348.656045 -269.742794) (xy 348.704185 -269.732966) (xy 348.753277 -269.730988)
			(xy 348.802051 -269.73691) (xy 348.849243 -269.750579) (xy 348.893632 -269.771642) (xy 348.934067 -269.799552)
			(xy 348.969501 -269.833587) (xy 348.999017 -269.872866) (xy 349.02185 -269.91637) (xy 349.037409 -269.962974)
			(xy 349.04529 -270.01147) (xy 349.045784 -270.036036) (xy 349.375742 -270.036036) (xy 349.379696 -269.987063)
			(xy 349.391454 -269.939359) (xy 349.410712 -269.894158) (xy 349.436971 -269.852632) (xy 349.469552 -269.815856)
			(xy 349.50761 -269.784782) (xy 349.55016 -269.760216) (xy 349.596099 -269.742794) (xy 349.644239 -269.732966)
			(xy 349.693331 -269.730988) (xy 349.742105 -269.73691) (xy 349.789297 -269.750579) (xy 349.833686 -269.771642)
			(xy 349.874121 -269.799552) (xy 349.909555 -269.833587) (xy 349.939071 -269.872866) (xy 349.961904 -269.91637)
			(xy 349.977463 -269.962974) (xy 349.985344 -270.01147) (xy 349.985838 -270.036036) (xy 351.25585 -270.036036)
			(xy 351.259804 -269.987063) (xy 351.271562 -269.939359) (xy 351.29082 -269.894158) (xy 351.317079 -269.852632)
			(xy 351.34966 -269.815856) (xy 351.387718 -269.784782) (xy 351.430268 -269.760216) (xy 351.476207 -269.742794)
			(xy 351.524347 -269.732966) (xy 351.573439 -269.730988) (xy 351.622213 -269.73691) (xy 351.669405 -269.750579)
			(xy 351.713794 -269.771642) (xy 351.754229 -269.799552) (xy 351.789663 -269.833587) (xy 351.819179 -269.872866)
			(xy 351.842012 -269.91637) (xy 351.857571 -269.962974) (xy 351.865452 -270.01147) (xy 351.865946 -270.036036)
			(xy 352.195904 -270.036036) (xy 352.199858 -269.987063) (xy 352.211616 -269.939359) (xy 352.230874 -269.894158)
			(xy 352.257133 -269.852632) (xy 352.289714 -269.815856) (xy 352.327772 -269.784782) (xy 352.370322 -269.760216)
			(xy 352.416261 -269.742794) (xy 352.464401 -269.732966) (xy 352.513493 -269.730988) (xy 352.562267 -269.73691)
			(xy 352.609459 -269.750579) (xy 352.653848 -269.771642) (xy 352.694283 -269.799552) (xy 352.729717 -269.833587)
			(xy 352.759233 -269.872866) (xy 352.782066 -269.91637) (xy 352.797625 -269.962974) (xy 352.805506 -270.01147)
			(xy 352.806 -270.036036) (xy 354.075758 -270.036036) (xy 354.079712 -269.987063) (xy 354.09147 -269.939359)
			(xy 354.110728 -269.894158) (xy 354.136987 -269.852632) (xy 354.169568 -269.815856) (xy 354.207626 -269.784782)
			(xy 354.250176 -269.760216) (xy 354.296115 -269.742794) (xy 354.344255 -269.732966) (xy 354.393347 -269.730988)
			(xy 354.442121 -269.73691) (xy 354.489313 -269.750579) (xy 354.533702 -269.771642) (xy 354.574137 -269.799552)
			(xy 354.609571 -269.833587) (xy 354.639087 -269.872866) (xy 354.66192 -269.91637) (xy 354.677479 -269.962974)
			(xy 354.68536 -270.01147) (xy 354.685854 -270.036036) (xy 355.015812 -270.036036) (xy 355.019766 -269.987063)
			(xy 355.031524 -269.939359) (xy 355.050782 -269.894158) (xy 355.077041 -269.852632) (xy 355.109622 -269.815856)
			(xy 355.14768 -269.784782) (xy 355.19023 -269.760216) (xy 355.236169 -269.742794) (xy 355.284309 -269.732966)
			(xy 355.333401 -269.730988) (xy 355.382175 -269.73691) (xy 355.429367 -269.750579) (xy 355.473756 -269.771642)
			(xy 355.514191 -269.799552) (xy 355.549625 -269.833587) (xy 355.579141 -269.872866) (xy 355.601974 -269.91637)
			(xy 355.617533 -269.962974) (xy 355.625414 -270.01147) (xy 355.625908 -270.036036) (xy 364.409494 -270.036036)
			(xy 364.413448 -269.987063) (xy 364.425206 -269.939359) (xy 364.444464 -269.894158) (xy 364.470723 -269.852632)
			(xy 364.503304 -269.815856) (xy 364.541362 -269.784782) (xy 364.583912 -269.760216) (xy 364.629851 -269.742794)
			(xy 364.677991 -269.732966) (xy 364.727083 -269.730988) (xy 364.775857 -269.73691) (xy 364.823049 -269.750579)
			(xy 364.867438 -269.771642) (xy 364.907873 -269.799552) (xy 364.943307 -269.833587) (xy 364.972823 -269.872866)
			(xy 364.995656 -269.91637) (xy 365.011215 -269.962974) (xy 365.019096 -270.01147) (xy 365.01959 -270.036036)
			(xy 365.349548 -270.036036) (xy 365.353502 -269.987063) (xy 365.36526 -269.939359) (xy 365.384518 -269.894158)
			(xy 365.410777 -269.852632) (xy 365.443358 -269.815856) (xy 365.481416 -269.784782) (xy 365.523966 -269.760216)
			(xy 365.569905 -269.742794) (xy 365.618045 -269.732966) (xy 365.667137 -269.730988) (xy 365.715911 -269.73691)
			(xy 365.763103 -269.750579) (xy 365.807492 -269.771642) (xy 365.847927 -269.799552) (xy 365.883361 -269.833587)
			(xy 365.912877 -269.872866) (xy 365.93571 -269.91637) (xy 365.951269 -269.962974) (xy 365.95915 -270.01147)
			(xy 365.959644 -270.036036) (xy 367.229402 -270.036036) (xy 367.233356 -269.987063) (xy 367.245114 -269.939359)
			(xy 367.264372 -269.894158) (xy 367.290631 -269.852632) (xy 367.323212 -269.815856) (xy 367.36127 -269.784782)
			(xy 367.40382 -269.760216) (xy 367.449759 -269.742794) (xy 367.497899 -269.732966) (xy 367.546991 -269.730988)
			(xy 367.595765 -269.73691) (xy 367.642957 -269.750579) (xy 367.687346 -269.771642) (xy 367.727781 -269.799552)
			(xy 367.763215 -269.833587) (xy 367.792731 -269.872866) (xy 367.815564 -269.91637) (xy 367.831123 -269.962974)
			(xy 367.839004 -270.01147) (xy 367.839498 -270.036036) (xy 368.169456 -270.036036) (xy 368.17341 -269.987063)
			(xy 368.185168 -269.939359) (xy 368.204426 -269.894158) (xy 368.230685 -269.852632) (xy 368.263266 -269.815856)
			(xy 368.301324 -269.784782) (xy 368.343874 -269.760216) (xy 368.389813 -269.742794) (xy 368.437953 -269.732966)
			(xy 368.487045 -269.730988) (xy 368.535819 -269.73691) (xy 368.583011 -269.750579) (xy 368.6274 -269.771642)
			(xy 368.667835 -269.799552) (xy 368.703269 -269.833587) (xy 368.732785 -269.872866) (xy 368.755618 -269.91637)
			(xy 368.771177 -269.962974) (xy 368.779058 -270.01147) (xy 368.779552 -270.036036) (xy 370.04931 -270.036036)
			(xy 370.053264 -269.987063) (xy 370.065022 -269.939359) (xy 370.08428 -269.894158) (xy 370.110539 -269.852632)
			(xy 370.14312 -269.815856) (xy 370.181178 -269.784782) (xy 370.223728 -269.760216) (xy 370.269667 -269.742794)
			(xy 370.317807 -269.732966) (xy 370.366899 -269.730988) (xy 370.415673 -269.73691) (xy 370.462865 -269.750579)
			(xy 370.507254 -269.771642) (xy 370.547689 -269.799552) (xy 370.583123 -269.833587) (xy 370.612639 -269.872866)
			(xy 370.635472 -269.91637) (xy 370.651031 -269.962974) (xy 370.658912 -270.01147) (xy 370.659406 -270.036036)
			(xy 370.989364 -270.036036) (xy 370.993318 -269.987063) (xy 371.005076 -269.939359) (xy 371.024334 -269.894158)
			(xy 371.050593 -269.852632) (xy 371.083174 -269.815856) (xy 371.121232 -269.784782) (xy 371.163782 -269.760216)
			(xy 371.209721 -269.742794) (xy 371.257861 -269.732966) (xy 371.306953 -269.730988) (xy 371.355727 -269.73691)
			(xy 371.402919 -269.750579) (xy 371.447308 -269.771642) (xy 371.487743 -269.799552) (xy 371.523177 -269.833587)
			(xy 371.552693 -269.872866) (xy 371.575526 -269.91637) (xy 371.591085 -269.962974) (xy 371.598966 -270.01147)
			(xy 371.59946 -270.036036) (xy 372.869472 -270.036036) (xy 372.873426 -269.987063) (xy 372.885184 -269.939359)
			(xy 372.904442 -269.894158) (xy 372.930701 -269.852632) (xy 372.963282 -269.815856) (xy 373.00134 -269.784782)
			(xy 373.04389 -269.760216) (xy 373.089829 -269.742794) (xy 373.137969 -269.732966) (xy 373.187061 -269.730988)
			(xy 373.235835 -269.73691) (xy 373.283027 -269.750579) (xy 373.327416 -269.771642) (xy 373.367851 -269.799552)
			(xy 373.403285 -269.833587) (xy 373.432801 -269.872866) (xy 373.455634 -269.91637) (xy 373.471193 -269.962974)
			(xy 373.479074 -270.01147) (xy 373.479568 -270.036036) (xy 373.809526 -270.036036) (xy 373.81348 -269.987063)
			(xy 373.825238 -269.939359) (xy 373.844496 -269.894158) (xy 373.870755 -269.852632) (xy 373.903336 -269.815856)
			(xy 373.941394 -269.784782) (xy 373.983944 -269.760216) (xy 374.029883 -269.742794) (xy 374.078023 -269.732966)
			(xy 374.127115 -269.730988) (xy 374.175889 -269.73691) (xy 374.223081 -269.750579) (xy 374.26747 -269.771642)
			(xy 374.307905 -269.799552) (xy 374.343339 -269.833587) (xy 374.372855 -269.872866) (xy 374.395688 -269.91637)
			(xy 374.411247 -269.962974) (xy 374.419128 -270.01147) (xy 374.419622 -270.036036) (xy 374.419128 -270.060602)
			(xy 374.411247 -270.109098) (xy 374.395688 -270.155702) (xy 374.372855 -270.199206) (xy 374.343339 -270.238485)
			(xy 374.307905 -270.27252) (xy 374.26747 -270.30043) (xy 374.223081 -270.321493) (xy 374.175889 -270.335162)
			(xy 374.127115 -270.341084) (xy 374.078023 -270.339106) (xy 374.029883 -270.329278) (xy 373.983944 -270.311856)
			(xy 373.941394 -270.28729) (xy 373.903336 -270.256216) (xy 373.870755 -270.21944) (xy 373.844496 -270.177914)
			(xy 373.825238 -270.132713) (xy 373.81348 -270.085009) (xy 373.809526 -270.036036) (xy 373.479568 -270.036036)
			(xy 373.479074 -270.060602) (xy 373.471193 -270.109098) (xy 373.455634 -270.155702) (xy 373.432801 -270.199206)
			(xy 373.403285 -270.238485) (xy 373.367851 -270.27252) (xy 373.327416 -270.30043) (xy 373.283027 -270.321493)
			(xy 373.235835 -270.335162) (xy 373.187061 -270.341084) (xy 373.137969 -270.339106) (xy 373.089829 -270.329278)
			(xy 373.04389 -270.311856) (xy 373.00134 -270.28729) (xy 372.963282 -270.256216) (xy 372.930701 -270.21944)
			(xy 372.904442 -270.177914) (xy 372.885184 -270.132713) (xy 372.873426 -270.085009) (xy 372.869472 -270.036036)
			(xy 371.59946 -270.036036) (xy 371.598966 -270.060602) (xy 371.591085 -270.109098) (xy 371.575526 -270.155702)
			(xy 371.552693 -270.199206) (xy 371.523177 -270.238485) (xy 371.487743 -270.27252) (xy 371.447308 -270.30043)
			(xy 371.402919 -270.321493) (xy 371.355727 -270.335162) (xy 371.306953 -270.341084) (xy 371.257861 -270.339106)
			(xy 371.209721 -270.329278) (xy 371.163782 -270.311856) (xy 371.121232 -270.28729) (xy 371.083174 -270.256216)
			(xy 371.050593 -270.21944) (xy 371.024334 -270.177914) (xy 371.005076 -270.132713) (xy 370.993318 -270.085009)
			(xy 370.989364 -270.036036) (xy 370.659406 -270.036036) (xy 370.658912 -270.060602) (xy 370.651031 -270.109098)
			(xy 370.635472 -270.155702) (xy 370.612639 -270.199206) (xy 370.583123 -270.238485) (xy 370.547689 -270.27252)
			(xy 370.507254 -270.30043) (xy 370.462865 -270.321493) (xy 370.415673 -270.335162) (xy 370.366899 -270.341084)
			(xy 370.317807 -270.339106) (xy 370.269667 -270.329278) (xy 370.223728 -270.311856) (xy 370.181178 -270.28729)
			(xy 370.14312 -270.256216) (xy 370.110539 -270.21944) (xy 370.08428 -270.177914) (xy 370.065022 -270.132713)
			(xy 370.053264 -270.085009) (xy 370.04931 -270.036036) (xy 368.779552 -270.036036) (xy 368.779058 -270.060602)
			(xy 368.771177 -270.109098) (xy 368.755618 -270.155702) (xy 368.732785 -270.199206) (xy 368.703269 -270.238485)
			(xy 368.667835 -270.27252) (xy 368.6274 -270.30043) (xy 368.583011 -270.321493) (xy 368.535819 -270.335162)
			(xy 368.487045 -270.341084) (xy 368.437953 -270.339106) (xy 368.389813 -270.329278) (xy 368.343874 -270.311856)
			(xy 368.301324 -270.28729) (xy 368.263266 -270.256216) (xy 368.230685 -270.21944) (xy 368.204426 -270.177914)
			(xy 368.185168 -270.132713) (xy 368.17341 -270.085009) (xy 368.169456 -270.036036) (xy 367.839498 -270.036036)
			(xy 367.839004 -270.060602) (xy 367.831123 -270.109098) (xy 367.815564 -270.155702) (xy 367.792731 -270.199206)
			(xy 367.763215 -270.238485) (xy 367.727781 -270.27252) (xy 367.687346 -270.30043) (xy 367.642957 -270.321493)
			(xy 367.595765 -270.335162) (xy 367.546991 -270.341084) (xy 367.497899 -270.339106) (xy 367.449759 -270.329278)
			(xy 367.40382 -270.311856) (xy 367.36127 -270.28729) (xy 367.323212 -270.256216) (xy 367.290631 -270.21944)
			(xy 367.264372 -270.177914) (xy 367.245114 -270.132713) (xy 367.233356 -270.085009) (xy 367.229402 -270.036036)
			(xy 365.959644 -270.036036) (xy 365.95915 -270.060602) (xy 365.951269 -270.109098) (xy 365.93571 -270.155702)
			(xy 365.912877 -270.199206) (xy 365.883361 -270.238485) (xy 365.847927 -270.27252) (xy 365.807492 -270.30043)
			(xy 365.763103 -270.321493) (xy 365.715911 -270.335162) (xy 365.667137 -270.341084) (xy 365.618045 -270.339106)
			(xy 365.569905 -270.329278) (xy 365.523966 -270.311856) (xy 365.481416 -270.28729) (xy 365.443358 -270.256216)
			(xy 365.410777 -270.21944) (xy 365.384518 -270.177914) (xy 365.36526 -270.132713) (xy 365.353502 -270.085009)
			(xy 365.349548 -270.036036) (xy 365.01959 -270.036036) (xy 365.019096 -270.060602) (xy 365.011215 -270.109098)
			(xy 364.995656 -270.155702) (xy 364.972823 -270.199206) (xy 364.943307 -270.238485) (xy 364.907873 -270.27252)
			(xy 364.867438 -270.30043) (xy 364.823049 -270.321493) (xy 364.775857 -270.335162) (xy 364.727083 -270.341084)
			(xy 364.677991 -270.339106) (xy 364.629851 -270.329278) (xy 364.583912 -270.311856) (xy 364.541362 -270.28729)
			(xy 364.503304 -270.256216) (xy 364.470723 -270.21944) (xy 364.444464 -270.177914) (xy 364.425206 -270.132713)
			(xy 364.413448 -270.085009) (xy 364.409494 -270.036036) (xy 355.625908 -270.036036) (xy 355.625414 -270.060602)
			(xy 355.617533 -270.109098) (xy 355.601974 -270.155702) (xy 355.579141 -270.199206) (xy 355.549625 -270.238485)
			(xy 355.514191 -270.27252) (xy 355.473756 -270.30043) (xy 355.429367 -270.321493) (xy 355.382175 -270.335162)
			(xy 355.333401 -270.341084) (xy 355.284309 -270.339106) (xy 355.236169 -270.329278) (xy 355.19023 -270.311856)
			(xy 355.14768 -270.28729) (xy 355.109622 -270.256216) (xy 355.077041 -270.21944) (xy 355.050782 -270.177914)
			(xy 355.031524 -270.132713) (xy 355.019766 -270.085009) (xy 355.015812 -270.036036) (xy 354.685854 -270.036036)
			(xy 354.68536 -270.060602) (xy 354.677479 -270.109098) (xy 354.66192 -270.155702) (xy 354.639087 -270.199206)
			(xy 354.609571 -270.238485) (xy 354.574137 -270.27252) (xy 354.533702 -270.30043) (xy 354.489313 -270.321493)
			(xy 354.442121 -270.335162) (xy 354.393347 -270.341084) (xy 354.344255 -270.339106) (xy 354.296115 -270.329278)
			(xy 354.250176 -270.311856) (xy 354.207626 -270.28729) (xy 354.169568 -270.256216) (xy 354.136987 -270.21944)
			(xy 354.110728 -270.177914) (xy 354.09147 -270.132713) (xy 354.079712 -270.085009) (xy 354.075758 -270.036036)
			(xy 352.806 -270.036036) (xy 352.805506 -270.060602) (xy 352.797625 -270.109098) (xy 352.782066 -270.155702)
			(xy 352.759233 -270.199206) (xy 352.729717 -270.238485) (xy 352.694283 -270.27252) (xy 352.653848 -270.30043)
			(xy 352.609459 -270.321493) (xy 352.562267 -270.335162) (xy 352.513493 -270.341084) (xy 352.464401 -270.339106)
			(xy 352.416261 -270.329278) (xy 352.370322 -270.311856) (xy 352.327772 -270.28729) (xy 352.289714 -270.256216)
			(xy 352.257133 -270.21944) (xy 352.230874 -270.177914) (xy 352.211616 -270.132713) (xy 352.199858 -270.085009)
			(xy 352.195904 -270.036036) (xy 351.865946 -270.036036) (xy 351.865452 -270.060602) (xy 351.857571 -270.109098)
			(xy 351.842012 -270.155702) (xy 351.819179 -270.199206) (xy 351.789663 -270.238485) (xy 351.754229 -270.27252)
			(xy 351.713794 -270.30043) (xy 351.669405 -270.321493) (xy 351.622213 -270.335162) (xy 351.573439 -270.341084)
			(xy 351.524347 -270.339106) (xy 351.476207 -270.329278) (xy 351.430268 -270.311856) (xy 351.387718 -270.28729)
			(xy 351.34966 -270.256216) (xy 351.317079 -270.21944) (xy 351.29082 -270.177914) (xy 351.271562 -270.132713)
			(xy 351.259804 -270.085009) (xy 351.25585 -270.036036) (xy 349.985838 -270.036036) (xy 349.985344 -270.060602)
			(xy 349.977463 -270.109098) (xy 349.961904 -270.155702) (xy 349.939071 -270.199206) (xy 349.909555 -270.238485)
			(xy 349.874121 -270.27252) (xy 349.833686 -270.30043) (xy 349.789297 -270.321493) (xy 349.742105 -270.335162)
			(xy 349.693331 -270.341084) (xy 349.644239 -270.339106) (xy 349.596099 -270.329278) (xy 349.55016 -270.311856)
			(xy 349.50761 -270.28729) (xy 349.469552 -270.256216) (xy 349.436971 -270.21944) (xy 349.410712 -270.177914)
			(xy 349.391454 -270.132713) (xy 349.379696 -270.085009) (xy 349.375742 -270.036036) (xy 349.045784 -270.036036)
			(xy 349.04529 -270.060602) (xy 349.037409 -270.109098) (xy 349.02185 -270.155702) (xy 348.999017 -270.199206)
			(xy 348.969501 -270.238485) (xy 348.934067 -270.27252) (xy 348.893632 -270.30043) (xy 348.849243 -270.321493)
			(xy 348.802051 -270.335162) (xy 348.753277 -270.341084) (xy 348.704185 -270.339106) (xy 348.656045 -270.329278)
			(xy 348.610106 -270.311856) (xy 348.567556 -270.28729) (xy 348.529498 -270.256216) (xy 348.496917 -270.21944)
			(xy 348.470658 -270.177914) (xy 348.4514 -270.132713) (xy 348.439642 -270.085009) (xy 348.435688 -270.036036)
			(xy 347.16593 -270.036036) (xy 347.165436 -270.060602) (xy 347.157555 -270.109098) (xy 347.141996 -270.155702)
			(xy 347.119163 -270.199206) (xy 347.089647 -270.238485) (xy 347.054213 -270.27252) (xy 347.013778 -270.30043)
			(xy 346.969389 -270.321493) (xy 346.922197 -270.335162) (xy 346.873423 -270.341084) (xy 346.824331 -270.339106)
			(xy 346.776191 -270.329278) (xy 346.730252 -270.311856) (xy 346.687702 -270.28729) (xy 346.649644 -270.256216)
			(xy 346.617063 -270.21944) (xy 346.590804 -270.177914) (xy 346.571546 -270.132713) (xy 346.559788 -270.085009)
			(xy 346.555834 -270.036036) (xy 346.225876 -270.036036) (xy 346.225382 -270.060602) (xy 346.217501 -270.109098)
			(xy 346.201942 -270.155702) (xy 346.179109 -270.199206) (xy 346.149593 -270.238485) (xy 346.114159 -270.27252)
			(xy 346.073724 -270.30043) (xy 346.029335 -270.321493) (xy 345.982143 -270.335162) (xy 345.933369 -270.341084)
			(xy 345.884277 -270.339106) (xy 345.836137 -270.329278) (xy 345.790198 -270.311856) (xy 345.747648 -270.28729)
			(xy 345.70959 -270.256216) (xy 345.677009 -270.21944) (xy 345.65075 -270.177914) (xy 345.631492 -270.132713)
			(xy 345.619734 -270.085009) (xy 345.61578 -270.036036) (xy 126.479549 -270.036036) (xy 126.479554 -270.03629)
			(xy 126.47906 -270.060856) (xy 126.471179 -270.109352) (xy 126.45562 -270.155956) (xy 126.432787 -270.19946)
			(xy 126.403271 -270.238739) (xy 126.367837 -270.272774) (xy 126.327402 -270.300684) (xy 126.283013 -270.321747)
			(xy 126.235821 -270.335416) (xy 126.187047 -270.341338) (xy 126.137955 -270.33936) (xy 126.089815 -270.329532)
			(xy 126.043876 -270.31211) (xy 126.001326 -270.287544) (xy 125.963268 -270.25647) (xy 125.930687 -270.219694)
			(xy 125.904428 -270.178168) (xy 125.88517 -270.132967) (xy 125.873412 -270.085263) (xy 125.869458 -270.03629)
			(xy 125.5395 -270.03629) (xy 125.539006 -270.060856) (xy 125.531125 -270.109352) (xy 125.515566 -270.155956)
			(xy 125.492733 -270.19946) (xy 125.463217 -270.238739) (xy 125.427783 -270.272774) (xy 125.387348 -270.300684)
			(xy 125.342959 -270.321747) (xy 125.295767 -270.335416) (xy 125.246993 -270.341338) (xy 125.197901 -270.33936)
			(xy 125.149761 -270.329532) (xy 125.103822 -270.31211) (xy 125.061272 -270.287544) (xy 125.023214 -270.25647)
			(xy 124.990633 -270.219694) (xy 124.964374 -270.178168) (xy 124.945116 -270.132967) (xy 124.933358 -270.085263)
			(xy 124.929404 -270.03629) (xy 123.659392 -270.03629) (xy 123.658898 -270.060856) (xy 123.651017 -270.109352)
			(xy 123.635458 -270.155956) (xy 123.612625 -270.19946) (xy 123.583109 -270.238739) (xy 123.547675 -270.272774)
			(xy 123.50724 -270.300684) (xy 123.462851 -270.321747) (xy 123.415659 -270.335416) (xy 123.366885 -270.341338)
			(xy 123.317793 -270.33936) (xy 123.269653 -270.329532) (xy 123.223714 -270.31211) (xy 123.181164 -270.287544)
			(xy 123.143106 -270.25647) (xy 123.110525 -270.219694) (xy 123.084266 -270.178168) (xy 123.065008 -270.132967)
			(xy 123.05325 -270.085263) (xy 123.049296 -270.03629) (xy 122.719338 -270.03629) (xy 122.718844 -270.060856)
			(xy 122.710963 -270.109352) (xy 122.695404 -270.155956) (xy 122.672571 -270.19946) (xy 122.643055 -270.238739)
			(xy 122.607621 -270.272774) (xy 122.567186 -270.300684) (xy 122.522797 -270.321747) (xy 122.475605 -270.335416)
			(xy 122.426831 -270.341338) (xy 122.377739 -270.33936) (xy 122.329599 -270.329532) (xy 122.28366 -270.31211)
			(xy 122.24111 -270.287544) (xy 122.203052 -270.25647) (xy 122.170471 -270.219694) (xy 122.144212 -270.178168)
			(xy 122.124954 -270.132967) (xy 122.113196 -270.085263) (xy 122.109242 -270.03629) (xy 120.839484 -270.03629)
			(xy 120.83899 -270.060856) (xy 120.831109 -270.109352) (xy 120.81555 -270.155956) (xy 120.792717 -270.19946)
			(xy 120.763201 -270.238739) (xy 120.727767 -270.272774) (xy 120.687332 -270.300684) (xy 120.642943 -270.321747)
			(xy 120.595751 -270.335416) (xy 120.546977 -270.341338) (xy 120.497885 -270.33936) (xy 120.449745 -270.329532)
			(xy 120.403806 -270.31211) (xy 120.361256 -270.287544) (xy 120.323198 -270.25647) (xy 120.290617 -270.219694)
			(xy 120.264358 -270.178168) (xy 120.2451 -270.132967) (xy 120.233342 -270.085263) (xy 120.229388 -270.03629)
			(xy 119.89943 -270.03629) (xy 119.898936 -270.060856) (xy 119.891055 -270.109352) (xy 119.875496 -270.155956)
			(xy 119.852663 -270.19946) (xy 119.823147 -270.238739) (xy 119.787713 -270.272774) (xy 119.747278 -270.300684)
			(xy 119.702889 -270.321747) (xy 119.655697 -270.335416) (xy 119.606923 -270.341338) (xy 119.557831 -270.33936)
			(xy 119.509691 -270.329532) (xy 119.463752 -270.31211) (xy 119.421202 -270.287544) (xy 119.383144 -270.25647)
			(xy 119.350563 -270.219694) (xy 119.324304 -270.178168) (xy 119.305046 -270.132967) (xy 119.293288 -270.085263)
			(xy 119.289334 -270.03629) (xy 118.019576 -270.03629) (xy 118.019082 -270.060856) (xy 118.011201 -270.109352)
			(xy 117.995642 -270.155956) (xy 117.972809 -270.19946) (xy 117.943293 -270.238739) (xy 117.907859 -270.272774)
			(xy 117.867424 -270.300684) (xy 117.823035 -270.321747) (xy 117.775843 -270.335416) (xy 117.727069 -270.341338)
			(xy 117.677977 -270.33936) (xy 117.629837 -270.329532) (xy 117.583898 -270.31211) (xy 117.541348 -270.287544)
			(xy 117.50329 -270.25647) (xy 117.470709 -270.219694) (xy 117.44445 -270.178168) (xy 117.425192 -270.132967)
			(xy 117.413434 -270.085263) (xy 117.40948 -270.03629) (xy 117.079522 -270.03629) (xy 117.079028 -270.060856)
			(xy 117.071147 -270.109352) (xy 117.055588 -270.155956) (xy 117.032755 -270.19946) (xy 117.003239 -270.238739)
			(xy 116.967805 -270.272774) (xy 116.92737 -270.300684) (xy 116.882981 -270.321747) (xy 116.835789 -270.335416)
			(xy 116.787015 -270.341338) (xy 116.737923 -270.33936) (xy 116.689783 -270.329532) (xy 116.643844 -270.31211)
			(xy 116.601294 -270.287544) (xy 116.563236 -270.25647) (xy 116.530655 -270.219694) (xy 116.504396 -270.178168)
			(xy 116.485138 -270.132967) (xy 116.47338 -270.085263) (xy 116.469426 -270.03629) (xy 107.68584 -270.03629)
			(xy 107.685346 -270.060856) (xy 107.677465 -270.109352) (xy 107.661906 -270.155956) (xy 107.639073 -270.19946)
			(xy 107.609557 -270.238739) (xy 107.574123 -270.272774) (xy 107.533688 -270.300684) (xy 107.489299 -270.321747)
			(xy 107.442107 -270.335416) (xy 107.393333 -270.341338) (xy 107.344241 -270.33936) (xy 107.296101 -270.329532)
			(xy 107.250162 -270.31211) (xy 107.207612 -270.287544) (xy 107.169554 -270.25647) (xy 107.136973 -270.219694)
			(xy 107.110714 -270.178168) (xy 107.091456 -270.132967) (xy 107.079698 -270.085263) (xy 107.075744 -270.03629)
			(xy 106.745786 -270.03629) (xy 106.745292 -270.060856) (xy 106.737411 -270.109352) (xy 106.721852 -270.155956)
			(xy 106.699019 -270.19946) (xy 106.669503 -270.238739) (xy 106.634069 -270.272774) (xy 106.593634 -270.300684)
			(xy 106.549245 -270.321747) (xy 106.502053 -270.335416) (xy 106.453279 -270.341338) (xy 106.404187 -270.33936)
			(xy 106.356047 -270.329532) (xy 106.310108 -270.31211) (xy 106.267558 -270.287544) (xy 106.2295 -270.25647)
			(xy 106.196919 -270.219694) (xy 106.17066 -270.178168) (xy 106.151402 -270.132967) (xy 106.139644 -270.085263)
			(xy 106.13569 -270.03629) (xy 104.865932 -270.03629) (xy 104.865438 -270.060856) (xy 104.857557 -270.109352)
			(xy 104.841998 -270.155956) (xy 104.819165 -270.19946) (xy 104.789649 -270.238739) (xy 104.754215 -270.272774)
			(xy 104.71378 -270.300684) (xy 104.669391 -270.321747) (xy 104.622199 -270.335416) (xy 104.573425 -270.341338)
			(xy 104.524333 -270.33936) (xy 104.476193 -270.329532) (xy 104.430254 -270.31211) (xy 104.387704 -270.287544)
			(xy 104.349646 -270.25647) (xy 104.317065 -270.219694) (xy 104.290806 -270.178168) (xy 104.271548 -270.132967)
			(xy 104.25979 -270.085263) (xy 104.255836 -270.03629) (xy 103.925878 -270.03629) (xy 103.925384 -270.060856)
			(xy 103.917503 -270.109352) (xy 103.901944 -270.155956) (xy 103.879111 -270.19946) (xy 103.849595 -270.238739)
			(xy 103.814161 -270.272774) (xy 103.773726 -270.300684) (xy 103.729337 -270.321747) (xy 103.682145 -270.335416)
			(xy 103.633371 -270.341338) (xy 103.584279 -270.33936) (xy 103.536139 -270.329532) (xy 103.4902 -270.31211)
			(xy 103.44765 -270.287544) (xy 103.409592 -270.25647) (xy 103.377011 -270.219694) (xy 103.350752 -270.178168)
			(xy 103.331494 -270.132967) (xy 103.319736 -270.085263) (xy 103.315782 -270.03629) (xy 102.04577 -270.03629)
			(xy 102.045276 -270.060856) (xy 102.037395 -270.109352) (xy 102.021836 -270.155956) (xy 101.999003 -270.19946)
			(xy 101.969487 -270.238739) (xy 101.934053 -270.272774) (xy 101.893618 -270.300684) (xy 101.849229 -270.321747)
			(xy 101.802037 -270.335416) (xy 101.753263 -270.341338) (xy 101.704171 -270.33936) (xy 101.656031 -270.329532)
			(xy 101.610092 -270.31211) (xy 101.567542 -270.287544) (xy 101.529484 -270.25647) (xy 101.496903 -270.219694)
			(xy 101.470644 -270.178168) (xy 101.451386 -270.132967) (xy 101.439628 -270.085263) (xy 101.435674 -270.03629)
			(xy 101.105716 -270.03629) (xy 101.105222 -270.060856) (xy 101.097341 -270.109352) (xy 101.081782 -270.155956)
			(xy 101.058949 -270.19946) (xy 101.029433 -270.238739) (xy 100.993999 -270.272774) (xy 100.953564 -270.300684)
			(xy 100.909175 -270.321747) (xy 100.861983 -270.335416) (xy 100.813209 -270.341338) (xy 100.764117 -270.33936)
			(xy 100.715977 -270.329532) (xy 100.670038 -270.31211) (xy 100.627488 -270.287544) (xy 100.58943 -270.25647)
			(xy 100.556849 -270.219694) (xy 100.53059 -270.178168) (xy 100.511332 -270.132967) (xy 100.499574 -270.085263)
			(xy 100.49562 -270.03629) (xy 99.225862 -270.03629) (xy 99.225368 -270.060856) (xy 99.217487 -270.109352)
			(xy 99.201928 -270.155956) (xy 99.179095 -270.19946) (xy 99.149579 -270.238739) (xy 99.114145 -270.272774)
			(xy 99.07371 -270.300684) (xy 99.029321 -270.321747) (xy 98.982129 -270.335416) (xy 98.933355 -270.341338)
			(xy 98.884263 -270.33936) (xy 98.836123 -270.329532) (xy 98.790184 -270.31211) (xy 98.747634 -270.287544)
			(xy 98.709576 -270.25647) (xy 98.676995 -270.219694) (xy 98.650736 -270.178168) (xy 98.631478 -270.132967)
			(xy 98.61972 -270.085263) (xy 98.615766 -270.03629) (xy 98.285808 -270.03629) (xy 98.285314 -270.060856)
			(xy 98.277433 -270.109352) (xy 98.261874 -270.155956) (xy 98.239041 -270.19946) (xy 98.209525 -270.238739)
			(xy 98.174091 -270.272774) (xy 98.133656 -270.300684) (xy 98.089267 -270.321747) (xy 98.042075 -270.335416)
			(xy 97.993301 -270.341338) (xy 97.944209 -270.33936) (xy 97.896069 -270.329532) (xy 97.85013 -270.31211)
			(xy 97.80758 -270.287544) (xy 97.769522 -270.25647) (xy 97.736941 -270.219694) (xy 97.710682 -270.178168)
			(xy 97.691424 -270.132967) (xy 97.679666 -270.085263) (xy 97.675712 -270.03629) (xy 2.509012 -270.03629)
			(xy 2.509012 -270.846296) (xy 108.485698 -270.846296) (xy 108.489652 -270.797323) (xy 108.50141 -270.749619)
			(xy 108.520668 -270.704418) (xy 108.546927 -270.662892) (xy 108.579508 -270.626116) (xy 108.617566 -270.595042)
			(xy 108.660116 -270.570476) (xy 108.706055 -270.553054) (xy 108.754195 -270.543226) (xy 108.803287 -270.541248)
			(xy 108.852061 -270.54717) (xy 108.899253 -270.560839) (xy 108.943642 -270.581902) (xy 108.984077 -270.609812)
			(xy 109.019511 -270.643847) (xy 109.049027 -270.683126) (xy 109.07186 -270.72663) (xy 109.087419 -270.773234)
			(xy 109.0953 -270.82173) (xy 109.095794 -270.846296) (xy 109.425752 -270.846296) (xy 109.429706 -270.797323)
			(xy 109.441464 -270.749619) (xy 109.460722 -270.704418) (xy 109.486981 -270.662892) (xy 109.519562 -270.626116)
			(xy 109.55762 -270.595042) (xy 109.60017 -270.570476) (xy 109.646109 -270.553054) (xy 109.694249 -270.543226)
			(xy 109.743341 -270.541248) (xy 109.792115 -270.54717) (xy 109.839307 -270.560839) (xy 109.883696 -270.581902)
			(xy 109.924131 -270.609812) (xy 109.959565 -270.643847) (xy 109.989081 -270.683126) (xy 110.011914 -270.72663)
			(xy 110.027473 -270.773234) (xy 110.035354 -270.82173) (xy 110.035848 -270.846296) (xy 114.119418 -270.846296)
			(xy 114.123372 -270.797323) (xy 114.13513 -270.749619) (xy 114.154388 -270.704418) (xy 114.180647 -270.662892)
			(xy 114.213228 -270.626116) (xy 114.251286 -270.595042) (xy 114.293836 -270.570476) (xy 114.339775 -270.553054)
			(xy 114.387915 -270.543226) (xy 114.437007 -270.541248) (xy 114.485781 -270.54717) (xy 114.532973 -270.560839)
			(xy 114.577362 -270.581902) (xy 114.617797 -270.609812) (xy 114.653231 -270.643847) (xy 114.682747 -270.683126)
			(xy 114.70558 -270.72663) (xy 114.721139 -270.773234) (xy 114.72902 -270.82173) (xy 114.729514 -270.846296)
			(xy 115.059472 -270.846296) (xy 115.063426 -270.797323) (xy 115.075184 -270.749619) (xy 115.094442 -270.704418)
			(xy 115.120701 -270.662892) (xy 115.153282 -270.626116) (xy 115.19134 -270.595042) (xy 115.23389 -270.570476)
			(xy 115.279829 -270.553054) (xy 115.327969 -270.543226) (xy 115.377061 -270.541248) (xy 115.425835 -270.54717)
			(xy 115.473027 -270.560839) (xy 115.517416 -270.581902) (xy 115.557851 -270.609812) (xy 115.593285 -270.643847)
			(xy 115.622801 -270.683126) (xy 115.645634 -270.72663) (xy 115.661193 -270.773234) (xy 115.669074 -270.82173)
			(xy 115.669563 -270.846042) (xy 356.425766 -270.846042) (xy 356.42972 -270.797069) (xy 356.441478 -270.749365)
			(xy 356.460736 -270.704164) (xy 356.486995 -270.662638) (xy 356.519576 -270.625862) (xy 356.557634 -270.594788)
			(xy 356.600184 -270.570222) (xy 356.646123 -270.5528) (xy 356.694263 -270.542972) (xy 356.743355 -270.540994)
			(xy 356.792129 -270.546916) (xy 356.839321 -270.560585) (xy 356.88371 -270.581648) (xy 356.924145 -270.609558)
			(xy 356.959579 -270.643593) (xy 356.989095 -270.682872) (xy 357.011928 -270.726376) (xy 357.027487 -270.77298)
			(xy 357.035368 -270.821476) (xy 357.035862 -270.846042) (xy 357.36582 -270.846042) (xy 357.369774 -270.797069)
			(xy 357.381532 -270.749365) (xy 357.40079 -270.704164) (xy 357.427049 -270.662638) (xy 357.45963 -270.625862)
			(xy 357.497688 -270.594788) (xy 357.540238 -270.570222) (xy 357.586177 -270.5528) (xy 357.634317 -270.542972)
			(xy 357.683409 -270.540994) (xy 357.732183 -270.546916) (xy 357.779375 -270.560585) (xy 357.823764 -270.581648)
			(xy 357.864199 -270.609558) (xy 357.899633 -270.643593) (xy 357.929149 -270.682872) (xy 357.951982 -270.726376)
			(xy 357.967541 -270.77298) (xy 357.975422 -270.821476) (xy 357.975916 -270.846042) (xy 362.059486 -270.846042)
			(xy 362.06344 -270.797069) (xy 362.075198 -270.749365) (xy 362.094456 -270.704164) (xy 362.120715 -270.662638)
			(xy 362.153296 -270.625862) (xy 362.191354 -270.594788) (xy 362.233904 -270.570222) (xy 362.279843 -270.5528)
			(xy 362.327983 -270.542972) (xy 362.377075 -270.540994) (xy 362.425849 -270.546916) (xy 362.473041 -270.560585)
			(xy 362.51743 -270.581648) (xy 362.557865 -270.609558) (xy 362.593299 -270.643593) (xy 362.622815 -270.682872)
			(xy 362.645648 -270.726376) (xy 362.661207 -270.77298) (xy 362.669088 -270.821476) (xy 362.669582 -270.846042)
			(xy 362.99954 -270.846042) (xy 363.003494 -270.797069) (xy 363.015252 -270.749365) (xy 363.03451 -270.704164)
			(xy 363.060769 -270.662638) (xy 363.09335 -270.625862) (xy 363.131408 -270.594788) (xy 363.173958 -270.570222)
			(xy 363.219897 -270.5528) (xy 363.268037 -270.542972) (xy 363.317129 -270.540994) (xy 363.365903 -270.546916)
			(xy 363.413095 -270.560585) (xy 363.457484 -270.581648) (xy 363.497919 -270.609558) (xy 363.533353 -270.643593)
			(xy 363.562869 -270.682872) (xy 363.585702 -270.726376) (xy 363.601261 -270.77298) (xy 363.609142 -270.821476)
			(xy 363.609636 -270.846042) (xy 363.609142 -270.870608) (xy 363.601261 -270.919104) (xy 363.585702 -270.965708)
			(xy 363.562869 -271.009212) (xy 363.533353 -271.048491) (xy 363.497919 -271.082526) (xy 363.457484 -271.110436)
			(xy 363.413095 -271.131499) (xy 363.365903 -271.145168) (xy 363.317129 -271.15109) (xy 363.268037 -271.149112)
			(xy 363.219897 -271.139284) (xy 363.173958 -271.121862) (xy 363.131408 -271.097296) (xy 363.09335 -271.066222)
			(xy 363.060769 -271.029446) (xy 363.03451 -270.98792) (xy 363.015252 -270.942719) (xy 363.003494 -270.895015)
			(xy 362.99954 -270.846042) (xy 362.669582 -270.846042) (xy 362.669088 -270.870608) (xy 362.661207 -270.919104)
			(xy 362.645648 -270.965708) (xy 362.622815 -271.009212) (xy 362.593299 -271.048491) (xy 362.557865 -271.082526)
			(xy 362.51743 -271.110436) (xy 362.473041 -271.131499) (xy 362.425849 -271.145168) (xy 362.377075 -271.15109)
			(xy 362.327983 -271.149112) (xy 362.279843 -271.139284) (xy 362.233904 -271.121862) (xy 362.191354 -271.097296)
			(xy 362.153296 -271.066222) (xy 362.120715 -271.029446) (xy 362.094456 -270.98792) (xy 362.075198 -270.942719)
			(xy 362.06344 -270.895015) (xy 362.059486 -270.846042) (xy 357.975916 -270.846042) (xy 357.975422 -270.870608)
			(xy 357.967541 -270.919104) (xy 357.951982 -270.965708) (xy 357.929149 -271.009212) (xy 357.899633 -271.048491)
			(xy 357.864199 -271.082526) (xy 357.823764 -271.110436) (xy 357.779375 -271.131499) (xy 357.732183 -271.145168)
			(xy 357.683409 -271.15109) (xy 357.634317 -271.149112) (xy 357.586177 -271.139284) (xy 357.540238 -271.121862)
			(xy 357.497688 -271.097296) (xy 357.45963 -271.066222) (xy 357.427049 -271.029446) (xy 357.40079 -270.98792)
			(xy 357.381532 -270.942719) (xy 357.369774 -270.895015) (xy 357.36582 -270.846042) (xy 357.035862 -270.846042)
			(xy 357.035368 -270.870608) (xy 357.027487 -270.919104) (xy 357.011928 -270.965708) (xy 356.989095 -271.009212)
			(xy 356.959579 -271.048491) (xy 356.924145 -271.082526) (xy 356.88371 -271.110436) (xy 356.839321 -271.131499)
			(xy 356.792129 -271.145168) (xy 356.743355 -271.15109) (xy 356.694263 -271.149112) (xy 356.646123 -271.139284)
			(xy 356.600184 -271.121862) (xy 356.557634 -271.097296) (xy 356.519576 -271.066222) (xy 356.486995 -271.029446)
			(xy 356.460736 -270.98792) (xy 356.441478 -270.942719) (xy 356.42972 -270.895015) (xy 356.425766 -270.846042)
			(xy 115.669563 -270.846042) (xy 115.669568 -270.846296) (xy 115.669074 -270.870862) (xy 115.661193 -270.919358)
			(xy 115.645634 -270.965962) (xy 115.622801 -271.009466) (xy 115.593285 -271.048745) (xy 115.557851 -271.08278)
			(xy 115.517416 -271.11069) (xy 115.473027 -271.131753) (xy 115.425835 -271.145422) (xy 115.377061 -271.151344)
			(xy 115.327969 -271.149366) (xy 115.279829 -271.139538) (xy 115.23389 -271.122116) (xy 115.19134 -271.09755)
			(xy 115.153282 -271.066476) (xy 115.120701 -271.0297) (xy 115.094442 -270.988174) (xy 115.075184 -270.942973)
			(xy 115.063426 -270.895269) (xy 115.059472 -270.846296) (xy 114.729514 -270.846296) (xy 114.72902 -270.870862)
			(xy 114.721139 -270.919358) (xy 114.70558 -270.965962) (xy 114.682747 -271.009466) (xy 114.653231 -271.048745)
			(xy 114.617797 -271.08278) (xy 114.577362 -271.11069) (xy 114.532973 -271.131753) (xy 114.485781 -271.145422)
			(xy 114.437007 -271.151344) (xy 114.387915 -271.149366) (xy 114.339775 -271.139538) (xy 114.293836 -271.122116)
			(xy 114.251286 -271.09755) (xy 114.213228 -271.066476) (xy 114.180647 -271.0297) (xy 114.154388 -270.988174)
			(xy 114.13513 -270.942973) (xy 114.123372 -270.895269) (xy 114.119418 -270.846296) (xy 110.035848 -270.846296)
			(xy 110.035354 -270.870862) (xy 110.027473 -270.919358) (xy 110.011914 -270.965962) (xy 109.989081 -271.009466)
			(xy 109.959565 -271.048745) (xy 109.924131 -271.08278) (xy 109.883696 -271.11069) (xy 109.839307 -271.131753)
			(xy 109.792115 -271.145422) (xy 109.743341 -271.151344) (xy 109.694249 -271.149366) (xy 109.646109 -271.139538)
			(xy 109.60017 -271.122116) (xy 109.55762 -271.09755) (xy 109.519562 -271.066476) (xy 109.486981 -271.0297)
			(xy 109.460722 -270.988174) (xy 109.441464 -270.942973) (xy 109.429706 -270.895269) (xy 109.425752 -270.846296)
			(xy 109.095794 -270.846296) (xy 109.0953 -270.870862) (xy 109.087419 -270.919358) (xy 109.07186 -270.965962)
			(xy 109.049027 -271.009466) (xy 109.019511 -271.048745) (xy 108.984077 -271.08278) (xy 108.943642 -271.11069)
			(xy 108.899253 -271.131753) (xy 108.852061 -271.145422) (xy 108.803287 -271.151344) (xy 108.754195 -271.149366)
			(xy 108.706055 -271.139538) (xy 108.660116 -271.122116) (xy 108.617566 -271.09755) (xy 108.579508 -271.066476)
			(xy 108.546927 -271.0297) (xy 108.520668 -270.988174) (xy 108.50141 -270.942973) (xy 108.489652 -270.895269)
			(xy 108.485698 -270.846296) (xy 2.509012 -270.846296) (xy 2.509012 -271.656302) (xy 97.675712 -271.656302)
			(xy 97.679666 -271.607329) (xy 97.691424 -271.559625) (xy 97.710682 -271.514424) (xy 97.736941 -271.472898)
			(xy 97.769522 -271.436122) (xy 97.80758 -271.405048) (xy 97.85013 -271.380482) (xy 97.896069 -271.36306)
			(xy 97.944209 -271.353232) (xy 97.993301 -271.351254) (xy 98.042075 -271.357176) (xy 98.089267 -271.370845)
			(xy 98.133656 -271.391908) (xy 98.174091 -271.419818) (xy 98.209525 -271.453853) (xy 98.239041 -271.493132)
			(xy 98.261874 -271.536636) (xy 98.277433 -271.58324) (xy 98.285314 -271.631736) (xy 98.285808 -271.656302)
			(xy 98.615766 -271.656302) (xy 98.61972 -271.607329) (xy 98.631478 -271.559625) (xy 98.650736 -271.514424)
			(xy 98.676995 -271.472898) (xy 98.709576 -271.436122) (xy 98.747634 -271.405048) (xy 98.790184 -271.380482)
			(xy 98.836123 -271.36306) (xy 98.884263 -271.353232) (xy 98.933355 -271.351254) (xy 98.982129 -271.357176)
			(xy 99.029321 -271.370845) (xy 99.07371 -271.391908) (xy 99.114145 -271.419818) (xy 99.149579 -271.453853)
			(xy 99.179095 -271.493132) (xy 99.201928 -271.536636) (xy 99.217487 -271.58324) (xy 99.225368 -271.631736)
			(xy 99.225862 -271.656302) (xy 100.49562 -271.656302) (xy 100.499574 -271.607329) (xy 100.511332 -271.559625)
			(xy 100.53059 -271.514424) (xy 100.556849 -271.472898) (xy 100.58943 -271.436122) (xy 100.627488 -271.405048)
			(xy 100.670038 -271.380482) (xy 100.715977 -271.36306) (xy 100.764117 -271.353232) (xy 100.813209 -271.351254)
			(xy 100.861983 -271.357176) (xy 100.909175 -271.370845) (xy 100.953564 -271.391908) (xy 100.993999 -271.419818)
			(xy 101.029433 -271.453853) (xy 101.058949 -271.493132) (xy 101.081782 -271.536636) (xy 101.097341 -271.58324)
			(xy 101.105222 -271.631736) (xy 101.105716 -271.656302) (xy 101.435674 -271.656302) (xy 101.439628 -271.607329)
			(xy 101.451386 -271.559625) (xy 101.470644 -271.514424) (xy 101.496903 -271.472898) (xy 101.529484 -271.436122)
			(xy 101.567542 -271.405048) (xy 101.610092 -271.380482) (xy 101.656031 -271.36306) (xy 101.704171 -271.353232)
			(xy 101.753263 -271.351254) (xy 101.802037 -271.357176) (xy 101.849229 -271.370845) (xy 101.893618 -271.391908)
			(xy 101.934053 -271.419818) (xy 101.969487 -271.453853) (xy 101.999003 -271.493132) (xy 102.021836 -271.536636)
			(xy 102.037395 -271.58324) (xy 102.045276 -271.631736) (xy 102.04577 -271.656302) (xy 103.315782 -271.656302)
			(xy 103.319736 -271.607329) (xy 103.331494 -271.559625) (xy 103.350752 -271.514424) (xy 103.377011 -271.472898)
			(xy 103.409592 -271.436122) (xy 103.44765 -271.405048) (xy 103.4902 -271.380482) (xy 103.536139 -271.36306)
			(xy 103.584279 -271.353232) (xy 103.633371 -271.351254) (xy 103.682145 -271.357176) (xy 103.729337 -271.370845)
			(xy 103.773726 -271.391908) (xy 103.814161 -271.419818) (xy 103.849595 -271.453853) (xy 103.879111 -271.493132)
			(xy 103.901944 -271.536636) (xy 103.917503 -271.58324) (xy 103.925384 -271.631736) (xy 103.925878 -271.656302)
			(xy 104.255836 -271.656302) (xy 104.25979 -271.607329) (xy 104.271548 -271.559625) (xy 104.290806 -271.514424)
			(xy 104.317065 -271.472898) (xy 104.349646 -271.436122) (xy 104.387704 -271.405048) (xy 104.430254 -271.380482)
			(xy 104.476193 -271.36306) (xy 104.524333 -271.353232) (xy 104.573425 -271.351254) (xy 104.622199 -271.357176)
			(xy 104.669391 -271.370845) (xy 104.71378 -271.391908) (xy 104.754215 -271.419818) (xy 104.789649 -271.453853)
			(xy 104.819165 -271.493132) (xy 104.841998 -271.536636) (xy 104.857557 -271.58324) (xy 104.865438 -271.631736)
			(xy 104.865932 -271.656302) (xy 106.13569 -271.656302) (xy 106.139644 -271.607329) (xy 106.151402 -271.559625)
			(xy 106.17066 -271.514424) (xy 106.196919 -271.472898) (xy 106.2295 -271.436122) (xy 106.267558 -271.405048)
			(xy 106.310108 -271.380482) (xy 106.356047 -271.36306) (xy 106.404187 -271.353232) (xy 106.453279 -271.351254)
			(xy 106.502053 -271.357176) (xy 106.549245 -271.370845) (xy 106.593634 -271.391908) (xy 106.634069 -271.419818)
			(xy 106.669503 -271.453853) (xy 106.699019 -271.493132) (xy 106.721852 -271.536636) (xy 106.737411 -271.58324)
			(xy 106.745292 -271.631736) (xy 106.745786 -271.656302) (xy 107.075744 -271.656302) (xy 107.079698 -271.607329)
			(xy 107.091456 -271.559625) (xy 107.110714 -271.514424) (xy 107.136973 -271.472898) (xy 107.169554 -271.436122)
			(xy 107.207612 -271.405048) (xy 107.250162 -271.380482) (xy 107.296101 -271.36306) (xy 107.344241 -271.353232)
			(xy 107.393333 -271.351254) (xy 107.442107 -271.357176) (xy 107.489299 -271.370845) (xy 107.533688 -271.391908)
			(xy 107.574123 -271.419818) (xy 107.609557 -271.453853) (xy 107.639073 -271.493132) (xy 107.661906 -271.536636)
			(xy 107.677465 -271.58324) (xy 107.685346 -271.631736) (xy 107.68584 -271.656302) (xy 116.469426 -271.656302)
			(xy 116.47338 -271.607329) (xy 116.485138 -271.559625) (xy 116.504396 -271.514424) (xy 116.530655 -271.472898)
			(xy 116.563236 -271.436122) (xy 116.601294 -271.405048) (xy 116.643844 -271.380482) (xy 116.689783 -271.36306)
			(xy 116.737923 -271.353232) (xy 116.787015 -271.351254) (xy 116.835789 -271.357176) (xy 116.882981 -271.370845)
			(xy 116.92737 -271.391908) (xy 116.967805 -271.419818) (xy 117.003239 -271.453853) (xy 117.032755 -271.493132)
			(xy 117.055588 -271.536636) (xy 117.071147 -271.58324) (xy 117.079028 -271.631736) (xy 117.079522 -271.656302)
			(xy 117.40948 -271.656302) (xy 117.413434 -271.607329) (xy 117.425192 -271.559625) (xy 117.44445 -271.514424)
			(xy 117.470709 -271.472898) (xy 117.50329 -271.436122) (xy 117.541348 -271.405048) (xy 117.583898 -271.380482)
			(xy 117.629837 -271.36306) (xy 117.677977 -271.353232) (xy 117.727069 -271.351254) (xy 117.775843 -271.357176)
			(xy 117.823035 -271.370845) (xy 117.867424 -271.391908) (xy 117.907859 -271.419818) (xy 117.943293 -271.453853)
			(xy 117.972809 -271.493132) (xy 117.995642 -271.536636) (xy 118.011201 -271.58324) (xy 118.019082 -271.631736)
			(xy 118.019576 -271.656302) (xy 119.289334 -271.656302) (xy 119.293288 -271.607329) (xy 119.305046 -271.559625)
			(xy 119.324304 -271.514424) (xy 119.350563 -271.472898) (xy 119.383144 -271.436122) (xy 119.421202 -271.405048)
			(xy 119.463752 -271.380482) (xy 119.509691 -271.36306) (xy 119.557831 -271.353232) (xy 119.606923 -271.351254)
			(xy 119.655697 -271.357176) (xy 119.702889 -271.370845) (xy 119.747278 -271.391908) (xy 119.787713 -271.419818)
			(xy 119.823147 -271.453853) (xy 119.852663 -271.493132) (xy 119.875496 -271.536636) (xy 119.891055 -271.58324)
			(xy 119.898936 -271.631736) (xy 119.89943 -271.656302) (xy 120.229388 -271.656302) (xy 120.233342 -271.607329)
			(xy 120.2451 -271.559625) (xy 120.264358 -271.514424) (xy 120.290617 -271.472898) (xy 120.323198 -271.436122)
			(xy 120.361256 -271.405048) (xy 120.403806 -271.380482) (xy 120.449745 -271.36306) (xy 120.497885 -271.353232)
			(xy 120.546977 -271.351254) (xy 120.595751 -271.357176) (xy 120.642943 -271.370845) (xy 120.687332 -271.391908)
			(xy 120.727767 -271.419818) (xy 120.763201 -271.453853) (xy 120.792717 -271.493132) (xy 120.81555 -271.536636)
			(xy 120.831109 -271.58324) (xy 120.83899 -271.631736) (xy 120.839484 -271.656302) (xy 122.109242 -271.656302)
			(xy 122.113196 -271.607329) (xy 122.124954 -271.559625) (xy 122.144212 -271.514424) (xy 122.170471 -271.472898)
			(xy 122.203052 -271.436122) (xy 122.24111 -271.405048) (xy 122.28366 -271.380482) (xy 122.329599 -271.36306)
			(xy 122.377739 -271.353232) (xy 122.426831 -271.351254) (xy 122.475605 -271.357176) (xy 122.522797 -271.370845)
			(xy 122.567186 -271.391908) (xy 122.607621 -271.419818) (xy 122.643055 -271.453853) (xy 122.672571 -271.493132)
			(xy 122.695404 -271.536636) (xy 122.710963 -271.58324) (xy 122.718844 -271.631736) (xy 122.719338 -271.656302)
			(xy 123.049296 -271.656302) (xy 123.05325 -271.607329) (xy 123.065008 -271.559625) (xy 123.084266 -271.514424)
			(xy 123.110525 -271.472898) (xy 123.143106 -271.436122) (xy 123.181164 -271.405048) (xy 123.223714 -271.380482)
			(xy 123.269653 -271.36306) (xy 123.317793 -271.353232) (xy 123.366885 -271.351254) (xy 123.415659 -271.357176)
			(xy 123.462851 -271.370845) (xy 123.50724 -271.391908) (xy 123.547675 -271.419818) (xy 123.583109 -271.453853)
			(xy 123.612625 -271.493132) (xy 123.635458 -271.536636) (xy 123.651017 -271.58324) (xy 123.658898 -271.631736)
			(xy 123.659392 -271.656302) (xy 124.929404 -271.656302) (xy 124.933358 -271.607329) (xy 124.945116 -271.559625)
			(xy 124.964374 -271.514424) (xy 124.990633 -271.472898) (xy 125.023214 -271.436122) (xy 125.061272 -271.405048)
			(xy 125.103822 -271.380482) (xy 125.149761 -271.36306) (xy 125.197901 -271.353232) (xy 125.246993 -271.351254)
			(xy 125.295767 -271.357176) (xy 125.342959 -271.370845) (xy 125.387348 -271.391908) (xy 125.427783 -271.419818)
			(xy 125.463217 -271.453853) (xy 125.492733 -271.493132) (xy 125.515566 -271.536636) (xy 125.531125 -271.58324)
			(xy 125.539006 -271.631736) (xy 125.5395 -271.656302) (xy 125.869458 -271.656302) (xy 125.873412 -271.607329)
			(xy 125.88517 -271.559625) (xy 125.904428 -271.514424) (xy 125.930687 -271.472898) (xy 125.963268 -271.436122)
			(xy 126.001326 -271.405048) (xy 126.043876 -271.380482) (xy 126.089815 -271.36306) (xy 126.137955 -271.353232)
			(xy 126.187047 -271.351254) (xy 126.235821 -271.357176) (xy 126.283013 -271.370845) (xy 126.327402 -271.391908)
			(xy 126.367837 -271.419818) (xy 126.403271 -271.453853) (xy 126.432787 -271.493132) (xy 126.45562 -271.536636)
			(xy 126.471179 -271.58324) (xy 126.47906 -271.631736) (xy 126.479549 -271.656048) (xy 345.61578 -271.656048)
			(xy 345.619734 -271.607075) (xy 345.631492 -271.559371) (xy 345.65075 -271.51417) (xy 345.677009 -271.472644)
			(xy 345.70959 -271.435868) (xy 345.747648 -271.404794) (xy 345.790198 -271.380228) (xy 345.836137 -271.362806)
			(xy 345.884277 -271.352978) (xy 345.933369 -271.351) (xy 345.982143 -271.356922) (xy 346.029335 -271.370591)
			(xy 346.073724 -271.391654) (xy 346.114159 -271.419564) (xy 346.149593 -271.453599) (xy 346.179109 -271.492878)
			(xy 346.201942 -271.536382) (xy 346.217501 -271.582986) (xy 346.225382 -271.631482) (xy 346.225876 -271.656048)
			(xy 346.555834 -271.656048) (xy 346.559788 -271.607075) (xy 346.571546 -271.559371) (xy 346.590804 -271.51417)
			(xy 346.617063 -271.472644) (xy 346.649644 -271.435868) (xy 346.687702 -271.404794) (xy 346.730252 -271.380228)
			(xy 346.776191 -271.362806) (xy 346.824331 -271.352978) (xy 346.873423 -271.351) (xy 346.922197 -271.356922)
			(xy 346.969389 -271.370591) (xy 347.013778 -271.391654) (xy 347.054213 -271.419564) (xy 347.089647 -271.453599)
			(xy 347.119163 -271.492878) (xy 347.141996 -271.536382) (xy 347.157555 -271.582986) (xy 347.165436 -271.631482)
			(xy 347.16593 -271.656048) (xy 348.435688 -271.656048) (xy 348.439642 -271.607075) (xy 348.4514 -271.559371)
			(xy 348.470658 -271.51417) (xy 348.496917 -271.472644) (xy 348.529498 -271.435868) (xy 348.567556 -271.404794)
			(xy 348.610106 -271.380228) (xy 348.656045 -271.362806) (xy 348.704185 -271.352978) (xy 348.753277 -271.351)
			(xy 348.802051 -271.356922) (xy 348.849243 -271.370591) (xy 348.893632 -271.391654) (xy 348.934067 -271.419564)
			(xy 348.969501 -271.453599) (xy 348.999017 -271.492878) (xy 349.02185 -271.536382) (xy 349.037409 -271.582986)
			(xy 349.04529 -271.631482) (xy 349.045784 -271.656048) (xy 349.375742 -271.656048) (xy 349.379696 -271.607075)
			(xy 349.391454 -271.559371) (xy 349.410712 -271.51417) (xy 349.436971 -271.472644) (xy 349.469552 -271.435868)
			(xy 349.50761 -271.404794) (xy 349.55016 -271.380228) (xy 349.596099 -271.362806) (xy 349.644239 -271.352978)
			(xy 349.693331 -271.351) (xy 349.742105 -271.356922) (xy 349.789297 -271.370591) (xy 349.833686 -271.391654)
			(xy 349.874121 -271.419564) (xy 349.909555 -271.453599) (xy 349.939071 -271.492878) (xy 349.961904 -271.536382)
			(xy 349.977463 -271.582986) (xy 349.985344 -271.631482) (xy 349.985838 -271.656048) (xy 351.25585 -271.656048)
			(xy 351.259804 -271.607075) (xy 351.271562 -271.559371) (xy 351.29082 -271.51417) (xy 351.317079 -271.472644)
			(xy 351.34966 -271.435868) (xy 351.387718 -271.404794) (xy 351.430268 -271.380228) (xy 351.476207 -271.362806)
			(xy 351.524347 -271.352978) (xy 351.573439 -271.351) (xy 351.622213 -271.356922) (xy 351.669405 -271.370591)
			(xy 351.713794 -271.391654) (xy 351.754229 -271.419564) (xy 351.789663 -271.453599) (xy 351.819179 -271.492878)
			(xy 351.842012 -271.536382) (xy 351.857571 -271.582986) (xy 351.865452 -271.631482) (xy 351.865946 -271.656048)
			(xy 352.195904 -271.656048) (xy 352.199858 -271.607075) (xy 352.211616 -271.559371) (xy 352.230874 -271.51417)
			(xy 352.257133 -271.472644) (xy 352.289714 -271.435868) (xy 352.327772 -271.404794) (xy 352.370322 -271.380228)
			(xy 352.416261 -271.362806) (xy 352.464401 -271.352978) (xy 352.513493 -271.351) (xy 352.562267 -271.356922)
			(xy 352.609459 -271.370591) (xy 352.653848 -271.391654) (xy 352.694283 -271.419564) (xy 352.729717 -271.453599)
			(xy 352.759233 -271.492878) (xy 352.782066 -271.536382) (xy 352.797625 -271.582986) (xy 352.805506 -271.631482)
			(xy 352.806 -271.656048) (xy 354.075758 -271.656048) (xy 354.079712 -271.607075) (xy 354.09147 -271.559371)
			(xy 354.110728 -271.51417) (xy 354.136987 -271.472644) (xy 354.169568 -271.435868) (xy 354.207626 -271.404794)
			(xy 354.250176 -271.380228) (xy 354.296115 -271.362806) (xy 354.344255 -271.352978) (xy 354.393347 -271.351)
			(xy 354.442121 -271.356922) (xy 354.489313 -271.370591) (xy 354.533702 -271.391654) (xy 354.574137 -271.419564)
			(xy 354.609571 -271.453599) (xy 354.639087 -271.492878) (xy 354.66192 -271.536382) (xy 354.677479 -271.582986)
			(xy 354.68536 -271.631482) (xy 354.685854 -271.656048) (xy 355.015812 -271.656048) (xy 355.019766 -271.607075)
			(xy 355.031524 -271.559371) (xy 355.050782 -271.51417) (xy 355.077041 -271.472644) (xy 355.109622 -271.435868)
			(xy 355.14768 -271.404794) (xy 355.19023 -271.380228) (xy 355.236169 -271.362806) (xy 355.284309 -271.352978)
			(xy 355.333401 -271.351) (xy 355.382175 -271.356922) (xy 355.429367 -271.370591) (xy 355.473756 -271.391654)
			(xy 355.514191 -271.419564) (xy 355.549625 -271.453599) (xy 355.579141 -271.492878) (xy 355.601974 -271.536382)
			(xy 355.617533 -271.582986) (xy 355.625414 -271.631482) (xy 355.625908 -271.656048) (xy 364.409494 -271.656048)
			(xy 364.413448 -271.607075) (xy 364.425206 -271.559371) (xy 364.444464 -271.51417) (xy 364.470723 -271.472644)
			(xy 364.503304 -271.435868) (xy 364.541362 -271.404794) (xy 364.583912 -271.380228) (xy 364.629851 -271.362806)
			(xy 364.677991 -271.352978) (xy 364.727083 -271.351) (xy 364.775857 -271.356922) (xy 364.823049 -271.370591)
			(xy 364.867438 -271.391654) (xy 364.907873 -271.419564) (xy 364.943307 -271.453599) (xy 364.972823 -271.492878)
			(xy 364.995656 -271.536382) (xy 365.011215 -271.582986) (xy 365.019096 -271.631482) (xy 365.01959 -271.656048)
			(xy 365.349548 -271.656048) (xy 365.353502 -271.607075) (xy 365.36526 -271.559371) (xy 365.384518 -271.51417)
			(xy 365.410777 -271.472644) (xy 365.443358 -271.435868) (xy 365.481416 -271.404794) (xy 365.523966 -271.380228)
			(xy 365.569905 -271.362806) (xy 365.618045 -271.352978) (xy 365.667137 -271.351) (xy 365.715911 -271.356922)
			(xy 365.763103 -271.370591) (xy 365.807492 -271.391654) (xy 365.847927 -271.419564) (xy 365.883361 -271.453599)
			(xy 365.912877 -271.492878) (xy 365.93571 -271.536382) (xy 365.951269 -271.582986) (xy 365.95915 -271.631482)
			(xy 365.959644 -271.656048) (xy 367.229402 -271.656048) (xy 367.233356 -271.607075) (xy 367.245114 -271.559371)
			(xy 367.264372 -271.51417) (xy 367.290631 -271.472644) (xy 367.323212 -271.435868) (xy 367.36127 -271.404794)
			(xy 367.40382 -271.380228) (xy 367.449759 -271.362806) (xy 367.497899 -271.352978) (xy 367.546991 -271.351)
			(xy 367.595765 -271.356922) (xy 367.642957 -271.370591) (xy 367.687346 -271.391654) (xy 367.727781 -271.419564)
			(xy 367.763215 -271.453599) (xy 367.792731 -271.492878) (xy 367.815564 -271.536382) (xy 367.831123 -271.582986)
			(xy 367.839004 -271.631482) (xy 367.839498 -271.656048) (xy 368.169456 -271.656048) (xy 368.17341 -271.607075)
			(xy 368.185168 -271.559371) (xy 368.204426 -271.51417) (xy 368.230685 -271.472644) (xy 368.263266 -271.435868)
			(xy 368.301324 -271.404794) (xy 368.343874 -271.380228) (xy 368.389813 -271.362806) (xy 368.437953 -271.352978)
			(xy 368.487045 -271.351) (xy 368.535819 -271.356922) (xy 368.583011 -271.370591) (xy 368.6274 -271.391654)
			(xy 368.667835 -271.419564) (xy 368.703269 -271.453599) (xy 368.732785 -271.492878) (xy 368.755618 -271.536382)
			(xy 368.771177 -271.582986) (xy 368.779058 -271.631482) (xy 368.779552 -271.656048) (xy 370.04931 -271.656048)
			(xy 370.053264 -271.607075) (xy 370.065022 -271.559371) (xy 370.08428 -271.51417) (xy 370.110539 -271.472644)
			(xy 370.14312 -271.435868) (xy 370.181178 -271.404794) (xy 370.223728 -271.380228) (xy 370.269667 -271.362806)
			(xy 370.317807 -271.352978) (xy 370.366899 -271.351) (xy 370.415673 -271.356922) (xy 370.462865 -271.370591)
			(xy 370.507254 -271.391654) (xy 370.547689 -271.419564) (xy 370.583123 -271.453599) (xy 370.612639 -271.492878)
			(xy 370.635472 -271.536382) (xy 370.651031 -271.582986) (xy 370.658912 -271.631482) (xy 370.659406 -271.656048)
			(xy 370.989364 -271.656048) (xy 370.993318 -271.607075) (xy 371.005076 -271.559371) (xy 371.024334 -271.51417)
			(xy 371.050593 -271.472644) (xy 371.083174 -271.435868) (xy 371.121232 -271.404794) (xy 371.163782 -271.380228)
			(xy 371.209721 -271.362806) (xy 371.257861 -271.352978) (xy 371.306953 -271.351) (xy 371.355727 -271.356922)
			(xy 371.402919 -271.370591) (xy 371.447308 -271.391654) (xy 371.487743 -271.419564) (xy 371.523177 -271.453599)
			(xy 371.552693 -271.492878) (xy 371.575526 -271.536382) (xy 371.591085 -271.582986) (xy 371.598966 -271.631482)
			(xy 371.59946 -271.656048) (xy 372.869472 -271.656048) (xy 372.873426 -271.607075) (xy 372.885184 -271.559371)
			(xy 372.904442 -271.51417) (xy 372.930701 -271.472644) (xy 372.963282 -271.435868) (xy 373.00134 -271.404794)
			(xy 373.04389 -271.380228) (xy 373.089829 -271.362806) (xy 373.137969 -271.352978) (xy 373.187061 -271.351)
			(xy 373.235835 -271.356922) (xy 373.283027 -271.370591) (xy 373.327416 -271.391654) (xy 373.367851 -271.419564)
			(xy 373.403285 -271.453599) (xy 373.432801 -271.492878) (xy 373.455634 -271.536382) (xy 373.471193 -271.582986)
			(xy 373.479074 -271.631482) (xy 373.479568 -271.656048) (xy 373.809526 -271.656048) (xy 373.81348 -271.607075)
			(xy 373.825238 -271.559371) (xy 373.844496 -271.51417) (xy 373.870755 -271.472644) (xy 373.903336 -271.435868)
			(xy 373.941394 -271.404794) (xy 373.983944 -271.380228) (xy 374.029883 -271.362806) (xy 374.078023 -271.352978)
			(xy 374.127115 -271.351) (xy 374.175889 -271.356922) (xy 374.223081 -271.370591) (xy 374.26747 -271.391654)
			(xy 374.307905 -271.419564) (xy 374.343339 -271.453599) (xy 374.372855 -271.492878) (xy 374.395688 -271.536382)
			(xy 374.411247 -271.582986) (xy 374.419128 -271.631482) (xy 374.419622 -271.656048) (xy 374.419128 -271.680614)
			(xy 374.411247 -271.72911) (xy 374.395688 -271.775714) (xy 374.372855 -271.819218) (xy 374.343339 -271.858497)
			(xy 374.307905 -271.892532) (xy 374.26747 -271.920442) (xy 374.223081 -271.941505) (xy 374.175889 -271.955174)
			(xy 374.127115 -271.961096) (xy 374.078023 -271.959118) (xy 374.029883 -271.94929) (xy 373.983944 -271.931868)
			(xy 373.941394 -271.907302) (xy 373.903336 -271.876228) (xy 373.870755 -271.839452) (xy 373.844496 -271.797926)
			(xy 373.825238 -271.752725) (xy 373.81348 -271.705021) (xy 373.809526 -271.656048) (xy 373.479568 -271.656048)
			(xy 373.479074 -271.680614) (xy 373.471193 -271.72911) (xy 373.455634 -271.775714) (xy 373.432801 -271.819218)
			(xy 373.403285 -271.858497) (xy 373.367851 -271.892532) (xy 373.327416 -271.920442) (xy 373.283027 -271.941505)
			(xy 373.235835 -271.955174) (xy 373.187061 -271.961096) (xy 373.137969 -271.959118) (xy 373.089829 -271.94929)
			(xy 373.04389 -271.931868) (xy 373.00134 -271.907302) (xy 372.963282 -271.876228) (xy 372.930701 -271.839452)
			(xy 372.904442 -271.797926) (xy 372.885184 -271.752725) (xy 372.873426 -271.705021) (xy 372.869472 -271.656048)
			(xy 371.59946 -271.656048) (xy 371.598966 -271.680614) (xy 371.591085 -271.72911) (xy 371.575526 -271.775714)
			(xy 371.552693 -271.819218) (xy 371.523177 -271.858497) (xy 371.487743 -271.892532) (xy 371.447308 -271.920442)
			(xy 371.402919 -271.941505) (xy 371.355727 -271.955174) (xy 371.306953 -271.961096) (xy 371.257861 -271.959118)
			(xy 371.209721 -271.94929) (xy 371.163782 -271.931868) (xy 371.121232 -271.907302) (xy 371.083174 -271.876228)
			(xy 371.050593 -271.839452) (xy 371.024334 -271.797926) (xy 371.005076 -271.752725) (xy 370.993318 -271.705021)
			(xy 370.989364 -271.656048) (xy 370.659406 -271.656048) (xy 370.658912 -271.680614) (xy 370.651031 -271.72911)
			(xy 370.635472 -271.775714) (xy 370.612639 -271.819218) (xy 370.583123 -271.858497) (xy 370.547689 -271.892532)
			(xy 370.507254 -271.920442) (xy 370.462865 -271.941505) (xy 370.415673 -271.955174) (xy 370.366899 -271.961096)
			(xy 370.317807 -271.959118) (xy 370.269667 -271.94929) (xy 370.223728 -271.931868) (xy 370.181178 -271.907302)
			(xy 370.14312 -271.876228) (xy 370.110539 -271.839452) (xy 370.08428 -271.797926) (xy 370.065022 -271.752725)
			(xy 370.053264 -271.705021) (xy 370.04931 -271.656048) (xy 368.779552 -271.656048) (xy 368.779058 -271.680614)
			(xy 368.771177 -271.72911) (xy 368.755618 -271.775714) (xy 368.732785 -271.819218) (xy 368.703269 -271.858497)
			(xy 368.667835 -271.892532) (xy 368.6274 -271.920442) (xy 368.583011 -271.941505) (xy 368.535819 -271.955174)
			(xy 368.487045 -271.961096) (xy 368.437953 -271.959118) (xy 368.389813 -271.94929) (xy 368.343874 -271.931868)
			(xy 368.301324 -271.907302) (xy 368.263266 -271.876228) (xy 368.230685 -271.839452) (xy 368.204426 -271.797926)
			(xy 368.185168 -271.752725) (xy 368.17341 -271.705021) (xy 368.169456 -271.656048) (xy 367.839498 -271.656048)
			(xy 367.839004 -271.680614) (xy 367.831123 -271.72911) (xy 367.815564 -271.775714) (xy 367.792731 -271.819218)
			(xy 367.763215 -271.858497) (xy 367.727781 -271.892532) (xy 367.687346 -271.920442) (xy 367.642957 -271.941505)
			(xy 367.595765 -271.955174) (xy 367.546991 -271.961096) (xy 367.497899 -271.959118) (xy 367.449759 -271.94929)
			(xy 367.40382 -271.931868) (xy 367.36127 -271.907302) (xy 367.323212 -271.876228) (xy 367.290631 -271.839452)
			(xy 367.264372 -271.797926) (xy 367.245114 -271.752725) (xy 367.233356 -271.705021) (xy 367.229402 -271.656048)
			(xy 365.959644 -271.656048) (xy 365.95915 -271.680614) (xy 365.951269 -271.72911) (xy 365.93571 -271.775714)
			(xy 365.912877 -271.819218) (xy 365.883361 -271.858497) (xy 365.847927 -271.892532) (xy 365.807492 -271.920442)
			(xy 365.763103 -271.941505) (xy 365.715911 -271.955174) (xy 365.667137 -271.961096) (xy 365.618045 -271.959118)
			(xy 365.569905 -271.94929) (xy 365.523966 -271.931868) (xy 365.481416 -271.907302) (xy 365.443358 -271.876228)
			(xy 365.410777 -271.839452) (xy 365.384518 -271.797926) (xy 365.36526 -271.752725) (xy 365.353502 -271.705021)
			(xy 365.349548 -271.656048) (xy 365.01959 -271.656048) (xy 365.019096 -271.680614) (xy 365.011215 -271.72911)
			(xy 364.995656 -271.775714) (xy 364.972823 -271.819218) (xy 364.943307 -271.858497) (xy 364.907873 -271.892532)
			(xy 364.867438 -271.920442) (xy 364.823049 -271.941505) (xy 364.775857 -271.955174) (xy 364.727083 -271.961096)
			(xy 364.677991 -271.959118) (xy 364.629851 -271.94929) (xy 364.583912 -271.931868) (xy 364.541362 -271.907302)
			(xy 364.503304 -271.876228) (xy 364.470723 -271.839452) (xy 364.444464 -271.797926) (xy 364.425206 -271.752725)
			(xy 364.413448 -271.705021) (xy 364.409494 -271.656048) (xy 355.625908 -271.656048) (xy 355.625414 -271.680614)
			(xy 355.617533 -271.72911) (xy 355.601974 -271.775714) (xy 355.579141 -271.819218) (xy 355.549625 -271.858497)
			(xy 355.514191 -271.892532) (xy 355.473756 -271.920442) (xy 355.429367 -271.941505) (xy 355.382175 -271.955174)
			(xy 355.333401 -271.961096) (xy 355.284309 -271.959118) (xy 355.236169 -271.94929) (xy 355.19023 -271.931868)
			(xy 355.14768 -271.907302) (xy 355.109622 -271.876228) (xy 355.077041 -271.839452) (xy 355.050782 -271.797926)
			(xy 355.031524 -271.752725) (xy 355.019766 -271.705021) (xy 355.015812 -271.656048) (xy 354.685854 -271.656048)
			(xy 354.68536 -271.680614) (xy 354.677479 -271.72911) (xy 354.66192 -271.775714) (xy 354.639087 -271.819218)
			(xy 354.609571 -271.858497) (xy 354.574137 -271.892532) (xy 354.533702 -271.920442) (xy 354.489313 -271.941505)
			(xy 354.442121 -271.955174) (xy 354.393347 -271.961096) (xy 354.344255 -271.959118) (xy 354.296115 -271.94929)
			(xy 354.250176 -271.931868) (xy 354.207626 -271.907302) (xy 354.169568 -271.876228) (xy 354.136987 -271.839452)
			(xy 354.110728 -271.797926) (xy 354.09147 -271.752725) (xy 354.079712 -271.705021) (xy 354.075758 -271.656048)
			(xy 352.806 -271.656048) (xy 352.805506 -271.680614) (xy 352.797625 -271.72911) (xy 352.782066 -271.775714)
			(xy 352.759233 -271.819218) (xy 352.729717 -271.858497) (xy 352.694283 -271.892532) (xy 352.653848 -271.920442)
			(xy 352.609459 -271.941505) (xy 352.562267 -271.955174) (xy 352.513493 -271.961096) (xy 352.464401 -271.959118)
			(xy 352.416261 -271.94929) (xy 352.370322 -271.931868) (xy 352.327772 -271.907302) (xy 352.289714 -271.876228)
			(xy 352.257133 -271.839452) (xy 352.230874 -271.797926) (xy 352.211616 -271.752725) (xy 352.199858 -271.705021)
			(xy 352.195904 -271.656048) (xy 351.865946 -271.656048) (xy 351.865452 -271.680614) (xy 351.857571 -271.72911)
			(xy 351.842012 -271.775714) (xy 351.819179 -271.819218) (xy 351.789663 -271.858497) (xy 351.754229 -271.892532)
			(xy 351.713794 -271.920442) (xy 351.669405 -271.941505) (xy 351.622213 -271.955174) (xy 351.573439 -271.961096)
			(xy 351.524347 -271.959118) (xy 351.476207 -271.94929) (xy 351.430268 -271.931868) (xy 351.387718 -271.907302)
			(xy 351.34966 -271.876228) (xy 351.317079 -271.839452) (xy 351.29082 -271.797926) (xy 351.271562 -271.752725)
			(xy 351.259804 -271.705021) (xy 351.25585 -271.656048) (xy 349.985838 -271.656048) (xy 349.985344 -271.680614)
			(xy 349.977463 -271.72911) (xy 349.961904 -271.775714) (xy 349.939071 -271.819218) (xy 349.909555 -271.858497)
			(xy 349.874121 -271.892532) (xy 349.833686 -271.920442) (xy 349.789297 -271.941505) (xy 349.742105 -271.955174)
			(xy 349.693331 -271.961096) (xy 349.644239 -271.959118) (xy 349.596099 -271.94929) (xy 349.55016 -271.931868)
			(xy 349.50761 -271.907302) (xy 349.469552 -271.876228) (xy 349.436971 -271.839452) (xy 349.410712 -271.797926)
			(xy 349.391454 -271.752725) (xy 349.379696 -271.705021) (xy 349.375742 -271.656048) (xy 349.045784 -271.656048)
			(xy 349.04529 -271.680614) (xy 349.037409 -271.72911) (xy 349.02185 -271.775714) (xy 348.999017 -271.819218)
			(xy 348.969501 -271.858497) (xy 348.934067 -271.892532) (xy 348.893632 -271.920442) (xy 348.849243 -271.941505)
			(xy 348.802051 -271.955174) (xy 348.753277 -271.961096) (xy 348.704185 -271.959118) (xy 348.656045 -271.94929)
			(xy 348.610106 -271.931868) (xy 348.567556 -271.907302) (xy 348.529498 -271.876228) (xy 348.496917 -271.839452)
			(xy 348.470658 -271.797926) (xy 348.4514 -271.752725) (xy 348.439642 -271.705021) (xy 348.435688 -271.656048)
			(xy 347.16593 -271.656048) (xy 347.165436 -271.680614) (xy 347.157555 -271.72911) (xy 347.141996 -271.775714)
			(xy 347.119163 -271.819218) (xy 347.089647 -271.858497) (xy 347.054213 -271.892532) (xy 347.013778 -271.920442)
			(xy 346.969389 -271.941505) (xy 346.922197 -271.955174) (xy 346.873423 -271.961096) (xy 346.824331 -271.959118)
			(xy 346.776191 -271.94929) (xy 346.730252 -271.931868) (xy 346.687702 -271.907302) (xy 346.649644 -271.876228)
			(xy 346.617063 -271.839452) (xy 346.590804 -271.797926) (xy 346.571546 -271.752725) (xy 346.559788 -271.705021)
			(xy 346.555834 -271.656048) (xy 346.225876 -271.656048) (xy 346.225382 -271.680614) (xy 346.217501 -271.72911)
			(xy 346.201942 -271.775714) (xy 346.179109 -271.819218) (xy 346.149593 -271.858497) (xy 346.114159 -271.892532)
			(xy 346.073724 -271.920442) (xy 346.029335 -271.941505) (xy 345.982143 -271.955174) (xy 345.933369 -271.961096)
			(xy 345.884277 -271.959118) (xy 345.836137 -271.94929) (xy 345.790198 -271.931868) (xy 345.747648 -271.907302)
			(xy 345.70959 -271.876228) (xy 345.677009 -271.839452) (xy 345.65075 -271.797926) (xy 345.631492 -271.752725)
			(xy 345.619734 -271.705021) (xy 345.61578 -271.656048) (xy 126.479549 -271.656048) (xy 126.479554 -271.656302)
			(xy 126.47906 -271.680868) (xy 126.471179 -271.729364) (xy 126.45562 -271.775968) (xy 126.432787 -271.819472)
			(xy 126.403271 -271.858751) (xy 126.367837 -271.892786) (xy 126.327402 -271.920696) (xy 126.283013 -271.941759)
			(xy 126.235821 -271.955428) (xy 126.187047 -271.96135) (xy 126.137955 -271.959372) (xy 126.089815 -271.949544)
			(xy 126.043876 -271.932122) (xy 126.001326 -271.907556) (xy 125.963268 -271.876482) (xy 125.930687 -271.839706)
			(xy 125.904428 -271.79818) (xy 125.88517 -271.752979) (xy 125.873412 -271.705275) (xy 125.869458 -271.656302)
			(xy 125.5395 -271.656302) (xy 125.539006 -271.680868) (xy 125.531125 -271.729364) (xy 125.515566 -271.775968)
			(xy 125.492733 -271.819472) (xy 125.463217 -271.858751) (xy 125.427783 -271.892786) (xy 125.387348 -271.920696)
			(xy 125.342959 -271.941759) (xy 125.295767 -271.955428) (xy 125.246993 -271.96135) (xy 125.197901 -271.959372)
			(xy 125.149761 -271.949544) (xy 125.103822 -271.932122) (xy 125.061272 -271.907556) (xy 125.023214 -271.876482)
			(xy 124.990633 -271.839706) (xy 124.964374 -271.79818) (xy 124.945116 -271.752979) (xy 124.933358 -271.705275)
			(xy 124.929404 -271.656302) (xy 123.659392 -271.656302) (xy 123.658898 -271.680868) (xy 123.651017 -271.729364)
			(xy 123.635458 -271.775968) (xy 123.612625 -271.819472) (xy 123.583109 -271.858751) (xy 123.547675 -271.892786)
			(xy 123.50724 -271.920696) (xy 123.462851 -271.941759) (xy 123.415659 -271.955428) (xy 123.366885 -271.96135)
			(xy 123.317793 -271.959372) (xy 123.269653 -271.949544) (xy 123.223714 -271.932122) (xy 123.181164 -271.907556)
			(xy 123.143106 -271.876482) (xy 123.110525 -271.839706) (xy 123.084266 -271.79818) (xy 123.065008 -271.752979)
			(xy 123.05325 -271.705275) (xy 123.049296 -271.656302) (xy 122.719338 -271.656302) (xy 122.718844 -271.680868)
			(xy 122.710963 -271.729364) (xy 122.695404 -271.775968) (xy 122.672571 -271.819472) (xy 122.643055 -271.858751)
			(xy 122.607621 -271.892786) (xy 122.567186 -271.920696) (xy 122.522797 -271.941759) (xy 122.475605 -271.955428)
			(xy 122.426831 -271.96135) (xy 122.377739 -271.959372) (xy 122.329599 -271.949544) (xy 122.28366 -271.932122)
			(xy 122.24111 -271.907556) (xy 122.203052 -271.876482) (xy 122.170471 -271.839706) (xy 122.144212 -271.79818)
			(xy 122.124954 -271.752979) (xy 122.113196 -271.705275) (xy 122.109242 -271.656302) (xy 120.839484 -271.656302)
			(xy 120.83899 -271.680868) (xy 120.831109 -271.729364) (xy 120.81555 -271.775968) (xy 120.792717 -271.819472)
			(xy 120.763201 -271.858751) (xy 120.727767 -271.892786) (xy 120.687332 -271.920696) (xy 120.642943 -271.941759)
			(xy 120.595751 -271.955428) (xy 120.546977 -271.96135) (xy 120.497885 -271.959372) (xy 120.449745 -271.949544)
			(xy 120.403806 -271.932122) (xy 120.361256 -271.907556) (xy 120.323198 -271.876482) (xy 120.290617 -271.839706)
			(xy 120.264358 -271.79818) (xy 120.2451 -271.752979) (xy 120.233342 -271.705275) (xy 120.229388 -271.656302)
			(xy 119.89943 -271.656302) (xy 119.898936 -271.680868) (xy 119.891055 -271.729364) (xy 119.875496 -271.775968)
			(xy 119.852663 -271.819472) (xy 119.823147 -271.858751) (xy 119.787713 -271.892786) (xy 119.747278 -271.920696)
			(xy 119.702889 -271.941759) (xy 119.655697 -271.955428) (xy 119.606923 -271.96135) (xy 119.557831 -271.959372)
			(xy 119.509691 -271.949544) (xy 119.463752 -271.932122) (xy 119.421202 -271.907556) (xy 119.383144 -271.876482)
			(xy 119.350563 -271.839706) (xy 119.324304 -271.79818) (xy 119.305046 -271.752979) (xy 119.293288 -271.705275)
			(xy 119.289334 -271.656302) (xy 118.019576 -271.656302) (xy 118.019082 -271.680868) (xy 118.011201 -271.729364)
			(xy 117.995642 -271.775968) (xy 117.972809 -271.819472) (xy 117.943293 -271.858751) (xy 117.907859 -271.892786)
			(xy 117.867424 -271.920696) (xy 117.823035 -271.941759) (xy 117.775843 -271.955428) (xy 117.727069 -271.96135)
			(xy 117.677977 -271.959372) (xy 117.629837 -271.949544) (xy 117.583898 -271.932122) (xy 117.541348 -271.907556)
			(xy 117.50329 -271.876482) (xy 117.470709 -271.839706) (xy 117.44445 -271.79818) (xy 117.425192 -271.752979)
			(xy 117.413434 -271.705275) (xy 117.40948 -271.656302) (xy 117.079522 -271.656302) (xy 117.079028 -271.680868)
			(xy 117.071147 -271.729364) (xy 117.055588 -271.775968) (xy 117.032755 -271.819472) (xy 117.003239 -271.858751)
			(xy 116.967805 -271.892786) (xy 116.92737 -271.920696) (xy 116.882981 -271.941759) (xy 116.835789 -271.955428)
			(xy 116.787015 -271.96135) (xy 116.737923 -271.959372) (xy 116.689783 -271.949544) (xy 116.643844 -271.932122)
			(xy 116.601294 -271.907556) (xy 116.563236 -271.876482) (xy 116.530655 -271.839706) (xy 116.504396 -271.79818)
			(xy 116.485138 -271.752979) (xy 116.47338 -271.705275) (xy 116.469426 -271.656302) (xy 107.68584 -271.656302)
			(xy 107.685346 -271.680868) (xy 107.677465 -271.729364) (xy 107.661906 -271.775968) (xy 107.639073 -271.819472)
			(xy 107.609557 -271.858751) (xy 107.574123 -271.892786) (xy 107.533688 -271.920696) (xy 107.489299 -271.941759)
			(xy 107.442107 -271.955428) (xy 107.393333 -271.96135) (xy 107.344241 -271.959372) (xy 107.296101 -271.949544)
			(xy 107.250162 -271.932122) (xy 107.207612 -271.907556) (xy 107.169554 -271.876482) (xy 107.136973 -271.839706)
			(xy 107.110714 -271.79818) (xy 107.091456 -271.752979) (xy 107.079698 -271.705275) (xy 107.075744 -271.656302)
			(xy 106.745786 -271.656302) (xy 106.745292 -271.680868) (xy 106.737411 -271.729364) (xy 106.721852 -271.775968)
			(xy 106.699019 -271.819472) (xy 106.669503 -271.858751) (xy 106.634069 -271.892786) (xy 106.593634 -271.920696)
			(xy 106.549245 -271.941759) (xy 106.502053 -271.955428) (xy 106.453279 -271.96135) (xy 106.404187 -271.959372)
			(xy 106.356047 -271.949544) (xy 106.310108 -271.932122) (xy 106.267558 -271.907556) (xy 106.2295 -271.876482)
			(xy 106.196919 -271.839706) (xy 106.17066 -271.79818) (xy 106.151402 -271.752979) (xy 106.139644 -271.705275)
			(xy 106.13569 -271.656302) (xy 104.865932 -271.656302) (xy 104.865438 -271.680868) (xy 104.857557 -271.729364)
			(xy 104.841998 -271.775968) (xy 104.819165 -271.819472) (xy 104.789649 -271.858751) (xy 104.754215 -271.892786)
			(xy 104.71378 -271.920696) (xy 104.669391 -271.941759) (xy 104.622199 -271.955428) (xy 104.573425 -271.96135)
			(xy 104.524333 -271.959372) (xy 104.476193 -271.949544) (xy 104.430254 -271.932122) (xy 104.387704 -271.907556)
			(xy 104.349646 -271.876482) (xy 104.317065 -271.839706) (xy 104.290806 -271.79818) (xy 104.271548 -271.752979)
			(xy 104.25979 -271.705275) (xy 104.255836 -271.656302) (xy 103.925878 -271.656302) (xy 103.925384 -271.680868)
			(xy 103.917503 -271.729364) (xy 103.901944 -271.775968) (xy 103.879111 -271.819472) (xy 103.849595 -271.858751)
			(xy 103.814161 -271.892786) (xy 103.773726 -271.920696) (xy 103.729337 -271.941759) (xy 103.682145 -271.955428)
			(xy 103.633371 -271.96135) (xy 103.584279 -271.959372) (xy 103.536139 -271.949544) (xy 103.4902 -271.932122)
			(xy 103.44765 -271.907556) (xy 103.409592 -271.876482) (xy 103.377011 -271.839706) (xy 103.350752 -271.79818)
			(xy 103.331494 -271.752979) (xy 103.319736 -271.705275) (xy 103.315782 -271.656302) (xy 102.04577 -271.656302)
			(xy 102.045276 -271.680868) (xy 102.037395 -271.729364) (xy 102.021836 -271.775968) (xy 101.999003 -271.819472)
			(xy 101.969487 -271.858751) (xy 101.934053 -271.892786) (xy 101.893618 -271.920696) (xy 101.849229 -271.941759)
			(xy 101.802037 -271.955428) (xy 101.753263 -271.96135) (xy 101.704171 -271.959372) (xy 101.656031 -271.949544)
			(xy 101.610092 -271.932122) (xy 101.567542 -271.907556) (xy 101.529484 -271.876482) (xy 101.496903 -271.839706)
			(xy 101.470644 -271.79818) (xy 101.451386 -271.752979) (xy 101.439628 -271.705275) (xy 101.435674 -271.656302)
			(xy 101.105716 -271.656302) (xy 101.105222 -271.680868) (xy 101.097341 -271.729364) (xy 101.081782 -271.775968)
			(xy 101.058949 -271.819472) (xy 101.029433 -271.858751) (xy 100.993999 -271.892786) (xy 100.953564 -271.920696)
			(xy 100.909175 -271.941759) (xy 100.861983 -271.955428) (xy 100.813209 -271.96135) (xy 100.764117 -271.959372)
			(xy 100.715977 -271.949544) (xy 100.670038 -271.932122) (xy 100.627488 -271.907556) (xy 100.58943 -271.876482)
			(xy 100.556849 -271.839706) (xy 100.53059 -271.79818) (xy 100.511332 -271.752979) (xy 100.499574 -271.705275)
			(xy 100.49562 -271.656302) (xy 99.225862 -271.656302) (xy 99.225368 -271.680868) (xy 99.217487 -271.729364)
			(xy 99.201928 -271.775968) (xy 99.179095 -271.819472) (xy 99.149579 -271.858751) (xy 99.114145 -271.892786)
			(xy 99.07371 -271.920696) (xy 99.029321 -271.941759) (xy 98.982129 -271.955428) (xy 98.933355 -271.96135)
			(xy 98.884263 -271.959372) (xy 98.836123 -271.949544) (xy 98.790184 -271.932122) (xy 98.747634 -271.907556)
			(xy 98.709576 -271.876482) (xy 98.676995 -271.839706) (xy 98.650736 -271.79818) (xy 98.631478 -271.752979)
			(xy 98.61972 -271.705275) (xy 98.615766 -271.656302) (xy 98.285808 -271.656302) (xy 98.285314 -271.680868)
			(xy 98.277433 -271.729364) (xy 98.261874 -271.775968) (xy 98.239041 -271.819472) (xy 98.209525 -271.858751)
			(xy 98.174091 -271.892786) (xy 98.133656 -271.920696) (xy 98.089267 -271.941759) (xy 98.042075 -271.955428)
			(xy 97.993301 -271.96135) (xy 97.944209 -271.959372) (xy 97.896069 -271.949544) (xy 97.85013 -271.932122)
			(xy 97.80758 -271.907556) (xy 97.769522 -271.876482) (xy 97.736941 -271.839706) (xy 97.710682 -271.79818)
			(xy 97.691424 -271.752979) (xy 97.679666 -271.705275) (xy 97.675712 -271.656302) (xy 2.509012 -271.656302)
			(xy 2.509012 -272.466308) (xy 108.485698 -272.466308) (xy 108.489652 -272.417335) (xy 108.50141 -272.369631)
			(xy 108.520668 -272.32443) (xy 108.546927 -272.282904) (xy 108.579508 -272.246128) (xy 108.617566 -272.215054)
			(xy 108.660116 -272.190488) (xy 108.706055 -272.173066) (xy 108.754195 -272.163238) (xy 108.803287 -272.16126)
			(xy 108.852061 -272.167182) (xy 108.899253 -272.180851) (xy 108.943642 -272.201914) (xy 108.984077 -272.229824)
			(xy 109.019511 -272.263859) (xy 109.049027 -272.303138) (xy 109.07186 -272.346642) (xy 109.087419 -272.393246)
			(xy 109.0953 -272.441742) (xy 109.095794 -272.466308) (xy 109.425752 -272.466308) (xy 109.429706 -272.417335)
			(xy 109.441464 -272.369631) (xy 109.460722 -272.32443) (xy 109.486981 -272.282904) (xy 109.519562 -272.246128)
			(xy 109.55762 -272.215054) (xy 109.60017 -272.190488) (xy 109.646109 -272.173066) (xy 109.694249 -272.163238)
			(xy 109.743341 -272.16126) (xy 109.792115 -272.167182) (xy 109.839307 -272.180851) (xy 109.883696 -272.201914)
			(xy 109.924131 -272.229824) (xy 109.959565 -272.263859) (xy 109.989081 -272.303138) (xy 110.011914 -272.346642)
			(xy 110.027473 -272.393246) (xy 110.035354 -272.441742) (xy 110.035848 -272.466308) (xy 114.119418 -272.466308)
			(xy 114.123372 -272.417335) (xy 114.13513 -272.369631) (xy 114.154388 -272.32443) (xy 114.180647 -272.282904)
			(xy 114.213228 -272.246128) (xy 114.251286 -272.215054) (xy 114.293836 -272.190488) (xy 114.339775 -272.173066)
			(xy 114.387915 -272.163238) (xy 114.437007 -272.16126) (xy 114.485781 -272.167182) (xy 114.532973 -272.180851)
			(xy 114.577362 -272.201914) (xy 114.617797 -272.229824) (xy 114.653231 -272.263859) (xy 114.682747 -272.303138)
			(xy 114.70558 -272.346642) (xy 114.721139 -272.393246) (xy 114.72902 -272.441742) (xy 114.729514 -272.466308)
			(xy 115.059472 -272.466308) (xy 115.063426 -272.417335) (xy 115.075184 -272.369631) (xy 115.094442 -272.32443)
			(xy 115.120701 -272.282904) (xy 115.153282 -272.246128) (xy 115.19134 -272.215054) (xy 115.23389 -272.190488)
			(xy 115.279829 -272.173066) (xy 115.327969 -272.163238) (xy 115.377061 -272.16126) (xy 115.425835 -272.167182)
			(xy 115.473027 -272.180851) (xy 115.517416 -272.201914) (xy 115.557851 -272.229824) (xy 115.593285 -272.263859)
			(xy 115.622801 -272.303138) (xy 115.645634 -272.346642) (xy 115.661193 -272.393246) (xy 115.669074 -272.441742)
			(xy 115.669563 -272.466054) (xy 356.425766 -272.466054) (xy 356.42972 -272.417081) (xy 356.441478 -272.369377)
			(xy 356.460736 -272.324176) (xy 356.486995 -272.28265) (xy 356.519576 -272.245874) (xy 356.557634 -272.2148)
			(xy 356.600184 -272.190234) (xy 356.646123 -272.172812) (xy 356.694263 -272.162984) (xy 356.743355 -272.161006)
			(xy 356.792129 -272.166928) (xy 356.839321 -272.180597) (xy 356.88371 -272.20166) (xy 356.924145 -272.22957)
			(xy 356.959579 -272.263605) (xy 356.989095 -272.302884) (xy 357.011928 -272.346388) (xy 357.027487 -272.392992)
			(xy 357.035368 -272.441488) (xy 357.035862 -272.466054) (xy 357.36582 -272.466054) (xy 357.369774 -272.417081)
			(xy 357.381532 -272.369377) (xy 357.40079 -272.324176) (xy 357.427049 -272.28265) (xy 357.45963 -272.245874)
			(xy 357.497688 -272.2148) (xy 357.540238 -272.190234) (xy 357.586177 -272.172812) (xy 357.634317 -272.162984)
			(xy 357.683409 -272.161006) (xy 357.732183 -272.166928) (xy 357.779375 -272.180597) (xy 357.823764 -272.20166)
			(xy 357.864199 -272.22957) (xy 357.899633 -272.263605) (xy 357.929149 -272.302884) (xy 357.951982 -272.346388)
			(xy 357.967541 -272.392992) (xy 357.975422 -272.441488) (xy 357.975916 -272.466054) (xy 362.059486 -272.466054)
			(xy 362.06344 -272.417081) (xy 362.075198 -272.369377) (xy 362.094456 -272.324176) (xy 362.120715 -272.28265)
			(xy 362.153296 -272.245874) (xy 362.191354 -272.2148) (xy 362.233904 -272.190234) (xy 362.279843 -272.172812)
			(xy 362.327983 -272.162984) (xy 362.377075 -272.161006) (xy 362.425849 -272.166928) (xy 362.473041 -272.180597)
			(xy 362.51743 -272.20166) (xy 362.557865 -272.22957) (xy 362.593299 -272.263605) (xy 362.622815 -272.302884)
			(xy 362.645648 -272.346388) (xy 362.661207 -272.392992) (xy 362.669088 -272.441488) (xy 362.669582 -272.466054)
			(xy 362.99954 -272.466054) (xy 363.003494 -272.417081) (xy 363.015252 -272.369377) (xy 363.03451 -272.324176)
			(xy 363.060769 -272.28265) (xy 363.09335 -272.245874) (xy 363.131408 -272.2148) (xy 363.173958 -272.190234)
			(xy 363.219897 -272.172812) (xy 363.268037 -272.162984) (xy 363.317129 -272.161006) (xy 363.365903 -272.166928)
			(xy 363.413095 -272.180597) (xy 363.457484 -272.20166) (xy 363.497919 -272.22957) (xy 363.533353 -272.263605)
			(xy 363.562869 -272.302884) (xy 363.585702 -272.346388) (xy 363.601261 -272.392992) (xy 363.609142 -272.441488)
			(xy 363.609636 -272.466054) (xy 363.609142 -272.49062) (xy 363.601261 -272.539116) (xy 363.585702 -272.58572)
			(xy 363.562869 -272.629224) (xy 363.533353 -272.668503) (xy 363.497919 -272.702538) (xy 363.457484 -272.730448)
			(xy 363.413095 -272.751511) (xy 363.365903 -272.76518) (xy 363.317129 -272.771102) (xy 363.268037 -272.769124)
			(xy 363.219897 -272.759296) (xy 363.173958 -272.741874) (xy 363.131408 -272.717308) (xy 363.09335 -272.686234)
			(xy 363.060769 -272.649458) (xy 363.03451 -272.607932) (xy 363.015252 -272.562731) (xy 363.003494 -272.515027)
			(xy 362.99954 -272.466054) (xy 362.669582 -272.466054) (xy 362.669088 -272.49062) (xy 362.661207 -272.539116)
			(xy 362.645648 -272.58572) (xy 362.622815 -272.629224) (xy 362.593299 -272.668503) (xy 362.557865 -272.702538)
			(xy 362.51743 -272.730448) (xy 362.473041 -272.751511) (xy 362.425849 -272.76518) (xy 362.377075 -272.771102)
			(xy 362.327983 -272.769124) (xy 362.279843 -272.759296) (xy 362.233904 -272.741874) (xy 362.191354 -272.717308)
			(xy 362.153296 -272.686234) (xy 362.120715 -272.649458) (xy 362.094456 -272.607932) (xy 362.075198 -272.562731)
			(xy 362.06344 -272.515027) (xy 362.059486 -272.466054) (xy 357.975916 -272.466054) (xy 357.975422 -272.49062)
			(xy 357.967541 -272.539116) (xy 357.951982 -272.58572) (xy 357.929149 -272.629224) (xy 357.899633 -272.668503)
			(xy 357.864199 -272.702538) (xy 357.823764 -272.730448) (xy 357.779375 -272.751511) (xy 357.732183 -272.76518)
			(xy 357.683409 -272.771102) (xy 357.634317 -272.769124) (xy 357.586177 -272.759296) (xy 357.540238 -272.741874)
			(xy 357.497688 -272.717308) (xy 357.45963 -272.686234) (xy 357.427049 -272.649458) (xy 357.40079 -272.607932)
			(xy 357.381532 -272.562731) (xy 357.369774 -272.515027) (xy 357.36582 -272.466054) (xy 357.035862 -272.466054)
			(xy 357.035368 -272.49062) (xy 357.027487 -272.539116) (xy 357.011928 -272.58572) (xy 356.989095 -272.629224)
			(xy 356.959579 -272.668503) (xy 356.924145 -272.702538) (xy 356.88371 -272.730448) (xy 356.839321 -272.751511)
			(xy 356.792129 -272.76518) (xy 356.743355 -272.771102) (xy 356.694263 -272.769124) (xy 356.646123 -272.759296)
			(xy 356.600184 -272.741874) (xy 356.557634 -272.717308) (xy 356.519576 -272.686234) (xy 356.486995 -272.649458)
			(xy 356.460736 -272.607932) (xy 356.441478 -272.562731) (xy 356.42972 -272.515027) (xy 356.425766 -272.466054)
			(xy 115.669563 -272.466054) (xy 115.669568 -272.466308) (xy 115.669074 -272.490874) (xy 115.661193 -272.53937)
			(xy 115.645634 -272.585974) (xy 115.622801 -272.629478) (xy 115.593285 -272.668757) (xy 115.557851 -272.702792)
			(xy 115.517416 -272.730702) (xy 115.473027 -272.751765) (xy 115.425835 -272.765434) (xy 115.377061 -272.771356)
			(xy 115.327969 -272.769378) (xy 115.279829 -272.75955) (xy 115.23389 -272.742128) (xy 115.19134 -272.717562)
			(xy 115.153282 -272.686488) (xy 115.120701 -272.649712) (xy 115.094442 -272.608186) (xy 115.075184 -272.562985)
			(xy 115.063426 -272.515281) (xy 115.059472 -272.466308) (xy 114.729514 -272.466308) (xy 114.72902 -272.490874)
			(xy 114.721139 -272.53937) (xy 114.70558 -272.585974) (xy 114.682747 -272.629478) (xy 114.653231 -272.668757)
			(xy 114.617797 -272.702792) (xy 114.577362 -272.730702) (xy 114.532973 -272.751765) (xy 114.485781 -272.765434)
			(xy 114.437007 -272.771356) (xy 114.387915 -272.769378) (xy 114.339775 -272.75955) (xy 114.293836 -272.742128)
			(xy 114.251286 -272.717562) (xy 114.213228 -272.686488) (xy 114.180647 -272.649712) (xy 114.154388 -272.608186)
			(xy 114.13513 -272.562985) (xy 114.123372 -272.515281) (xy 114.119418 -272.466308) (xy 110.035848 -272.466308)
			(xy 110.035354 -272.490874) (xy 110.027473 -272.53937) (xy 110.011914 -272.585974) (xy 109.989081 -272.629478)
			(xy 109.959565 -272.668757) (xy 109.924131 -272.702792) (xy 109.883696 -272.730702) (xy 109.839307 -272.751765)
			(xy 109.792115 -272.765434) (xy 109.743341 -272.771356) (xy 109.694249 -272.769378) (xy 109.646109 -272.75955)
			(xy 109.60017 -272.742128) (xy 109.55762 -272.717562) (xy 109.519562 -272.686488) (xy 109.486981 -272.649712)
			(xy 109.460722 -272.608186) (xy 109.441464 -272.562985) (xy 109.429706 -272.515281) (xy 109.425752 -272.466308)
			(xy 109.095794 -272.466308) (xy 109.0953 -272.490874) (xy 109.087419 -272.53937) (xy 109.07186 -272.585974)
			(xy 109.049027 -272.629478) (xy 109.019511 -272.668757) (xy 108.984077 -272.702792) (xy 108.943642 -272.730702)
			(xy 108.899253 -272.751765) (xy 108.852061 -272.765434) (xy 108.803287 -272.771356) (xy 108.754195 -272.769378)
			(xy 108.706055 -272.75955) (xy 108.660116 -272.742128) (xy 108.617566 -272.717562) (xy 108.579508 -272.686488)
			(xy 108.546927 -272.649712) (xy 108.520668 -272.608186) (xy 108.50141 -272.562985) (xy 108.489652 -272.515281)
			(xy 108.485698 -272.466308) (xy 2.509012 -272.466308) (xy 2.509012 -273.276314) (xy 97.675712 -273.276314)
			(xy 97.679666 -273.227341) (xy 97.691424 -273.179637) (xy 97.710682 -273.134436) (xy 97.736941 -273.09291)
			(xy 97.769522 -273.056134) (xy 97.80758 -273.02506) (xy 97.85013 -273.000494) (xy 97.896069 -272.983072)
			(xy 97.944209 -272.973244) (xy 97.993301 -272.971266) (xy 98.042075 -272.977188) (xy 98.089267 -272.990857)
			(xy 98.133656 -273.01192) (xy 98.174091 -273.03983) (xy 98.209525 -273.073865) (xy 98.239041 -273.113144)
			(xy 98.261874 -273.156648) (xy 98.277433 -273.203252) (xy 98.285314 -273.251748) (xy 98.285808 -273.276314)
			(xy 98.615766 -273.276314) (xy 98.61972 -273.227341) (xy 98.631478 -273.179637) (xy 98.650736 -273.134436)
			(xy 98.676995 -273.09291) (xy 98.709576 -273.056134) (xy 98.747634 -273.02506) (xy 98.790184 -273.000494)
			(xy 98.836123 -272.983072) (xy 98.884263 -272.973244) (xy 98.933355 -272.971266) (xy 98.982129 -272.977188)
			(xy 99.029321 -272.990857) (xy 99.07371 -273.01192) (xy 99.114145 -273.03983) (xy 99.149579 -273.073865)
			(xy 99.179095 -273.113144) (xy 99.201928 -273.156648) (xy 99.217487 -273.203252) (xy 99.225368 -273.251748)
			(xy 99.225862 -273.276314) (xy 100.49562 -273.276314) (xy 100.499574 -273.227341) (xy 100.511332 -273.179637)
			(xy 100.53059 -273.134436) (xy 100.556849 -273.09291) (xy 100.58943 -273.056134) (xy 100.627488 -273.02506)
			(xy 100.670038 -273.000494) (xy 100.715977 -272.983072) (xy 100.764117 -272.973244) (xy 100.813209 -272.971266)
			(xy 100.861983 -272.977188) (xy 100.909175 -272.990857) (xy 100.953564 -273.01192) (xy 100.993999 -273.03983)
			(xy 101.029433 -273.073865) (xy 101.058949 -273.113144) (xy 101.081782 -273.156648) (xy 101.097341 -273.203252)
			(xy 101.105222 -273.251748) (xy 101.105716 -273.276314) (xy 101.435674 -273.276314) (xy 101.439628 -273.227341)
			(xy 101.451386 -273.179637) (xy 101.470644 -273.134436) (xy 101.496903 -273.09291) (xy 101.529484 -273.056134)
			(xy 101.567542 -273.02506) (xy 101.610092 -273.000494) (xy 101.656031 -272.983072) (xy 101.704171 -272.973244)
			(xy 101.753263 -272.971266) (xy 101.802037 -272.977188) (xy 101.849229 -272.990857) (xy 101.893618 -273.01192)
			(xy 101.934053 -273.03983) (xy 101.969487 -273.073865) (xy 101.999003 -273.113144) (xy 102.021836 -273.156648)
			(xy 102.037395 -273.203252) (xy 102.045276 -273.251748) (xy 102.04577 -273.276314) (xy 103.315782 -273.276314)
			(xy 103.319736 -273.227341) (xy 103.331494 -273.179637) (xy 103.350752 -273.134436) (xy 103.377011 -273.09291)
			(xy 103.409592 -273.056134) (xy 103.44765 -273.02506) (xy 103.4902 -273.000494) (xy 103.536139 -272.983072)
			(xy 103.584279 -272.973244) (xy 103.633371 -272.971266) (xy 103.682145 -272.977188) (xy 103.729337 -272.990857)
			(xy 103.773726 -273.01192) (xy 103.814161 -273.03983) (xy 103.849595 -273.073865) (xy 103.879111 -273.113144)
			(xy 103.901944 -273.156648) (xy 103.917503 -273.203252) (xy 103.925384 -273.251748) (xy 103.925878 -273.276314)
			(xy 104.255836 -273.276314) (xy 104.25979 -273.227341) (xy 104.271548 -273.179637) (xy 104.290806 -273.134436)
			(xy 104.317065 -273.09291) (xy 104.349646 -273.056134) (xy 104.387704 -273.02506) (xy 104.430254 -273.000494)
			(xy 104.476193 -272.983072) (xy 104.524333 -272.973244) (xy 104.573425 -272.971266) (xy 104.622199 -272.977188)
			(xy 104.669391 -272.990857) (xy 104.71378 -273.01192) (xy 104.754215 -273.03983) (xy 104.789649 -273.073865)
			(xy 104.819165 -273.113144) (xy 104.841998 -273.156648) (xy 104.857557 -273.203252) (xy 104.865438 -273.251748)
			(xy 104.865932 -273.276314) (xy 106.13569 -273.276314) (xy 106.139644 -273.227341) (xy 106.151402 -273.179637)
			(xy 106.17066 -273.134436) (xy 106.196919 -273.09291) (xy 106.2295 -273.056134) (xy 106.267558 -273.02506)
			(xy 106.310108 -273.000494) (xy 106.356047 -272.983072) (xy 106.404187 -272.973244) (xy 106.453279 -272.971266)
			(xy 106.502053 -272.977188) (xy 106.549245 -272.990857) (xy 106.593634 -273.01192) (xy 106.634069 -273.03983)
			(xy 106.669503 -273.073865) (xy 106.699019 -273.113144) (xy 106.721852 -273.156648) (xy 106.737411 -273.203252)
			(xy 106.745292 -273.251748) (xy 106.745786 -273.276314) (xy 107.075744 -273.276314) (xy 107.079698 -273.227341)
			(xy 107.091456 -273.179637) (xy 107.110714 -273.134436) (xy 107.136973 -273.09291) (xy 107.169554 -273.056134)
			(xy 107.207612 -273.02506) (xy 107.250162 -273.000494) (xy 107.296101 -272.983072) (xy 107.344241 -272.973244)
			(xy 107.393333 -272.971266) (xy 107.442107 -272.977188) (xy 107.489299 -272.990857) (xy 107.533688 -273.01192)
			(xy 107.574123 -273.03983) (xy 107.609557 -273.073865) (xy 107.639073 -273.113144) (xy 107.661906 -273.156648)
			(xy 107.677465 -273.203252) (xy 107.685346 -273.251748) (xy 107.68584 -273.276314) (xy 116.469426 -273.276314)
			(xy 116.47338 -273.227341) (xy 116.485138 -273.179637) (xy 116.504396 -273.134436) (xy 116.530655 -273.09291)
			(xy 116.563236 -273.056134) (xy 116.601294 -273.02506) (xy 116.643844 -273.000494) (xy 116.689783 -272.983072)
			(xy 116.737923 -272.973244) (xy 116.787015 -272.971266) (xy 116.835789 -272.977188) (xy 116.882981 -272.990857)
			(xy 116.92737 -273.01192) (xy 116.967805 -273.03983) (xy 117.003239 -273.073865) (xy 117.032755 -273.113144)
			(xy 117.055588 -273.156648) (xy 117.071147 -273.203252) (xy 117.079028 -273.251748) (xy 117.079522 -273.276314)
			(xy 117.40948 -273.276314) (xy 117.413434 -273.227341) (xy 117.425192 -273.179637) (xy 117.44445 -273.134436)
			(xy 117.470709 -273.09291) (xy 117.50329 -273.056134) (xy 117.541348 -273.02506) (xy 117.583898 -273.000494)
			(xy 117.629837 -272.983072) (xy 117.677977 -272.973244) (xy 117.727069 -272.971266) (xy 117.775843 -272.977188)
			(xy 117.823035 -272.990857) (xy 117.867424 -273.01192) (xy 117.907859 -273.03983) (xy 117.943293 -273.073865)
			(xy 117.972809 -273.113144) (xy 117.995642 -273.156648) (xy 118.011201 -273.203252) (xy 118.019082 -273.251748)
			(xy 118.019576 -273.276314) (xy 119.289334 -273.276314) (xy 119.293288 -273.227341) (xy 119.305046 -273.179637)
			(xy 119.324304 -273.134436) (xy 119.350563 -273.09291) (xy 119.383144 -273.056134) (xy 119.421202 -273.02506)
			(xy 119.463752 -273.000494) (xy 119.509691 -272.983072) (xy 119.557831 -272.973244) (xy 119.606923 -272.971266)
			(xy 119.655697 -272.977188) (xy 119.702889 -272.990857) (xy 119.747278 -273.01192) (xy 119.787713 -273.03983)
			(xy 119.823147 -273.073865) (xy 119.852663 -273.113144) (xy 119.875496 -273.156648) (xy 119.891055 -273.203252)
			(xy 119.898936 -273.251748) (xy 119.89943 -273.276314) (xy 120.229388 -273.276314) (xy 120.233342 -273.227341)
			(xy 120.2451 -273.179637) (xy 120.264358 -273.134436) (xy 120.290617 -273.09291) (xy 120.323198 -273.056134)
			(xy 120.361256 -273.02506) (xy 120.403806 -273.000494) (xy 120.449745 -272.983072) (xy 120.497885 -272.973244)
			(xy 120.546977 -272.971266) (xy 120.595751 -272.977188) (xy 120.642943 -272.990857) (xy 120.687332 -273.01192)
			(xy 120.727767 -273.03983) (xy 120.763201 -273.073865) (xy 120.792717 -273.113144) (xy 120.81555 -273.156648)
			(xy 120.831109 -273.203252) (xy 120.83899 -273.251748) (xy 120.839484 -273.276314) (xy 122.109242 -273.276314)
			(xy 122.113196 -273.227341) (xy 122.124954 -273.179637) (xy 122.144212 -273.134436) (xy 122.170471 -273.09291)
			(xy 122.203052 -273.056134) (xy 122.24111 -273.02506) (xy 122.28366 -273.000494) (xy 122.329599 -272.983072)
			(xy 122.377739 -272.973244) (xy 122.426831 -272.971266) (xy 122.475605 -272.977188) (xy 122.522797 -272.990857)
			(xy 122.567186 -273.01192) (xy 122.607621 -273.03983) (xy 122.643055 -273.073865) (xy 122.672571 -273.113144)
			(xy 122.695404 -273.156648) (xy 122.710963 -273.203252) (xy 122.718844 -273.251748) (xy 122.719338 -273.276314)
			(xy 123.049296 -273.276314) (xy 123.05325 -273.227341) (xy 123.065008 -273.179637) (xy 123.084266 -273.134436)
			(xy 123.110525 -273.09291) (xy 123.143106 -273.056134) (xy 123.181164 -273.02506) (xy 123.223714 -273.000494)
			(xy 123.269653 -272.983072) (xy 123.317793 -272.973244) (xy 123.366885 -272.971266) (xy 123.415659 -272.977188)
			(xy 123.462851 -272.990857) (xy 123.50724 -273.01192) (xy 123.547675 -273.03983) (xy 123.583109 -273.073865)
			(xy 123.612625 -273.113144) (xy 123.635458 -273.156648) (xy 123.651017 -273.203252) (xy 123.658898 -273.251748)
			(xy 123.659392 -273.276314) (xy 124.929404 -273.276314) (xy 124.933358 -273.227341) (xy 124.945116 -273.179637)
			(xy 124.964374 -273.134436) (xy 124.990633 -273.09291) (xy 125.023214 -273.056134) (xy 125.061272 -273.02506)
			(xy 125.103822 -273.000494) (xy 125.149761 -272.983072) (xy 125.197901 -272.973244) (xy 125.246993 -272.971266)
			(xy 125.295767 -272.977188) (xy 125.342959 -272.990857) (xy 125.387348 -273.01192) (xy 125.427783 -273.03983)
			(xy 125.463217 -273.073865) (xy 125.492733 -273.113144) (xy 125.515566 -273.156648) (xy 125.531125 -273.203252)
			(xy 125.539006 -273.251748) (xy 125.5395 -273.276314) (xy 125.869458 -273.276314) (xy 125.873412 -273.227341)
			(xy 125.88517 -273.179637) (xy 125.904428 -273.134436) (xy 125.930687 -273.09291) (xy 125.963268 -273.056134)
			(xy 126.001326 -273.02506) (xy 126.043876 -273.000494) (xy 126.089815 -272.983072) (xy 126.137955 -272.973244)
			(xy 126.187047 -272.971266) (xy 126.235821 -272.977188) (xy 126.283013 -272.990857) (xy 126.327402 -273.01192)
			(xy 126.367837 -273.03983) (xy 126.403271 -273.073865) (xy 126.432787 -273.113144) (xy 126.45562 -273.156648)
			(xy 126.471179 -273.203252) (xy 126.47906 -273.251748) (xy 126.479549 -273.27606) (xy 345.61578 -273.27606)
			(xy 345.619734 -273.227087) (xy 345.631492 -273.179383) (xy 345.65075 -273.134182) (xy 345.677009 -273.092656)
			(xy 345.70959 -273.05588) (xy 345.747648 -273.024806) (xy 345.790198 -273.00024) (xy 345.836137 -272.982818)
			(xy 345.884277 -272.97299) (xy 345.933369 -272.971012) (xy 345.982143 -272.976934) (xy 346.029335 -272.990603)
			(xy 346.073724 -273.011666) (xy 346.114159 -273.039576) (xy 346.149593 -273.073611) (xy 346.179109 -273.11289)
			(xy 346.201942 -273.156394) (xy 346.217501 -273.202998) (xy 346.225382 -273.251494) (xy 346.225876 -273.27606)
			(xy 346.555834 -273.27606) (xy 346.559788 -273.227087) (xy 346.571546 -273.179383) (xy 346.590804 -273.134182)
			(xy 346.617063 -273.092656) (xy 346.649644 -273.05588) (xy 346.687702 -273.024806) (xy 346.730252 -273.00024)
			(xy 346.776191 -272.982818) (xy 346.824331 -272.97299) (xy 346.873423 -272.971012) (xy 346.922197 -272.976934)
			(xy 346.969389 -272.990603) (xy 347.013778 -273.011666) (xy 347.054213 -273.039576) (xy 347.089647 -273.073611)
			(xy 347.119163 -273.11289) (xy 347.141996 -273.156394) (xy 347.157555 -273.202998) (xy 347.165436 -273.251494)
			(xy 347.16593 -273.27606) (xy 348.435688 -273.27606) (xy 348.439642 -273.227087) (xy 348.4514 -273.179383)
			(xy 348.470658 -273.134182) (xy 348.496917 -273.092656) (xy 348.529498 -273.05588) (xy 348.567556 -273.024806)
			(xy 348.610106 -273.00024) (xy 348.656045 -272.982818) (xy 348.704185 -272.97299) (xy 348.753277 -272.971012)
			(xy 348.802051 -272.976934) (xy 348.849243 -272.990603) (xy 348.893632 -273.011666) (xy 348.934067 -273.039576)
			(xy 348.969501 -273.073611) (xy 348.999017 -273.11289) (xy 349.02185 -273.156394) (xy 349.037409 -273.202998)
			(xy 349.04529 -273.251494) (xy 349.045784 -273.27606) (xy 349.375742 -273.27606) (xy 349.379696 -273.227087)
			(xy 349.391454 -273.179383) (xy 349.410712 -273.134182) (xy 349.436971 -273.092656) (xy 349.469552 -273.05588)
			(xy 349.50761 -273.024806) (xy 349.55016 -273.00024) (xy 349.596099 -272.982818) (xy 349.644239 -272.97299)
			(xy 349.693331 -272.971012) (xy 349.742105 -272.976934) (xy 349.789297 -272.990603) (xy 349.833686 -273.011666)
			(xy 349.874121 -273.039576) (xy 349.909555 -273.073611) (xy 349.939071 -273.11289) (xy 349.961904 -273.156394)
			(xy 349.977463 -273.202998) (xy 349.985344 -273.251494) (xy 349.985838 -273.27606) (xy 351.25585 -273.27606)
			(xy 351.259804 -273.227087) (xy 351.271562 -273.179383) (xy 351.29082 -273.134182) (xy 351.317079 -273.092656)
			(xy 351.34966 -273.05588) (xy 351.387718 -273.024806) (xy 351.430268 -273.00024) (xy 351.476207 -272.982818)
			(xy 351.524347 -272.97299) (xy 351.573439 -272.971012) (xy 351.622213 -272.976934) (xy 351.669405 -272.990603)
			(xy 351.713794 -273.011666) (xy 351.754229 -273.039576) (xy 351.789663 -273.073611) (xy 351.819179 -273.11289)
			(xy 351.842012 -273.156394) (xy 351.857571 -273.202998) (xy 351.865452 -273.251494) (xy 351.865946 -273.27606)
			(xy 352.195904 -273.27606) (xy 352.199858 -273.227087) (xy 352.211616 -273.179383) (xy 352.230874 -273.134182)
			(xy 352.257133 -273.092656) (xy 352.289714 -273.05588) (xy 352.327772 -273.024806) (xy 352.370322 -273.00024)
			(xy 352.416261 -272.982818) (xy 352.464401 -272.97299) (xy 352.513493 -272.971012) (xy 352.562267 -272.976934)
			(xy 352.609459 -272.990603) (xy 352.653848 -273.011666) (xy 352.694283 -273.039576) (xy 352.729717 -273.073611)
			(xy 352.759233 -273.11289) (xy 352.782066 -273.156394) (xy 352.797625 -273.202998) (xy 352.805506 -273.251494)
			(xy 352.806 -273.27606) (xy 354.075758 -273.27606) (xy 354.079712 -273.227087) (xy 354.09147 -273.179383)
			(xy 354.110728 -273.134182) (xy 354.136987 -273.092656) (xy 354.169568 -273.05588) (xy 354.207626 -273.024806)
			(xy 354.250176 -273.00024) (xy 354.296115 -272.982818) (xy 354.344255 -272.97299) (xy 354.393347 -272.971012)
			(xy 354.442121 -272.976934) (xy 354.489313 -272.990603) (xy 354.533702 -273.011666) (xy 354.574137 -273.039576)
			(xy 354.609571 -273.073611) (xy 354.639087 -273.11289) (xy 354.66192 -273.156394) (xy 354.677479 -273.202998)
			(xy 354.68536 -273.251494) (xy 354.685854 -273.27606) (xy 355.015812 -273.27606) (xy 355.019766 -273.227087)
			(xy 355.031524 -273.179383) (xy 355.050782 -273.134182) (xy 355.077041 -273.092656) (xy 355.109622 -273.05588)
			(xy 355.14768 -273.024806) (xy 355.19023 -273.00024) (xy 355.236169 -272.982818) (xy 355.284309 -272.97299)
			(xy 355.333401 -272.971012) (xy 355.382175 -272.976934) (xy 355.429367 -272.990603) (xy 355.473756 -273.011666)
			(xy 355.514191 -273.039576) (xy 355.549625 -273.073611) (xy 355.579141 -273.11289) (xy 355.601974 -273.156394)
			(xy 355.617533 -273.202998) (xy 355.625414 -273.251494) (xy 355.625908 -273.27606) (xy 364.409494 -273.27606)
			(xy 364.413448 -273.227087) (xy 364.425206 -273.179383) (xy 364.444464 -273.134182) (xy 364.470723 -273.092656)
			(xy 364.503304 -273.05588) (xy 364.541362 -273.024806) (xy 364.583912 -273.00024) (xy 364.629851 -272.982818)
			(xy 364.677991 -272.97299) (xy 364.727083 -272.971012) (xy 364.775857 -272.976934) (xy 364.823049 -272.990603)
			(xy 364.867438 -273.011666) (xy 364.907873 -273.039576) (xy 364.943307 -273.073611) (xy 364.972823 -273.11289)
			(xy 364.995656 -273.156394) (xy 365.011215 -273.202998) (xy 365.019096 -273.251494) (xy 365.01959 -273.27606)
			(xy 365.349548 -273.27606) (xy 365.353502 -273.227087) (xy 365.36526 -273.179383) (xy 365.384518 -273.134182)
			(xy 365.410777 -273.092656) (xy 365.443358 -273.05588) (xy 365.481416 -273.024806) (xy 365.523966 -273.00024)
			(xy 365.569905 -272.982818) (xy 365.618045 -272.97299) (xy 365.667137 -272.971012) (xy 365.715911 -272.976934)
			(xy 365.763103 -272.990603) (xy 365.807492 -273.011666) (xy 365.847927 -273.039576) (xy 365.883361 -273.073611)
			(xy 365.912877 -273.11289) (xy 365.93571 -273.156394) (xy 365.951269 -273.202998) (xy 365.95915 -273.251494)
			(xy 365.959644 -273.27606) (xy 367.229402 -273.27606) (xy 367.233356 -273.227087) (xy 367.245114 -273.179383)
			(xy 367.264372 -273.134182) (xy 367.290631 -273.092656) (xy 367.323212 -273.05588) (xy 367.36127 -273.024806)
			(xy 367.40382 -273.00024) (xy 367.449759 -272.982818) (xy 367.497899 -272.97299) (xy 367.546991 -272.971012)
			(xy 367.595765 -272.976934) (xy 367.642957 -272.990603) (xy 367.687346 -273.011666) (xy 367.727781 -273.039576)
			(xy 367.763215 -273.073611) (xy 367.792731 -273.11289) (xy 367.815564 -273.156394) (xy 367.831123 -273.202998)
			(xy 367.839004 -273.251494) (xy 367.839498 -273.27606) (xy 368.169456 -273.27606) (xy 368.17341 -273.227087)
			(xy 368.185168 -273.179383) (xy 368.204426 -273.134182) (xy 368.230685 -273.092656) (xy 368.263266 -273.05588)
			(xy 368.301324 -273.024806) (xy 368.343874 -273.00024) (xy 368.389813 -272.982818) (xy 368.437953 -272.97299)
			(xy 368.487045 -272.971012) (xy 368.535819 -272.976934) (xy 368.583011 -272.990603) (xy 368.6274 -273.011666)
			(xy 368.667835 -273.039576) (xy 368.703269 -273.073611) (xy 368.732785 -273.11289) (xy 368.755618 -273.156394)
			(xy 368.771177 -273.202998) (xy 368.779058 -273.251494) (xy 368.779552 -273.27606) (xy 370.04931 -273.27606)
			(xy 370.053264 -273.227087) (xy 370.065022 -273.179383) (xy 370.08428 -273.134182) (xy 370.110539 -273.092656)
			(xy 370.14312 -273.05588) (xy 370.181178 -273.024806) (xy 370.223728 -273.00024) (xy 370.269667 -272.982818)
			(xy 370.317807 -272.97299) (xy 370.366899 -272.971012) (xy 370.415673 -272.976934) (xy 370.462865 -272.990603)
			(xy 370.507254 -273.011666) (xy 370.547689 -273.039576) (xy 370.583123 -273.073611) (xy 370.612639 -273.11289)
			(xy 370.635472 -273.156394) (xy 370.651031 -273.202998) (xy 370.658912 -273.251494) (xy 370.659406 -273.27606)
			(xy 370.989364 -273.27606) (xy 370.993318 -273.227087) (xy 371.005076 -273.179383) (xy 371.024334 -273.134182)
			(xy 371.050593 -273.092656) (xy 371.083174 -273.05588) (xy 371.121232 -273.024806) (xy 371.163782 -273.00024)
			(xy 371.209721 -272.982818) (xy 371.257861 -272.97299) (xy 371.306953 -272.971012) (xy 371.355727 -272.976934)
			(xy 371.402919 -272.990603) (xy 371.447308 -273.011666) (xy 371.487743 -273.039576) (xy 371.523177 -273.073611)
			(xy 371.552693 -273.11289) (xy 371.575526 -273.156394) (xy 371.591085 -273.202998) (xy 371.598966 -273.251494)
			(xy 371.59946 -273.27606) (xy 372.869472 -273.27606) (xy 372.873426 -273.227087) (xy 372.885184 -273.179383)
			(xy 372.904442 -273.134182) (xy 372.930701 -273.092656) (xy 372.963282 -273.05588) (xy 373.00134 -273.024806)
			(xy 373.04389 -273.00024) (xy 373.089829 -272.982818) (xy 373.137969 -272.97299) (xy 373.187061 -272.971012)
			(xy 373.235835 -272.976934) (xy 373.283027 -272.990603) (xy 373.327416 -273.011666) (xy 373.367851 -273.039576)
			(xy 373.403285 -273.073611) (xy 373.432801 -273.11289) (xy 373.455634 -273.156394) (xy 373.471193 -273.202998)
			(xy 373.479074 -273.251494) (xy 373.479568 -273.27606) (xy 373.809526 -273.27606) (xy 373.81348 -273.227087)
			(xy 373.825238 -273.179383) (xy 373.844496 -273.134182) (xy 373.870755 -273.092656) (xy 373.903336 -273.05588)
			(xy 373.941394 -273.024806) (xy 373.983944 -273.00024) (xy 374.029883 -272.982818) (xy 374.078023 -272.97299)
			(xy 374.127115 -272.971012) (xy 374.175889 -272.976934) (xy 374.223081 -272.990603) (xy 374.26747 -273.011666)
			(xy 374.307905 -273.039576) (xy 374.343339 -273.073611) (xy 374.372855 -273.11289) (xy 374.395688 -273.156394)
			(xy 374.411247 -273.202998) (xy 374.419128 -273.251494) (xy 374.419622 -273.27606) (xy 374.419128 -273.300626)
			(xy 374.411247 -273.349122) (xy 374.395688 -273.395726) (xy 374.372855 -273.43923) (xy 374.343339 -273.478509)
			(xy 374.307905 -273.512544) (xy 374.26747 -273.540454) (xy 374.223081 -273.561517) (xy 374.175889 -273.575186)
			(xy 374.127115 -273.581108) (xy 374.078023 -273.57913) (xy 374.029883 -273.569302) (xy 373.983944 -273.55188)
			(xy 373.941394 -273.527314) (xy 373.903336 -273.49624) (xy 373.870755 -273.459464) (xy 373.844496 -273.417938)
			(xy 373.825238 -273.372737) (xy 373.81348 -273.325033) (xy 373.809526 -273.27606) (xy 373.479568 -273.27606)
			(xy 373.479074 -273.300626) (xy 373.471193 -273.349122) (xy 373.455634 -273.395726) (xy 373.432801 -273.43923)
			(xy 373.403285 -273.478509) (xy 373.367851 -273.512544) (xy 373.327416 -273.540454) (xy 373.283027 -273.561517)
			(xy 373.235835 -273.575186) (xy 373.187061 -273.581108) (xy 373.137969 -273.57913) (xy 373.089829 -273.569302)
			(xy 373.04389 -273.55188) (xy 373.00134 -273.527314) (xy 372.963282 -273.49624) (xy 372.930701 -273.459464)
			(xy 372.904442 -273.417938) (xy 372.885184 -273.372737) (xy 372.873426 -273.325033) (xy 372.869472 -273.27606)
			(xy 371.59946 -273.27606) (xy 371.598966 -273.300626) (xy 371.591085 -273.349122) (xy 371.575526 -273.395726)
			(xy 371.552693 -273.43923) (xy 371.523177 -273.478509) (xy 371.487743 -273.512544) (xy 371.447308 -273.540454)
			(xy 371.402919 -273.561517) (xy 371.355727 -273.575186) (xy 371.306953 -273.581108) (xy 371.257861 -273.57913)
			(xy 371.209721 -273.569302) (xy 371.163782 -273.55188) (xy 371.121232 -273.527314) (xy 371.083174 -273.49624)
			(xy 371.050593 -273.459464) (xy 371.024334 -273.417938) (xy 371.005076 -273.372737) (xy 370.993318 -273.325033)
			(xy 370.989364 -273.27606) (xy 370.659406 -273.27606) (xy 370.658912 -273.300626) (xy 370.651031 -273.349122)
			(xy 370.635472 -273.395726) (xy 370.612639 -273.43923) (xy 370.583123 -273.478509) (xy 370.547689 -273.512544)
			(xy 370.507254 -273.540454) (xy 370.462865 -273.561517) (xy 370.415673 -273.575186) (xy 370.366899 -273.581108)
			(xy 370.317807 -273.57913) (xy 370.269667 -273.569302) (xy 370.223728 -273.55188) (xy 370.181178 -273.527314)
			(xy 370.14312 -273.49624) (xy 370.110539 -273.459464) (xy 370.08428 -273.417938) (xy 370.065022 -273.372737)
			(xy 370.053264 -273.325033) (xy 370.04931 -273.27606) (xy 368.779552 -273.27606) (xy 368.779058 -273.300626)
			(xy 368.771177 -273.349122) (xy 368.755618 -273.395726) (xy 368.732785 -273.43923) (xy 368.703269 -273.478509)
			(xy 368.667835 -273.512544) (xy 368.6274 -273.540454) (xy 368.583011 -273.561517) (xy 368.535819 -273.575186)
			(xy 368.487045 -273.581108) (xy 368.437953 -273.57913) (xy 368.389813 -273.569302) (xy 368.343874 -273.55188)
			(xy 368.301324 -273.527314) (xy 368.263266 -273.49624) (xy 368.230685 -273.459464) (xy 368.204426 -273.417938)
			(xy 368.185168 -273.372737) (xy 368.17341 -273.325033) (xy 368.169456 -273.27606) (xy 367.839498 -273.27606)
			(xy 367.839004 -273.300626) (xy 367.831123 -273.349122) (xy 367.815564 -273.395726) (xy 367.792731 -273.43923)
			(xy 367.763215 -273.478509) (xy 367.727781 -273.512544) (xy 367.687346 -273.540454) (xy 367.642957 -273.561517)
			(xy 367.595765 -273.575186) (xy 367.546991 -273.581108) (xy 367.497899 -273.57913) (xy 367.449759 -273.569302)
			(xy 367.40382 -273.55188) (xy 367.36127 -273.527314) (xy 367.323212 -273.49624) (xy 367.290631 -273.459464)
			(xy 367.264372 -273.417938) (xy 367.245114 -273.372737) (xy 367.233356 -273.325033) (xy 367.229402 -273.27606)
			(xy 365.959644 -273.27606) (xy 365.95915 -273.300626) (xy 365.951269 -273.349122) (xy 365.93571 -273.395726)
			(xy 365.912877 -273.43923) (xy 365.883361 -273.478509) (xy 365.847927 -273.512544) (xy 365.807492 -273.540454)
			(xy 365.763103 -273.561517) (xy 365.715911 -273.575186) (xy 365.667137 -273.581108) (xy 365.618045 -273.57913)
			(xy 365.569905 -273.569302) (xy 365.523966 -273.55188) (xy 365.481416 -273.527314) (xy 365.443358 -273.49624)
			(xy 365.410777 -273.459464) (xy 365.384518 -273.417938) (xy 365.36526 -273.372737) (xy 365.353502 -273.325033)
			(xy 365.349548 -273.27606) (xy 365.01959 -273.27606) (xy 365.019096 -273.300626) (xy 365.011215 -273.349122)
			(xy 364.995656 -273.395726) (xy 364.972823 -273.43923) (xy 364.943307 -273.478509) (xy 364.907873 -273.512544)
			(xy 364.867438 -273.540454) (xy 364.823049 -273.561517) (xy 364.775857 -273.575186) (xy 364.727083 -273.581108)
			(xy 364.677991 -273.57913) (xy 364.629851 -273.569302) (xy 364.583912 -273.55188) (xy 364.541362 -273.527314)
			(xy 364.503304 -273.49624) (xy 364.470723 -273.459464) (xy 364.444464 -273.417938) (xy 364.425206 -273.372737)
			(xy 364.413448 -273.325033) (xy 364.409494 -273.27606) (xy 355.625908 -273.27606) (xy 355.625414 -273.300626)
			(xy 355.617533 -273.349122) (xy 355.601974 -273.395726) (xy 355.579141 -273.43923) (xy 355.549625 -273.478509)
			(xy 355.514191 -273.512544) (xy 355.473756 -273.540454) (xy 355.429367 -273.561517) (xy 355.382175 -273.575186)
			(xy 355.333401 -273.581108) (xy 355.284309 -273.57913) (xy 355.236169 -273.569302) (xy 355.19023 -273.55188)
			(xy 355.14768 -273.527314) (xy 355.109622 -273.49624) (xy 355.077041 -273.459464) (xy 355.050782 -273.417938)
			(xy 355.031524 -273.372737) (xy 355.019766 -273.325033) (xy 355.015812 -273.27606) (xy 354.685854 -273.27606)
			(xy 354.68536 -273.300626) (xy 354.677479 -273.349122) (xy 354.66192 -273.395726) (xy 354.639087 -273.43923)
			(xy 354.609571 -273.478509) (xy 354.574137 -273.512544) (xy 354.533702 -273.540454) (xy 354.489313 -273.561517)
			(xy 354.442121 -273.575186) (xy 354.393347 -273.581108) (xy 354.344255 -273.57913) (xy 354.296115 -273.569302)
			(xy 354.250176 -273.55188) (xy 354.207626 -273.527314) (xy 354.169568 -273.49624) (xy 354.136987 -273.459464)
			(xy 354.110728 -273.417938) (xy 354.09147 -273.372737) (xy 354.079712 -273.325033) (xy 354.075758 -273.27606)
			(xy 352.806 -273.27606) (xy 352.805506 -273.300626) (xy 352.797625 -273.349122) (xy 352.782066 -273.395726)
			(xy 352.759233 -273.43923) (xy 352.729717 -273.478509) (xy 352.694283 -273.512544) (xy 352.653848 -273.540454)
			(xy 352.609459 -273.561517) (xy 352.562267 -273.575186) (xy 352.513493 -273.581108) (xy 352.464401 -273.57913)
			(xy 352.416261 -273.569302) (xy 352.370322 -273.55188) (xy 352.327772 -273.527314) (xy 352.289714 -273.49624)
			(xy 352.257133 -273.459464) (xy 352.230874 -273.417938) (xy 352.211616 -273.372737) (xy 352.199858 -273.325033)
			(xy 352.195904 -273.27606) (xy 351.865946 -273.27606) (xy 351.865452 -273.300626) (xy 351.857571 -273.349122)
			(xy 351.842012 -273.395726) (xy 351.819179 -273.43923) (xy 351.789663 -273.478509) (xy 351.754229 -273.512544)
			(xy 351.713794 -273.540454) (xy 351.669405 -273.561517) (xy 351.622213 -273.575186) (xy 351.573439 -273.581108)
			(xy 351.524347 -273.57913) (xy 351.476207 -273.569302) (xy 351.430268 -273.55188) (xy 351.387718 -273.527314)
			(xy 351.34966 -273.49624) (xy 351.317079 -273.459464) (xy 351.29082 -273.417938) (xy 351.271562 -273.372737)
			(xy 351.259804 -273.325033) (xy 351.25585 -273.27606) (xy 349.985838 -273.27606) (xy 349.985344 -273.300626)
			(xy 349.977463 -273.349122) (xy 349.961904 -273.395726) (xy 349.939071 -273.43923) (xy 349.909555 -273.478509)
			(xy 349.874121 -273.512544) (xy 349.833686 -273.540454) (xy 349.789297 -273.561517) (xy 349.742105 -273.575186)
			(xy 349.693331 -273.581108) (xy 349.644239 -273.57913) (xy 349.596099 -273.569302) (xy 349.55016 -273.55188)
			(xy 349.50761 -273.527314) (xy 349.469552 -273.49624) (xy 349.436971 -273.459464) (xy 349.410712 -273.417938)
			(xy 349.391454 -273.372737) (xy 349.379696 -273.325033) (xy 349.375742 -273.27606) (xy 349.045784 -273.27606)
			(xy 349.04529 -273.300626) (xy 349.037409 -273.349122) (xy 349.02185 -273.395726) (xy 348.999017 -273.43923)
			(xy 348.969501 -273.478509) (xy 348.934067 -273.512544) (xy 348.893632 -273.540454) (xy 348.849243 -273.561517)
			(xy 348.802051 -273.575186) (xy 348.753277 -273.581108) (xy 348.704185 -273.57913) (xy 348.656045 -273.569302)
			(xy 348.610106 -273.55188) (xy 348.567556 -273.527314) (xy 348.529498 -273.49624) (xy 348.496917 -273.459464)
			(xy 348.470658 -273.417938) (xy 348.4514 -273.372737) (xy 348.439642 -273.325033) (xy 348.435688 -273.27606)
			(xy 347.16593 -273.27606) (xy 347.165436 -273.300626) (xy 347.157555 -273.349122) (xy 347.141996 -273.395726)
			(xy 347.119163 -273.43923) (xy 347.089647 -273.478509) (xy 347.054213 -273.512544) (xy 347.013778 -273.540454)
			(xy 346.969389 -273.561517) (xy 346.922197 -273.575186) (xy 346.873423 -273.581108) (xy 346.824331 -273.57913)
			(xy 346.776191 -273.569302) (xy 346.730252 -273.55188) (xy 346.687702 -273.527314) (xy 346.649644 -273.49624)
			(xy 346.617063 -273.459464) (xy 346.590804 -273.417938) (xy 346.571546 -273.372737) (xy 346.559788 -273.325033)
			(xy 346.555834 -273.27606) (xy 346.225876 -273.27606) (xy 346.225382 -273.300626) (xy 346.217501 -273.349122)
			(xy 346.201942 -273.395726) (xy 346.179109 -273.43923) (xy 346.149593 -273.478509) (xy 346.114159 -273.512544)
			(xy 346.073724 -273.540454) (xy 346.029335 -273.561517) (xy 345.982143 -273.575186) (xy 345.933369 -273.581108)
			(xy 345.884277 -273.57913) (xy 345.836137 -273.569302) (xy 345.790198 -273.55188) (xy 345.747648 -273.527314)
			(xy 345.70959 -273.49624) (xy 345.677009 -273.459464) (xy 345.65075 -273.417938) (xy 345.631492 -273.372737)
			(xy 345.619734 -273.325033) (xy 345.61578 -273.27606) (xy 126.479549 -273.27606) (xy 126.479554 -273.276314)
			(xy 126.47906 -273.30088) (xy 126.471179 -273.349376) (xy 126.45562 -273.39598) (xy 126.432787 -273.439484)
			(xy 126.403271 -273.478763) (xy 126.367837 -273.512798) (xy 126.327402 -273.540708) (xy 126.283013 -273.561771)
			(xy 126.235821 -273.57544) (xy 126.187047 -273.581362) (xy 126.137955 -273.579384) (xy 126.089815 -273.569556)
			(xy 126.043876 -273.552134) (xy 126.001326 -273.527568) (xy 125.963268 -273.496494) (xy 125.930687 -273.459718)
			(xy 125.904428 -273.418192) (xy 125.88517 -273.372991) (xy 125.873412 -273.325287) (xy 125.869458 -273.276314)
			(xy 125.5395 -273.276314) (xy 125.539006 -273.30088) (xy 125.531125 -273.349376) (xy 125.515566 -273.39598)
			(xy 125.492733 -273.439484) (xy 125.463217 -273.478763) (xy 125.427783 -273.512798) (xy 125.387348 -273.540708)
			(xy 125.342959 -273.561771) (xy 125.295767 -273.57544) (xy 125.246993 -273.581362) (xy 125.197901 -273.579384)
			(xy 125.149761 -273.569556) (xy 125.103822 -273.552134) (xy 125.061272 -273.527568) (xy 125.023214 -273.496494)
			(xy 124.990633 -273.459718) (xy 124.964374 -273.418192) (xy 124.945116 -273.372991) (xy 124.933358 -273.325287)
			(xy 124.929404 -273.276314) (xy 123.659392 -273.276314) (xy 123.658898 -273.30088) (xy 123.651017 -273.349376)
			(xy 123.635458 -273.39598) (xy 123.612625 -273.439484) (xy 123.583109 -273.478763) (xy 123.547675 -273.512798)
			(xy 123.50724 -273.540708) (xy 123.462851 -273.561771) (xy 123.415659 -273.57544) (xy 123.366885 -273.581362)
			(xy 123.317793 -273.579384) (xy 123.269653 -273.569556) (xy 123.223714 -273.552134) (xy 123.181164 -273.527568)
			(xy 123.143106 -273.496494) (xy 123.110525 -273.459718) (xy 123.084266 -273.418192) (xy 123.065008 -273.372991)
			(xy 123.05325 -273.325287) (xy 123.049296 -273.276314) (xy 122.719338 -273.276314) (xy 122.718844 -273.30088)
			(xy 122.710963 -273.349376) (xy 122.695404 -273.39598) (xy 122.672571 -273.439484) (xy 122.643055 -273.478763)
			(xy 122.607621 -273.512798) (xy 122.567186 -273.540708) (xy 122.522797 -273.561771) (xy 122.475605 -273.57544)
			(xy 122.426831 -273.581362) (xy 122.377739 -273.579384) (xy 122.329599 -273.569556) (xy 122.28366 -273.552134)
			(xy 122.24111 -273.527568) (xy 122.203052 -273.496494) (xy 122.170471 -273.459718) (xy 122.144212 -273.418192)
			(xy 122.124954 -273.372991) (xy 122.113196 -273.325287) (xy 122.109242 -273.276314) (xy 120.839484 -273.276314)
			(xy 120.83899 -273.30088) (xy 120.831109 -273.349376) (xy 120.81555 -273.39598) (xy 120.792717 -273.439484)
			(xy 120.763201 -273.478763) (xy 120.727767 -273.512798) (xy 120.687332 -273.540708) (xy 120.642943 -273.561771)
			(xy 120.595751 -273.57544) (xy 120.546977 -273.581362) (xy 120.497885 -273.579384) (xy 120.449745 -273.569556)
			(xy 120.403806 -273.552134) (xy 120.361256 -273.527568) (xy 120.323198 -273.496494) (xy 120.290617 -273.459718)
			(xy 120.264358 -273.418192) (xy 120.2451 -273.372991) (xy 120.233342 -273.325287) (xy 120.229388 -273.276314)
			(xy 119.89943 -273.276314) (xy 119.898936 -273.30088) (xy 119.891055 -273.349376) (xy 119.875496 -273.39598)
			(xy 119.852663 -273.439484) (xy 119.823147 -273.478763) (xy 119.787713 -273.512798) (xy 119.747278 -273.540708)
			(xy 119.702889 -273.561771) (xy 119.655697 -273.57544) (xy 119.606923 -273.581362) (xy 119.557831 -273.579384)
			(xy 119.509691 -273.569556) (xy 119.463752 -273.552134) (xy 119.421202 -273.527568) (xy 119.383144 -273.496494)
			(xy 119.350563 -273.459718) (xy 119.324304 -273.418192) (xy 119.305046 -273.372991) (xy 119.293288 -273.325287)
			(xy 119.289334 -273.276314) (xy 118.019576 -273.276314) (xy 118.019082 -273.30088) (xy 118.011201 -273.349376)
			(xy 117.995642 -273.39598) (xy 117.972809 -273.439484) (xy 117.943293 -273.478763) (xy 117.907859 -273.512798)
			(xy 117.867424 -273.540708) (xy 117.823035 -273.561771) (xy 117.775843 -273.57544) (xy 117.727069 -273.581362)
			(xy 117.677977 -273.579384) (xy 117.629837 -273.569556) (xy 117.583898 -273.552134) (xy 117.541348 -273.527568)
			(xy 117.50329 -273.496494) (xy 117.470709 -273.459718) (xy 117.44445 -273.418192) (xy 117.425192 -273.372991)
			(xy 117.413434 -273.325287) (xy 117.40948 -273.276314) (xy 117.079522 -273.276314) (xy 117.079028 -273.30088)
			(xy 117.071147 -273.349376) (xy 117.055588 -273.39598) (xy 117.032755 -273.439484) (xy 117.003239 -273.478763)
			(xy 116.967805 -273.512798) (xy 116.92737 -273.540708) (xy 116.882981 -273.561771) (xy 116.835789 -273.57544)
			(xy 116.787015 -273.581362) (xy 116.737923 -273.579384) (xy 116.689783 -273.569556) (xy 116.643844 -273.552134)
			(xy 116.601294 -273.527568) (xy 116.563236 -273.496494) (xy 116.530655 -273.459718) (xy 116.504396 -273.418192)
			(xy 116.485138 -273.372991) (xy 116.47338 -273.325287) (xy 116.469426 -273.276314) (xy 107.68584 -273.276314)
			(xy 107.685346 -273.30088) (xy 107.677465 -273.349376) (xy 107.661906 -273.39598) (xy 107.639073 -273.439484)
			(xy 107.609557 -273.478763) (xy 107.574123 -273.512798) (xy 107.533688 -273.540708) (xy 107.489299 -273.561771)
			(xy 107.442107 -273.57544) (xy 107.393333 -273.581362) (xy 107.344241 -273.579384) (xy 107.296101 -273.569556)
			(xy 107.250162 -273.552134) (xy 107.207612 -273.527568) (xy 107.169554 -273.496494) (xy 107.136973 -273.459718)
			(xy 107.110714 -273.418192) (xy 107.091456 -273.372991) (xy 107.079698 -273.325287) (xy 107.075744 -273.276314)
			(xy 106.745786 -273.276314) (xy 106.745292 -273.30088) (xy 106.737411 -273.349376) (xy 106.721852 -273.39598)
			(xy 106.699019 -273.439484) (xy 106.669503 -273.478763) (xy 106.634069 -273.512798) (xy 106.593634 -273.540708)
			(xy 106.549245 -273.561771) (xy 106.502053 -273.57544) (xy 106.453279 -273.581362) (xy 106.404187 -273.579384)
			(xy 106.356047 -273.569556) (xy 106.310108 -273.552134) (xy 106.267558 -273.527568) (xy 106.2295 -273.496494)
			(xy 106.196919 -273.459718) (xy 106.17066 -273.418192) (xy 106.151402 -273.372991) (xy 106.139644 -273.325287)
			(xy 106.13569 -273.276314) (xy 104.865932 -273.276314) (xy 104.865438 -273.30088) (xy 104.857557 -273.349376)
			(xy 104.841998 -273.39598) (xy 104.819165 -273.439484) (xy 104.789649 -273.478763) (xy 104.754215 -273.512798)
			(xy 104.71378 -273.540708) (xy 104.669391 -273.561771) (xy 104.622199 -273.57544) (xy 104.573425 -273.581362)
			(xy 104.524333 -273.579384) (xy 104.476193 -273.569556) (xy 104.430254 -273.552134) (xy 104.387704 -273.527568)
			(xy 104.349646 -273.496494) (xy 104.317065 -273.459718) (xy 104.290806 -273.418192) (xy 104.271548 -273.372991)
			(xy 104.25979 -273.325287) (xy 104.255836 -273.276314) (xy 103.925878 -273.276314) (xy 103.925384 -273.30088)
			(xy 103.917503 -273.349376) (xy 103.901944 -273.39598) (xy 103.879111 -273.439484) (xy 103.849595 -273.478763)
			(xy 103.814161 -273.512798) (xy 103.773726 -273.540708) (xy 103.729337 -273.561771) (xy 103.682145 -273.57544)
			(xy 103.633371 -273.581362) (xy 103.584279 -273.579384) (xy 103.536139 -273.569556) (xy 103.4902 -273.552134)
			(xy 103.44765 -273.527568) (xy 103.409592 -273.496494) (xy 103.377011 -273.459718) (xy 103.350752 -273.418192)
			(xy 103.331494 -273.372991) (xy 103.319736 -273.325287) (xy 103.315782 -273.276314) (xy 102.04577 -273.276314)
			(xy 102.045276 -273.30088) (xy 102.037395 -273.349376) (xy 102.021836 -273.39598) (xy 101.999003 -273.439484)
			(xy 101.969487 -273.478763) (xy 101.934053 -273.512798) (xy 101.893618 -273.540708) (xy 101.849229 -273.561771)
			(xy 101.802037 -273.57544) (xy 101.753263 -273.581362) (xy 101.704171 -273.579384) (xy 101.656031 -273.569556)
			(xy 101.610092 -273.552134) (xy 101.567542 -273.527568) (xy 101.529484 -273.496494) (xy 101.496903 -273.459718)
			(xy 101.470644 -273.418192) (xy 101.451386 -273.372991) (xy 101.439628 -273.325287) (xy 101.435674 -273.276314)
			(xy 101.105716 -273.276314) (xy 101.105222 -273.30088) (xy 101.097341 -273.349376) (xy 101.081782 -273.39598)
			(xy 101.058949 -273.439484) (xy 101.029433 -273.478763) (xy 100.993999 -273.512798) (xy 100.953564 -273.540708)
			(xy 100.909175 -273.561771) (xy 100.861983 -273.57544) (xy 100.813209 -273.581362) (xy 100.764117 -273.579384)
			(xy 100.715977 -273.569556) (xy 100.670038 -273.552134) (xy 100.627488 -273.527568) (xy 100.58943 -273.496494)
			(xy 100.556849 -273.459718) (xy 100.53059 -273.418192) (xy 100.511332 -273.372991) (xy 100.499574 -273.325287)
			(xy 100.49562 -273.276314) (xy 99.225862 -273.276314) (xy 99.225368 -273.30088) (xy 99.217487 -273.349376)
			(xy 99.201928 -273.39598) (xy 99.179095 -273.439484) (xy 99.149579 -273.478763) (xy 99.114145 -273.512798)
			(xy 99.07371 -273.540708) (xy 99.029321 -273.561771) (xy 98.982129 -273.57544) (xy 98.933355 -273.581362)
			(xy 98.884263 -273.579384) (xy 98.836123 -273.569556) (xy 98.790184 -273.552134) (xy 98.747634 -273.527568)
			(xy 98.709576 -273.496494) (xy 98.676995 -273.459718) (xy 98.650736 -273.418192) (xy 98.631478 -273.372991)
			(xy 98.61972 -273.325287) (xy 98.615766 -273.276314) (xy 98.285808 -273.276314) (xy 98.285314 -273.30088)
			(xy 98.277433 -273.349376) (xy 98.261874 -273.39598) (xy 98.239041 -273.439484) (xy 98.209525 -273.478763)
			(xy 98.174091 -273.512798) (xy 98.133656 -273.540708) (xy 98.089267 -273.561771) (xy 98.042075 -273.57544)
			(xy 97.993301 -273.581362) (xy 97.944209 -273.579384) (xy 97.896069 -273.569556) (xy 97.85013 -273.552134)
			(xy 97.80758 -273.527568) (xy 97.769522 -273.496494) (xy 97.736941 -273.459718) (xy 97.710682 -273.418192)
			(xy 97.691424 -273.372991) (xy 97.679666 -273.325287) (xy 97.675712 -273.276314) (xy 2.509012 -273.276314)
			(xy 2.509012 -274.08632) (xy 108.485698 -274.08632) (xy 108.489652 -274.037347) (xy 108.50141 -273.989643)
			(xy 108.520668 -273.944442) (xy 108.546927 -273.902916) (xy 108.579508 -273.86614) (xy 108.617566 -273.835066)
			(xy 108.660116 -273.8105) (xy 108.706055 -273.793078) (xy 108.754195 -273.78325) (xy 108.803287 -273.781272)
			(xy 108.852061 -273.787194) (xy 108.899253 -273.800863) (xy 108.943642 -273.821926) (xy 108.984077 -273.849836)
			(xy 109.019511 -273.883871) (xy 109.049027 -273.92315) (xy 109.07186 -273.966654) (xy 109.087419 -274.013258)
			(xy 109.0953 -274.061754) (xy 109.095794 -274.08632) (xy 109.425752 -274.08632) (xy 109.429706 -274.037347)
			(xy 109.441464 -273.989643) (xy 109.460722 -273.944442) (xy 109.486981 -273.902916) (xy 109.519562 -273.86614)
			(xy 109.55762 -273.835066) (xy 109.60017 -273.8105) (xy 109.646109 -273.793078) (xy 109.694249 -273.78325)
			(xy 109.743341 -273.781272) (xy 109.792115 -273.787194) (xy 109.839307 -273.800863) (xy 109.883696 -273.821926)
			(xy 109.924131 -273.849836) (xy 109.959565 -273.883871) (xy 109.989081 -273.92315) (xy 110.011914 -273.966654)
			(xy 110.027473 -274.013258) (xy 110.035354 -274.061754) (xy 110.035848 -274.08632) (xy 114.119418 -274.08632)
			(xy 114.123372 -274.037347) (xy 114.13513 -273.989643) (xy 114.154388 -273.944442) (xy 114.180647 -273.902916)
			(xy 114.213228 -273.86614) (xy 114.251286 -273.835066) (xy 114.293836 -273.8105) (xy 114.339775 -273.793078)
			(xy 114.387915 -273.78325) (xy 114.437007 -273.781272) (xy 114.485781 -273.787194) (xy 114.532973 -273.800863)
			(xy 114.577362 -273.821926) (xy 114.617797 -273.849836) (xy 114.653231 -273.883871) (xy 114.682747 -273.92315)
			(xy 114.70558 -273.966654) (xy 114.721139 -274.013258) (xy 114.72902 -274.061754) (xy 114.729514 -274.08632)
			(xy 115.059472 -274.08632) (xy 115.063426 -274.037347) (xy 115.075184 -273.989643) (xy 115.094442 -273.944442)
			(xy 115.120701 -273.902916) (xy 115.153282 -273.86614) (xy 115.19134 -273.835066) (xy 115.23389 -273.8105)
			(xy 115.279829 -273.793078) (xy 115.327969 -273.78325) (xy 115.377061 -273.781272) (xy 115.425835 -273.787194)
			(xy 115.473027 -273.800863) (xy 115.517416 -273.821926) (xy 115.557851 -273.849836) (xy 115.593285 -273.883871)
			(xy 115.622801 -273.92315) (xy 115.645634 -273.966654) (xy 115.661193 -274.013258) (xy 115.669074 -274.061754)
			(xy 115.669563 -274.086066) (xy 356.425766 -274.086066) (xy 356.42972 -274.037093) (xy 356.441478 -273.989389)
			(xy 356.460736 -273.944188) (xy 356.486995 -273.902662) (xy 356.519576 -273.865886) (xy 356.557634 -273.834812)
			(xy 356.600184 -273.810246) (xy 356.646123 -273.792824) (xy 356.694263 -273.782996) (xy 356.743355 -273.781018)
			(xy 356.792129 -273.78694) (xy 356.839321 -273.800609) (xy 356.88371 -273.821672) (xy 356.924145 -273.849582)
			(xy 356.959579 -273.883617) (xy 356.989095 -273.922896) (xy 357.011928 -273.9664) (xy 357.027487 -274.013004)
			(xy 357.035368 -274.0615) (xy 357.035862 -274.086066) (xy 357.36582 -274.086066) (xy 357.369774 -274.037093)
			(xy 357.381532 -273.989389) (xy 357.40079 -273.944188) (xy 357.427049 -273.902662) (xy 357.45963 -273.865886)
			(xy 357.497688 -273.834812) (xy 357.540238 -273.810246) (xy 357.586177 -273.792824) (xy 357.634317 -273.782996)
			(xy 357.683409 -273.781018) (xy 357.732183 -273.78694) (xy 357.779375 -273.800609) (xy 357.823764 -273.821672)
			(xy 357.864199 -273.849582) (xy 357.899633 -273.883617) (xy 357.929149 -273.922896) (xy 357.951982 -273.9664)
			(xy 357.967541 -274.013004) (xy 357.975422 -274.0615) (xy 357.975916 -274.086066) (xy 362.059486 -274.086066)
			(xy 362.06344 -274.037093) (xy 362.075198 -273.989389) (xy 362.094456 -273.944188) (xy 362.120715 -273.902662)
			(xy 362.153296 -273.865886) (xy 362.191354 -273.834812) (xy 362.233904 -273.810246) (xy 362.279843 -273.792824)
			(xy 362.327983 -273.782996) (xy 362.377075 -273.781018) (xy 362.425849 -273.78694) (xy 362.473041 -273.800609)
			(xy 362.51743 -273.821672) (xy 362.557865 -273.849582) (xy 362.593299 -273.883617) (xy 362.622815 -273.922896)
			(xy 362.645648 -273.9664) (xy 362.661207 -274.013004) (xy 362.669088 -274.0615) (xy 362.669582 -274.086066)
			(xy 362.99954 -274.086066) (xy 363.003494 -274.037093) (xy 363.015252 -273.989389) (xy 363.03451 -273.944188)
			(xy 363.060769 -273.902662) (xy 363.09335 -273.865886) (xy 363.131408 -273.834812) (xy 363.173958 -273.810246)
			(xy 363.219897 -273.792824) (xy 363.268037 -273.782996) (xy 363.317129 -273.781018) (xy 363.365903 -273.78694)
			(xy 363.413095 -273.800609) (xy 363.457484 -273.821672) (xy 363.497919 -273.849582) (xy 363.533353 -273.883617)
			(xy 363.562869 -273.922896) (xy 363.585702 -273.9664) (xy 363.601261 -274.013004) (xy 363.609142 -274.0615)
			(xy 363.609636 -274.086066) (xy 363.609142 -274.110632) (xy 363.601261 -274.159128) (xy 363.585702 -274.205732)
			(xy 363.562869 -274.249236) (xy 363.533353 -274.288515) (xy 363.497919 -274.32255) (xy 363.457484 -274.35046)
			(xy 363.413095 -274.371523) (xy 363.365903 -274.385192) (xy 363.317129 -274.391114) (xy 363.268037 -274.389136)
			(xy 363.219897 -274.379308) (xy 363.173958 -274.361886) (xy 363.131408 -274.33732) (xy 363.09335 -274.306246)
			(xy 363.060769 -274.26947) (xy 363.03451 -274.227944) (xy 363.015252 -274.182743) (xy 363.003494 -274.135039)
			(xy 362.99954 -274.086066) (xy 362.669582 -274.086066) (xy 362.669088 -274.110632) (xy 362.661207 -274.159128)
			(xy 362.645648 -274.205732) (xy 362.622815 -274.249236) (xy 362.593299 -274.288515) (xy 362.557865 -274.32255)
			(xy 362.51743 -274.35046) (xy 362.473041 -274.371523) (xy 362.425849 -274.385192) (xy 362.377075 -274.391114)
			(xy 362.327983 -274.389136) (xy 362.279843 -274.379308) (xy 362.233904 -274.361886) (xy 362.191354 -274.33732)
			(xy 362.153296 -274.306246) (xy 362.120715 -274.26947) (xy 362.094456 -274.227944) (xy 362.075198 -274.182743)
			(xy 362.06344 -274.135039) (xy 362.059486 -274.086066) (xy 357.975916 -274.086066) (xy 357.975422 -274.110632)
			(xy 357.967541 -274.159128) (xy 357.951982 -274.205732) (xy 357.929149 -274.249236) (xy 357.899633 -274.288515)
			(xy 357.864199 -274.32255) (xy 357.823764 -274.35046) (xy 357.779375 -274.371523) (xy 357.732183 -274.385192)
			(xy 357.683409 -274.391114) (xy 357.634317 -274.389136) (xy 357.586177 -274.379308) (xy 357.540238 -274.361886)
			(xy 357.497688 -274.33732) (xy 357.45963 -274.306246) (xy 357.427049 -274.26947) (xy 357.40079 -274.227944)
			(xy 357.381532 -274.182743) (xy 357.369774 -274.135039) (xy 357.36582 -274.086066) (xy 357.035862 -274.086066)
			(xy 357.035368 -274.110632) (xy 357.027487 -274.159128) (xy 357.011928 -274.205732) (xy 356.989095 -274.249236)
			(xy 356.959579 -274.288515) (xy 356.924145 -274.32255) (xy 356.88371 -274.35046) (xy 356.839321 -274.371523)
			(xy 356.792129 -274.385192) (xy 356.743355 -274.391114) (xy 356.694263 -274.389136) (xy 356.646123 -274.379308)
			(xy 356.600184 -274.361886) (xy 356.557634 -274.33732) (xy 356.519576 -274.306246) (xy 356.486995 -274.26947)
			(xy 356.460736 -274.227944) (xy 356.441478 -274.182743) (xy 356.42972 -274.135039) (xy 356.425766 -274.086066)
			(xy 115.669563 -274.086066) (xy 115.669568 -274.08632) (xy 115.669074 -274.110886) (xy 115.661193 -274.159382)
			(xy 115.645634 -274.205986) (xy 115.622801 -274.24949) (xy 115.593285 -274.288769) (xy 115.557851 -274.322804)
			(xy 115.517416 -274.350714) (xy 115.473027 -274.371777) (xy 115.425835 -274.385446) (xy 115.377061 -274.391368)
			(xy 115.327969 -274.38939) (xy 115.279829 -274.379562) (xy 115.23389 -274.36214) (xy 115.19134 -274.337574)
			(xy 115.153282 -274.3065) (xy 115.120701 -274.269724) (xy 115.094442 -274.228198) (xy 115.075184 -274.182997)
			(xy 115.063426 -274.135293) (xy 115.059472 -274.08632) (xy 114.729514 -274.08632) (xy 114.72902 -274.110886)
			(xy 114.721139 -274.159382) (xy 114.70558 -274.205986) (xy 114.682747 -274.24949) (xy 114.653231 -274.288769)
			(xy 114.617797 -274.322804) (xy 114.577362 -274.350714) (xy 114.532973 -274.371777) (xy 114.485781 -274.385446)
			(xy 114.437007 -274.391368) (xy 114.387915 -274.38939) (xy 114.339775 -274.379562) (xy 114.293836 -274.36214)
			(xy 114.251286 -274.337574) (xy 114.213228 -274.3065) (xy 114.180647 -274.269724) (xy 114.154388 -274.228198)
			(xy 114.13513 -274.182997) (xy 114.123372 -274.135293) (xy 114.119418 -274.08632) (xy 110.035848 -274.08632)
			(xy 110.035354 -274.110886) (xy 110.027473 -274.159382) (xy 110.011914 -274.205986) (xy 109.989081 -274.24949)
			(xy 109.959565 -274.288769) (xy 109.924131 -274.322804) (xy 109.883696 -274.350714) (xy 109.839307 -274.371777)
			(xy 109.792115 -274.385446) (xy 109.743341 -274.391368) (xy 109.694249 -274.38939) (xy 109.646109 -274.379562)
			(xy 109.60017 -274.36214) (xy 109.55762 -274.337574) (xy 109.519562 -274.3065) (xy 109.486981 -274.269724)
			(xy 109.460722 -274.228198) (xy 109.441464 -274.182997) (xy 109.429706 -274.135293) (xy 109.425752 -274.08632)
			(xy 109.095794 -274.08632) (xy 109.0953 -274.110886) (xy 109.087419 -274.159382) (xy 109.07186 -274.205986)
			(xy 109.049027 -274.24949) (xy 109.019511 -274.288769) (xy 108.984077 -274.322804) (xy 108.943642 -274.350714)
			(xy 108.899253 -274.371777) (xy 108.852061 -274.385446) (xy 108.803287 -274.391368) (xy 108.754195 -274.38939)
			(xy 108.706055 -274.379562) (xy 108.660116 -274.36214) (xy 108.617566 -274.337574) (xy 108.579508 -274.3065)
			(xy 108.546927 -274.269724) (xy 108.520668 -274.228198) (xy 108.50141 -274.182997) (xy 108.489652 -274.135293)
			(xy 108.485698 -274.08632) (xy 2.509012 -274.08632) (xy 2.509012 -274.896326) (xy 97.675712 -274.896326)
			(xy 97.679666 -274.847353) (xy 97.691424 -274.799649) (xy 97.710682 -274.754448) (xy 97.736941 -274.712922)
			(xy 97.769522 -274.676146) (xy 97.80758 -274.645072) (xy 97.85013 -274.620506) (xy 97.896069 -274.603084)
			(xy 97.944209 -274.593256) (xy 97.993301 -274.591278) (xy 98.042075 -274.5972) (xy 98.089267 -274.610869)
			(xy 98.133656 -274.631932) (xy 98.174091 -274.659842) (xy 98.209525 -274.693877) (xy 98.239041 -274.733156)
			(xy 98.261874 -274.77666) (xy 98.277433 -274.823264) (xy 98.285314 -274.87176) (xy 98.285808 -274.896326)
			(xy 98.615766 -274.896326) (xy 98.61972 -274.847353) (xy 98.631478 -274.799649) (xy 98.650736 -274.754448)
			(xy 98.676995 -274.712922) (xy 98.709576 -274.676146) (xy 98.747634 -274.645072) (xy 98.790184 -274.620506)
			(xy 98.836123 -274.603084) (xy 98.884263 -274.593256) (xy 98.933355 -274.591278) (xy 98.982129 -274.5972)
			(xy 99.029321 -274.610869) (xy 99.07371 -274.631932) (xy 99.114145 -274.659842) (xy 99.149579 -274.693877)
			(xy 99.179095 -274.733156) (xy 99.201928 -274.77666) (xy 99.217487 -274.823264) (xy 99.225368 -274.87176)
			(xy 99.225862 -274.896326) (xy 100.49562 -274.896326) (xy 100.499574 -274.847353) (xy 100.511332 -274.799649)
			(xy 100.53059 -274.754448) (xy 100.556849 -274.712922) (xy 100.58943 -274.676146) (xy 100.627488 -274.645072)
			(xy 100.670038 -274.620506) (xy 100.715977 -274.603084) (xy 100.764117 -274.593256) (xy 100.813209 -274.591278)
			(xy 100.861983 -274.5972) (xy 100.909175 -274.610869) (xy 100.953564 -274.631932) (xy 100.993999 -274.659842)
			(xy 101.029433 -274.693877) (xy 101.058949 -274.733156) (xy 101.081782 -274.77666) (xy 101.097341 -274.823264)
			(xy 101.105222 -274.87176) (xy 101.105716 -274.896326) (xy 101.435674 -274.896326) (xy 101.439628 -274.847353)
			(xy 101.451386 -274.799649) (xy 101.470644 -274.754448) (xy 101.496903 -274.712922) (xy 101.529484 -274.676146)
			(xy 101.567542 -274.645072) (xy 101.610092 -274.620506) (xy 101.656031 -274.603084) (xy 101.704171 -274.593256)
			(xy 101.753263 -274.591278) (xy 101.802037 -274.5972) (xy 101.849229 -274.610869) (xy 101.893618 -274.631932)
			(xy 101.934053 -274.659842) (xy 101.969487 -274.693877) (xy 101.999003 -274.733156) (xy 102.021836 -274.77666)
			(xy 102.037395 -274.823264) (xy 102.045276 -274.87176) (xy 102.04577 -274.896326) (xy 103.315782 -274.896326)
			(xy 103.319736 -274.847353) (xy 103.331494 -274.799649) (xy 103.350752 -274.754448) (xy 103.377011 -274.712922)
			(xy 103.409592 -274.676146) (xy 103.44765 -274.645072) (xy 103.4902 -274.620506) (xy 103.536139 -274.603084)
			(xy 103.584279 -274.593256) (xy 103.633371 -274.591278) (xy 103.682145 -274.5972) (xy 103.729337 -274.610869)
			(xy 103.773726 -274.631932) (xy 103.814161 -274.659842) (xy 103.849595 -274.693877) (xy 103.879111 -274.733156)
			(xy 103.901944 -274.77666) (xy 103.917503 -274.823264) (xy 103.925384 -274.87176) (xy 103.925878 -274.896326)
			(xy 104.255836 -274.896326) (xy 104.25979 -274.847353) (xy 104.271548 -274.799649) (xy 104.290806 -274.754448)
			(xy 104.317065 -274.712922) (xy 104.349646 -274.676146) (xy 104.387704 -274.645072) (xy 104.430254 -274.620506)
			(xy 104.476193 -274.603084) (xy 104.524333 -274.593256) (xy 104.573425 -274.591278) (xy 104.622199 -274.5972)
			(xy 104.669391 -274.610869) (xy 104.71378 -274.631932) (xy 104.754215 -274.659842) (xy 104.789649 -274.693877)
			(xy 104.819165 -274.733156) (xy 104.841998 -274.77666) (xy 104.857557 -274.823264) (xy 104.865438 -274.87176)
			(xy 104.865932 -274.896326) (xy 106.13569 -274.896326) (xy 106.139644 -274.847353) (xy 106.151402 -274.799649)
			(xy 106.17066 -274.754448) (xy 106.196919 -274.712922) (xy 106.2295 -274.676146) (xy 106.267558 -274.645072)
			(xy 106.310108 -274.620506) (xy 106.356047 -274.603084) (xy 106.404187 -274.593256) (xy 106.453279 -274.591278)
			(xy 106.502053 -274.5972) (xy 106.549245 -274.610869) (xy 106.593634 -274.631932) (xy 106.634069 -274.659842)
			(xy 106.669503 -274.693877) (xy 106.699019 -274.733156) (xy 106.721852 -274.77666) (xy 106.737411 -274.823264)
			(xy 106.745292 -274.87176) (xy 106.745786 -274.896326) (xy 107.075744 -274.896326) (xy 107.079698 -274.847353)
			(xy 107.091456 -274.799649) (xy 107.110714 -274.754448) (xy 107.136973 -274.712922) (xy 107.169554 -274.676146)
			(xy 107.207612 -274.645072) (xy 107.250162 -274.620506) (xy 107.296101 -274.603084) (xy 107.344241 -274.593256)
			(xy 107.393333 -274.591278) (xy 107.442107 -274.5972) (xy 107.489299 -274.610869) (xy 107.533688 -274.631932)
			(xy 107.574123 -274.659842) (xy 107.609557 -274.693877) (xy 107.639073 -274.733156) (xy 107.661906 -274.77666)
			(xy 107.677465 -274.823264) (xy 107.685346 -274.87176) (xy 107.68584 -274.896326) (xy 116.469426 -274.896326)
			(xy 116.47338 -274.847353) (xy 116.485138 -274.799649) (xy 116.504396 -274.754448) (xy 116.530655 -274.712922)
			(xy 116.563236 -274.676146) (xy 116.601294 -274.645072) (xy 116.643844 -274.620506) (xy 116.689783 -274.603084)
			(xy 116.737923 -274.593256) (xy 116.787015 -274.591278) (xy 116.835789 -274.5972) (xy 116.882981 -274.610869)
			(xy 116.92737 -274.631932) (xy 116.967805 -274.659842) (xy 117.003239 -274.693877) (xy 117.032755 -274.733156)
			(xy 117.055588 -274.77666) (xy 117.071147 -274.823264) (xy 117.079028 -274.87176) (xy 117.079522 -274.896326)
			(xy 117.40948 -274.896326) (xy 117.413434 -274.847353) (xy 117.425192 -274.799649) (xy 117.44445 -274.754448)
			(xy 117.470709 -274.712922) (xy 117.50329 -274.676146) (xy 117.541348 -274.645072) (xy 117.583898 -274.620506)
			(xy 117.629837 -274.603084) (xy 117.677977 -274.593256) (xy 117.727069 -274.591278) (xy 117.775843 -274.5972)
			(xy 117.823035 -274.610869) (xy 117.867424 -274.631932) (xy 117.907859 -274.659842) (xy 117.943293 -274.693877)
			(xy 117.972809 -274.733156) (xy 117.995642 -274.77666) (xy 118.011201 -274.823264) (xy 118.019082 -274.87176)
			(xy 118.019576 -274.896326) (xy 119.289334 -274.896326) (xy 119.293288 -274.847353) (xy 119.305046 -274.799649)
			(xy 119.324304 -274.754448) (xy 119.350563 -274.712922) (xy 119.383144 -274.676146) (xy 119.421202 -274.645072)
			(xy 119.463752 -274.620506) (xy 119.509691 -274.603084) (xy 119.557831 -274.593256) (xy 119.606923 -274.591278)
			(xy 119.655697 -274.5972) (xy 119.702889 -274.610869) (xy 119.747278 -274.631932) (xy 119.787713 -274.659842)
			(xy 119.823147 -274.693877) (xy 119.852663 -274.733156) (xy 119.875496 -274.77666) (xy 119.891055 -274.823264)
			(xy 119.898936 -274.87176) (xy 119.89943 -274.896326) (xy 120.229388 -274.896326) (xy 120.233342 -274.847353)
			(xy 120.2451 -274.799649) (xy 120.264358 -274.754448) (xy 120.290617 -274.712922) (xy 120.323198 -274.676146)
			(xy 120.361256 -274.645072) (xy 120.403806 -274.620506) (xy 120.449745 -274.603084) (xy 120.497885 -274.593256)
			(xy 120.546977 -274.591278) (xy 120.595751 -274.5972) (xy 120.642943 -274.610869) (xy 120.687332 -274.631932)
			(xy 120.727767 -274.659842) (xy 120.763201 -274.693877) (xy 120.792717 -274.733156) (xy 120.81555 -274.77666)
			(xy 120.831109 -274.823264) (xy 120.83899 -274.87176) (xy 120.839484 -274.896326) (xy 122.109242 -274.896326)
			(xy 122.113196 -274.847353) (xy 122.124954 -274.799649) (xy 122.144212 -274.754448) (xy 122.170471 -274.712922)
			(xy 122.203052 -274.676146) (xy 122.24111 -274.645072) (xy 122.28366 -274.620506) (xy 122.329599 -274.603084)
			(xy 122.377739 -274.593256) (xy 122.426831 -274.591278) (xy 122.475605 -274.5972) (xy 122.522797 -274.610869)
			(xy 122.567186 -274.631932) (xy 122.607621 -274.659842) (xy 122.643055 -274.693877) (xy 122.672571 -274.733156)
			(xy 122.695404 -274.77666) (xy 122.710963 -274.823264) (xy 122.718844 -274.87176) (xy 122.719338 -274.896326)
			(xy 123.049296 -274.896326) (xy 123.05325 -274.847353) (xy 123.065008 -274.799649) (xy 123.084266 -274.754448)
			(xy 123.110525 -274.712922) (xy 123.143106 -274.676146) (xy 123.181164 -274.645072) (xy 123.223714 -274.620506)
			(xy 123.269653 -274.603084) (xy 123.317793 -274.593256) (xy 123.366885 -274.591278) (xy 123.415659 -274.5972)
			(xy 123.462851 -274.610869) (xy 123.50724 -274.631932) (xy 123.547675 -274.659842) (xy 123.583109 -274.693877)
			(xy 123.612625 -274.733156) (xy 123.635458 -274.77666) (xy 123.651017 -274.823264) (xy 123.658898 -274.87176)
			(xy 123.659392 -274.896326) (xy 124.929404 -274.896326) (xy 124.933358 -274.847353) (xy 124.945116 -274.799649)
			(xy 124.964374 -274.754448) (xy 124.990633 -274.712922) (xy 125.023214 -274.676146) (xy 125.061272 -274.645072)
			(xy 125.103822 -274.620506) (xy 125.149761 -274.603084) (xy 125.197901 -274.593256) (xy 125.246993 -274.591278)
			(xy 125.295767 -274.5972) (xy 125.342959 -274.610869) (xy 125.387348 -274.631932) (xy 125.427783 -274.659842)
			(xy 125.463217 -274.693877) (xy 125.492733 -274.733156) (xy 125.515566 -274.77666) (xy 125.531125 -274.823264)
			(xy 125.539006 -274.87176) (xy 125.5395 -274.896326) (xy 125.869458 -274.896326) (xy 125.873412 -274.847353)
			(xy 125.88517 -274.799649) (xy 125.904428 -274.754448) (xy 125.930687 -274.712922) (xy 125.963268 -274.676146)
			(xy 126.001326 -274.645072) (xy 126.043876 -274.620506) (xy 126.089815 -274.603084) (xy 126.137955 -274.593256)
			(xy 126.187047 -274.591278) (xy 126.235821 -274.5972) (xy 126.283013 -274.610869) (xy 126.327402 -274.631932)
			(xy 126.367837 -274.659842) (xy 126.403271 -274.693877) (xy 126.432787 -274.733156) (xy 126.45562 -274.77666)
			(xy 126.471179 -274.823264) (xy 126.47906 -274.87176) (xy 126.479549 -274.896072) (xy 345.61578 -274.896072)
			(xy 345.619734 -274.847099) (xy 345.631492 -274.799395) (xy 345.65075 -274.754194) (xy 345.677009 -274.712668)
			(xy 345.70959 -274.675892) (xy 345.747648 -274.644818) (xy 345.790198 -274.620252) (xy 345.836137 -274.60283)
			(xy 345.884277 -274.593002) (xy 345.933369 -274.591024) (xy 345.982143 -274.596946) (xy 346.029335 -274.610615)
			(xy 346.073724 -274.631678) (xy 346.114159 -274.659588) (xy 346.149593 -274.693623) (xy 346.179109 -274.732902)
			(xy 346.201942 -274.776406) (xy 346.217501 -274.82301) (xy 346.225382 -274.871506) (xy 346.225876 -274.896072)
			(xy 346.555834 -274.896072) (xy 346.559788 -274.847099) (xy 346.571546 -274.799395) (xy 346.590804 -274.754194)
			(xy 346.617063 -274.712668) (xy 346.649644 -274.675892) (xy 346.687702 -274.644818) (xy 346.730252 -274.620252)
			(xy 346.776191 -274.60283) (xy 346.824331 -274.593002) (xy 346.873423 -274.591024) (xy 346.922197 -274.596946)
			(xy 346.969389 -274.610615) (xy 347.013778 -274.631678) (xy 347.054213 -274.659588) (xy 347.089647 -274.693623)
			(xy 347.119163 -274.732902) (xy 347.141996 -274.776406) (xy 347.157555 -274.82301) (xy 347.165436 -274.871506)
			(xy 347.16593 -274.896072) (xy 348.435688 -274.896072) (xy 348.439642 -274.847099) (xy 348.4514 -274.799395)
			(xy 348.470658 -274.754194) (xy 348.496917 -274.712668) (xy 348.529498 -274.675892) (xy 348.567556 -274.644818)
			(xy 348.610106 -274.620252) (xy 348.656045 -274.60283) (xy 348.704185 -274.593002) (xy 348.753277 -274.591024)
			(xy 348.802051 -274.596946) (xy 348.849243 -274.610615) (xy 348.893632 -274.631678) (xy 348.934067 -274.659588)
			(xy 348.969501 -274.693623) (xy 348.999017 -274.732902) (xy 349.02185 -274.776406) (xy 349.037409 -274.82301)
			(xy 349.04529 -274.871506) (xy 349.045784 -274.896072) (xy 349.375742 -274.896072) (xy 349.379696 -274.847099)
			(xy 349.391454 -274.799395) (xy 349.410712 -274.754194) (xy 349.436971 -274.712668) (xy 349.469552 -274.675892)
			(xy 349.50761 -274.644818) (xy 349.55016 -274.620252) (xy 349.596099 -274.60283) (xy 349.644239 -274.593002)
			(xy 349.693331 -274.591024) (xy 349.742105 -274.596946) (xy 349.789297 -274.610615) (xy 349.833686 -274.631678)
			(xy 349.874121 -274.659588) (xy 349.909555 -274.693623) (xy 349.939071 -274.732902) (xy 349.961904 -274.776406)
			(xy 349.977463 -274.82301) (xy 349.985344 -274.871506) (xy 349.985838 -274.896072) (xy 351.25585 -274.896072)
			(xy 351.259804 -274.847099) (xy 351.271562 -274.799395) (xy 351.29082 -274.754194) (xy 351.317079 -274.712668)
			(xy 351.34966 -274.675892) (xy 351.387718 -274.644818) (xy 351.430268 -274.620252) (xy 351.476207 -274.60283)
			(xy 351.524347 -274.593002) (xy 351.573439 -274.591024) (xy 351.622213 -274.596946) (xy 351.669405 -274.610615)
			(xy 351.713794 -274.631678) (xy 351.754229 -274.659588) (xy 351.789663 -274.693623) (xy 351.819179 -274.732902)
			(xy 351.842012 -274.776406) (xy 351.857571 -274.82301) (xy 351.865452 -274.871506) (xy 351.865946 -274.896072)
			(xy 352.195904 -274.896072) (xy 352.199858 -274.847099) (xy 352.211616 -274.799395) (xy 352.230874 -274.754194)
			(xy 352.257133 -274.712668) (xy 352.289714 -274.675892) (xy 352.327772 -274.644818) (xy 352.370322 -274.620252)
			(xy 352.416261 -274.60283) (xy 352.464401 -274.593002) (xy 352.513493 -274.591024) (xy 352.562267 -274.596946)
			(xy 352.609459 -274.610615) (xy 352.653848 -274.631678) (xy 352.694283 -274.659588) (xy 352.729717 -274.693623)
			(xy 352.759233 -274.732902) (xy 352.782066 -274.776406) (xy 352.797625 -274.82301) (xy 352.805506 -274.871506)
			(xy 352.806 -274.896072) (xy 354.075758 -274.896072) (xy 354.079712 -274.847099) (xy 354.09147 -274.799395)
			(xy 354.110728 -274.754194) (xy 354.136987 -274.712668) (xy 354.169568 -274.675892) (xy 354.207626 -274.644818)
			(xy 354.250176 -274.620252) (xy 354.296115 -274.60283) (xy 354.344255 -274.593002) (xy 354.393347 -274.591024)
			(xy 354.442121 -274.596946) (xy 354.489313 -274.610615) (xy 354.533702 -274.631678) (xy 354.574137 -274.659588)
			(xy 354.609571 -274.693623) (xy 354.639087 -274.732902) (xy 354.66192 -274.776406) (xy 354.677479 -274.82301)
			(xy 354.68536 -274.871506) (xy 354.685854 -274.896072) (xy 355.015812 -274.896072) (xy 355.019766 -274.847099)
			(xy 355.031524 -274.799395) (xy 355.050782 -274.754194) (xy 355.077041 -274.712668) (xy 355.109622 -274.675892)
			(xy 355.14768 -274.644818) (xy 355.19023 -274.620252) (xy 355.236169 -274.60283) (xy 355.284309 -274.593002)
			(xy 355.333401 -274.591024) (xy 355.382175 -274.596946) (xy 355.429367 -274.610615) (xy 355.473756 -274.631678)
			(xy 355.514191 -274.659588) (xy 355.549625 -274.693623) (xy 355.579141 -274.732902) (xy 355.601974 -274.776406)
			(xy 355.617533 -274.82301) (xy 355.625414 -274.871506) (xy 355.625908 -274.896072) (xy 364.409494 -274.896072)
			(xy 364.413448 -274.847099) (xy 364.425206 -274.799395) (xy 364.444464 -274.754194) (xy 364.470723 -274.712668)
			(xy 364.503304 -274.675892) (xy 364.541362 -274.644818) (xy 364.583912 -274.620252) (xy 364.629851 -274.60283)
			(xy 364.677991 -274.593002) (xy 364.727083 -274.591024) (xy 364.775857 -274.596946) (xy 364.823049 -274.610615)
			(xy 364.867438 -274.631678) (xy 364.907873 -274.659588) (xy 364.943307 -274.693623) (xy 364.972823 -274.732902)
			(xy 364.995656 -274.776406) (xy 365.011215 -274.82301) (xy 365.019096 -274.871506) (xy 365.01959 -274.896072)
			(xy 365.349548 -274.896072) (xy 365.353502 -274.847099) (xy 365.36526 -274.799395) (xy 365.384518 -274.754194)
			(xy 365.410777 -274.712668) (xy 365.443358 -274.675892) (xy 365.481416 -274.644818) (xy 365.523966 -274.620252)
			(xy 365.569905 -274.60283) (xy 365.618045 -274.593002) (xy 365.667137 -274.591024) (xy 365.715911 -274.596946)
			(xy 365.763103 -274.610615) (xy 365.807492 -274.631678) (xy 365.847927 -274.659588) (xy 365.883361 -274.693623)
			(xy 365.912877 -274.732902) (xy 365.93571 -274.776406) (xy 365.951269 -274.82301) (xy 365.95915 -274.871506)
			(xy 365.959644 -274.896072) (xy 367.229402 -274.896072) (xy 367.233356 -274.847099) (xy 367.245114 -274.799395)
			(xy 367.264372 -274.754194) (xy 367.290631 -274.712668) (xy 367.323212 -274.675892) (xy 367.36127 -274.644818)
			(xy 367.40382 -274.620252) (xy 367.449759 -274.60283) (xy 367.497899 -274.593002) (xy 367.546991 -274.591024)
			(xy 367.595765 -274.596946) (xy 367.642957 -274.610615) (xy 367.687346 -274.631678) (xy 367.727781 -274.659588)
			(xy 367.763215 -274.693623) (xy 367.792731 -274.732902) (xy 367.815564 -274.776406) (xy 367.831123 -274.82301)
			(xy 367.839004 -274.871506) (xy 367.839498 -274.896072) (xy 368.169456 -274.896072) (xy 368.17341 -274.847099)
			(xy 368.185168 -274.799395) (xy 368.204426 -274.754194) (xy 368.230685 -274.712668) (xy 368.263266 -274.675892)
			(xy 368.301324 -274.644818) (xy 368.343874 -274.620252) (xy 368.389813 -274.60283) (xy 368.437953 -274.593002)
			(xy 368.487045 -274.591024) (xy 368.535819 -274.596946) (xy 368.583011 -274.610615) (xy 368.6274 -274.631678)
			(xy 368.667835 -274.659588) (xy 368.703269 -274.693623) (xy 368.732785 -274.732902) (xy 368.755618 -274.776406)
			(xy 368.771177 -274.82301) (xy 368.779058 -274.871506) (xy 368.779552 -274.896072) (xy 370.04931 -274.896072)
			(xy 370.053264 -274.847099) (xy 370.065022 -274.799395) (xy 370.08428 -274.754194) (xy 370.110539 -274.712668)
			(xy 370.14312 -274.675892) (xy 370.181178 -274.644818) (xy 370.223728 -274.620252) (xy 370.269667 -274.60283)
			(xy 370.317807 -274.593002) (xy 370.366899 -274.591024) (xy 370.415673 -274.596946) (xy 370.462865 -274.610615)
			(xy 370.507254 -274.631678) (xy 370.547689 -274.659588) (xy 370.583123 -274.693623) (xy 370.612639 -274.732902)
			(xy 370.635472 -274.776406) (xy 370.651031 -274.82301) (xy 370.658912 -274.871506) (xy 370.659406 -274.896072)
			(xy 370.989364 -274.896072) (xy 370.993318 -274.847099) (xy 371.005076 -274.799395) (xy 371.024334 -274.754194)
			(xy 371.050593 -274.712668) (xy 371.083174 -274.675892) (xy 371.121232 -274.644818) (xy 371.163782 -274.620252)
			(xy 371.209721 -274.60283) (xy 371.257861 -274.593002) (xy 371.306953 -274.591024) (xy 371.355727 -274.596946)
			(xy 371.402919 -274.610615) (xy 371.447308 -274.631678) (xy 371.487743 -274.659588) (xy 371.523177 -274.693623)
			(xy 371.552693 -274.732902) (xy 371.575526 -274.776406) (xy 371.591085 -274.82301) (xy 371.598966 -274.871506)
			(xy 371.59946 -274.896072) (xy 372.869472 -274.896072) (xy 372.873426 -274.847099) (xy 372.885184 -274.799395)
			(xy 372.904442 -274.754194) (xy 372.930701 -274.712668) (xy 372.963282 -274.675892) (xy 373.00134 -274.644818)
			(xy 373.04389 -274.620252) (xy 373.089829 -274.60283) (xy 373.137969 -274.593002) (xy 373.187061 -274.591024)
			(xy 373.235835 -274.596946) (xy 373.283027 -274.610615) (xy 373.327416 -274.631678) (xy 373.367851 -274.659588)
			(xy 373.403285 -274.693623) (xy 373.432801 -274.732902) (xy 373.455634 -274.776406) (xy 373.471193 -274.82301)
			(xy 373.479074 -274.871506) (xy 373.479568 -274.896072) (xy 373.809526 -274.896072) (xy 373.81348 -274.847099)
			(xy 373.825238 -274.799395) (xy 373.844496 -274.754194) (xy 373.870755 -274.712668) (xy 373.903336 -274.675892)
			(xy 373.941394 -274.644818) (xy 373.983944 -274.620252) (xy 374.029883 -274.60283) (xy 374.078023 -274.593002)
			(xy 374.127115 -274.591024) (xy 374.175889 -274.596946) (xy 374.223081 -274.610615) (xy 374.26747 -274.631678)
			(xy 374.307905 -274.659588) (xy 374.343339 -274.693623) (xy 374.372855 -274.732902) (xy 374.395688 -274.776406)
			(xy 374.411247 -274.82301) (xy 374.419128 -274.871506) (xy 374.419622 -274.896072) (xy 374.419128 -274.920638)
			(xy 374.411247 -274.969134) (xy 374.395688 -275.015738) (xy 374.372855 -275.059242) (xy 374.343339 -275.098521)
			(xy 374.307905 -275.132556) (xy 374.26747 -275.160466) (xy 374.223081 -275.181529) (xy 374.175889 -275.195198)
			(xy 374.127115 -275.20112) (xy 374.078023 -275.199142) (xy 374.029883 -275.189314) (xy 373.983944 -275.171892)
			(xy 373.941394 -275.147326) (xy 373.903336 -275.116252) (xy 373.870755 -275.079476) (xy 373.844496 -275.03795)
			(xy 373.825238 -274.992749) (xy 373.81348 -274.945045) (xy 373.809526 -274.896072) (xy 373.479568 -274.896072)
			(xy 373.479074 -274.920638) (xy 373.471193 -274.969134) (xy 373.455634 -275.015738) (xy 373.432801 -275.059242)
			(xy 373.403285 -275.098521) (xy 373.367851 -275.132556) (xy 373.327416 -275.160466) (xy 373.283027 -275.181529)
			(xy 373.235835 -275.195198) (xy 373.187061 -275.20112) (xy 373.137969 -275.199142) (xy 373.089829 -275.189314)
			(xy 373.04389 -275.171892) (xy 373.00134 -275.147326) (xy 372.963282 -275.116252) (xy 372.930701 -275.079476)
			(xy 372.904442 -275.03795) (xy 372.885184 -274.992749) (xy 372.873426 -274.945045) (xy 372.869472 -274.896072)
			(xy 371.59946 -274.896072) (xy 371.598966 -274.920638) (xy 371.591085 -274.969134) (xy 371.575526 -275.015738)
			(xy 371.552693 -275.059242) (xy 371.523177 -275.098521) (xy 371.487743 -275.132556) (xy 371.447308 -275.160466)
			(xy 371.402919 -275.181529) (xy 371.355727 -275.195198) (xy 371.306953 -275.20112) (xy 371.257861 -275.199142)
			(xy 371.209721 -275.189314) (xy 371.163782 -275.171892) (xy 371.121232 -275.147326) (xy 371.083174 -275.116252)
			(xy 371.050593 -275.079476) (xy 371.024334 -275.03795) (xy 371.005076 -274.992749) (xy 370.993318 -274.945045)
			(xy 370.989364 -274.896072) (xy 370.659406 -274.896072) (xy 370.658912 -274.920638) (xy 370.651031 -274.969134)
			(xy 370.635472 -275.015738) (xy 370.612639 -275.059242) (xy 370.583123 -275.098521) (xy 370.547689 -275.132556)
			(xy 370.507254 -275.160466) (xy 370.462865 -275.181529) (xy 370.415673 -275.195198) (xy 370.366899 -275.20112)
			(xy 370.317807 -275.199142) (xy 370.269667 -275.189314) (xy 370.223728 -275.171892) (xy 370.181178 -275.147326)
			(xy 370.14312 -275.116252) (xy 370.110539 -275.079476) (xy 370.08428 -275.03795) (xy 370.065022 -274.992749)
			(xy 370.053264 -274.945045) (xy 370.04931 -274.896072) (xy 368.779552 -274.896072) (xy 368.779058 -274.920638)
			(xy 368.771177 -274.969134) (xy 368.755618 -275.015738) (xy 368.732785 -275.059242) (xy 368.703269 -275.098521)
			(xy 368.667835 -275.132556) (xy 368.6274 -275.160466) (xy 368.583011 -275.181529) (xy 368.535819 -275.195198)
			(xy 368.487045 -275.20112) (xy 368.437953 -275.199142) (xy 368.389813 -275.189314) (xy 368.343874 -275.171892)
			(xy 368.301324 -275.147326) (xy 368.263266 -275.116252) (xy 368.230685 -275.079476) (xy 368.204426 -275.03795)
			(xy 368.185168 -274.992749) (xy 368.17341 -274.945045) (xy 368.169456 -274.896072) (xy 367.839498 -274.896072)
			(xy 367.839004 -274.920638) (xy 367.831123 -274.969134) (xy 367.815564 -275.015738) (xy 367.792731 -275.059242)
			(xy 367.763215 -275.098521) (xy 367.727781 -275.132556) (xy 367.687346 -275.160466) (xy 367.642957 -275.181529)
			(xy 367.595765 -275.195198) (xy 367.546991 -275.20112) (xy 367.497899 -275.199142) (xy 367.449759 -275.189314)
			(xy 367.40382 -275.171892) (xy 367.36127 -275.147326) (xy 367.323212 -275.116252) (xy 367.290631 -275.079476)
			(xy 367.264372 -275.03795) (xy 367.245114 -274.992749) (xy 367.233356 -274.945045) (xy 367.229402 -274.896072)
			(xy 365.959644 -274.896072) (xy 365.95915 -274.920638) (xy 365.951269 -274.969134) (xy 365.93571 -275.015738)
			(xy 365.912877 -275.059242) (xy 365.883361 -275.098521) (xy 365.847927 -275.132556) (xy 365.807492 -275.160466)
			(xy 365.763103 -275.181529) (xy 365.715911 -275.195198) (xy 365.667137 -275.20112) (xy 365.618045 -275.199142)
			(xy 365.569905 -275.189314) (xy 365.523966 -275.171892) (xy 365.481416 -275.147326) (xy 365.443358 -275.116252)
			(xy 365.410777 -275.079476) (xy 365.384518 -275.03795) (xy 365.36526 -274.992749) (xy 365.353502 -274.945045)
			(xy 365.349548 -274.896072) (xy 365.01959 -274.896072) (xy 365.019096 -274.920638) (xy 365.011215 -274.969134)
			(xy 364.995656 -275.015738) (xy 364.972823 -275.059242) (xy 364.943307 -275.098521) (xy 364.907873 -275.132556)
			(xy 364.867438 -275.160466) (xy 364.823049 -275.181529) (xy 364.775857 -275.195198) (xy 364.727083 -275.20112)
			(xy 364.677991 -275.199142) (xy 364.629851 -275.189314) (xy 364.583912 -275.171892) (xy 364.541362 -275.147326)
			(xy 364.503304 -275.116252) (xy 364.470723 -275.079476) (xy 364.444464 -275.03795) (xy 364.425206 -274.992749)
			(xy 364.413448 -274.945045) (xy 364.409494 -274.896072) (xy 355.625908 -274.896072) (xy 355.625414 -274.920638)
			(xy 355.617533 -274.969134) (xy 355.601974 -275.015738) (xy 355.579141 -275.059242) (xy 355.549625 -275.098521)
			(xy 355.514191 -275.132556) (xy 355.473756 -275.160466) (xy 355.429367 -275.181529) (xy 355.382175 -275.195198)
			(xy 355.333401 -275.20112) (xy 355.284309 -275.199142) (xy 355.236169 -275.189314) (xy 355.19023 -275.171892)
			(xy 355.14768 -275.147326) (xy 355.109622 -275.116252) (xy 355.077041 -275.079476) (xy 355.050782 -275.03795)
			(xy 355.031524 -274.992749) (xy 355.019766 -274.945045) (xy 355.015812 -274.896072) (xy 354.685854 -274.896072)
			(xy 354.68536 -274.920638) (xy 354.677479 -274.969134) (xy 354.66192 -275.015738) (xy 354.639087 -275.059242)
			(xy 354.609571 -275.098521) (xy 354.574137 -275.132556) (xy 354.533702 -275.160466) (xy 354.489313 -275.181529)
			(xy 354.442121 -275.195198) (xy 354.393347 -275.20112) (xy 354.344255 -275.199142) (xy 354.296115 -275.189314)
			(xy 354.250176 -275.171892) (xy 354.207626 -275.147326) (xy 354.169568 -275.116252) (xy 354.136987 -275.079476)
			(xy 354.110728 -275.03795) (xy 354.09147 -274.992749) (xy 354.079712 -274.945045) (xy 354.075758 -274.896072)
			(xy 352.806 -274.896072) (xy 352.805506 -274.920638) (xy 352.797625 -274.969134) (xy 352.782066 -275.015738)
			(xy 352.759233 -275.059242) (xy 352.729717 -275.098521) (xy 352.694283 -275.132556) (xy 352.653848 -275.160466)
			(xy 352.609459 -275.181529) (xy 352.562267 -275.195198) (xy 352.513493 -275.20112) (xy 352.464401 -275.199142)
			(xy 352.416261 -275.189314) (xy 352.370322 -275.171892) (xy 352.327772 -275.147326) (xy 352.289714 -275.116252)
			(xy 352.257133 -275.079476) (xy 352.230874 -275.03795) (xy 352.211616 -274.992749) (xy 352.199858 -274.945045)
			(xy 352.195904 -274.896072) (xy 351.865946 -274.896072) (xy 351.865452 -274.920638) (xy 351.857571 -274.969134)
			(xy 351.842012 -275.015738) (xy 351.819179 -275.059242) (xy 351.789663 -275.098521) (xy 351.754229 -275.132556)
			(xy 351.713794 -275.160466) (xy 351.669405 -275.181529) (xy 351.622213 -275.195198) (xy 351.573439 -275.20112)
			(xy 351.524347 -275.199142) (xy 351.476207 -275.189314) (xy 351.430268 -275.171892) (xy 351.387718 -275.147326)
			(xy 351.34966 -275.116252) (xy 351.317079 -275.079476) (xy 351.29082 -275.03795) (xy 351.271562 -274.992749)
			(xy 351.259804 -274.945045) (xy 351.25585 -274.896072) (xy 349.985838 -274.896072) (xy 349.985344 -274.920638)
			(xy 349.977463 -274.969134) (xy 349.961904 -275.015738) (xy 349.939071 -275.059242) (xy 349.909555 -275.098521)
			(xy 349.874121 -275.132556) (xy 349.833686 -275.160466) (xy 349.789297 -275.181529) (xy 349.742105 -275.195198)
			(xy 349.693331 -275.20112) (xy 349.644239 -275.199142) (xy 349.596099 -275.189314) (xy 349.55016 -275.171892)
			(xy 349.50761 -275.147326) (xy 349.469552 -275.116252) (xy 349.436971 -275.079476) (xy 349.410712 -275.03795)
			(xy 349.391454 -274.992749) (xy 349.379696 -274.945045) (xy 349.375742 -274.896072) (xy 349.045784 -274.896072)
			(xy 349.04529 -274.920638) (xy 349.037409 -274.969134) (xy 349.02185 -275.015738) (xy 348.999017 -275.059242)
			(xy 348.969501 -275.098521) (xy 348.934067 -275.132556) (xy 348.893632 -275.160466) (xy 348.849243 -275.181529)
			(xy 348.802051 -275.195198) (xy 348.753277 -275.20112) (xy 348.704185 -275.199142) (xy 348.656045 -275.189314)
			(xy 348.610106 -275.171892) (xy 348.567556 -275.147326) (xy 348.529498 -275.116252) (xy 348.496917 -275.079476)
			(xy 348.470658 -275.03795) (xy 348.4514 -274.992749) (xy 348.439642 -274.945045) (xy 348.435688 -274.896072)
			(xy 347.16593 -274.896072) (xy 347.165436 -274.920638) (xy 347.157555 -274.969134) (xy 347.141996 -275.015738)
			(xy 347.119163 -275.059242) (xy 347.089647 -275.098521) (xy 347.054213 -275.132556) (xy 347.013778 -275.160466)
			(xy 346.969389 -275.181529) (xy 346.922197 -275.195198) (xy 346.873423 -275.20112) (xy 346.824331 -275.199142)
			(xy 346.776191 -275.189314) (xy 346.730252 -275.171892) (xy 346.687702 -275.147326) (xy 346.649644 -275.116252)
			(xy 346.617063 -275.079476) (xy 346.590804 -275.03795) (xy 346.571546 -274.992749) (xy 346.559788 -274.945045)
			(xy 346.555834 -274.896072) (xy 346.225876 -274.896072) (xy 346.225382 -274.920638) (xy 346.217501 -274.969134)
			(xy 346.201942 -275.015738) (xy 346.179109 -275.059242) (xy 346.149593 -275.098521) (xy 346.114159 -275.132556)
			(xy 346.073724 -275.160466) (xy 346.029335 -275.181529) (xy 345.982143 -275.195198) (xy 345.933369 -275.20112)
			(xy 345.884277 -275.199142) (xy 345.836137 -275.189314) (xy 345.790198 -275.171892) (xy 345.747648 -275.147326)
			(xy 345.70959 -275.116252) (xy 345.677009 -275.079476) (xy 345.65075 -275.03795) (xy 345.631492 -274.992749)
			(xy 345.619734 -274.945045) (xy 345.61578 -274.896072) (xy 126.479549 -274.896072) (xy 126.479554 -274.896326)
			(xy 126.47906 -274.920892) (xy 126.471179 -274.969388) (xy 126.45562 -275.015992) (xy 126.432787 -275.059496)
			(xy 126.403271 -275.098775) (xy 126.367837 -275.13281) (xy 126.327402 -275.16072) (xy 126.283013 -275.181783)
			(xy 126.235821 -275.195452) (xy 126.187047 -275.201374) (xy 126.137955 -275.199396) (xy 126.089815 -275.189568)
			(xy 126.043876 -275.172146) (xy 126.001326 -275.14758) (xy 125.963268 -275.116506) (xy 125.930687 -275.07973)
			(xy 125.904428 -275.038204) (xy 125.88517 -274.993003) (xy 125.873412 -274.945299) (xy 125.869458 -274.896326)
			(xy 125.5395 -274.896326) (xy 125.539006 -274.920892) (xy 125.531125 -274.969388) (xy 125.515566 -275.015992)
			(xy 125.492733 -275.059496) (xy 125.463217 -275.098775) (xy 125.427783 -275.13281) (xy 125.387348 -275.16072)
			(xy 125.342959 -275.181783) (xy 125.295767 -275.195452) (xy 125.246993 -275.201374) (xy 125.197901 -275.199396)
			(xy 125.149761 -275.189568) (xy 125.103822 -275.172146) (xy 125.061272 -275.14758) (xy 125.023214 -275.116506)
			(xy 124.990633 -275.07973) (xy 124.964374 -275.038204) (xy 124.945116 -274.993003) (xy 124.933358 -274.945299)
			(xy 124.929404 -274.896326) (xy 123.659392 -274.896326) (xy 123.658898 -274.920892) (xy 123.651017 -274.969388)
			(xy 123.635458 -275.015992) (xy 123.612625 -275.059496) (xy 123.583109 -275.098775) (xy 123.547675 -275.13281)
			(xy 123.50724 -275.16072) (xy 123.462851 -275.181783) (xy 123.415659 -275.195452) (xy 123.366885 -275.201374)
			(xy 123.317793 -275.199396) (xy 123.269653 -275.189568) (xy 123.223714 -275.172146) (xy 123.181164 -275.14758)
			(xy 123.143106 -275.116506) (xy 123.110525 -275.07973) (xy 123.084266 -275.038204) (xy 123.065008 -274.993003)
			(xy 123.05325 -274.945299) (xy 123.049296 -274.896326) (xy 122.719338 -274.896326) (xy 122.718844 -274.920892)
			(xy 122.710963 -274.969388) (xy 122.695404 -275.015992) (xy 122.672571 -275.059496) (xy 122.643055 -275.098775)
			(xy 122.607621 -275.13281) (xy 122.567186 -275.16072) (xy 122.522797 -275.181783) (xy 122.475605 -275.195452)
			(xy 122.426831 -275.201374) (xy 122.377739 -275.199396) (xy 122.329599 -275.189568) (xy 122.28366 -275.172146)
			(xy 122.24111 -275.14758) (xy 122.203052 -275.116506) (xy 122.170471 -275.07973) (xy 122.144212 -275.038204)
			(xy 122.124954 -274.993003) (xy 122.113196 -274.945299) (xy 122.109242 -274.896326) (xy 120.839484 -274.896326)
			(xy 120.83899 -274.920892) (xy 120.831109 -274.969388) (xy 120.81555 -275.015992) (xy 120.792717 -275.059496)
			(xy 120.763201 -275.098775) (xy 120.727767 -275.13281) (xy 120.687332 -275.16072) (xy 120.642943 -275.181783)
			(xy 120.595751 -275.195452) (xy 120.546977 -275.201374) (xy 120.497885 -275.199396) (xy 120.449745 -275.189568)
			(xy 120.403806 -275.172146) (xy 120.361256 -275.14758) (xy 120.323198 -275.116506) (xy 120.290617 -275.07973)
			(xy 120.264358 -275.038204) (xy 120.2451 -274.993003) (xy 120.233342 -274.945299) (xy 120.229388 -274.896326)
			(xy 119.89943 -274.896326) (xy 119.898936 -274.920892) (xy 119.891055 -274.969388) (xy 119.875496 -275.015992)
			(xy 119.852663 -275.059496) (xy 119.823147 -275.098775) (xy 119.787713 -275.13281) (xy 119.747278 -275.16072)
			(xy 119.702889 -275.181783) (xy 119.655697 -275.195452) (xy 119.606923 -275.201374) (xy 119.557831 -275.199396)
			(xy 119.509691 -275.189568) (xy 119.463752 -275.172146) (xy 119.421202 -275.14758) (xy 119.383144 -275.116506)
			(xy 119.350563 -275.07973) (xy 119.324304 -275.038204) (xy 119.305046 -274.993003) (xy 119.293288 -274.945299)
			(xy 119.289334 -274.896326) (xy 118.019576 -274.896326) (xy 118.019082 -274.920892) (xy 118.011201 -274.969388)
			(xy 117.995642 -275.015992) (xy 117.972809 -275.059496) (xy 117.943293 -275.098775) (xy 117.907859 -275.13281)
			(xy 117.867424 -275.16072) (xy 117.823035 -275.181783) (xy 117.775843 -275.195452) (xy 117.727069 -275.201374)
			(xy 117.677977 -275.199396) (xy 117.629837 -275.189568) (xy 117.583898 -275.172146) (xy 117.541348 -275.14758)
			(xy 117.50329 -275.116506) (xy 117.470709 -275.07973) (xy 117.44445 -275.038204) (xy 117.425192 -274.993003)
			(xy 117.413434 -274.945299) (xy 117.40948 -274.896326) (xy 117.079522 -274.896326) (xy 117.079028 -274.920892)
			(xy 117.071147 -274.969388) (xy 117.055588 -275.015992) (xy 117.032755 -275.059496) (xy 117.003239 -275.098775)
			(xy 116.967805 -275.13281) (xy 116.92737 -275.16072) (xy 116.882981 -275.181783) (xy 116.835789 -275.195452)
			(xy 116.787015 -275.201374) (xy 116.737923 -275.199396) (xy 116.689783 -275.189568) (xy 116.643844 -275.172146)
			(xy 116.601294 -275.14758) (xy 116.563236 -275.116506) (xy 116.530655 -275.07973) (xy 116.504396 -275.038204)
			(xy 116.485138 -274.993003) (xy 116.47338 -274.945299) (xy 116.469426 -274.896326) (xy 107.68584 -274.896326)
			(xy 107.685346 -274.920892) (xy 107.677465 -274.969388) (xy 107.661906 -275.015992) (xy 107.639073 -275.059496)
			(xy 107.609557 -275.098775) (xy 107.574123 -275.13281) (xy 107.533688 -275.16072) (xy 107.489299 -275.181783)
			(xy 107.442107 -275.195452) (xy 107.393333 -275.201374) (xy 107.344241 -275.199396) (xy 107.296101 -275.189568)
			(xy 107.250162 -275.172146) (xy 107.207612 -275.14758) (xy 107.169554 -275.116506) (xy 107.136973 -275.07973)
			(xy 107.110714 -275.038204) (xy 107.091456 -274.993003) (xy 107.079698 -274.945299) (xy 107.075744 -274.896326)
			(xy 106.745786 -274.896326) (xy 106.745292 -274.920892) (xy 106.737411 -274.969388) (xy 106.721852 -275.015992)
			(xy 106.699019 -275.059496) (xy 106.669503 -275.098775) (xy 106.634069 -275.13281) (xy 106.593634 -275.16072)
			(xy 106.549245 -275.181783) (xy 106.502053 -275.195452) (xy 106.453279 -275.201374) (xy 106.404187 -275.199396)
			(xy 106.356047 -275.189568) (xy 106.310108 -275.172146) (xy 106.267558 -275.14758) (xy 106.2295 -275.116506)
			(xy 106.196919 -275.07973) (xy 106.17066 -275.038204) (xy 106.151402 -274.993003) (xy 106.139644 -274.945299)
			(xy 106.13569 -274.896326) (xy 104.865932 -274.896326) (xy 104.865438 -274.920892) (xy 104.857557 -274.969388)
			(xy 104.841998 -275.015992) (xy 104.819165 -275.059496) (xy 104.789649 -275.098775) (xy 104.754215 -275.13281)
			(xy 104.71378 -275.16072) (xy 104.669391 -275.181783) (xy 104.622199 -275.195452) (xy 104.573425 -275.201374)
			(xy 104.524333 -275.199396) (xy 104.476193 -275.189568) (xy 104.430254 -275.172146) (xy 104.387704 -275.14758)
			(xy 104.349646 -275.116506) (xy 104.317065 -275.07973) (xy 104.290806 -275.038204) (xy 104.271548 -274.993003)
			(xy 104.25979 -274.945299) (xy 104.255836 -274.896326) (xy 103.925878 -274.896326) (xy 103.925384 -274.920892)
			(xy 103.917503 -274.969388) (xy 103.901944 -275.015992) (xy 103.879111 -275.059496) (xy 103.849595 -275.098775)
			(xy 103.814161 -275.13281) (xy 103.773726 -275.16072) (xy 103.729337 -275.181783) (xy 103.682145 -275.195452)
			(xy 103.633371 -275.201374) (xy 103.584279 -275.199396) (xy 103.536139 -275.189568) (xy 103.4902 -275.172146)
			(xy 103.44765 -275.14758) (xy 103.409592 -275.116506) (xy 103.377011 -275.07973) (xy 103.350752 -275.038204)
			(xy 103.331494 -274.993003) (xy 103.319736 -274.945299) (xy 103.315782 -274.896326) (xy 102.04577 -274.896326)
			(xy 102.045276 -274.920892) (xy 102.037395 -274.969388) (xy 102.021836 -275.015992) (xy 101.999003 -275.059496)
			(xy 101.969487 -275.098775) (xy 101.934053 -275.13281) (xy 101.893618 -275.16072) (xy 101.849229 -275.181783)
			(xy 101.802037 -275.195452) (xy 101.753263 -275.201374) (xy 101.704171 -275.199396) (xy 101.656031 -275.189568)
			(xy 101.610092 -275.172146) (xy 101.567542 -275.14758) (xy 101.529484 -275.116506) (xy 101.496903 -275.07973)
			(xy 101.470644 -275.038204) (xy 101.451386 -274.993003) (xy 101.439628 -274.945299) (xy 101.435674 -274.896326)
			(xy 101.105716 -274.896326) (xy 101.105222 -274.920892) (xy 101.097341 -274.969388) (xy 101.081782 -275.015992)
			(xy 101.058949 -275.059496) (xy 101.029433 -275.098775) (xy 100.993999 -275.13281) (xy 100.953564 -275.16072)
			(xy 100.909175 -275.181783) (xy 100.861983 -275.195452) (xy 100.813209 -275.201374) (xy 100.764117 -275.199396)
			(xy 100.715977 -275.189568) (xy 100.670038 -275.172146) (xy 100.627488 -275.14758) (xy 100.58943 -275.116506)
			(xy 100.556849 -275.07973) (xy 100.53059 -275.038204) (xy 100.511332 -274.993003) (xy 100.499574 -274.945299)
			(xy 100.49562 -274.896326) (xy 99.225862 -274.896326) (xy 99.225368 -274.920892) (xy 99.217487 -274.969388)
			(xy 99.201928 -275.015992) (xy 99.179095 -275.059496) (xy 99.149579 -275.098775) (xy 99.114145 -275.13281)
			(xy 99.07371 -275.16072) (xy 99.029321 -275.181783) (xy 98.982129 -275.195452) (xy 98.933355 -275.201374)
			(xy 98.884263 -275.199396) (xy 98.836123 -275.189568) (xy 98.790184 -275.172146) (xy 98.747634 -275.14758)
			(xy 98.709576 -275.116506) (xy 98.676995 -275.07973) (xy 98.650736 -275.038204) (xy 98.631478 -274.993003)
			(xy 98.61972 -274.945299) (xy 98.615766 -274.896326) (xy 98.285808 -274.896326) (xy 98.285314 -274.920892)
			(xy 98.277433 -274.969388) (xy 98.261874 -275.015992) (xy 98.239041 -275.059496) (xy 98.209525 -275.098775)
			(xy 98.174091 -275.13281) (xy 98.133656 -275.16072) (xy 98.089267 -275.181783) (xy 98.042075 -275.195452)
			(xy 97.993301 -275.201374) (xy 97.944209 -275.199396) (xy 97.896069 -275.189568) (xy 97.85013 -275.172146)
			(xy 97.80758 -275.14758) (xy 97.769522 -275.116506) (xy 97.736941 -275.07973) (xy 97.710682 -275.038204)
			(xy 97.691424 -274.993003) (xy 97.679666 -274.945299) (xy 97.675712 -274.896326) (xy 2.509012 -274.896326)
			(xy 2.509012 -275.706332) (xy 108.485698 -275.706332) (xy 108.489652 -275.657359) (xy 108.50141 -275.609655)
			(xy 108.520668 -275.564454) (xy 108.546927 -275.522928) (xy 108.579508 -275.486152) (xy 108.617566 -275.455078)
			(xy 108.660116 -275.430512) (xy 108.706055 -275.41309) (xy 108.754195 -275.403262) (xy 108.803287 -275.401284)
			(xy 108.852061 -275.407206) (xy 108.899253 -275.420875) (xy 108.943642 -275.441938) (xy 108.984077 -275.469848)
			(xy 109.019511 -275.503883) (xy 109.049027 -275.543162) (xy 109.07186 -275.586666) (xy 109.087419 -275.63327)
			(xy 109.0953 -275.681766) (xy 109.095794 -275.706332) (xy 109.425752 -275.706332) (xy 109.429706 -275.657359)
			(xy 109.441464 -275.609655) (xy 109.460722 -275.564454) (xy 109.486981 -275.522928) (xy 109.519562 -275.486152)
			(xy 109.55762 -275.455078) (xy 109.60017 -275.430512) (xy 109.646109 -275.41309) (xy 109.694249 -275.403262)
			(xy 109.743341 -275.401284) (xy 109.792115 -275.407206) (xy 109.839307 -275.420875) (xy 109.883696 -275.441938)
			(xy 109.924131 -275.469848) (xy 109.959565 -275.503883) (xy 109.989081 -275.543162) (xy 110.011914 -275.586666)
			(xy 110.027473 -275.63327) (xy 110.035354 -275.681766) (xy 110.035848 -275.706332) (xy 114.119418 -275.706332)
			(xy 114.123372 -275.657359) (xy 114.13513 -275.609655) (xy 114.154388 -275.564454) (xy 114.180647 -275.522928)
			(xy 114.213228 -275.486152) (xy 114.251286 -275.455078) (xy 114.293836 -275.430512) (xy 114.339775 -275.41309)
			(xy 114.387915 -275.403262) (xy 114.437007 -275.401284) (xy 114.485781 -275.407206) (xy 114.532973 -275.420875)
			(xy 114.577362 -275.441938) (xy 114.617797 -275.469848) (xy 114.653231 -275.503883) (xy 114.682747 -275.543162)
			(xy 114.70558 -275.586666) (xy 114.721139 -275.63327) (xy 114.72902 -275.681766) (xy 114.729514 -275.706332)
			(xy 115.059472 -275.706332) (xy 115.063426 -275.657359) (xy 115.075184 -275.609655) (xy 115.094442 -275.564454)
			(xy 115.120701 -275.522928) (xy 115.153282 -275.486152) (xy 115.19134 -275.455078) (xy 115.23389 -275.430512)
			(xy 115.279829 -275.41309) (xy 115.327969 -275.403262) (xy 115.377061 -275.401284) (xy 115.425835 -275.407206)
			(xy 115.473027 -275.420875) (xy 115.517416 -275.441938) (xy 115.557851 -275.469848) (xy 115.593285 -275.503883)
			(xy 115.622801 -275.543162) (xy 115.645634 -275.586666) (xy 115.661193 -275.63327) (xy 115.669074 -275.681766)
			(xy 115.669563 -275.706078) (xy 356.425766 -275.706078) (xy 356.42972 -275.657105) (xy 356.441478 -275.609401)
			(xy 356.460736 -275.5642) (xy 356.486995 -275.522674) (xy 356.519576 -275.485898) (xy 356.557634 -275.454824)
			(xy 356.600184 -275.430258) (xy 356.646123 -275.412836) (xy 356.694263 -275.403008) (xy 356.743355 -275.40103)
			(xy 356.792129 -275.406952) (xy 356.839321 -275.420621) (xy 356.88371 -275.441684) (xy 356.924145 -275.469594)
			(xy 356.959579 -275.503629) (xy 356.989095 -275.542908) (xy 357.011928 -275.586412) (xy 357.027487 -275.633016)
			(xy 357.035368 -275.681512) (xy 357.035862 -275.706078) (xy 357.36582 -275.706078) (xy 357.369774 -275.657105)
			(xy 357.381532 -275.609401) (xy 357.40079 -275.5642) (xy 357.427049 -275.522674) (xy 357.45963 -275.485898)
			(xy 357.497688 -275.454824) (xy 357.540238 -275.430258) (xy 357.586177 -275.412836) (xy 357.634317 -275.403008)
			(xy 357.683409 -275.40103) (xy 357.732183 -275.406952) (xy 357.779375 -275.420621) (xy 357.823764 -275.441684)
			(xy 357.864199 -275.469594) (xy 357.899633 -275.503629) (xy 357.929149 -275.542908) (xy 357.951982 -275.586412)
			(xy 357.967541 -275.633016) (xy 357.975422 -275.681512) (xy 357.975916 -275.706078) (xy 362.059486 -275.706078)
			(xy 362.06344 -275.657105) (xy 362.075198 -275.609401) (xy 362.094456 -275.5642) (xy 362.120715 -275.522674)
			(xy 362.153296 -275.485898) (xy 362.191354 -275.454824) (xy 362.233904 -275.430258) (xy 362.279843 -275.412836)
			(xy 362.327983 -275.403008) (xy 362.377075 -275.40103) (xy 362.425849 -275.406952) (xy 362.473041 -275.420621)
			(xy 362.51743 -275.441684) (xy 362.557865 -275.469594) (xy 362.593299 -275.503629) (xy 362.622815 -275.542908)
			(xy 362.645648 -275.586412) (xy 362.661207 -275.633016) (xy 362.669088 -275.681512) (xy 362.669582 -275.706078)
			(xy 362.99954 -275.706078) (xy 363.003494 -275.657105) (xy 363.015252 -275.609401) (xy 363.03451 -275.5642)
			(xy 363.060769 -275.522674) (xy 363.09335 -275.485898) (xy 363.131408 -275.454824) (xy 363.173958 -275.430258)
			(xy 363.219897 -275.412836) (xy 363.268037 -275.403008) (xy 363.317129 -275.40103) (xy 363.365903 -275.406952)
			(xy 363.413095 -275.420621) (xy 363.457484 -275.441684) (xy 363.497919 -275.469594) (xy 363.533353 -275.503629)
			(xy 363.562869 -275.542908) (xy 363.585702 -275.586412) (xy 363.601261 -275.633016) (xy 363.609142 -275.681512)
			(xy 363.609636 -275.706078) (xy 363.609142 -275.730644) (xy 363.601261 -275.77914) (xy 363.585702 -275.825744)
			(xy 363.562869 -275.869248) (xy 363.533353 -275.908527) (xy 363.497919 -275.942562) (xy 363.457484 -275.970472)
			(xy 363.413095 -275.991535) (xy 363.365903 -276.005204) (xy 363.317129 -276.011126) (xy 363.268037 -276.009148)
			(xy 363.219897 -275.99932) (xy 363.173958 -275.981898) (xy 363.131408 -275.957332) (xy 363.09335 -275.926258)
			(xy 363.060769 -275.889482) (xy 363.03451 -275.847956) (xy 363.015252 -275.802755) (xy 363.003494 -275.755051)
			(xy 362.99954 -275.706078) (xy 362.669582 -275.706078) (xy 362.669088 -275.730644) (xy 362.661207 -275.77914)
			(xy 362.645648 -275.825744) (xy 362.622815 -275.869248) (xy 362.593299 -275.908527) (xy 362.557865 -275.942562)
			(xy 362.51743 -275.970472) (xy 362.473041 -275.991535) (xy 362.425849 -276.005204) (xy 362.377075 -276.011126)
			(xy 362.327983 -276.009148) (xy 362.279843 -275.99932) (xy 362.233904 -275.981898) (xy 362.191354 -275.957332)
			(xy 362.153296 -275.926258) (xy 362.120715 -275.889482) (xy 362.094456 -275.847956) (xy 362.075198 -275.802755)
			(xy 362.06344 -275.755051) (xy 362.059486 -275.706078) (xy 357.975916 -275.706078) (xy 357.975422 -275.730644)
			(xy 357.967541 -275.77914) (xy 357.951982 -275.825744) (xy 357.929149 -275.869248) (xy 357.899633 -275.908527)
			(xy 357.864199 -275.942562) (xy 357.823764 -275.970472) (xy 357.779375 -275.991535) (xy 357.732183 -276.005204)
			(xy 357.683409 -276.011126) (xy 357.634317 -276.009148) (xy 357.586177 -275.99932) (xy 357.540238 -275.981898)
			(xy 357.497688 -275.957332) (xy 357.45963 -275.926258) (xy 357.427049 -275.889482) (xy 357.40079 -275.847956)
			(xy 357.381532 -275.802755) (xy 357.369774 -275.755051) (xy 357.36582 -275.706078) (xy 357.035862 -275.706078)
			(xy 357.035368 -275.730644) (xy 357.027487 -275.77914) (xy 357.011928 -275.825744) (xy 356.989095 -275.869248)
			(xy 356.959579 -275.908527) (xy 356.924145 -275.942562) (xy 356.88371 -275.970472) (xy 356.839321 -275.991535)
			(xy 356.792129 -276.005204) (xy 356.743355 -276.011126) (xy 356.694263 -276.009148) (xy 356.646123 -275.99932)
			(xy 356.600184 -275.981898) (xy 356.557634 -275.957332) (xy 356.519576 -275.926258) (xy 356.486995 -275.889482)
			(xy 356.460736 -275.847956) (xy 356.441478 -275.802755) (xy 356.42972 -275.755051) (xy 356.425766 -275.706078)
			(xy 115.669563 -275.706078) (xy 115.669568 -275.706332) (xy 115.669074 -275.730898) (xy 115.661193 -275.779394)
			(xy 115.645634 -275.825998) (xy 115.622801 -275.869502) (xy 115.593285 -275.908781) (xy 115.557851 -275.942816)
			(xy 115.517416 -275.970726) (xy 115.473027 -275.991789) (xy 115.425835 -276.005458) (xy 115.377061 -276.01138)
			(xy 115.327969 -276.009402) (xy 115.279829 -275.999574) (xy 115.23389 -275.982152) (xy 115.19134 -275.957586)
			(xy 115.153282 -275.926512) (xy 115.120701 -275.889736) (xy 115.094442 -275.84821) (xy 115.075184 -275.803009)
			(xy 115.063426 -275.755305) (xy 115.059472 -275.706332) (xy 114.729514 -275.706332) (xy 114.72902 -275.730898)
			(xy 114.721139 -275.779394) (xy 114.70558 -275.825998) (xy 114.682747 -275.869502) (xy 114.653231 -275.908781)
			(xy 114.617797 -275.942816) (xy 114.577362 -275.970726) (xy 114.532973 -275.991789) (xy 114.485781 -276.005458)
			(xy 114.437007 -276.01138) (xy 114.387915 -276.009402) (xy 114.339775 -275.999574) (xy 114.293836 -275.982152)
			(xy 114.251286 -275.957586) (xy 114.213228 -275.926512) (xy 114.180647 -275.889736) (xy 114.154388 -275.84821)
			(xy 114.13513 -275.803009) (xy 114.123372 -275.755305) (xy 114.119418 -275.706332) (xy 110.035848 -275.706332)
			(xy 110.035354 -275.730898) (xy 110.027473 -275.779394) (xy 110.011914 -275.825998) (xy 109.989081 -275.869502)
			(xy 109.959565 -275.908781) (xy 109.924131 -275.942816) (xy 109.883696 -275.970726) (xy 109.839307 -275.991789)
			(xy 109.792115 -276.005458) (xy 109.743341 -276.01138) (xy 109.694249 -276.009402) (xy 109.646109 -275.999574)
			(xy 109.60017 -275.982152) (xy 109.55762 -275.957586) (xy 109.519562 -275.926512) (xy 109.486981 -275.889736)
			(xy 109.460722 -275.84821) (xy 109.441464 -275.803009) (xy 109.429706 -275.755305) (xy 109.425752 -275.706332)
			(xy 109.095794 -275.706332) (xy 109.0953 -275.730898) (xy 109.087419 -275.779394) (xy 109.07186 -275.825998)
			(xy 109.049027 -275.869502) (xy 109.019511 -275.908781) (xy 108.984077 -275.942816) (xy 108.943642 -275.970726)
			(xy 108.899253 -275.991789) (xy 108.852061 -276.005458) (xy 108.803287 -276.01138) (xy 108.754195 -276.009402)
			(xy 108.706055 -275.999574) (xy 108.660116 -275.982152) (xy 108.617566 -275.957586) (xy 108.579508 -275.926512)
			(xy 108.546927 -275.889736) (xy 108.520668 -275.84821) (xy 108.50141 -275.803009) (xy 108.489652 -275.755305)
			(xy 108.485698 -275.706332) (xy 2.509012 -275.706332) (xy 2.509012 -276.516338) (xy 97.675712 -276.516338)
			(xy 97.679666 -276.467365) (xy 97.691424 -276.419661) (xy 97.710682 -276.37446) (xy 97.736941 -276.332934)
			(xy 97.769522 -276.296158) (xy 97.80758 -276.265084) (xy 97.85013 -276.240518) (xy 97.896069 -276.223096)
			(xy 97.944209 -276.213268) (xy 97.993301 -276.21129) (xy 98.042075 -276.217212) (xy 98.089267 -276.230881)
			(xy 98.133656 -276.251944) (xy 98.174091 -276.279854) (xy 98.209525 -276.313889) (xy 98.239041 -276.353168)
			(xy 98.261874 -276.396672) (xy 98.277433 -276.443276) (xy 98.285314 -276.491772) (xy 98.285808 -276.516338)
			(xy 98.615766 -276.516338) (xy 98.61972 -276.467365) (xy 98.631478 -276.419661) (xy 98.650736 -276.37446)
			(xy 98.676995 -276.332934) (xy 98.709576 -276.296158) (xy 98.747634 -276.265084) (xy 98.790184 -276.240518)
			(xy 98.836123 -276.223096) (xy 98.884263 -276.213268) (xy 98.933355 -276.21129) (xy 98.982129 -276.217212)
			(xy 99.029321 -276.230881) (xy 99.07371 -276.251944) (xy 99.114145 -276.279854) (xy 99.149579 -276.313889)
			(xy 99.179095 -276.353168) (xy 99.201928 -276.396672) (xy 99.217487 -276.443276) (xy 99.225368 -276.491772)
			(xy 99.225862 -276.516338) (xy 100.49562 -276.516338) (xy 100.499574 -276.467365) (xy 100.511332 -276.419661)
			(xy 100.53059 -276.37446) (xy 100.556849 -276.332934) (xy 100.58943 -276.296158) (xy 100.627488 -276.265084)
			(xy 100.670038 -276.240518) (xy 100.715977 -276.223096) (xy 100.764117 -276.213268) (xy 100.813209 -276.21129)
			(xy 100.861983 -276.217212) (xy 100.909175 -276.230881) (xy 100.953564 -276.251944) (xy 100.993999 -276.279854)
			(xy 101.029433 -276.313889) (xy 101.058949 -276.353168) (xy 101.081782 -276.396672) (xy 101.097341 -276.443276)
			(xy 101.105222 -276.491772) (xy 101.105716 -276.516338) (xy 101.435674 -276.516338) (xy 101.439628 -276.467365)
			(xy 101.451386 -276.419661) (xy 101.470644 -276.37446) (xy 101.496903 -276.332934) (xy 101.529484 -276.296158)
			(xy 101.567542 -276.265084) (xy 101.610092 -276.240518) (xy 101.656031 -276.223096) (xy 101.704171 -276.213268)
			(xy 101.753263 -276.21129) (xy 101.802037 -276.217212) (xy 101.849229 -276.230881) (xy 101.893618 -276.251944)
			(xy 101.934053 -276.279854) (xy 101.969487 -276.313889) (xy 101.999003 -276.353168) (xy 102.021836 -276.396672)
			(xy 102.037395 -276.443276) (xy 102.045276 -276.491772) (xy 102.04577 -276.516338) (xy 103.315782 -276.516338)
			(xy 103.319736 -276.467365) (xy 103.331494 -276.419661) (xy 103.350752 -276.37446) (xy 103.377011 -276.332934)
			(xy 103.409592 -276.296158) (xy 103.44765 -276.265084) (xy 103.4902 -276.240518) (xy 103.536139 -276.223096)
			(xy 103.584279 -276.213268) (xy 103.633371 -276.21129) (xy 103.682145 -276.217212) (xy 103.729337 -276.230881)
			(xy 103.773726 -276.251944) (xy 103.814161 -276.279854) (xy 103.849595 -276.313889) (xy 103.879111 -276.353168)
			(xy 103.901944 -276.396672) (xy 103.917503 -276.443276) (xy 103.925384 -276.491772) (xy 103.925878 -276.516338)
			(xy 104.255836 -276.516338) (xy 104.25979 -276.467365) (xy 104.271548 -276.419661) (xy 104.290806 -276.37446)
			(xy 104.317065 -276.332934) (xy 104.349646 -276.296158) (xy 104.387704 -276.265084) (xy 104.430254 -276.240518)
			(xy 104.476193 -276.223096) (xy 104.524333 -276.213268) (xy 104.573425 -276.21129) (xy 104.622199 -276.217212)
			(xy 104.669391 -276.230881) (xy 104.71378 -276.251944) (xy 104.754215 -276.279854) (xy 104.789649 -276.313889)
			(xy 104.819165 -276.353168) (xy 104.841998 -276.396672) (xy 104.857557 -276.443276) (xy 104.865438 -276.491772)
			(xy 104.865932 -276.516338) (xy 106.13569 -276.516338) (xy 106.139644 -276.467365) (xy 106.151402 -276.419661)
			(xy 106.17066 -276.37446) (xy 106.196919 -276.332934) (xy 106.2295 -276.296158) (xy 106.267558 -276.265084)
			(xy 106.310108 -276.240518) (xy 106.356047 -276.223096) (xy 106.404187 -276.213268) (xy 106.453279 -276.21129)
			(xy 106.502053 -276.217212) (xy 106.549245 -276.230881) (xy 106.593634 -276.251944) (xy 106.634069 -276.279854)
			(xy 106.669503 -276.313889) (xy 106.699019 -276.353168) (xy 106.721852 -276.396672) (xy 106.737411 -276.443276)
			(xy 106.745292 -276.491772) (xy 106.745786 -276.516338) (xy 107.075744 -276.516338) (xy 107.079698 -276.467365)
			(xy 107.091456 -276.419661) (xy 107.110714 -276.37446) (xy 107.136973 -276.332934) (xy 107.169554 -276.296158)
			(xy 107.207612 -276.265084) (xy 107.250162 -276.240518) (xy 107.296101 -276.223096) (xy 107.344241 -276.213268)
			(xy 107.393333 -276.21129) (xy 107.442107 -276.217212) (xy 107.489299 -276.230881) (xy 107.533688 -276.251944)
			(xy 107.574123 -276.279854) (xy 107.609557 -276.313889) (xy 107.639073 -276.353168) (xy 107.661906 -276.396672)
			(xy 107.677465 -276.443276) (xy 107.685346 -276.491772) (xy 107.68584 -276.516338) (xy 116.469426 -276.516338)
			(xy 116.47338 -276.467365) (xy 116.485138 -276.419661) (xy 116.504396 -276.37446) (xy 116.530655 -276.332934)
			(xy 116.563236 -276.296158) (xy 116.601294 -276.265084) (xy 116.643844 -276.240518) (xy 116.689783 -276.223096)
			(xy 116.737923 -276.213268) (xy 116.787015 -276.21129) (xy 116.835789 -276.217212) (xy 116.882981 -276.230881)
			(xy 116.92737 -276.251944) (xy 116.967805 -276.279854) (xy 117.003239 -276.313889) (xy 117.032755 -276.353168)
			(xy 117.055588 -276.396672) (xy 117.071147 -276.443276) (xy 117.079028 -276.491772) (xy 117.079522 -276.516338)
			(xy 117.40948 -276.516338) (xy 117.413434 -276.467365) (xy 117.425192 -276.419661) (xy 117.44445 -276.37446)
			(xy 117.470709 -276.332934) (xy 117.50329 -276.296158) (xy 117.541348 -276.265084) (xy 117.583898 -276.240518)
			(xy 117.629837 -276.223096) (xy 117.677977 -276.213268) (xy 117.727069 -276.21129) (xy 117.775843 -276.217212)
			(xy 117.823035 -276.230881) (xy 117.867424 -276.251944) (xy 117.907859 -276.279854) (xy 117.943293 -276.313889)
			(xy 117.972809 -276.353168) (xy 117.995642 -276.396672) (xy 118.011201 -276.443276) (xy 118.019082 -276.491772)
			(xy 118.019576 -276.516338) (xy 119.289334 -276.516338) (xy 119.293288 -276.467365) (xy 119.305046 -276.419661)
			(xy 119.324304 -276.37446) (xy 119.350563 -276.332934) (xy 119.383144 -276.296158) (xy 119.421202 -276.265084)
			(xy 119.463752 -276.240518) (xy 119.509691 -276.223096) (xy 119.557831 -276.213268) (xy 119.606923 -276.21129)
			(xy 119.655697 -276.217212) (xy 119.702889 -276.230881) (xy 119.747278 -276.251944) (xy 119.787713 -276.279854)
			(xy 119.823147 -276.313889) (xy 119.852663 -276.353168) (xy 119.875496 -276.396672) (xy 119.891055 -276.443276)
			(xy 119.898936 -276.491772) (xy 119.89943 -276.516338) (xy 120.229388 -276.516338) (xy 120.233342 -276.467365)
			(xy 120.2451 -276.419661) (xy 120.264358 -276.37446) (xy 120.290617 -276.332934) (xy 120.323198 -276.296158)
			(xy 120.361256 -276.265084) (xy 120.403806 -276.240518) (xy 120.449745 -276.223096) (xy 120.497885 -276.213268)
			(xy 120.546977 -276.21129) (xy 120.595751 -276.217212) (xy 120.642943 -276.230881) (xy 120.687332 -276.251944)
			(xy 120.727767 -276.279854) (xy 120.763201 -276.313889) (xy 120.792717 -276.353168) (xy 120.81555 -276.396672)
			(xy 120.831109 -276.443276) (xy 120.83899 -276.491772) (xy 120.839484 -276.516338) (xy 122.109242 -276.516338)
			(xy 122.113196 -276.467365) (xy 122.124954 -276.419661) (xy 122.144212 -276.37446) (xy 122.170471 -276.332934)
			(xy 122.203052 -276.296158) (xy 122.24111 -276.265084) (xy 122.28366 -276.240518) (xy 122.329599 -276.223096)
			(xy 122.377739 -276.213268) (xy 122.426831 -276.21129) (xy 122.475605 -276.217212) (xy 122.522797 -276.230881)
			(xy 122.567186 -276.251944) (xy 122.607621 -276.279854) (xy 122.643055 -276.313889) (xy 122.672571 -276.353168)
			(xy 122.695404 -276.396672) (xy 122.710963 -276.443276) (xy 122.718844 -276.491772) (xy 122.719338 -276.516338)
			(xy 123.049296 -276.516338) (xy 123.05325 -276.467365) (xy 123.065008 -276.419661) (xy 123.084266 -276.37446)
			(xy 123.110525 -276.332934) (xy 123.143106 -276.296158) (xy 123.181164 -276.265084) (xy 123.223714 -276.240518)
			(xy 123.269653 -276.223096) (xy 123.317793 -276.213268) (xy 123.366885 -276.21129) (xy 123.415659 -276.217212)
			(xy 123.462851 -276.230881) (xy 123.50724 -276.251944) (xy 123.547675 -276.279854) (xy 123.583109 -276.313889)
			(xy 123.612625 -276.353168) (xy 123.635458 -276.396672) (xy 123.651017 -276.443276) (xy 123.658898 -276.491772)
			(xy 123.659392 -276.516338) (xy 124.929404 -276.516338) (xy 124.933358 -276.467365) (xy 124.945116 -276.419661)
			(xy 124.964374 -276.37446) (xy 124.990633 -276.332934) (xy 125.023214 -276.296158) (xy 125.061272 -276.265084)
			(xy 125.103822 -276.240518) (xy 125.149761 -276.223096) (xy 125.197901 -276.213268) (xy 125.246993 -276.21129)
			(xy 125.295767 -276.217212) (xy 125.342959 -276.230881) (xy 125.387348 -276.251944) (xy 125.427783 -276.279854)
			(xy 125.463217 -276.313889) (xy 125.492733 -276.353168) (xy 125.515566 -276.396672) (xy 125.531125 -276.443276)
			(xy 125.539006 -276.491772) (xy 125.5395 -276.516338) (xy 125.869458 -276.516338) (xy 125.873412 -276.467365)
			(xy 125.88517 -276.419661) (xy 125.904428 -276.37446) (xy 125.930687 -276.332934) (xy 125.963268 -276.296158)
			(xy 126.001326 -276.265084) (xy 126.043876 -276.240518) (xy 126.089815 -276.223096) (xy 126.137955 -276.213268)
			(xy 126.187047 -276.21129) (xy 126.235821 -276.217212) (xy 126.283013 -276.230881) (xy 126.327402 -276.251944)
			(xy 126.367837 -276.279854) (xy 126.403271 -276.313889) (xy 126.432787 -276.353168) (xy 126.45562 -276.396672)
			(xy 126.471179 -276.443276) (xy 126.47906 -276.491772) (xy 126.479549 -276.516084) (xy 345.61578 -276.516084)
			(xy 345.619734 -276.467111) (xy 345.631492 -276.419407) (xy 345.65075 -276.374206) (xy 345.677009 -276.33268)
			(xy 345.70959 -276.295904) (xy 345.747648 -276.26483) (xy 345.790198 -276.240264) (xy 345.836137 -276.222842)
			(xy 345.884277 -276.213014) (xy 345.933369 -276.211036) (xy 345.982143 -276.216958) (xy 346.029335 -276.230627)
			(xy 346.073724 -276.25169) (xy 346.114159 -276.2796) (xy 346.149593 -276.313635) (xy 346.179109 -276.352914)
			(xy 346.201942 -276.396418) (xy 346.217501 -276.443022) (xy 346.225382 -276.491518) (xy 346.225876 -276.516084)
			(xy 346.555834 -276.516084) (xy 346.559788 -276.467111) (xy 346.571546 -276.419407) (xy 346.590804 -276.374206)
			(xy 346.617063 -276.33268) (xy 346.649644 -276.295904) (xy 346.687702 -276.26483) (xy 346.730252 -276.240264)
			(xy 346.776191 -276.222842) (xy 346.824331 -276.213014) (xy 346.873423 -276.211036) (xy 346.922197 -276.216958)
			(xy 346.969389 -276.230627) (xy 347.013778 -276.25169) (xy 347.054213 -276.2796) (xy 347.089647 -276.313635)
			(xy 347.119163 -276.352914) (xy 347.141996 -276.396418) (xy 347.157555 -276.443022) (xy 347.165436 -276.491518)
			(xy 347.16593 -276.516084) (xy 348.435688 -276.516084) (xy 348.439642 -276.467111) (xy 348.4514 -276.419407)
			(xy 348.470658 -276.374206) (xy 348.496917 -276.33268) (xy 348.529498 -276.295904) (xy 348.567556 -276.26483)
			(xy 348.610106 -276.240264) (xy 348.656045 -276.222842) (xy 348.704185 -276.213014) (xy 348.753277 -276.211036)
			(xy 348.802051 -276.216958) (xy 348.849243 -276.230627) (xy 348.893632 -276.25169) (xy 348.934067 -276.2796)
			(xy 348.969501 -276.313635) (xy 348.999017 -276.352914) (xy 349.02185 -276.396418) (xy 349.037409 -276.443022)
			(xy 349.04529 -276.491518) (xy 349.045784 -276.516084) (xy 349.375742 -276.516084) (xy 349.379696 -276.467111)
			(xy 349.391454 -276.419407) (xy 349.410712 -276.374206) (xy 349.436971 -276.33268) (xy 349.469552 -276.295904)
			(xy 349.50761 -276.26483) (xy 349.55016 -276.240264) (xy 349.596099 -276.222842) (xy 349.644239 -276.213014)
			(xy 349.693331 -276.211036) (xy 349.742105 -276.216958) (xy 349.789297 -276.230627) (xy 349.833686 -276.25169)
			(xy 349.874121 -276.2796) (xy 349.909555 -276.313635) (xy 349.939071 -276.352914) (xy 349.961904 -276.396418)
			(xy 349.977463 -276.443022) (xy 349.985344 -276.491518) (xy 349.985838 -276.516084) (xy 351.25585 -276.516084)
			(xy 351.259804 -276.467111) (xy 351.271562 -276.419407) (xy 351.29082 -276.374206) (xy 351.317079 -276.33268)
			(xy 351.34966 -276.295904) (xy 351.387718 -276.26483) (xy 351.430268 -276.240264) (xy 351.476207 -276.222842)
			(xy 351.524347 -276.213014) (xy 351.573439 -276.211036) (xy 351.622213 -276.216958) (xy 351.669405 -276.230627)
			(xy 351.713794 -276.25169) (xy 351.754229 -276.2796) (xy 351.789663 -276.313635) (xy 351.819179 -276.352914)
			(xy 351.842012 -276.396418) (xy 351.857571 -276.443022) (xy 351.865452 -276.491518) (xy 351.865946 -276.516084)
			(xy 352.195904 -276.516084) (xy 352.199858 -276.467111) (xy 352.211616 -276.419407) (xy 352.230874 -276.374206)
			(xy 352.257133 -276.33268) (xy 352.289714 -276.295904) (xy 352.327772 -276.26483) (xy 352.370322 -276.240264)
			(xy 352.416261 -276.222842) (xy 352.464401 -276.213014) (xy 352.513493 -276.211036) (xy 352.562267 -276.216958)
			(xy 352.609459 -276.230627) (xy 352.653848 -276.25169) (xy 352.694283 -276.2796) (xy 352.729717 -276.313635)
			(xy 352.759233 -276.352914) (xy 352.782066 -276.396418) (xy 352.797625 -276.443022) (xy 352.805506 -276.491518)
			(xy 352.806 -276.516084) (xy 354.075758 -276.516084) (xy 354.079712 -276.467111) (xy 354.09147 -276.419407)
			(xy 354.110728 -276.374206) (xy 354.136987 -276.33268) (xy 354.169568 -276.295904) (xy 354.207626 -276.26483)
			(xy 354.250176 -276.240264) (xy 354.296115 -276.222842) (xy 354.344255 -276.213014) (xy 354.393347 -276.211036)
			(xy 354.442121 -276.216958) (xy 354.489313 -276.230627) (xy 354.533702 -276.25169) (xy 354.574137 -276.2796)
			(xy 354.609571 -276.313635) (xy 354.639087 -276.352914) (xy 354.66192 -276.396418) (xy 354.677479 -276.443022)
			(xy 354.68536 -276.491518) (xy 354.685854 -276.516084) (xy 355.015812 -276.516084) (xy 355.019766 -276.467111)
			(xy 355.031524 -276.419407) (xy 355.050782 -276.374206) (xy 355.077041 -276.33268) (xy 355.109622 -276.295904)
			(xy 355.14768 -276.26483) (xy 355.19023 -276.240264) (xy 355.236169 -276.222842) (xy 355.284309 -276.213014)
			(xy 355.333401 -276.211036) (xy 355.382175 -276.216958) (xy 355.429367 -276.230627) (xy 355.473756 -276.25169)
			(xy 355.514191 -276.2796) (xy 355.549625 -276.313635) (xy 355.579141 -276.352914) (xy 355.601974 -276.396418)
			(xy 355.617533 -276.443022) (xy 355.625414 -276.491518) (xy 355.625908 -276.516084) (xy 364.409494 -276.516084)
			(xy 364.413448 -276.467111) (xy 364.425206 -276.419407) (xy 364.444464 -276.374206) (xy 364.470723 -276.33268)
			(xy 364.503304 -276.295904) (xy 364.541362 -276.26483) (xy 364.583912 -276.240264) (xy 364.629851 -276.222842)
			(xy 364.677991 -276.213014) (xy 364.727083 -276.211036) (xy 364.775857 -276.216958) (xy 364.823049 -276.230627)
			(xy 364.867438 -276.25169) (xy 364.907873 -276.2796) (xy 364.943307 -276.313635) (xy 364.972823 -276.352914)
			(xy 364.995656 -276.396418) (xy 365.011215 -276.443022) (xy 365.019096 -276.491518) (xy 365.01959 -276.516084)
			(xy 365.349548 -276.516084) (xy 365.353502 -276.467111) (xy 365.36526 -276.419407) (xy 365.384518 -276.374206)
			(xy 365.410777 -276.33268) (xy 365.443358 -276.295904) (xy 365.481416 -276.26483) (xy 365.523966 -276.240264)
			(xy 365.569905 -276.222842) (xy 365.618045 -276.213014) (xy 365.667137 -276.211036) (xy 365.715911 -276.216958)
			(xy 365.763103 -276.230627) (xy 365.807492 -276.25169) (xy 365.847927 -276.2796) (xy 365.883361 -276.313635)
			(xy 365.912877 -276.352914) (xy 365.93571 -276.396418) (xy 365.951269 -276.443022) (xy 365.95915 -276.491518)
			(xy 365.959644 -276.516084) (xy 367.229402 -276.516084) (xy 367.233356 -276.467111) (xy 367.245114 -276.419407)
			(xy 367.264372 -276.374206) (xy 367.290631 -276.33268) (xy 367.323212 -276.295904) (xy 367.36127 -276.26483)
			(xy 367.40382 -276.240264) (xy 367.449759 -276.222842) (xy 367.497899 -276.213014) (xy 367.546991 -276.211036)
			(xy 367.595765 -276.216958) (xy 367.642957 -276.230627) (xy 367.687346 -276.25169) (xy 367.727781 -276.2796)
			(xy 367.763215 -276.313635) (xy 367.792731 -276.352914) (xy 367.815564 -276.396418) (xy 367.831123 -276.443022)
			(xy 367.839004 -276.491518) (xy 367.839498 -276.516084) (xy 368.169456 -276.516084) (xy 368.17341 -276.467111)
			(xy 368.185168 -276.419407) (xy 368.204426 -276.374206) (xy 368.230685 -276.33268) (xy 368.263266 -276.295904)
			(xy 368.301324 -276.26483) (xy 368.343874 -276.240264) (xy 368.389813 -276.222842) (xy 368.437953 -276.213014)
			(xy 368.487045 -276.211036) (xy 368.535819 -276.216958) (xy 368.583011 -276.230627) (xy 368.6274 -276.25169)
			(xy 368.667835 -276.2796) (xy 368.703269 -276.313635) (xy 368.732785 -276.352914) (xy 368.755618 -276.396418)
			(xy 368.771177 -276.443022) (xy 368.779058 -276.491518) (xy 368.779552 -276.516084) (xy 370.04931 -276.516084)
			(xy 370.053264 -276.467111) (xy 370.065022 -276.419407) (xy 370.08428 -276.374206) (xy 370.110539 -276.33268)
			(xy 370.14312 -276.295904) (xy 370.181178 -276.26483) (xy 370.223728 -276.240264) (xy 370.269667 -276.222842)
			(xy 370.317807 -276.213014) (xy 370.366899 -276.211036) (xy 370.415673 -276.216958) (xy 370.462865 -276.230627)
			(xy 370.507254 -276.25169) (xy 370.547689 -276.2796) (xy 370.583123 -276.313635) (xy 370.612639 -276.352914)
			(xy 370.635472 -276.396418) (xy 370.651031 -276.443022) (xy 370.658912 -276.491518) (xy 370.659406 -276.516084)
			(xy 370.989364 -276.516084) (xy 370.993318 -276.467111) (xy 371.005076 -276.419407) (xy 371.024334 -276.374206)
			(xy 371.050593 -276.33268) (xy 371.083174 -276.295904) (xy 371.121232 -276.26483) (xy 371.163782 -276.240264)
			(xy 371.209721 -276.222842) (xy 371.257861 -276.213014) (xy 371.306953 -276.211036) (xy 371.355727 -276.216958)
			(xy 371.402919 -276.230627) (xy 371.447308 -276.25169) (xy 371.487743 -276.2796) (xy 371.523177 -276.313635)
			(xy 371.552693 -276.352914) (xy 371.575526 -276.396418) (xy 371.591085 -276.443022) (xy 371.598966 -276.491518)
			(xy 371.59946 -276.516084) (xy 372.869472 -276.516084) (xy 372.873426 -276.467111) (xy 372.885184 -276.419407)
			(xy 372.904442 -276.374206) (xy 372.930701 -276.33268) (xy 372.963282 -276.295904) (xy 373.00134 -276.26483)
			(xy 373.04389 -276.240264) (xy 373.089829 -276.222842) (xy 373.137969 -276.213014) (xy 373.187061 -276.211036)
			(xy 373.235835 -276.216958) (xy 373.283027 -276.230627) (xy 373.327416 -276.25169) (xy 373.367851 -276.2796)
			(xy 373.403285 -276.313635) (xy 373.432801 -276.352914) (xy 373.455634 -276.396418) (xy 373.471193 -276.443022)
			(xy 373.479074 -276.491518) (xy 373.479568 -276.516084) (xy 373.809526 -276.516084) (xy 373.81348 -276.467111)
			(xy 373.825238 -276.419407) (xy 373.844496 -276.374206) (xy 373.870755 -276.33268) (xy 373.903336 -276.295904)
			(xy 373.941394 -276.26483) (xy 373.983944 -276.240264) (xy 374.029883 -276.222842) (xy 374.078023 -276.213014)
			(xy 374.127115 -276.211036) (xy 374.175889 -276.216958) (xy 374.223081 -276.230627) (xy 374.26747 -276.25169)
			(xy 374.307905 -276.2796) (xy 374.343339 -276.313635) (xy 374.372855 -276.352914) (xy 374.395688 -276.396418)
			(xy 374.411247 -276.443022) (xy 374.419128 -276.491518) (xy 374.419622 -276.516084) (xy 374.419128 -276.54065)
			(xy 374.411247 -276.589146) (xy 374.395688 -276.63575) (xy 374.372855 -276.679254) (xy 374.343339 -276.718533)
			(xy 374.307905 -276.752568) (xy 374.26747 -276.780478) (xy 374.223081 -276.801541) (xy 374.175889 -276.81521)
			(xy 374.127115 -276.821132) (xy 374.078023 -276.819154) (xy 374.029883 -276.809326) (xy 373.983944 -276.791904)
			(xy 373.941394 -276.767338) (xy 373.903336 -276.736264) (xy 373.870755 -276.699488) (xy 373.844496 -276.657962)
			(xy 373.825238 -276.612761) (xy 373.81348 -276.565057) (xy 373.809526 -276.516084) (xy 373.479568 -276.516084)
			(xy 373.479074 -276.54065) (xy 373.471193 -276.589146) (xy 373.455634 -276.63575) (xy 373.432801 -276.679254)
			(xy 373.403285 -276.718533) (xy 373.367851 -276.752568) (xy 373.327416 -276.780478) (xy 373.283027 -276.801541)
			(xy 373.235835 -276.81521) (xy 373.187061 -276.821132) (xy 373.137969 -276.819154) (xy 373.089829 -276.809326)
			(xy 373.04389 -276.791904) (xy 373.00134 -276.767338) (xy 372.963282 -276.736264) (xy 372.930701 -276.699488)
			(xy 372.904442 -276.657962) (xy 372.885184 -276.612761) (xy 372.873426 -276.565057) (xy 372.869472 -276.516084)
			(xy 371.59946 -276.516084) (xy 371.598966 -276.54065) (xy 371.591085 -276.589146) (xy 371.575526 -276.63575)
			(xy 371.552693 -276.679254) (xy 371.523177 -276.718533) (xy 371.487743 -276.752568) (xy 371.447308 -276.780478)
			(xy 371.402919 -276.801541) (xy 371.355727 -276.81521) (xy 371.306953 -276.821132) (xy 371.257861 -276.819154)
			(xy 371.209721 -276.809326) (xy 371.163782 -276.791904) (xy 371.121232 -276.767338) (xy 371.083174 -276.736264)
			(xy 371.050593 -276.699488) (xy 371.024334 -276.657962) (xy 371.005076 -276.612761) (xy 370.993318 -276.565057)
			(xy 370.989364 -276.516084) (xy 370.659406 -276.516084) (xy 370.658912 -276.54065) (xy 370.651031 -276.589146)
			(xy 370.635472 -276.63575) (xy 370.612639 -276.679254) (xy 370.583123 -276.718533) (xy 370.547689 -276.752568)
			(xy 370.507254 -276.780478) (xy 370.462865 -276.801541) (xy 370.415673 -276.81521) (xy 370.366899 -276.821132)
			(xy 370.317807 -276.819154) (xy 370.269667 -276.809326) (xy 370.223728 -276.791904) (xy 370.181178 -276.767338)
			(xy 370.14312 -276.736264) (xy 370.110539 -276.699488) (xy 370.08428 -276.657962) (xy 370.065022 -276.612761)
			(xy 370.053264 -276.565057) (xy 370.04931 -276.516084) (xy 368.779552 -276.516084) (xy 368.779058 -276.54065)
			(xy 368.771177 -276.589146) (xy 368.755618 -276.63575) (xy 368.732785 -276.679254) (xy 368.703269 -276.718533)
			(xy 368.667835 -276.752568) (xy 368.6274 -276.780478) (xy 368.583011 -276.801541) (xy 368.535819 -276.81521)
			(xy 368.487045 -276.821132) (xy 368.437953 -276.819154) (xy 368.389813 -276.809326) (xy 368.343874 -276.791904)
			(xy 368.301324 -276.767338) (xy 368.263266 -276.736264) (xy 368.230685 -276.699488) (xy 368.204426 -276.657962)
			(xy 368.185168 -276.612761) (xy 368.17341 -276.565057) (xy 368.169456 -276.516084) (xy 367.839498 -276.516084)
			(xy 367.839004 -276.54065) (xy 367.831123 -276.589146) (xy 367.815564 -276.63575) (xy 367.792731 -276.679254)
			(xy 367.763215 -276.718533) (xy 367.727781 -276.752568) (xy 367.687346 -276.780478) (xy 367.642957 -276.801541)
			(xy 367.595765 -276.81521) (xy 367.546991 -276.821132) (xy 367.497899 -276.819154) (xy 367.449759 -276.809326)
			(xy 367.40382 -276.791904) (xy 367.36127 -276.767338) (xy 367.323212 -276.736264) (xy 367.290631 -276.699488)
			(xy 367.264372 -276.657962) (xy 367.245114 -276.612761) (xy 367.233356 -276.565057) (xy 367.229402 -276.516084)
			(xy 365.959644 -276.516084) (xy 365.95915 -276.54065) (xy 365.951269 -276.589146) (xy 365.93571 -276.63575)
			(xy 365.912877 -276.679254) (xy 365.883361 -276.718533) (xy 365.847927 -276.752568) (xy 365.807492 -276.780478)
			(xy 365.763103 -276.801541) (xy 365.715911 -276.81521) (xy 365.667137 -276.821132) (xy 365.618045 -276.819154)
			(xy 365.569905 -276.809326) (xy 365.523966 -276.791904) (xy 365.481416 -276.767338) (xy 365.443358 -276.736264)
			(xy 365.410777 -276.699488) (xy 365.384518 -276.657962) (xy 365.36526 -276.612761) (xy 365.353502 -276.565057)
			(xy 365.349548 -276.516084) (xy 365.01959 -276.516084) (xy 365.019096 -276.54065) (xy 365.011215 -276.589146)
			(xy 364.995656 -276.63575) (xy 364.972823 -276.679254) (xy 364.943307 -276.718533) (xy 364.907873 -276.752568)
			(xy 364.867438 -276.780478) (xy 364.823049 -276.801541) (xy 364.775857 -276.81521) (xy 364.727083 -276.821132)
			(xy 364.677991 -276.819154) (xy 364.629851 -276.809326) (xy 364.583912 -276.791904) (xy 364.541362 -276.767338)
			(xy 364.503304 -276.736264) (xy 364.470723 -276.699488) (xy 364.444464 -276.657962) (xy 364.425206 -276.612761)
			(xy 364.413448 -276.565057) (xy 364.409494 -276.516084) (xy 355.625908 -276.516084) (xy 355.625414 -276.54065)
			(xy 355.617533 -276.589146) (xy 355.601974 -276.63575) (xy 355.579141 -276.679254) (xy 355.549625 -276.718533)
			(xy 355.514191 -276.752568) (xy 355.473756 -276.780478) (xy 355.429367 -276.801541) (xy 355.382175 -276.81521)
			(xy 355.333401 -276.821132) (xy 355.284309 -276.819154) (xy 355.236169 -276.809326) (xy 355.19023 -276.791904)
			(xy 355.14768 -276.767338) (xy 355.109622 -276.736264) (xy 355.077041 -276.699488) (xy 355.050782 -276.657962)
			(xy 355.031524 -276.612761) (xy 355.019766 -276.565057) (xy 355.015812 -276.516084) (xy 354.685854 -276.516084)
			(xy 354.68536 -276.54065) (xy 354.677479 -276.589146) (xy 354.66192 -276.63575) (xy 354.639087 -276.679254)
			(xy 354.609571 -276.718533) (xy 354.574137 -276.752568) (xy 354.533702 -276.780478) (xy 354.489313 -276.801541)
			(xy 354.442121 -276.81521) (xy 354.393347 -276.821132) (xy 354.344255 -276.819154) (xy 354.296115 -276.809326)
			(xy 354.250176 -276.791904) (xy 354.207626 -276.767338) (xy 354.169568 -276.736264) (xy 354.136987 -276.699488)
			(xy 354.110728 -276.657962) (xy 354.09147 -276.612761) (xy 354.079712 -276.565057) (xy 354.075758 -276.516084)
			(xy 352.806 -276.516084) (xy 352.805506 -276.54065) (xy 352.797625 -276.589146) (xy 352.782066 -276.63575)
			(xy 352.759233 -276.679254) (xy 352.729717 -276.718533) (xy 352.694283 -276.752568) (xy 352.653848 -276.780478)
			(xy 352.609459 -276.801541) (xy 352.562267 -276.81521) (xy 352.513493 -276.821132) (xy 352.464401 -276.819154)
			(xy 352.416261 -276.809326) (xy 352.370322 -276.791904) (xy 352.327772 -276.767338) (xy 352.289714 -276.736264)
			(xy 352.257133 -276.699488) (xy 352.230874 -276.657962) (xy 352.211616 -276.612761) (xy 352.199858 -276.565057)
			(xy 352.195904 -276.516084) (xy 351.865946 -276.516084) (xy 351.865452 -276.54065) (xy 351.857571 -276.589146)
			(xy 351.842012 -276.63575) (xy 351.819179 -276.679254) (xy 351.789663 -276.718533) (xy 351.754229 -276.752568)
			(xy 351.713794 -276.780478) (xy 351.669405 -276.801541) (xy 351.622213 -276.81521) (xy 351.573439 -276.821132)
			(xy 351.524347 -276.819154) (xy 351.476207 -276.809326) (xy 351.430268 -276.791904) (xy 351.387718 -276.767338)
			(xy 351.34966 -276.736264) (xy 351.317079 -276.699488) (xy 351.29082 -276.657962) (xy 351.271562 -276.612761)
			(xy 351.259804 -276.565057) (xy 351.25585 -276.516084) (xy 349.985838 -276.516084) (xy 349.985344 -276.54065)
			(xy 349.977463 -276.589146) (xy 349.961904 -276.63575) (xy 349.939071 -276.679254) (xy 349.909555 -276.718533)
			(xy 349.874121 -276.752568) (xy 349.833686 -276.780478) (xy 349.789297 -276.801541) (xy 349.742105 -276.81521)
			(xy 349.693331 -276.821132) (xy 349.644239 -276.819154) (xy 349.596099 -276.809326) (xy 349.55016 -276.791904)
			(xy 349.50761 -276.767338) (xy 349.469552 -276.736264) (xy 349.436971 -276.699488) (xy 349.410712 -276.657962)
			(xy 349.391454 -276.612761) (xy 349.379696 -276.565057) (xy 349.375742 -276.516084) (xy 349.045784 -276.516084)
			(xy 349.04529 -276.54065) (xy 349.037409 -276.589146) (xy 349.02185 -276.63575) (xy 348.999017 -276.679254)
			(xy 348.969501 -276.718533) (xy 348.934067 -276.752568) (xy 348.893632 -276.780478) (xy 348.849243 -276.801541)
			(xy 348.802051 -276.81521) (xy 348.753277 -276.821132) (xy 348.704185 -276.819154) (xy 348.656045 -276.809326)
			(xy 348.610106 -276.791904) (xy 348.567556 -276.767338) (xy 348.529498 -276.736264) (xy 348.496917 -276.699488)
			(xy 348.470658 -276.657962) (xy 348.4514 -276.612761) (xy 348.439642 -276.565057) (xy 348.435688 -276.516084)
			(xy 347.16593 -276.516084) (xy 347.165436 -276.54065) (xy 347.157555 -276.589146) (xy 347.141996 -276.63575)
			(xy 347.119163 -276.679254) (xy 347.089647 -276.718533) (xy 347.054213 -276.752568) (xy 347.013778 -276.780478)
			(xy 346.969389 -276.801541) (xy 346.922197 -276.81521) (xy 346.873423 -276.821132) (xy 346.824331 -276.819154)
			(xy 346.776191 -276.809326) (xy 346.730252 -276.791904) (xy 346.687702 -276.767338) (xy 346.649644 -276.736264)
			(xy 346.617063 -276.699488) (xy 346.590804 -276.657962) (xy 346.571546 -276.612761) (xy 346.559788 -276.565057)
			(xy 346.555834 -276.516084) (xy 346.225876 -276.516084) (xy 346.225382 -276.54065) (xy 346.217501 -276.589146)
			(xy 346.201942 -276.63575) (xy 346.179109 -276.679254) (xy 346.149593 -276.718533) (xy 346.114159 -276.752568)
			(xy 346.073724 -276.780478) (xy 346.029335 -276.801541) (xy 345.982143 -276.81521) (xy 345.933369 -276.821132)
			(xy 345.884277 -276.819154) (xy 345.836137 -276.809326) (xy 345.790198 -276.791904) (xy 345.747648 -276.767338)
			(xy 345.70959 -276.736264) (xy 345.677009 -276.699488) (xy 345.65075 -276.657962) (xy 345.631492 -276.612761)
			(xy 345.619734 -276.565057) (xy 345.61578 -276.516084) (xy 126.479549 -276.516084) (xy 126.479554 -276.516338)
			(xy 126.47906 -276.540904) (xy 126.471179 -276.5894) (xy 126.45562 -276.636004) (xy 126.432787 -276.679508)
			(xy 126.403271 -276.718787) (xy 126.367837 -276.752822) (xy 126.327402 -276.780732) (xy 126.283013 -276.801795)
			(xy 126.235821 -276.815464) (xy 126.187047 -276.821386) (xy 126.137955 -276.819408) (xy 126.089815 -276.80958)
			(xy 126.043876 -276.792158) (xy 126.001326 -276.767592) (xy 125.963268 -276.736518) (xy 125.930687 -276.699742)
			(xy 125.904428 -276.658216) (xy 125.88517 -276.613015) (xy 125.873412 -276.565311) (xy 125.869458 -276.516338)
			(xy 125.5395 -276.516338) (xy 125.539006 -276.540904) (xy 125.531125 -276.5894) (xy 125.515566 -276.636004)
			(xy 125.492733 -276.679508) (xy 125.463217 -276.718787) (xy 125.427783 -276.752822) (xy 125.387348 -276.780732)
			(xy 125.342959 -276.801795) (xy 125.295767 -276.815464) (xy 125.246993 -276.821386) (xy 125.197901 -276.819408)
			(xy 125.149761 -276.80958) (xy 125.103822 -276.792158) (xy 125.061272 -276.767592) (xy 125.023214 -276.736518)
			(xy 124.990633 -276.699742) (xy 124.964374 -276.658216) (xy 124.945116 -276.613015) (xy 124.933358 -276.565311)
			(xy 124.929404 -276.516338) (xy 123.659392 -276.516338) (xy 123.658898 -276.540904) (xy 123.651017 -276.5894)
			(xy 123.635458 -276.636004) (xy 123.612625 -276.679508) (xy 123.583109 -276.718787) (xy 123.547675 -276.752822)
			(xy 123.50724 -276.780732) (xy 123.462851 -276.801795) (xy 123.415659 -276.815464) (xy 123.366885 -276.821386)
			(xy 123.317793 -276.819408) (xy 123.269653 -276.80958) (xy 123.223714 -276.792158) (xy 123.181164 -276.767592)
			(xy 123.143106 -276.736518) (xy 123.110525 -276.699742) (xy 123.084266 -276.658216) (xy 123.065008 -276.613015)
			(xy 123.05325 -276.565311) (xy 123.049296 -276.516338) (xy 122.719338 -276.516338) (xy 122.718844 -276.540904)
			(xy 122.710963 -276.5894) (xy 122.695404 -276.636004) (xy 122.672571 -276.679508) (xy 122.643055 -276.718787)
			(xy 122.607621 -276.752822) (xy 122.567186 -276.780732) (xy 122.522797 -276.801795) (xy 122.475605 -276.815464)
			(xy 122.426831 -276.821386) (xy 122.377739 -276.819408) (xy 122.329599 -276.80958) (xy 122.28366 -276.792158)
			(xy 122.24111 -276.767592) (xy 122.203052 -276.736518) (xy 122.170471 -276.699742) (xy 122.144212 -276.658216)
			(xy 122.124954 -276.613015) (xy 122.113196 -276.565311) (xy 122.109242 -276.516338) (xy 120.839484 -276.516338)
			(xy 120.83899 -276.540904) (xy 120.831109 -276.5894) (xy 120.81555 -276.636004) (xy 120.792717 -276.679508)
			(xy 120.763201 -276.718787) (xy 120.727767 -276.752822) (xy 120.687332 -276.780732) (xy 120.642943 -276.801795)
			(xy 120.595751 -276.815464) (xy 120.546977 -276.821386) (xy 120.497885 -276.819408) (xy 120.449745 -276.80958)
			(xy 120.403806 -276.792158) (xy 120.361256 -276.767592) (xy 120.323198 -276.736518) (xy 120.290617 -276.699742)
			(xy 120.264358 -276.658216) (xy 120.2451 -276.613015) (xy 120.233342 -276.565311) (xy 120.229388 -276.516338)
			(xy 119.89943 -276.516338) (xy 119.898936 -276.540904) (xy 119.891055 -276.5894) (xy 119.875496 -276.636004)
			(xy 119.852663 -276.679508) (xy 119.823147 -276.718787) (xy 119.787713 -276.752822) (xy 119.747278 -276.780732)
			(xy 119.702889 -276.801795) (xy 119.655697 -276.815464) (xy 119.606923 -276.821386) (xy 119.557831 -276.819408)
			(xy 119.509691 -276.80958) (xy 119.463752 -276.792158) (xy 119.421202 -276.767592) (xy 119.383144 -276.736518)
			(xy 119.350563 -276.699742) (xy 119.324304 -276.658216) (xy 119.305046 -276.613015) (xy 119.293288 -276.565311)
			(xy 119.289334 -276.516338) (xy 118.019576 -276.516338) (xy 118.019082 -276.540904) (xy 118.011201 -276.5894)
			(xy 117.995642 -276.636004) (xy 117.972809 -276.679508) (xy 117.943293 -276.718787) (xy 117.907859 -276.752822)
			(xy 117.867424 -276.780732) (xy 117.823035 -276.801795) (xy 117.775843 -276.815464) (xy 117.727069 -276.821386)
			(xy 117.677977 -276.819408) (xy 117.629837 -276.80958) (xy 117.583898 -276.792158) (xy 117.541348 -276.767592)
			(xy 117.50329 -276.736518) (xy 117.470709 -276.699742) (xy 117.44445 -276.658216) (xy 117.425192 -276.613015)
			(xy 117.413434 -276.565311) (xy 117.40948 -276.516338) (xy 117.079522 -276.516338) (xy 117.079028 -276.540904)
			(xy 117.071147 -276.5894) (xy 117.055588 -276.636004) (xy 117.032755 -276.679508) (xy 117.003239 -276.718787)
			(xy 116.967805 -276.752822) (xy 116.92737 -276.780732) (xy 116.882981 -276.801795) (xy 116.835789 -276.815464)
			(xy 116.787015 -276.821386) (xy 116.737923 -276.819408) (xy 116.689783 -276.80958) (xy 116.643844 -276.792158)
			(xy 116.601294 -276.767592) (xy 116.563236 -276.736518) (xy 116.530655 -276.699742) (xy 116.504396 -276.658216)
			(xy 116.485138 -276.613015) (xy 116.47338 -276.565311) (xy 116.469426 -276.516338) (xy 107.68584 -276.516338)
			(xy 107.685346 -276.540904) (xy 107.677465 -276.5894) (xy 107.661906 -276.636004) (xy 107.639073 -276.679508)
			(xy 107.609557 -276.718787) (xy 107.574123 -276.752822) (xy 107.533688 -276.780732) (xy 107.489299 -276.801795)
			(xy 107.442107 -276.815464) (xy 107.393333 -276.821386) (xy 107.344241 -276.819408) (xy 107.296101 -276.80958)
			(xy 107.250162 -276.792158) (xy 107.207612 -276.767592) (xy 107.169554 -276.736518) (xy 107.136973 -276.699742)
			(xy 107.110714 -276.658216) (xy 107.091456 -276.613015) (xy 107.079698 -276.565311) (xy 107.075744 -276.516338)
			(xy 106.745786 -276.516338) (xy 106.745292 -276.540904) (xy 106.737411 -276.5894) (xy 106.721852 -276.636004)
			(xy 106.699019 -276.679508) (xy 106.669503 -276.718787) (xy 106.634069 -276.752822) (xy 106.593634 -276.780732)
			(xy 106.549245 -276.801795) (xy 106.502053 -276.815464) (xy 106.453279 -276.821386) (xy 106.404187 -276.819408)
			(xy 106.356047 -276.80958) (xy 106.310108 -276.792158) (xy 106.267558 -276.767592) (xy 106.2295 -276.736518)
			(xy 106.196919 -276.699742) (xy 106.17066 -276.658216) (xy 106.151402 -276.613015) (xy 106.139644 -276.565311)
			(xy 106.13569 -276.516338) (xy 104.865932 -276.516338) (xy 104.865438 -276.540904) (xy 104.857557 -276.5894)
			(xy 104.841998 -276.636004) (xy 104.819165 -276.679508) (xy 104.789649 -276.718787) (xy 104.754215 -276.752822)
			(xy 104.71378 -276.780732) (xy 104.669391 -276.801795) (xy 104.622199 -276.815464) (xy 104.573425 -276.821386)
			(xy 104.524333 -276.819408) (xy 104.476193 -276.80958) (xy 104.430254 -276.792158) (xy 104.387704 -276.767592)
			(xy 104.349646 -276.736518) (xy 104.317065 -276.699742) (xy 104.290806 -276.658216) (xy 104.271548 -276.613015)
			(xy 104.25979 -276.565311) (xy 104.255836 -276.516338) (xy 103.925878 -276.516338) (xy 103.925384 -276.540904)
			(xy 103.917503 -276.5894) (xy 103.901944 -276.636004) (xy 103.879111 -276.679508) (xy 103.849595 -276.718787)
			(xy 103.814161 -276.752822) (xy 103.773726 -276.780732) (xy 103.729337 -276.801795) (xy 103.682145 -276.815464)
			(xy 103.633371 -276.821386) (xy 103.584279 -276.819408) (xy 103.536139 -276.80958) (xy 103.4902 -276.792158)
			(xy 103.44765 -276.767592) (xy 103.409592 -276.736518) (xy 103.377011 -276.699742) (xy 103.350752 -276.658216)
			(xy 103.331494 -276.613015) (xy 103.319736 -276.565311) (xy 103.315782 -276.516338) (xy 102.04577 -276.516338)
			(xy 102.045276 -276.540904) (xy 102.037395 -276.5894) (xy 102.021836 -276.636004) (xy 101.999003 -276.679508)
			(xy 101.969487 -276.718787) (xy 101.934053 -276.752822) (xy 101.893618 -276.780732) (xy 101.849229 -276.801795)
			(xy 101.802037 -276.815464) (xy 101.753263 -276.821386) (xy 101.704171 -276.819408) (xy 101.656031 -276.80958)
			(xy 101.610092 -276.792158) (xy 101.567542 -276.767592) (xy 101.529484 -276.736518) (xy 101.496903 -276.699742)
			(xy 101.470644 -276.658216) (xy 101.451386 -276.613015) (xy 101.439628 -276.565311) (xy 101.435674 -276.516338)
			(xy 101.105716 -276.516338) (xy 101.105222 -276.540904) (xy 101.097341 -276.5894) (xy 101.081782 -276.636004)
			(xy 101.058949 -276.679508) (xy 101.029433 -276.718787) (xy 100.993999 -276.752822) (xy 100.953564 -276.780732)
			(xy 100.909175 -276.801795) (xy 100.861983 -276.815464) (xy 100.813209 -276.821386) (xy 100.764117 -276.819408)
			(xy 100.715977 -276.80958) (xy 100.670038 -276.792158) (xy 100.627488 -276.767592) (xy 100.58943 -276.736518)
			(xy 100.556849 -276.699742) (xy 100.53059 -276.658216) (xy 100.511332 -276.613015) (xy 100.499574 -276.565311)
			(xy 100.49562 -276.516338) (xy 99.225862 -276.516338) (xy 99.225368 -276.540904) (xy 99.217487 -276.5894)
			(xy 99.201928 -276.636004) (xy 99.179095 -276.679508) (xy 99.149579 -276.718787) (xy 99.114145 -276.752822)
			(xy 99.07371 -276.780732) (xy 99.029321 -276.801795) (xy 98.982129 -276.815464) (xy 98.933355 -276.821386)
			(xy 98.884263 -276.819408) (xy 98.836123 -276.80958) (xy 98.790184 -276.792158) (xy 98.747634 -276.767592)
			(xy 98.709576 -276.736518) (xy 98.676995 -276.699742) (xy 98.650736 -276.658216) (xy 98.631478 -276.613015)
			(xy 98.61972 -276.565311) (xy 98.615766 -276.516338) (xy 98.285808 -276.516338) (xy 98.285314 -276.540904)
			(xy 98.277433 -276.5894) (xy 98.261874 -276.636004) (xy 98.239041 -276.679508) (xy 98.209525 -276.718787)
			(xy 98.174091 -276.752822) (xy 98.133656 -276.780732) (xy 98.089267 -276.801795) (xy 98.042075 -276.815464)
			(xy 97.993301 -276.821386) (xy 97.944209 -276.819408) (xy 97.896069 -276.80958) (xy 97.85013 -276.792158)
			(xy 97.80758 -276.767592) (xy 97.769522 -276.736518) (xy 97.736941 -276.699742) (xy 97.710682 -276.658216)
			(xy 97.691424 -276.613015) (xy 97.679666 -276.565311) (xy 97.675712 -276.516338) (xy 2.509012 -276.516338)
			(xy 2.509012 -277.326344) (xy 108.485698 -277.326344) (xy 108.489652 -277.277371) (xy 108.50141 -277.229667)
			(xy 108.520668 -277.184466) (xy 108.546927 -277.14294) (xy 108.579508 -277.106164) (xy 108.617566 -277.07509)
			(xy 108.660116 -277.050524) (xy 108.706055 -277.033102) (xy 108.754195 -277.023274) (xy 108.803287 -277.021296)
			(xy 108.852061 -277.027218) (xy 108.899253 -277.040887) (xy 108.943642 -277.06195) (xy 108.984077 -277.08986)
			(xy 109.019511 -277.123895) (xy 109.049027 -277.163174) (xy 109.07186 -277.206678) (xy 109.087419 -277.253282)
			(xy 109.0953 -277.301778) (xy 109.095794 -277.326344) (xy 109.425752 -277.326344) (xy 109.429706 -277.277371)
			(xy 109.441464 -277.229667) (xy 109.460722 -277.184466) (xy 109.486981 -277.14294) (xy 109.519562 -277.106164)
			(xy 109.55762 -277.07509) (xy 109.60017 -277.050524) (xy 109.646109 -277.033102) (xy 109.694249 -277.023274)
			(xy 109.743341 -277.021296) (xy 109.792115 -277.027218) (xy 109.839307 -277.040887) (xy 109.883696 -277.06195)
			(xy 109.924131 -277.08986) (xy 109.959565 -277.123895) (xy 109.989081 -277.163174) (xy 110.011914 -277.206678)
			(xy 110.027473 -277.253282) (xy 110.035354 -277.301778) (xy 110.035848 -277.326344) (xy 114.119418 -277.326344)
			(xy 114.123372 -277.277371) (xy 114.13513 -277.229667) (xy 114.154388 -277.184466) (xy 114.180647 -277.14294)
			(xy 114.213228 -277.106164) (xy 114.251286 -277.07509) (xy 114.293836 -277.050524) (xy 114.339775 -277.033102)
			(xy 114.387915 -277.023274) (xy 114.437007 -277.021296) (xy 114.485781 -277.027218) (xy 114.532973 -277.040887)
			(xy 114.577362 -277.06195) (xy 114.617797 -277.08986) (xy 114.653231 -277.123895) (xy 114.682747 -277.163174)
			(xy 114.70558 -277.206678) (xy 114.721139 -277.253282) (xy 114.72902 -277.301778) (xy 114.729514 -277.326344)
			(xy 115.059472 -277.326344) (xy 115.063426 -277.277371) (xy 115.075184 -277.229667) (xy 115.094442 -277.184466)
			(xy 115.120701 -277.14294) (xy 115.153282 -277.106164) (xy 115.19134 -277.07509) (xy 115.23389 -277.050524)
			(xy 115.279829 -277.033102) (xy 115.327969 -277.023274) (xy 115.377061 -277.021296) (xy 115.425835 -277.027218)
			(xy 115.473027 -277.040887) (xy 115.517416 -277.06195) (xy 115.557851 -277.08986) (xy 115.593285 -277.123895)
			(xy 115.622801 -277.163174) (xy 115.645634 -277.206678) (xy 115.661193 -277.253282) (xy 115.669074 -277.301778)
			(xy 115.669563 -277.32609) (xy 356.425766 -277.32609) (xy 356.42972 -277.277117) (xy 356.441478 -277.229413)
			(xy 356.460736 -277.184212) (xy 356.486995 -277.142686) (xy 356.519576 -277.10591) (xy 356.557634 -277.074836)
			(xy 356.600184 -277.05027) (xy 356.646123 -277.032848) (xy 356.694263 -277.02302) (xy 356.743355 -277.021042)
			(xy 356.792129 -277.026964) (xy 356.839321 -277.040633) (xy 356.88371 -277.061696) (xy 356.924145 -277.089606)
			(xy 356.959579 -277.123641) (xy 356.989095 -277.16292) (xy 357.011928 -277.206424) (xy 357.027487 -277.253028)
			(xy 357.035368 -277.301524) (xy 357.035862 -277.32609) (xy 357.36582 -277.32609) (xy 357.369774 -277.277117)
			(xy 357.381532 -277.229413) (xy 357.40079 -277.184212) (xy 357.427049 -277.142686) (xy 357.45963 -277.10591)
			(xy 357.497688 -277.074836) (xy 357.540238 -277.05027) (xy 357.586177 -277.032848) (xy 357.634317 -277.02302)
			(xy 357.683409 -277.021042) (xy 357.732183 -277.026964) (xy 357.779375 -277.040633) (xy 357.823764 -277.061696)
			(xy 357.864199 -277.089606) (xy 357.899633 -277.123641) (xy 357.929149 -277.16292) (xy 357.951982 -277.206424)
			(xy 357.967541 -277.253028) (xy 357.975422 -277.301524) (xy 357.975916 -277.32609) (xy 362.059486 -277.32609)
			(xy 362.06344 -277.277117) (xy 362.075198 -277.229413) (xy 362.094456 -277.184212) (xy 362.120715 -277.142686)
			(xy 362.153296 -277.10591) (xy 362.191354 -277.074836) (xy 362.233904 -277.05027) (xy 362.279843 -277.032848)
			(xy 362.327983 -277.02302) (xy 362.377075 -277.021042) (xy 362.425849 -277.026964) (xy 362.473041 -277.040633)
			(xy 362.51743 -277.061696) (xy 362.557865 -277.089606) (xy 362.593299 -277.123641) (xy 362.622815 -277.16292)
			(xy 362.645648 -277.206424) (xy 362.661207 -277.253028) (xy 362.669088 -277.301524) (xy 362.669582 -277.32609)
			(xy 362.99954 -277.32609) (xy 363.003494 -277.277117) (xy 363.015252 -277.229413) (xy 363.03451 -277.184212)
			(xy 363.060769 -277.142686) (xy 363.09335 -277.10591) (xy 363.131408 -277.074836) (xy 363.173958 -277.05027)
			(xy 363.219897 -277.032848) (xy 363.268037 -277.02302) (xy 363.317129 -277.021042) (xy 363.365903 -277.026964)
			(xy 363.413095 -277.040633) (xy 363.457484 -277.061696) (xy 363.497919 -277.089606) (xy 363.533353 -277.123641)
			(xy 363.562869 -277.16292) (xy 363.585702 -277.206424) (xy 363.601261 -277.253028) (xy 363.609142 -277.301524)
			(xy 363.609636 -277.32609) (xy 363.609142 -277.350656) (xy 363.601261 -277.399152) (xy 363.585702 -277.445756)
			(xy 363.562869 -277.48926) (xy 363.533353 -277.528539) (xy 363.497919 -277.562574) (xy 363.457484 -277.590484)
			(xy 363.413095 -277.611547) (xy 363.365903 -277.625216) (xy 363.317129 -277.631138) (xy 363.268037 -277.62916)
			(xy 363.219897 -277.619332) (xy 363.173958 -277.60191) (xy 363.131408 -277.577344) (xy 363.09335 -277.54627)
			(xy 363.060769 -277.509494) (xy 363.03451 -277.467968) (xy 363.015252 -277.422767) (xy 363.003494 -277.375063)
			(xy 362.99954 -277.32609) (xy 362.669582 -277.32609) (xy 362.669088 -277.350656) (xy 362.661207 -277.399152)
			(xy 362.645648 -277.445756) (xy 362.622815 -277.48926) (xy 362.593299 -277.528539) (xy 362.557865 -277.562574)
			(xy 362.51743 -277.590484) (xy 362.473041 -277.611547) (xy 362.425849 -277.625216) (xy 362.377075 -277.631138)
			(xy 362.327983 -277.62916) (xy 362.279843 -277.619332) (xy 362.233904 -277.60191) (xy 362.191354 -277.577344)
			(xy 362.153296 -277.54627) (xy 362.120715 -277.509494) (xy 362.094456 -277.467968) (xy 362.075198 -277.422767)
			(xy 362.06344 -277.375063) (xy 362.059486 -277.32609) (xy 357.975916 -277.32609) (xy 357.975422 -277.350656)
			(xy 357.967541 -277.399152) (xy 357.951982 -277.445756) (xy 357.929149 -277.48926) (xy 357.899633 -277.528539)
			(xy 357.864199 -277.562574) (xy 357.823764 -277.590484) (xy 357.779375 -277.611547) (xy 357.732183 -277.625216)
			(xy 357.683409 -277.631138) (xy 357.634317 -277.62916) (xy 357.586177 -277.619332) (xy 357.540238 -277.60191)
			(xy 357.497688 -277.577344) (xy 357.45963 -277.54627) (xy 357.427049 -277.509494) (xy 357.40079 -277.467968)
			(xy 357.381532 -277.422767) (xy 357.369774 -277.375063) (xy 357.36582 -277.32609) (xy 357.035862 -277.32609)
			(xy 357.035368 -277.350656) (xy 357.027487 -277.399152) (xy 357.011928 -277.445756) (xy 356.989095 -277.48926)
			(xy 356.959579 -277.528539) (xy 356.924145 -277.562574) (xy 356.88371 -277.590484) (xy 356.839321 -277.611547)
			(xy 356.792129 -277.625216) (xy 356.743355 -277.631138) (xy 356.694263 -277.62916) (xy 356.646123 -277.619332)
			(xy 356.600184 -277.60191) (xy 356.557634 -277.577344) (xy 356.519576 -277.54627) (xy 356.486995 -277.509494)
			(xy 356.460736 -277.467968) (xy 356.441478 -277.422767) (xy 356.42972 -277.375063) (xy 356.425766 -277.32609)
			(xy 115.669563 -277.32609) (xy 115.669568 -277.326344) (xy 115.669074 -277.35091) (xy 115.661193 -277.399406)
			(xy 115.645634 -277.44601) (xy 115.622801 -277.489514) (xy 115.593285 -277.528793) (xy 115.557851 -277.562828)
			(xy 115.517416 -277.590738) (xy 115.473027 -277.611801) (xy 115.425835 -277.62547) (xy 115.377061 -277.631392)
			(xy 115.327969 -277.629414) (xy 115.279829 -277.619586) (xy 115.23389 -277.602164) (xy 115.19134 -277.577598)
			(xy 115.153282 -277.546524) (xy 115.120701 -277.509748) (xy 115.094442 -277.468222) (xy 115.075184 -277.423021)
			(xy 115.063426 -277.375317) (xy 115.059472 -277.326344) (xy 114.729514 -277.326344) (xy 114.72902 -277.35091)
			(xy 114.721139 -277.399406) (xy 114.70558 -277.44601) (xy 114.682747 -277.489514) (xy 114.653231 -277.528793)
			(xy 114.617797 -277.562828) (xy 114.577362 -277.590738) (xy 114.532973 -277.611801) (xy 114.485781 -277.62547)
			(xy 114.437007 -277.631392) (xy 114.387915 -277.629414) (xy 114.339775 -277.619586) (xy 114.293836 -277.602164)
			(xy 114.251286 -277.577598) (xy 114.213228 -277.546524) (xy 114.180647 -277.509748) (xy 114.154388 -277.468222)
			(xy 114.13513 -277.423021) (xy 114.123372 -277.375317) (xy 114.119418 -277.326344) (xy 110.035848 -277.326344)
			(xy 110.035354 -277.35091) (xy 110.027473 -277.399406) (xy 110.011914 -277.44601) (xy 109.989081 -277.489514)
			(xy 109.959565 -277.528793) (xy 109.924131 -277.562828) (xy 109.883696 -277.590738) (xy 109.839307 -277.611801)
			(xy 109.792115 -277.62547) (xy 109.743341 -277.631392) (xy 109.694249 -277.629414) (xy 109.646109 -277.619586)
			(xy 109.60017 -277.602164) (xy 109.55762 -277.577598) (xy 109.519562 -277.546524) (xy 109.486981 -277.509748)
			(xy 109.460722 -277.468222) (xy 109.441464 -277.423021) (xy 109.429706 -277.375317) (xy 109.425752 -277.326344)
			(xy 109.095794 -277.326344) (xy 109.0953 -277.35091) (xy 109.087419 -277.399406) (xy 109.07186 -277.44601)
			(xy 109.049027 -277.489514) (xy 109.019511 -277.528793) (xy 108.984077 -277.562828) (xy 108.943642 -277.590738)
			(xy 108.899253 -277.611801) (xy 108.852061 -277.62547) (xy 108.803287 -277.631392) (xy 108.754195 -277.629414)
			(xy 108.706055 -277.619586) (xy 108.660116 -277.602164) (xy 108.617566 -277.577598) (xy 108.579508 -277.546524)
			(xy 108.546927 -277.509748) (xy 108.520668 -277.468222) (xy 108.50141 -277.423021) (xy 108.489652 -277.375317)
			(xy 108.485698 -277.326344) (xy 2.509012 -277.326344) (xy 2.509012 -278.13635) (xy 97.675712 -278.13635)
			(xy 97.679666 -278.087377) (xy 97.691424 -278.039673) (xy 97.710682 -277.994472) (xy 97.736941 -277.952946)
			(xy 97.769522 -277.91617) (xy 97.80758 -277.885096) (xy 97.85013 -277.86053) (xy 97.896069 -277.843108)
			(xy 97.944209 -277.83328) (xy 97.993301 -277.831302) (xy 98.042075 -277.837224) (xy 98.089267 -277.850893)
			(xy 98.133656 -277.871956) (xy 98.174091 -277.899866) (xy 98.209525 -277.933901) (xy 98.239041 -277.97318)
			(xy 98.261874 -278.016684) (xy 98.277433 -278.063288) (xy 98.285314 -278.111784) (xy 98.285808 -278.13635)
			(xy 98.615766 -278.13635) (xy 98.61972 -278.087377) (xy 98.631478 -278.039673) (xy 98.650736 -277.994472)
			(xy 98.676995 -277.952946) (xy 98.709576 -277.91617) (xy 98.747634 -277.885096) (xy 98.790184 -277.86053)
			(xy 98.836123 -277.843108) (xy 98.884263 -277.83328) (xy 98.933355 -277.831302) (xy 98.982129 -277.837224)
			(xy 99.029321 -277.850893) (xy 99.07371 -277.871956) (xy 99.114145 -277.899866) (xy 99.149579 -277.933901)
			(xy 99.179095 -277.97318) (xy 99.201928 -278.016684) (xy 99.217487 -278.063288) (xy 99.225368 -278.111784)
			(xy 99.225862 -278.13635) (xy 100.49562 -278.13635) (xy 100.499574 -278.087377) (xy 100.511332 -278.039673)
			(xy 100.53059 -277.994472) (xy 100.556849 -277.952946) (xy 100.58943 -277.91617) (xy 100.627488 -277.885096)
			(xy 100.670038 -277.86053) (xy 100.715977 -277.843108) (xy 100.764117 -277.83328) (xy 100.813209 -277.831302)
			(xy 100.861983 -277.837224) (xy 100.909175 -277.850893) (xy 100.953564 -277.871956) (xy 100.993999 -277.899866)
			(xy 101.029433 -277.933901) (xy 101.058949 -277.97318) (xy 101.081782 -278.016684) (xy 101.097341 -278.063288)
			(xy 101.105222 -278.111784) (xy 101.105716 -278.13635) (xy 101.435674 -278.13635) (xy 101.439628 -278.087377)
			(xy 101.451386 -278.039673) (xy 101.470644 -277.994472) (xy 101.496903 -277.952946) (xy 101.529484 -277.91617)
			(xy 101.567542 -277.885096) (xy 101.610092 -277.86053) (xy 101.656031 -277.843108) (xy 101.704171 -277.83328)
			(xy 101.753263 -277.831302) (xy 101.802037 -277.837224) (xy 101.849229 -277.850893) (xy 101.893618 -277.871956)
			(xy 101.934053 -277.899866) (xy 101.969487 -277.933901) (xy 101.999003 -277.97318) (xy 102.021836 -278.016684)
			(xy 102.037395 -278.063288) (xy 102.045276 -278.111784) (xy 102.04577 -278.13635) (xy 103.315782 -278.13635)
			(xy 103.319736 -278.087377) (xy 103.331494 -278.039673) (xy 103.350752 -277.994472) (xy 103.377011 -277.952946)
			(xy 103.409592 -277.91617) (xy 103.44765 -277.885096) (xy 103.4902 -277.86053) (xy 103.536139 -277.843108)
			(xy 103.584279 -277.83328) (xy 103.633371 -277.831302) (xy 103.682145 -277.837224) (xy 103.729337 -277.850893)
			(xy 103.773726 -277.871956) (xy 103.814161 -277.899866) (xy 103.849595 -277.933901) (xy 103.879111 -277.97318)
			(xy 103.901944 -278.016684) (xy 103.917503 -278.063288) (xy 103.925384 -278.111784) (xy 103.925878 -278.13635)
			(xy 104.255836 -278.13635) (xy 104.25979 -278.087377) (xy 104.271548 -278.039673) (xy 104.290806 -277.994472)
			(xy 104.317065 -277.952946) (xy 104.349646 -277.91617) (xy 104.387704 -277.885096) (xy 104.430254 -277.86053)
			(xy 104.476193 -277.843108) (xy 104.524333 -277.83328) (xy 104.573425 -277.831302) (xy 104.622199 -277.837224)
			(xy 104.669391 -277.850893) (xy 104.71378 -277.871956) (xy 104.754215 -277.899866) (xy 104.789649 -277.933901)
			(xy 104.819165 -277.97318) (xy 104.841998 -278.016684) (xy 104.857557 -278.063288) (xy 104.865438 -278.111784)
			(xy 104.865932 -278.13635) (xy 106.13569 -278.13635) (xy 106.139644 -278.087377) (xy 106.151402 -278.039673)
			(xy 106.17066 -277.994472) (xy 106.196919 -277.952946) (xy 106.2295 -277.91617) (xy 106.267558 -277.885096)
			(xy 106.310108 -277.86053) (xy 106.356047 -277.843108) (xy 106.404187 -277.83328) (xy 106.453279 -277.831302)
			(xy 106.502053 -277.837224) (xy 106.549245 -277.850893) (xy 106.593634 -277.871956) (xy 106.634069 -277.899866)
			(xy 106.669503 -277.933901) (xy 106.699019 -277.97318) (xy 106.721852 -278.016684) (xy 106.737411 -278.063288)
			(xy 106.745292 -278.111784) (xy 106.745786 -278.13635) (xy 107.075744 -278.13635) (xy 107.079698 -278.087377)
			(xy 107.091456 -278.039673) (xy 107.110714 -277.994472) (xy 107.136973 -277.952946) (xy 107.169554 -277.91617)
			(xy 107.207612 -277.885096) (xy 107.250162 -277.86053) (xy 107.296101 -277.843108) (xy 107.344241 -277.83328)
			(xy 107.393333 -277.831302) (xy 107.442107 -277.837224) (xy 107.489299 -277.850893) (xy 107.533688 -277.871956)
			(xy 107.574123 -277.899866) (xy 107.609557 -277.933901) (xy 107.639073 -277.97318) (xy 107.661906 -278.016684)
			(xy 107.677465 -278.063288) (xy 107.685346 -278.111784) (xy 107.68584 -278.13635) (xy 116.469426 -278.13635)
			(xy 116.47338 -278.087377) (xy 116.485138 -278.039673) (xy 116.504396 -277.994472) (xy 116.530655 -277.952946)
			(xy 116.563236 -277.91617) (xy 116.601294 -277.885096) (xy 116.643844 -277.86053) (xy 116.689783 -277.843108)
			(xy 116.737923 -277.83328) (xy 116.787015 -277.831302) (xy 116.835789 -277.837224) (xy 116.882981 -277.850893)
			(xy 116.92737 -277.871956) (xy 116.967805 -277.899866) (xy 117.003239 -277.933901) (xy 117.032755 -277.97318)
			(xy 117.055588 -278.016684) (xy 117.071147 -278.063288) (xy 117.079028 -278.111784) (xy 117.079522 -278.13635)
			(xy 117.40948 -278.13635) (xy 117.413434 -278.087377) (xy 117.425192 -278.039673) (xy 117.44445 -277.994472)
			(xy 117.470709 -277.952946) (xy 117.50329 -277.91617) (xy 117.541348 -277.885096) (xy 117.583898 -277.86053)
			(xy 117.629837 -277.843108) (xy 117.677977 -277.83328) (xy 117.727069 -277.831302) (xy 117.775843 -277.837224)
			(xy 117.823035 -277.850893) (xy 117.867424 -277.871956) (xy 117.907859 -277.899866) (xy 117.943293 -277.933901)
			(xy 117.972809 -277.97318) (xy 117.995642 -278.016684) (xy 118.011201 -278.063288) (xy 118.019082 -278.111784)
			(xy 118.019576 -278.13635) (xy 119.289334 -278.13635) (xy 119.293288 -278.087377) (xy 119.305046 -278.039673)
			(xy 119.324304 -277.994472) (xy 119.350563 -277.952946) (xy 119.383144 -277.91617) (xy 119.421202 -277.885096)
			(xy 119.463752 -277.86053) (xy 119.509691 -277.843108) (xy 119.557831 -277.83328) (xy 119.606923 -277.831302)
			(xy 119.655697 -277.837224) (xy 119.702889 -277.850893) (xy 119.747278 -277.871956) (xy 119.787713 -277.899866)
			(xy 119.823147 -277.933901) (xy 119.852663 -277.97318) (xy 119.875496 -278.016684) (xy 119.891055 -278.063288)
			(xy 119.898936 -278.111784) (xy 119.89943 -278.13635) (xy 120.229388 -278.13635) (xy 120.233342 -278.087377)
			(xy 120.2451 -278.039673) (xy 120.264358 -277.994472) (xy 120.290617 -277.952946) (xy 120.323198 -277.91617)
			(xy 120.361256 -277.885096) (xy 120.403806 -277.86053) (xy 120.449745 -277.843108) (xy 120.497885 -277.83328)
			(xy 120.546977 -277.831302) (xy 120.595751 -277.837224) (xy 120.642943 -277.850893) (xy 120.687332 -277.871956)
			(xy 120.727767 -277.899866) (xy 120.763201 -277.933901) (xy 120.792717 -277.97318) (xy 120.81555 -278.016684)
			(xy 120.831109 -278.063288) (xy 120.83899 -278.111784) (xy 120.839484 -278.13635) (xy 122.109242 -278.13635)
			(xy 122.113196 -278.087377) (xy 122.124954 -278.039673) (xy 122.144212 -277.994472) (xy 122.170471 -277.952946)
			(xy 122.203052 -277.91617) (xy 122.24111 -277.885096) (xy 122.28366 -277.86053) (xy 122.329599 -277.843108)
			(xy 122.377739 -277.83328) (xy 122.426831 -277.831302) (xy 122.475605 -277.837224) (xy 122.522797 -277.850893)
			(xy 122.567186 -277.871956) (xy 122.607621 -277.899866) (xy 122.643055 -277.933901) (xy 122.672571 -277.97318)
			(xy 122.695404 -278.016684) (xy 122.710963 -278.063288) (xy 122.718844 -278.111784) (xy 122.719338 -278.13635)
			(xy 123.049296 -278.13635) (xy 123.05325 -278.087377) (xy 123.065008 -278.039673) (xy 123.084266 -277.994472)
			(xy 123.110525 -277.952946) (xy 123.143106 -277.91617) (xy 123.181164 -277.885096) (xy 123.223714 -277.86053)
			(xy 123.269653 -277.843108) (xy 123.317793 -277.83328) (xy 123.366885 -277.831302) (xy 123.415659 -277.837224)
			(xy 123.462851 -277.850893) (xy 123.50724 -277.871956) (xy 123.547675 -277.899866) (xy 123.583109 -277.933901)
			(xy 123.612625 -277.97318) (xy 123.635458 -278.016684) (xy 123.651017 -278.063288) (xy 123.658898 -278.111784)
			(xy 123.659392 -278.13635) (xy 124.929404 -278.13635) (xy 124.933358 -278.087377) (xy 124.945116 -278.039673)
			(xy 124.964374 -277.994472) (xy 124.990633 -277.952946) (xy 125.023214 -277.91617) (xy 125.061272 -277.885096)
			(xy 125.103822 -277.86053) (xy 125.149761 -277.843108) (xy 125.197901 -277.83328) (xy 125.246993 -277.831302)
			(xy 125.295767 -277.837224) (xy 125.342959 -277.850893) (xy 125.387348 -277.871956) (xy 125.427783 -277.899866)
			(xy 125.463217 -277.933901) (xy 125.492733 -277.97318) (xy 125.515566 -278.016684) (xy 125.531125 -278.063288)
			(xy 125.539006 -278.111784) (xy 125.5395 -278.13635) (xy 125.869458 -278.13635) (xy 125.873412 -278.087377)
			(xy 125.88517 -278.039673) (xy 125.904428 -277.994472) (xy 125.930687 -277.952946) (xy 125.963268 -277.91617)
			(xy 126.001326 -277.885096) (xy 126.043876 -277.86053) (xy 126.089815 -277.843108) (xy 126.137955 -277.83328)
			(xy 126.187047 -277.831302) (xy 126.235821 -277.837224) (xy 126.283013 -277.850893) (xy 126.327402 -277.871956)
			(xy 126.367837 -277.899866) (xy 126.403271 -277.933901) (xy 126.432787 -277.97318) (xy 126.45562 -278.016684)
			(xy 126.471179 -278.063288) (xy 126.47906 -278.111784) (xy 126.479549 -278.136096) (xy 345.61578 -278.136096)
			(xy 345.619734 -278.087123) (xy 345.631492 -278.039419) (xy 345.65075 -277.994218) (xy 345.677009 -277.952692)
			(xy 345.70959 -277.915916) (xy 345.747648 -277.884842) (xy 345.790198 -277.860276) (xy 345.836137 -277.842854)
			(xy 345.884277 -277.833026) (xy 345.933369 -277.831048) (xy 345.982143 -277.83697) (xy 346.029335 -277.850639)
			(xy 346.073724 -277.871702) (xy 346.114159 -277.899612) (xy 346.149593 -277.933647) (xy 346.179109 -277.972926)
			(xy 346.201942 -278.01643) (xy 346.217501 -278.063034) (xy 346.225382 -278.11153) (xy 346.225876 -278.136096)
			(xy 346.555834 -278.136096) (xy 346.559788 -278.087123) (xy 346.571546 -278.039419) (xy 346.590804 -277.994218)
			(xy 346.617063 -277.952692) (xy 346.649644 -277.915916) (xy 346.687702 -277.884842) (xy 346.730252 -277.860276)
			(xy 346.776191 -277.842854) (xy 346.824331 -277.833026) (xy 346.873423 -277.831048) (xy 346.922197 -277.83697)
			(xy 346.969389 -277.850639) (xy 347.013778 -277.871702) (xy 347.054213 -277.899612) (xy 347.089647 -277.933647)
			(xy 347.119163 -277.972926) (xy 347.141996 -278.01643) (xy 347.157555 -278.063034) (xy 347.165436 -278.11153)
			(xy 347.16593 -278.136096) (xy 348.435688 -278.136096) (xy 348.439642 -278.087123) (xy 348.4514 -278.039419)
			(xy 348.470658 -277.994218) (xy 348.496917 -277.952692) (xy 348.529498 -277.915916) (xy 348.567556 -277.884842)
			(xy 348.610106 -277.860276) (xy 348.656045 -277.842854) (xy 348.704185 -277.833026) (xy 348.753277 -277.831048)
			(xy 348.802051 -277.83697) (xy 348.849243 -277.850639) (xy 348.893632 -277.871702) (xy 348.934067 -277.899612)
			(xy 348.969501 -277.933647) (xy 348.999017 -277.972926) (xy 349.02185 -278.01643) (xy 349.037409 -278.063034)
			(xy 349.04529 -278.11153) (xy 349.045784 -278.136096) (xy 349.375742 -278.136096) (xy 349.379696 -278.087123)
			(xy 349.391454 -278.039419) (xy 349.410712 -277.994218) (xy 349.436971 -277.952692) (xy 349.469552 -277.915916)
			(xy 349.50761 -277.884842) (xy 349.55016 -277.860276) (xy 349.596099 -277.842854) (xy 349.644239 -277.833026)
			(xy 349.693331 -277.831048) (xy 349.742105 -277.83697) (xy 349.789297 -277.850639) (xy 349.833686 -277.871702)
			(xy 349.874121 -277.899612) (xy 349.909555 -277.933647) (xy 349.939071 -277.972926) (xy 349.961904 -278.01643)
			(xy 349.977463 -278.063034) (xy 349.985344 -278.11153) (xy 349.985838 -278.136096) (xy 351.25585 -278.136096)
			(xy 351.259804 -278.087123) (xy 351.271562 -278.039419) (xy 351.29082 -277.994218) (xy 351.317079 -277.952692)
			(xy 351.34966 -277.915916) (xy 351.387718 -277.884842) (xy 351.430268 -277.860276) (xy 351.476207 -277.842854)
			(xy 351.524347 -277.833026) (xy 351.573439 -277.831048) (xy 351.622213 -277.83697) (xy 351.669405 -277.850639)
			(xy 351.713794 -277.871702) (xy 351.754229 -277.899612) (xy 351.789663 -277.933647) (xy 351.819179 -277.972926)
			(xy 351.842012 -278.01643) (xy 351.857571 -278.063034) (xy 351.865452 -278.11153) (xy 351.865946 -278.136096)
			(xy 352.195904 -278.136096) (xy 352.199858 -278.087123) (xy 352.211616 -278.039419) (xy 352.230874 -277.994218)
			(xy 352.257133 -277.952692) (xy 352.289714 -277.915916) (xy 352.327772 -277.884842) (xy 352.370322 -277.860276)
			(xy 352.416261 -277.842854) (xy 352.464401 -277.833026) (xy 352.513493 -277.831048) (xy 352.562267 -277.83697)
			(xy 352.609459 -277.850639) (xy 352.653848 -277.871702) (xy 352.694283 -277.899612) (xy 352.729717 -277.933647)
			(xy 352.759233 -277.972926) (xy 352.782066 -278.01643) (xy 352.797625 -278.063034) (xy 352.805506 -278.11153)
			(xy 352.806 -278.136096) (xy 354.075758 -278.136096) (xy 354.079712 -278.087123) (xy 354.09147 -278.039419)
			(xy 354.110728 -277.994218) (xy 354.136987 -277.952692) (xy 354.169568 -277.915916) (xy 354.207626 -277.884842)
			(xy 354.250176 -277.860276) (xy 354.296115 -277.842854) (xy 354.344255 -277.833026) (xy 354.393347 -277.831048)
			(xy 354.442121 -277.83697) (xy 354.489313 -277.850639) (xy 354.533702 -277.871702) (xy 354.574137 -277.899612)
			(xy 354.609571 -277.933647) (xy 354.639087 -277.972926) (xy 354.66192 -278.01643) (xy 354.677479 -278.063034)
			(xy 354.68536 -278.11153) (xy 354.685854 -278.136096) (xy 355.015812 -278.136096) (xy 355.019766 -278.087123)
			(xy 355.031524 -278.039419) (xy 355.050782 -277.994218) (xy 355.077041 -277.952692) (xy 355.109622 -277.915916)
			(xy 355.14768 -277.884842) (xy 355.19023 -277.860276) (xy 355.236169 -277.842854) (xy 355.284309 -277.833026)
			(xy 355.333401 -277.831048) (xy 355.382175 -277.83697) (xy 355.429367 -277.850639) (xy 355.473756 -277.871702)
			(xy 355.514191 -277.899612) (xy 355.549625 -277.933647) (xy 355.579141 -277.972926) (xy 355.601974 -278.01643)
			(xy 355.617533 -278.063034) (xy 355.625414 -278.11153) (xy 355.625908 -278.136096) (xy 364.409494 -278.136096)
			(xy 364.413448 -278.087123) (xy 364.425206 -278.039419) (xy 364.444464 -277.994218) (xy 364.470723 -277.952692)
			(xy 364.503304 -277.915916) (xy 364.541362 -277.884842) (xy 364.583912 -277.860276) (xy 364.629851 -277.842854)
			(xy 364.677991 -277.833026) (xy 364.727083 -277.831048) (xy 364.775857 -277.83697) (xy 364.823049 -277.850639)
			(xy 364.867438 -277.871702) (xy 364.907873 -277.899612) (xy 364.943307 -277.933647) (xy 364.972823 -277.972926)
			(xy 364.995656 -278.01643) (xy 365.011215 -278.063034) (xy 365.019096 -278.11153) (xy 365.01959 -278.136096)
			(xy 365.349548 -278.136096) (xy 365.353502 -278.087123) (xy 365.36526 -278.039419) (xy 365.384518 -277.994218)
			(xy 365.410777 -277.952692) (xy 365.443358 -277.915916) (xy 365.481416 -277.884842) (xy 365.523966 -277.860276)
			(xy 365.569905 -277.842854) (xy 365.618045 -277.833026) (xy 365.667137 -277.831048) (xy 365.715911 -277.83697)
			(xy 365.763103 -277.850639) (xy 365.807492 -277.871702) (xy 365.847927 -277.899612) (xy 365.883361 -277.933647)
			(xy 365.912877 -277.972926) (xy 365.93571 -278.01643) (xy 365.951269 -278.063034) (xy 365.95915 -278.11153)
			(xy 365.959644 -278.136096) (xy 367.229402 -278.136096) (xy 367.233356 -278.087123) (xy 367.245114 -278.039419)
			(xy 367.264372 -277.994218) (xy 367.290631 -277.952692) (xy 367.323212 -277.915916) (xy 367.36127 -277.884842)
			(xy 367.40382 -277.860276) (xy 367.449759 -277.842854) (xy 367.497899 -277.833026) (xy 367.546991 -277.831048)
			(xy 367.595765 -277.83697) (xy 367.642957 -277.850639) (xy 367.687346 -277.871702) (xy 367.727781 -277.899612)
			(xy 367.763215 -277.933647) (xy 367.792731 -277.972926) (xy 367.815564 -278.01643) (xy 367.831123 -278.063034)
			(xy 367.839004 -278.11153) (xy 367.839498 -278.136096) (xy 368.169456 -278.136096) (xy 368.17341 -278.087123)
			(xy 368.185168 -278.039419) (xy 368.204426 -277.994218) (xy 368.230685 -277.952692) (xy 368.263266 -277.915916)
			(xy 368.301324 -277.884842) (xy 368.343874 -277.860276) (xy 368.389813 -277.842854) (xy 368.437953 -277.833026)
			(xy 368.487045 -277.831048) (xy 368.535819 -277.83697) (xy 368.583011 -277.850639) (xy 368.6274 -277.871702)
			(xy 368.667835 -277.899612) (xy 368.703269 -277.933647) (xy 368.732785 -277.972926) (xy 368.755618 -278.01643)
			(xy 368.771177 -278.063034) (xy 368.779058 -278.11153) (xy 368.779552 -278.136096) (xy 370.04931 -278.136096)
			(xy 370.053264 -278.087123) (xy 370.065022 -278.039419) (xy 370.08428 -277.994218) (xy 370.110539 -277.952692)
			(xy 370.14312 -277.915916) (xy 370.181178 -277.884842) (xy 370.223728 -277.860276) (xy 370.269667 -277.842854)
			(xy 370.317807 -277.833026) (xy 370.366899 -277.831048) (xy 370.415673 -277.83697) (xy 370.462865 -277.850639)
			(xy 370.507254 -277.871702) (xy 370.547689 -277.899612) (xy 370.583123 -277.933647) (xy 370.612639 -277.972926)
			(xy 370.635472 -278.01643) (xy 370.651031 -278.063034) (xy 370.658912 -278.11153) (xy 370.659406 -278.136096)
			(xy 370.989364 -278.136096) (xy 370.993318 -278.087123) (xy 371.005076 -278.039419) (xy 371.024334 -277.994218)
			(xy 371.050593 -277.952692) (xy 371.083174 -277.915916) (xy 371.121232 -277.884842) (xy 371.163782 -277.860276)
			(xy 371.209721 -277.842854) (xy 371.257861 -277.833026) (xy 371.306953 -277.831048) (xy 371.355727 -277.83697)
			(xy 371.402919 -277.850639) (xy 371.447308 -277.871702) (xy 371.487743 -277.899612) (xy 371.523177 -277.933647)
			(xy 371.552693 -277.972926) (xy 371.575526 -278.01643) (xy 371.591085 -278.063034) (xy 371.598966 -278.11153)
			(xy 371.59946 -278.136096) (xy 372.869472 -278.136096) (xy 372.873426 -278.087123) (xy 372.885184 -278.039419)
			(xy 372.904442 -277.994218) (xy 372.930701 -277.952692) (xy 372.963282 -277.915916) (xy 373.00134 -277.884842)
			(xy 373.04389 -277.860276) (xy 373.089829 -277.842854) (xy 373.137969 -277.833026) (xy 373.187061 -277.831048)
			(xy 373.235835 -277.83697) (xy 373.283027 -277.850639) (xy 373.327416 -277.871702) (xy 373.367851 -277.899612)
			(xy 373.403285 -277.933647) (xy 373.432801 -277.972926) (xy 373.455634 -278.01643) (xy 373.471193 -278.063034)
			(xy 373.479074 -278.11153) (xy 373.479568 -278.136096) (xy 373.809526 -278.136096) (xy 373.81348 -278.087123)
			(xy 373.825238 -278.039419) (xy 373.844496 -277.994218) (xy 373.870755 -277.952692) (xy 373.903336 -277.915916)
			(xy 373.941394 -277.884842) (xy 373.983944 -277.860276) (xy 374.029883 -277.842854) (xy 374.078023 -277.833026)
			(xy 374.127115 -277.831048) (xy 374.175889 -277.83697) (xy 374.223081 -277.850639) (xy 374.26747 -277.871702)
			(xy 374.307905 -277.899612) (xy 374.343339 -277.933647) (xy 374.372855 -277.972926) (xy 374.395688 -278.01643)
			(xy 374.411247 -278.063034) (xy 374.419128 -278.11153) (xy 374.419622 -278.136096) (xy 374.419128 -278.160662)
			(xy 374.411247 -278.209158) (xy 374.395688 -278.255762) (xy 374.372855 -278.299266) (xy 374.343339 -278.338545)
			(xy 374.307905 -278.37258) (xy 374.26747 -278.40049) (xy 374.223081 -278.421553) (xy 374.175889 -278.435222)
			(xy 374.127115 -278.441144) (xy 374.078023 -278.439166) (xy 374.029883 -278.429338) (xy 373.983944 -278.411916)
			(xy 373.941394 -278.38735) (xy 373.903336 -278.356276) (xy 373.870755 -278.3195) (xy 373.844496 -278.277974)
			(xy 373.825238 -278.232773) (xy 373.81348 -278.185069) (xy 373.809526 -278.136096) (xy 373.479568 -278.136096)
			(xy 373.479074 -278.160662) (xy 373.471193 -278.209158) (xy 373.455634 -278.255762) (xy 373.432801 -278.299266)
			(xy 373.403285 -278.338545) (xy 373.367851 -278.37258) (xy 373.327416 -278.40049) (xy 373.283027 -278.421553)
			(xy 373.235835 -278.435222) (xy 373.187061 -278.441144) (xy 373.137969 -278.439166) (xy 373.089829 -278.429338)
			(xy 373.04389 -278.411916) (xy 373.00134 -278.38735) (xy 372.963282 -278.356276) (xy 372.930701 -278.3195)
			(xy 372.904442 -278.277974) (xy 372.885184 -278.232773) (xy 372.873426 -278.185069) (xy 372.869472 -278.136096)
			(xy 371.59946 -278.136096) (xy 371.598966 -278.160662) (xy 371.591085 -278.209158) (xy 371.575526 -278.255762)
			(xy 371.552693 -278.299266) (xy 371.523177 -278.338545) (xy 371.487743 -278.37258) (xy 371.447308 -278.40049)
			(xy 371.402919 -278.421553) (xy 371.355727 -278.435222) (xy 371.306953 -278.441144) (xy 371.257861 -278.439166)
			(xy 371.209721 -278.429338) (xy 371.163782 -278.411916) (xy 371.121232 -278.38735) (xy 371.083174 -278.356276)
			(xy 371.050593 -278.3195) (xy 371.024334 -278.277974) (xy 371.005076 -278.232773) (xy 370.993318 -278.185069)
			(xy 370.989364 -278.136096) (xy 370.659406 -278.136096) (xy 370.658912 -278.160662) (xy 370.651031 -278.209158)
			(xy 370.635472 -278.255762) (xy 370.612639 -278.299266) (xy 370.583123 -278.338545) (xy 370.547689 -278.37258)
			(xy 370.507254 -278.40049) (xy 370.462865 -278.421553) (xy 370.415673 -278.435222) (xy 370.366899 -278.441144)
			(xy 370.317807 -278.439166) (xy 370.269667 -278.429338) (xy 370.223728 -278.411916) (xy 370.181178 -278.38735)
			(xy 370.14312 -278.356276) (xy 370.110539 -278.3195) (xy 370.08428 -278.277974) (xy 370.065022 -278.232773)
			(xy 370.053264 -278.185069) (xy 370.04931 -278.136096) (xy 368.779552 -278.136096) (xy 368.779058 -278.160662)
			(xy 368.771177 -278.209158) (xy 368.755618 -278.255762) (xy 368.732785 -278.299266) (xy 368.703269 -278.338545)
			(xy 368.667835 -278.37258) (xy 368.6274 -278.40049) (xy 368.583011 -278.421553) (xy 368.535819 -278.435222)
			(xy 368.487045 -278.441144) (xy 368.437953 -278.439166) (xy 368.389813 -278.429338) (xy 368.343874 -278.411916)
			(xy 368.301324 -278.38735) (xy 368.263266 -278.356276) (xy 368.230685 -278.3195) (xy 368.204426 -278.277974)
			(xy 368.185168 -278.232773) (xy 368.17341 -278.185069) (xy 368.169456 -278.136096) (xy 367.839498 -278.136096)
			(xy 367.839004 -278.160662) (xy 367.831123 -278.209158) (xy 367.815564 -278.255762) (xy 367.792731 -278.299266)
			(xy 367.763215 -278.338545) (xy 367.727781 -278.37258) (xy 367.687346 -278.40049) (xy 367.642957 -278.421553)
			(xy 367.595765 -278.435222) (xy 367.546991 -278.441144) (xy 367.497899 -278.439166) (xy 367.449759 -278.429338)
			(xy 367.40382 -278.411916) (xy 367.36127 -278.38735) (xy 367.323212 -278.356276) (xy 367.290631 -278.3195)
			(xy 367.264372 -278.277974) (xy 367.245114 -278.232773) (xy 367.233356 -278.185069) (xy 367.229402 -278.136096)
			(xy 365.959644 -278.136096) (xy 365.95915 -278.160662) (xy 365.951269 -278.209158) (xy 365.93571 -278.255762)
			(xy 365.912877 -278.299266) (xy 365.883361 -278.338545) (xy 365.847927 -278.37258) (xy 365.807492 -278.40049)
			(xy 365.763103 -278.421553) (xy 365.715911 -278.435222) (xy 365.667137 -278.441144) (xy 365.618045 -278.439166)
			(xy 365.569905 -278.429338) (xy 365.523966 -278.411916) (xy 365.481416 -278.38735) (xy 365.443358 -278.356276)
			(xy 365.410777 -278.3195) (xy 365.384518 -278.277974) (xy 365.36526 -278.232773) (xy 365.353502 -278.185069)
			(xy 365.349548 -278.136096) (xy 365.01959 -278.136096) (xy 365.019096 -278.160662) (xy 365.011215 -278.209158)
			(xy 364.995656 -278.255762) (xy 364.972823 -278.299266) (xy 364.943307 -278.338545) (xy 364.907873 -278.37258)
			(xy 364.867438 -278.40049) (xy 364.823049 -278.421553) (xy 364.775857 -278.435222) (xy 364.727083 -278.441144)
			(xy 364.677991 -278.439166) (xy 364.629851 -278.429338) (xy 364.583912 -278.411916) (xy 364.541362 -278.38735)
			(xy 364.503304 -278.356276) (xy 364.470723 -278.3195) (xy 364.444464 -278.277974) (xy 364.425206 -278.232773)
			(xy 364.413448 -278.185069) (xy 364.409494 -278.136096) (xy 355.625908 -278.136096) (xy 355.625414 -278.160662)
			(xy 355.617533 -278.209158) (xy 355.601974 -278.255762) (xy 355.579141 -278.299266) (xy 355.549625 -278.338545)
			(xy 355.514191 -278.37258) (xy 355.473756 -278.40049) (xy 355.429367 -278.421553) (xy 355.382175 -278.435222)
			(xy 355.333401 -278.441144) (xy 355.284309 -278.439166) (xy 355.236169 -278.429338) (xy 355.19023 -278.411916)
			(xy 355.14768 -278.38735) (xy 355.109622 -278.356276) (xy 355.077041 -278.3195) (xy 355.050782 -278.277974)
			(xy 355.031524 -278.232773) (xy 355.019766 -278.185069) (xy 355.015812 -278.136096) (xy 354.685854 -278.136096)
			(xy 354.68536 -278.160662) (xy 354.677479 -278.209158) (xy 354.66192 -278.255762) (xy 354.639087 -278.299266)
			(xy 354.609571 -278.338545) (xy 354.574137 -278.37258) (xy 354.533702 -278.40049) (xy 354.489313 -278.421553)
			(xy 354.442121 -278.435222) (xy 354.393347 -278.441144) (xy 354.344255 -278.439166) (xy 354.296115 -278.429338)
			(xy 354.250176 -278.411916) (xy 354.207626 -278.38735) (xy 354.169568 -278.356276) (xy 354.136987 -278.3195)
			(xy 354.110728 -278.277974) (xy 354.09147 -278.232773) (xy 354.079712 -278.185069) (xy 354.075758 -278.136096)
			(xy 352.806 -278.136096) (xy 352.805506 -278.160662) (xy 352.797625 -278.209158) (xy 352.782066 -278.255762)
			(xy 352.759233 -278.299266) (xy 352.729717 -278.338545) (xy 352.694283 -278.37258) (xy 352.653848 -278.40049)
			(xy 352.609459 -278.421553) (xy 352.562267 -278.435222) (xy 352.513493 -278.441144) (xy 352.464401 -278.439166)
			(xy 352.416261 -278.429338) (xy 352.370322 -278.411916) (xy 352.327772 -278.38735) (xy 352.289714 -278.356276)
			(xy 352.257133 -278.3195) (xy 352.230874 -278.277974) (xy 352.211616 -278.232773) (xy 352.199858 -278.185069)
			(xy 352.195904 -278.136096) (xy 351.865946 -278.136096) (xy 351.865452 -278.160662) (xy 351.857571 -278.209158)
			(xy 351.842012 -278.255762) (xy 351.819179 -278.299266) (xy 351.789663 -278.338545) (xy 351.754229 -278.37258)
			(xy 351.713794 -278.40049) (xy 351.669405 -278.421553) (xy 351.622213 -278.435222) (xy 351.573439 -278.441144)
			(xy 351.524347 -278.439166) (xy 351.476207 -278.429338) (xy 351.430268 -278.411916) (xy 351.387718 -278.38735)
			(xy 351.34966 -278.356276) (xy 351.317079 -278.3195) (xy 351.29082 -278.277974) (xy 351.271562 -278.232773)
			(xy 351.259804 -278.185069) (xy 351.25585 -278.136096) (xy 349.985838 -278.136096) (xy 349.985344 -278.160662)
			(xy 349.977463 -278.209158) (xy 349.961904 -278.255762) (xy 349.939071 -278.299266) (xy 349.909555 -278.338545)
			(xy 349.874121 -278.37258) (xy 349.833686 -278.40049) (xy 349.789297 -278.421553) (xy 349.742105 -278.435222)
			(xy 349.693331 -278.441144) (xy 349.644239 -278.439166) (xy 349.596099 -278.429338) (xy 349.55016 -278.411916)
			(xy 349.50761 -278.38735) (xy 349.469552 -278.356276) (xy 349.436971 -278.3195) (xy 349.410712 -278.277974)
			(xy 349.391454 -278.232773) (xy 349.379696 -278.185069) (xy 349.375742 -278.136096) (xy 349.045784 -278.136096)
			(xy 349.04529 -278.160662) (xy 349.037409 -278.209158) (xy 349.02185 -278.255762) (xy 348.999017 -278.299266)
			(xy 348.969501 -278.338545) (xy 348.934067 -278.37258) (xy 348.893632 -278.40049) (xy 348.849243 -278.421553)
			(xy 348.802051 -278.435222) (xy 348.753277 -278.441144) (xy 348.704185 -278.439166) (xy 348.656045 -278.429338)
			(xy 348.610106 -278.411916) (xy 348.567556 -278.38735) (xy 348.529498 -278.356276) (xy 348.496917 -278.3195)
			(xy 348.470658 -278.277974) (xy 348.4514 -278.232773) (xy 348.439642 -278.185069) (xy 348.435688 -278.136096)
			(xy 347.16593 -278.136096) (xy 347.165436 -278.160662) (xy 347.157555 -278.209158) (xy 347.141996 -278.255762)
			(xy 347.119163 -278.299266) (xy 347.089647 -278.338545) (xy 347.054213 -278.37258) (xy 347.013778 -278.40049)
			(xy 346.969389 -278.421553) (xy 346.922197 -278.435222) (xy 346.873423 -278.441144) (xy 346.824331 -278.439166)
			(xy 346.776191 -278.429338) (xy 346.730252 -278.411916) (xy 346.687702 -278.38735) (xy 346.649644 -278.356276)
			(xy 346.617063 -278.3195) (xy 346.590804 -278.277974) (xy 346.571546 -278.232773) (xy 346.559788 -278.185069)
			(xy 346.555834 -278.136096) (xy 346.225876 -278.136096) (xy 346.225382 -278.160662) (xy 346.217501 -278.209158)
			(xy 346.201942 -278.255762) (xy 346.179109 -278.299266) (xy 346.149593 -278.338545) (xy 346.114159 -278.37258)
			(xy 346.073724 -278.40049) (xy 346.029335 -278.421553) (xy 345.982143 -278.435222) (xy 345.933369 -278.441144)
			(xy 345.884277 -278.439166) (xy 345.836137 -278.429338) (xy 345.790198 -278.411916) (xy 345.747648 -278.38735)
			(xy 345.70959 -278.356276) (xy 345.677009 -278.3195) (xy 345.65075 -278.277974) (xy 345.631492 -278.232773)
			(xy 345.619734 -278.185069) (xy 345.61578 -278.136096) (xy 126.479549 -278.136096) (xy 126.479554 -278.13635)
			(xy 126.47906 -278.160916) (xy 126.471179 -278.209412) (xy 126.45562 -278.256016) (xy 126.432787 -278.29952)
			(xy 126.403271 -278.338799) (xy 126.367837 -278.372834) (xy 126.327402 -278.400744) (xy 126.283013 -278.421807)
			(xy 126.235821 -278.435476) (xy 126.187047 -278.441398) (xy 126.137955 -278.43942) (xy 126.089815 -278.429592)
			(xy 126.043876 -278.41217) (xy 126.001326 -278.387604) (xy 125.963268 -278.35653) (xy 125.930687 -278.319754)
			(xy 125.904428 -278.278228) (xy 125.88517 -278.233027) (xy 125.873412 -278.185323) (xy 125.869458 -278.13635)
			(xy 125.5395 -278.13635) (xy 125.539006 -278.160916) (xy 125.531125 -278.209412) (xy 125.515566 -278.256016)
			(xy 125.492733 -278.29952) (xy 125.463217 -278.338799) (xy 125.427783 -278.372834) (xy 125.387348 -278.400744)
			(xy 125.342959 -278.421807) (xy 125.295767 -278.435476) (xy 125.246993 -278.441398) (xy 125.197901 -278.43942)
			(xy 125.149761 -278.429592) (xy 125.103822 -278.41217) (xy 125.061272 -278.387604) (xy 125.023214 -278.35653)
			(xy 124.990633 -278.319754) (xy 124.964374 -278.278228) (xy 124.945116 -278.233027) (xy 124.933358 -278.185323)
			(xy 124.929404 -278.13635) (xy 123.659392 -278.13635) (xy 123.658898 -278.160916) (xy 123.651017 -278.209412)
			(xy 123.635458 -278.256016) (xy 123.612625 -278.29952) (xy 123.583109 -278.338799) (xy 123.547675 -278.372834)
			(xy 123.50724 -278.400744) (xy 123.462851 -278.421807) (xy 123.415659 -278.435476) (xy 123.366885 -278.441398)
			(xy 123.317793 -278.43942) (xy 123.269653 -278.429592) (xy 123.223714 -278.41217) (xy 123.181164 -278.387604)
			(xy 123.143106 -278.35653) (xy 123.110525 -278.319754) (xy 123.084266 -278.278228) (xy 123.065008 -278.233027)
			(xy 123.05325 -278.185323) (xy 123.049296 -278.13635) (xy 122.719338 -278.13635) (xy 122.718844 -278.160916)
			(xy 122.710963 -278.209412) (xy 122.695404 -278.256016) (xy 122.672571 -278.29952) (xy 122.643055 -278.338799)
			(xy 122.607621 -278.372834) (xy 122.567186 -278.400744) (xy 122.522797 -278.421807) (xy 122.475605 -278.435476)
			(xy 122.426831 -278.441398) (xy 122.377739 -278.43942) (xy 122.329599 -278.429592) (xy 122.28366 -278.41217)
			(xy 122.24111 -278.387604) (xy 122.203052 -278.35653) (xy 122.170471 -278.319754) (xy 122.144212 -278.278228)
			(xy 122.124954 -278.233027) (xy 122.113196 -278.185323) (xy 122.109242 -278.13635) (xy 120.839484 -278.13635)
			(xy 120.83899 -278.160916) (xy 120.831109 -278.209412) (xy 120.81555 -278.256016) (xy 120.792717 -278.29952)
			(xy 120.763201 -278.338799) (xy 120.727767 -278.372834) (xy 120.687332 -278.400744) (xy 120.642943 -278.421807)
			(xy 120.595751 -278.435476) (xy 120.546977 -278.441398) (xy 120.497885 -278.43942) (xy 120.449745 -278.429592)
			(xy 120.403806 -278.41217) (xy 120.361256 -278.387604) (xy 120.323198 -278.35653) (xy 120.290617 -278.319754)
			(xy 120.264358 -278.278228) (xy 120.2451 -278.233027) (xy 120.233342 -278.185323) (xy 120.229388 -278.13635)
			(xy 119.89943 -278.13635) (xy 119.898936 -278.160916) (xy 119.891055 -278.209412) (xy 119.875496 -278.256016)
			(xy 119.852663 -278.29952) (xy 119.823147 -278.338799) (xy 119.787713 -278.372834) (xy 119.747278 -278.400744)
			(xy 119.702889 -278.421807) (xy 119.655697 -278.435476) (xy 119.606923 -278.441398) (xy 119.557831 -278.43942)
			(xy 119.509691 -278.429592) (xy 119.463752 -278.41217) (xy 119.421202 -278.387604) (xy 119.383144 -278.35653)
			(xy 119.350563 -278.319754) (xy 119.324304 -278.278228) (xy 119.305046 -278.233027) (xy 119.293288 -278.185323)
			(xy 119.289334 -278.13635) (xy 118.019576 -278.13635) (xy 118.019082 -278.160916) (xy 118.011201 -278.209412)
			(xy 117.995642 -278.256016) (xy 117.972809 -278.29952) (xy 117.943293 -278.338799) (xy 117.907859 -278.372834)
			(xy 117.867424 -278.400744) (xy 117.823035 -278.421807) (xy 117.775843 -278.435476) (xy 117.727069 -278.441398)
			(xy 117.677977 -278.43942) (xy 117.629837 -278.429592) (xy 117.583898 -278.41217) (xy 117.541348 -278.387604)
			(xy 117.50329 -278.35653) (xy 117.470709 -278.319754) (xy 117.44445 -278.278228) (xy 117.425192 -278.233027)
			(xy 117.413434 -278.185323) (xy 117.40948 -278.13635) (xy 117.079522 -278.13635) (xy 117.079028 -278.160916)
			(xy 117.071147 -278.209412) (xy 117.055588 -278.256016) (xy 117.032755 -278.29952) (xy 117.003239 -278.338799)
			(xy 116.967805 -278.372834) (xy 116.92737 -278.400744) (xy 116.882981 -278.421807) (xy 116.835789 -278.435476)
			(xy 116.787015 -278.441398) (xy 116.737923 -278.43942) (xy 116.689783 -278.429592) (xy 116.643844 -278.41217)
			(xy 116.601294 -278.387604) (xy 116.563236 -278.35653) (xy 116.530655 -278.319754) (xy 116.504396 -278.278228)
			(xy 116.485138 -278.233027) (xy 116.47338 -278.185323) (xy 116.469426 -278.13635) (xy 107.68584 -278.13635)
			(xy 107.685346 -278.160916) (xy 107.677465 -278.209412) (xy 107.661906 -278.256016) (xy 107.639073 -278.29952)
			(xy 107.609557 -278.338799) (xy 107.574123 -278.372834) (xy 107.533688 -278.400744) (xy 107.489299 -278.421807)
			(xy 107.442107 -278.435476) (xy 107.393333 -278.441398) (xy 107.344241 -278.43942) (xy 107.296101 -278.429592)
			(xy 107.250162 -278.41217) (xy 107.207612 -278.387604) (xy 107.169554 -278.35653) (xy 107.136973 -278.319754)
			(xy 107.110714 -278.278228) (xy 107.091456 -278.233027) (xy 107.079698 -278.185323) (xy 107.075744 -278.13635)
			(xy 106.745786 -278.13635) (xy 106.745292 -278.160916) (xy 106.737411 -278.209412) (xy 106.721852 -278.256016)
			(xy 106.699019 -278.29952) (xy 106.669503 -278.338799) (xy 106.634069 -278.372834) (xy 106.593634 -278.400744)
			(xy 106.549245 -278.421807) (xy 106.502053 -278.435476) (xy 106.453279 -278.441398) (xy 106.404187 -278.43942)
			(xy 106.356047 -278.429592) (xy 106.310108 -278.41217) (xy 106.267558 -278.387604) (xy 106.2295 -278.35653)
			(xy 106.196919 -278.319754) (xy 106.17066 -278.278228) (xy 106.151402 -278.233027) (xy 106.139644 -278.185323)
			(xy 106.13569 -278.13635) (xy 104.865932 -278.13635) (xy 104.865438 -278.160916) (xy 104.857557 -278.209412)
			(xy 104.841998 -278.256016) (xy 104.819165 -278.29952) (xy 104.789649 -278.338799) (xy 104.754215 -278.372834)
			(xy 104.71378 -278.400744) (xy 104.669391 -278.421807) (xy 104.622199 -278.435476) (xy 104.573425 -278.441398)
			(xy 104.524333 -278.43942) (xy 104.476193 -278.429592) (xy 104.430254 -278.41217) (xy 104.387704 -278.387604)
			(xy 104.349646 -278.35653) (xy 104.317065 -278.319754) (xy 104.290806 -278.278228) (xy 104.271548 -278.233027)
			(xy 104.25979 -278.185323) (xy 104.255836 -278.13635) (xy 103.925878 -278.13635) (xy 103.925384 -278.160916)
			(xy 103.917503 -278.209412) (xy 103.901944 -278.256016) (xy 103.879111 -278.29952) (xy 103.849595 -278.338799)
			(xy 103.814161 -278.372834) (xy 103.773726 -278.400744) (xy 103.729337 -278.421807) (xy 103.682145 -278.435476)
			(xy 103.633371 -278.441398) (xy 103.584279 -278.43942) (xy 103.536139 -278.429592) (xy 103.4902 -278.41217)
			(xy 103.44765 -278.387604) (xy 103.409592 -278.35653) (xy 103.377011 -278.319754) (xy 103.350752 -278.278228)
			(xy 103.331494 -278.233027) (xy 103.319736 -278.185323) (xy 103.315782 -278.13635) (xy 102.04577 -278.13635)
			(xy 102.045276 -278.160916) (xy 102.037395 -278.209412) (xy 102.021836 -278.256016) (xy 101.999003 -278.29952)
			(xy 101.969487 -278.338799) (xy 101.934053 -278.372834) (xy 101.893618 -278.400744) (xy 101.849229 -278.421807)
			(xy 101.802037 -278.435476) (xy 101.753263 -278.441398) (xy 101.704171 -278.43942) (xy 101.656031 -278.429592)
			(xy 101.610092 -278.41217) (xy 101.567542 -278.387604) (xy 101.529484 -278.35653) (xy 101.496903 -278.319754)
			(xy 101.470644 -278.278228) (xy 101.451386 -278.233027) (xy 101.439628 -278.185323) (xy 101.435674 -278.13635)
			(xy 101.105716 -278.13635) (xy 101.105222 -278.160916) (xy 101.097341 -278.209412) (xy 101.081782 -278.256016)
			(xy 101.058949 -278.29952) (xy 101.029433 -278.338799) (xy 100.993999 -278.372834) (xy 100.953564 -278.400744)
			(xy 100.909175 -278.421807) (xy 100.861983 -278.435476) (xy 100.813209 -278.441398) (xy 100.764117 -278.43942)
			(xy 100.715977 -278.429592) (xy 100.670038 -278.41217) (xy 100.627488 -278.387604) (xy 100.58943 -278.35653)
			(xy 100.556849 -278.319754) (xy 100.53059 -278.278228) (xy 100.511332 -278.233027) (xy 100.499574 -278.185323)
			(xy 100.49562 -278.13635) (xy 99.225862 -278.13635) (xy 99.225368 -278.160916) (xy 99.217487 -278.209412)
			(xy 99.201928 -278.256016) (xy 99.179095 -278.29952) (xy 99.149579 -278.338799) (xy 99.114145 -278.372834)
			(xy 99.07371 -278.400744) (xy 99.029321 -278.421807) (xy 98.982129 -278.435476) (xy 98.933355 -278.441398)
			(xy 98.884263 -278.43942) (xy 98.836123 -278.429592) (xy 98.790184 -278.41217) (xy 98.747634 -278.387604)
			(xy 98.709576 -278.35653) (xy 98.676995 -278.319754) (xy 98.650736 -278.278228) (xy 98.631478 -278.233027)
			(xy 98.61972 -278.185323) (xy 98.615766 -278.13635) (xy 98.285808 -278.13635) (xy 98.285314 -278.160916)
			(xy 98.277433 -278.209412) (xy 98.261874 -278.256016) (xy 98.239041 -278.29952) (xy 98.209525 -278.338799)
			(xy 98.174091 -278.372834) (xy 98.133656 -278.400744) (xy 98.089267 -278.421807) (xy 98.042075 -278.435476)
			(xy 97.993301 -278.441398) (xy 97.944209 -278.43942) (xy 97.896069 -278.429592) (xy 97.85013 -278.41217)
			(xy 97.80758 -278.387604) (xy 97.769522 -278.35653) (xy 97.736941 -278.319754) (xy 97.710682 -278.278228)
			(xy 97.691424 -278.233027) (xy 97.679666 -278.185323) (xy 97.675712 -278.13635) (xy 2.509012 -278.13635)
			(xy 2.509012 -278.946356) (xy 108.485698 -278.946356) (xy 108.489652 -278.897383) (xy 108.50141 -278.849679)
			(xy 108.520668 -278.804478) (xy 108.546927 -278.762952) (xy 108.579508 -278.726176) (xy 108.617566 -278.695102)
			(xy 108.660116 -278.670536) (xy 108.706055 -278.653114) (xy 108.754195 -278.643286) (xy 108.803287 -278.641308)
			(xy 108.852061 -278.64723) (xy 108.899253 -278.660899) (xy 108.943642 -278.681962) (xy 108.984077 -278.709872)
			(xy 109.019511 -278.743907) (xy 109.049027 -278.783186) (xy 109.07186 -278.82669) (xy 109.087419 -278.873294)
			(xy 109.0953 -278.92179) (xy 109.095794 -278.946356) (xy 109.425752 -278.946356) (xy 109.429706 -278.897383)
			(xy 109.441464 -278.849679) (xy 109.460722 -278.804478) (xy 109.486981 -278.762952) (xy 109.519562 -278.726176)
			(xy 109.55762 -278.695102) (xy 109.60017 -278.670536) (xy 109.646109 -278.653114) (xy 109.694249 -278.643286)
			(xy 109.743341 -278.641308) (xy 109.792115 -278.64723) (xy 109.839307 -278.660899) (xy 109.883696 -278.681962)
			(xy 109.924131 -278.709872) (xy 109.959565 -278.743907) (xy 109.989081 -278.783186) (xy 110.011914 -278.82669)
			(xy 110.027473 -278.873294) (xy 110.035354 -278.92179) (xy 110.035848 -278.946356) (xy 114.119418 -278.946356)
			(xy 114.123372 -278.897383) (xy 114.13513 -278.849679) (xy 114.154388 -278.804478) (xy 114.180647 -278.762952)
			(xy 114.213228 -278.726176) (xy 114.251286 -278.695102) (xy 114.293836 -278.670536) (xy 114.339775 -278.653114)
			(xy 114.387915 -278.643286) (xy 114.437007 -278.641308) (xy 114.485781 -278.64723) (xy 114.532973 -278.660899)
			(xy 114.577362 -278.681962) (xy 114.617797 -278.709872) (xy 114.653231 -278.743907) (xy 114.682747 -278.783186)
			(xy 114.70558 -278.82669) (xy 114.721139 -278.873294) (xy 114.72902 -278.92179) (xy 114.729514 -278.946356)
			(xy 115.059472 -278.946356) (xy 115.063426 -278.897383) (xy 115.075184 -278.849679) (xy 115.094442 -278.804478)
			(xy 115.120701 -278.762952) (xy 115.153282 -278.726176) (xy 115.19134 -278.695102) (xy 115.23389 -278.670536)
			(xy 115.279829 -278.653114) (xy 115.327969 -278.643286) (xy 115.377061 -278.641308) (xy 115.425835 -278.64723)
			(xy 115.473027 -278.660899) (xy 115.517416 -278.681962) (xy 115.557851 -278.709872) (xy 115.593285 -278.743907)
			(xy 115.622801 -278.783186) (xy 115.645634 -278.82669) (xy 115.661193 -278.873294) (xy 115.669074 -278.92179)
			(xy 115.669563 -278.946102) (xy 356.425766 -278.946102) (xy 356.42972 -278.897129) (xy 356.441478 -278.849425)
			(xy 356.460736 -278.804224) (xy 356.486995 -278.762698) (xy 356.519576 -278.725922) (xy 356.557634 -278.694848)
			(xy 356.600184 -278.670282) (xy 356.646123 -278.65286) (xy 356.694263 -278.643032) (xy 356.743355 -278.641054)
			(xy 356.792129 -278.646976) (xy 356.839321 -278.660645) (xy 356.88371 -278.681708) (xy 356.924145 -278.709618)
			(xy 356.959579 -278.743653) (xy 356.989095 -278.782932) (xy 357.011928 -278.826436) (xy 357.027487 -278.87304)
			(xy 357.035368 -278.921536) (xy 357.035862 -278.946102) (xy 357.36582 -278.946102) (xy 357.369774 -278.897129)
			(xy 357.381532 -278.849425) (xy 357.40079 -278.804224) (xy 357.427049 -278.762698) (xy 357.45963 -278.725922)
			(xy 357.497688 -278.694848) (xy 357.540238 -278.670282) (xy 357.586177 -278.65286) (xy 357.634317 -278.643032)
			(xy 357.683409 -278.641054) (xy 357.732183 -278.646976) (xy 357.779375 -278.660645) (xy 357.823764 -278.681708)
			(xy 357.864199 -278.709618) (xy 357.899633 -278.743653) (xy 357.929149 -278.782932) (xy 357.951982 -278.826436)
			(xy 357.967541 -278.87304) (xy 357.975422 -278.921536) (xy 357.975916 -278.946102) (xy 362.059486 -278.946102)
			(xy 362.06344 -278.897129) (xy 362.075198 -278.849425) (xy 362.094456 -278.804224) (xy 362.120715 -278.762698)
			(xy 362.153296 -278.725922) (xy 362.191354 -278.694848) (xy 362.233904 -278.670282) (xy 362.279843 -278.65286)
			(xy 362.327983 -278.643032) (xy 362.377075 -278.641054) (xy 362.425849 -278.646976) (xy 362.473041 -278.660645)
			(xy 362.51743 -278.681708) (xy 362.557865 -278.709618) (xy 362.593299 -278.743653) (xy 362.622815 -278.782932)
			(xy 362.645648 -278.826436) (xy 362.661207 -278.87304) (xy 362.669088 -278.921536) (xy 362.669582 -278.946102)
			(xy 362.99954 -278.946102) (xy 363.003494 -278.897129) (xy 363.015252 -278.849425) (xy 363.03451 -278.804224)
			(xy 363.060769 -278.762698) (xy 363.09335 -278.725922) (xy 363.131408 -278.694848) (xy 363.173958 -278.670282)
			(xy 363.219897 -278.65286) (xy 363.268037 -278.643032) (xy 363.317129 -278.641054) (xy 363.365903 -278.646976)
			(xy 363.413095 -278.660645) (xy 363.457484 -278.681708) (xy 363.497919 -278.709618) (xy 363.533353 -278.743653)
			(xy 363.562869 -278.782932) (xy 363.585702 -278.826436) (xy 363.601261 -278.87304) (xy 363.609142 -278.921536)
			(xy 363.609636 -278.946102) (xy 363.609142 -278.970668) (xy 363.601261 -279.019164) (xy 363.585702 -279.065768)
			(xy 363.562869 -279.109272) (xy 363.533353 -279.148551) (xy 363.497919 -279.182586) (xy 363.457484 -279.210496)
			(xy 363.413095 -279.231559) (xy 363.365903 -279.245228) (xy 363.317129 -279.25115) (xy 363.268037 -279.249172)
			(xy 363.219897 -279.239344) (xy 363.173958 -279.221922) (xy 363.131408 -279.197356) (xy 363.09335 -279.166282)
			(xy 363.060769 -279.129506) (xy 363.03451 -279.08798) (xy 363.015252 -279.042779) (xy 363.003494 -278.995075)
			(xy 362.99954 -278.946102) (xy 362.669582 -278.946102) (xy 362.669088 -278.970668) (xy 362.661207 -279.019164)
			(xy 362.645648 -279.065768) (xy 362.622815 -279.109272) (xy 362.593299 -279.148551) (xy 362.557865 -279.182586)
			(xy 362.51743 -279.210496) (xy 362.473041 -279.231559) (xy 362.425849 -279.245228) (xy 362.377075 -279.25115)
			(xy 362.327983 -279.249172) (xy 362.279843 -279.239344) (xy 362.233904 -279.221922) (xy 362.191354 -279.197356)
			(xy 362.153296 -279.166282) (xy 362.120715 -279.129506) (xy 362.094456 -279.08798) (xy 362.075198 -279.042779)
			(xy 362.06344 -278.995075) (xy 362.059486 -278.946102) (xy 357.975916 -278.946102) (xy 357.975422 -278.970668)
			(xy 357.967541 -279.019164) (xy 357.951982 -279.065768) (xy 357.929149 -279.109272) (xy 357.899633 -279.148551)
			(xy 357.864199 -279.182586) (xy 357.823764 -279.210496) (xy 357.779375 -279.231559) (xy 357.732183 -279.245228)
			(xy 357.683409 -279.25115) (xy 357.634317 -279.249172) (xy 357.586177 -279.239344) (xy 357.540238 -279.221922)
			(xy 357.497688 -279.197356) (xy 357.45963 -279.166282) (xy 357.427049 -279.129506) (xy 357.40079 -279.08798)
			(xy 357.381532 -279.042779) (xy 357.369774 -278.995075) (xy 357.36582 -278.946102) (xy 357.035862 -278.946102)
			(xy 357.035368 -278.970668) (xy 357.027487 -279.019164) (xy 357.011928 -279.065768) (xy 356.989095 -279.109272)
			(xy 356.959579 -279.148551) (xy 356.924145 -279.182586) (xy 356.88371 -279.210496) (xy 356.839321 -279.231559)
			(xy 356.792129 -279.245228) (xy 356.743355 -279.25115) (xy 356.694263 -279.249172) (xy 356.646123 -279.239344)
			(xy 356.600184 -279.221922) (xy 356.557634 -279.197356) (xy 356.519576 -279.166282) (xy 356.486995 -279.129506)
			(xy 356.460736 -279.08798) (xy 356.441478 -279.042779) (xy 356.42972 -278.995075) (xy 356.425766 -278.946102)
			(xy 115.669563 -278.946102) (xy 115.669568 -278.946356) (xy 115.669074 -278.970922) (xy 115.661193 -279.019418)
			(xy 115.645634 -279.066022) (xy 115.622801 -279.109526) (xy 115.593285 -279.148805) (xy 115.557851 -279.18284)
			(xy 115.517416 -279.21075) (xy 115.473027 -279.231813) (xy 115.425835 -279.245482) (xy 115.377061 -279.251404)
			(xy 115.327969 -279.249426) (xy 115.279829 -279.239598) (xy 115.23389 -279.222176) (xy 115.19134 -279.19761)
			(xy 115.153282 -279.166536) (xy 115.120701 -279.12976) (xy 115.094442 -279.088234) (xy 115.075184 -279.043033)
			(xy 115.063426 -278.995329) (xy 115.059472 -278.946356) (xy 114.729514 -278.946356) (xy 114.72902 -278.970922)
			(xy 114.721139 -279.019418) (xy 114.70558 -279.066022) (xy 114.682747 -279.109526) (xy 114.653231 -279.148805)
			(xy 114.617797 -279.18284) (xy 114.577362 -279.21075) (xy 114.532973 -279.231813) (xy 114.485781 -279.245482)
			(xy 114.437007 -279.251404) (xy 114.387915 -279.249426) (xy 114.339775 -279.239598) (xy 114.293836 -279.222176)
			(xy 114.251286 -279.19761) (xy 114.213228 -279.166536) (xy 114.180647 -279.12976) (xy 114.154388 -279.088234)
			(xy 114.13513 -279.043033) (xy 114.123372 -278.995329) (xy 114.119418 -278.946356) (xy 110.035848 -278.946356)
			(xy 110.035354 -278.970922) (xy 110.027473 -279.019418) (xy 110.011914 -279.066022) (xy 109.989081 -279.109526)
			(xy 109.959565 -279.148805) (xy 109.924131 -279.18284) (xy 109.883696 -279.21075) (xy 109.839307 -279.231813)
			(xy 109.792115 -279.245482) (xy 109.743341 -279.251404) (xy 109.694249 -279.249426) (xy 109.646109 -279.239598)
			(xy 109.60017 -279.222176) (xy 109.55762 -279.19761) (xy 109.519562 -279.166536) (xy 109.486981 -279.12976)
			(xy 109.460722 -279.088234) (xy 109.441464 -279.043033) (xy 109.429706 -278.995329) (xy 109.425752 -278.946356)
			(xy 109.095794 -278.946356) (xy 109.0953 -278.970922) (xy 109.087419 -279.019418) (xy 109.07186 -279.066022)
			(xy 109.049027 -279.109526) (xy 109.019511 -279.148805) (xy 108.984077 -279.18284) (xy 108.943642 -279.21075)
			(xy 108.899253 -279.231813) (xy 108.852061 -279.245482) (xy 108.803287 -279.251404) (xy 108.754195 -279.249426)
			(xy 108.706055 -279.239598) (xy 108.660116 -279.222176) (xy 108.617566 -279.19761) (xy 108.579508 -279.166536)
			(xy 108.546927 -279.12976) (xy 108.520668 -279.088234) (xy 108.50141 -279.043033) (xy 108.489652 -278.995329)
			(xy 108.485698 -278.946356) (xy 2.509012 -278.946356) (xy 2.509012 -279.756362) (xy 106.13569 -279.756362)
			(xy 106.139644 -279.707389) (xy 106.151402 -279.659685) (xy 106.17066 -279.614484) (xy 106.196919 -279.572958)
			(xy 106.2295 -279.536182) (xy 106.267558 -279.505108) (xy 106.310108 -279.480542) (xy 106.356047 -279.46312)
			(xy 106.404187 -279.453292) (xy 106.453279 -279.451314) (xy 106.502053 -279.457236) (xy 106.549245 -279.470905)
			(xy 106.593634 -279.491968) (xy 106.634069 -279.519878) (xy 106.669503 -279.553913) (xy 106.699019 -279.593192)
			(xy 106.721852 -279.636696) (xy 106.737411 -279.6833) (xy 106.745292 -279.731796) (xy 106.745786 -279.756362)
			(xy 107.075744 -279.756362) (xy 107.079698 -279.707389) (xy 107.091456 -279.659685) (xy 107.110714 -279.614484)
			(xy 107.136973 -279.572958) (xy 107.169554 -279.536182) (xy 107.207612 -279.505108) (xy 107.250162 -279.480542)
			(xy 107.296101 -279.46312) (xy 107.344241 -279.453292) (xy 107.393333 -279.451314) (xy 107.442107 -279.457236)
			(xy 107.489299 -279.470905) (xy 107.533688 -279.491968) (xy 107.574123 -279.519878) (xy 107.609557 -279.553913)
			(xy 107.639073 -279.593192) (xy 107.661906 -279.636696) (xy 107.677465 -279.6833) (xy 107.685346 -279.731796)
			(xy 107.68584 -279.756362) (xy 116.469426 -279.756362) (xy 116.47338 -279.707389) (xy 116.485138 -279.659685)
			(xy 116.504396 -279.614484) (xy 116.530655 -279.572958) (xy 116.563236 -279.536182) (xy 116.601294 -279.505108)
			(xy 116.643844 -279.480542) (xy 116.689783 -279.46312) (xy 116.737923 -279.453292) (xy 116.787015 -279.451314)
			(xy 116.835789 -279.457236) (xy 116.882981 -279.470905) (xy 116.92737 -279.491968) (xy 116.967805 -279.519878)
			(xy 117.003239 -279.553913) (xy 117.032755 -279.593192) (xy 117.055588 -279.636696) (xy 117.071147 -279.6833)
			(xy 117.079028 -279.731796) (xy 117.079522 -279.756362) (xy 117.40948 -279.756362) (xy 117.413434 -279.707389)
			(xy 117.425192 -279.659685) (xy 117.44445 -279.614484) (xy 117.470709 -279.572958) (xy 117.50329 -279.536182)
			(xy 117.541348 -279.505108) (xy 117.583898 -279.480542) (xy 117.629837 -279.46312) (xy 117.677977 -279.453292)
			(xy 117.727069 -279.451314) (xy 117.775843 -279.457236) (xy 117.823035 -279.470905) (xy 117.867424 -279.491968)
			(xy 117.907859 -279.519878) (xy 117.943293 -279.553913) (xy 117.972809 -279.593192) (xy 117.995642 -279.636696)
			(xy 118.011201 -279.6833) (xy 118.019082 -279.731796) (xy 118.019571 -279.756108) (xy 354.075758 -279.756108)
			(xy 354.079712 -279.707135) (xy 354.09147 -279.659431) (xy 354.110728 -279.61423) (xy 354.136987 -279.572704)
			(xy 354.169568 -279.535928) (xy 354.207626 -279.504854) (xy 354.250176 -279.480288) (xy 354.296115 -279.462866)
			(xy 354.344255 -279.453038) (xy 354.393347 -279.45106) (xy 354.442121 -279.456982) (xy 354.489313 -279.470651)
			(xy 354.533702 -279.491714) (xy 354.574137 -279.519624) (xy 354.609571 -279.553659) (xy 354.639087 -279.592938)
			(xy 354.66192 -279.636442) (xy 354.677479 -279.683046) (xy 354.68536 -279.731542) (xy 354.685854 -279.756108)
			(xy 355.015812 -279.756108) (xy 355.019766 -279.707135) (xy 355.031524 -279.659431) (xy 355.050782 -279.61423)
			(xy 355.077041 -279.572704) (xy 355.109622 -279.535928) (xy 355.14768 -279.504854) (xy 355.19023 -279.480288)
			(xy 355.236169 -279.462866) (xy 355.284309 -279.453038) (xy 355.333401 -279.45106) (xy 355.382175 -279.456982)
			(xy 355.429367 -279.470651) (xy 355.473756 -279.491714) (xy 355.514191 -279.519624) (xy 355.549625 -279.553659)
			(xy 355.579141 -279.592938) (xy 355.601974 -279.636442) (xy 355.617533 -279.683046) (xy 355.625414 -279.731542)
			(xy 355.625908 -279.756108) (xy 364.409494 -279.756108) (xy 364.413448 -279.707135) (xy 364.425206 -279.659431)
			(xy 364.444464 -279.61423) (xy 364.470723 -279.572704) (xy 364.503304 -279.535928) (xy 364.541362 -279.504854)
			(xy 364.583912 -279.480288) (xy 364.629851 -279.462866) (xy 364.677991 -279.453038) (xy 364.727083 -279.45106)
			(xy 364.775857 -279.456982) (xy 364.823049 -279.470651) (xy 364.867438 -279.491714) (xy 364.907873 -279.519624)
			(xy 364.943307 -279.553659) (xy 364.972823 -279.592938) (xy 364.995656 -279.636442) (xy 365.011215 -279.683046)
			(xy 365.019096 -279.731542) (xy 365.01959 -279.756108) (xy 365.349548 -279.756108) (xy 365.353502 -279.707135)
			(xy 365.36526 -279.659431) (xy 365.384518 -279.61423) (xy 365.410777 -279.572704) (xy 365.443358 -279.535928)
			(xy 365.481416 -279.504854) (xy 365.523966 -279.480288) (xy 365.569905 -279.462866) (xy 365.618045 -279.453038)
			(xy 365.667137 -279.45106) (xy 365.715911 -279.456982) (xy 365.763103 -279.470651) (xy 365.807492 -279.491714)
			(xy 365.847927 -279.519624) (xy 365.883361 -279.553659) (xy 365.912877 -279.592938) (xy 365.93571 -279.636442)
			(xy 365.951269 -279.683046) (xy 365.95915 -279.731542) (xy 365.959644 -279.756108) (xy 365.95915 -279.780674)
			(xy 365.951269 -279.82917) (xy 365.93571 -279.875774) (xy 365.912877 -279.919278) (xy 365.883361 -279.958557)
			(xy 365.847927 -279.992592) (xy 365.807492 -280.020502) (xy 365.763103 -280.041565) (xy 365.715911 -280.055234)
			(xy 365.667137 -280.061156) (xy 365.618045 -280.059178) (xy 365.569905 -280.04935) (xy 365.523966 -280.031928)
			(xy 365.481416 -280.007362) (xy 365.443358 -279.976288) (xy 365.410777 -279.939512) (xy 365.384518 -279.897986)
			(xy 365.36526 -279.852785) (xy 365.353502 -279.805081) (xy 365.349548 -279.756108) (xy 365.01959 -279.756108)
			(xy 365.019096 -279.780674) (xy 365.011215 -279.82917) (xy 364.995656 -279.875774) (xy 364.972823 -279.919278)
			(xy 364.943307 -279.958557) (xy 364.907873 -279.992592) (xy 364.867438 -280.020502) (xy 364.823049 -280.041565)
			(xy 364.775857 -280.055234) (xy 364.727083 -280.061156) (xy 364.677991 -280.059178) (xy 364.629851 -280.04935)
			(xy 364.583912 -280.031928) (xy 364.541362 -280.007362) (xy 364.503304 -279.976288) (xy 364.470723 -279.939512)
			(xy 364.444464 -279.897986) (xy 364.425206 -279.852785) (xy 364.413448 -279.805081) (xy 364.409494 -279.756108)
			(xy 355.625908 -279.756108) (xy 355.625414 -279.780674) (xy 355.617533 -279.82917) (xy 355.601974 -279.875774)
			(xy 355.579141 -279.919278) (xy 355.549625 -279.958557) (xy 355.514191 -279.992592) (xy 355.473756 -280.020502)
			(xy 355.429367 -280.041565) (xy 355.382175 -280.055234) (xy 355.333401 -280.061156) (xy 355.284309 -280.059178)
			(xy 355.236169 -280.04935) (xy 355.19023 -280.031928) (xy 355.14768 -280.007362) (xy 355.109622 -279.976288)
			(xy 355.077041 -279.939512) (xy 355.050782 -279.897986) (xy 355.031524 -279.852785) (xy 355.019766 -279.805081)
			(xy 355.015812 -279.756108) (xy 354.685854 -279.756108) (xy 354.68536 -279.780674) (xy 354.677479 -279.82917)
			(xy 354.66192 -279.875774) (xy 354.639087 -279.919278) (xy 354.609571 -279.958557) (xy 354.574137 -279.992592)
			(xy 354.533702 -280.020502) (xy 354.489313 -280.041565) (xy 354.442121 -280.055234) (xy 354.393347 -280.061156)
			(xy 354.344255 -280.059178) (xy 354.296115 -280.04935) (xy 354.250176 -280.031928) (xy 354.207626 -280.007362)
			(xy 354.169568 -279.976288) (xy 354.136987 -279.939512) (xy 354.110728 -279.897986) (xy 354.09147 -279.852785)
			(xy 354.079712 -279.805081) (xy 354.075758 -279.756108) (xy 118.019571 -279.756108) (xy 118.019576 -279.756362)
			(xy 118.019082 -279.780928) (xy 118.011201 -279.829424) (xy 117.995642 -279.876028) (xy 117.972809 -279.919532)
			(xy 117.943293 -279.958811) (xy 117.907859 -279.992846) (xy 117.867424 -280.020756) (xy 117.823035 -280.041819)
			(xy 117.775843 -280.055488) (xy 117.727069 -280.06141) (xy 117.677977 -280.059432) (xy 117.629837 -280.049604)
			(xy 117.583898 -280.032182) (xy 117.541348 -280.007616) (xy 117.50329 -279.976542) (xy 117.470709 -279.939766)
			(xy 117.44445 -279.89824) (xy 117.425192 -279.853039) (xy 117.413434 -279.805335) (xy 117.40948 -279.756362)
			(xy 117.079522 -279.756362) (xy 117.079028 -279.780928) (xy 117.071147 -279.829424) (xy 117.055588 -279.876028)
			(xy 117.032755 -279.919532) (xy 117.003239 -279.958811) (xy 116.967805 -279.992846) (xy 116.92737 -280.020756)
			(xy 116.882981 -280.041819) (xy 116.835789 -280.055488) (xy 116.787015 -280.06141) (xy 116.737923 -280.059432)
			(xy 116.689783 -280.049604) (xy 116.643844 -280.032182) (xy 116.601294 -280.007616) (xy 116.563236 -279.976542)
			(xy 116.530655 -279.939766) (xy 116.504396 -279.89824) (xy 116.485138 -279.853039) (xy 116.47338 -279.805335)
			(xy 116.469426 -279.756362) (xy 107.68584 -279.756362) (xy 107.685346 -279.780928) (xy 107.677465 -279.829424)
			(xy 107.661906 -279.876028) (xy 107.639073 -279.919532) (xy 107.609557 -279.958811) (xy 107.574123 -279.992846)
			(xy 107.533688 -280.020756) (xy 107.489299 -280.041819) (xy 107.442107 -280.055488) (xy 107.393333 -280.06141)
			(xy 107.344241 -280.059432) (xy 107.296101 -280.049604) (xy 107.250162 -280.032182) (xy 107.207612 -280.007616)
			(xy 107.169554 -279.976542) (xy 107.136973 -279.939766) (xy 107.110714 -279.89824) (xy 107.091456 -279.853039)
			(xy 107.079698 -279.805335) (xy 107.075744 -279.756362) (xy 106.745786 -279.756362) (xy 106.745292 -279.780928)
			(xy 106.737411 -279.829424) (xy 106.721852 -279.876028) (xy 106.699019 -279.919532) (xy 106.669503 -279.958811)
			(xy 106.634069 -279.992846) (xy 106.593634 -280.020756) (xy 106.549245 -280.041819) (xy 106.502053 -280.055488)
			(xy 106.453279 -280.06141) (xy 106.404187 -280.059432) (xy 106.356047 -280.049604) (xy 106.310108 -280.032182)
			(xy 106.267558 -280.007616) (xy 106.2295 -279.976542) (xy 106.196919 -279.939766) (xy 106.17066 -279.89824)
			(xy 106.151402 -279.853039) (xy 106.139644 -279.805335) (xy 106.13569 -279.756362) (xy 2.509012 -279.756362)
			(xy 2.509012 -281.3764) (xy 97.674859 -281.3764) (xy 97.679035 -281.32601) (xy 97.691448 -281.276995)
			(xy 97.711759 -281.230691) (xy 97.739414 -281.188362) (xy 97.77366 -281.151162) (xy 97.813561 -281.120107)
			(xy 97.85803 -281.096042) (xy 97.905853 -281.079626) (xy 97.955727 -281.071304) (xy 97.981008 -281.070812)
			(xy 98.921062 -281.070812) (xy 98.946341 -281.071354) (xy 98.996209 -281.07967) (xy 99.044029 -281.096081)
			(xy 99.088494 -281.12014) (xy 99.128393 -281.15119) (xy 99.162637 -281.188384) (xy 99.190291 -281.230707)
			(xy 99.210601 -281.277006) (xy 99.223013 -281.326016) (xy 99.227189 -281.3764) (xy 100.495088 -281.3764)
			(xy 100.499263 -281.326019) (xy 100.511672 -281.277012) (xy 100.531978 -281.230715) (xy 100.559627 -281.188392)
			(xy 100.593865 -281.151197) (xy 100.633757 -281.120144) (xy 100.678216 -281.09608) (xy 100.72603 -281.079662)
			(xy 100.775893 -281.071336) (xy 100.80117 -281.070812) (xy 101.741224 -281.070812) (xy 101.766497 -281.071388)
			(xy 101.816353 -281.079711) (xy 101.864159 -281.096126) (xy 101.908611 -281.120186) (xy 101.948498 -281.151233)
			(xy 101.98273 -281.188422) (xy 102.010375 -281.230738) (xy 102.030678 -281.277027) (xy 102.043086 -281.326027)
			(xy 102.04726 -281.3764) (xy 122.108688 -281.3764) (xy 122.112863 -281.326017) (xy 122.125274 -281.277007)
			(xy 122.145582 -281.230709) (xy 122.173233 -281.188385) (xy 122.207473 -281.151189) (xy 122.247369 -281.120136)
			(xy 122.291831 -281.096074) (xy 122.339648 -281.079657) (xy 122.389514 -281.071335) (xy 122.414792 -281.070812)
			(xy 123.354846 -281.070812) (xy 123.380118 -281.071389) (xy 123.429971 -281.079715) (xy 123.477774 -281.096133)
			(xy 123.522223 -281.120193) (xy 123.562106 -281.151241) (xy 123.596336 -281.18843) (xy 123.623978 -281.230745)
			(xy 123.64428 -281.277032) (xy 123.656686 -281.326029) (xy 123.66086 -281.3764) (xy 124.928589 -281.3764)
			(xy 124.932763 -281.326016) (xy 124.945174 -281.277006) (xy 124.965483 -281.230707) (xy 124.993135 -281.188382)
			(xy 125.027376 -281.151186) (xy 125.067273 -281.120134) (xy 125.111736 -281.096071) (xy 125.159554 -281.079655)
			(xy 125.209422 -281.071334) (xy 125.2347 -281.070812) (xy 126.174754 -281.070812) (xy 126.200033 -281.071353)
			(xy 126.249903 -281.079668) (xy 126.297723 -281.096079) (xy 126.34219 -281.120137) (xy 126.38209 -281.151187)
			(xy 126.416335 -281.188381) (xy 126.44399 -281.230705) (xy 126.464301 -281.277004) (xy 126.476713 -281.326015)
			(xy 126.480864 -281.3761) (xy 345.615289 -281.3761) (xy 345.619459 -281.325768) (xy 345.631857 -281.276808)
			(xy 345.652144 -281.230557) (xy 345.679766 -281.188275) (xy 345.713971 -281.151116) (xy 345.753825 -281.120094)
			(xy 345.798241 -281.096054) (xy 345.846008 -281.079652) (xy 345.895824 -281.071335) (xy 345.921076 -281.070812)
			(xy 346.86113 -281.070812) (xy 346.886385 -281.071296) (xy 346.936207 -281.079614) (xy 346.983979 -281.096019)
			(xy 347.028401 -281.120062) (xy 347.068259 -281.151089) (xy 347.102467 -281.188252) (xy 347.130092 -281.230539)
			(xy 347.150381 -281.276796) (xy 347.16278 -281.325762) (xy 347.166951 -281.3761) (xy 348.43536 -281.3761)
			(xy 348.439532 -281.325756) (xy 348.451934 -281.276786) (xy 348.472227 -281.230526) (xy 348.499859 -281.188237)
			(xy 348.534075 -281.151073) (xy 348.573942 -281.120048) (xy 348.618371 -281.096009) (xy 348.666152 -281.079611)
			(xy 348.71598 -281.071302) (xy 348.741238 -281.070812) (xy 349.681292 -281.070812) (xy 349.706552 -281.071264)
			(xy 349.756383 -281.079578) (xy 349.804165 -281.095981) (xy 349.848596 -281.120025) (xy 349.888464 -281.151054)
			(xy 349.92268 -281.188222) (xy 349.950312 -281.230515) (xy 349.970606 -281.276779) (xy 349.983008 -281.325753)
			(xy 349.98718 -281.3761) (xy 370.049089 -281.3761) (xy 370.053259 -281.325769) (xy 370.065656 -281.276811)
			(xy 370.085941 -281.230561) (xy 370.113562 -281.18828) (xy 370.147764 -281.151122) (xy 370.187616 -281.120099)
			(xy 370.23203 -281.096058) (xy 370.279795 -281.079655) (xy 370.329608 -281.071337) (xy 370.35486 -281.070812)
			(xy 371.294914 -281.070812) (xy 371.32017 -281.071295) (xy 371.369993 -281.079611) (xy 371.417768 -281.096014)
			(xy 371.462192 -281.120057) (xy 371.502053 -281.151083) (xy 371.536263 -281.188247) (xy 371.56389 -281.230535)
			(xy 371.58418 -281.276793) (xy 371.59658 -281.32576) (xy 371.600751 -281.3761) (xy 372.868989 -281.3761)
			(xy 372.873159 -281.325768) (xy 372.885556 -281.27681) (xy 372.905842 -281.230559) (xy 372.933464 -281.188278)
			(xy 372.967667 -281.151119) (xy 373.00752 -281.120096) (xy 373.051935 -281.096056) (xy 373.099702 -281.079653)
			(xy 373.149516 -281.071336) (xy 373.174768 -281.070812) (xy 374.114822 -281.070812) (xy 374.140078 -281.071295)
			(xy 374.1899 -281.079613) (xy 374.237674 -281.096016) (xy 374.282096 -281.120059) (xy 374.321956 -281.151086)
			(xy 374.356165 -281.18825) (xy 374.383791 -281.230537) (xy 374.404081 -281.276795) (xy 374.41648 -281.325761)
			(xy 374.420651 -281.3761) (xy 374.41648 -281.426439) (xy 374.404081 -281.475405) (xy 374.383791 -281.521663)
			(xy 374.356165 -281.56395) (xy 374.321956 -281.601114) (xy 374.282096 -281.632141) (xy 374.237674 -281.656184)
			(xy 374.1899 -281.672587) (xy 374.140078 -281.680905) (xy 374.114822 -281.681428) (xy 373.174768 -281.681428)
			(xy 373.149516 -281.680864) (xy 373.099702 -281.672547) (xy 373.051935 -281.656144) (xy 373.00752 -281.632104)
			(xy 372.967667 -281.601081) (xy 372.933464 -281.563922) (xy 372.905842 -281.521641) (xy 372.885556 -281.47539)
			(xy 372.873159 -281.426432) (xy 372.868989 -281.3761) (xy 371.600751 -281.3761) (xy 371.59658 -281.42644)
			(xy 371.58418 -281.475407) (xy 371.56389 -281.521665) (xy 371.536263 -281.563953) (xy 371.502053 -281.601117)
			(xy 371.462192 -281.632143) (xy 371.417768 -281.656186) (xy 371.369993 -281.672589) (xy 371.32017 -281.680905)
			(xy 371.294914 -281.681428) (xy 370.35486 -281.681428) (xy 370.329609 -281.680863) (xy 370.279795 -281.672545)
			(xy 370.23203 -281.656142) (xy 370.187616 -281.632101) (xy 370.147764 -281.601078) (xy 370.113562 -281.56392)
			(xy 370.085941 -281.521639) (xy 370.065656 -281.475389) (xy 370.053259 -281.426431) (xy 370.049089 -281.3761)
			(xy 349.98718 -281.3761) (xy 349.983008 -281.426447) (xy 349.970606 -281.475421) (xy 349.950312 -281.521685)
			(xy 349.92268 -281.563978) (xy 349.888464 -281.601146) (xy 349.848596 -281.632175) (xy 349.804165 -281.656219)
			(xy 349.756383 -281.672622) (xy 349.706552 -281.680936) (xy 349.681292 -281.681428) (xy 348.741238 -281.681428)
			(xy 348.71598 -281.680898) (xy 348.666152 -281.672589) (xy 348.618371 -281.656191) (xy 348.573941 -281.632152)
			(xy 348.534075 -281.601127) (xy 348.499859 -281.563963) (xy 348.472227 -281.521674) (xy 348.451934 -281.475414)
			(xy 348.439532 -281.426444) (xy 348.43536 -281.3761) (xy 347.166951 -281.3761) (xy 347.16278 -281.426438)
			(xy 347.150381 -281.475404) (xy 347.130092 -281.521661) (xy 347.102467 -281.563948) (xy 347.068259 -281.601111)
			(xy 347.028401 -281.632138) (xy 346.983979 -281.656181) (xy 346.936207 -281.672586) (xy 346.886385 -281.680904)
			(xy 346.86113 -281.681428) (xy 345.921076 -281.681428) (xy 345.895824 -281.680865) (xy 345.846008 -281.672548)
			(xy 345.798241 -281.656146) (xy 345.753825 -281.632106) (xy 345.713971 -281.601084) (xy 345.679766 -281.563925)
			(xy 345.652144 -281.521643) (xy 345.631857 -281.475392) (xy 345.619459 -281.426432) (xy 345.615289 -281.3761)
			(xy 126.480864 -281.3761) (xy 126.480889 -281.3764) (xy 126.476713 -281.426785) (xy 126.464301 -281.475796)
			(xy 126.44399 -281.522095) (xy 126.416335 -281.564419) (xy 126.38209 -281.601613) (xy 126.34219 -281.632663)
			(xy 126.297723 -281.656721) (xy 126.249903 -281.673132) (xy 126.200033 -281.681447) (xy 126.174754 -281.681936)
			(xy 125.2347 -281.681936) (xy 125.209422 -281.681466) (xy 125.159554 -281.673145) (xy 125.111736 -281.656729)
			(xy 125.067273 -281.632666) (xy 125.027376 -281.601614) (xy 124.993135 -281.564418) (xy 124.965483 -281.522093)
			(xy 124.945174 -281.475794) (xy 124.932763 -281.426784) (xy 124.928589 -281.3764) (xy 123.66086 -281.3764)
			(xy 123.656686 -281.426771) (xy 123.64428 -281.475768) (xy 123.623978 -281.522055) (xy 123.596336 -281.56437)
			(xy 123.562106 -281.601559) (xy 123.522223 -281.632607) (xy 123.477774 -281.656667) (xy 123.429971 -281.673085)
			(xy 123.380118 -281.681411) (xy 123.354846 -281.681936) (xy 122.414792 -281.681936) (xy 122.389514 -281.681465)
			(xy 122.339648 -281.673143) (xy 122.291831 -281.656726) (xy 122.247369 -281.632664) (xy 122.207473 -281.601611)
			(xy 122.173233 -281.564415) (xy 122.145582 -281.522091) (xy 122.125274 -281.475793) (xy 122.112863 -281.426783)
			(xy 122.108688 -281.3764) (xy 102.04726 -281.3764) (xy 102.043086 -281.426773) (xy 102.030678 -281.475773)
			(xy 102.010375 -281.522062) (xy 101.98273 -281.564378) (xy 101.948498 -281.601567) (xy 101.908611 -281.632614)
			(xy 101.864159 -281.656674) (xy 101.816353 -281.673089) (xy 101.766497 -281.681412) (xy 101.741224 -281.681936)
			(xy 100.80117 -281.681936) (xy 100.775893 -281.681464) (xy 100.72603 -281.673138) (xy 100.678216 -281.65672)
			(xy 100.633757 -281.632656) (xy 100.593865 -281.601603) (xy 100.559627 -281.564408) (xy 100.531978 -281.522085)
			(xy 100.511672 -281.475788) (xy 100.499263 -281.426781) (xy 100.495088 -281.3764) (xy 99.227189 -281.3764)
			(xy 99.223013 -281.426784) (xy 99.210601 -281.475794) (xy 99.190291 -281.522093) (xy 99.162637 -281.564416)
			(xy 99.128393 -281.60161) (xy 99.088494 -281.63266) (xy 99.044029 -281.656719) (xy 98.996209 -281.67313)
			(xy 98.946341 -281.681446) (xy 98.921062 -281.681936) (xy 97.981008 -281.681936) (xy 97.955727 -281.681496)
			(xy 97.905853 -281.673174) (xy 97.85803 -281.656758) (xy 97.813561 -281.632693) (xy 97.77366 -281.601638)
			(xy 97.739414 -281.564438) (xy 97.711759 -281.522109) (xy 97.691448 -281.475805) (xy 97.679035 -281.42679)
			(xy 97.674859 -281.3764) (xy 2.509012 -281.3764) (xy 2.509012 -282.1864) (xy 108.485149 -282.1864)
			(xy 108.48932 -282.136059) (xy 108.50172 -282.087092) (xy 108.522011 -282.040833) (xy 108.549639 -281.998544)
			(xy 108.58385 -281.96138) (xy 108.623712 -281.930354) (xy 108.668137 -281.906312) (xy 108.715913 -281.889909)
			(xy 108.765737 -281.881594) (xy 108.790994 -281.881072) (xy 109.731048 -281.881072) (xy 109.756299 -281.881637)
			(xy 109.806111 -281.889957) (xy 109.853875 -281.906361) (xy 109.898288 -281.930402) (xy 109.938139 -281.961425)
			(xy 109.97234 -281.998583) (xy 109.99996 -282.040863) (xy 110.020245 -282.087113) (xy 110.032641 -282.13607)
			(xy 110.036811 -282.1864) (xy 114.11882 -282.1864) (xy 114.122992 -282.136052) (xy 114.135394 -282.087078)
			(xy 114.155689 -282.040813) (xy 114.183321 -281.99852) (xy 114.217539 -281.961352) (xy 114.257407 -281.930323)
			(xy 114.301839 -281.906279) (xy 114.349622 -281.889877) (xy 114.399454 -281.881564) (xy 114.424714 -281.881072)
			(xy 115.364768 -281.881072) (xy 115.390026 -281.881602) (xy 115.439853 -281.889912) (xy 115.487633 -281.90631)
			(xy 115.532062 -281.93035) (xy 115.571927 -281.961375) (xy 115.606142 -281.998539) (xy 115.633773 -282.040827)
			(xy 115.654067 -282.087088) (xy 115.666468 -282.136057) (xy 115.670615 -282.1861) (xy 356.42504 -282.1861)
			(xy 356.429214 -282.135728) (xy 356.441621 -282.08673) (xy 356.461923 -282.040442) (xy 356.489566 -281.998127)
			(xy 356.523797 -281.960938) (xy 356.563681 -281.92989) (xy 356.608132 -281.90583) (xy 356.655936 -281.889414)
			(xy 356.70579 -281.881089) (xy 356.731062 -281.880564) (xy 357.671116 -281.880564) (xy 357.696394 -281.881035)
			(xy 357.746259 -281.889359) (xy 357.794074 -281.905776) (xy 357.838536 -281.929839) (xy 357.87843 -281.960892)
			(xy 357.912669 -281.998088) (xy 357.940319 -282.040411) (xy 357.960627 -282.086709) (xy 357.973037 -282.135717)
			(xy 357.977212 -282.1861) (xy 362.05874 -282.1861) (xy 362.062914 -282.135726) (xy 362.075322 -282.086726)
			(xy 362.095626 -282.040437) (xy 362.123271 -281.99812) (xy 362.157505 -281.960931) (xy 362.197392 -281.929883)
			(xy 362.241845 -281.905824) (xy 362.289652 -281.88941) (xy 362.339509 -281.881087) (xy 362.364782 -281.880564)
			(xy 363.304836 -281.880564) (xy 363.330113 -281.881037) (xy 363.379975 -281.889363) (xy 363.427788 -281.905782)
			(xy 363.472246 -281.929846) (xy 363.512138 -281.960899) (xy 363.546374 -281.998094) (xy 363.574022 -282.040417)
			(xy 363.594328 -282.086713) (xy 363.606737 -282.135719) (xy 363.610912 -282.1861) (xy 363.606737 -282.236481)
			(xy 363.594328 -282.285487) (xy 363.574022 -282.331783) (xy 363.546374 -282.374106) (xy 363.512138 -282.411301)
			(xy 363.472246 -282.442354) (xy 363.427788 -282.466418) (xy 363.379975 -282.482837) (xy 363.330113 -282.491163)
			(xy 363.304836 -282.491688) (xy 362.364782 -282.491688) (xy 362.339509 -282.491113) (xy 362.289652 -282.48279)
			(xy 362.241845 -282.466376) (xy 362.197392 -282.442317) (xy 362.157505 -282.411269) (xy 362.123271 -282.37408)
			(xy 362.095626 -282.331763) (xy 362.075322 -282.285474) (xy 362.062914 -282.236474) (xy 362.05874 -282.1861)
			(xy 357.977212 -282.1861) (xy 357.973037 -282.236483) (xy 357.960627 -282.285491) (xy 357.940319 -282.331789)
			(xy 357.912669 -282.374112) (xy 357.87843 -282.411308) (xy 357.838536 -282.442361) (xy 357.794074 -282.466424)
			(xy 357.746259 -282.482841) (xy 357.696394 -282.491165) (xy 357.671116 -282.491688) (xy 356.731062 -282.491688)
			(xy 356.70579 -282.491111) (xy 356.655936 -282.482786) (xy 356.608132 -282.46637) (xy 356.563681 -282.44231)
			(xy 356.523797 -282.411262) (xy 356.489566 -282.374073) (xy 356.461923 -282.331758) (xy 356.441621 -282.28547)
			(xy 356.429214 -282.236472) (xy 356.42504 -282.1861) (xy 115.670615 -282.1861) (xy 115.67064 -282.1864)
			(xy 115.666468 -282.236743) (xy 115.654067 -282.285712) (xy 115.633773 -282.331973) (xy 115.606142 -282.374261)
			(xy 115.571927 -282.411425) (xy 115.532062 -282.44245) (xy 115.487633 -282.46649) (xy 115.439853 -282.482888)
			(xy 115.390026 -282.491198) (xy 115.364768 -282.491688) (xy 114.424714 -282.491688) (xy 114.399454 -282.491236)
			(xy 114.349622 -282.482923) (xy 114.301839 -282.466521) (xy 114.257407 -282.442477) (xy 114.217539 -282.411448)
			(xy 114.183321 -282.37428) (xy 114.155689 -282.331987) (xy 114.135394 -282.285722) (xy 114.122992 -282.236748)
			(xy 114.11882 -282.1864) (xy 110.036811 -282.1864) (xy 110.032641 -282.23673) (xy 110.020245 -282.285687)
			(xy 109.99996 -282.331937) (xy 109.97234 -282.374217) (xy 109.938139 -282.411375) (xy 109.898288 -282.442398)
			(xy 109.853875 -282.466439) (xy 109.806111 -282.482843) (xy 109.756299 -282.491163) (xy 109.731048 -282.491688)
			(xy 108.790994 -282.491688) (xy 108.765737 -282.491206) (xy 108.715913 -282.482891) (xy 108.668137 -282.466488)
			(xy 108.623712 -282.442446) (xy 108.58385 -282.41142) (xy 108.549639 -282.374256) (xy 108.522011 -282.331967)
			(xy 108.50172 -282.285708) (xy 108.48932 -282.236741) (xy 108.485149 -282.1864) (xy 2.509012 -282.1864)
			(xy 2.509012 -282.9964) (xy 97.674871 -282.9964) (xy 97.679047 -282.946012) (xy 97.691459 -282.896999)
			(xy 97.711769 -282.850697) (xy 97.739424 -282.808369) (xy 97.773668 -282.771171) (xy 97.813568 -282.740117)
			(xy 97.858035 -282.716053) (xy 97.905856 -282.699637) (xy 97.955728 -282.691316) (xy 97.981008 -282.690824)
			(xy 98.921062 -282.690824) (xy 98.946342 -282.691342) (xy 98.996212 -282.699658) (xy 99.044033 -282.71607)
			(xy 99.088501 -282.74013) (xy 99.128401 -282.771181) (xy 99.162646 -282.808377) (xy 99.190302 -282.850702)
			(xy 99.210613 -282.897002) (xy 99.223025 -282.946014) (xy 99.227201 -282.9964) (xy 100.4951 -282.9964)
			(xy 100.499275 -282.946021) (xy 100.511684 -282.897016) (xy 100.531989 -282.850721) (xy 100.559637 -282.8084)
			(xy 100.593873 -282.771206) (xy 100.633764 -282.740154) (xy 100.678221 -282.716091) (xy 100.726032 -282.699673)
			(xy 100.775894 -282.691348) (xy 100.80117 -282.690824) (xy 101.741224 -282.690824) (xy 101.766498 -282.691376)
			(xy 101.816356 -282.699699) (xy 101.864164 -282.716115) (xy 101.908618 -282.740176) (xy 101.948506 -282.771224)
			(xy 101.98274 -282.808415) (xy 102.010385 -282.850733) (xy 102.030689 -282.897024) (xy 102.043098 -282.946025)
			(xy 102.047272 -282.9964) (xy 103.315 -282.9964) (xy 103.319175 -282.94602) (xy 103.331584 -282.897014)
			(xy 103.35189 -282.850719) (xy 103.379539 -282.808397) (xy 103.413776 -282.771203) (xy 103.453668 -282.740151)
			(xy 103.498126 -282.716089) (xy 103.545939 -282.699672) (xy 103.595802 -282.691348) (xy 103.621078 -282.690824)
			(xy 104.561132 -282.690824) (xy 104.586405 -282.691376) (xy 104.636262 -282.699701) (xy 104.684069 -282.716117)
			(xy 104.728522 -282.740178) (xy 104.768409 -282.771227) (xy 104.802642 -282.808418) (xy 104.830287 -282.850735)
			(xy 104.85059 -282.897025) (xy 104.862998 -282.946026) (xy 104.867172 -282.9964) (xy 106.1349 -282.9964)
			(xy 106.139075 -282.946019) (xy 106.151485 -282.897012) (xy 106.171791 -282.850717) (xy 106.199441 -282.808394)
			(xy 106.233679 -282.7712) (xy 106.273572 -282.740149) (xy 106.318032 -282.716086) (xy 106.365846 -282.69967)
			(xy 106.415709 -282.691347) (xy 106.440986 -282.690824) (xy 107.38104 -282.690824) (xy 107.406313 -282.691377)
			(xy 107.456169 -282.699702) (xy 107.503975 -282.71612) (xy 107.548426 -282.740181) (xy 107.588312 -282.77123)
			(xy 107.622544 -282.80842) (xy 107.650188 -282.850737) (xy 107.67049 -282.897027) (xy 107.682898 -282.946026)
			(xy 107.687072 -282.9964) (xy 116.468571 -282.9964) (xy 116.472747 -282.946011) (xy 116.48516 -282.896996)
			(xy 116.505471 -282.850693) (xy 116.533127 -282.808365) (xy 116.567373 -282.771166) (xy 116.607275 -282.740112)
			(xy 116.651744 -282.716049) (xy 116.699568 -282.699634) (xy 116.749441 -282.691315) (xy 116.774722 -282.690824)
			(xy 117.714776 -282.690824) (xy 117.740055 -282.691343) (xy 117.789924 -282.699661) (xy 117.837743 -282.716074)
			(xy 117.882208 -282.740135) (xy 117.922107 -282.771186) (xy 117.95635 -282.808381) (xy 117.984004 -282.850706)
			(xy 118.004313 -282.897005) (xy 118.016725 -282.946015) (xy 118.020901 -282.9964) (xy 119.288471 -282.9964)
			(xy 119.292647 -282.94601) (xy 119.30506 -282.896994) (xy 119.325373 -282.850691) (xy 119.353029 -282.808362)
			(xy 119.387276 -282.771163) (xy 119.427179 -282.740109) (xy 119.47165 -282.716047) (xy 119.519474 -282.699633)
			(xy 119.569348 -282.691315) (xy 119.59463 -282.690824) (xy 120.534684 -282.690824) (xy 120.559962 -282.691344)
			(xy 120.60983 -282.699663) (xy 120.657648 -282.716077) (xy 120.702113 -282.740137) (xy 120.74201 -282.771189)
			(xy 120.776252 -282.808384) (xy 120.803905 -282.850708) (xy 120.824214 -282.897006) (xy 120.836625 -282.946016)
			(xy 120.840801 -282.9964) (xy 122.1087 -282.9964) (xy 122.112875 -282.946019) (xy 122.125285 -282.897011)
			(xy 122.145592 -282.850715) (xy 122.173242 -282.808392) (xy 122.207481 -282.771198) (xy 122.247375 -282.740147)
			(xy 122.291836 -282.716085) (xy 122.33965 -282.699669) (xy 122.389515 -282.691347) (xy 122.414792 -282.690824)
			(xy 123.354846 -282.690824) (xy 123.380119 -282.691377) (xy 123.429974 -282.699704) (xy 123.477779 -282.716122)
			(xy 123.52223 -282.740183) (xy 123.562114 -282.771232) (xy 123.596345 -282.808422) (xy 123.623989 -282.850739)
			(xy 123.644291 -282.897028) (xy 123.656698 -282.946027) (xy 123.660872 -282.9964) (xy 124.928601 -282.9964)
			(xy 124.932775 -282.946018) (xy 124.945186 -282.89701) (xy 124.965494 -282.850713) (xy 124.993144 -282.80839)
			(xy 125.027384 -282.771195) (xy 125.067279 -282.740144) (xy 125.111741 -282.716082) (xy 125.159557 -282.699667)
			(xy 125.209423 -282.691346) (xy 125.2347 -282.690824) (xy 126.174754 -282.690824) (xy 126.200034 -282.691341)
			(xy 126.249906 -282.699657) (xy 126.297728 -282.716068) (xy 126.342197 -282.740127) (xy 126.382098 -282.771178)
			(xy 126.416344 -282.808374) (xy 126.444 -282.850699) (xy 126.464312 -282.897) (xy 126.476725 -282.946013)
			(xy 126.480876 -282.9961) (xy 345.615301 -282.9961) (xy 345.619471 -282.94577) (xy 345.631868 -282.896812)
			(xy 345.652154 -282.850562) (xy 345.679775 -282.808282) (xy 345.713979 -282.771125) (xy 345.753831 -282.740104)
			(xy 345.798246 -282.716065) (xy 345.846011 -282.699663) (xy 345.895825 -282.691347) (xy 345.921076 -282.690824)
			(xy 346.86113 -282.690824) (xy 346.886386 -282.691284) (xy 346.936209 -282.699603) (xy 346.983984 -282.716008)
			(xy 347.028407 -282.740052) (xy 347.068267 -282.77108) (xy 347.102477 -282.808245) (xy 347.130103 -282.850534)
			(xy 347.150393 -282.896792) (xy 347.162792 -282.94576) (xy 347.166963 -282.9961) (xy 348.435372 -282.9961)
			(xy 348.439544 -282.945758) (xy 348.451945 -282.89679) (xy 348.472238 -282.850531) (xy 348.499869 -282.808244)
			(xy 348.534083 -282.771081) (xy 348.573948 -282.740058) (xy 348.618376 -282.71602) (xy 348.666155 -282.699622)
			(xy 348.715981 -282.691314) (xy 348.741238 -282.690824) (xy 349.681292 -282.690824) (xy 349.706553 -282.691252)
			(xy 349.756386 -282.699567) (xy 349.80417 -282.71597) (xy 349.848603 -282.740015) (xy 349.888472 -282.771045)
			(xy 349.92269 -282.808215) (xy 349.950323 -282.850509) (xy 349.970617 -282.896775) (xy 349.98302 -282.945751)
			(xy 349.987192 -282.9961) (xy 351.255272 -282.9961) (xy 351.259444 -282.945758) (xy 351.271846 -282.896789)
			(xy 351.292139 -282.850529) (xy 351.319771 -282.808241) (xy 351.353986 -282.771079) (xy 351.393852 -282.740055)
			(xy 351.438281 -282.716017) (xy 351.486061 -282.699621) (xy 351.535888 -282.691313) (xy 351.561146 -282.690824)
			(xy 352.5012 -282.690824) (xy 352.526458 -282.691282) (xy 352.576285 -282.699596) (xy 352.624064 -282.715999)
			(xy 352.668491 -282.740042) (xy 352.708355 -282.771069) (xy 352.742569 -282.808235) (xy 352.770198 -282.850525)
			(xy 352.79049 -282.896786) (xy 352.802891 -282.945757) (xy 352.807063 -282.9961) (xy 354.075301 -282.9961)
			(xy 354.079471 -282.945772) (xy 354.091867 -282.896816) (xy 354.112151 -282.850569) (xy 354.13977 -282.80829)
			(xy 354.17397 -282.771133) (xy 354.213819 -282.740111) (xy 354.258231 -282.716071) (xy 354.305993 -282.699668)
			(xy 354.355804 -282.691349) (xy 354.381054 -282.690824) (xy 355.321108 -282.690824) (xy 355.346366 -282.691282)
			(xy 355.396191 -282.699598) (xy 355.443969 -282.716001) (xy 355.488395 -282.740045) (xy 355.528258 -282.771072)
			(xy 355.562471 -282.808238) (xy 355.5901 -282.850528) (xy 355.610391 -282.896788) (xy 355.622792 -282.945757)
			(xy 355.626963 -282.9961) (xy 364.409001 -282.9961) (xy 364.413172 -282.945768) (xy 364.425569 -282.896809)
			(xy 364.445856 -282.850559) (xy 364.473479 -282.808278) (xy 364.507684 -282.77112) (xy 364.547539 -282.740099)
			(xy 364.591955 -282.71606) (xy 364.639723 -282.69966) (xy 364.689538 -282.691346) (xy 364.71479 -282.690824)
			(xy 365.654844 -282.690824) (xy 365.6801 -282.691285) (xy 365.729921 -282.699605) (xy 365.777694 -282.716012)
			(xy 365.822115 -282.740057) (xy 365.861972 -282.771085) (xy 365.89618 -282.80825) (xy 365.923805 -282.850538)
			(xy 365.944094 -282.896795) (xy 365.956492 -282.945761) (xy 365.960663 -282.9961) (xy 367.228901 -282.9961)
			(xy 367.233072 -282.945767) (xy 367.24547 -282.896808) (xy 367.265758 -282.850556) (xy 367.293381 -282.808275)
			(xy 367.327587 -282.771117) (xy 367.367443 -282.740096) (xy 367.411861 -282.716058) (xy 367.459629 -282.699659)
			(xy 367.509445 -282.691346) (xy 367.534698 -282.690824) (xy 368.474752 -282.690824) (xy 368.500015 -282.691249)
			(xy 368.549853 -282.699558) (xy 368.597643 -282.715958) (xy 368.642082 -282.740001) (xy 368.681956 -282.771031)
			(xy 368.716179 -282.808201) (xy 368.743817 -282.850498) (xy 368.764115 -282.896767) (xy 368.776519 -282.945747)
			(xy 368.780692 -282.9961) (xy 370.049101 -282.9961) (xy 370.053271 -282.945771) (xy 370.065667 -282.896815)
			(xy 370.085952 -282.850567) (xy 370.113571 -282.808288) (xy 370.147772 -282.771131) (xy 370.187623 -282.740109)
			(xy 370.232035 -282.716069) (xy 370.279798 -282.699667) (xy 370.329609 -282.691349) (xy 370.35486 -282.690824)
			(xy 371.294914 -282.690824) (xy 371.320171 -282.691283) (xy 371.369996 -282.699599) (xy 371.417773 -282.716003)
			(xy 371.462199 -282.740047) (xy 371.502061 -282.771074) (xy 371.536273 -282.80824) (xy 371.563901 -282.850529)
			(xy 371.584191 -282.896789) (xy 371.596592 -282.945758) (xy 371.600763 -282.9961) (xy 372.869001 -282.9961)
			(xy 372.873171 -282.94577) (xy 372.885568 -282.896814) (xy 372.905853 -282.850565) (xy 372.933473 -282.808285)
			(xy 372.967676 -282.771128) (xy 373.007527 -282.740106) (xy 373.05194 -282.716067) (xy 373.099705 -282.699665)
			(xy 373.149517 -282.691348) (xy 373.174768 -282.690824) (xy 374.114822 -282.690824) (xy 374.140079 -282.691283)
			(xy 374.189903 -282.699601) (xy 374.237679 -282.716005) (xy 374.282103 -282.740049) (xy 374.321964 -282.771077)
			(xy 374.356175 -282.808242) (xy 374.383802 -282.850531) (xy 374.404092 -282.896791) (xy 374.416492 -282.945759)
			(xy 374.420663 -282.9961) (xy 374.416492 -283.046441) (xy 374.404092 -283.095409) (xy 374.383802 -283.141669)
			(xy 374.356175 -283.183958) (xy 374.321964 -283.221123) (xy 374.282103 -283.252151) (xy 374.237679 -283.276195)
			(xy 374.189903 -283.292599) (xy 374.140079 -283.300917) (xy 374.114822 -283.30144) (xy 373.174768 -283.30144)
			(xy 373.149517 -283.300852) (xy 373.099705 -283.292535) (xy 373.05194 -283.276133) (xy 373.007527 -283.252094)
			(xy 372.967676 -283.221072) (xy 372.933473 -283.183915) (xy 372.905853 -283.141635) (xy 372.885568 -283.095386)
			(xy 372.873171 -283.04643) (xy 372.869001 -282.9961) (xy 371.600763 -282.9961) (xy 371.596592 -283.046442)
			(xy 371.584191 -283.095411) (xy 371.563901 -283.141671) (xy 371.536273 -283.18396) (xy 371.502061 -283.221126)
			(xy 371.462199 -283.252153) (xy 371.417773 -283.276197) (xy 371.369996 -283.292601) (xy 371.320171 -283.300917)
			(xy 371.294914 -283.30144) (xy 370.35486 -283.30144) (xy 370.329609 -283.300851) (xy 370.279798 -283.292533)
			(xy 370.232035 -283.276131) (xy 370.187623 -283.252091) (xy 370.147772 -283.221069) (xy 370.113571 -283.183912)
			(xy 370.085952 -283.141633) (xy 370.065667 -283.095385) (xy 370.053271 -283.046429) (xy 370.049101 -282.9961)
			(xy 368.780692 -282.9961) (xy 368.776519 -283.046453) (xy 368.764115 -283.095433) (xy 368.743817 -283.141702)
			(xy 368.716179 -283.183999) (xy 368.681956 -283.221169) (xy 368.642082 -283.252199) (xy 368.597643 -283.276242)
			(xy 368.549853 -283.292642) (xy 368.500015 -283.300951) (xy 368.474752 -283.30144) (xy 367.534698 -283.30144)
			(xy 367.509445 -283.300854) (xy 367.459629 -283.292541) (xy 367.411861 -283.276142) (xy 367.367443 -283.252104)
			(xy 367.327587 -283.221083) (xy 367.293381 -283.183925) (xy 367.265758 -283.141644) (xy 367.24547 -283.095392)
			(xy 367.233072 -283.046433) (xy 367.228901 -282.9961) (xy 365.960663 -282.9961) (xy 365.956492 -283.046439)
			(xy 365.944094 -283.095405) (xy 365.923805 -283.141662) (xy 365.89618 -283.18395) (xy 365.861972 -283.221115)
			(xy 365.822115 -283.252143) (xy 365.777694 -283.276188) (xy 365.729921 -283.292595) (xy 365.6801 -283.300915)
			(xy 365.654844 -283.30144) (xy 364.71479 -283.30144) (xy 364.689538 -283.300854) (xy 364.639723 -283.29254)
			(xy 364.591955 -283.27614) (xy 364.547539 -283.252101) (xy 364.507684 -283.22108) (xy 364.473479 -283.183922)
			(xy 364.445856 -283.141641) (xy 364.425569 -283.095391) (xy 364.413172 -283.046432) (xy 364.409001 -282.9961)
			(xy 355.626963 -282.9961) (xy 355.622792 -283.046443) (xy 355.610391 -283.095412) (xy 355.5901 -283.141672)
			(xy 355.562471 -283.183962) (xy 355.528258 -283.221128) (xy 355.488395 -283.252155) (xy 355.443969 -283.276199)
			(xy 355.396191 -283.292602) (xy 355.346366 -283.300918) (xy 355.321108 -283.30144) (xy 354.381054 -283.30144)
			(xy 354.355804 -283.300851) (xy 354.305993 -283.292532) (xy 354.258231 -283.276129) (xy 354.213819 -283.252089)
			(xy 354.17397 -283.221067) (xy 354.13977 -283.18391) (xy 354.112151 -283.141631) (xy 354.091867 -283.095384)
			(xy 354.079471 -283.046428) (xy 354.075301 -282.9961) (xy 352.807063 -282.9961) (xy 352.802891 -283.046443)
			(xy 352.79049 -283.095414) (xy 352.770198 -283.141675) (xy 352.742569 -283.183965) (xy 352.708355 -283.221131)
			(xy 352.668491 -283.252158) (xy 352.624064 -283.276201) (xy 352.576285 -283.292604) (xy 352.526458 -283.300918)
			(xy 352.5012 -283.30144) (xy 351.561146 -283.30144) (xy 351.535888 -283.300887) (xy 351.486061 -283.292579)
			(xy 351.438281 -283.276183) (xy 351.393852 -283.252145) (xy 351.353986 -283.221121) (xy 351.319771 -283.183959)
			(xy 351.292139 -283.141671) (xy 351.271846 -283.095411) (xy 351.259444 -283.046442) (xy 351.255272 -282.9961)
			(xy 349.987192 -282.9961) (xy 349.98302 -283.046449) (xy 349.970617 -283.095425) (xy 349.950323 -283.141691)
			(xy 349.92269 -283.183985) (xy 349.888472 -283.221155) (xy 349.848603 -283.252185) (xy 349.80417 -283.27623)
			(xy 349.756386 -283.292633) (xy 349.706553 -283.300948) (xy 349.681292 -283.30144) (xy 348.741238 -283.30144)
			(xy 348.715981 -283.300886) (xy 348.666155 -283.292578) (xy 348.618376 -283.27618) (xy 348.573948 -283.252142)
			(xy 348.534083 -283.221119) (xy 348.499869 -283.183956) (xy 348.472238 -283.141669) (xy 348.451945 -283.09541)
			(xy 348.439544 -283.046442) (xy 348.435372 -282.9961) (xy 347.166963 -282.9961) (xy 347.162792 -283.04644)
			(xy 347.150393 -283.095408) (xy 347.130103 -283.141666) (xy 347.102477 -283.183955) (xy 347.068267 -283.22112)
			(xy 347.028407 -283.252148) (xy 346.983984 -283.276192) (xy 346.936209 -283.292597) (xy 346.886386 -283.300916)
			(xy 346.86113 -283.30144) (xy 345.921076 -283.30144) (xy 345.895825 -283.300853) (xy 345.846011 -283.292537)
			(xy 345.798246 -283.276135) (xy 345.753831 -283.252096) (xy 345.713979 -283.221075) (xy 345.679775 -283.183918)
			(xy 345.652154 -283.141638) (xy 345.631868 -283.095388) (xy 345.619471 -283.04643) (xy 345.615301 -282.9961)
			(xy 126.480876 -282.9961) (xy 126.480901 -282.9964) (xy 126.476725 -283.046787) (xy 126.464312 -283.0958)
			(xy 126.444 -283.142101) (xy 126.416344 -283.184426) (xy 126.382098 -283.221622) (xy 126.342197 -283.252673)
			(xy 126.297728 -283.276732) (xy 126.249906 -283.293143) (xy 126.200034 -283.301459) (xy 126.174754 -283.301948)
			(xy 125.2347 -283.301948) (xy 125.209423 -283.301454) (xy 125.159557 -283.293133) (xy 125.111741 -283.276718)
			(xy 125.067279 -283.252656) (xy 125.027384 -283.221605) (xy 124.993144 -283.18441) (xy 124.965494 -283.142087)
			(xy 124.945186 -283.09579) (xy 124.932775 -283.046782) (xy 124.928601 -282.9964) (xy 123.660872 -282.9964)
			(xy 123.656698 -283.046773) (xy 123.644291 -283.095772) (xy 123.623989 -283.142061) (xy 123.596345 -283.184378)
			(xy 123.562114 -283.221568) (xy 123.52223 -283.252617) (xy 123.477779 -283.276678) (xy 123.429974 -283.293096)
			(xy 123.380119 -283.301423) (xy 123.354846 -283.301948) (xy 122.414792 -283.301948) (xy 122.389515 -283.301453)
			(xy 122.33965 -283.293131) (xy 122.291836 -283.276715) (xy 122.247375 -283.252653) (xy 122.207481 -283.221602)
			(xy 122.173242 -283.184408) (xy 122.145592 -283.142085) (xy 122.125285 -283.095789) (xy 122.112875 -283.046781)
			(xy 122.1087 -282.9964) (xy 120.840801 -282.9964) (xy 120.836625 -283.046784) (xy 120.824214 -283.095794)
			(xy 120.803905 -283.142092) (xy 120.776252 -283.184416) (xy 120.74201 -283.221611) (xy 120.702113 -283.252663)
			(xy 120.657648 -283.276723) (xy 120.60983 -283.293137) (xy 120.559962 -283.301456) (xy 120.534684 -283.301948)
			(xy 119.59463 -283.301948) (xy 119.569348 -283.301485) (xy 119.519474 -283.293167) (xy 119.47165 -283.276753)
			(xy 119.427179 -283.252691) (xy 119.387276 -283.221637) (xy 119.353029 -283.184438) (xy 119.325373 -283.142109)
			(xy 119.30506 -283.095806) (xy 119.292647 -283.04679) (xy 119.288471 -282.9964) (xy 118.020901 -282.9964)
			(xy 118.016725 -283.046785) (xy 118.004313 -283.095795) (xy 117.984004 -283.142094) (xy 117.95635 -283.184419)
			(xy 117.922107 -283.221614) (xy 117.882208 -283.252665) (xy 117.837743 -283.276726) (xy 117.789924 -283.293139)
			(xy 117.740055 -283.301457) (xy 117.714776 -283.301948) (xy 116.774722 -283.301948) (xy 116.749441 -283.301485)
			(xy 116.699568 -283.293166) (xy 116.651744 -283.276751) (xy 116.607275 -283.252688) (xy 116.567373 -283.221634)
			(xy 116.533127 -283.184435) (xy 116.505471 -283.142107) (xy 116.48516 -283.095804) (xy 116.472747 -283.046789)
			(xy 116.468571 -282.9964) (xy 107.687072 -282.9964) (xy 107.682898 -283.046774) (xy 107.67049 -283.095773)
			(xy 107.650188 -283.142063) (xy 107.622544 -283.18438) (xy 107.588312 -283.22157) (xy 107.548426 -283.252619)
			(xy 107.503975 -283.27668) (xy 107.456169 -283.293098) (xy 107.406313 -283.301423) (xy 107.38104 -283.301948)
			(xy 106.440986 -283.301948) (xy 106.415709 -283.301453) (xy 106.365846 -283.29313) (xy 106.318032 -283.276714)
			(xy 106.273572 -283.252651) (xy 106.233679 -283.2216) (xy 106.199441 -283.184406) (xy 106.171791 -283.142083)
			(xy 106.151485 -283.095788) (xy 106.139075 -283.046781) (xy 106.1349 -282.9964) (xy 104.867172 -282.9964)
			(xy 104.862998 -283.046774) (xy 104.85059 -283.095775) (xy 104.830287 -283.142065) (xy 104.802642 -283.184382)
			(xy 104.768409 -283.221573) (xy 104.728522 -283.252622) (xy 104.684069 -283.276683) (xy 104.636262 -283.293099)
			(xy 104.586405 -283.301424) (xy 104.561132 -283.301948) (xy 103.621078 -283.301948) (xy 103.595802 -283.301452)
			(xy 103.545939 -283.293128) (xy 103.498126 -283.276711) (xy 103.453668 -283.252649) (xy 103.413776 -283.221597)
			(xy 103.379539 -283.184403) (xy 103.35189 -283.142081) (xy 103.331584 -283.095786) (xy 103.319175 -283.04678)
			(xy 103.315 -282.9964) (xy 102.047272 -282.9964) (xy 102.043098 -283.046775) (xy 102.030689 -283.095776)
			(xy 102.010385 -283.142067) (xy 101.98274 -283.184385) (xy 101.948506 -283.221576) (xy 101.908618 -283.252624)
			(xy 101.864164 -283.276685) (xy 101.816356 -283.293101) (xy 101.766498 -283.301424) (xy 101.741224 -283.301948)
			(xy 100.80117 -283.301948) (xy 100.775894 -283.301452) (xy 100.726032 -283.293127) (xy 100.678221 -283.276709)
			(xy 100.633764 -283.252646) (xy 100.593873 -283.221594) (xy 100.559637 -283.1844) (xy 100.531989 -283.142079)
			(xy 100.511684 -283.095784) (xy 100.499275 -283.046779) (xy 100.4951 -282.9964) (xy 99.227201 -282.9964)
			(xy 99.223025 -283.046786) (xy 99.210613 -283.095798) (xy 99.190302 -283.142098) (xy 99.162646 -283.184423)
			(xy 99.128401 -283.221619) (xy 99.088501 -283.25267) (xy 99.044033 -283.27673) (xy 98.996212 -283.293142)
			(xy 98.946342 -283.301458) (xy 98.921062 -283.301948) (xy 97.981008 -283.301948) (xy 97.955728 -283.301484)
			(xy 97.905856 -283.293163) (xy 97.858035 -283.276747) (xy 97.813568 -283.252683) (xy 97.773668 -283.221629)
			(xy 97.739424 -283.184431) (xy 97.711769 -283.142103) (xy 97.691459 -283.095801) (xy 97.679047 -283.046788)
			(xy 97.674871 -282.9964) (xy 2.509012 -282.9964) (xy 2.509012 -283.8064) (xy 108.485161 -283.8064)
			(xy 108.489332 -283.756061) (xy 108.501732 -283.707095) (xy 108.522022 -283.660838) (xy 108.549649 -283.618552)
			(xy 108.583859 -283.581389) (xy 108.623719 -283.550364) (xy 108.668142 -283.526323) (xy 108.715916 -283.509921)
			(xy 108.765738 -283.501606) (xy 108.790994 -283.501084) (xy 109.731048 -283.501084) (xy 109.7563 -283.501625)
			(xy 109.806114 -283.509945) (xy 109.85388 -283.52635) (xy 109.898295 -283.550392) (xy 109.938147 -283.581416)
			(xy 109.97235 -283.618576) (xy 109.999971 -283.660858) (xy 110.020256 -283.707109) (xy 110.032653 -283.756068)
			(xy 110.036823 -283.8064) (xy 114.118832 -283.8064) (xy 114.123004 -283.756054) (xy 114.135406 -283.707082)
			(xy 114.155699 -283.660819) (xy 114.183331 -283.618527) (xy 114.217547 -283.581361) (xy 114.257413 -283.550333)
			(xy 114.301844 -283.52629) (xy 114.349625 -283.509889) (xy 114.399455 -283.501576) (xy 114.424714 -283.501084)
			(xy 115.364768 -283.501084) (xy 115.390027 -283.50159) (xy 115.439856 -283.5099) (xy 115.487638 -283.526299)
			(xy 115.532068 -283.55034) (xy 115.571936 -283.581366) (xy 115.606152 -283.618531) (xy 115.633784 -283.660822)
			(xy 115.654078 -283.707084) (xy 115.66648 -283.756055) (xy 115.670627 -283.8061) (xy 356.425052 -283.8061)
			(xy 356.429226 -283.75573) (xy 356.441632 -283.706734) (xy 356.461934 -283.660448) (xy 356.489576 -283.618134)
			(xy 356.523805 -283.580947) (xy 356.563688 -283.5499) (xy 356.608136 -283.525841) (xy 356.655939 -283.509425)
			(xy 356.705791 -283.501101) (xy 356.731062 -283.500576) (xy 357.671116 -283.500576) (xy 357.696395 -283.501023)
			(xy 357.746262 -283.509347) (xy 357.794079 -283.525765) (xy 357.838542 -283.549829) (xy 357.878438 -283.580883)
			(xy 357.912679 -283.61808) (xy 357.94033 -283.660406) (xy 357.960638 -283.706705) (xy 357.973049 -283.755715)
			(xy 357.977224 -283.8061) (xy 362.058752 -283.8061) (xy 362.062926 -283.755728) (xy 362.075334 -283.70673)
			(xy 362.095637 -283.660442) (xy 362.123281 -283.618128) (xy 362.157513 -283.58094) (xy 362.197398 -283.549894)
			(xy 362.24185 -283.525835) (xy 362.289655 -283.509421) (xy 362.33951 -283.501099) (xy 362.364782 -283.500576)
			(xy 363.304836 -283.500576) (xy 363.330114 -283.501025) (xy 363.379978 -283.509351) (xy 363.427793 -283.525771)
			(xy 363.472253 -283.549836) (xy 363.512146 -283.58089) (xy 363.546384 -283.618087) (xy 363.574033 -283.660411)
			(xy 363.594339 -283.706709) (xy 363.606749 -283.755717) (xy 363.610924 -283.8061) (xy 363.606749 -283.856483)
			(xy 363.594339 -283.905491) (xy 363.574033 -283.951789) (xy 363.546384 -283.994113) (xy 363.512146 -284.03131)
			(xy 363.472253 -284.062364) (xy 363.427793 -284.086429) (xy 363.379978 -284.102849) (xy 363.330114 -284.111175)
			(xy 363.304836 -284.1117) (xy 362.364782 -284.1117) (xy 362.33951 -284.111101) (xy 362.289655 -284.102779)
			(xy 362.24185 -284.086365) (xy 362.197398 -284.062306) (xy 362.157513 -284.03126) (xy 362.123281 -283.994072)
			(xy 362.095637 -283.951758) (xy 362.075334 -283.90547) (xy 362.062926 -283.856472) (xy 362.058752 -283.8061)
			(xy 357.977224 -283.8061) (xy 357.973049 -283.856485) (xy 357.960638 -283.905495) (xy 357.94033 -283.951794)
			(xy 357.912679 -283.99412) (xy 357.878438 -284.031317) (xy 357.838542 -284.062371) (xy 357.794079 -284.086435)
			(xy 357.746262 -284.102853) (xy 357.696395 -284.111177) (xy 357.671116 -284.1117) (xy 356.731062 -284.1117)
			(xy 356.705791 -284.111099) (xy 356.655939 -284.102775) (xy 356.608136 -284.086359) (xy 356.563688 -284.0623)
			(xy 356.523805 -284.031253) (xy 356.489576 -283.994066) (xy 356.461934 -283.951752) (xy 356.441632 -283.905466)
			(xy 356.429226 -283.85647) (xy 356.425052 -283.8061) (xy 115.670627 -283.8061) (xy 115.670652 -283.8064)
			(xy 115.66648 -283.856745) (xy 115.654078 -283.905716) (xy 115.633784 -283.951978) (xy 115.606152 -283.994269)
			(xy 115.571936 -284.031434) (xy 115.532068 -284.06246) (xy 115.487638 -284.086501) (xy 115.439856 -284.1029)
			(xy 115.390027 -284.11121) (xy 115.364768 -284.1117) (xy 114.424714 -284.1117) (xy 114.399455 -284.111224)
			(xy 114.349625 -284.102911) (xy 114.301844 -284.08651) (xy 114.257413 -284.062467) (xy 114.217547 -284.031439)
			(xy 114.183331 -283.994273) (xy 114.155699 -283.951981) (xy 114.135406 -283.905718) (xy 114.123004 -283.856746)
			(xy 114.118832 -283.8064) (xy 110.036823 -283.8064) (xy 110.032653 -283.856732) (xy 110.020256 -283.905691)
			(xy 109.999971 -283.951942) (xy 109.97235 -283.994224) (xy 109.938147 -284.031384) (xy 109.898295 -284.062408)
			(xy 109.85388 -284.08645) (xy 109.806114 -284.102855) (xy 109.7563 -284.111175) (xy 109.731048 -284.1117)
			(xy 108.790994 -284.1117) (xy 108.765738 -284.111194) (xy 108.715916 -284.102879) (xy 108.668142 -284.086477)
			(xy 108.623719 -284.062436) (xy 108.583859 -284.031411) (xy 108.549649 -283.994248) (xy 108.522022 -283.951962)
			(xy 108.501732 -283.905705) (xy 108.489332 -283.856739) (xy 108.485161 -283.8064) (xy 2.509012 -283.8064)
			(xy 2.509012 -284.6164) (xy 97.674883 -284.6164) (xy 97.679059 -284.566014) (xy 97.69147 -284.517003)
			(xy 97.71178 -284.470702) (xy 97.739433 -284.428377) (xy 97.773676 -284.39118) (xy 97.813574 -284.360127)
			(xy 97.85804 -284.336064) (xy 97.905859 -284.319649) (xy 97.955729 -284.311328) (xy 97.981008 -284.310836)
			(xy 98.921062 -284.310836) (xy 98.946343 -284.31133) (xy 98.996215 -284.319647) (xy 99.044038 -284.336059)
			(xy 99.088508 -284.36012) (xy 99.12841 -284.391172) (xy 99.162656 -284.428369) (xy 99.190312 -284.470696)
			(xy 99.210624 -284.516998) (xy 99.223037 -284.566012) (xy 99.227213 -284.6164) (xy 100.495112 -284.6164)
			(xy 100.499287 -284.566023) (xy 100.511695 -284.51702) (xy 100.532 -284.470727) (xy 100.559646 -284.428407)
			(xy 100.593881 -284.391215) (xy 100.63377 -284.360164) (xy 100.678226 -284.336102) (xy 100.726035 -284.319685)
			(xy 100.775895 -284.31136) (xy 100.80117 -284.310836) (xy 101.741224 -284.310836) (xy 101.766499 -284.311364)
			(xy 101.816359 -284.319688) (xy 101.864169 -284.336104) (xy 101.908625 -284.360165) (xy 101.948514 -284.391216)
			(xy 101.982749 -284.428408) (xy 102.010396 -284.470727) (xy 102.030701 -284.51702) (xy 102.043109 -284.566023)
			(xy 102.047284 -284.6164) (xy 103.315012 -284.6164) (xy 103.319187 -284.566022) (xy 103.331596 -284.517018)
			(xy 103.351901 -284.470725) (xy 103.379548 -284.428404) (xy 103.413784 -284.391212) (xy 103.453674 -284.360161)
			(xy 103.498131 -284.3361) (xy 103.545942 -284.319683) (xy 103.595803 -284.31136) (xy 103.621078 -284.310836)
			(xy 104.561132 -284.310836) (xy 104.586406 -284.311364) (xy 104.636265 -284.319689) (xy 104.684074 -284.336106)
			(xy 104.728529 -284.360168) (xy 104.768417 -284.391218) (xy 104.802651 -284.42841) (xy 104.830297 -284.470729)
			(xy 104.850601 -284.517021) (xy 104.863009 -284.566024) (xy 104.867184 -284.6164) (xy 106.134912 -284.6164)
			(xy 106.139087 -284.566021) (xy 106.151496 -284.517016) (xy 106.171802 -284.470722) (xy 106.19945 -284.428402)
			(xy 106.233687 -284.391209) (xy 106.273579 -284.360159) (xy 106.318037 -284.336097) (xy 106.365849 -284.319682)
			(xy 106.41571 -284.311359) (xy 106.440986 -284.310836) (xy 107.38104 -284.310836) (xy 107.406314 -284.311365)
			(xy 107.456172 -284.319691) (xy 107.503979 -284.336109) (xy 107.548433 -284.360171) (xy 107.58832 -284.391221)
			(xy 107.622553 -284.428413) (xy 107.650198 -284.470731) (xy 107.670502 -284.517023) (xy 107.68291 -284.566024)
			(xy 107.687084 -284.6164) (xy 116.468583 -284.6164) (xy 116.472759 -284.566013) (xy 116.485171 -284.517)
			(xy 116.505482 -284.470699) (xy 116.533137 -284.428372) (xy 116.567381 -284.391175) (xy 116.607282 -284.360122)
			(xy 116.651749 -284.33606) (xy 116.699571 -284.319646) (xy 116.749442 -284.311327) (xy 116.774722 -284.310836)
			(xy 117.714776 -284.310836) (xy 117.740056 -284.311331) (xy 117.789927 -284.319649) (xy 117.837748 -284.336063)
			(xy 117.882215 -284.360125) (xy 117.922115 -284.391177) (xy 117.95636 -284.428374) (xy 117.984014 -284.4707)
			(xy 118.004325 -284.517001) (xy 118.016737 -284.566013) (xy 118.020913 -284.6164) (xy 119.288483 -284.6164)
			(xy 119.292659 -284.566012) (xy 119.305072 -284.516998) (xy 119.325383 -284.470696) (xy 119.353039 -284.428369)
			(xy 119.387285 -284.391172) (xy 119.427186 -284.360119) (xy 119.471655 -284.336058) (xy 119.519477 -284.319644)
			(xy 119.569349 -284.311327) (xy 119.59463 -284.310836) (xy 120.534684 -284.310836) (xy 120.559963 -284.311332)
			(xy 120.609833 -284.319651) (xy 120.657653 -284.336066) (xy 120.702119 -284.360127) (xy 120.742018 -284.39118)
			(xy 120.776262 -284.428376) (xy 120.803915 -284.470702) (xy 120.824225 -284.517002) (xy 120.836637 -284.566014)
			(xy 120.840813 -284.6164) (xy 122.108712 -284.6164) (xy 122.112887 -284.56602) (xy 122.125297 -284.517015)
			(xy 122.145603 -284.470721) (xy 122.173252 -284.4284) (xy 122.207489 -284.391207) (xy 122.247382 -284.360157)
			(xy 122.291841 -284.336096) (xy 122.339653 -284.31968) (xy 122.389516 -284.311359) (xy 122.414792 -284.310836)
			(xy 123.354846 -284.310836) (xy 123.38012 -284.311366) (xy 123.429977 -284.319692) (xy 123.477783 -284.336111)
			(xy 123.522236 -284.360173) (xy 123.562123 -284.391223) (xy 123.596355 -284.428415) (xy 123.623999 -284.470733)
			(xy 123.644302 -284.517024) (xy 123.65671 -284.566025) (xy 123.660884 -284.6164) (xy 124.928613 -284.6164)
			(xy 124.932787 -284.56602) (xy 124.945197 -284.517014) (xy 124.965504 -284.470718) (xy 124.993154 -284.428397)
			(xy 125.027393 -284.391204) (xy 125.067286 -284.360154) (xy 125.111746 -284.336093) (xy 125.15956 -284.319679)
			(xy 125.209423 -284.311358) (xy 125.2347 -284.310836) (xy 126.174754 -284.310836) (xy 126.200035 -284.311329)
			(xy 126.249909 -284.319645) (xy 126.297733 -284.336057) (xy 126.342203 -284.360117) (xy 126.382107 -284.391169)
			(xy 126.416354 -284.428366) (xy 126.444011 -284.470694) (xy 126.464323 -284.516996) (xy 126.476737 -284.566011)
			(xy 126.480888 -284.6161) (xy 345.615313 -284.6161) (xy 345.619483 -284.565772) (xy 345.63188 -284.516816)
			(xy 345.652165 -284.470568) (xy 345.679785 -284.42829) (xy 345.713987 -284.391134) (xy 345.753838 -284.360114)
			(xy 345.798251 -284.336076) (xy 345.846014 -284.319675) (xy 345.895826 -284.311359) (xy 345.921076 -284.310836)
			(xy 346.86113 -284.310836) (xy 346.886387 -284.311272) (xy 346.936213 -284.31959) (xy 346.983989 -284.335996)
			(xy 347.028414 -284.360042) (xy 347.068275 -284.391071) (xy 347.102487 -284.428237) (xy 347.130114 -284.470528)
			(xy 347.150404 -284.516788) (xy 347.162804 -284.565758) (xy 347.166976 -284.6161) (xy 348.435384 -284.6161)
			(xy 348.439556 -284.56576) (xy 348.451957 -284.516794) (xy 348.472249 -284.470537) (xy 348.499878 -284.428251)
			(xy 348.534091 -284.39109) (xy 348.573955 -284.360068) (xy 348.618381 -284.336031) (xy 348.666158 -284.319634)
			(xy 348.715982 -284.311326) (xy 348.741238 -284.310836) (xy 349.681292 -284.310836) (xy 349.706554 -284.31124)
			(xy 349.756388 -284.319555) (xy 349.804175 -284.335959) (xy 349.848609 -284.360005) (xy 349.88848 -284.391036)
			(xy 349.922699 -284.428207) (xy 349.950333 -284.470504) (xy 349.970629 -284.516772) (xy 349.983032 -284.565749)
			(xy 349.987204 -284.6161) (xy 351.255284 -284.6161) (xy 351.259456 -284.56576) (xy 351.271857 -284.516793)
			(xy 351.29215 -284.470535) (xy 351.31978 -284.428249) (xy 351.353994 -284.391087) (xy 351.393859 -284.360065)
			(xy 351.438286 -284.336028) (xy 351.486064 -284.319632) (xy 351.535889 -284.311325) (xy 351.561146 -284.310836)
			(xy 352.5012 -284.310836) (xy 352.526459 -284.311269) (xy 352.576288 -284.319584) (xy 352.624069 -284.335987)
			(xy 352.668498 -284.360031) (xy 352.708364 -284.39106) (xy 352.742579 -284.428227) (xy 352.770209 -284.470519)
			(xy 352.790502 -284.516782) (xy 352.802904 -284.565755) (xy 352.807076 -284.6161) (xy 354.075313 -284.6161)
			(xy 354.079483 -284.565774) (xy 354.091878 -284.51682) (xy 354.112161 -284.470574) (xy 354.139779 -284.428297)
			(xy 354.173978 -284.391142) (xy 354.213826 -284.360121) (xy 354.258236 -284.336082) (xy 354.305996 -284.31968)
			(xy 354.355805 -284.311361) (xy 354.381054 -284.310836) (xy 355.321108 -284.310836) (xy 355.346367 -284.31127)
			(xy 355.396195 -284.319586) (xy 355.443974 -284.33599) (xy 355.488402 -284.360034) (xy 355.528267 -284.391063)
			(xy 355.562481 -284.42823) (xy 355.590111 -284.470522) (xy 355.610403 -284.516784) (xy 355.622804 -284.565755)
			(xy 355.626976 -284.6161) (xy 364.409013 -284.6161) (xy 364.413183 -284.56577) (xy 364.425581 -284.516813)
			(xy 364.445867 -284.470564) (xy 364.473488 -284.428285) (xy 364.507692 -284.391129) (xy 364.547545 -284.360109)
			(xy 364.59196 -284.336071) (xy 364.639726 -284.319672) (xy 364.689539 -284.311358) (xy 364.71479 -284.310836)
			(xy 365.654844 -284.310836) (xy 365.680101 -284.311273) (xy 365.729924 -284.319593) (xy 365.777699 -284.336)
			(xy 365.822121 -284.360047) (xy 365.861981 -284.391076) (xy 365.89619 -284.428242) (xy 365.923816 -284.470532)
			(xy 365.944105 -284.516791) (xy 365.956505 -284.565759) (xy 365.960676 -284.6161) (xy 367.228913 -284.6161)
			(xy 367.233084 -284.565769) (xy 367.245481 -284.516812) (xy 367.265768 -284.470562) (xy 367.293391 -284.428282)
			(xy 367.327595 -284.391126) (xy 367.367449 -284.360106) (xy 367.411865 -284.336069) (xy 367.459632 -284.31967)
			(xy 367.509446 -284.311358) (xy 367.534698 -284.310836) (xy 368.474752 -284.310836) (xy 368.500016 -284.311237)
			(xy 368.549856 -284.319547) (xy 368.597648 -284.335947) (xy 368.642088 -284.359991) (xy 368.681965 -284.391022)
			(xy 368.716189 -284.428194) (xy 368.743827 -284.470492) (xy 368.764126 -284.516764) (xy 368.776531 -284.565745)
			(xy 368.780704 -284.6161) (xy 370.049113 -284.6161) (xy 370.053283 -284.565773) (xy 370.065679 -284.516819)
			(xy 370.085962 -284.470573) (xy 370.113581 -284.428295) (xy 370.147781 -284.391139) (xy 370.187629 -284.360119)
			(xy 370.23204 -284.33608) (xy 370.279801 -284.319678) (xy 370.32961 -284.311361) (xy 370.35486 -284.310836)
			(xy 371.294914 -284.310836) (xy 371.320172 -284.31127) (xy 371.369999 -284.319587) (xy 371.417778 -284.335992)
			(xy 371.462205 -284.360036) (xy 371.502069 -284.391065) (xy 371.536282 -284.428232) (xy 371.563912 -284.470523)
			(xy 371.584203 -284.516785) (xy 371.596604 -284.565756) (xy 371.600776 -284.6161) (xy 372.869013 -284.6161)
			(xy 372.873183 -284.565772) (xy 372.885579 -284.516818) (xy 372.905864 -284.47057) (xy 372.933483 -284.428292)
			(xy 372.967684 -284.391137) (xy 373.007533 -284.360116) (xy 373.051945 -284.336078) (xy 373.099708 -284.319677)
			(xy 373.149518 -284.31136) (xy 373.174768 -284.310836) (xy 374.114822 -284.310836) (xy 374.14008 -284.311271)
			(xy 374.189906 -284.319589) (xy 374.237684 -284.335994) (xy 374.28211 -284.360039) (xy 374.321972 -284.391068)
			(xy 374.356184 -284.428235) (xy 374.383813 -284.470525) (xy 374.404104 -284.516787) (xy 374.416504 -284.565757)
			(xy 374.420676 -284.6161) (xy 374.416504 -284.666443) (xy 374.404104 -284.715413) (xy 374.383813 -284.761675)
			(xy 374.356184 -284.803965) (xy 374.321972 -284.841132) (xy 374.28211 -284.872161) (xy 374.237684 -284.896206)
			(xy 374.189906 -284.912611) (xy 374.14008 -284.920929) (xy 374.114822 -284.921452) (xy 373.174768 -284.921452)
			(xy 373.149518 -284.92084) (xy 373.099708 -284.912523) (xy 373.051945 -284.896122) (xy 373.007533 -284.872084)
			(xy 372.967684 -284.841063) (xy 372.933483 -284.803908) (xy 372.905864 -284.76163) (xy 372.885579 -284.715382)
			(xy 372.873183 -284.666428) (xy 372.869013 -284.6161) (xy 371.600776 -284.6161) (xy 371.596604 -284.666444)
			(xy 371.584203 -284.715415) (xy 371.563912 -284.761677) (xy 371.536282 -284.803968) (xy 371.502069 -284.841135)
			(xy 371.462205 -284.872164) (xy 371.417778 -284.896208) (xy 371.369999 -284.912613) (xy 371.320172 -284.92093)
			(xy 371.294914 -284.921452) (xy 370.35486 -284.921452) (xy 370.32961 -284.920839) (xy 370.279801 -284.912522)
			(xy 370.23204 -284.89612) (xy 370.187629 -284.872081) (xy 370.147781 -284.841061) (xy 370.113581 -284.803905)
			(xy 370.085962 -284.761627) (xy 370.065679 -284.715381) (xy 370.053283 -284.666427) (xy 370.049113 -284.6161)
			(xy 368.780704 -284.6161) (xy 368.776531 -284.666455) (xy 368.764126 -284.715436) (xy 368.743827 -284.761708)
			(xy 368.716189 -284.804006) (xy 368.681965 -284.841178) (xy 368.642088 -284.872209) (xy 368.597648 -284.896253)
			(xy 368.549856 -284.912653) (xy 368.500016 -284.920963) (xy 368.474752 -284.921452) (xy 367.534698 -284.921452)
			(xy 367.509446 -284.920842) (xy 367.459632 -284.91253) (xy 367.411865 -284.896131) (xy 367.367449 -284.872094)
			(xy 367.327595 -284.841074) (xy 367.293391 -284.803918) (xy 367.265768 -284.761638) (xy 367.245481 -284.715388)
			(xy 367.233084 -284.666431) (xy 367.228913 -284.6161) (xy 365.960676 -284.6161) (xy 365.956505 -284.666441)
			(xy 365.944105 -284.715409) (xy 365.923816 -284.761668) (xy 365.89619 -284.803958) (xy 365.861981 -284.841124)
			(xy 365.822121 -284.872153) (xy 365.777699 -284.8962) (xy 365.729924 -284.912607) (xy 365.680101 -284.920927)
			(xy 365.654844 -284.921452) (xy 364.71479 -284.921452) (xy 364.689539 -284.920842) (xy 364.639726 -284.912528)
			(xy 364.59196 -284.896129) (xy 364.547545 -284.872091) (xy 364.507692 -284.841071) (xy 364.473489 -284.803915)
			(xy 364.445867 -284.761636) (xy 364.425581 -284.715387) (xy 364.413183 -284.66643) (xy 364.409013 -284.6161)
			(xy 355.626976 -284.6161) (xy 355.622804 -284.666445) (xy 355.610403 -284.715416) (xy 355.590111 -284.761678)
			(xy 355.562481 -284.80397) (xy 355.528267 -284.841137) (xy 355.488402 -284.872166) (xy 355.443974 -284.89621)
			(xy 355.396195 -284.912614) (xy 355.346367 -284.92093) (xy 355.321108 -284.921452) (xy 354.381054 -284.921452)
			(xy 354.355805 -284.920839) (xy 354.305996 -284.91252) (xy 354.258236 -284.896118) (xy 354.213826 -284.872079)
			(xy 354.173978 -284.841058) (xy 354.139779 -284.803903) (xy 354.112161 -284.761626) (xy 354.091878 -284.71538)
			(xy 354.079483 -284.666426) (xy 354.075313 -284.6161) (xy 352.807076 -284.6161) (xy 352.802904 -284.666445)
			(xy 352.790502 -284.715418) (xy 352.770209 -284.761681) (xy 352.742579 -284.803973) (xy 352.708364 -284.84114)
			(xy 352.668498 -284.872169) (xy 352.624069 -284.896213) (xy 352.576288 -284.912616) (xy 352.526459 -284.920931)
			(xy 352.5012 -284.921452) (xy 351.561146 -284.921452) (xy 351.535889 -284.920875) (xy 351.486064 -284.912568)
			(xy 351.438286 -284.896172) (xy 351.393859 -284.872135) (xy 351.353994 -284.841113) (xy 351.31978 -284.803951)
			(xy 351.29215 -284.761665) (xy 351.271857 -284.715407) (xy 351.259456 -284.66644) (xy 351.255284 -284.6161)
			(xy 349.987204 -284.6161) (xy 349.983032 -284.666451) (xy 349.970629 -284.715428) (xy 349.950333 -284.761696)
			(xy 349.922699 -284.803993) (xy 349.88848 -284.841164) (xy 349.848609 -284.872195) (xy 349.804175 -284.896241)
			(xy 349.756388 -284.912645) (xy 349.706554 -284.92096) (xy 349.681292 -284.921452) (xy 348.741238 -284.921452)
			(xy 348.715982 -284.920874) (xy 348.666158 -284.912566) (xy 348.618381 -284.896169) (xy 348.573955 -284.872132)
			(xy 348.534091 -284.84111) (xy 348.499878 -284.803949) (xy 348.472249 -284.761663) (xy 348.451957 -284.715406)
			(xy 348.439556 -284.66644) (xy 348.435384 -284.6161) (xy 347.166976 -284.6161) (xy 347.162804 -284.666442)
			(xy 347.150404 -284.715412) (xy 347.130114 -284.761672) (xy 347.102487 -284.803963) (xy 347.068275 -284.841129)
			(xy 347.028414 -284.872158) (xy 346.983989 -284.896204) (xy 346.936213 -284.91261) (xy 346.886387 -284.920928)
			(xy 346.86113 -284.921452) (xy 345.921076 -284.921452) (xy 345.895826 -284.920841) (xy 345.846014 -284.912525)
			(xy 345.798251 -284.896124) (xy 345.753838 -284.872086) (xy 345.713987 -284.841066) (xy 345.679785 -284.80391)
			(xy 345.652165 -284.761632) (xy 345.63188 -284.715384) (xy 345.619483 -284.666428) (xy 345.615313 -284.6161)
			(xy 126.480888 -284.6161) (xy 126.480913 -284.6164) (xy 126.476737 -284.666789) (xy 126.464323 -284.715804)
			(xy 126.444011 -284.762106) (xy 126.416354 -284.804434) (xy 126.382107 -284.841631) (xy 126.342203 -284.872683)
			(xy 126.297733 -284.896743) (xy 126.249909 -284.913155) (xy 126.200035 -284.921471) (xy 126.174754 -284.92196)
			(xy 125.2347 -284.92196) (xy 125.209423 -284.921442) (xy 125.15956 -284.913121) (xy 125.111746 -284.896707)
			(xy 125.067286 -284.872646) (xy 125.027393 -284.841596) (xy 124.993154 -284.804403) (xy 124.965504 -284.762082)
			(xy 124.945197 -284.715786) (xy 124.932787 -284.66678) (xy 124.928613 -284.6164) (xy 123.660884 -284.6164)
			(xy 123.65671 -284.666775) (xy 123.644302 -284.715776) (xy 123.623999 -284.762067) (xy 123.596355 -284.804385)
			(xy 123.562123 -284.841577) (xy 123.522236 -284.872627) (xy 123.477783 -284.896689) (xy 123.429977 -284.913108)
			(xy 123.38012 -284.921434) (xy 123.354846 -284.92196) (xy 122.414792 -284.92196) (xy 122.389516 -284.921441)
			(xy 122.339653 -284.91312) (xy 122.291841 -284.896704) (xy 122.247382 -284.872643) (xy 122.207489 -284.841593)
			(xy 122.173252 -284.8044) (xy 122.145603 -284.762079) (xy 122.125297 -284.715785) (xy 122.112887 -284.66678)
			(xy 122.108712 -284.6164) (xy 120.840813 -284.6164) (xy 120.836637 -284.666786) (xy 120.824225 -284.715798)
			(xy 120.803915 -284.762098) (xy 120.776262 -284.804424) (xy 120.742018 -284.84162) (xy 120.702119 -284.872673)
			(xy 120.657653 -284.896734) (xy 120.609833 -284.913149) (xy 120.559963 -284.921468) (xy 120.534684 -284.92196)
			(xy 119.59463 -284.92196) (xy 119.569349 -284.921473) (xy 119.519477 -284.913156) (xy 119.471655 -284.896742)
			(xy 119.427186 -284.872681) (xy 119.387285 -284.841628) (xy 119.353039 -284.804431) (xy 119.325383 -284.762104)
			(xy 119.305072 -284.715802) (xy 119.292659 -284.666788) (xy 119.288483 -284.6164) (xy 118.020913 -284.6164)
			(xy 118.016737 -284.666787) (xy 118.004325 -284.715799) (xy 117.984014 -284.7621) (xy 117.95636 -284.804426)
			(xy 117.922115 -284.841623) (xy 117.882215 -284.872675) (xy 117.837748 -284.896737) (xy 117.789927 -284.913151)
			(xy 117.740056 -284.921469) (xy 117.714776 -284.92196) (xy 116.774722 -284.92196) (xy 116.749442 -284.921473)
			(xy 116.699571 -284.913154) (xy 116.651749 -284.89674) (xy 116.607282 -284.872678) (xy 116.567381 -284.841625)
			(xy 116.533137 -284.804428) (xy 116.505482 -284.762101) (xy 116.485171 -284.7158) (xy 116.472759 -284.666787)
			(xy 116.468583 -284.6164) (xy 107.687084 -284.6164) (xy 107.68291 -284.666776) (xy 107.670502 -284.715777)
			(xy 107.650198 -284.762069) (xy 107.622553 -284.804387) (xy 107.58832 -284.841579) (xy 107.548433 -284.872629)
			(xy 107.503979 -284.896691) (xy 107.456172 -284.913109) (xy 107.406314 -284.921435) (xy 107.38104 -284.92196)
			(xy 106.440986 -284.92196) (xy 106.41571 -284.921441) (xy 106.365849 -284.913118) (xy 106.318037 -284.896703)
			(xy 106.273579 -284.872641) (xy 106.233687 -284.841591) (xy 106.19945 -284.804398) (xy 106.171802 -284.762078)
			(xy 106.151496 -284.715784) (xy 106.139087 -284.666779) (xy 106.134912 -284.6164) (xy 104.867184 -284.6164)
			(xy 104.863009 -284.666776) (xy 104.850601 -284.715779) (xy 104.830297 -284.762071) (xy 104.802651 -284.80439)
			(xy 104.768417 -284.841582) (xy 104.728529 -284.872632) (xy 104.684074 -284.896694) (xy 104.636265 -284.913111)
			(xy 104.586406 -284.921436) (xy 104.561132 -284.92196) (xy 103.621078 -284.92196) (xy 103.595803 -284.92144)
			(xy 103.545942 -284.913117) (xy 103.498131 -284.8967) (xy 103.453674 -284.872639) (xy 103.413784 -284.841588)
			(xy 103.379548 -284.804396) (xy 103.351901 -284.762075) (xy 103.331596 -284.715782) (xy 103.319187 -284.666778)
			(xy 103.315012 -284.6164) (xy 102.047284 -284.6164) (xy 102.043109 -284.666777) (xy 102.030701 -284.71578)
			(xy 102.010396 -284.762073) (xy 101.982749 -284.804392) (xy 101.948514 -284.841584) (xy 101.908625 -284.872635)
			(xy 101.864169 -284.896696) (xy 101.816359 -284.913112) (xy 101.766499 -284.921436) (xy 101.741224 -284.92196)
			(xy 100.80117 -284.92196) (xy 100.775895 -284.92144) (xy 100.726035 -284.913115) (xy 100.678226 -284.896698)
			(xy 100.63377 -284.872636) (xy 100.593881 -284.841585) (xy 100.559646 -284.804393) (xy 100.532 -284.762073)
			(xy 100.511695 -284.71578) (xy 100.499287 -284.666777) (xy 100.495112 -284.6164) (xy 99.227213 -284.6164)
			(xy 99.223037 -284.666788) (xy 99.210624 -284.715802) (xy 99.190312 -284.762104) (xy 99.162656 -284.804431)
			(xy 99.12841 -284.841628) (xy 99.088508 -284.87268) (xy 99.044038 -284.896741) (xy 98.996215 -284.913153)
			(xy 98.946343 -284.92147) (xy 98.921062 -284.92196) (xy 97.981008 -284.92196) (xy 97.955729 -284.921472)
			(xy 97.905859 -284.913151) (xy 97.85804 -284.896736) (xy 97.813574 -284.872673) (xy 97.773676 -284.84162)
			(xy 97.739433 -284.804423) (xy 97.71178 -284.762098) (xy 97.69147 -284.715797) (xy 97.679059 -284.666786)
			(xy 97.674883 -284.6164) (xy 2.509012 -284.6164) (xy 2.509012 -285.4264) (xy 108.485173 -285.4264)
			(xy 108.489344 -285.376063) (xy 108.501743 -285.327099) (xy 108.522032 -285.280844) (xy 108.549658 -285.238559)
			(xy 108.583867 -285.201398) (xy 108.623725 -285.170374) (xy 108.668147 -285.146334) (xy 108.715919 -285.129932)
			(xy 108.765739 -285.121618) (xy 108.790994 -285.121096) (xy 109.731048 -285.121096) (xy 109.756301 -285.121613)
			(xy 109.806117 -285.129933) (xy 109.853885 -285.146339) (xy 109.898301 -285.170382) (xy 109.938155 -285.201407)
			(xy 109.972359 -285.238568) (xy 109.999981 -285.280852) (xy 110.020267 -285.327105) (xy 110.032665 -285.376066)
			(xy 110.036835 -285.4264) (xy 114.118844 -285.4264) (xy 114.123016 -285.376056) (xy 114.135417 -285.327086)
			(xy 114.15571 -285.280825) (xy 114.18334 -285.238535) (xy 114.217555 -285.201369) (xy 114.25742 -285.170343)
			(xy 114.301849 -285.146301) (xy 114.349628 -285.1299) (xy 114.399456 -285.121588) (xy 114.424714 -285.121096)
			(xy 115.364768 -285.121096) (xy 115.390028 -285.121578) (xy 115.439859 -285.129889) (xy 115.487643 -285.146288)
			(xy 115.532075 -285.17033) (xy 115.571944 -285.201357) (xy 115.606161 -285.238524) (xy 115.633795 -285.280816)
			(xy 115.654089 -285.32708) (xy 115.666492 -285.376053) (xy 115.670639 -285.4261) (xy 356.425064 -285.4261)
			(xy 356.429238 -285.375732) (xy 356.441644 -285.326738) (xy 356.461944 -285.280454) (xy 356.489585 -285.238142)
			(xy 356.523813 -285.200956) (xy 356.563694 -285.16991) (xy 356.608141 -285.145852) (xy 356.655942 -285.129437)
			(xy 356.705792 -285.121113) (xy 356.731062 -285.120588) (xy 357.671116 -285.120588) (xy 357.696396 -285.121011)
			(xy 357.746265 -285.129335) (xy 357.794084 -285.145754) (xy 357.838549 -285.169819) (xy 357.878446 -285.200875)
			(xy 357.912688 -285.238073) (xy 357.940341 -285.2804) (xy 357.960649 -285.326701) (xy 357.97306 -285.375713)
			(xy 357.977236 -285.4261) (xy 362.058764 -285.4261) (xy 362.062938 -285.37573) (xy 362.075345 -285.326734)
			(xy 362.095647 -285.280448) (xy 362.12329 -285.238135) (xy 362.157521 -285.200949) (xy 362.197405 -285.169904)
			(xy 362.241855 -285.145846) (xy 362.289658 -285.129433) (xy 362.339511 -285.121111) (xy 362.364782 -285.120588)
			(xy 363.304836 -285.120588) (xy 363.330115 -285.121013) (xy 363.379981 -285.12934) (xy 363.427798 -285.14576)
			(xy 363.472259 -285.169826) (xy 363.512154 -285.200882) (xy 363.546393 -285.23808) (xy 363.574044 -285.280406)
			(xy 363.594351 -285.326705) (xy 363.606761 -285.375716) (xy 363.610936 -285.4261) (xy 363.606761 -285.476485)
			(xy 363.594351 -285.525495) (xy 363.574044 -285.571794) (xy 363.546393 -285.61412) (xy 363.512154 -285.651318)
			(xy 363.472259 -285.682374) (xy 363.427798 -285.70644) (xy 363.379981 -285.72286) (xy 363.330115 -285.731187)
			(xy 363.304836 -285.731712) (xy 362.364782 -285.731712) (xy 362.339511 -285.731089) (xy 362.289658 -285.722767)
			(xy 362.241855 -285.706354) (xy 362.197405 -285.682296) (xy 362.157521 -285.651251) (xy 362.12329 -285.614065)
			(xy 362.095647 -285.571752) (xy 362.075345 -285.525466) (xy 362.062938 -285.47647) (xy 362.058764 -285.4261)
			(xy 357.977236 -285.4261) (xy 357.97306 -285.476487) (xy 357.960649 -285.525499) (xy 357.940341 -285.5718)
			(xy 357.912688 -285.614127) (xy 357.878446 -285.651325) (xy 357.838549 -285.682381) (xy 357.794084 -285.706446)
			(xy 357.746265 -285.722865) (xy 357.696396 -285.731189) (xy 357.671116 -285.731712) (xy 356.731062 -285.731712)
			(xy 356.705792 -285.731087) (xy 356.655942 -285.722763) (xy 356.608141 -285.706348) (xy 356.563694 -285.68229)
			(xy 356.523813 -285.651244) (xy 356.489585 -285.614058) (xy 356.461944 -285.571746) (xy 356.441644 -285.525462)
			(xy 356.429238 -285.476468) (xy 356.425064 -285.4261) (xy 115.670639 -285.4261) (xy 115.670664 -285.4264)
			(xy 115.666492 -285.476747) (xy 115.654089 -285.52572) (xy 115.633795 -285.571984) (xy 115.606161 -285.614276)
			(xy 115.571944 -285.651443) (xy 115.532075 -285.68247) (xy 115.487643 -285.706512) (xy 115.439859 -285.722911)
			(xy 115.390028 -285.731222) (xy 115.364768 -285.731712) (xy 114.424714 -285.731712) (xy 114.399456 -285.731212)
			(xy 114.349628 -285.7229) (xy 114.301849 -285.706499) (xy 114.25742 -285.682457) (xy 114.217555 -285.651431)
			(xy 114.18334 -285.614265) (xy 114.15571 -285.571975) (xy 114.135417 -285.525714) (xy 114.123016 -285.476744)
			(xy 114.118844 -285.4264) (xy 110.036835 -285.4264) (xy 110.032665 -285.476734) (xy 110.020267 -285.525695)
			(xy 109.999981 -285.571948) (xy 109.972359 -285.614232) (xy 109.938155 -285.651393) (xy 109.898301 -285.682418)
			(xy 109.853885 -285.706461) (xy 109.806117 -285.722867) (xy 109.756301 -285.731187) (xy 109.731048 -285.731712)
			(xy 108.790994 -285.731712) (xy 108.765739 -285.731182) (xy 108.715919 -285.722868) (xy 108.668147 -285.706466)
			(xy 108.623725 -285.682426) (xy 108.583867 -285.651402) (xy 108.549658 -285.614241) (xy 108.522032 -285.571956)
			(xy 108.501743 -285.525701) (xy 108.489344 -285.476737) (xy 108.485173 -285.4264) (xy 2.509012 -285.4264)
			(xy 2.509012 -286.2364) (xy 100.495124 -286.2364) (xy 100.499298 -286.186025) (xy 100.511706 -286.137023)
			(xy 100.53201 -286.090733) (xy 100.559656 -286.048415) (xy 100.593889 -286.011224) (xy 100.633777 -285.980174)
			(xy 100.678231 -285.956113) (xy 100.726038 -285.939697) (xy 100.775896 -285.931372) (xy 100.80117 -285.930848)
			(xy 101.741224 -285.930848) (xy 101.7665 -285.931352) (xy 101.816362 -285.939676) (xy 101.864173 -285.956093)
			(xy 101.908631 -285.980155) (xy 101.948522 -286.011207) (xy 101.982759 -286.0484) (xy 102.010407 -286.090721)
			(xy 102.030712 -286.137016) (xy 102.043121 -286.186021) (xy 102.047296 -286.2364) (xy 103.315024 -286.2364)
			(xy 103.319199 -286.186024) (xy 103.331607 -286.137022) (xy 103.351911 -286.09073) (xy 103.379558 -286.048412)
			(xy 103.413792 -286.011221) (xy 103.453681 -285.980171) (xy 103.498136 -285.956111) (xy 103.545945 -285.939695)
			(xy 103.595804 -285.931372) (xy 103.621078 -285.930848) (xy 104.561132 -285.930848) (xy 104.586407 -285.931352)
			(xy 104.636268 -285.939678) (xy 104.684079 -285.956095) (xy 104.728535 -285.980158) (xy 104.768425 -286.01121)
			(xy 104.802661 -286.048403) (xy 104.830308 -286.090724) (xy 104.850613 -286.137017) (xy 104.863021 -286.186022)
			(xy 104.867196 -286.2364) (xy 106.134924 -286.2364) (xy 106.139099 -286.186023) (xy 106.151508 -286.13702)
			(xy 106.171813 -286.090728) (xy 106.19946 -286.048409) (xy 106.233695 -286.011218) (xy 106.273585 -285.980169)
			(xy 106.318041 -285.956108) (xy 106.365851 -285.939693) (xy 106.415711 -285.931371) (xy 106.440986 -285.930848)
			(xy 107.38104 -285.930848) (xy 107.406315 -285.931353) (xy 107.456175 -285.939679) (xy 107.503984 -285.956098)
			(xy 107.54844 -285.980161) (xy 107.588328 -286.011213) (xy 107.622563 -286.048406) (xy 107.650209 -286.090726)
			(xy 107.670513 -286.137019) (xy 107.682921 -286.186022) (xy 107.687096 -286.2364) (xy 116.468595 -286.2364)
			(xy 116.472771 -286.186015) (xy 116.485183 -286.137004) (xy 116.505492 -286.090704) (xy 116.533146 -286.048379)
			(xy 116.56739 -286.011184) (xy 116.607288 -285.980132) (xy 116.651754 -285.956071) (xy 116.699574 -285.939658)
			(xy 116.749443 -285.931339) (xy 116.774722 -285.930848) (xy 117.714776 -285.930848) (xy 117.740057 -285.931319)
			(xy 117.789929 -285.939638) (xy 117.837753 -285.956052) (xy 117.882222 -285.980115) (xy 117.922123 -286.011168)
			(xy 117.956369 -286.048366) (xy 117.984025 -286.090694) (xy 118.004336 -286.136997) (xy 118.016749 -286.186011)
			(xy 118.020925 -286.2364) (xy 119.288495 -286.2364) (xy 119.292671 -286.186014) (xy 119.305083 -286.137002)
			(xy 119.325394 -286.090702) (xy 119.353048 -286.048377) (xy 119.387293 -286.011181) (xy 119.427193 -285.980129)
			(xy 119.47166 -285.956069) (xy 119.51948 -285.939656) (xy 119.56935 -285.931339) (xy 119.59463 -285.930848)
			(xy 120.534684 -285.930848) (xy 120.559964 -285.93132) (xy 120.609836 -285.93964) (xy 120.657658 -285.956055)
			(xy 120.702126 -285.980117) (xy 120.742026 -286.011171) (xy 120.776271 -286.048369) (xy 120.803926 -286.090696)
			(xy 120.824237 -286.136998) (xy 120.836649 -286.186012) (xy 120.840825 -286.2364) (xy 122.108724 -286.2364)
			(xy 122.112899 -286.186022) (xy 122.125308 -286.137019) (xy 122.145613 -286.090726) (xy 122.173261 -286.048407)
			(xy 122.207498 -286.011216) (xy 122.247388 -285.980167) (xy 122.291845 -285.956107) (xy 122.339656 -285.939692)
			(xy 122.389517 -285.931371) (xy 122.414792 -285.930848) (xy 123.354846 -285.930848) (xy 123.380121 -285.931354)
			(xy 123.42998 -285.93968) (xy 123.477788 -285.9561) (xy 123.522243 -285.980163) (xy 123.562131 -286.011215)
			(xy 123.596364 -286.048408) (xy 123.62401 -286.090727) (xy 123.644314 -286.13702) (xy 123.656722 -286.186023)
			(xy 123.660879 -286.2362) (xy 348.435296 -286.2362) (xy 348.439469 -286.185846) (xy 348.451873 -286.136866)
			(xy 348.472171 -286.090595) (xy 348.499809 -286.048297) (xy 348.534032 -286.011126) (xy 348.573906 -285.980094)
			(xy 348.618345 -285.95605) (xy 348.666136 -285.939649) (xy 348.715975 -285.931338) (xy 348.741238 -285.930848)
			(xy 349.681292 -285.930848) (xy 349.706547 -285.931428) (xy 349.756367 -285.93974) (xy 349.804139 -285.956139)
			(xy 349.848561 -285.980178) (xy 349.88842 -286.011201) (xy 349.92263 -286.048361) (xy 349.950256 -286.090645)
			(xy 349.970545 -286.1369) (xy 349.982945 -286.185864) (xy 349.987116 -286.2362) (xy 351.255196 -286.2362)
			(xy 351.259369 -286.185845) (xy 351.271774 -286.136864) (xy 351.292072 -286.090593) (xy 351.319711 -286.048295)
			(xy 351.353935 -286.011123) (xy 351.393811 -285.980092) (xy 351.438251 -285.956048) (xy 351.486043 -285.939647)
			(xy 351.535882 -285.931337) (xy 351.561146 -285.930848) (xy 352.5012 -285.930848) (xy 352.526452 -285.931457)
			(xy 352.576266 -285.93977) (xy 352.624033 -285.956168) (xy 352.66845 -285.980205) (xy 352.708304 -286.011225)
			(xy 352.742509 -286.048382) (xy 352.770132 -286.090661) (xy 352.790419 -286.136911) (xy 352.802816 -286.185869)
			(xy 352.806987 -286.2362) (xy 354.075224 -286.2362) (xy 354.079395 -286.185859) (xy 354.091795 -286.136892)
			(xy 354.112084 -286.090632) (xy 354.139709 -286.048343) (xy 354.173918 -286.011177) (xy 354.213778 -285.980147)
			(xy 354.2582 -285.956101) (xy 354.305974 -285.939694) (xy 354.355797 -285.931373) (xy 354.381054 -285.930848)
			(xy 355.321108 -285.930848) (xy 355.346359 -285.931458) (xy 355.396173 -285.939772) (xy 355.443939 -285.956171)
			(xy 355.488354 -285.980208) (xy 355.528207 -286.011228) (xy 355.562411 -286.048384) (xy 355.590033 -286.090664)
			(xy 355.610319 -286.136913) (xy 355.622717 -286.18587) (xy 355.626887 -286.2362) (xy 364.408924 -286.2362)
			(xy 364.413096 -286.185856) (xy 364.425497 -286.136884) (xy 364.445789 -286.090622) (xy 364.473419 -286.048331)
			(xy 364.507632 -286.011164) (xy 364.547497 -285.980135) (xy 364.591924 -285.95609) (xy 364.639704 -285.939686)
			(xy 364.689532 -285.93137) (xy 364.71479 -285.930848) (xy 365.654844 -285.930848) (xy 365.680093 -285.931461)
			(xy 365.729902 -285.939779) (xy 365.777663 -285.956181) (xy 365.822073 -285.980221) (xy 365.861921 -286.011241)
			(xy 365.89612 -286.048396) (xy 365.923738 -286.090674) (xy 365.944022 -286.13692) (xy 365.956417 -286.185874)
			(xy 365.960587 -286.2362) (xy 367.228824 -286.2362) (xy 367.232996 -286.185855) (xy 367.245398 -286.136883)
			(xy 367.26569 -286.09062) (xy 367.293321 -286.048328) (xy 367.327535 -286.011161) (xy 367.367401 -285.980132)
			(xy 367.41183 -285.956088) (xy 367.45961 -285.939685) (xy 367.509439 -285.931369) (xy 367.534698 -285.930848)
			(xy 368.474752 -285.930848) (xy 368.500009 -285.931425) (xy 368.549834 -285.939732) (xy 368.597612 -285.956128)
			(xy 368.64204 -285.980164) (xy 368.681905 -286.011187) (xy 368.716119 -286.048348) (xy 368.74375 -286.090634)
			(xy 368.764043 -286.136892) (xy 368.776444 -286.185859) (xy 368.780616 -286.2362) (xy 370.049024 -286.2362)
			(xy 370.053196 -286.185859) (xy 370.065595 -286.13689) (xy 370.085885 -286.09063) (xy 370.113511 -286.048341)
			(xy 370.147721 -286.011174) (xy 370.187581 -285.980145) (xy 370.232004 -285.956099) (xy 370.279779 -285.939692)
			(xy 370.329603 -285.931372) (xy 370.35486 -285.930848) (xy 371.294914 -285.930848) (xy 371.320165 -285.931459)
			(xy 371.369978 -285.939773) (xy 371.417743 -285.956173) (xy 371.462157 -285.98021) (xy 371.502009 -286.01123)
			(xy 371.536213 -286.048386) (xy 371.563834 -286.090665) (xy 371.58412 -286.136914) (xy 371.596517 -286.185871)
			(xy 371.600687 -286.2362) (xy 371.596517 -286.286529) (xy 371.58412 -286.335486) (xy 371.563834 -286.381735)
			(xy 371.536213 -286.424014) (xy 371.502009 -286.46117) (xy 371.462157 -286.49219) (xy 371.417743 -286.516227)
			(xy 371.369978 -286.532627) (xy 371.320165 -286.540941) (xy 371.294914 -286.541464) (xy 370.35486 -286.541464)
			(xy 370.329603 -286.541028) (xy 370.279779 -286.532708) (xy 370.232004 -286.516301) (xy 370.187581 -286.492255)
			(xy 370.147721 -286.461226) (xy 370.113511 -286.424059) (xy 370.085884 -286.38177) (xy 370.065595 -286.33551)
			(xy 370.053196 -286.286541) (xy 370.049024 -286.2362) (xy 368.780616 -286.2362) (xy 368.776444 -286.286541)
			(xy 368.764043 -286.335508) (xy 368.74375 -286.381766) (xy 368.716119 -286.424052) (xy 368.681905 -286.461213)
			(xy 368.64204 -286.492236) (xy 368.597612 -286.516272) (xy 368.549834 -286.532668) (xy 368.500009 -286.540975)
			(xy 368.474752 -286.541464) (xy 367.534698 -286.541464) (xy 367.509439 -286.541031) (xy 367.45961 -286.532715)
			(xy 367.41183 -286.516312) (xy 367.367401 -286.492268) (xy 367.327535 -286.461239) (xy 367.293321 -286.424072)
			(xy 367.26569 -286.38178) (xy 367.245398 -286.335517) (xy 367.232996 -286.286545) (xy 367.228824 -286.2362)
			(xy 365.960587 -286.2362) (xy 365.956417 -286.286526) (xy 365.944022 -286.33548) (xy 365.923738 -286.381726)
			(xy 365.89612 -286.424004) (xy 365.861921 -286.461159) (xy 365.822073 -286.492179) (xy 365.777663 -286.516219)
			(xy 365.729902 -286.532621) (xy 365.680093 -286.540939) (xy 365.654844 -286.541464) (xy 364.71479 -286.541464)
			(xy 364.689532 -286.54103) (xy 364.639704 -286.532714) (xy 364.591924 -286.51631) (xy 364.547497 -286.492265)
			(xy 364.507632 -286.461236) (xy 364.473419 -286.424069) (xy 364.445789 -286.381778) (xy 364.425497 -286.335516)
			(xy 364.413096 -286.286544) (xy 364.408924 -286.2362) (xy 355.626887 -286.2362) (xy 355.622717 -286.28653)
			(xy 355.610319 -286.335487) (xy 355.590033 -286.381736) (xy 355.562411 -286.424016) (xy 355.528207 -286.461172)
			(xy 355.488354 -286.492192) (xy 355.443939 -286.516229) (xy 355.396173 -286.532628) (xy 355.346359 -286.540942)
			(xy 355.321108 -286.541464) (xy 354.381054 -286.541464) (xy 354.355797 -286.541027) (xy 354.305974 -286.532706)
			(xy 354.2582 -286.516299) (xy 354.213778 -286.492253) (xy 354.173918 -286.461223) (xy 354.139709 -286.424057)
			(xy 354.112084 -286.381768) (xy 354.091795 -286.335508) (xy 354.079395 -286.286541) (xy 354.075224 -286.2362)
			(xy 352.806987 -286.2362) (xy 352.802816 -286.286531) (xy 352.790419 -286.335489) (xy 352.770132 -286.381739)
			(xy 352.742509 -286.424018) (xy 352.708304 -286.461175) (xy 352.66845 -286.492195) (xy 352.624033 -286.516232)
			(xy 352.576266 -286.53263) (xy 352.526452 -286.540943) (xy 352.5012 -286.541464) (xy 351.561146 -286.541464)
			(xy 351.535882 -286.541063) (xy 351.486043 -286.532753) (xy 351.438251 -286.516352) (xy 351.393811 -286.492309)
			(xy 351.353935 -286.461277) (xy 351.319711 -286.424105) (xy 351.292072 -286.381807) (xy 351.271774 -286.335536)
			(xy 351.259369 -286.286555) (xy 351.255196 -286.2362) (xy 349.987116 -286.2362) (xy 349.982945 -286.286536)
			(xy 349.970545 -286.3355) (xy 349.950256 -286.381755) (xy 349.92263 -286.424039) (xy 349.88842 -286.461199)
			(xy 349.848561 -286.492222) (xy 349.804139 -286.516261) (xy 349.756367 -286.53266) (xy 349.706547 -286.540972)
			(xy 349.681292 -286.541464) (xy 348.741238 -286.541464) (xy 348.715975 -286.541062) (xy 348.666136 -286.532751)
			(xy 348.618345 -286.51635) (xy 348.573907 -286.492306) (xy 348.534032 -286.461274) (xy 348.499809 -286.424103)
			(xy 348.472171 -286.381805) (xy 348.451873 -286.335534) (xy 348.439469 -286.286554) (xy 348.435296 -286.2362)
			(xy 123.660879 -286.2362) (xy 123.660896 -286.2364) (xy 123.656722 -286.286777) (xy 123.644314 -286.33578)
			(xy 123.62401 -286.382073) (xy 123.596364 -286.424392) (xy 123.562131 -286.461585) (xy 123.522243 -286.492637)
			(xy 123.477788 -286.5167) (xy 123.42998 -286.53312) (xy 123.380121 -286.541446) (xy 123.354846 -286.541972)
			(xy 122.414792 -286.541972) (xy 122.389517 -286.541429) (xy 122.339656 -286.533108) (xy 122.291845 -286.516693)
			(xy 122.247388 -286.492633) (xy 122.207498 -286.461584) (xy 122.173261 -286.424393) (xy 122.145613 -286.382074)
			(xy 122.125308 -286.335781) (xy 122.112899 -286.286778) (xy 122.108724 -286.2364) (xy 120.840825 -286.2364)
			(xy 120.836649 -286.286788) (xy 120.824237 -286.335802) (xy 120.803926 -286.382104) (xy 120.776271 -286.424431)
			(xy 120.742026 -286.461629) (xy 120.702126 -286.492683) (xy 120.657658 -286.516745) (xy 120.609836 -286.53316)
			(xy 120.559964 -286.54148) (xy 120.534684 -286.541972) (xy 119.59463 -286.541972) (xy 119.56935 -286.541461)
			(xy 119.51948 -286.533144) (xy 119.47166 -286.516731) (xy 119.427193 -286.492671) (xy 119.387293 -286.461619)
			(xy 119.353048 -286.424423) (xy 119.325394 -286.382098) (xy 119.305083 -286.335798) (xy 119.292671 -286.286786)
			(xy 119.288495 -286.2364) (xy 118.020925 -286.2364) (xy 118.016749 -286.286789) (xy 118.004336 -286.335803)
			(xy 117.984025 -286.382106) (xy 117.956369 -286.424434) (xy 117.922123 -286.461632) (xy 117.882222 -286.492685)
			(xy 117.837753 -286.516748) (xy 117.789929 -286.533162) (xy 117.740057 -286.541481) (xy 117.714776 -286.541972)
			(xy 116.774722 -286.541972) (xy 116.749443 -286.541461) (xy 116.699574 -286.533142) (xy 116.651754 -286.516729)
			(xy 116.607288 -286.492668) (xy 116.56739 -286.461616) (xy 116.533146 -286.424421) (xy 116.505492 -286.382096)
			(xy 116.485183 -286.335796) (xy 116.472771 -286.286785) (xy 116.468595 -286.2364) (xy 107.687096 -286.2364)
			(xy 107.682921 -286.286778) (xy 107.670513 -286.335781) (xy 107.650209 -286.382074) (xy 107.622563 -286.424394)
			(xy 107.588328 -286.461587) (xy 107.54844 -286.492639) (xy 107.503984 -286.516702) (xy 107.456175 -286.533121)
			(xy 107.406315 -286.541447) (xy 107.38104 -286.541972) (xy 106.440986 -286.541972) (xy 106.415711 -286.541429)
			(xy 106.365851 -286.533107) (xy 106.318041 -286.516692) (xy 106.273585 -286.492631) (xy 106.233695 -286.461582)
			(xy 106.19946 -286.424391) (xy 106.171813 -286.382072) (xy 106.151508 -286.33578) (xy 106.139099 -286.286777)
			(xy 106.134924 -286.2364) (xy 104.867196 -286.2364) (xy 104.863021 -286.286778) (xy 104.850613 -286.335783)
			(xy 104.830308 -286.382076) (xy 104.802661 -286.424397) (xy 104.768425 -286.46159) (xy 104.728535 -286.492642)
			(xy 104.684079 -286.516705) (xy 104.636268 -286.533122) (xy 104.586407 -286.541448) (xy 104.561132 -286.541972)
			(xy 103.621078 -286.541972) (xy 103.595804 -286.541428) (xy 103.545945 -286.533105) (xy 103.498136 -286.516689)
			(xy 103.453681 -286.492629) (xy 103.413792 -286.461579) (xy 103.379558 -286.424388) (xy 103.351911 -286.38207)
			(xy 103.331607 -286.335778) (xy 103.319199 -286.286776) (xy 103.315024 -286.2364) (xy 102.047296 -286.2364)
			(xy 102.043121 -286.286779) (xy 102.030712 -286.335784) (xy 102.010407 -286.382079) (xy 101.982759 -286.4244)
			(xy 101.948522 -286.461593) (xy 101.908631 -286.492645) (xy 101.864173 -286.516707) (xy 101.816362 -286.533124)
			(xy 101.7665 -286.541448) (xy 101.741224 -286.541972) (xy 100.80117 -286.541972) (xy 100.775896 -286.541428)
			(xy 100.726038 -286.533103) (xy 100.678231 -286.516687) (xy 100.633777 -286.492626) (xy 100.593889 -286.461576)
			(xy 100.559656 -286.424385) (xy 100.53201 -286.382067) (xy 100.511706 -286.335777) (xy 100.499298 -286.286775)
			(xy 100.495124 -286.2364) (xy 2.509012 -286.2364) (xy 2.509012 -300.146974) (xy 340.219284 -300.146974)
			(xy 340.219284 -299.130974) (xy 340.21977 -299.103723) (xy 340.227526 -299.049775) (xy 340.242881 -298.99748)
			(xy 340.265523 -298.947903) (xy 340.294989 -298.902053) (xy 340.33068 -298.860862) (xy 340.371871 -298.825171)
			(xy 340.417721 -298.795705) (xy 340.467298 -298.773063) (xy 340.519593 -298.757708) (xy 340.573541 -298.749952)
			(xy 340.628043 -298.749952) (xy 340.681991 -298.757708) (xy 340.734286 -298.773063) (xy 340.783863 -298.795705)
			(xy 340.829713 -298.825171) (xy 340.870904 -298.860862) (xy 340.906595 -298.902053) (xy 340.936061 -298.947903)
			(xy 340.958703 -298.99748) (xy 340.974058 -299.049775) (xy 340.981814 -299.103723) (xy 340.9823 -299.130974)
			(xy 340.9823 -300.146974) (xy 340.981814 -300.174225) (xy 340.974058 -300.228173) (xy 340.958703 -300.280468)
			(xy 340.936061 -300.330045) (xy 340.906595 -300.375895) (xy 340.870904 -300.417086) (xy 340.829713 -300.452777)
			(xy 340.783863 -300.482243) (xy 340.734286 -300.504885) (xy 340.681991 -300.52024) (xy 340.628043 -300.527996)
			(xy 340.573541 -300.527996) (xy 340.519593 -300.52024) (xy 340.467298 -300.504885) (xy 340.417721 -300.482243)
			(xy 340.371871 -300.452777) (xy 340.33068 -300.417086) (xy 340.294989 -300.375895) (xy 340.265523 -300.330045)
			(xy 340.242881 -300.280468) (xy 340.227526 -300.228173) (xy 340.21977 -300.174225) (xy 340.219284 -300.146974)
			(xy 2.509012 -300.146974) (xy 2.509012 -304.780442) (xy 78.811124 -304.780442) (xy 78.815155 -304.638049)
			(xy 78.827236 -304.496113) (xy 78.847327 -304.355087) (xy 78.875365 -304.215424) (xy 78.911259 -304.07757)
			(xy 78.954895 -303.941968) (xy 79.006132 -303.809053) (xy 79.064808 -303.679248) (xy 79.130732 -303.552971)
			(xy 79.203696 -303.430626) (xy 79.283464 -303.312605) (xy 79.369782 -303.199286) (xy 79.462372 -303.091032)
			(xy 79.560939 -302.98819) (xy 79.665166 -302.891088) (xy 79.774719 -302.800039) (xy 79.889248 -302.715334)
			(xy 80.008386 -302.637244) (xy 80.131752 -302.566019) (xy 80.258949 -302.501887) (xy 80.38957 -302.445055)
			(xy 80.523198 -302.395703) (xy 80.659404 -302.353991) (xy 80.797751 -302.320051) (xy 80.937797 -302.293992)
			(xy 81.079093 -302.275899) (xy 81.221186 -302.265828) (xy 81.363622 -302.263812) (xy 81.505943 -302.269858)
			(xy 81.647695 -302.283946) (xy 81.788422 -302.306031) (xy 81.927675 -302.336042) (xy 82.065006 -302.373883)
			(xy 82.199977 -302.419433) (xy 82.332155 -302.472547) (xy 82.461116 -302.533053) (xy 82.586447 -302.600758)
			(xy 82.707747 -302.675446) (xy 82.824628 -302.756876) (xy 82.936714 -302.844789) (xy 83.043647 -302.938902)
			(xy 83.145084 -303.038914) (xy 83.240701 -303.144504) (xy 83.330191 -303.255335) (xy 83.413267 -303.371052)
			(xy 83.489663 -303.491283) (xy 83.559136 -303.615643) (xy 83.621461 -303.743735) (xy 83.676439 -303.875148)
			(xy 83.723895 -304.009461) (xy 83.763676 -304.146243) (xy 83.795654 -304.285057) (xy 83.819729 -304.425458)
			(xy 83.835821 -304.566995) (xy 83.84388 -304.709217) (xy 83.844384 -304.780442) (xy 140.011408 -304.780442)
			(xy 140.015438 -304.638078) (xy 140.027516 -304.49617) (xy 140.047604 -304.355173) (xy 140.075636 -304.215538)
			(xy 140.111523 -304.077712) (xy 140.15515 -303.942138) (xy 140.206377 -303.809249) (xy 140.26504 -303.67947)
			(xy 140.330952 -303.553219) (xy 140.403901 -303.430899) (xy 140.483653 -303.312902) (xy 140.569953 -303.199606)
			(xy 140.662525 -303.091373) (xy 140.761071 -302.988551) (xy 140.865277 -302.89147) (xy 140.974809 -302.800439)
			(xy 141.089315 -302.715751) (xy 141.208429 -302.637676) (xy 141.331769 -302.566466) (xy 141.45894 -302.502347)
			(xy 141.589536 -302.445526) (xy 141.723136 -302.396185) (xy 141.859315 -302.35448) (xy 141.997634 -302.320547)
			(xy 142.137652 -302.294494) (xy 142.278919 -302.276404) (xy 142.420984 -302.266335) (xy 142.563391 -302.26432)
			(xy 142.705684 -302.270364) (xy 142.847406 -302.28445) (xy 142.988105 -302.30653) (xy 143.12733 -302.336535)
			(xy 143.264634 -302.374369) (xy 143.399577 -302.41991) (xy 143.531728 -302.473013) (xy 143.660663 -302.533507)
			(xy 143.785969 -302.601198) (xy 143.907245 -302.675871) (xy 144.024101 -302.757285) (xy 144.136165 -302.845179)
			(xy 144.243077 -302.939273) (xy 144.344494 -303.039265) (xy 144.440091 -303.144834) (xy 144.529563 -303.255643)
			(xy 144.612622 -303.371336) (xy 144.689003 -303.491543) (xy 144.758461 -303.615878) (xy 144.820774 -303.743944)
			(xy 144.875741 -303.875331) (xy 144.923187 -304.009616) (xy 144.96296 -304.146371) (xy 144.994932 -304.285157)
			(xy 145.019002 -304.425529) (xy 145.035091 -304.567039) (xy 145.043148 -304.709231) (xy 145.04365 -304.780188)
			(xy 326.751192 -304.780188) (xy 326.755223 -304.637795) (xy 326.767304 -304.495859) (xy 326.787395 -304.354833)
			(xy 326.815433 -304.21517) (xy 326.851327 -304.077316) (xy 326.894963 -303.941714) (xy 326.9462 -303.808799)
			(xy 327.004876 -303.678994) (xy 327.0708 -303.552717) (xy 327.143764 -303.430372) (xy 327.223532 -303.312351)
			(xy 327.30985 -303.199032) (xy 327.40244 -303.090778) (xy 327.501007 -302.987936) (xy 327.605234 -302.890834)
			(xy 327.714787 -302.799785) (xy 327.829316 -302.71508) (xy 327.948454 -302.63699) (xy 328.07182 -302.565765)
			(xy 328.199017 -302.501633) (xy 328.329638 -302.444801) (xy 328.463266 -302.395449) (xy 328.599472 -302.353737)
			(xy 328.737819 -302.319797) (xy 328.877865 -302.293738) (xy 329.019161 -302.275645) (xy 329.161254 -302.265574)
			(xy 329.30369 -302.263558) (xy 329.446011 -302.269604) (xy 329.587763 -302.283692) (xy 329.72849 -302.305777)
			(xy 329.867743 -302.335788) (xy 330.005074 -302.373629) (xy 330.140045 -302.419179) (xy 330.272223 -302.472293)
			(xy 330.401184 -302.532799) (xy 330.526515 -302.600504) (xy 330.647815 -302.675192) (xy 330.764696 -302.756622)
			(xy 330.876782 -302.844535) (xy 330.983715 -302.938648) (xy 331.085152 -303.03866) (xy 331.180769 -303.14425)
			(xy 331.270259 -303.255081) (xy 331.353335 -303.370798) (xy 331.429731 -303.491029) (xy 331.499204 -303.615389)
			(xy 331.561529 -303.743481) (xy 331.616507 -303.874894) (xy 331.663963 -304.009207) (xy 331.703744 -304.145989)
			(xy 331.735722 -304.284803) (xy 331.759797 -304.425204) (xy 331.775889 -304.566741) (xy 331.782371 -304.681128)
			(xy 333.795116 -304.681128) (xy 333.795116 -303.817528) (xy 333.795602 -303.790259) (xy 333.803364 -303.736275)
			(xy 333.818729 -303.683945) (xy 333.841386 -303.634335) (xy 333.870872 -303.588454) (xy 333.906587 -303.547237)
			(xy 333.947804 -303.511522) (xy 333.993685 -303.482036) (xy 334.043295 -303.459379) (xy 334.095625 -303.444014)
			(xy 334.149609 -303.436252) (xy 334.204147 -303.436252) (xy 334.258131 -303.444014) (xy 334.310461 -303.459379)
			(xy 334.360071 -303.482036) (xy 334.405952 -303.511522) (xy 334.447169 -303.547237) (xy 334.482884 -303.588454)
			(xy 334.51237 -303.634335) (xy 334.535027 -303.683945) (xy 334.550392 -303.736275) (xy 334.558154 -303.790259)
			(xy 334.55864 -303.817528) (xy 334.55864 -304.681128) (xy 334.558154 -304.708397) (xy 334.550392 -304.762381)
			(xy 334.545164 -304.780188) (xy 387.951476 -304.780188) (xy 387.955506 -304.637824) (xy 387.967584 -304.495916)
			(xy 387.987672 -304.354919) (xy 388.015704 -304.215284) (xy 388.051591 -304.077458) (xy 388.095218 -303.941884)
			(xy 388.146445 -303.808995) (xy 388.205108 -303.679216) (xy 388.27102 -303.552965) (xy 388.343969 -303.430645)
			(xy 388.423721 -303.312648) (xy 388.510021 -303.199352) (xy 388.602593 -303.091119) (xy 388.701139 -302.988297)
			(xy 388.805345 -302.891216) (xy 388.914877 -302.800185) (xy 389.029383 -302.715497) (xy 389.148497 -302.637422)
			(xy 389.271837 -302.566212) (xy 389.399008 -302.502093) (xy 389.529604 -302.445272) (xy 389.663204 -302.395931)
			(xy 389.799383 -302.354226) (xy 389.937702 -302.320293) (xy 390.07772 -302.29424) (xy 390.218987 -302.27615)
			(xy 390.361052 -302.266081) (xy 390.503459 -302.264066) (xy 390.645752 -302.27011) (xy 390.787474 -302.284196)
			(xy 390.928173 -302.306276) (xy 391.067398 -302.336281) (xy 391.204702 -302.374115) (xy 391.339645 -302.419656)
			(xy 391.471796 -302.472759) (xy 391.600731 -302.533253) (xy 391.726037 -302.600944) (xy 391.847313 -302.675617)
			(xy 391.964169 -302.757031) (xy 392.076233 -302.844925) (xy 392.183145 -302.939019) (xy 392.284562 -303.039011)
			(xy 392.380159 -303.14458) (xy 392.469631 -303.255389) (xy 392.55269 -303.371082) (xy 392.629071 -303.491289)
			(xy 392.698529 -303.615624) (xy 392.760842 -303.74369) (xy 392.815809 -303.875077) (xy 392.863255 -304.009362)
			(xy 392.903028 -304.146117) (xy 392.935 -304.284903) (xy 392.95907 -304.425275) (xy 392.975159 -304.566785)
			(xy 392.983216 -304.708977) (xy 392.98372 -304.780188) (xy 392.983216 -304.851399) (xy 392.975159 -304.993591)
			(xy 392.95907 -305.135101) (xy 392.935 -305.275473) (xy 392.903028 -305.414259) (xy 392.863255 -305.551014)
			(xy 392.815809 -305.685299) (xy 392.760842 -305.816686) (xy 392.698529 -305.944752) (xy 392.629071 -306.069087)
			(xy 392.55269 -306.189294) (xy 392.469631 -306.304987) (xy 392.380159 -306.415796) (xy 392.284562 -306.521365)
			(xy 392.183145 -306.621357) (xy 392.076233 -306.715451) (xy 391.964169 -306.803345) (xy 391.847313 -306.884759)
			(xy 391.726037 -306.959432) (xy 391.600731 -307.027123) (xy 391.471796 -307.087617) (xy 391.339645 -307.14072)
			(xy 391.204702 -307.186261) (xy 391.067398 -307.224095) (xy 390.928173 -307.2541) (xy 390.787474 -307.27618)
			(xy 390.645752 -307.290266) (xy 390.503459 -307.29631) (xy 390.361052 -307.294295) (xy 390.218987 -307.284226)
			(xy 390.07772 -307.266136) (xy 389.937702 -307.240083) (xy 389.799383 -307.20615) (xy 389.663204 -307.164445)
			(xy 389.529604 -307.115104) (xy 389.399008 -307.058283) (xy 389.271837 -306.994164) (xy 389.148497 -306.922954)
			(xy 389.029383 -306.844879) (xy 388.914877 -306.760191) (xy 388.805345 -306.66916) (xy 388.701139 -306.572079)
			(xy 388.602593 -306.469257) (xy 388.510021 -306.361024) (xy 388.423721 -306.247728) (xy 388.343969 -306.129731)
			(xy 388.27102 -306.007411) (xy 388.205108 -305.88116) (xy 388.146445 -305.751381) (xy 388.095218 -305.618492)
			(xy 388.051591 -305.482918) (xy 388.015704 -305.345092) (xy 387.987672 -305.205457) (xy 387.967584 -305.06446)
			(xy 387.955506 -304.922552) (xy 387.951476 -304.780188) (xy 334.545164 -304.780188) (xy 334.535027 -304.814711)
			(xy 334.51237 -304.864321) (xy 334.482884 -304.910202) (xy 334.447169 -304.951419) (xy 334.405952 -304.987134)
			(xy 334.360071 -305.01662) (xy 334.310461 -305.039277) (xy 334.258131 -305.054642) (xy 334.204147 -305.062404)
			(xy 334.149609 -305.062404) (xy 334.095625 -305.054642) (xy 334.043295 -305.039277) (xy 333.993685 -305.01662)
			(xy 333.947804 -304.987134) (xy 333.906587 -304.951419) (xy 333.870872 -304.910202) (xy 333.841386 -304.864321)
			(xy 333.818729 -304.814711) (xy 333.803364 -304.762381) (xy 333.795602 -304.708397) (xy 333.795116 -304.681128)
			(xy 331.782371 -304.681128) (xy 331.783948 -304.708963) (xy 331.784452 -304.780188) (xy 331.783948 -304.851413)
			(xy 331.775889 -304.993635) (xy 331.759797 -305.135172) (xy 331.735722 -305.275573) (xy 331.703744 -305.414387)
			(xy 331.663963 -305.551169) (xy 331.616507 -305.685482) (xy 331.561529 -305.816895) (xy 331.499204 -305.944987)
			(xy 331.429731 -306.069347) (xy 331.353335 -306.189578) (xy 331.270259 -306.305295) (xy 331.180769 -306.416126)
			(xy 331.16552 -306.432966) (xy 340.495636 -306.432966) (xy 340.495636 -305.569366) (xy 340.496122 -305.542115)
			(xy 340.503878 -305.488167) (xy 340.519233 -305.435872) (xy 340.541875 -305.386295) (xy 340.571341 -305.340445)
			(xy 340.607032 -305.299254) (xy 340.648223 -305.263563) (xy 340.694073 -305.234097) (xy 340.74365 -305.211455)
			(xy 340.795945 -305.1961) (xy 340.849893 -305.188344) (xy 340.904395 -305.188344) (xy 340.958343 -305.1961)
			(xy 341.010638 -305.211455) (xy 341.060215 -305.234097) (xy 341.106065 -305.263563) (xy 341.147256 -305.299254)
			(xy 341.182947 -305.340445) (xy 341.212413 -305.386295) (xy 341.235055 -305.435872) (xy 341.25041 -305.488167)
			(xy 341.258166 -305.542115) (xy 341.258652 -305.569366) (xy 341.258652 -306.432966) (xy 341.258166 -306.460217)
			(xy 341.25041 -306.514165) (xy 341.235055 -306.56646) (xy 341.212413 -306.616037) (xy 341.182947 -306.661887)
			(xy 341.147256 -306.703078) (xy 341.106065 -306.738769) (xy 341.060215 -306.768235) (xy 341.010638 -306.790877)
			(xy 340.958343 -306.806232) (xy 340.904395 -306.813988) (xy 340.849893 -306.813988) (xy 340.795945 -306.806232)
			(xy 340.74365 -306.790877) (xy 340.694073 -306.768235) (xy 340.648223 -306.738769) (xy 340.607032 -306.703078)
			(xy 340.571341 -306.661887) (xy 340.541875 -306.616037) (xy 340.519233 -306.56646) (xy 340.503878 -306.514165)
			(xy 340.496122 -306.460217) (xy 340.495636 -306.432966) (xy 331.16552 -306.432966) (xy 331.085152 -306.521716)
			(xy 330.983715 -306.621728) (xy 330.876782 -306.715841) (xy 330.764696 -306.803754) (xy 330.647815 -306.885184)
			(xy 330.526515 -306.959872) (xy 330.401184 -307.027577) (xy 330.272223 -307.088083) (xy 330.140045 -307.141197)
			(xy 330.005074 -307.186747) (xy 329.867743 -307.224588) (xy 329.72849 -307.254599) (xy 329.587763 -307.276684)
			(xy 329.446011 -307.290772) (xy 329.30369 -307.296818) (xy 329.161254 -307.294802) (xy 329.019161 -307.284731)
			(xy 328.877865 -307.266638) (xy 328.737819 -307.240579) (xy 328.599472 -307.206639) (xy 328.463266 -307.164927)
			(xy 328.329638 -307.115575) (xy 328.199017 -307.058743) (xy 328.07182 -306.994611) (xy 327.948454 -306.923386)
			(xy 327.829316 -306.845296) (xy 327.714787 -306.760591) (xy 327.605234 -306.669542) (xy 327.501007 -306.57244)
			(xy 327.40244 -306.469598) (xy 327.30985 -306.361344) (xy 327.223532 -306.248025) (xy 327.143764 -306.130004)
			(xy 327.0708 -306.007659) (xy 327.004876 -305.881382) (xy 326.9462 -305.751577) (xy 326.894963 -305.618662)
			(xy 326.851327 -305.48306) (xy 326.815433 -305.345206) (xy 326.787395 -305.205543) (xy 326.767304 -305.064517)
			(xy 326.755223 -304.922581) (xy 326.751192 -304.780188) (xy 145.04365 -304.780188) (xy 145.043652 -304.780442)
			(xy 145.043148 -304.851653) (xy 145.035091 -304.993845) (xy 145.019002 -305.135355) (xy 144.994932 -305.275727)
			(xy 144.96296 -305.414513) (xy 144.923187 -305.551268) (xy 144.875741 -305.685553) (xy 144.820774 -305.81694)
			(xy 144.758461 -305.945006) (xy 144.689003 -306.069341) (xy 144.612622 -306.189548) (xy 144.529563 -306.305241)
			(xy 144.440091 -306.41605) (xy 144.344494 -306.521619) (xy 144.243077 -306.621611) (xy 144.136165 -306.715705)
			(xy 144.024101 -306.803599) (xy 143.907245 -306.885013) (xy 143.785969 -306.959686) (xy 143.660663 -307.027377)
			(xy 143.531728 -307.087871) (xy 143.399577 -307.140974) (xy 143.264634 -307.186515) (xy 143.12733 -307.224349)
			(xy 142.988105 -307.254354) (xy 142.847406 -307.276434) (xy 142.705684 -307.29052) (xy 142.563391 -307.296564)
			(xy 142.420984 -307.294549) (xy 142.278919 -307.28448) (xy 142.137652 -307.26639) (xy 141.997634 -307.240337)
			(xy 141.859315 -307.206404) (xy 141.723136 -307.164699) (xy 141.589536 -307.115358) (xy 141.45894 -307.058537)
			(xy 141.331769 -306.994418) (xy 141.208429 -306.923208) (xy 141.089315 -306.845133) (xy 140.974809 -306.760445)
			(xy 140.865277 -306.669414) (xy 140.761071 -306.572333) (xy 140.662525 -306.469511) (xy 140.569953 -306.361278)
			(xy 140.483653 -306.247982) (xy 140.403901 -306.129985) (xy 140.330952 -306.007665) (xy 140.26504 -305.881414)
			(xy 140.206377 -305.751635) (xy 140.15515 -305.618746) (xy 140.111523 -305.483172) (xy 140.075636 -305.345346)
			(xy 140.047604 -305.205711) (xy 140.027516 -305.064714) (xy 140.015438 -304.922806) (xy 140.011408 -304.780442)
			(xy 83.844384 -304.780442) (xy 83.84388 -304.851667) (xy 83.835821 -304.993889) (xy 83.819729 -305.135426)
			(xy 83.795654 -305.275827) (xy 83.763676 -305.414641) (xy 83.723895 -305.551423) (xy 83.676439 -305.685736)
			(xy 83.621461 -305.817149) (xy 83.559136 -305.945241) (xy 83.489663 -306.069601) (xy 83.413267 -306.189832)
			(xy 83.330191 -306.305549) (xy 83.240701 -306.41638) (xy 83.145084 -306.52197) (xy 83.043647 -306.621982)
			(xy 82.936714 -306.716095) (xy 82.824628 -306.804008) (xy 82.707747 -306.885438) (xy 82.586447 -306.960126)
			(xy 82.461116 -307.027831) (xy 82.332155 -307.088337) (xy 82.199977 -307.141451) (xy 82.065006 -307.187001)
			(xy 81.927675 -307.224842) (xy 81.788422 -307.254853) (xy 81.647695 -307.276938) (xy 81.505943 -307.291026)
			(xy 81.363622 -307.297072) (xy 81.221186 -307.295056) (xy 81.079093 -307.284985) (xy 80.937797 -307.266892)
			(xy 80.797751 -307.240833) (xy 80.659404 -307.206893) (xy 80.523198 -307.165181) (xy 80.38957 -307.115829)
			(xy 80.258949 -307.058997) (xy 80.131752 -306.994865) (xy 80.008386 -306.92364) (xy 79.889248 -306.84555)
			(xy 79.774719 -306.760845) (xy 79.665166 -306.669796) (xy 79.560939 -306.572694) (xy 79.462372 -306.469852)
			(xy 79.369782 -306.361598) (xy 79.283464 -306.248279) (xy 79.203696 -306.130258) (xy 79.130732 -306.007913)
			(xy 79.064808 -305.881636) (xy 79.006132 -305.751831) (xy 78.954895 -305.618916) (xy 78.911259 -305.483314)
			(xy 78.875365 -305.34546) (xy 78.847327 -305.205797) (xy 78.827236 -305.064771) (xy 78.815155 -304.922835)
			(xy 78.811124 -304.780442) (xy 2.509012 -304.780442) (xy 2.509012 -309.504588) (xy 79.192628 -309.504588)
			(xy 79.192628 -308.640988) (xy 79.193114 -308.613737) (xy 79.20087 -308.559789) (xy 79.216225 -308.507494)
			(xy 79.238867 -308.457917) (xy 79.268333 -308.412067) (xy 79.304024 -308.370876) (xy 79.345215 -308.335185)
			(xy 79.391065 -308.305719) (xy 79.440642 -308.283077) (xy 79.492937 -308.267722) (xy 79.546885 -308.259966)
			(xy 79.601387 -308.259966) (xy 79.655335 -308.267722) (xy 79.70763 -308.283077) (xy 79.757207 -308.305719)
			(xy 79.803057 -308.335185) (xy 79.844248 -308.370876) (xy 79.879939 -308.412067) (xy 79.909405 -308.457917)
			(xy 79.92811 -308.498873) (xy 93.275072 -308.498873) (xy 93.275072 -308.444327) (xy 93.282834 -308.390335)
			(xy 93.298202 -308.337998) (xy 93.320862 -308.288381) (xy 93.350352 -308.242493) (xy 93.386073 -308.20127)
			(xy 93.427297 -308.16555) (xy 93.473184 -308.13606) (xy 93.522802 -308.113401) (xy 93.575139 -308.098034)
			(xy 93.629131 -308.090271) (xy 93.656404 -308.089808) (xy 94.520004 -308.089808) (xy 94.547271 -308.090355)
			(xy 94.60125 -308.098116) (xy 94.653575 -308.113481) (xy 94.703181 -308.136135) (xy 94.749058 -308.165619)
			(xy 94.790271 -308.201331) (xy 94.825983 -308.242546) (xy 94.855467 -308.288423) (xy 94.878121 -308.338029)
			(xy 94.893485 -308.390354) (xy 94.901246 -308.444333) (xy 94.901246 -308.498867) (xy 94.893485 -308.552846)
			(xy 94.878121 -308.605171) (xy 94.855467 -308.654777) (xy 94.825983 -308.700654) (xy 94.790271 -308.741869)
			(xy 94.749058 -308.777581) (xy 94.703181 -308.807065) (xy 94.653575 -308.829719) (xy 94.60125 -308.845084)
			(xy 94.547271 -308.852845) (xy 94.520004 -308.853332) (xy 93.656404 -308.853332) (xy 93.629131 -308.852929)
			(xy 93.575139 -308.845166) (xy 93.522802 -308.829799) (xy 93.473184 -308.80714) (xy 93.427297 -308.77765)
			(xy 93.386073 -308.74193) (xy 93.350352 -308.700707) (xy 93.320862 -308.654819) (xy 93.298202 -308.605202)
			(xy 93.282834 -308.552865) (xy 93.275072 -308.498873) (xy 79.92811 -308.498873) (xy 79.932047 -308.507494)
			(xy 79.947402 -308.559789) (xy 79.955158 -308.613737) (xy 79.955644 -308.640988) (xy 79.955644 -309.303166)
			(xy 341.51824 -309.303166) (xy 341.51824 -308.439566) (xy 341.518726 -308.412297) (xy 341.526488 -308.358313)
			(xy 341.541853 -308.305983) (xy 341.56451 -308.256373) (xy 341.593996 -308.210492) (xy 341.629711 -308.169275)
			(xy 341.670928 -308.13356) (xy 341.716809 -308.104074) (xy 341.766419 -308.081417) (xy 341.818749 -308.066052)
			(xy 341.872733 -308.05829) (xy 341.927271 -308.05829) (xy 341.981255 -308.066052) (xy 342.033585 -308.081417)
			(xy 342.083195 -308.104074) (xy 342.129076 -308.13356) (xy 342.170293 -308.169275) (xy 342.206008 -308.210492)
			(xy 342.235494 -308.256373) (xy 342.258151 -308.305983) (xy 342.273516 -308.358313) (xy 342.281278 -308.412297)
			(xy 342.281764 -308.439566) (xy 342.281764 -309.303166) (xy 342.281278 -309.330435) (xy 342.273516 -309.384419)
			(xy 342.258151 -309.436749) (xy 342.235494 -309.486359) (xy 342.206008 -309.53224) (xy 342.170293 -309.573457)
			(xy 342.129076 -309.609172) (xy 342.083195 -309.638658) (xy 342.033585 -309.661315) (xy 341.981255 -309.67668)
			(xy 341.927271 -309.684442) (xy 341.872733 -309.684442) (xy 341.818749 -309.67668) (xy 341.766419 -309.661315)
			(xy 341.716809 -309.638658) (xy 341.670928 -309.609172) (xy 341.629711 -309.573457) (xy 341.593996 -309.53224)
			(xy 341.56451 -309.486359) (xy 341.541853 -309.436749) (xy 341.526488 -309.384419) (xy 341.518726 -309.330435)
			(xy 341.51824 -309.303166) (xy 79.955644 -309.303166) (xy 79.955644 -309.504588) (xy 79.955158 -309.531839)
			(xy 79.947402 -309.585787) (xy 79.932047 -309.638082) (xy 79.909405 -309.687659) (xy 79.879939 -309.733509)
			(xy 79.844248 -309.7747) (xy 79.803057 -309.810391) (xy 79.757207 -309.839857) (xy 79.70763 -309.862499)
			(xy 79.655335 -309.877854) (xy 79.601387 -309.88561) (xy 79.546885 -309.88561) (xy 79.492937 -309.877854)
			(xy 79.440642 -309.862499) (xy 79.391065 -309.839857) (xy 79.345215 -309.810391) (xy 79.304024 -309.7747)
			(xy 79.268333 -309.733509) (xy 79.238867 -309.687659) (xy 79.216225 -309.638082) (xy 79.20087 -309.585787)
			(xy 79.193114 -309.531839) (xy 79.192628 -309.504588) (xy 2.509012 -309.504588) (xy 2.509012 -310.603646)
			(xy 98.925888 -310.603646) (xy 98.925888 -309.740046) (xy 98.926374 -309.712795) (xy 98.93413 -309.658847)
			(xy 98.949485 -309.606552) (xy 98.972127 -309.556975) (xy 99.001593 -309.511125) (xy 99.037284 -309.469934)
			(xy 99.078475 -309.434243) (xy 99.124325 -309.404777) (xy 99.173902 -309.382135) (xy 99.226197 -309.36678)
			(xy 99.280145 -309.359024) (xy 99.334647 -309.359024) (xy 99.388595 -309.36678) (xy 99.44089 -309.382135)
			(xy 99.490467 -309.404777) (xy 99.536317 -309.434243) (xy 99.577508 -309.469934) (xy 99.613199 -309.511125)
			(xy 99.642665 -309.556975) (xy 99.665307 -309.606552) (xy 99.680662 -309.658847) (xy 99.688418 -309.712795)
			(xy 99.688904 -309.740046) (xy 99.688904 -310.603646) (xy 99.688418 -310.630897) (xy 99.680662 -310.684845)
			(xy 99.665307 -310.73714) (xy 99.642665 -310.786717) (xy 99.613199 -310.832567) (xy 99.577508 -310.873758)
			(xy 99.536317 -310.909449) (xy 99.490467 -310.938915) (xy 99.44089 -310.961557) (xy 99.388595 -310.976912)
			(xy 99.334647 -310.984668) (xy 99.280145 -310.984668) (xy 99.226197 -310.976912) (xy 99.173902 -310.961557)
			(xy 99.124325 -310.938915) (xy 99.078475 -310.909449) (xy 99.037284 -310.873758) (xy 99.001593 -310.832567)
			(xy 98.972127 -310.786717) (xy 98.949485 -310.73714) (xy 98.93413 -310.684845) (xy 98.926374 -310.630897)
			(xy 98.925888 -310.603646) (xy 2.509012 -310.603646) (xy 2.509012 -311.513728) (xy 347.772228 -311.513728)
			(xy 347.772228 -310.650128) (xy 347.772714 -310.622859) (xy 347.780476 -310.568875) (xy 347.795841 -310.516545)
			(xy 347.818498 -310.466935) (xy 347.847984 -310.421054) (xy 347.883699 -310.379837) (xy 347.924916 -310.344122)
			(xy 347.970797 -310.314636) (xy 348.020407 -310.291979) (xy 348.072737 -310.276614) (xy 348.126721 -310.268852)
			(xy 348.181259 -310.268852) (xy 348.235243 -310.276614) (xy 348.287573 -310.291979) (xy 348.337183 -310.314636)
			(xy 348.383064 -310.344122) (xy 348.424281 -310.379837) (xy 348.459996 -310.421054) (xy 348.489482 -310.466935)
			(xy 348.512139 -310.516545) (xy 348.527504 -310.568875) (xy 348.535266 -310.622859) (xy 348.535752 -310.650128)
			(xy 348.535752 -311.513728) (xy 348.535266 -311.540997) (xy 348.527504 -311.594981) (xy 348.512139 -311.647311)
			(xy 348.489482 -311.696921) (xy 348.459996 -311.742802) (xy 348.424281 -311.784019) (xy 348.383064 -311.819734)
			(xy 348.337183 -311.84922) (xy 348.287573 -311.871877) (xy 348.235243 -311.887242) (xy 348.181259 -311.895004)
			(xy 348.126721 -311.895004) (xy 348.072737 -311.887242) (xy 348.020407 -311.871877) (xy 347.970797 -311.84922)
			(xy 347.924916 -311.819734) (xy 347.883699 -311.784019) (xy 347.847984 -311.742802) (xy 347.818498 -311.696921)
			(xy 347.795841 -311.647311) (xy 347.780476 -311.594981) (xy 347.772714 -311.540997) (xy 347.772228 -311.513728)
			(xy 2.509012 -311.513728) (xy 2.509012 -314.997338) (xy 98.330512 -314.997338) (xy 98.330512 -314.133738)
			(xy 98.330998 -314.106487) (xy 98.338754 -314.052539) (xy 98.354109 -314.000244) (xy 98.376751 -313.950667)
			(xy 98.406217 -313.904817) (xy 98.441908 -313.863626) (xy 98.483099 -313.827935) (xy 98.528949 -313.798469)
			(xy 98.578526 -313.775827) (xy 98.630821 -313.760472) (xy 98.684769 -313.752716) (xy 98.739271 -313.752716)
			(xy 98.793219 -313.760472) (xy 98.845514 -313.775827) (xy 98.895091 -313.798469) (xy 98.940941 -313.827935)
			(xy 98.982132 -313.863626) (xy 99.017823 -313.904817) (xy 99.047289 -313.950667) (xy 99.069931 -314.000244)
			(xy 99.085286 -314.052539) (xy 99.093042 -314.106487) (xy 99.093528 -314.133738) (xy 99.093528 -314.997338)
			(xy 99.093042 -315.024589) (xy 99.085286 -315.078537) (xy 99.069931 -315.130832) (xy 99.047289 -315.180409)
			(xy 99.017823 -315.226259) (xy 98.982132 -315.26745) (xy 98.940941 -315.303141) (xy 98.895091 -315.332607)
			(xy 98.845514 -315.355249) (xy 98.793219 -315.370604) (xy 98.739271 -315.37836) (xy 98.684769 -315.37836)
			(xy 98.630821 -315.370604) (xy 98.578526 -315.355249) (xy 98.528949 -315.332607) (xy 98.483099 -315.303141)
			(xy 98.441908 -315.26745) (xy 98.406217 -315.226259) (xy 98.376751 -315.180409) (xy 98.354109 -315.130832)
			(xy 98.338754 -315.078537) (xy 98.330998 -315.024589) (xy 98.330512 -314.997338) (xy 2.509012 -314.997338)
			(xy 2.509012 -336.9884) (xy 70.218517 -336.9884) (xy 70.222508 -336.904617) (xy 70.234446 -336.821593)
			(xy 70.254221 -336.74008) (xy 70.281655 -336.660815) (xy 70.3165 -336.584518) (xy 70.35844 -336.511878)
			(xy 70.407095 -336.443554) (xy 70.462025 -336.380164) (xy 70.522731 -336.322283) (xy 70.588664 -336.270435)
			(xy 70.659228 -336.225089) (xy 70.733783 -336.186656) (xy 70.811653 -336.155484) (xy 70.892134 -336.131855)
			(xy 70.974497 -336.115984) (xy 71.057995 -336.108014) (xy 71.099934 -336.107532) (xy 71.137123 -336.107938)
			(xy 71.211236 -336.114223) (xy 71.284556 -336.126727) (xy 71.356562 -336.145363) (xy 71.39178 -336.157316)
			(xy 71.399977 -336.15983) (xy 71.417111 -336.15983) (xy 71.425308 -336.157316) (xy 71.460496 -336.145371)
			(xy 71.532436 -336.126725) (xy 71.605692 -336.114215) (xy 71.679742 -336.107929) (xy 71.7169 -336.107532)
			(xy 71.717408 -336.107532) (xy 71.748142 -336.108294) (xy 71.757646 -336.056715) (xy 71.787316 -335.956115)
			(xy 71.807324 -335.907634) (xy 71.810983 -335.897931) (xy 71.810971 -335.877211) (xy 71.807324 -335.867502)
			(xy 71.790219 -335.826242) (xy 71.763427 -335.741032) (xy 71.74539 -335.653549) (xy 71.736293 -335.564691)
			(xy 71.735696 -335.52003) (xy 71.735696 -335.519268) (xy 71.736195 -335.477343) (xy 71.744165 -335.393872)
			(xy 71.760034 -335.311537) (xy 71.783657 -335.231083) (xy 71.814821 -335.153239) (xy 71.853244 -335.078709)
			(xy 71.898577 -335.00817) (xy 71.95041 -334.942259) (xy 72.008273 -334.881573) (xy 72.071643 -334.826663)
			(xy 72.139946 -334.778025) (xy 72.212563 -334.7361) (xy 72.288836 -334.701267) (xy 72.368075 -334.673842)
			(xy 72.449561 -334.654073) (xy 72.532558 -334.64214) (xy 72.616314 -334.638151) (xy 72.70007 -334.64214)
			(xy 72.783067 -334.654073) (xy 72.864553 -334.673842) (xy 72.943792 -334.701267) (xy 73.020065 -334.7361)
			(xy 73.092682 -334.778025) (xy 73.160985 -334.826663) (xy 73.224355 -334.881573) (xy 73.282218 -334.942259)
			(xy 73.334051 -335.00817) (xy 73.379384 -335.078709) (xy 73.417807 -335.153239) (xy 73.448971 -335.231083)
			(xy 73.472594 -335.311537) (xy 73.488463 -335.393872) (xy 73.496433 -335.477343) (xy 73.496932 -335.519268)
			(xy 73.496932 -335.52003) (xy 73.496371 -335.564694) (xy 73.487295 -335.653559) (xy 73.46926 -335.741047)
			(xy 73.442452 -335.826257) (xy 73.425304 -335.867502) (xy 73.421681 -335.877216) (xy 73.421669 -335.897926)
			(xy 73.425304 -335.907634) (xy 73.441139 -335.945575) (xy 73.466487 -336.02379) (xy 73.484436 -336.104027)
			(xy 73.494829 -336.185587) (xy 73.496678 -336.226658) (xy 73.496932 -336.24012) (xy 73.51141 -336.263234)
			(xy 73.61301 -336.31759) (xy 73.639934 -336.316828) (xy 73.651618 -336.309462) (xy 73.686811 -336.288202)
			(xy 73.76042 -336.251553) (xy 73.837094 -336.221845) (xy 73.91618 -336.199333) (xy 73.997005 -336.184209)
			(xy 74.07888 -336.1766) (xy 74.119994 -336.176112) (xy 74.161107 -336.176619) (xy 74.242983 -336.184205)
			(xy 74.32381 -336.199313) (xy 74.402898 -336.221815) (xy 74.479573 -336.251518) (xy 74.553179 -336.288168)
			(xy 74.623091 -336.331454) (xy 74.68871 -336.381006) (xy 74.749477 -336.4364) (xy 74.804874 -336.497166)
			(xy 74.854428 -336.562783) (xy 74.897716 -336.632693) (xy 74.934369 -336.706298) (xy 74.964075 -336.782971)
			(xy 74.986579 -336.862059) (xy 75.001691 -336.942885) (xy 75.005252 -336.9813) (xy 78.574105 -336.9813)
			(xy 78.578096 -336.897517) (xy 78.590033 -336.814493) (xy 78.609809 -336.732979) (xy 78.637243 -336.653715)
			(xy 78.672087 -336.577417) (xy 78.714027 -336.504776) (xy 78.762681 -336.436452) (xy 78.81761 -336.373061)
			(xy 78.878316 -336.31518) (xy 78.94425 -336.26333) (xy 79.014813 -336.217984) (xy 79.089367 -336.179549)
			(xy 79.167237 -336.148376) (xy 79.247718 -336.124747) (xy 79.330081 -336.108874) (xy 79.413579 -336.100902)
			(xy 79.455518 -336.10042) (xy 79.492708 -336.100802) (xy 79.566821 -336.107094) (xy 79.640141 -336.119606)
			(xy 79.712146 -336.138248) (xy 79.747364 -336.150204) (xy 79.755561 -336.152718) (xy 79.772695 -336.152718)
			(xy 79.780892 -336.150204) (xy 79.816103 -336.138226) (xy 79.888108 -336.119576) (xy 79.961431 -336.107072)
			(xy 80.035547 -336.100804) (xy 80.072738 -336.10042) (xy 80.10906 -336.101182) (xy 80.115245 -336.066241)
			(xy 80.132513 -335.997409) (xy 80.155273 -335.930194) (xy 80.169004 -335.897474) (xy 80.172641 -335.887764)
			(xy 80.172644 -335.86705) (xy 80.169004 -335.857342) (xy 80.151879 -335.81609) (xy 80.125092 -335.730877)
			(xy 80.107061 -335.643392) (xy 80.09797 -335.554532) (xy 80.097376 -335.50987) (xy 80.097376 -335.509108)
			(xy 80.097875 -335.467183) (xy 80.105845 -335.383712) (xy 80.121714 -335.301377) (xy 80.145337 -335.220923)
			(xy 80.176501 -335.143079) (xy 80.214924 -335.068549) (xy 80.260257 -334.99801) (xy 80.31209 -334.932099)
			(xy 80.369953 -334.871413) (xy 80.433323 -334.816503) (xy 80.501626 -334.767865) (xy 80.574243 -334.72594)
			(xy 80.650516 -334.691107) (xy 80.729755 -334.663682) (xy 80.811241 -334.643913) (xy 80.894238 -334.63198)
			(xy 80.977994 -334.627991) (xy 81.06175 -334.63198) (xy 81.144747 -334.643913) (xy 81.226233 -334.663682)
			(xy 81.305472 -334.691107) (xy 81.381745 -334.72594) (xy 81.454362 -334.767865) (xy 81.522665 -334.816503)
			(xy 81.586035 -334.871413) (xy 81.643898 -334.932099) (xy 81.695731 -334.99801) (xy 81.741064 -335.068549)
			(xy 81.779487 -335.143079) (xy 81.810651 -335.220923) (xy 81.834274 -335.301377) (xy 81.850143 -335.383712)
			(xy 81.858113 -335.467183) (xy 81.858612 -335.509108) (xy 81.858612 -335.50987) (xy 81.858066 -335.554534)
			(xy 81.848986 -335.6434) (xy 81.830947 -335.730888) (xy 81.804134 -335.816098) (xy 81.786984 -335.857342)
			(xy 81.783338 -335.867049) (xy 81.783341 -335.887765) (xy 81.786984 -335.897474) (xy 81.802748 -335.935334)
			(xy 81.827987 -336.013369) (xy 81.845871 -336.093411) (xy 81.856247 -336.174768) (xy 81.858104 -336.215736)
			(xy 81.858828 -336.22455) (xy 81.865419 -336.240944) (xy 81.877182 -336.254128) (xy 81.884774 -336.258662)
			(xy 81.973928 -336.306922) (xy 82.000852 -336.30616) (xy 82.012536 -336.299048) (xy 82.047432 -336.278305)
			(xy 82.120306 -336.242523) (xy 82.19614 -336.213534) (xy 82.2743 -336.191579) (xy 82.354137 -336.176843)
			(xy 82.434985 -336.169448) (xy 82.475578 -336.169) (xy 82.516691 -336.169534) (xy 82.598566 -336.177119)
			(xy 82.679391 -336.192225) (xy 82.758479 -336.214725) (xy 82.835153 -336.244426) (xy 82.908759 -336.281075)
			(xy 82.97867 -336.324359) (xy 83.044289 -336.373909) (xy 83.105056 -336.429302) (xy 83.160453 -336.490065)
			(xy 83.210007 -336.555681) (xy 83.253296 -336.625589) (xy 83.28995 -336.699193) (xy 83.319656 -336.775864)
			(xy 83.342161 -336.85495) (xy 83.357273 -336.935775) (xy 83.360149 -336.9668) (xy 86.931981 -336.9668)
			(xy 86.935971 -336.883042) (xy 86.947905 -336.800043) (xy 86.967674 -336.718554) (xy 86.9951 -336.639313)
			(xy 87.029935 -336.563039) (xy 87.071862 -336.490421) (xy 87.120503 -336.422117) (xy 87.175416 -336.358746)
			(xy 87.236104 -336.300883) (xy 87.302018 -336.24905) (xy 87.37256 -336.203717) (xy 87.447092 -336.165296)
			(xy 87.52494 -336.134133) (xy 87.605396 -336.110512) (xy 87.687734 -336.094645) (xy 87.771208 -336.086677)
			(xy 87.813134 -336.086196) (xy 87.81415 -336.086196) (xy 87.851207 -336.086587) (xy 87.925057 -336.092856)
			(xy 87.998119 -336.105302) (xy 88.069879 -336.123838) (xy 88.10498 -336.135726) (xy 88.113177 -336.13824)
			(xy 88.130311 -336.13824) (xy 88.138508 -336.135726) (xy 88.173727 -336.123789) (xy 88.245736 -336.1052)
			(xy 88.319058 -336.092757) (xy 88.393169 -336.086549) (xy 88.430354 -336.086196) (xy 88.454992 -336.08645)
			(xy 88.464629 -336.040549) (xy 88.49238 -335.950951) (xy 88.510364 -335.907634) (xy 88.514021 -335.89793)
			(xy 88.514009 -335.877211) (xy 88.510364 -335.867502) (xy 88.493256 -335.826243) (xy 88.466465 -335.741033)
			(xy 88.448429 -335.65355) (xy 88.439333 -335.564691) (xy 88.438736 -335.52003) (xy 88.438736 -335.519268)
			(xy 88.439235 -335.477343) (xy 88.447205 -335.393872) (xy 88.463074 -335.311537) (xy 88.486697 -335.231083)
			(xy 88.517861 -335.153239) (xy 88.556284 -335.078709) (xy 88.601617 -335.00817) (xy 88.65345 -334.942259)
			(xy 88.711313 -334.881573) (xy 88.774683 -334.826663) (xy 88.842986 -334.778025) (xy 88.915603 -334.7361)
			(xy 88.991876 -334.701267) (xy 89.071115 -334.673842) (xy 89.152601 -334.654073) (xy 89.235598 -334.64214)
			(xy 89.319354 -334.638151) (xy 89.40311 -334.64214) (xy 89.486107 -334.654073) (xy 89.567593 -334.673842)
			(xy 89.646832 -334.701267) (xy 89.723105 -334.7361) (xy 89.795722 -334.778025) (xy 89.864025 -334.826663)
			(xy 89.927395 -334.881573) (xy 89.985258 -334.942259) (xy 90.037091 -335.00817) (xy 90.082424 -335.078709)
			(xy 90.120847 -335.153239) (xy 90.152011 -335.231083) (xy 90.175634 -335.311537) (xy 90.191503 -335.393872)
			(xy 90.199473 -335.477343) (xy 90.199972 -335.519268) (xy 90.199972 -335.52003) (xy 90.199408 -335.564694)
			(xy 90.190332 -335.653559) (xy 90.172298 -335.741047) (xy 90.145491 -335.826257) (xy 90.128344 -335.867502)
			(xy 90.124724 -335.877216) (xy 90.124712 -335.897925) (xy 90.128344 -335.907634) (xy 90.14352 -335.944017)
			(xy 90.168055 -336.018939) (xy 90.185802 -336.095753) (xy 90.196619 -336.173844) (xy 90.198956 -336.213196)
			(xy 90.198956 -336.21345) (xy 90.199799 -336.222253) (xy 90.206694 -336.238523) (xy 90.218709 -336.251482)
			(xy 90.226388 -336.255868) (xy 90.316812 -336.302604) (xy 90.343482 -336.301334) (xy 90.355166 -336.293968)
			(xy 90.390883 -336.271832) (xy 90.465707 -336.233583) (xy 90.543804 -336.20256) (xy 90.624479 -336.17904)
			(xy 90.707013 -336.163233) (xy 90.790669 -336.155279) (xy 90.832686 -336.154776) (xy 90.833194 -336.154776)
			(xy 90.874302 -336.155218) (xy 90.956167 -336.162803) (xy 91.036983 -336.177907) (xy 91.116061 -336.200402)
			(xy 91.192727 -336.230097) (xy 91.266326 -336.266738) (xy 91.336231 -336.310013) (xy 91.401845 -336.359552)
			(xy 91.46261 -336.414933) (xy 91.518006 -336.475684) (xy 91.567562 -336.541286) (xy 91.610854 -336.61118)
			(xy 91.647513 -336.68477) (xy 91.677227 -336.761428) (xy 91.699742 -336.840501) (xy 91.714867 -336.921313)
			(xy 91.722471 -337.003176) (xy 91.722641 -337.0176) (xy 95.263181 -337.0176) (xy 95.267171 -336.933842)
			(xy 95.279105 -336.850843) (xy 95.298874 -336.769354) (xy 95.3263 -336.690113) (xy 95.361135 -336.613839)
			(xy 95.403062 -336.541221) (xy 95.451703 -336.472917) (xy 95.506616 -336.409546) (xy 95.567304 -336.351683)
			(xy 95.633218 -336.29985) (xy 95.70376 -336.254517) (xy 95.778292 -336.216096) (xy 95.85614 -336.184933)
			(xy 95.936596 -336.161312) (xy 96.018934 -336.145445) (xy 96.102408 -336.137477) (xy 96.144334 -336.136996)
			(xy 96.14535 -336.136996) (xy 96.182407 -336.137387) (xy 96.256257 -336.143656) (xy 96.329319 -336.156102)
			(xy 96.401079 -336.174638) (xy 96.43618 -336.186526) (xy 96.444377 -336.18904) (xy 96.461511 -336.18904)
			(xy 96.469708 -336.186526) (xy 96.504897 -336.174599) (xy 96.576843 -336.15602) (xy 96.650101 -336.143577)
			(xy 96.724146 -336.137359) (xy 96.7613 -336.136996) (xy 96.761808 -336.136996) (xy 96.796352 -336.137504)
			(xy 96.805918 -336.09484) (xy 96.832381 -336.0115) (xy 96.849184 -335.971134) (xy 96.852845 -335.961431)
			(xy 96.852833 -335.940711) (xy 96.849184 -335.931002) (xy 96.832077 -335.889743) (xy 96.805286 -335.804532)
			(xy 96.78725 -335.717049) (xy 96.778153 -335.628191) (xy 96.777556 -335.58353) (xy 96.777556 -335.582768)
			(xy 96.778055 -335.540843) (xy 96.786025 -335.457372) (xy 96.801894 -335.375037) (xy 96.825517 -335.294583)
			(xy 96.856681 -335.216739) (xy 96.895104 -335.142209) (xy 96.940437 -335.07167) (xy 96.99227 -335.005759)
			(xy 97.050133 -334.945073) (xy 97.113503 -334.890163) (xy 97.181806 -334.841525) (xy 97.254423 -334.7996)
			(xy 97.330696 -334.764767) (xy 97.409935 -334.737342) (xy 97.491421 -334.717573) (xy 97.574418 -334.70564)
			(xy 97.658174 -334.701651) (xy 97.74193 -334.70564) (xy 97.824927 -334.717573) (xy 97.906413 -334.737342)
			(xy 97.985652 -334.764767) (xy 98.061925 -334.7996) (xy 98.134542 -334.841525) (xy 98.202845 -334.890163)
			(xy 98.266215 -334.945073) (xy 98.324078 -335.005759) (xy 98.375911 -335.07167) (xy 98.421244 -335.142209)
			(xy 98.459667 -335.216739) (xy 98.490831 -335.294583) (xy 98.514454 -335.375037) (xy 98.530323 -335.457372)
			(xy 98.538293 -335.540843) (xy 98.538792 -335.582768) (xy 98.538792 -335.58353) (xy 98.538226 -335.628194)
			(xy 98.529151 -335.717059) (xy 98.511117 -335.804547) (xy 98.484311 -335.889757) (xy 98.467164 -335.931002)
			(xy 98.463542 -335.940716) (xy 98.463531 -335.961426) (xy 98.467164 -335.971134) (xy 98.48433 -336.012473)
			(xy 98.511159 -336.097874) (xy 98.529194 -336.185554) (xy 98.538249 -336.27461) (xy 98.538792 -336.319368)
			(xy 98.538552 -336.350973) (xy 98.534101 -336.414026) (xy 98.529902 -336.445352) (xy 98.528378 -336.45602)
			(xy 98.53422 -336.477102) (xy 98.590608 -336.543396) (xy 98.597904 -336.55118) (xy 98.617064 -336.560504)
			(xy 98.627692 -336.56143) (xy 98.6282 -336.56143) (xy 98.671147 -336.563026) (xy 98.756458 -336.573467)
			(xy 98.840365 -336.592088) (xy 98.922084 -336.618714) (xy 99.000854 -336.653099) (xy 99.07594 -336.69492)
			(xy 99.146643 -336.743788) (xy 99.212303 -336.799248) (xy 99.272307 -336.860782) (xy 99.326097 -336.927817)
			(xy 99.362614 -336.9836) (xy 318.155561 -336.9836) (xy 318.15955 -336.899842) (xy 318.171484 -336.816843)
			(xy 318.191253 -336.735354) (xy 318.218678 -336.656114) (xy 318.253512 -336.579839) (xy 318.295438 -336.50722)
			(xy 318.344078 -336.438916) (xy 318.398989 -336.375544) (xy 318.459676 -336.317679) (xy 318.525589 -336.265845)
			(xy 318.59613 -336.220511) (xy 318.670661 -336.182087) (xy 318.748507 -336.150922) (xy 318.828963 -336.127298)
			(xy 318.911301 -336.111429) (xy 318.994774 -336.103459) (xy 319.0367 -336.10296) (xy 319.037716 -336.10296)
			(xy 319.074773 -336.103363) (xy 319.148622 -336.109628) (xy 319.221685 -336.122071) (xy 319.293445 -336.140604)
			(xy 319.328546 -336.15249) (xy 319.336743 -336.155004) (xy 319.353877 -336.155004) (xy 319.362074 -336.15249)
			(xy 319.397267 -336.140575) (xy 319.469212 -336.121992) (xy 319.542468 -336.109546) (xy 319.616513 -336.103324)
			(xy 319.653666 -336.10296) (xy 319.654174 -336.10296) (xy 319.681606 -336.103214) (xy 319.687655 -336.066844)
			(xy 319.704988 -335.995173) (xy 319.728195 -335.925184) (xy 319.742312 -335.891124) (xy 319.745871 -335.881532)
			(xy 319.745875 -335.86109) (xy 319.742312 -335.8515) (xy 319.725303 -335.810117) (xy 319.698681 -335.724692)
			(xy 319.680772 -335.637026) (xy 319.671759 -335.548004) (xy 319.671192 -335.503266) (xy 319.671192 -335.503012)
			(xy 319.671696 -335.460664) (xy 319.679747 -335.37635) (xy 319.695776 -335.293184) (xy 319.719637 -335.211917)
			(xy 319.751116 -335.133287) (xy 319.789927 -335.058006) (xy 319.835717 -334.986754) (xy 319.888073 -334.920178)
			(xy 319.946521 -334.85888) (xy 320.010531 -334.803415) (xy 320.079523 -334.754286) (xy 320.152873 -334.711937)
			(xy 320.229916 -334.676753) (xy 320.309955 -334.649051) (xy 320.392264 -334.629083) (xy 320.476099 -334.61703)
			(xy 320.5607 -334.613) (xy 320.645301 -334.61703) (xy 320.729136 -334.629083) (xy 320.811445 -334.649051)
			(xy 320.891484 -334.676753) (xy 320.968527 -334.711937) (xy 321.041877 -334.754286) (xy 321.110869 -334.803415)
			(xy 321.174879 -334.85888) (xy 321.233327 -334.920178) (xy 321.285683 -334.986754) (xy 321.331473 -335.058006)
			(xy 321.370284 -335.133287) (xy 321.401763 -335.211917) (xy 321.425624 -335.293184) (xy 321.441653 -335.37635)
			(xy 321.449704 -335.460664) (xy 321.450208 -335.503012) (xy 321.450208 -335.503266) (xy 321.449645 -335.548004)
			(xy 321.440627 -335.637026) (xy 321.422721 -335.724694) (xy 321.396107 -335.810121) (xy 321.379088 -335.8515)
			(xy 321.375596 -335.861115) (xy 321.37573 -335.881553) (xy 321.379342 -335.891124) (xy 321.395061 -335.929255)
			(xy 321.42019 -336.007817) (xy 321.437947 -336.088366) (xy 321.448179 -336.170212) (xy 321.449954 -336.211418)
			(xy 321.450208 -336.22488) (xy 321.464178 -336.24774) (xy 321.564762 -336.303112) (xy 321.591432 -336.302604)
			(xy 321.603116 -336.295746) (xy 321.637431 -336.275914) (xy 321.708951 -336.241747) (xy 321.783227 -336.214078)
			(xy 321.859671 -336.193127) (xy 321.937675 -336.179058) (xy 322.016621 -336.171985) (xy 322.056252 -336.17154)
			(xy 322.05676 -336.17154) (xy 322.097864 -336.17199) (xy 322.179721 -336.179572) (xy 322.26053 -336.194675)
			(xy 322.3396 -336.21717) (xy 322.416257 -336.246866) (xy 322.489847 -336.283508) (xy 322.559742 -336.326784)
			(xy 322.625346 -336.376325) (xy 322.686098 -336.431708) (xy 322.74148 -336.492461) (xy 322.791021 -336.558064)
			(xy 322.834296 -336.62796) (xy 322.870938 -336.70155) (xy 322.900632 -336.778207) (xy 322.923127 -336.857278)
			(xy 322.938229 -336.938087) (xy 322.941787 -336.9765) (xy 326.511148 -336.9765) (xy 326.515138 -336.892742)
			(xy 326.527072 -336.809743) (xy 326.546841 -336.728254) (xy 326.574266 -336.649013) (xy 326.609099 -336.572737)
			(xy 326.651025 -336.500118) (xy 326.699664 -336.431814) (xy 326.754575 -336.368441) (xy 326.815262 -336.310576)
			(xy 326.881174 -336.258741) (xy 326.951715 -336.213406) (xy 327.026246 -336.174981) (xy 327.104092 -336.143815)
			(xy 327.184547 -336.12019) (xy 327.266885 -336.104319) (xy 327.350358 -336.096347) (xy 327.392284 -336.095848)
			(xy 327.3933 -336.095848) (xy 327.430357 -336.096256) (xy 327.504206 -336.10252) (xy 327.577268 -336.114961)
			(xy 327.649028 -336.133493) (xy 327.68413 -336.145378) (xy 327.692327 -336.147892) (xy 327.709461 -336.147892)
			(xy 327.717658 -336.145378) (xy 327.752881 -336.133453) (xy 327.824889 -336.114861) (xy 327.898209 -336.102415)
			(xy 327.972319 -336.096203) (xy 328.009504 -336.095848) (xy 328.043286 -336.096356) (xy 328.05281 -336.047304)
			(xy 328.081456 -335.951571) (xy 328.100436 -335.905348) (xy 328.10398 -335.895751) (xy 328.103994 -335.875314)
			(xy 328.100436 -335.865724) (xy 328.083404 -335.82435) (xy 328.056787 -335.738922) (xy 328.038886 -335.651253)
			(xy 328.02988 -335.562229) (xy 328.029316 -335.51749) (xy 328.029316 -335.517236) (xy 328.02982 -335.474888)
			(xy 328.037871 -335.390574) (xy 328.0539 -335.307408) (xy 328.077761 -335.226141) (xy 328.10924 -335.147511)
			(xy 328.148051 -335.07223) (xy 328.193841 -335.000978) (xy 328.246197 -334.934402) (xy 328.304645 -334.873104)
			(xy 328.368655 -334.817639) (xy 328.437647 -334.76851) (xy 328.510997 -334.726161) (xy 328.58804 -334.690977)
			(xy 328.668079 -334.663275) (xy 328.750388 -334.643307) (xy 328.834223 -334.631254) (xy 328.918824 -334.627224)
			(xy 329.003425 -334.631254) (xy 329.08726 -334.643307) (xy 329.169569 -334.663275) (xy 329.249608 -334.690977)
			(xy 329.326651 -334.726161) (xy 329.400001 -334.76851) (xy 329.468993 -334.817639) (xy 329.533003 -334.873104)
			(xy 329.591451 -334.934402) (xy 329.643807 -335.000978) (xy 329.689597 -335.07223) (xy 329.728408 -335.147511)
			(xy 329.759887 -335.226141) (xy 329.783748 -335.307408) (xy 329.799777 -335.390574) (xy 329.807828 -335.474888)
			(xy 329.808332 -335.517236) (xy 329.808332 -335.51749) (xy 329.807775 -335.562229) (xy 329.798756 -335.651251)
			(xy 329.780848 -335.738918) (xy 329.754231 -335.824345) (xy 329.737212 -335.865724) (xy 329.733624 -335.875308)
			(xy 329.733638 -335.895757) (xy 329.737212 -335.905348) (xy 329.752022 -335.941175) (xy 329.776095 -336.014872)
			(xy 329.793653 -336.090386) (xy 329.804563 -336.167144) (xy 329.807062 -336.20583) (xy 329.807824 -336.219038)
			(xy 329.822048 -336.24139) (xy 329.91044 -336.288888) (xy 329.918254 -336.292745) (xy 329.93547 -336.295369)
			(xy 329.95256 -336.292022) (xy 329.960224 -336.287872) (xy 329.994483 -336.268147) (xy 330.065868 -336.23417)
			(xy 330.139986 -336.206662) (xy 330.216254 -336.18584) (xy 330.294068 -336.171868) (xy 330.372815 -336.164856)
			(xy 330.412344 -336.164428) (xy 330.453448 -336.164825) (xy 330.535306 -336.172414) (xy 330.616114 -336.187524)
			(xy 330.695183 -336.210025) (xy 330.771839 -336.239726) (xy 330.845427 -336.276373) (xy 330.91532 -336.319653)
			(xy 330.980922 -336.369198) (xy 331.041672 -336.424584) (xy 331.097053 -336.48534) (xy 331.146592 -336.550946)
			(xy 331.189866 -336.620843) (xy 331.226507 -336.694434) (xy 331.256201 -336.771093) (xy 331.278695 -336.850164)
			(xy 331.293797 -336.930973) (xy 331.296671 -336.962) (xy 334.868517 -336.962) (xy 334.872507 -336.878219)
			(xy 334.884444 -336.795197) (xy 334.904219 -336.713686) (xy 334.931652 -336.634423) (xy 334.966495 -336.558127)
			(xy 335.008433 -336.485488) (xy 335.057086 -336.417165) (xy 335.112013 -336.353776) (xy 335.172717 -336.295895)
			(xy 335.238647 -336.244046) (xy 335.309208 -336.198699) (xy 335.38376 -336.160265) (xy 335.461628 -336.129092)
			(xy 335.542106 -336.105461) (xy 335.624466 -336.089588) (xy 335.707962 -336.081615) (xy 335.7499 -336.081116)
			(xy 335.78709 -336.081504) (xy 335.861203 -336.087794) (xy 335.934522 -336.100304) (xy 336.006528 -336.118945)
			(xy 336.041746 -336.1309) (xy 336.049943 -336.133414) (xy 336.067077 -336.133414) (xy 336.075274 -336.1309)
			(xy 336.110487 -336.118927) (xy 336.182491 -336.100276) (xy 336.255813 -336.08777) (xy 336.329929 -336.0815)
			(xy 336.36712 -336.081116) (xy 336.407506 -336.082132) (xy 336.417036 -336.036786) (xy 336.444265 -335.948213)
			(xy 336.461862 -335.905348) (xy 336.465474 -335.895775) (xy 336.465619 -335.875336) (xy 336.462116 -335.865724)
			(xy 336.445083 -335.824351) (xy 336.418467 -335.738922) (xy 336.400565 -335.651253) (xy 336.39156 -335.562229)
			(xy 336.390996 -335.51749) (xy 336.390996 -335.517236) (xy 336.3915 -335.474888) (xy 336.399551 -335.390574)
			(xy 336.41558 -335.307408) (xy 336.439441 -335.226141) (xy 336.47092 -335.147511) (xy 336.509731 -335.07223)
			(xy 336.555521 -335.000978) (xy 336.607877 -334.934402) (xy 336.666325 -334.873104) (xy 336.730335 -334.817639)
			(xy 336.799327 -334.76851) (xy 336.872677 -334.726161) (xy 336.94972 -334.690977) (xy 337.029759 -334.663275)
			(xy 337.112068 -334.643307) (xy 337.195903 -334.631254) (xy 337.280504 -334.627224) (xy 337.365105 -334.631254)
			(xy 337.44894 -334.643307) (xy 337.531249 -334.663275) (xy 337.611288 -334.690977) (xy 337.688331 -334.726161)
			(xy 337.761681 -334.76851) (xy 337.830673 -334.817639) (xy 337.894683 -334.873104) (xy 337.953131 -334.934402)
			(xy 338.005487 -335.000978) (xy 338.051277 -335.07223) (xy 338.090088 -335.147511) (xy 338.121567 -335.226141)
			(xy 338.145428 -335.307408) (xy 338.161457 -335.390574) (xy 338.169508 -335.474888) (xy 338.170012 -335.517236)
			(xy 338.170012 -335.51749) (xy 338.169456 -335.562229) (xy 338.160437 -335.651251) (xy 338.142528 -335.738918)
			(xy 338.115912 -335.824345) (xy 338.098892 -335.865724) (xy 338.095386 -335.875335) (xy 338.09553 -335.895777)
			(xy 338.099146 -335.905348) (xy 338.117792 -335.95091) (xy 338.146101 -336.045203) (xy 338.163844 -336.142042)
			(xy 338.16798 -336.191098) (xy 338.168919 -336.199672) (xy 338.175759 -336.215494) (xy 338.187449 -336.228161)
			(xy 338.194904 -336.2325) (xy 338.283042 -336.278728) (xy 338.309204 -336.27822) (xy 338.320634 -336.271616)
			(xy 338.354723 -336.252133) (xy 338.425722 -336.218592) (xy 338.499399 -336.191437) (xy 338.575183 -336.170878)
			(xy 338.652483 -336.157075) (xy 338.730699 -336.150137) (xy 338.76996 -336.149696) (xy 338.811054 -336.150204)
			(xy 338.892893 -336.157783) (xy 338.973684 -336.172879) (xy 339.052737 -336.195365) (xy 339.129379 -336.225047)
			(xy 339.202956 -336.261673) (xy 339.27284 -336.304931) (xy 339.338435 -336.354452) (xy 339.399182 -336.409813)
			(xy 339.454563 -336.470542) (xy 339.504105 -336.536121) (xy 339.547386 -336.605991) (xy 339.584036 -336.679555)
			(xy 339.613743 -336.756188) (xy 339.636254 -336.835234) (xy 339.651377 -336.916019) (xy 339.658982 -336.997856)
			(xy 339.659159 -337.0128) (xy 343.199717 -337.0128) (xy 343.203707 -336.929019) (xy 343.215644 -336.845997)
			(xy 343.235419 -336.764486) (xy 343.262852 -336.685223) (xy 343.297695 -336.608927) (xy 343.339633 -336.536288)
			(xy 343.388286 -336.467965) (xy 343.443213 -336.404576) (xy 343.503917 -336.346695) (xy 343.569847 -336.294846)
			(xy 343.640408 -336.249499) (xy 343.71496 -336.211065) (xy 343.792828 -336.179892) (xy 343.873306 -336.156261)
			(xy 343.955666 -336.140388) (xy 344.039162 -336.132415) (xy 344.0811 -336.131916) (xy 344.11829 -336.132304)
			(xy 344.192403 -336.138594) (xy 344.265722 -336.151104) (xy 344.337728 -336.169745) (xy 344.372946 -336.1817)
			(xy 344.381143 -336.184214) (xy 344.398277 -336.184214) (xy 344.406474 -336.1817) (xy 344.441687 -336.169727)
			(xy 344.513691 -336.151076) (xy 344.587013 -336.13857) (xy 344.661129 -336.1323) (xy 344.69832 -336.131916)
			(xy 344.712798 -336.13217) (xy 344.724169 -336.131792) (xy 344.744841 -336.122355) (xy 344.759419 -336.104924)
			(xy 344.762836 -336.09407) (xy 344.771457 -336.062103) (xy 344.792812 -335.999426) (xy 344.805508 -335.968848)
			(xy 344.809054 -335.959252) (xy 344.809067 -335.938814) (xy 344.805508 -335.929224) (xy 344.788475 -335.887851)
			(xy 344.761859 -335.802423) (xy 344.743957 -335.714753) (xy 344.734952 -335.625729) (xy 344.734388 -335.58099)
			(xy 344.734388 -335.580736) (xy 344.734892 -335.538388) (xy 344.742943 -335.454074) (xy 344.758972 -335.370908)
			(xy 344.782833 -335.289641) (xy 344.814312 -335.211011) (xy 344.853123 -335.13573) (xy 344.898913 -335.064478)
			(xy 344.951269 -334.997902) (xy 345.009717 -334.936604) (xy 345.073727 -334.881139) (xy 345.142719 -334.83201)
			(xy 345.216069 -334.789661) (xy 345.293112 -334.754477) (xy 345.373151 -334.726775) (xy 345.45546 -334.706807)
			(xy 345.539295 -334.694754) (xy 345.623896 -334.690724) (xy 345.708497 -334.694754) (xy 345.792332 -334.706807)
			(xy 345.874641 -334.726775) (xy 345.95468 -334.754477) (xy 346.031723 -334.789661) (xy 346.105073 -334.83201)
			(xy 346.174065 -334.881139) (xy 346.238075 -334.936604) (xy 346.296523 -334.997902) (xy 346.348879 -335.064478)
			(xy 346.394669 -335.13573) (xy 346.43348 -335.211011) (xy 346.464959 -335.289641) (xy 346.48882 -335.370908)
			(xy 346.504849 -335.454074) (xy 346.5129 -335.538388) (xy 346.513404 -335.580736) (xy 346.513404 -335.58099)
			(xy 346.512849 -335.625729) (xy 346.50383 -335.714751) (xy 346.485921 -335.802418) (xy 346.459304 -335.887845)
			(xy 346.442284 -335.929224) (xy 346.438698 -335.938808) (xy 346.438711 -335.959257) (xy 346.442284 -335.968848)
			(xy 346.459319 -336.010255) (xy 346.48595 -336.095744) (xy 346.503854 -336.183477) (xy 346.51285 -336.272565)
			(xy 346.513404 -336.317336) (xy 346.513182 -336.348682) (xy 346.508857 -336.411225) (xy 346.504768 -336.442304)
			(xy 346.503244 -336.452972) (xy 346.508832 -336.473546) (xy 346.56268 -336.539586) (xy 346.569651 -336.547336)
			(xy 346.588142 -336.55691) (xy 346.598494 -336.558128) (xy 346.599002 -336.558128) (xy 346.640786 -336.561293)
			(xy 346.723543 -336.574476) (xy 346.804694 -336.595383) (xy 346.883519 -336.62383) (xy 346.959319 -336.659564)
			(xy 347.031422 -336.702268) (xy 347.09919 -336.751564) (xy 347.162022 -336.807015) (xy 347.21936 -336.868129)
			(xy 347.270696 -336.934365) (xy 347.315576 -337.005135) (xy 347.353601 -337.079812) (xy 347.384434 -337.157734)
			(xy 347.407802 -337.238211) (xy 347.423499 -337.320529) (xy 347.431384 -337.403958) (xy 347.431868 -337.445858)
			(xy 347.431868 -337.446874) (xy 347.431339 -337.489485) (xy 347.423121 -337.57431) (xy 347.406824 -337.657959)
			(xy 347.382599 -337.739665) (xy 347.367098 -337.77936) (xy 347.363634 -337.789438) (xy 347.36443 -337.810709)
			(xy 347.368622 -337.820508) (xy 347.385666 -337.856788) (xy 347.413917 -337.931808) (xy 347.435302 -338.009067)
			(xy 347.449648 -338.087936) (xy 347.456838 -338.167776) (xy 347.457268 -338.207858) (xy 347.456674 -338.254253)
			(xy 347.447033 -338.346541) (xy 347.42784 -338.437325) (xy 347.399305 -338.525619) (xy 347.381068 -338.568284)
			(xy 347.377284 -338.578233) (xy 347.377268 -338.599491) (xy 347.381068 -338.609432) (xy 347.399296 -338.652101)
			(xy 347.427845 -338.740391) (xy 347.447043 -338.831174) (xy 347.456681 -338.923462) (xy 347.457268 -338.969858)
			(xy 347.456674 -339.016253) (xy 347.447033 -339.108541) (xy 347.42784 -339.199325) (xy 347.399305 -339.287619)
			(xy 347.381068 -339.330284) (xy 347.377284 -339.340233) (xy 347.377268 -339.361491) (xy 347.381068 -339.371432)
			(xy 347.39928 -339.414039) (xy 347.427799 -339.502205) (xy 347.446995 -339.592859) (xy 347.456658 -339.685018)
			(xy 347.457268 -339.73135) (xy 347.457268 -339.731858) (xy 347.456747 -339.772964) (xy 347.449167 -339.854825)
			(xy 347.434067 -339.935639) (xy 347.411576 -340.014714) (xy 347.381885 -340.091377) (xy 347.345249 -340.164975)
			(xy 347.30198 -340.234878) (xy 347.252446 -340.300492) (xy 347.19707 -340.361256) (xy 347.136324 -340.416653)
			(xy 347.070727 -340.466209) (xy 347.000838 -340.509502) (xy 346.927254 -340.546163) (xy 346.8506 -340.575879)
			(xy 346.771533 -340.598397) (xy 346.690725 -340.613525) (xy 346.608866 -340.621133) (xy 346.56776 -340.62162)
			(xy 346.525159 -340.621134) (xy 346.440349 -340.612975) (xy 346.356708 -340.596745) (xy 346.275001 -340.572593)
			(xy 346.195978 -340.540739) (xy 346.120362 -340.501477) (xy 346.048846 -340.455165) (xy 345.982085 -340.402229)
			(xy 345.920691 -340.343152) (xy 345.865226 -340.278476) (xy 345.840304 -340.243922) (xy 345.834713 -340.236567)
			(xy 345.819465 -340.226159) (xy 345.810586 -340.223602) (xy 345.769427 -340.213207) (xy 345.689122 -340.185668)
			(xy 345.611806 -340.150603) (xy 345.538183 -340.108332) (xy 345.468921 -340.05924) (xy 345.40465 -340.003772)
			(xy 345.345957 -339.942434) (xy 345.293373 -339.875784) (xy 345.247379 -339.804427) (xy 345.208391 -339.729013)
			(xy 345.176765 -339.650228) (xy 345.152789 -339.568788) (xy 345.136679 -339.485435) (xy 345.128584 -339.400926)
			(xy 345.128088 -339.358478) (xy 345.128088 -339.358224) (xy 345.128648 -339.313485) (xy 345.137666 -339.224464)
			(xy 345.155574 -339.136796) (xy 345.182189 -339.051369) (xy 345.199208 -339.00999) (xy 345.202787 -339.000403)
			(xy 345.202779 -338.979957) (xy 345.199208 -338.970366) (xy 345.182177 -338.928958) (xy 345.155545 -338.843469)
			(xy 345.13764 -338.755736) (xy 345.128642 -338.666649) (xy 345.128088 -338.621878) (xy 345.128637 -338.577108)
			(xy 345.137642 -338.488021) (xy 345.15555 -338.400289) (xy 345.182178 -338.314799) (xy 345.199208 -338.27339)
			(xy 345.202787 -338.263803) (xy 345.202779 -338.243357) (xy 345.199208 -338.233766) (xy 345.182177 -338.192358)
			(xy 345.155545 -338.106869) (xy 345.13764 -338.019136) (xy 345.128642 -337.930049) (xy 345.128088 -337.885278)
			(xy 345.128088 -337.87334) (xy 345.101609 -337.867394) (xy 345.049374 -337.852651) (xy 345.023694 -337.843876)
			(xy 345.015497 -337.841362) (xy 344.998363 -337.841362) (xy 344.990166 -337.843876) (xy 344.95495 -337.855837)
			(xy 344.882946 -337.874492) (xy 344.809626 -337.887) (xy 344.73551 -337.893274) (xy 344.69832 -337.89366)
			(xy 344.661131 -337.893262) (xy 344.587018 -337.886974) (xy 344.513698 -337.874467) (xy 344.441692 -337.855829)
			(xy 344.406474 -337.843876) (xy 344.398277 -337.841362) (xy 344.381143 -337.841362) (xy 344.372946 -337.843876)
			(xy 344.337731 -337.855842) (xy 344.265728 -337.874496) (xy 344.192406 -337.887003) (xy 344.11829 -337.893275)
			(xy 344.0811 -337.89366) (xy 344.039162 -337.893185) (xy 343.955666 -337.885212) (xy 343.873306 -337.869339)
			(xy 343.792828 -337.845708) (xy 343.71496 -337.814535) (xy 343.640408 -337.776101) (xy 343.569847 -337.730754)
			(xy 343.503917 -337.678905) (xy 343.443213 -337.621024) (xy 343.388286 -337.557635) (xy 343.339633 -337.489312)
			(xy 343.297695 -337.416673) (xy 343.262852 -337.340377) (xy 343.235419 -337.261114) (xy 343.215644 -337.179603)
			(xy 343.203707 -337.096581) (xy 343.199717 -337.0128) (xy 339.659159 -337.0128) (xy 339.659468 -337.03895)
			(xy 339.659468 -337.039458) (xy 339.6589 -337.084228) (xy 339.649901 -337.173314) (xy 339.631999 -337.261046)
			(xy 339.605375 -337.346537) (xy 339.588348 -337.387946) (xy 339.584808 -337.397544) (xy 339.584792 -337.41798)
			(xy 339.588348 -337.42757) (xy 339.605388 -337.468975) (xy 339.632018 -337.554465) (xy 339.649921 -337.642198)
			(xy 339.658915 -337.731287) (xy 339.659468 -337.776058) (xy 339.6589 -337.820828) (xy 339.649901 -337.909914)
			(xy 339.631999 -337.997646) (xy 339.605375 -338.083137) (xy 339.588348 -338.124546) (xy 339.584808 -338.134144)
			(xy 339.584792 -338.15458) (xy 339.588348 -338.16417) (xy 339.605377 -338.205545) (xy 339.631995 -338.290972)
			(xy 339.649897 -338.378641) (xy 339.658904 -338.467665) (xy 339.659468 -338.512404) (xy 339.659468 -338.512658)
			(xy 339.658947 -338.553764) (xy 339.651367 -338.635625) (xy 339.636267 -338.716439) (xy 339.613776 -338.795514)
			(xy 339.584085 -338.872177) (xy 339.547449 -338.945775) (xy 339.50418 -339.015678) (xy 339.454646 -339.081292)
			(xy 339.39927 -339.142056) (xy 339.338524 -339.197453) (xy 339.272927 -339.247009) (xy 339.203038 -339.290302)
			(xy 339.129454 -339.326963) (xy 339.0528 -339.356679) (xy 338.973733 -339.379197) (xy 338.892925 -339.394325)
			(xy 338.811066 -339.401933) (xy 338.76996 -339.40242) (xy 338.728351 -339.40191) (xy 338.645495 -339.394139)
			(xy 338.563727 -339.378669) (xy 338.483759 -339.355636) (xy 338.40629 -339.325239) (xy 338.331996 -339.287745)
			(xy 338.296504 -339.266022) (xy 338.287367 -339.260856) (xy 338.26665 -339.257639) (xy 338.246374 -339.262975)
			(xy 338.23783 -339.26907) (xy 338.204174 -339.295024) (xy 338.132784 -339.341153) (xy 338.057318 -339.380258)
			(xy 337.978465 -339.411983) (xy 337.896945 -339.436039) (xy 337.8135 -339.452205) (xy 337.728894 -339.460335)
			(xy 337.686396 -339.46084) (xy 337.645302 -339.460338) (xy 337.563464 -339.452755) (xy 337.482675 -339.437656)
			(xy 337.403623 -339.415168) (xy 337.326982 -339.385484) (xy 337.253407 -339.348856) (xy 337.183524 -339.305597)
			(xy 337.11793 -339.256076) (xy 337.057184 -339.200716) (xy 337.001804 -339.139987) (xy 336.952262 -339.074409)
			(xy 336.908981 -339.00454) (xy 336.87233 -338.930976) (xy 336.842621 -338.854345) (xy 336.820109 -338.7753)
			(xy 336.804984 -338.694515) (xy 336.797375 -338.61268) (xy 336.796888 -338.571586) (xy 336.796888 -338.571078)
			(xy 336.797437 -338.526308) (xy 336.806442 -338.437221) (xy 336.82435 -338.349489) (xy 336.850978 -338.263999)
			(xy 336.868008 -338.22259) (xy 336.871587 -338.213003) (xy 336.871579 -338.192557) (xy 336.868008 -338.182966)
			(xy 336.850977 -338.141558) (xy 336.824345 -338.056069) (xy 336.80644 -337.968336) (xy 336.797442 -337.879249)
			(xy 336.796888 -337.834478) (xy 336.796888 -337.82254) (xy 336.770409 -337.816594) (xy 336.718174 -337.801851)
			(xy 336.692494 -337.793076) (xy 336.684297 -337.790562) (xy 336.667163 -337.790562) (xy 336.658966 -337.793076)
			(xy 336.62375 -337.805037) (xy 336.551746 -337.823692) (xy 336.478426 -337.8362) (xy 336.40431 -337.842474)
			(xy 336.36712 -337.84286) (xy 336.329931 -337.842462) (xy 336.255818 -337.836174) (xy 336.182498 -337.823667)
			(xy 336.110492 -337.805029) (xy 336.075274 -337.793076) (xy 336.067077 -337.790562) (xy 336.049943 -337.790562)
			(xy 336.041746 -337.793076) (xy 336.006531 -337.805042) (xy 335.934528 -337.823696) (xy 335.861206 -337.836203)
			(xy 335.78709 -337.842475) (xy 335.7499 -337.84286) (xy 335.707962 -337.842385) (xy 335.624466 -337.834412)
			(xy 335.542106 -337.818539) (xy 335.461628 -337.794908) (xy 335.38376 -337.763735) (xy 335.309208 -337.725301)
			(xy 335.238647 -337.679954) (xy 335.172717 -337.628105) (xy 335.112013 -337.570224) (xy 335.057086 -337.506835)
			(xy 335.008433 -337.438512) (xy 334.966495 -337.365873) (xy 334.931652 -337.289577) (xy 334.904219 -337.210314)
			(xy 334.884444 -337.128803) (xy 334.872507 -337.045781) (xy 334.868517 -336.962) (xy 331.296671 -336.962)
			(xy 331.301379 -337.012832) (xy 331.301852 -337.053936) (xy 331.301852 -337.05419) (xy 331.301293 -337.098929)
			(xy 331.292274 -337.18795) (xy 331.274367 -337.275618) (xy 331.247751 -337.361045) (xy 331.230732 -337.402424)
			(xy 331.227148 -337.412009) (xy 331.227161 -337.432457) (xy 331.230732 -337.442048) (xy 331.247764 -337.483456)
			(xy 331.274397 -337.568945) (xy 331.292302 -337.656677) (xy 331.301298 -337.745765) (xy 331.301852 -337.790536)
			(xy 331.301312 -337.835307) (xy 331.292305 -337.924394) (xy 331.274395 -338.012126) (xy 331.247763 -338.097615)
			(xy 331.230732 -338.139024) (xy 331.227148 -338.148609) (xy 331.227161 -338.169057) (xy 331.230732 -338.178648)
			(xy 331.247759 -338.220024) (xy 331.274376 -338.305451) (xy 331.292279 -338.39312) (xy 331.301287 -338.482143)
			(xy 331.301852 -338.526882) (xy 331.301852 -338.527136) (xy 331.301368 -338.568238) (xy 331.29378 -338.65009)
			(xy 331.278673 -338.730894) (xy 331.256175 -338.809959) (xy 331.226478 -338.886611) (xy 331.189836 -338.960196)
			(xy 331.14656 -339.030087) (xy 331.097021 -339.095686) (xy 331.041641 -339.156436) (xy 330.980892 -339.211816)
			(xy 330.915293 -339.261356) (xy 330.845403 -339.304632) (xy 330.771818 -339.341275) (xy 330.695167 -339.370972)
			(xy 330.616102 -339.393471) (xy 330.535298 -339.408579) (xy 330.453446 -339.416167) (xy 330.412344 -339.416644)
			(xy 330.411582 -339.416644) (xy 330.370042 -339.416142) (xy 330.287326 -339.408361) (xy 330.205695 -339.392907)
			(xy 330.125859 -339.369913) (xy 330.048513 -339.339581) (xy 329.97433 -339.302172) (xy 329.938888 -339.2805)
			(xy 329.929757 -339.275322) (xy 329.909036 -339.272112) (xy 329.888759 -339.277452) (xy 329.880214 -339.283548)
			(xy 329.846565 -339.30947) (xy 329.775191 -339.355528) (xy 329.699752 -339.394575) (xy 329.620935 -339.426254)
			(xy 329.539458 -339.450278) (xy 329.456062 -339.466427) (xy 329.371506 -339.474554) (xy 329.329034 -339.475064)
			(xy 329.32878 -339.475064) (xy 329.287675 -339.474667) (xy 329.205817 -339.46708) (xy 329.125007 -339.451972)
			(xy 329.045936 -339.429472) (xy 328.969279 -339.399772) (xy 328.895689 -339.363126) (xy 328.825795 -339.319846)
			(xy 328.760192 -339.270301) (xy 328.69944 -339.214915) (xy 328.644058 -339.154159) (xy 328.594518 -339.088553)
			(xy 328.551243 -339.018655) (xy 328.514602 -338.945062) (xy 328.484908 -338.868403) (xy 328.462414 -338.789331)
			(xy 328.447312 -338.70852) (xy 328.43973 -338.626661) (xy 328.439272 -338.585556) (xy 328.439272 -338.585302)
			(xy 328.43986 -338.540564) (xy 328.44887 -338.451543) (xy 328.466769 -338.363876) (xy 328.493377 -338.278448)
			(xy 328.510392 -338.237068) (xy 328.513984 -338.227485) (xy 328.513968 -338.207035) (xy 328.510392 -338.197444)
			(xy 328.493353 -338.156039) (xy 328.466723 -338.070549) (xy 328.44882 -337.982815) (xy 328.439825 -337.893727)
			(xy 328.439272 -337.848956) (xy 328.439272 -337.837018) (xy 328.412793 -337.831074) (xy 328.360558 -337.81633)
			(xy 328.334878 -337.807554) (xy 328.326681 -337.80504) (xy 328.309547 -337.80504) (xy 328.30135 -337.807554)
			(xy 328.266125 -337.819474) (xy 328.194118 -337.838068) (xy 328.120798 -337.850516) (xy 328.046689 -337.856728)
			(xy 328.009504 -337.857084) (xy 327.97232 -337.856715) (xy 327.898212 -337.850493) (xy 327.824892 -337.838051)
			(xy 327.752881 -337.819476) (xy 327.717658 -337.807554) (xy 327.709461 -337.80504) (xy 327.692327 -337.80504)
			(xy 327.68413 -337.807554) (xy 327.649029 -337.819442) (xy 327.577272 -337.837992) (xy 327.504209 -337.850438)
			(xy 327.430358 -337.856691) (xy 327.3933 -337.857084) (xy 327.392284 -337.857084) (xy 327.350358 -337.856653)
			(xy 327.266885 -337.848681) (xy 327.184547 -337.83281) (xy 327.104092 -337.809185) (xy 327.026246 -337.778019)
			(xy 326.951715 -337.739594) (xy 326.881174 -337.694259) (xy 326.815262 -337.642424) (xy 326.754575 -337.584559)
			(xy 326.699664 -337.521186) (xy 326.651025 -337.452882) (xy 326.609099 -337.380263) (xy 326.574266 -337.303987)
			(xy 326.546841 -337.224746) (xy 326.527072 -337.143257) (xy 326.515138 -337.060258) (xy 326.511148 -336.9765)
			(xy 322.941787 -336.9765) (xy 322.94581 -337.019944) (xy 322.946268 -337.061048) (xy 322.946268 -337.061302)
			(xy 322.945685 -337.10604) (xy 322.936674 -337.195061) (xy 322.918774 -337.282729) (xy 322.892164 -337.368156)
			(xy 322.875148 -337.409536) (xy 322.871556 -337.419119) (xy 322.871574 -337.439569) (xy 322.875148 -337.44916)
			(xy 322.892185 -337.490566) (xy 322.918816 -337.576056) (xy 322.93672 -337.663789) (xy 322.945715 -337.752877)
			(xy 322.946268 -337.797648) (xy 322.945697 -337.842418) (xy 322.936698 -337.931504) (xy 322.918797 -338.019236)
			(xy 322.892175 -338.104727) (xy 322.875148 -338.146136) (xy 322.871556 -338.155719) (xy 322.871574 -338.176169)
			(xy 322.875148 -338.18576) (xy 322.892174 -338.227136) (xy 322.918792 -338.312563) (xy 322.936696 -338.400232)
			(xy 322.945704 -338.489255) (xy 322.946268 -338.533994) (xy 322.946268 -338.534248) (xy 322.945879 -338.575352)
			(xy 322.938289 -338.65721) (xy 322.923179 -338.738019) (xy 322.900678 -338.817088) (xy 322.870976 -338.893744)
			(xy 322.834329 -338.967333) (xy 322.791048 -339.037226) (xy 322.741503 -339.102828) (xy 322.686116 -339.163578)
			(xy 322.62536 -339.218959) (xy 322.559753 -339.268498) (xy 322.489856 -339.311772) (xy 322.416264 -339.348412)
			(xy 322.339605 -339.378106) (xy 322.260533 -339.400599) (xy 322.179723 -339.415702) (xy 322.097864 -339.423283)
			(xy 322.05676 -339.423756) (xy 322.055998 -339.423756) (xy 322.014458 -339.423244) (xy 321.931742 -339.415465)
			(xy 321.850112 -339.400013) (xy 321.770276 -339.377021) (xy 321.69293 -339.34669) (xy 321.618746 -339.309284)
			(xy 321.583304 -339.287612) (xy 321.574167 -339.282447) (xy 321.55345 -339.279232) (xy 321.533175 -339.284566)
			(xy 321.52463 -339.29066) (xy 321.491012 -339.316622) (xy 321.419631 -339.362677) (xy 321.344187 -339.401718)
			(xy 321.265365 -339.433392) (xy 321.183883 -339.457409) (xy 321.100483 -339.47355) (xy 321.015924 -339.48167)
			(xy 320.97345 -339.482176) (xy 320.973196 -339.482176) (xy 320.932092 -339.481752) (xy 320.850234 -339.474166)
			(xy 320.769426 -339.459059) (xy 320.690356 -339.436561) (xy 320.613699 -339.406863) (xy 320.54011 -339.370219)
			(xy 320.470216 -339.326941) (xy 320.404613 -339.277398) (xy 320.343861 -339.222013) (xy 320.288479 -339.161259)
			(xy 320.238939 -339.095655) (xy 320.195664 -339.025759) (xy 320.159022 -338.952168) (xy 320.129327 -338.87551)
			(xy 320.106832 -338.796439) (xy 320.091729 -338.71563) (xy 320.084147 -338.633772) (xy 320.083688 -338.592668)
			(xy 320.083688 -338.592414) (xy 320.084245 -338.547675) (xy 320.093264 -338.458653) (xy 320.111172 -338.370986)
			(xy 320.137789 -338.285559) (xy 320.154808 -338.24418) (xy 320.158393 -338.234595) (xy 320.158381 -338.214147)
			(xy 320.154808 -338.204556) (xy 320.137774 -338.163149) (xy 320.111142 -338.07766) (xy 320.093238 -337.989927)
			(xy 320.084242 -337.900839) (xy 320.083688 -337.856068) (xy 320.083688 -337.84413) (xy 320.057209 -337.838184)
			(xy 320.004974 -337.823441) (xy 319.979294 -337.814666) (xy 319.971097 -337.812152) (xy 319.953963 -337.812152)
			(xy 319.945766 -337.814666) (xy 319.910549 -337.82661) (xy 319.838539 -337.845197) (xy 319.765217 -337.857638)
			(xy 319.691106 -337.863844) (xy 319.65392 -337.864196) (xy 319.616736 -337.863827) (xy 319.542628 -337.857606)
			(xy 319.469308 -337.845164) (xy 319.397297 -337.826589) (xy 319.362074 -337.814666) (xy 319.353877 -337.812152)
			(xy 319.336743 -337.812152) (xy 319.328546 -337.814666) (xy 319.293452 -337.826578) (xy 319.221693 -337.845121)
			(xy 319.148627 -337.85756) (xy 319.074774 -337.863807) (xy 319.037716 -337.864196) (xy 319.0367 -337.864196)
			(xy 318.994774 -337.863741) (xy 318.911301 -337.855771) (xy 318.828963 -337.839902) (xy 318.748507 -337.816278)
			(xy 318.670661 -337.785113) (xy 318.59613 -337.746689) (xy 318.525589 -337.701355) (xy 318.459676 -337.649521)
			(xy 318.398989 -337.591656) (xy 318.344078 -337.528284) (xy 318.295438 -337.45998) (xy 318.253512 -337.387361)
			(xy 318.218678 -337.311086) (xy 318.191253 -337.231846) (xy 318.171484 -337.150357) (xy 318.15955 -337.067358)
			(xy 318.155561 -336.9836) (xy 99.362614 -336.9836) (xy 99.373171 -336.999727) (xy 99.41309 -337.075842)
			(xy 99.445481 -337.155452) (xy 99.470043 -337.237815) (xy 99.486546 -337.322163) (xy 99.494837 -337.40771)
			(xy 99.495356 -337.450684) (xy 99.495356 -337.451192) (xy 99.494833 -337.493866) (xy 99.486634 -337.578818)
			(xy 99.47034 -337.662596) (xy 99.446101 -337.744429) (xy 99.430586 -337.784186) (xy 99.426944 -337.794219)
			(xy 99.427619 -337.815536) (xy 99.431856 -337.825334) (xy 99.448914 -337.861614) (xy 99.477225 -337.936624)
			(xy 99.498666 -338.013878) (xy 99.513065 -338.092749) (xy 99.520304 -338.172597) (xy 99.520756 -338.212684)
			(xy 99.520272 -338.252763) (xy 99.512982 -338.33259) (xy 99.498549 -338.411439) (xy 99.488244 -338.450174)
			(xy 99.485843 -338.460698) (xy 99.489132 -338.482012) (xy 99.494594 -338.491322) (xy 99.517345 -338.52734)
			(xy 99.556637 -338.602937) (xy 99.588514 -338.681946) (xy 99.612684 -338.763644) (xy 99.628925 -338.847279)
			(xy 99.637089 -338.932085) (xy 99.637596 -338.974684) (xy 99.637001 -339.021087) (xy 99.627302 -339.113385)
			(xy 99.608039 -339.204171) (xy 99.579422 -339.292455) (xy 99.561142 -339.33511) (xy 99.557344 -339.345055)
			(xy 99.557338 -339.366316) (xy 99.561142 -339.376258) (xy 99.579397 -339.418922) (xy 99.607993 -339.507209)
			(xy 99.627252 -339.597991) (xy 99.636966 -339.690283) (xy 99.637596 -339.736684) (xy 99.637118 -339.777779)
			(xy 99.629538 -339.859619) (xy 99.614439 -339.94041) (xy 99.591952 -340.019465) (xy 99.562267 -340.096107)
			(xy 99.525639 -340.169684) (xy 99.482378 -340.239568) (xy 99.432856 -340.305164) (xy 99.377493 -340.36591)
			(xy 99.316762 -340.421291) (xy 99.251181 -340.470833) (xy 99.18131 -340.514113) (xy 99.107743 -340.550763)
			(xy 99.031109 -340.58047) (xy 98.952062 -340.60298) (xy 98.871275 -340.618102) (xy 98.789437 -340.625707)
			(xy 98.748342 -340.626192) (xy 98.747834 -340.626192) (xy 98.704859 -340.625663) (xy 98.619309 -340.617375)
			(xy 98.534957 -340.600874) (xy 98.45259 -340.576313) (xy 98.372977 -340.543922) (xy 98.296859 -340.504001)
			(xy 98.224947 -340.456925) (xy 98.157912 -340.403131) (xy 98.096378 -340.343122) (xy 98.040919 -340.277458)
			(xy 98.01606 -340.242398) (xy 98.010455 -340.235056) (xy 97.995216 -340.224641) (xy 97.986342 -340.222078)
			(xy 97.94544 -340.211492) (xy 97.865683 -340.183605) (xy 97.788928 -340.148281) (xy 97.715869 -340.105839)
			(xy 97.647164 -340.05666) (xy 97.583432 -340.001188) (xy 97.525246 -339.939922) (xy 97.473132 -339.873416)
			(xy 97.427559 -339.802268) (xy 97.388937 -339.727119) (xy 97.357615 -339.648646) (xy 97.333875 -339.567557)
			(xy 97.317931 -339.484583) (xy 97.309927 -339.40047) (xy 97.309432 -339.358224) (xy 97.309829 -339.321956)
			(xy 97.315809 -339.249667) (xy 97.327648 -339.178103) (xy 97.336102 -339.142832) (xy 97.338115 -339.132729)
			(xy 97.334853 -339.112411) (xy 97.329752 -339.103462) (xy 97.30766 -339.067807) (xy 97.269551 -338.993079)
			(xy 97.238646 -338.915096) (xy 97.215218 -338.83455) (xy 97.199477 -338.752156) (xy 97.191562 -338.668646)
			(xy 97.191068 -338.626704) (xy 97.191648 -338.581935) (xy 97.200654 -338.49285) (xy 97.218554 -338.405119)
			(xy 97.245168 -338.319627) (xy 97.262188 -338.278216) (xy 97.265753 -338.268625) (xy 97.265754 -338.248182)
			(xy 97.262188 -338.238592) (xy 97.245172 -338.197246) (xy 97.218563 -338.111882) (xy 97.20066 -338.024278)
			(xy 97.191642 -337.935319) (xy 97.191068 -337.890612) (xy 97.191068 -337.889596) (xy 97.191322 -337.878166)
			(xy 97.164844 -337.872216) (xy 97.112609 -337.857476) (xy 97.086928 -337.848702) (xy 97.078731 -337.846188)
			(xy 97.061597 -337.846188) (xy 97.0534 -337.848702) (xy 97.01818 -337.860638) (xy 96.946171 -337.879227)
			(xy 96.87285 -337.89167) (xy 96.798739 -337.897878) (xy 96.761554 -337.898232) (xy 96.724369 -337.89788)
			(xy 96.650261 -337.891654) (xy 96.576941 -337.879206) (xy 96.504931 -337.860627) (xy 96.469708 -337.848702)
			(xy 96.461511 -337.846188) (xy 96.444377 -337.846188) (xy 96.43618 -337.848702) (xy 96.401082 -337.860602)
			(xy 96.329324 -337.879149) (xy 96.25626 -337.891592) (xy 96.182408 -337.897841) (xy 96.14535 -337.898232)
			(xy 96.144334 -337.898232) (xy 96.102408 -337.897723) (xy 96.018934 -337.889755) (xy 95.936596 -337.873888)
			(xy 95.85614 -337.850267) (xy 95.778292 -337.819104) (xy 95.70376 -337.780683) (xy 95.633218 -337.73535)
			(xy 95.567304 -337.683517) (xy 95.506616 -337.625654) (xy 95.451703 -337.562283) (xy 95.403062 -337.493979)
			(xy 95.361135 -337.421361) (xy 95.3263 -337.345087) (xy 95.298874 -337.265846) (xy 95.279105 -337.184357)
			(xy 95.267171 -337.101358) (xy 95.263181 -337.0176) (xy 91.722641 -337.0176) (xy 91.722956 -337.044284)
			(xy 91.722404 -337.089054) (xy 91.71339 -337.178139) (xy 91.695482 -337.26587) (xy 91.668861 -337.351361)
			(xy 91.651836 -337.392772) (xy 91.648282 -337.402366) (xy 91.648276 -337.422805) (xy 91.651836 -337.432396)
			(xy 91.668872 -337.473803) (xy 91.695506 -337.559291) (xy 91.71341 -337.647024) (xy 91.722404 -337.736113)
			(xy 91.722956 -337.780884) (xy 91.722404 -337.825654) (xy 91.71339 -337.914739) (xy 91.695482 -338.00247)
			(xy 91.668861 -338.087961) (xy 91.651836 -338.129372) (xy 91.648282 -338.138966) (xy 91.648276 -338.159405)
			(xy 91.651836 -338.168996) (xy 91.668872 -338.210403) (xy 91.695506 -338.295891) (xy 91.71341 -338.383624)
			(xy 91.722404 -338.472713) (xy 91.722956 -338.517484) (xy 91.722432 -338.558593) (xy 91.714846 -338.64046)
			(xy 91.699738 -338.721278) (xy 91.677236 -338.800357) (xy 91.647532 -338.877021) (xy 91.610881 -338.950618)
			(xy 91.567594 -339.020518) (xy 91.518041 -339.086125) (xy 91.462645 -339.146879) (xy 91.401879 -339.202262)
			(xy 91.336261 -339.251801) (xy 91.266352 -339.295073) (xy 91.192747 -339.331709) (xy 91.116076 -339.361396)
			(xy 91.036993 -339.383882) (xy 90.956172 -339.398973) (xy 90.874303 -339.406541) (xy 90.833194 -339.406992)
			(xy 90.791589 -339.406554) (xy 90.70874 -339.398816) (xy 90.626975 -339.383379) (xy 90.547007 -339.360379)
			(xy 90.469535 -339.330016) (xy 90.395235 -339.292555) (xy 90.359738 -339.270848) (xy 90.350631 -339.26562)
			(xy 90.329893 -339.262421) (xy 90.309608 -339.267785) (xy 90.301064 -339.273896) (xy 90.267427 -339.299833)
			(xy 90.196051 -339.345891) (xy 90.12061 -339.384937) (xy 90.041791 -339.416615) (xy 89.960312 -339.440636)
			(xy 89.876914 -339.456781) (xy 89.792357 -339.464905) (xy 89.749884 -339.465412) (xy 89.74963 -339.465412)
			(xy 89.708522 -339.464959) (xy 89.626657 -339.457377) (xy 89.545841 -339.442274) (xy 89.466762 -339.41978)
			(xy 89.390096 -339.390087) (xy 89.316497 -339.353447) (xy 89.246591 -339.310173) (xy 89.180976 -339.260635)
			(xy 89.120211 -339.205254) (xy 89.064815 -339.144504) (xy 89.015259 -339.078902) (xy 88.971967 -339.009008)
			(xy 88.935308 -338.935418) (xy 88.905594 -338.85876) (xy 88.883079 -338.779687) (xy 88.867956 -338.698875)
			(xy 88.860352 -338.617012) (xy 88.859868 -338.575904) (xy 88.860448 -338.531135) (xy 88.869454 -338.44205)
			(xy 88.887354 -338.354319) (xy 88.913968 -338.268827) (xy 88.930988 -338.227416) (xy 88.934553 -338.217825)
			(xy 88.934554 -338.197382) (xy 88.930988 -338.187792) (xy 88.913972 -338.146446) (xy 88.887363 -338.061082)
			(xy 88.86946 -337.973478) (xy 88.860442 -337.884519) (xy 88.859868 -337.839812) (xy 88.859868 -337.838796)
			(xy 88.860122 -337.827366) (xy 88.833644 -337.821416) (xy 88.781409 -337.806676) (xy 88.755728 -337.797902)
			(xy 88.747531 -337.795388) (xy 88.730397 -337.795388) (xy 88.7222 -337.797902) (xy 88.68698 -337.809838)
			(xy 88.614971 -337.828427) (xy 88.54165 -337.84087) (xy 88.467539 -337.847078) (xy 88.430354 -337.847432)
			(xy 88.393169 -337.84708) (xy 88.319061 -337.840854) (xy 88.245741 -337.828406) (xy 88.173731 -337.809827)
			(xy 88.138508 -337.797902) (xy 88.130311 -337.795388) (xy 88.113177 -337.795388) (xy 88.10498 -337.797902)
			(xy 88.069882 -337.809802) (xy 87.998124 -337.828349) (xy 87.92506 -337.840792) (xy 87.851208 -337.847041)
			(xy 87.81415 -337.847432) (xy 87.813134 -337.847432) (xy 87.771208 -337.846923) (xy 87.687734 -337.838955)
			(xy 87.605396 -337.823088) (xy 87.52494 -337.799467) (xy 87.447092 -337.768304) (xy 87.37256 -337.729883)
			(xy 87.302018 -337.68455) (xy 87.236104 -337.632717) (xy 87.175416 -337.574854) (xy 87.120503 -337.511483)
			(xy 87.071862 -337.443179) (xy 87.029935 -337.370561) (xy 86.9951 -337.294287) (xy 86.967674 -337.215046)
			(xy 86.947905 -337.133557) (xy 86.935971 -337.050558) (xy 86.931981 -336.9668) (xy 83.360149 -336.9668)
			(xy 83.364863 -337.017649) (xy 83.36534 -337.058762) (xy 83.364781 -337.103532) (xy 83.35577 -337.192617)
			(xy 83.337863 -337.280348) (xy 83.311243 -337.365839) (xy 83.29422 -337.40725) (xy 83.290679 -337.416847)
			(xy 83.290665 -337.437283) (xy 83.29422 -337.446874) (xy 83.311248 -337.488284) (xy 83.337884 -337.573771)
			(xy 83.355791 -337.661503) (xy 83.364787 -337.750591) (xy 83.36534 -337.795362) (xy 83.364781 -337.840132)
			(xy 83.35577 -337.929217) (xy 83.337863 -338.016948) (xy 83.311243 -338.102439) (xy 83.29422 -338.14385)
			(xy 83.290679 -338.153447) (xy 83.290665 -338.173883) (xy 83.29422 -338.183474) (xy 83.311248 -338.224884)
			(xy 83.337884 -338.310371) (xy 83.355791 -338.398103) (xy 83.364787 -338.487191) (xy 83.36534 -338.531962)
			(xy 83.364865 -338.573077) (xy 83.357281 -338.654956) (xy 83.342174 -338.735786) (xy 83.319674 -338.814878)
			(xy 83.289971 -338.891556) (xy 83.253319 -338.965166) (xy 83.210032 -339.03508) (xy 83.160479 -339.100701)
			(xy 83.105082 -339.16147) (xy 83.044313 -339.216869) (xy 82.978693 -339.266423) (xy 82.90878 -339.309712)
			(xy 82.83517 -339.346364) (xy 82.758493 -339.376068) (xy 82.679402 -339.398571) (xy 82.598572 -339.413679)
			(xy 82.516693 -339.421265) (xy 82.475578 -339.421724) (xy 82.433968 -339.421253) (xy 82.351111 -339.413475)
			(xy 82.269342 -339.397998) (xy 82.189374 -339.374957) (xy 82.111906 -339.344554) (xy 82.037613 -339.307053)
			(xy 82.002122 -339.285326) (xy 81.992978 -339.280175) (xy 81.972265 -339.276953) (xy 81.951992 -339.282282)
			(xy 81.943448 -339.288374) (xy 81.909821 -339.314367) (xy 81.838426 -339.360491) (xy 81.762954 -339.399592)
			(xy 81.684096 -339.431311) (xy 81.602571 -339.455361) (xy 81.519123 -339.471521) (xy 81.434513 -339.479643)
			(xy 81.392014 -339.480144) (xy 81.350899 -339.479688) (xy 81.269019 -339.472102) (xy 81.188189 -339.456993)
			(xy 81.109097 -339.434491) (xy 81.032419 -339.404786) (xy 80.95881 -339.368133) (xy 80.888896 -339.324845)
			(xy 80.823275 -339.27529) (xy 80.762506 -339.219892) (xy 80.707108 -339.159122) (xy 80.657553 -339.093501)
			(xy 80.614265 -339.023587) (xy 80.577612 -338.949977) (xy 80.547908 -338.873299) (xy 80.525406 -338.794207)
			(xy 80.510297 -338.713377) (xy 80.502712 -338.631497) (xy 80.502252 -338.590382) (xy 80.502826 -338.545613)
			(xy 80.511834 -338.456528) (xy 80.529735 -338.368797) (xy 80.556351 -338.283305) (xy 80.573372 -338.241894)
			(xy 80.576945 -338.232306) (xy 80.576939 -338.211861) (xy 80.573372 -338.20227) (xy 80.556348 -338.160927)
			(xy 80.529742 -338.075562) (xy 80.511841 -337.987957) (xy 80.502825 -337.898997) (xy 80.502252 -337.85429)
			(xy 80.502252 -337.853274) (xy 80.502506 -337.841844) (xy 80.476028 -337.835896) (xy 80.423793 -337.821155)
			(xy 80.398112 -337.81238) (xy 80.389915 -337.809866) (xy 80.372781 -337.809866) (xy 80.364584 -337.81238)
			(xy 80.329366 -337.824336) (xy 80.257364 -337.842992) (xy 80.184043 -337.855502) (xy 80.109928 -337.861777)
			(xy 80.072738 -337.862164) (xy 80.035549 -337.861761) (xy 79.961436 -337.855475) (xy 79.888116 -337.842969)
			(xy 79.81611 -337.824332) (xy 79.780892 -337.81238) (xy 79.772695 -337.809866) (xy 79.755561 -337.809866)
			(xy 79.747364 -337.81238) (xy 79.712148 -337.824342) (xy 79.640145 -337.842996) (xy 79.566824 -337.855505)
			(xy 79.492708 -337.861778) (xy 79.455518 -337.862164) (xy 79.413579 -337.861698) (xy 79.330081 -337.853726)
			(xy 79.247718 -337.837853) (xy 79.167237 -337.814224) (xy 79.089367 -337.783051) (xy 79.014813 -337.744616)
			(xy 78.94425 -337.69927) (xy 78.878316 -337.64742) (xy 78.81761 -337.589539) (xy 78.762681 -337.526148)
			(xy 78.714027 -337.457824) (xy 78.672087 -337.385183) (xy 78.637243 -337.308885) (xy 78.609809 -337.229621)
			(xy 78.590033 -337.148107) (xy 78.578096 -337.065083) (xy 78.574105 -336.9813) (xy 75.005252 -336.9813)
			(xy 75.00928 -337.024761) (xy 75.009756 -337.065874) (xy 75.009201 -337.110644) (xy 75.000188 -337.199729)
			(xy 74.982281 -337.28746) (xy 74.95566 -337.372951) (xy 74.938636 -337.414362) (xy 74.935088 -337.423957)
			(xy 74.935078 -337.444395) (xy 74.938636 -337.453986) (xy 74.955669 -337.495394) (xy 74.982303 -337.580882)
			(xy 75.000209 -337.668615) (xy 75.009203 -337.757703) (xy 75.009756 -337.802474) (xy 75.009201 -337.847244)
			(xy 75.000188 -337.936329) (xy 74.982281 -338.02406) (xy 74.95566 -338.109551) (xy 74.938636 -338.150962)
			(xy 74.935088 -338.160557) (xy 74.935078 -338.180995) (xy 74.938636 -338.190586) (xy 74.955669 -338.231994)
			(xy 74.982303 -338.317482) (xy 75.000209 -338.405215) (xy 75.009203 -338.494303) (xy 75.009756 -338.539074)
			(xy 75.009277 -338.580189) (xy 75.001692 -338.662067) (xy 74.986584 -338.742897) (xy 74.964083 -338.821988)
			(xy 74.93438 -338.898665) (xy 74.897729 -338.972274) (xy 74.854442 -339.042187) (xy 74.804888 -339.107809)
			(xy 74.749492 -339.168577) (xy 74.688724 -339.223976) (xy 74.623104 -339.27353) (xy 74.553192 -339.316819)
			(xy 74.479583 -339.353472) (xy 74.402907 -339.383177) (xy 74.323816 -339.40568) (xy 74.242987 -339.420789)
			(xy 74.161109 -339.428376) (xy 74.119994 -339.428836) (xy 74.078384 -339.428356) (xy 73.995528 -339.420579)
			(xy 73.913759 -339.405104) (xy 73.833791 -339.382065) (xy 73.756322 -339.351663) (xy 73.682029 -339.314164)
			(xy 73.646538 -339.292438) (xy 73.63743 -339.287211) (xy 73.616693 -339.284013) (xy 73.596408 -339.289376)
			(xy 73.587864 -339.295486) (xy 73.554233 -339.321473) (xy 73.482838 -339.367598) (xy 73.407368 -339.406699)
			(xy 73.32851 -339.438419) (xy 73.246986 -339.46247) (xy 73.163538 -339.47863) (xy 73.078929 -339.486754)
			(xy 73.03643 -339.487256) (xy 72.995315 -339.486773) (xy 72.913437 -339.479188) (xy 72.832607 -339.464081)
			(xy 72.753517 -339.44158) (xy 72.67684 -339.411877) (xy 72.60323 -339.375226) (xy 72.533317 -339.33194)
			(xy 72.467696 -339.282387) (xy 72.406927 -339.22699) (xy 72.351529 -339.166223) (xy 72.301974 -339.100603)
			(xy 72.258685 -339.030691) (xy 72.222032 -338.957082) (xy 72.192327 -338.880406) (xy 72.169824 -338.801316)
			(xy 72.154715 -338.720487) (xy 72.147128 -338.638609) (xy 72.146668 -338.597494) (xy 72.147245 -338.552725)
			(xy 72.156251 -338.46364) (xy 72.174152 -338.375909) (xy 72.200767 -338.290417) (xy 72.217788 -338.249006)
			(xy 72.221359 -338.239417) (xy 72.221356 -338.218972) (xy 72.217788 -338.209382) (xy 72.200768 -338.168037)
			(xy 72.174161 -338.082673) (xy 72.156259 -337.995068) (xy 72.147241 -337.906109) (xy 72.146668 -337.861402)
			(xy 72.146668 -337.860386) (xy 72.146922 -337.848956) (xy 72.120444 -337.843006) (xy 72.068209 -337.828266)
			(xy 72.042528 -337.819492) (xy 72.034331 -337.816978) (xy 72.017197 -337.816978) (xy 72.009 -337.819492)
			(xy 71.973781 -337.831444) (xy 71.901779 -337.850101) (xy 71.828459 -337.862612) (xy 71.754344 -337.868888)
			(xy 71.717154 -337.869276) (xy 71.679965 -337.868873) (xy 71.605852 -337.862587) (xy 71.532532 -337.850082)
			(xy 71.460526 -337.831445) (xy 71.425308 -337.819492) (xy 71.417111 -337.816978) (xy 71.399977 -337.816978)
			(xy 71.39178 -337.819492) (xy 71.356562 -337.83145) (xy 71.28456 -337.850105) (xy 71.211239 -337.862615)
			(xy 71.137124 -337.868889) (xy 71.099934 -337.869276) (xy 71.057995 -337.868786) (xy 70.974497 -337.860816)
			(xy 70.892134 -337.844945) (xy 70.811653 -337.821316) (xy 70.733783 -337.790144) (xy 70.659228 -337.751711)
			(xy 70.588664 -337.706365) (xy 70.522731 -337.654517) (xy 70.462025 -337.596636) (xy 70.407095 -337.533246)
			(xy 70.35844 -337.464922) (xy 70.3165 -337.392282) (xy 70.281655 -337.315985) (xy 70.254221 -337.23672)
			(xy 70.234446 -337.155207) (xy 70.222508 -337.072183) (xy 70.218517 -336.9884) (xy 2.509012 -336.9884)
			(xy 2.509012 -341.9277) (xy 103.538816 -341.9277) (xy 103.542807 -341.843921) (xy 103.554743 -341.760902)
			(xy 103.574517 -341.679392) (xy 103.601948 -341.600131) (xy 103.63679 -341.523837) (xy 103.678726 -341.4512)
			(xy 103.727376 -341.382878) (xy 103.7823 -341.319489) (xy 103.843001 -341.261608) (xy 103.908929 -341.20976)
			(xy 103.979486 -341.164412) (xy 104.054035 -341.125977) (xy 104.131899 -341.094802) (xy 104.212375 -341.071169)
			(xy 104.294732 -341.055293) (xy 104.378225 -341.047317) (xy 104.420162 -341.046816) (xy 104.457351 -341.047215)
			(xy 104.531464 -341.053502) (xy 104.604784 -341.066008) (xy 104.67679 -341.084646) (xy 104.712008 -341.0966)
			(xy 104.720205 -341.099114) (xy 104.737339 -341.099114) (xy 104.745536 -341.0966) (xy 104.780752 -341.084638)
			(xy 104.852755 -341.065983) (xy 104.926076 -341.053475) (xy 105.000192 -341.047202) (xy 105.037382 -341.046816)
			(xy 105.07218 -341.047578) (xy 105.081741 -341.004913) (xy 105.108207 -340.921573) (xy 105.125012 -340.881208)
			(xy 105.128629 -340.871492) (xy 105.128644 -340.850784) (xy 105.125012 -340.841076) (xy 105.107898 -340.799819)
			(xy 105.081109 -340.714608) (xy 105.063074 -340.627124) (xy 105.053979 -340.538265) (xy 105.053384 -340.493604)
			(xy 105.053384 -340.492842) (xy 105.053883 -340.450917) (xy 105.061853 -340.367446) (xy 105.077722 -340.285111)
			(xy 105.101345 -340.204657) (xy 105.132509 -340.126813) (xy 105.170932 -340.052283) (xy 105.216265 -339.981744)
			(xy 105.268098 -339.915833) (xy 105.325961 -339.855147) (xy 105.389331 -339.800237) (xy 105.457634 -339.751599)
			(xy 105.530251 -339.709674) (xy 105.606524 -339.674841) (xy 105.685763 -339.647416) (xy 105.767249 -339.627647)
			(xy 105.850246 -339.615714) (xy 105.934002 -339.611725) (xy 106.017758 -339.615714) (xy 106.100755 -339.627647)
			(xy 106.182241 -339.647416) (xy 106.26148 -339.674841) (xy 106.337753 -339.709674) (xy 106.41037 -339.751599)
			(xy 106.478673 -339.800237) (xy 106.542043 -339.855147) (xy 106.599906 -339.915833) (xy 106.651739 -339.981744)
			(xy 106.697072 -340.052283) (xy 106.735495 -340.126813) (xy 106.766659 -340.204657) (xy 106.790282 -340.285111)
			(xy 106.806151 -340.367446) (xy 106.814121 -340.450917) (xy 106.81462 -340.492842) (xy 106.81462 -340.493604)
			(xy 106.814051 -340.538267) (xy 106.804977 -340.627133) (xy 106.786945 -340.714621) (xy 106.760139 -340.799831)
			(xy 106.742992 -340.841076) (xy 106.739326 -340.850777) (xy 106.739342 -340.871499) (xy 106.742992 -340.881208)
			(xy 106.751628 -340.901528) (xy 106.756582 -340.912278) (xy 106.774248 -340.927996) (xy 106.797062 -340.934212)
			(xy 106.808778 -340.932516) (xy 106.8525 -340.924198) (xy 106.941059 -340.915292) (xy 106.985562 -340.914736)
			(xy 106.98607 -340.914736) (xy 107.027176 -340.915241) (xy 107.109038 -340.922823) (xy 107.189852 -340.937924)
			(xy 107.268928 -340.960416) (xy 107.345591 -340.990108) (xy 107.419189 -341.026745) (xy 107.489092 -341.070016)
			(xy 107.554706 -341.119551) (xy 107.61547 -341.174927) (xy 107.670867 -341.235674) (xy 107.720423 -341.301272)
			(xy 107.763716 -341.371161) (xy 107.800377 -341.444747) (xy 107.830093 -341.521401) (xy 107.85261 -341.60047)
			(xy 107.867738 -341.681278) (xy 107.875346 -341.763138) (xy 107.875832 -341.804244) (xy 107.875268 -341.849014)
			(xy 107.867795 -341.9229) (xy 351.475729 -341.9229) (xy 351.479719 -341.839138) (xy 351.491654 -341.756134)
			(xy 351.511424 -341.674641) (xy 351.538852 -341.595396) (xy 351.573688 -341.519117) (xy 351.615617 -341.446494)
			(xy 351.66426 -341.378187) (xy 351.719176 -341.314813) (xy 351.779867 -341.256945) (xy 351.845785 -341.205109)
			(xy 351.916331 -341.159774) (xy 351.990867 -341.12135) (xy 352.068718 -341.090185) (xy 352.149179 -341.066562)
			(xy 352.231522 -341.050694) (xy 352.314999 -341.042726) (xy 352.356928 -341.042244) (xy 352.357944 -341.042244)
			(xy 352.395001 -341.04264) (xy 352.46885 -341.048907) (xy 352.541913 -341.061352) (xy 352.613673 -341.079887)
			(xy 352.648774 -341.091774) (xy 352.656971 -341.094288) (xy 352.674105 -341.094288) (xy 352.682302 -341.091774)
			(xy 352.717522 -341.079841) (xy 352.789531 -341.06125) (xy 352.862852 -341.048806) (xy 352.936963 -341.042598)
			(xy 352.974148 -341.042244) (xy 352.988626 -341.042244) (xy 352.999994 -341.041829) (xy 353.020668 -341.032414)
			(xy 353.035248 -341.014994) (xy 353.038664 -341.004144) (xy 353.047281 -340.972176) (xy 353.068638 -340.909499)
			(xy 353.081336 -340.878922) (xy 353.084895 -340.86933) (xy 353.084899 -340.848889) (xy 353.081336 -340.839298)
			(xy 353.064328 -340.797915) (xy 353.037705 -340.71249) (xy 353.019796 -340.624824) (xy 353.010783 -340.535802)
			(xy 353.010216 -340.491064) (xy 353.010216 -340.49081) (xy 353.01072 -340.448462) (xy 353.018771 -340.364148)
			(xy 353.0348 -340.280982) (xy 353.058661 -340.199715) (xy 353.09014 -340.121085) (xy 353.128951 -340.045804)
			(xy 353.174741 -339.974552) (xy 353.227097 -339.907976) (xy 353.285545 -339.846678) (xy 353.349555 -339.791213)
			(xy 353.418547 -339.742084) (xy 353.491897 -339.699735) (xy 353.56894 -339.664551) (xy 353.648979 -339.636849)
			(xy 353.731288 -339.616881) (xy 353.815123 -339.604828) (xy 353.899724 -339.600798) (xy 353.984325 -339.604828)
			(xy 354.06816 -339.616881) (xy 354.150469 -339.636849) (xy 354.230508 -339.664551) (xy 354.307551 -339.699735)
			(xy 354.380901 -339.742084) (xy 354.449893 -339.791213) (xy 354.513903 -339.846678) (xy 354.572351 -339.907976)
			(xy 354.624707 -339.974552) (xy 354.670497 -340.045804) (xy 354.709308 -340.121085) (xy 354.740787 -340.199715)
			(xy 354.764648 -340.280982) (xy 354.780677 -340.364148) (xy 354.788728 -340.448462) (xy 354.789232 -340.49081)
			(xy 354.789232 -340.491064) (xy 354.788666 -340.535802) (xy 354.779649 -340.624824) (xy 354.761744 -340.712491)
			(xy 354.73513 -340.797919) (xy 354.718112 -340.839298) (xy 354.714539 -340.848887) (xy 354.714543 -340.869332)
			(xy 354.718112 -340.878922) (xy 354.735129 -340.920302) (xy 354.761749 -341.005728) (xy 354.779655 -341.093395)
			(xy 354.788666 -341.182417) (xy 354.789232 -341.227156) (xy 354.789232 -341.228172) (xy 354.789643 -341.238195)
			(xy 354.79731 -341.256718) (xy 354.811486 -341.270892) (xy 354.830009 -341.278557) (xy 354.840032 -341.278972)
			(xy 354.840286 -341.278972) (xy 354.84794 -341.278603) (xy 354.862532 -341.273956) (xy 354.868988 -341.269828)
			(xy 354.869242 -341.269828) (xy 354.906515 -341.244617) (xy 354.985224 -341.200991) (xy 355.067937 -341.165538)
			(xy 355.153807 -341.13862) (xy 355.241957 -341.120513) (xy 355.331485 -341.111402) (xy 355.37648 -341.110824)
			(xy 355.376988 -341.110824) (xy 355.418092 -341.111264) (xy 355.499949 -341.118848) (xy 355.580757 -341.133953)
			(xy 355.659827 -341.15645) (xy 355.736484 -341.186147) (xy 355.810073 -341.22279) (xy 355.879967 -341.266067)
			(xy 355.94557 -341.315609) (xy 356.006322 -341.370992) (xy 356.061704 -341.431745) (xy 356.111244 -341.497349)
			(xy 356.15452 -341.567245) (xy 356.191162 -341.640835) (xy 356.220857 -341.717492) (xy 356.243352 -341.796562)
			(xy 356.258455 -341.877371) (xy 356.266037 -341.959228) (xy 356.266496 -342.000332) (xy 356.266496 -342.000586)
			(xy 356.26594 -342.045325) (xy 356.256921 -342.134347) (xy 356.239013 -342.222014) (xy 356.212396 -342.307441)
			(xy 356.195376 -342.34882) (xy 356.191792 -342.358405) (xy 356.191804 -342.378853) (xy 356.195376 -342.388444)
			(xy 356.212409 -342.429852) (xy 356.239041 -342.515341) (xy 356.256946 -342.603073) (xy 356.265942 -342.692161)
			(xy 356.266496 -342.736932) (xy 356.265952 -342.781703) (xy 356.256945 -342.87079) (xy 356.239036 -342.958522)
			(xy 356.212407 -343.044011) (xy 356.195376 -343.08542) (xy 356.191792 -343.095005) (xy 356.191804 -343.115453)
			(xy 356.195376 -343.125044) (xy 356.212398 -343.166422) (xy 356.239017 -343.251848) (xy 356.256922 -343.339516)
			(xy 356.265931 -343.428539) (xy 356.266496 -343.473278) (xy 356.266496 -343.473532) (xy 356.266064 -343.514635)
			(xy 356.258476 -343.596491) (xy 356.243368 -343.677298) (xy 356.220868 -343.756366) (xy 356.191169 -343.83302)
			(xy 356.154525 -343.906608) (xy 356.111246 -343.9765) (xy 356.061704 -344.042101) (xy 356.00632 -344.102851)
			(xy 355.945567 -344.158232) (xy 355.879964 -344.207771) (xy 355.810069 -344.251046) (xy 355.73648 -344.287687)
			(xy 355.659824 -344.317382) (xy 355.580755 -344.339878) (xy 355.499948 -344.354982) (xy 355.418091 -344.362566)
			(xy 355.376988 -344.36304) (xy 355.376226 -344.36304) (xy 355.334685 -344.362565) (xy 355.251968 -344.35478)
			(xy 355.170337 -344.33932) (xy 355.090501 -344.316321) (xy 355.013156 -344.285984) (xy 354.938974 -344.248571)
			(xy 354.903532 -344.226896) (xy 354.894382 -344.221758) (xy 354.873674 -344.218535) (xy 354.853403 -344.223857)
			(xy 354.844858 -344.229944) (xy 354.811228 -344.255891) (xy 354.73985 -344.301947) (xy 354.664408 -344.340991)
			(xy 354.585588 -344.372667) (xy 354.504107 -344.396686) (xy 354.420709 -344.412831) (xy 354.336151 -344.420953)
			(xy 354.293678 -344.42146) (xy 354.293424 -344.42146) (xy 354.25232 -344.421025) (xy 354.170462 -344.413441)
			(xy 354.089653 -344.398337) (xy 354.010583 -344.375841) (xy 353.933926 -344.346144) (xy 353.860336 -344.309501)
			(xy 353.790441 -344.266224) (xy 353.724837 -344.216682) (xy 353.664085 -344.161298) (xy 353.608703 -344.100544)
			(xy 353.559163 -344.03494) (xy 353.515887 -343.965043) (xy 353.479246 -343.891453) (xy 353.449552 -343.814794)
			(xy 353.427057 -343.735723) (xy 353.411955 -343.654914) (xy 353.404374 -343.573056) (xy 353.403916 -343.531952)
			(xy 353.403916 -343.531698) (xy 353.4045 -343.48696) (xy 353.413511 -343.397939) (xy 353.431411 -343.310272)
			(xy 353.45802 -343.224844) (xy 353.475036 -343.183464) (xy 353.478628 -343.173881) (xy 353.47861 -343.153431)
			(xy 353.475036 -343.14384) (xy 353.457998 -343.102434) (xy 353.431368 -343.016945) (xy 353.413464 -342.929211)
			(xy 353.404469 -342.840123) (xy 353.403916 -342.795352) (xy 353.403916 -342.783414) (xy 353.377438 -342.777466)
			(xy 353.325203 -342.762725) (xy 353.299522 -342.75395) (xy 353.291325 -342.751436) (xy 353.274191 -342.751436)
			(xy 353.265994 -342.75395) (xy 353.230774 -342.765885) (xy 353.158765 -342.784475) (xy 353.085444 -342.796919)
			(xy 353.011333 -342.803127) (xy 352.974148 -342.80348) (xy 352.936964 -342.803098) (xy 352.862857 -342.79688)
			(xy 352.789537 -342.784441) (xy 352.717525 -342.76587) (xy 352.682302 -342.75395) (xy 352.674105 -342.751436)
			(xy 352.656971 -342.751436) (xy 352.648774 -342.75395) (xy 352.613678 -342.765853) (xy 352.541919 -342.784399)
			(xy 352.468854 -342.796841) (xy 352.395002 -342.80309) (xy 352.357944 -342.80348) (xy 352.356928 -342.80348)
			(xy 352.314999 -342.803074) (xy 352.231522 -342.795106) (xy 352.149179 -342.779238) (xy 352.068718 -342.755615)
			(xy 351.990867 -342.72445) (xy 351.916331 -342.686026) (xy 351.845785 -342.640691) (xy 351.779867 -342.588855)
			(xy 351.719176 -342.530987) (xy 351.66426 -342.467613) (xy 351.615617 -342.399306) (xy 351.573688 -342.326683)
			(xy 351.538852 -342.250404) (xy 351.511424 -342.171159) (xy 351.491654 -342.089666) (xy 351.479719 -342.006662)
			(xy 351.475729 -341.9229) (xy 107.867795 -341.9229) (xy 107.866258 -341.938099) (xy 107.848353 -342.02583)
			(xy 107.821735 -342.111321) (xy 107.804712 -342.152732) (xy 107.80112 -342.162315) (xy 107.801136 -342.182765)
			(xy 107.804712 -342.192356) (xy 107.821734 -342.233768) (xy 107.848372 -342.319255) (xy 107.86628 -342.406986)
			(xy 107.875278 -342.496074) (xy 107.875832 -342.540844) (xy 107.875405 -342.579435) (xy 107.868704 -342.656327)
			(xy 107.855365 -342.732349) (xy 107.835489 -342.806929) (xy 107.822746 -342.843358) (xy 107.81982 -342.852801)
			(xy 107.820595 -342.872535) (xy 107.82427 -342.881712) (xy 107.843302 -342.9251) (xy 107.873066 -343.015053)
			(xy 107.893096 -343.107662) (xy 107.903166 -343.201875) (xy 107.903772 -343.24925) (xy 107.903772 -343.249504)
			(xy 107.903199 -343.294273) (xy 107.894192 -343.383358) (xy 107.87629 -343.471089) (xy 107.849674 -343.556581)
			(xy 107.832652 -343.597992) (xy 107.829086 -343.607582) (xy 107.829087 -343.628025) (xy 107.832652 -343.637616)
			(xy 107.849695 -343.67902) (xy 107.876327 -343.76451) (xy 107.894229 -343.852244) (xy 107.903221 -343.941333)
			(xy 107.903772 -343.986104) (xy 107.903338 -344.0272) (xy 107.895755 -344.109042) (xy 107.880654 -344.189835)
			(xy 107.858164 -344.268891) (xy 107.828477 -344.345534) (xy 107.791846 -344.419112) (xy 107.748583 -344.488997)
			(xy 107.699057 -344.554593) (xy 107.643692 -344.61534) (xy 107.582958 -344.670721) (xy 107.517374 -344.720262)
			(xy 107.447499 -344.763541) (xy 107.37393 -344.80019) (xy 107.297294 -344.829896) (xy 107.218244 -344.852405)
			(xy 107.137454 -344.867525) (xy 107.055614 -344.875128) (xy 107.014518 -344.875612) (xy 107.01401 -344.875612)
			(xy 106.971454 -344.875048) (xy 106.886731 -344.866913) (xy 106.803172 -344.850725) (xy 106.72154 -344.826633)
			(xy 106.642582 -344.794856) (xy 106.567018 -344.755685) (xy 106.49554 -344.709478) (xy 106.428801 -344.656658)
			(xy 106.36741 -344.597706) (xy 106.311928 -344.533162) (xy 106.262863 -344.463615) (xy 106.220663 -344.389701)
			(xy 106.202734 -344.351102) (xy 106.197143 -344.340314) (xy 106.178175 -344.325188) (xy 106.166412 -344.322146)
			(xy 106.123815 -344.31302) (xy 106.04054 -344.287419) (xy 105.960165 -344.253801) (xy 105.883461 -344.212489)
			(xy 105.811162 -344.163878) (xy 105.74396 -344.108434) (xy 105.682498 -344.046687) (xy 105.627365 -343.979229)
			(xy 105.579089 -343.906705) (xy 105.538133 -343.829811) (xy 105.504888 -343.749281) (xy 105.479672 -343.665888)
			(xy 105.462727 -343.58043) (xy 105.454216 -343.493725) (xy 105.453688 -343.450164) (xy 105.454253 -343.405394)
			(xy 105.463263 -343.316309) (xy 105.481167 -343.228578) (xy 105.507785 -343.143087) (xy 105.524808 -343.101676)
			(xy 105.528395 -343.092092) (xy 105.528382 -343.071643) (xy 105.524808 -343.062052) (xy 105.508891 -343.02338)
			(xy 105.483531 -342.943684) (xy 105.46577 -342.861957) (xy 105.460292 -342.820498) (xy 105.458558 -342.81058)
			(xy 105.448632 -342.793088) (xy 105.43277 -342.780723) (xy 105.423208 -342.777572) (xy 105.40795 -342.773353)
			(xy 105.377717 -342.763951) (xy 105.362756 -342.758776) (xy 105.354559 -342.756262) (xy 105.337425 -342.756262)
			(xy 105.329228 -342.758776) (xy 105.294015 -342.770747) (xy 105.222011 -342.789399) (xy 105.148689 -342.801905)
			(xy 105.074572 -342.808175) (xy 105.037382 -342.80856) (xy 105.000192 -342.808173) (xy 104.926079 -342.801882)
			(xy 104.85276 -342.789372) (xy 104.780754 -342.770731) (xy 104.745536 -342.758776) (xy 104.737339 -342.756262)
			(xy 104.720205 -342.756262) (xy 104.712008 -342.758776) (xy 104.676797 -342.770753) (xy 104.604792 -342.789403)
			(xy 104.531469 -342.801908) (xy 104.457353 -342.808176) (xy 104.420162 -342.80856) (xy 104.378225 -342.808083)
			(xy 104.294732 -342.800107) (xy 104.212375 -342.784231) (xy 104.131899 -342.760598) (xy 104.054035 -342.729423)
			(xy 103.979486 -342.690988) (xy 103.908929 -342.64564) (xy 103.843001 -342.593792) (xy 103.7823 -342.535911)
			(xy 103.727376 -342.472522) (xy 103.678726 -342.4042) (xy 103.63679 -342.331563) (xy 103.601948 -342.255269)
			(xy 103.574517 -342.176008) (xy 103.554743 -342.094498) (xy 103.542807 -342.011479) (xy 103.538816 -341.9277)
			(xy 2.509012 -341.9277) (xy 2.509012 -345.238324) (xy 88.42502 -345.238324) (xy 88.42502 -345.237562)
			(xy 88.425476 -345.196455) (xy 88.433064 -345.114592) (xy 88.448171 -345.033778) (xy 88.470668 -344.954703)
			(xy 88.500364 -344.87804) (xy 88.537005 -344.804443) (xy 88.58028 -344.73454) (xy 88.629818 -344.668927)
			(xy 88.685198 -344.608163) (xy 88.745947 -344.552768) (xy 88.811546 -344.503212) (xy 88.881438 -344.459919)
			(xy 88.955025 -344.423259) (xy 89.031681 -344.393542) (xy 89.110751 -344.371024) (xy 89.19156 -344.355896)
			(xy 89.273421 -344.348287) (xy 89.314528 -344.3478) (xy 89.358923 -344.348358) (xy 89.447268 -344.357247)
			(xy 89.534288 -344.374894) (xy 89.619117 -344.401123) (xy 89.660222 -344.417904) (xy 89.668919 -344.421068)
			(xy 89.687398 -344.421734) (xy 89.69629 -344.419174) (xy 89.742575 -344.404089) (xy 89.837607 -344.382956)
			(xy 89.934379 -344.372329) (xy 89.983056 -344.371676) (xy 89.984326 -344.371676) (xy 90.022483 -344.372111)
			(xy 90.098512 -344.378695) (xy 90.173695 -344.391776) (xy 90.24748 -344.411259) (xy 90.283538 -344.423746)
			(xy 90.291854 -344.426332) (xy 90.309258 -344.426332) (xy 90.317574 -344.423746) (xy 90.353782 -344.41121)
			(xy 90.427885 -344.391692) (xy 90.503391 -344.378612) (xy 90.579741 -344.372068) (xy 90.618056 -344.371676)
			(xy 90.664451 -344.372276) (xy 90.756739 -344.381916) (xy 90.847523 -344.401107) (xy 90.935817 -344.429641)
			(xy 90.978482 -344.447876) (xy 90.988424 -344.451682) (xy 91.009688 -344.451682) (xy 91.01963 -344.447876)
			(xy 91.062298 -344.429645) (xy 91.150588 -344.401097) (xy 91.241371 -344.381901) (xy 91.33366 -344.372263)
			(xy 91.380056 -344.371676) (xy 91.418372 -344.372058) (xy 91.494725 -344.378586) (xy 91.570232 -344.391667)
			(xy 91.644331 -344.411203) (xy 91.680538 -344.423746) (xy 91.688854 -344.426332) (xy 91.706258 -344.426332)
			(xy 91.714574 -344.423746) (xy 91.750782 -344.41121) (xy 91.824885 -344.391692) (xy 91.900391 -344.378612)
			(xy 91.976741 -344.372068) (xy 92.015056 -344.371676) (xy 92.053372 -344.372058) (xy 92.129725 -344.378586)
			(xy 92.205232 -344.391667) (xy 92.279331 -344.411203) (xy 92.315538 -344.423746) (xy 92.323854 -344.426332)
			(xy 92.341258 -344.426332) (xy 92.349574 -344.423746) (xy 92.385691 -344.411238) (xy 92.459606 -344.391753)
			(xy 92.534918 -344.378674) (xy 92.611074 -344.372097) (xy 92.649294 -344.371676) (xy 92.650056 -344.371676)
			(xy 92.691158 -344.372194) (xy 92.773012 -344.379775) (xy 92.853817 -344.394876) (xy 92.932883 -344.417369)
			(xy 93.009537 -344.447061) (xy 93.083125 -344.4837) (xy 93.153018 -344.526972) (xy 93.21862 -344.576508)
			(xy 93.279371 -344.631887) (xy 93.334753 -344.692634) (xy 93.384294 -344.758233) (xy 93.427571 -344.828123)
			(xy 93.464215 -344.901708) (xy 93.493912 -344.97836) (xy 93.51641 -345.057425) (xy 93.531517 -345.138229)
			(xy 93.539103 -345.220082) (xy 93.539564 -345.261184) (xy 93.539564 -345.261692) (xy 93.539139 -345.302203)
			(xy 93.531771 -345.38289) (xy 93.517086 -345.462571) (xy 93.495207 -345.540583) (xy 93.466315 -345.616279)
			(xy 93.448886 -345.652852) (xy 93.444973 -345.661871) (xy 93.443532 -345.68146) (xy 93.446092 -345.690952)
			(xy 93.460285 -345.736019) (xy 93.480192 -345.828387) (xy 93.490186 -345.922345) (xy 93.490796 -345.96959)
			(xy 93.490238 -346.015229) (xy 93.480936 -346.106032) (xy 93.462388 -346.195406) (xy 93.44914 -346.239084)
			(xy 93.446696 -346.248096) (xy 93.447735 -346.266724) (xy 93.451172 -346.275406) (xy 93.469867 -346.318487)
			(xy 93.49915 -346.407722) (xy 93.518862 -346.499547) (xy 93.527728 -346.583) (xy 200.85558 -346.583)
			(xy 200.856207 -346.536598) (xy 200.865897 -346.444301) (xy 200.88515 -346.353515) (xy 200.913758 -346.26523)
			(xy 200.932034 -346.222574) (xy 200.935843 -346.212632) (xy 200.935843 -346.191368) (xy 200.932034 -346.181426)
			(xy 200.913772 -346.138765) (xy 200.885179 -346.050477) (xy 200.865922 -345.959694) (xy 200.856209 -345.867401)
			(xy 200.85558 -345.821) (xy 200.856064 -345.779859) (xy 200.863695 -345.69793) (xy 200.878855 -345.617056)
			(xy 200.901414 -345.537926) (xy 200.931179 -345.461215) (xy 200.967897 -345.38758) (xy 200.989184 -345.35237)
			(xy 200.993752 -345.344157) (xy 200.997195 -345.3257) (xy 200.993752 -345.307243) (xy 200.989184 -345.29903)
			(xy 200.967885 -345.263826) (xy 200.931155 -345.190194) (xy 200.901383 -345.113484) (xy 200.878824 -345.034352)
			(xy 200.86367 -344.953474) (xy 200.856051 -344.871542) (xy 200.85558 -344.8304) (xy 200.856207 -344.783998)
			(xy 200.865897 -344.691701) (xy 200.88515 -344.600915) (xy 200.913758 -344.51263) (xy 200.932034 -344.469974)
			(xy 200.935843 -344.460032) (xy 200.935843 -344.438768) (xy 200.932034 -344.428826) (xy 200.913772 -344.386165)
			(xy 200.885179 -344.297877) (xy 200.865922 -344.207094) (xy 200.856209 -344.114801) (xy 200.85558 -344.0684)
			(xy 200.856084 -344.026039) (xy 200.864137 -343.941702) (xy 200.880171 -343.858512) (xy 200.904039 -343.777222)
			(xy 200.935527 -343.69857) (xy 200.974349 -343.623267) (xy 201.020152 -343.551995) (xy 201.072523 -343.485399)
			(xy 201.130988 -343.424084) (xy 201.195016 -343.368603) (xy 201.264028 -343.31946) (xy 201.337398 -343.2771)
			(xy 201.414463 -343.241905) (xy 201.494525 -343.214196) (xy 201.576858 -343.194222) (xy 201.660717 -343.182165)
			(xy 201.745342 -343.178134) (xy 201.829967 -343.182165) (xy 201.913826 -343.194222) (xy 201.996159 -343.214196)
			(xy 202.076221 -343.241905) (xy 202.153286 -343.2771) (xy 202.226656 -343.31946) (xy 202.295668 -343.368603)
			(xy 202.359696 -343.424084) (xy 202.418161 -343.485399) (xy 202.470532 -343.551995) (xy 202.516335 -343.623267)
			(xy 202.555157 -343.69857) (xy 202.586645 -343.777222) (xy 202.610513 -343.858512) (xy 202.626547 -343.941702)
			(xy 202.6346 -344.026039) (xy 202.635104 -344.0684) (xy 202.634479 -344.114802) (xy 202.624789 -344.2071)
			(xy 202.605534 -344.297885) (xy 202.576926 -344.38617) (xy 202.55865 -344.428826) (xy 202.554842 -344.438768)
			(xy 202.554842 -344.460032) (xy 202.55865 -344.469974) (xy 202.576911 -344.512635) (xy 202.605505 -344.600923)
			(xy 202.624762 -344.691706) (xy 202.634475 -344.783999) (xy 202.635104 -344.8304) (xy 202.634622 -344.871541)
			(xy 202.626991 -344.95347) (xy 202.611831 -345.034344) (xy 202.589272 -345.113474) (xy 202.559506 -345.190185)
			(xy 202.522787 -345.263821) (xy 202.5015 -345.29903) (xy 202.496933 -345.307243) (xy 202.493491 -345.3257)
			(xy 202.496933 -345.344157) (xy 202.5015 -345.35237) (xy 202.522797 -345.387575) (xy 202.559528 -345.461207)
			(xy 202.5893 -345.537917) (xy 202.61186 -345.617049) (xy 202.627014 -345.697926) (xy 202.634633 -345.779858)
			(xy 202.635104 -345.821) (xy 202.634479 -345.867402) (xy 202.624789 -345.9597) (xy 202.605534 -346.050485)
			(xy 202.576926 -346.13877) (xy 202.55865 -346.181426) (xy 202.554842 -346.191368) (xy 202.554842 -346.212632)
			(xy 202.55865 -346.222574) (xy 202.576911 -346.265235) (xy 202.605505 -346.353523) (xy 202.624762 -346.444306)
			(xy 202.634475 -346.536599) (xy 202.635104 -346.583) (xy 202.6346 -346.625361) (xy 202.626547 -346.709698)
			(xy 202.610513 -346.792888) (xy 202.586645 -346.874178) (xy 202.555157 -346.95283) (xy 202.516335 -347.028133)
			(xy 202.470532 -347.099405) (xy 202.418161 -347.166001) (xy 202.359696 -347.227316) (xy 202.295668 -347.282797)
			(xy 202.226656 -347.33194) (xy 202.153286 -347.3743) (xy 202.076221 -347.409495) (xy 201.996159 -347.437204)
			(xy 201.913826 -347.457178) (xy 201.829967 -347.469235) (xy 201.745342 -347.473267) (xy 201.660717 -347.469235)
			(xy 201.576858 -347.457178) (xy 201.494525 -347.437204) (xy 201.414463 -347.409495) (xy 201.337398 -347.3743)
			(xy 201.264028 -347.33194) (xy 201.195016 -347.282797) (xy 201.130988 -347.227316) (xy 201.072523 -347.166001)
			(xy 201.020152 -347.099405) (xy 200.974349 -347.028133) (xy 200.935527 -346.95283) (xy 200.904039 -346.874178)
			(xy 200.880171 -346.792888) (xy 200.864137 -346.709698) (xy 200.856084 -346.625361) (xy 200.85558 -346.583)
			(xy 93.527728 -346.583) (xy 93.528784 -346.592938) (xy 93.529404 -346.639896) (xy 93.528944 -346.681007)
			(xy 93.521356 -346.762877) (xy 93.506246 -346.843698) (xy 93.483741 -346.92278) (xy 93.454034 -346.999447)
			(xy 93.417379 -347.073045) (xy 93.374088 -347.142947) (xy 93.324531 -347.208555) (xy 93.269131 -347.26931)
			(xy 93.20836 -347.324693) (xy 93.142737 -347.374232) (xy 93.072823 -347.417503) (xy 92.999214 -347.454137)
			(xy 92.922539 -347.483822) (xy 92.843451 -347.506304) (xy 92.762626 -347.521391) (xy 92.680753 -347.528955)
			(xy 92.639642 -347.529404) (xy 92.601326 -347.529024) (xy 92.524973 -347.522495) (xy 92.449466 -347.509414)
			(xy 92.375367 -347.489878) (xy 92.33916 -347.477334) (xy 92.330844 -347.474748) (xy 92.31344 -347.474748)
			(xy 92.305124 -347.477334) (xy 92.268906 -347.489842) (xy 92.194807 -347.509368) (xy 92.119304 -347.522455)
			(xy 92.042956 -347.529008) (xy 92.004642 -347.529404) (xy 91.961529 -347.52892) (xy 91.875703 -347.520642)
			(xy 91.791081 -347.504091) (xy 91.70846 -347.479423) (xy 91.668346 -347.463618) (xy 91.658977 -347.460281)
			(xy 91.639107 -347.460281) (xy 91.629738 -347.463618) (xy 91.589623 -347.479419) (xy 91.506999 -347.504075)
			(xy 91.422379 -347.520627) (xy 91.336554 -347.528919) (xy 91.293442 -347.529404) (xy 91.255126 -347.529024)
			(xy 91.178773 -347.522495) (xy 91.103266 -347.509414) (xy 91.029167 -347.489878) (xy 90.99296 -347.477334)
			(xy 90.984644 -347.474748) (xy 90.96724 -347.474748) (xy 90.958924 -347.477334) (xy 90.922706 -347.489842)
			(xy 90.848607 -347.509368) (xy 90.773104 -347.522455) (xy 90.696756 -347.529008) (xy 90.658442 -347.529404)
			(xy 90.620126 -347.529024) (xy 90.543773 -347.522495) (xy 90.468266 -347.509414) (xy 90.394167 -347.489878)
			(xy 90.35796 -347.477334) (xy 90.349644 -347.474748) (xy 90.33224 -347.474748) (xy 90.323924 -347.477334)
			(xy 90.287706 -347.489842) (xy 90.213607 -347.509368) (xy 90.138104 -347.522455) (xy 90.061756 -347.529008)
			(xy 90.023442 -347.529404) (xy 89.985126 -347.529024) (xy 89.908773 -347.522495) (xy 89.833266 -347.509414)
			(xy 89.759167 -347.489878) (xy 89.72296 -347.477334) (xy 89.714644 -347.474748) (xy 89.69724 -347.474748)
			(xy 89.688924 -347.477334) (xy 89.652807 -347.489842) (xy 89.578892 -347.509327) (xy 89.50358 -347.522407)
			(xy 89.427424 -347.528983) (xy 89.389204 -347.529404) (xy 89.388442 -347.529404) (xy 89.347337 -347.528847)
			(xy 89.265478 -347.521267) (xy 89.184667 -347.506168) (xy 89.105593 -347.483678) (xy 89.028932 -347.453989)
			(xy 88.955336 -347.417355) (xy 88.885433 -347.374087) (xy 88.81982 -347.324556) (xy 88.759057 -347.269183)
			(xy 88.70366 -347.20844) (xy 88.654104 -347.142846) (xy 88.61081 -347.07296) (xy 88.574148 -346.999378)
			(xy 88.54443 -346.922728) (xy 88.52191 -346.843663) (xy 88.506779 -346.762857) (xy 88.499168 -346.681001)
			(xy 88.49868 -346.639896) (xy 88.49928 -346.594251) (xy 88.508675 -346.503445) (xy 88.527305 -346.414075)
			(xy 88.54059 -346.370402) (xy 88.543039 -346.361391) (xy 88.541996 -346.342762) (xy 88.538558 -346.33408)
			(xy 88.519895 -346.290993) (xy 88.490688 -346.201748) (xy 88.471043 -346.109924) (xy 88.461176 -346.016541)
			(xy 88.46058 -345.96959) (xy 88.460997 -345.930463) (xy 88.467845 -345.852508) (xy 88.481506 -345.775455)
			(xy 88.501874 -345.699897) (xy 88.514936 -345.663012) (xy 88.517951 -345.653293) (xy 88.516917 -345.632991)
			(xy 88.512904 -345.623642) (xy 88.496039 -345.587523) (xy 88.46806 -345.512874) (xy 88.44687 -345.436021)
			(xy 88.432638 -345.357582) (xy 88.425479 -345.278184) (xy 88.42502 -345.238324) (xy 2.509012 -345.238324)
			(xy 2.509012 -348.70949) (xy 28.410141 -348.70949) (xy 28.414132 -348.625708) (xy 28.426069 -348.542686)
			(xy 28.445844 -348.461173) (xy 28.473277 -348.38191) (xy 28.508121 -348.305613) (xy 28.550059 -348.232974)
			(xy 28.598712 -348.16465) (xy 28.65364 -348.101261) (xy 28.714345 -348.043379) (xy 28.780276 -347.99153)
			(xy 28.850838 -347.946183) (xy 28.92539 -347.907749) (xy 29.003259 -347.876576) (xy 29.083738 -347.852945)
			(xy 29.166099 -347.837072) (xy 29.249596 -347.829099) (xy 29.291534 -347.828616) (xy 29.328723 -347.829023)
			(xy 29.402836 -347.835307) (xy 29.476156 -347.847812) (xy 29.548162 -347.866448) (xy 29.58338 -347.8784)
			(xy 29.591577 -347.880914) (xy 29.608711 -347.880914) (xy 29.616908 -347.8784) (xy 29.652035 -347.866473)
			(xy 29.723849 -347.847849) (xy 29.796976 -347.835339) (xy 29.870898 -347.829031) (xy 29.907992 -347.828616)
			(xy 29.909516 -347.828616) (xy 29.916374 -347.82887) (xy 29.922431 -347.792721) (xy 29.939716 -347.721486)
			(xy 29.962803 -347.651915) (xy 29.976826 -347.61805) (xy 29.980289 -347.608427) (xy 29.980173 -347.587996)
			(xy 29.976572 -347.578426) (xy 29.959544 -347.537016) (xy 29.932908 -347.451529) (xy 29.915001 -347.363797)
			(xy 29.906005 -347.274709) (xy 29.905452 -347.229938) (xy 29.905933 -347.189355) (xy 29.913331 -347.108527)
			(xy 29.928059 -347.028709) (xy 29.949995 -346.950564) (xy 29.978957 -346.874741) (xy 30.014703 -346.801871)
			(xy 30.056938 -346.732559) (xy 30.10531 -346.667382) (xy 30.159416 -346.606881) (xy 30.218807 -346.551559)
			(xy 30.28299 -346.501876) (xy 30.351431 -346.458245) (xy 30.38729 -346.439236) (xy 30.395816 -346.434265)
			(xy 30.408633 -346.419285) (xy 30.414885 -346.400588) (xy 30.414722 -346.390722) (xy 30.41396 -346.365322)
			(xy 30.414481 -346.337437) (xy 30.422793 -346.28229) (xy 30.439231 -346.228998) (xy 30.463429 -346.178752)
			(xy 30.494845 -346.132673) (xy 30.532778 -346.091791) (xy 30.57638 -346.057019) (xy 30.624678 -346.029134)
			(xy 30.676593 -346.008759) (xy 30.730964 -345.996349) (xy 30.786578 -345.992182) (xy 30.842192 -345.996349)
			(xy 30.896563 -346.008759) (xy 30.948478 -346.029134) (xy 30.996776 -346.057019) (xy 31.040378 -346.091791)
			(xy 31.078311 -346.132673) (xy 31.109727 -346.178752) (xy 31.133925 -346.228998) (xy 31.150363 -346.28229)
			(xy 31.158675 -346.337437) (xy 31.159196 -346.365322) (xy 31.158688 -346.383356) (xy 31.15866 -346.393249)
			(xy 31.165282 -346.411875) (xy 31.178455 -346.426614) (xy 31.187136 -346.431362) (xy 31.224041 -346.449965)
			(xy 31.294555 -346.49308) (xy 31.360766 -346.542551) (xy 31.4221 -346.597952) (xy 31.47803 -346.658805)
			(xy 31.528073 -346.724585) (xy 31.571797 -346.794724) (xy 31.608825 -346.868616) (xy 31.638837 -346.945626)
			(xy 31.661575 -347.025088) (xy 31.676842 -347.106317) (xy 31.684507 -347.188612) (xy 31.684976 -347.229938)
			(xy 31.684414 -347.274708) (xy 31.675404 -347.363793) (xy 31.657499 -347.451524) (xy 31.630879 -347.537015)
			(xy 31.613856 -347.578426) (xy 31.61027 -347.58801) (xy 31.610284 -347.608459) (xy 31.613856 -347.61805)
			(xy 31.630031 -347.657368) (xy 31.655701 -347.738424) (xy 31.673532 -347.821557) (xy 31.68336 -347.906011)
			(xy 31.684722 -347.948504) (xy 31.684976 -347.96222) (xy 31.6992 -347.985588) (xy 31.788862 -348.034102)
			(xy 31.796927 -348.038113) (xy 31.814734 -348.040741) (xy 31.832352 -348.037052) (xy 31.84017 -348.032578)
			(xy 31.875522 -348.010993) (xy 31.949529 -347.973778) (xy 32.026677 -347.943609) (xy 32.106297 -347.920748)
			(xy 32.187699 -347.905393) (xy 32.270176 -347.897677) (xy 32.311594 -347.897196) (xy 32.352707 -347.897719)
			(xy 32.434582 -347.905305) (xy 32.515408 -347.920413) (xy 32.594495 -347.942914) (xy 32.671169 -347.972616)
			(xy 32.744775 -348.009266) (xy 32.814686 -348.05255) (xy 32.880304 -348.102101) (xy 32.941071 -348.157495)
			(xy 32.996468 -348.218259) (xy 33.046022 -348.283875) (xy 33.089311 -348.353783) (xy 33.125965 -348.427387)
			(xy 33.155671 -348.504059) (xy 33.178176 -348.583145) (xy 33.193289 -348.66397) (xy 33.197509 -348.70949)
			(xy 36.690541 -348.70949) (xy 36.694532 -348.625708) (xy 36.706469 -348.542686) (xy 36.726244 -348.461173)
			(xy 36.753677 -348.38191) (xy 36.788521 -348.305613) (xy 36.830459 -348.232974) (xy 36.879112 -348.16465)
			(xy 36.93404 -348.101261) (xy 36.994745 -348.043379) (xy 37.060676 -347.99153) (xy 37.131238 -347.946183)
			(xy 37.20579 -347.907749) (xy 37.283659 -347.876576) (xy 37.364138 -347.852945) (xy 37.446499 -347.837072)
			(xy 37.529996 -347.829099) (xy 37.571934 -347.828616) (xy 37.609123 -347.829023) (xy 37.683236 -347.835307)
			(xy 37.756556 -347.847812) (xy 37.828562 -347.866448) (xy 37.86378 -347.8784) (xy 37.871977 -347.880914)
			(xy 37.889111 -347.880914) (xy 37.897308 -347.8784) (xy 37.93549 -347.865472) (xy 38.013674 -347.845816)
			(xy 38.093328 -347.833391) (xy 38.133528 -347.830394) (xy 38.144516 -347.829167) (xy 38.163935 -347.818636)
			(xy 38.177169 -347.800949) (xy 38.18001 -347.790262) (xy 38.189419 -347.748079) (xy 38.215379 -347.665637)
			(xy 38.231826 -347.62567) (xy 38.235335 -347.61606) (xy 38.235189 -347.595617) (xy 38.231572 -347.586046)
			(xy 38.21455 -347.544634) (xy 38.187912 -347.459147) (xy 38.170004 -347.371416) (xy 38.161006 -347.282328)
			(xy 38.160452 -347.237558) (xy 38.160956 -347.195197) (xy 38.169009 -347.11086) (xy 38.185043 -347.02767)
			(xy 38.208911 -346.94638) (xy 38.240399 -346.867728) (xy 38.279221 -346.792425) (xy 38.325024 -346.721153)
			(xy 38.377395 -346.654557) (xy 38.43586 -346.593242) (xy 38.499888 -346.537761) (xy 38.5689 -346.488618)
			(xy 38.64227 -346.446258) (xy 38.719335 -346.411063) (xy 38.799397 -346.383354) (xy 38.88173 -346.36338)
			(xy 38.965589 -346.351323) (xy 39.050214 -346.347292) (xy 39.134839 -346.351323) (xy 39.218698 -346.36338)
			(xy 39.301031 -346.383354) (xy 39.381093 -346.411063) (xy 39.458158 -346.446258) (xy 39.531528 -346.488618)
			(xy 39.60054 -346.537761) (xy 39.664568 -346.593242) (xy 39.723033 -346.654557) (xy 39.775404 -346.721153)
			(xy 39.821207 -346.792425) (xy 39.860029 -346.867728) (xy 39.891517 -346.94638) (xy 39.915385 -347.02767)
			(xy 39.931419 -347.11086) (xy 39.939472 -347.195197) (xy 39.939976 -347.237558) (xy 39.939421 -347.282328)
			(xy 39.930409 -347.371413) (xy 39.912502 -347.459144) (xy 39.88588 -347.544635) (xy 39.868856 -347.586046)
			(xy 39.865251 -347.595621) (xy 39.865104 -347.616057) (xy 39.868602 -347.62567) (xy 39.88516 -347.665899)
			(xy 39.911278 -347.748887) (xy 39.929176 -347.834027) (xy 39.938683 -347.920507) (xy 39.939722 -347.963998)
			(xy 39.939722 -347.964252) (xy 39.94031 -347.973302) (xy 39.94696 -347.990157) (xy 39.959055 -348.003648)
			(xy 39.9669 -348.008194) (xy 40.058086 -348.056454) (xy 40.086026 -348.05493) (xy 40.09771 -348.04731)
			(xy 40.134305 -348.023444) (xy 40.211348 -347.98223) (xy 40.292061 -347.948768) (xy 40.375665 -347.923381)
			(xy 40.461356 -347.906311) (xy 40.548307 -347.897725) (xy 40.591994 -347.897196) (xy 40.633107 -347.897719)
			(xy 40.714982 -347.905305) (xy 40.795808 -347.920413) (xy 40.874895 -347.942914) (xy 40.951569 -347.972616)
			(xy 41.025175 -348.009266) (xy 41.095086 -348.05255) (xy 41.160704 -348.102101) (xy 41.221471 -348.157495)
			(xy 41.276868 -348.218259) (xy 41.326422 -348.283875) (xy 41.369711 -348.353783) (xy 41.406365 -348.427387)
			(xy 41.436071 -348.504059) (xy 41.458576 -348.583145) (xy 41.473689 -348.66397) (xy 41.47791 -348.7095)
			(xy 44.996301 -348.7095) (xy 45.000292 -348.625716) (xy 45.01223 -348.54269) (xy 45.032006 -348.461175)
			(xy 45.05944 -348.381909) (xy 45.094286 -348.30561) (xy 45.136227 -348.232969) (xy 45.184883 -348.164644)
			(xy 45.239813 -348.101253) (xy 45.30052 -348.043371) (xy 45.366455 -347.991522) (xy 45.43702 -347.946175)
			(xy 45.511576 -347.907741) (xy 45.589448 -347.876568) (xy 45.66993 -347.852939) (xy 45.752294 -347.837068)
			(xy 45.835794 -347.829098) (xy 45.877734 -347.828616) (xy 45.914923 -347.829023) (xy 45.989036 -347.835307)
			(xy 46.062356 -347.847812) (xy 46.134362 -347.866448) (xy 46.16958 -347.8784) (xy 46.177777 -347.880914)
			(xy 46.194911 -347.880914) (xy 46.203108 -347.8784) (xy 46.238327 -347.866445) (xy 46.310329 -347.847789)
			(xy 46.383649 -347.835279) (xy 46.457764 -347.829003) (xy 46.494954 -347.828616) (xy 46.496732 -347.82887)
			(xy 46.506097 -347.78788) (xy 46.53154 -347.707736) (xy 46.547532 -347.66885) (xy 46.551076 -347.659253)
			(xy 46.55109 -347.638816) (xy 46.547532 -347.629226) (xy 46.530501 -347.587817) (xy 46.503866 -347.502329)
			(xy 46.485961 -347.414597) (xy 46.476965 -347.325509) (xy 46.476412 -347.280738) (xy 46.476916 -347.238377)
			(xy 46.484969 -347.15404) (xy 46.501003 -347.07085) (xy 46.524871 -346.98956) (xy 46.556359 -346.910908)
			(xy 46.595181 -346.835605) (xy 46.640984 -346.764333) (xy 46.693355 -346.697737) (xy 46.75182 -346.636422)
			(xy 46.815848 -346.580941) (xy 46.88486 -346.531798) (xy 46.95823 -346.489438) (xy 47.035295 -346.454243)
			(xy 47.115357 -346.426534) (xy 47.19769 -346.40656) (xy 47.281549 -346.394503) (xy 47.366174 -346.390472)
			(xy 47.450799 -346.394503) (xy 47.534658 -346.40656) (xy 47.616991 -346.426534) (xy 47.697053 -346.454243)
			(xy 47.774118 -346.489438) (xy 47.847488 -346.531798) (xy 47.9165 -346.580941) (xy 47.980528 -346.636422)
			(xy 48.038993 -346.697737) (xy 48.091364 -346.764333) (xy 48.137167 -346.835605) (xy 48.175989 -346.910908)
			(xy 48.207477 -346.98956) (xy 48.231345 -347.07085) (xy 48.247379 -347.15404) (xy 48.255432 -347.238377)
			(xy 48.255936 -347.280738) (xy 48.25537 -347.325508) (xy 48.24636 -347.414592) (xy 48.228456 -347.502324)
			(xy 48.201838 -347.587815) (xy 48.184816 -347.629226) (xy 48.181232 -347.638811) (xy 48.181246 -347.659259)
			(xy 48.184816 -347.66885) (xy 48.199304 -347.703977) (xy 48.222973 -347.776187) (xy 48.2404 -347.850153)
			(xy 48.251457 -347.925335) (xy 48.254158 -347.963236) (xy 48.255104 -347.972078) (xy 48.26215 -347.988388)
			(xy 48.274337 -348.001315) (xy 48.282098 -348.005654) (xy 48.37303 -348.051374) (xy 48.3997 -348.04985)
			(xy 48.41113 -348.04223) (xy 48.447343 -348.019182) (xy 48.523387 -347.979349) (xy 48.602912 -347.947022)
			(xy 48.685181 -347.922504) (xy 48.769429 -347.90602) (xy 48.854872 -347.897725) (xy 48.897794 -347.897196)
			(xy 48.938907 -347.897719) (xy 49.020782 -347.905305) (xy 49.101608 -347.920413) (xy 49.180695 -347.942914)
			(xy 49.257369 -347.972616) (xy 49.330975 -348.009266) (xy 49.400886 -348.05255) (xy 49.466504 -348.102101)
			(xy 49.527271 -348.157495) (xy 49.582668 -348.218259) (xy 49.632222 -348.283875) (xy 49.675511 -348.353783)
			(xy 49.712165 -348.427387) (xy 49.741871 -348.504059) (xy 49.764376 -348.583145) (xy 49.779489 -348.66397)
			(xy 49.78371 -348.7095) (xy 53.352901 -348.7095) (xy 53.356892 -348.625716) (xy 53.36883 -348.54269)
			(xy 53.388606 -348.461175) (xy 53.41604 -348.381909) (xy 53.450886 -348.30561) (xy 53.492827 -348.232969)
			(xy 53.541483 -348.164644) (xy 53.596413 -348.101253) (xy 53.65712 -348.043371) (xy 53.723055 -347.991522)
			(xy 53.79362 -347.946175) (xy 53.868176 -347.907741) (xy 53.946048 -347.876568) (xy 54.02653 -347.852939)
			(xy 54.108894 -347.837068) (xy 54.192394 -347.829098) (xy 54.234334 -347.828616) (xy 54.271523 -347.829023)
			(xy 54.345636 -347.835307) (xy 54.418956 -347.847812) (xy 54.490962 -347.866448) (xy 54.52618 -347.8784)
			(xy 54.534377 -347.880914) (xy 54.551511 -347.880914) (xy 54.559708 -347.8784) (xy 54.594654 -347.86653)
			(xy 54.66609 -347.847969) (xy 54.738831 -347.835458) (xy 54.812365 -347.829087) (xy 54.849268 -347.828616)
			(xy 54.85384 -347.82887) (xy 54.854348 -347.82887) (xy 54.863907 -347.782599) (xy 54.89152 -347.692237)
			(xy 54.909466 -347.64853) (xy 54.912939 -347.63891) (xy 54.912815 -347.618477) (xy 54.909212 -347.608906)
			(xy 54.892173 -347.5675) (xy 54.865541 -347.482011) (xy 54.847637 -347.394278) (xy 54.838644 -347.305189)
			(xy 54.838092 -347.260418) (xy 54.838596 -347.218057) (xy 54.846649 -347.13372) (xy 54.862683 -347.05053)
			(xy 54.886551 -346.96924) (xy 54.918039 -346.890588) (xy 54.956861 -346.815285) (xy 55.002664 -346.744013)
			(xy 55.055035 -346.677417) (xy 55.1135 -346.616102) (xy 55.177528 -346.560621) (xy 55.24654 -346.511478)
			(xy 55.31991 -346.469118) (xy 55.396975 -346.433923) (xy 55.477037 -346.406214) (xy 55.55937 -346.38624)
			(xy 55.643229 -346.374183) (xy 55.727854 -346.370152) (xy 55.812479 -346.374183) (xy 55.896338 -346.38624)
			(xy 55.978671 -346.406214) (xy 56.058733 -346.433923) (xy 56.135798 -346.469118) (xy 56.209168 -346.511478)
			(xy 56.27818 -346.560621) (xy 56.342208 -346.616102) (xy 56.400673 -346.677417) (xy 56.453044 -346.744013)
			(xy 56.498847 -346.815285) (xy 56.537669 -346.890588) (xy 56.569157 -346.96924) (xy 56.593025 -347.05053)
			(xy 56.609059 -347.13372) (xy 56.617112 -347.218057) (xy 56.617616 -347.260418) (xy 56.617044 -347.305187)
			(xy 56.608037 -347.394272) (xy 56.590134 -347.482003) (xy 56.563518 -347.567495) (xy 56.546496 -347.608906)
			(xy 56.542919 -347.618493) (xy 56.542926 -347.63894) (xy 56.546496 -347.64853) (xy 56.561684 -347.685398)
			(xy 56.586189 -347.761282) (xy 56.603812 -347.839053) (xy 56.614411 -347.918088) (xy 56.6166 -347.957902)
			(xy 56.617108 -347.971364) (xy 56.63184 -347.994224) (xy 56.734456 -348.047564) (xy 56.761634 -348.04604)
			(xy 56.773064 -348.038674) (xy 56.808981 -348.016152) (xy 56.88432 -347.977266) (xy 56.963017 -347.945725)
			(xy 57.044358 -347.921816) (xy 57.127605 -347.905754) (xy 57.212003 -347.897686) (xy 57.254394 -347.897196)
			(xy 57.295507 -347.897719) (xy 57.377382 -347.905305) (xy 57.458208 -347.920413) (xy 57.537295 -347.942914)
			(xy 57.613969 -347.972616) (xy 57.687575 -348.009266) (xy 57.757486 -348.05255) (xy 57.823104 -348.102101)
			(xy 57.883871 -348.157495) (xy 57.939268 -348.218259) (xy 57.988822 -348.283875) (xy 58.032111 -348.353783)
			(xy 58.068765 -348.427387) (xy 58.098471 -348.504059) (xy 58.120976 -348.583145) (xy 58.136089 -348.66397)
			(xy 58.14031 -348.7095) (xy 61.684101 -348.7095) (xy 61.688092 -348.625716) (xy 61.70003 -348.54269)
			(xy 61.719806 -348.461175) (xy 61.74724 -348.381909) (xy 61.782086 -348.30561) (xy 61.824027 -348.232969)
			(xy 61.872683 -348.164644) (xy 61.927613 -348.101253) (xy 61.98832 -348.043371) (xy 62.054255 -347.991522)
			(xy 62.12482 -347.946175) (xy 62.199376 -347.907741) (xy 62.277248 -347.876568) (xy 62.35773 -347.852939)
			(xy 62.440094 -347.837068) (xy 62.523594 -347.829098) (xy 62.565534 -347.828616) (xy 62.602723 -347.829023)
			(xy 62.676836 -347.835307) (xy 62.750156 -347.847812) (xy 62.822162 -347.866448) (xy 62.85738 -347.8784)
			(xy 62.865577 -347.880914) (xy 62.882711 -347.880914) (xy 62.890908 -347.8784) (xy 62.926096 -347.866455)
			(xy 62.998036 -347.847809) (xy 63.071292 -347.835299) (xy 63.145342 -347.829013) (xy 63.1825 -347.828616)
			(xy 63.183008 -347.828616) (xy 63.206122 -347.829124) (xy 63.215205 -347.793715) (xy 63.238479 -347.724411)
			(xy 63.252604 -347.690694) (xy 63.256229 -347.680981) (xy 63.25624 -347.66027) (xy 63.252604 -347.650562)
			(xy 63.235485 -347.609307) (xy 63.208697 -347.524095) (xy 63.190664 -347.436611) (xy 63.181571 -347.347751)
			(xy 63.180976 -347.30309) (xy 63.180976 -347.302328) (xy 63.181475 -347.260403) (xy 63.189445 -347.176932)
			(xy 63.205314 -347.094597) (xy 63.228937 -347.014143) (xy 63.260101 -346.936299) (xy 63.298524 -346.861769)
			(xy 63.343857 -346.79123) (xy 63.39569 -346.725319) (xy 63.453553 -346.664633) (xy 63.516923 -346.609723)
			(xy 63.585226 -346.561085) (xy 63.657843 -346.51916) (xy 63.734116 -346.484327) (xy 63.813355 -346.456902)
			(xy 63.894841 -346.437133) (xy 63.977838 -346.4252) (xy 64.061594 -346.421211) (xy 64.14535 -346.4252)
			(xy 64.228347 -346.437133) (xy 64.309833 -346.456902) (xy 64.389072 -346.484327) (xy 64.465345 -346.51916)
			(xy 64.537962 -346.561085) (xy 64.606265 -346.609723) (xy 64.669635 -346.664633) (xy 64.727498 -346.725319)
			(xy 64.779331 -346.79123) (xy 64.824664 -346.861769) (xy 64.863087 -346.936299) (xy 64.894251 -347.014143)
			(xy 64.917874 -347.094597) (xy 64.933743 -347.176932) (xy 64.941713 -347.260403) (xy 64.942212 -347.302328)
			(xy 64.942212 -347.30309) (xy 64.941639 -347.347753) (xy 64.932567 -347.436619) (xy 64.914535 -347.524107)
			(xy 64.88773 -347.609317) (xy 64.870584 -347.650562) (xy 64.866927 -347.660266) (xy 64.866937 -347.680985)
			(xy 64.870584 -347.690694) (xy 64.888862 -347.734789) (xy 64.91689 -347.826038) (xy 64.934892 -347.919782)
			(xy 64.939418 -347.9673) (xy 64.940434 -347.980508) (xy 64.955674 -348.00286) (xy 65.046352 -348.047056)
			(xy 65.054393 -348.050544) (xy 65.071798 -348.052482) (xy 65.088843 -348.048463) (xy 65.09639 -348.044008)
			(xy 65.096644 -348.043754) (xy 65.132959 -348.020439) (xy 65.209305 -347.980191) (xy 65.289189 -347.947525)
			(xy 65.371861 -347.922748) (xy 65.456544 -347.906093) (xy 65.542442 -347.897716) (xy 65.585594 -347.897196)
			(xy 65.626707 -347.897719) (xy 65.708582 -347.905305) (xy 65.789408 -347.920413) (xy 65.868495 -347.942914)
			(xy 65.945169 -347.972616) (xy 66.018775 -348.009266) (xy 66.088686 -348.05255) (xy 66.154304 -348.102101)
			(xy 66.215071 -348.157495) (xy 66.270468 -348.218259) (xy 66.320022 -348.283875) (xy 66.363311 -348.353783)
			(xy 66.399965 -348.427387) (xy 66.429671 -348.504059) (xy 66.452176 -348.583145) (xy 66.467289 -348.66397)
			(xy 66.474879 -348.745845) (xy 66.475356 -348.786958) (xy 66.474795 -348.831728) (xy 66.467942 -348.89948)
			(xy 81.294224 -348.89948) (xy 81.294687 -348.858913) (xy 81.30208 -348.778118) (xy 81.316804 -348.698332)
			(xy 81.338734 -348.620219) (xy 81.36769 -348.544429) (xy 81.385156 -348.507812) (xy 81.389058 -348.498717)
			(xy 81.390365 -348.478988) (xy 81.387696 -348.469458) (xy 81.373498 -348.424437) (xy 81.353605 -348.332151)
			(xy 81.343609 -348.238277) (xy 81.342992 -348.191074) (xy 81.343496 -348.148713) (xy 81.351549 -348.064376)
			(xy 81.367583 -347.981186) (xy 81.391451 -347.899896) (xy 81.422939 -347.821244) (xy 81.461761 -347.745941)
			(xy 81.507564 -347.674669) (xy 81.559935 -347.608073) (xy 81.6184 -347.546758) (xy 81.682428 -347.491277)
			(xy 81.75144 -347.442134) (xy 81.82481 -347.399774) (xy 81.901875 -347.364579) (xy 81.981937 -347.33687)
			(xy 82.06427 -347.316896) (xy 82.148129 -347.304839) (xy 82.232754 -347.300808) (xy 82.317379 -347.304839)
			(xy 82.401238 -347.316896) (xy 82.483571 -347.33687) (xy 82.563633 -347.364579) (xy 82.640698 -347.399774)
			(xy 82.714068 -347.442134) (xy 82.78308 -347.491277) (xy 82.847108 -347.546758) (xy 82.905573 -347.608073)
			(xy 82.957944 -347.674669) (xy 83.003747 -347.745941) (xy 83.042569 -347.821244) (xy 83.074057 -347.899896)
			(xy 83.097925 -347.981186) (xy 83.113959 -348.064376) (xy 83.122012 -348.148713) (xy 83.122516 -348.191074)
			(xy 83.12207 -348.231641) (xy 83.114672 -348.312437) (xy 83.099945 -348.392223) (xy 83.07801 -348.470336)
			(xy 83.049051 -348.546125) (xy 83.031584 -348.582742) (xy 83.027707 -348.591846) (xy 83.026383 -348.611567)
			(xy 83.029044 -348.621096) (xy 83.043232 -348.66612) (xy 83.063129 -348.758404) (xy 83.073129 -348.852278)
			(xy 83.073245 -348.861126) (xy 83.956144 -348.861126) (xy 83.956552 -348.820564) (xy 83.963891 -348.739773)
			(xy 83.978566 -348.659987) (xy 84.000454 -348.581872) (xy 84.029373 -348.506078) (xy 84.046822 -348.469458)
			(xy 84.05073 -348.460437) (xy 84.052174 -348.440849) (xy 84.049616 -348.431358) (xy 84.035467 -348.386455)
			(xy 84.015597 -348.294425) (xy 84.005567 -348.200811) (xy 84.004912 -348.153736) (xy 84.004912 -348.15272)
			(xy 84.005416 -348.110372) (xy 84.013467 -348.026058) (xy 84.029496 -347.942892) (xy 84.053357 -347.861625)
			(xy 84.084836 -347.782995) (xy 84.123647 -347.707714) (xy 84.169437 -347.636462) (xy 84.221793 -347.569886)
			(xy 84.280241 -347.508588) (xy 84.344251 -347.453123) (xy 84.413243 -347.403994) (xy 84.486593 -347.361645)
			(xy 84.563636 -347.326461) (xy 84.643675 -347.298759) (xy 84.725984 -347.278791) (xy 84.809819 -347.266738)
			(xy 84.89442 -347.262708) (xy 84.979021 -347.266738) (xy 85.062856 -347.278791) (xy 85.145165 -347.298759)
			(xy 85.225204 -347.326461) (xy 85.302247 -347.361645) (xy 85.375597 -347.403994) (xy 85.444589 -347.453123)
			(xy 85.508599 -347.508588) (xy 85.567047 -347.569886) (xy 85.619403 -347.636462) (xy 85.665193 -347.707714)
			(xy 85.704004 -347.782995) (xy 85.735483 -347.861625) (xy 85.759344 -347.942892) (xy 85.775373 -348.026058)
			(xy 85.783424 -348.110372) (xy 85.783928 -348.15272) (xy 85.783928 -348.153228) (xy 85.783471 -348.193738)
			(xy 85.77611 -348.274424) (xy 85.761432 -348.354104) (xy 85.73956 -348.432117) (xy 85.710675 -348.507814)
			(xy 85.69325 -348.544388) (xy 85.689318 -348.553401) (xy 85.687887 -348.572996) (xy 85.690456 -348.582488)
			(xy 85.70466 -348.627551) (xy 85.721282 -348.7047) (xy 275.231844 -348.7047) (xy 275.235834 -348.620942)
			(xy 275.247768 -348.537942) (xy 275.267537 -348.456452) (xy 275.294962 -348.377211) (xy 275.329796 -348.300935)
			(xy 275.371722 -348.228316) (xy 275.420361 -348.16001) (xy 275.475273 -348.096638) (xy 275.53596 -348.038772)
			(xy 275.601873 -347.986937) (xy 275.672414 -347.941602) (xy 275.746946 -347.903177) (xy 275.824792 -347.872011)
			(xy 275.905248 -347.848386) (xy 275.987586 -347.832515) (xy 276.071059 -347.824543) (xy 276.112986 -347.824044)
			(xy 276.114002 -347.824044) (xy 276.151059 -347.824452) (xy 276.224908 -347.830716) (xy 276.29797 -347.843157)
			(xy 276.36973 -347.861689) (xy 276.404832 -347.873574) (xy 276.413029 -347.876088) (xy 276.430163 -347.876088)
			(xy 276.43836 -347.873574) (xy 276.478966 -347.8599) (xy 276.562216 -347.839604) (xy 276.647042 -347.827484)
			(xy 276.68982 -347.82506) (xy 276.700434 -347.823969) (xy 276.719453 -347.814348) (xy 276.732947 -347.797851)
			(xy 276.736302 -347.787722) (xy 276.744404 -347.759433) (xy 276.763852 -347.703889) (xy 276.775164 -347.676724)
			(xy 276.778721 -347.667131) (xy 276.778725 -347.646691) (xy 276.775164 -347.6371) (xy 276.758127 -347.595694)
			(xy 276.731493 -347.510205) (xy 276.713589 -347.422472) (xy 276.704596 -347.333383) (xy 276.704044 -347.288612)
			(xy 276.704548 -347.246251) (xy 276.712601 -347.161914) (xy 276.728635 -347.078724) (xy 276.752503 -346.997434)
			(xy 276.783991 -346.918782) (xy 276.822813 -346.843479) (xy 276.868616 -346.772207) (xy 276.920987 -346.705611)
			(xy 276.979452 -346.644296) (xy 277.04348 -346.588815) (xy 277.112492 -346.539672) (xy 277.185862 -346.497312)
			(xy 277.262927 -346.462117) (xy 277.342989 -346.434408) (xy 277.425322 -346.414434) (xy 277.509181 -346.402377)
			(xy 277.593806 -346.398346) (xy 277.678431 -346.402377) (xy 277.76229 -346.414434) (xy 277.844623 -346.434408)
			(xy 277.924685 -346.462117) (xy 278.00175 -346.497312) (xy 278.07512 -346.539672) (xy 278.144132 -346.588815)
			(xy 278.20816 -346.644296) (xy 278.266625 -346.705611) (xy 278.318996 -346.772207) (xy 278.364799 -346.843479)
			(xy 278.403621 -346.918782) (xy 278.435109 -346.997434) (xy 278.458977 -347.078724) (xy 278.475011 -347.161914)
			(xy 278.483064 -347.246251) (xy 278.483568 -347.288612) (xy 278.482998 -347.333381) (xy 278.47399 -347.422466)
			(xy 278.456088 -347.510198) (xy 278.42947 -347.595689) (xy 278.412448 -347.6371) (xy 278.408812 -347.646665)
			(xy 278.408686 -347.667111) (xy 278.412194 -347.676724) (xy 278.426408 -347.711074) (xy 278.449728 -347.781668)
			(xy 278.467082 -347.85396) (xy 278.478348 -347.927447) (xy 278.481282 -347.964506) (xy 278.482267 -347.973327)
			(xy 278.489457 -347.989544) (xy 278.501708 -348.002373) (xy 278.509476 -348.00667) (xy 278.600662 -348.051628)
			(xy 278.62784 -348.049596) (xy 278.639016 -348.04223) (xy 278.675581 -348.018458) (xy 278.752524 -347.977387)
			(xy 278.833117 -347.944041) (xy 278.916586 -347.91874) (xy 279.00213 -347.901729) (xy 279.088929 -347.893169)
			(xy 279.132538 -347.892624) (xy 279.133046 -347.892624) (xy 279.174153 -347.893069) (xy 279.256016 -347.900657)
			(xy 279.336831 -347.915765) (xy 279.415907 -347.938263) (xy 279.49257 -347.96796) (xy 279.566167 -348.004602)
			(xy 279.63607 -348.047877) (xy 279.701683 -348.097416) (xy 279.762447 -348.152796) (xy 279.817842 -348.213546)
			(xy 279.867398 -348.279147) (xy 279.91069 -348.349039) (xy 279.947351 -348.422627) (xy 279.977067 -348.499283)
			(xy 279.999585 -348.578353) (xy 280.014712 -348.659164) (xy 280.018945 -348.7047) (xy 283.512244 -348.7047)
			(xy 283.516234 -348.620942) (xy 283.528168 -348.537942) (xy 283.547937 -348.456452) (xy 283.575362 -348.377211)
			(xy 283.610196 -348.300935) (xy 283.652122 -348.228316) (xy 283.700761 -348.16001) (xy 283.755673 -348.096638)
			(xy 283.81636 -348.038772) (xy 283.882273 -347.986937) (xy 283.952814 -347.941602) (xy 284.027346 -347.903177)
			(xy 284.105192 -347.872011) (xy 284.185648 -347.848386) (xy 284.267986 -347.832515) (xy 284.351459 -347.824543)
			(xy 284.393386 -347.824044) (xy 284.394402 -347.824044) (xy 284.431459 -347.824452) (xy 284.505308 -347.830716)
			(xy 284.57837 -347.843157) (xy 284.65013 -347.861689) (xy 284.685232 -347.873574) (xy 284.693429 -347.876088)
			(xy 284.710563 -347.876088) (xy 284.71876 -347.873574) (xy 284.756938 -347.860634) (xy 284.835124 -347.840982)
			(xy 284.91478 -347.828562) (xy 284.95498 -347.825568) (xy 284.965838 -347.82436) (xy 284.985096 -347.814096)
			(xy 284.99831 -347.79673) (xy 285.001208 -347.786198) (xy 285.010486 -347.747118) (xy 285.035162 -347.670674)
			(xy 285.050484 -347.633544) (xy 285.054028 -347.623948) (xy 285.05404 -347.603511) (xy 285.050484 -347.59392)
			(xy 285.033454 -347.552511) (xy 285.006819 -347.467023) (xy 284.988912 -347.379291) (xy 284.979917 -347.290203)
			(xy 284.979364 -347.245432) (xy 284.979868 -347.203071) (xy 284.987921 -347.118734) (xy 285.003955 -347.035544)
			(xy 285.027823 -346.954254) (xy 285.059311 -346.875602) (xy 285.098133 -346.800299) (xy 285.143936 -346.729027)
			(xy 285.196307 -346.662431) (xy 285.254772 -346.601116) (xy 285.3188 -346.545635) (xy 285.387812 -346.496492)
			(xy 285.461182 -346.454132) (xy 285.538247 -346.418937) (xy 285.618309 -346.391228) (xy 285.700642 -346.371254)
			(xy 285.784501 -346.359197) (xy 285.869126 -346.355166) (xy 285.953751 -346.359197) (xy 286.03761 -346.371254)
			(xy 286.119943 -346.391228) (xy 286.200005 -346.418937) (xy 286.27707 -346.454132) (xy 286.35044 -346.496492)
			(xy 286.419452 -346.545635) (xy 286.48348 -346.601116) (xy 286.541945 -346.662431) (xy 286.594316 -346.729027)
			(xy 286.640119 -346.800299) (xy 286.678941 -346.875602) (xy 286.710429 -346.954254) (xy 286.734297 -347.035544)
			(xy 286.750331 -347.118734) (xy 286.758384 -347.203071) (xy 286.758888 -347.245432) (xy 286.758323 -347.290202)
			(xy 286.749314 -347.379287) (xy 286.73141 -347.467018) (xy 286.704791 -347.552509) (xy 286.687768 -347.59392)
			(xy 286.684185 -347.603505) (xy 286.684197 -347.623953) (xy 286.687768 -347.633544) (xy 286.703871 -347.672618)
			(xy 286.72945 -347.753174) (xy 286.747275 -347.835792) (xy 286.757183 -347.919728) (xy 286.758634 -347.961966)
			(xy 286.758888 -347.975936) (xy 286.77362 -347.999558) (xy 286.86506 -348.047056) (xy 286.873276 -348.050887)
			(xy 286.891249 -348.053129) (xy 286.908879 -348.048973) (xy 286.916622 -348.044262) (xy 286.916876 -348.044008)
			(xy 286.95358 -348.019938) (xy 287.030887 -347.978361) (xy 287.111915 -347.944605) (xy 287.195876 -347.918998)
			(xy 287.281951 -347.901791) (xy 287.369303 -347.893149) (xy 287.413192 -347.892624) (xy 287.413446 -347.892624)
			(xy 287.454553 -347.893069) (xy 287.536416 -347.900657) (xy 287.617231 -347.915765) (xy 287.696307 -347.938263)
			(xy 287.77297 -347.96796) (xy 287.846567 -348.004602) (xy 287.91647 -348.047877) (xy 287.982083 -348.097416)
			(xy 288.042847 -348.152796) (xy 288.098242 -348.213546) (xy 288.147798 -348.279147) (xy 288.19109 -348.349039)
			(xy 288.227751 -348.422627) (xy 288.257467 -348.499283) (xy 288.279985 -348.578353) (xy 288.295112 -348.659164)
			(xy 288.299345 -348.7047) (xy 291.818044 -348.7047) (xy 291.822034 -348.620942) (xy 291.833968 -348.537942)
			(xy 291.853737 -348.456452) (xy 291.881162 -348.377211) (xy 291.915996 -348.300935) (xy 291.957922 -348.228316)
			(xy 292.006561 -348.16001) (xy 292.061473 -348.096638) (xy 292.12216 -348.038772) (xy 292.188073 -347.986937)
			(xy 292.258614 -347.941602) (xy 292.333146 -347.903177) (xy 292.410992 -347.872011) (xy 292.491448 -347.848386)
			(xy 292.573786 -347.832515) (xy 292.657259 -347.824543) (xy 292.699186 -347.824044) (xy 292.700202 -347.824044)
			(xy 292.737259 -347.824452) (xy 292.811108 -347.830716) (xy 292.88417 -347.843157) (xy 292.95593 -347.861689)
			(xy 292.991032 -347.873574) (xy 292.999229 -347.876088) (xy 293.016363 -347.876088) (xy 293.02456 -347.873574)
			(xy 293.057737 -347.862322) (xy 293.125493 -347.844496) (xy 293.194454 -347.832123) (xy 293.229284 -347.828362)
			(xy 293.240044 -347.82673) (xy 293.258819 -347.815766) (xy 293.271409 -347.798041) (xy 293.273988 -347.787468)
			(xy 293.28351 -347.742121) (xy 293.310744 -347.653548) (xy 293.328344 -347.610684) (xy 293.331924 -347.601098)
			(xy 293.331914 -347.580651) (xy 293.328344 -347.57106) (xy 293.311293 -347.529659) (xy 293.284663 -347.444168)
			(xy 293.266763 -347.356433) (xy 293.257774 -347.267343) (xy 293.257224 -347.222572) (xy 293.257728 -347.180211)
			(xy 293.265781 -347.095874) (xy 293.281815 -347.012684) (xy 293.305683 -346.931394) (xy 293.337171 -346.852742)
			(xy 293.375993 -346.777439) (xy 293.421796 -346.706167) (xy 293.474167 -346.639571) (xy 293.532632 -346.578256)
			(xy 293.59666 -346.522775) (xy 293.665672 -346.473632) (xy 293.739042 -346.431272) (xy 293.816107 -346.396077)
			(xy 293.896169 -346.368368) (xy 293.978502 -346.348394) (xy 294.062361 -346.336337) (xy 294.146986 -346.332306)
			(xy 294.231611 -346.336337) (xy 294.31547 -346.348394) (xy 294.397803 -346.368368) (xy 294.477865 -346.396077)
			(xy 294.55493 -346.431272) (xy 294.6283 -346.473632) (xy 294.697312 -346.522775) (xy 294.76134 -346.578256)
			(xy 294.819805 -346.639571) (xy 294.872176 -346.706167) (xy 294.917979 -346.777439) (xy 294.956801 -346.852742)
			(xy 294.988289 -346.931394) (xy 295.012157 -347.012684) (xy 295.028191 -347.095874) (xy 295.036244 -347.180211)
			(xy 295.036748 -347.222572) (xy 295.036192 -347.267342) (xy 295.027179 -347.356427) (xy 295.009272 -347.444158)
			(xy 294.982652 -347.529649) (xy 294.965628 -347.57106) (xy 294.962081 -347.580656) (xy 294.96207 -347.601093)
			(xy 294.965628 -347.610684) (xy 294.982659 -347.652092) (xy 295.009295 -347.73758) (xy 295.0272 -347.825313)
			(xy 295.036195 -347.914401) (xy 295.036748 -347.959172) (xy 295.036494 -347.977206) (xy 295.03624 -347.991684)
			(xy 295.050718 -348.016576) (xy 295.157144 -348.071948) (xy 295.185846 -348.069916) (xy 295.19753 -348.061534)
			(xy 295.230035 -348.038582) (xy 295.298406 -347.997866) (xy 295.370142 -347.963421) (xy 295.444669 -347.935524)
			(xy 295.521391 -347.914398) (xy 295.599693 -347.900211) (xy 295.67895 -347.893078) (xy 295.718738 -347.892624)
			(xy 295.719246 -347.892624) (xy 295.760353 -347.893069) (xy 295.842216 -347.900657) (xy 295.923031 -347.915765)
			(xy 296.002107 -347.938263) (xy 296.07877 -347.96796) (xy 296.152367 -348.004602) (xy 296.22227 -348.047877)
			(xy 296.287883 -348.097416) (xy 296.348647 -348.152796) (xy 296.404042 -348.213546) (xy 296.453598 -348.279147)
			(xy 296.49689 -348.349039) (xy 296.533551 -348.422627) (xy 296.563267 -348.499283) (xy 296.585785 -348.578353)
			(xy 296.600912 -348.659164) (xy 296.605145 -348.7047) (xy 300.174644 -348.7047) (xy 300.178634 -348.620942)
			(xy 300.190568 -348.537942) (xy 300.210337 -348.456452) (xy 300.237762 -348.377211) (xy 300.272596 -348.300935)
			(xy 300.314522 -348.228316) (xy 300.363161 -348.16001) (xy 300.418073 -348.096638) (xy 300.47876 -348.038772)
			(xy 300.544673 -347.986937) (xy 300.615214 -347.941602) (xy 300.689746 -347.903177) (xy 300.767592 -347.872011)
			(xy 300.848048 -347.848386) (xy 300.930386 -347.832515) (xy 301.013859 -347.824543) (xy 301.055786 -347.824044)
			(xy 301.056802 -347.824044) (xy 301.093859 -347.824452) (xy 301.167708 -347.830716) (xy 301.24077 -347.843157)
			(xy 301.31253 -347.861689) (xy 301.347632 -347.873574) (xy 301.355829 -347.876088) (xy 301.372963 -347.876088)
			(xy 301.38116 -347.873574) (xy 301.419296 -347.860641) (xy 301.497398 -347.840993) (xy 301.576968 -347.828568)
			(xy 301.617126 -347.825568) (xy 301.627844 -347.824451) (xy 301.646914 -347.814446) (xy 301.660249 -347.797535)
			(xy 301.663354 -347.787214) (xy 301.672203 -347.75314) (xy 301.694583 -347.686387) (xy 301.708058 -347.653864)
			(xy 301.711569 -347.644255) (xy 301.711421 -347.623811) (xy 301.707804 -347.61424) (xy 301.690776 -347.57283)
			(xy 301.66414 -347.487343) (xy 301.646234 -347.39961) (xy 301.637237 -347.310523) (xy 301.636684 -347.265752)
			(xy 301.637188 -347.223391) (xy 301.645241 -347.139054) (xy 301.661275 -347.055864) (xy 301.685143 -346.974574)
			(xy 301.716631 -346.895922) (xy 301.755453 -346.820619) (xy 301.801256 -346.749347) (xy 301.853627 -346.682751)
			(xy 301.912092 -346.621436) (xy 301.97612 -346.565955) (xy 302.045132 -346.516812) (xy 302.118502 -346.474452)
			(xy 302.195567 -346.439257) (xy 302.275629 -346.411548) (xy 302.357962 -346.391574) (xy 302.441821 -346.379517)
			(xy 302.526446 -346.375486) (xy 302.611071 -346.379517) (xy 302.69493 -346.391574) (xy 302.777263 -346.411548)
			(xy 302.857325 -346.439257) (xy 302.93439 -346.474452) (xy 303.00776 -346.516812) (xy 303.076772 -346.565955)
			(xy 303.1408 -346.621436) (xy 303.199265 -346.682751) (xy 303.251636 -346.749347) (xy 303.297439 -346.820619)
			(xy 303.336261 -346.895922) (xy 303.367749 -346.974574) (xy 303.391617 -347.055864) (xy 303.407651 -347.139054)
			(xy 303.415704 -347.223391) (xy 303.416208 -347.265752) (xy 303.415649 -347.310522) (xy 303.406637 -347.399607)
			(xy 303.388731 -347.487338) (xy 303.362111 -347.572829) (xy 303.345088 -347.61424) (xy 303.341549 -347.623838)
			(xy 303.341532 -347.644274) (xy 303.345088 -347.653864) (xy 303.36051 -347.691224) (xy 303.385289 -347.768163)
			(xy 303.402976 -347.847034) (xy 303.413426 -347.927187) (xy 303.415446 -347.967554) (xy 303.415954 -347.981524)
			(xy 303.430686 -348.004638) (xy 303.535334 -348.057216) (xy 303.562766 -348.055184) (xy 303.574196 -348.04731)
			(xy 303.611146 -348.022772) (xy 303.689046 -347.980345) (xy 303.770779 -347.945874) (xy 303.855535 -347.919702)
			(xy 303.942473 -347.902087) (xy 304.030732 -347.893205) (xy 304.075084 -347.892624) (xy 304.075846 -347.892624)
			(xy 304.116953 -347.893069) (xy 304.198816 -347.900657) (xy 304.279631 -347.915765) (xy 304.358707 -347.938263)
			(xy 304.43537 -347.96796) (xy 304.508967 -348.004602) (xy 304.57887 -348.047877) (xy 304.644483 -348.097416)
			(xy 304.705247 -348.152796) (xy 304.760642 -348.213546) (xy 304.810198 -348.279147) (xy 304.85349 -348.349039)
			(xy 304.890151 -348.422627) (xy 304.919867 -348.499283) (xy 304.942385 -348.578353) (xy 304.957512 -348.659164)
			(xy 304.961745 -348.7047) (xy 308.505844 -348.7047) (xy 308.509834 -348.620942) (xy 308.521768 -348.537942)
			(xy 308.541537 -348.456452) (xy 308.568962 -348.377211) (xy 308.603796 -348.300935) (xy 308.645722 -348.228316)
			(xy 308.694361 -348.16001) (xy 308.749273 -348.096638) (xy 308.80996 -348.038772) (xy 308.875873 -347.986937)
			(xy 308.946414 -347.941602) (xy 309.020946 -347.903177) (xy 309.098792 -347.872011) (xy 309.179248 -347.848386)
			(xy 309.261586 -347.832515) (xy 309.345059 -347.824543) (xy 309.386986 -347.824044) (xy 309.388002 -347.824044)
			(xy 309.425059 -347.824452) (xy 309.498908 -347.830716) (xy 309.57197 -347.843157) (xy 309.64373 -347.861689)
			(xy 309.678832 -347.873574) (xy 309.687029 -347.876088) (xy 309.704163 -347.876088) (xy 309.71236 -347.873574)
			(xy 309.752087 -347.860214) (xy 309.833476 -347.84017) (xy 309.916402 -347.827952) (xy 309.958232 -347.825314)
			(xy 309.969008 -347.824123) (xy 309.988202 -347.814097) (xy 310.001607 -347.79709) (xy 310.004714 -347.786706)
			(xy 310.013576 -347.75276) (xy 310.035956 -347.686262) (xy 310.049418 -347.653864) (xy 310.052931 -347.644255)
			(xy 310.052783 -347.623811) (xy 310.049164 -347.61424) (xy 310.03214 -347.572829) (xy 310.005503 -347.487342)
			(xy 309.987595 -347.39961) (xy 309.978598 -347.310522) (xy 309.978044 -347.265752) (xy 309.978548 -347.223391)
			(xy 309.986601 -347.139054) (xy 310.002635 -347.055864) (xy 310.026503 -346.974574) (xy 310.057991 -346.895922)
			(xy 310.096813 -346.820619) (xy 310.142616 -346.749347) (xy 310.194987 -346.682751) (xy 310.253452 -346.621436)
			(xy 310.31748 -346.565955) (xy 310.386492 -346.516812) (xy 310.459862 -346.474452) (xy 310.536927 -346.439257)
			(xy 310.616989 -346.411548) (xy 310.699322 -346.391574) (xy 310.783181 -346.379517) (xy 310.867806 -346.375486)
			(xy 310.952431 -346.379517) (xy 311.03629 -346.391574) (xy 311.118623 -346.411548) (xy 311.198685 -346.439257)
			(xy 311.27575 -346.474452) (xy 311.34912 -346.516812) (xy 311.418132 -346.565955) (xy 311.48216 -346.621436)
			(xy 311.540625 -346.682751) (xy 311.592996 -346.749347) (xy 311.638799 -346.820619) (xy 311.677621 -346.895922)
			(xy 311.709109 -346.974574) (xy 311.732977 -347.055864) (xy 311.749011 -347.139054) (xy 311.757064 -347.223391)
			(xy 311.757568 -347.265752) (xy 311.757012 -347.310522) (xy 311.748 -347.399607) (xy 311.730093 -347.487338)
			(xy 311.703472 -347.572829) (xy 311.686448 -347.61424) (xy 311.682911 -347.623839) (xy 311.682894 -347.644274)
			(xy 311.686448 -347.653864) (xy 311.701578 -347.690518) (xy 311.725997 -347.765967) (xy 311.743615 -347.843288)
			(xy 311.754293 -347.921869) (xy 311.756552 -347.961458) (xy 311.757251 -347.970429) (xy 311.764179 -347.987026)
			(xy 311.776392 -348.000229) (xy 311.784238 -348.004638) (xy 311.875678 -348.050866) (xy 311.902856 -348.049088)
			(xy 311.914286 -348.041468) (xy 311.950798 -348.017804) (xy 312.027605 -347.976914) (xy 312.10804 -347.943725)
			(xy 312.191333 -347.918554) (xy 312.276687 -347.901641) (xy 312.363285 -347.893148) (xy 312.406792 -347.892624)
			(xy 312.407046 -347.892624) (xy 312.448153 -347.893069) (xy 312.530016 -347.900657) (xy 312.610831 -347.915765)
			(xy 312.689907 -347.938263) (xy 312.76657 -347.96796) (xy 312.840167 -348.004602) (xy 312.91007 -348.047877)
			(xy 312.975683 -348.097416) (xy 313.036447 -348.152796) (xy 313.091842 -348.213546) (xy 313.141398 -348.279147)
			(xy 313.18469 -348.349039) (xy 313.221351 -348.422627) (xy 313.251067 -348.499283) (xy 313.273585 -348.578353)
			(xy 313.288712 -348.659164) (xy 313.296321 -348.741025) (xy 313.296808 -348.782132) (xy 313.296242 -348.826902)
			(xy 313.287233 -348.915987) (xy 313.269329 -349.003718) (xy 313.242711 -349.089209) (xy 313.225688 -349.13062)
			(xy 313.222104 -349.140205) (xy 313.222115 -349.160653) (xy 313.225688 -349.170244) (xy 313.242711 -349.211656)
			(xy 313.269347 -349.297143) (xy 313.287256 -349.384874) (xy 313.291976 -349.43161) (xy 326.552821 -349.43161)
			(xy 326.556826 -349.325861) (xy 326.568816 -349.220718) (xy 326.588725 -349.116783) (xy 326.616436 -349.014651)
			(xy 326.651793 -348.914907) (xy 326.694591 -348.818123) (xy 326.744587 -348.724853) (xy 326.801494 -348.635632)
			(xy 326.864985 -348.550969) (xy 326.934697 -348.471351) (xy 327.010231 -348.397233) (xy 327.091154 -348.32904)
			(xy 327.177003 -348.267162) (xy 327.267286 -348.211955) (xy 327.361485 -348.163733) (xy 327.459062 -348.122773)
			(xy 327.559457 -348.089311) (xy 327.662095 -348.063537) (xy 327.766388 -348.045599) (xy 327.871739 -348.0356)
			(xy 327.977545 -348.033597) (xy 328.083199 -348.039602) (xy 328.188096 -348.053581) (xy 328.291636 -348.075452)
			(xy 328.393225 -348.105092) (xy 328.492282 -348.14233) (xy 328.588239 -348.186952) (xy 328.680546 -348.238704)
			(xy 328.768675 -348.297289) (xy 328.852121 -348.362371) (xy 328.930405 -348.433577) (xy 329.00308 -348.5105)
			(xy 329.06973 -348.5927) (xy 329.129972 -348.679704) (xy 329.183461 -348.771015) (xy 329.229892 -348.86611)
			(xy 329.268997 -348.964444) (xy 329.300554 -349.065455) (xy 329.324381 -349.168562) (xy 329.340342 -349.273176)
			(xy 329.348346 -349.378698) (xy 329.348846 -349.43161) (xy 334.012801 -349.43161) (xy 334.016806 -349.325861)
			(xy 334.028796 -349.220718) (xy 334.048705 -349.116783) (xy 334.076416 -349.014651) (xy 334.111773 -348.914907)
			(xy 334.154571 -348.818123) (xy 334.204567 -348.724853) (xy 334.261474 -348.635632) (xy 334.324965 -348.550969)
			(xy 334.394677 -348.471351) (xy 334.470211 -348.397233) (xy 334.551134 -348.32904) (xy 334.636983 -348.267162)
			(xy 334.727266 -348.211955) (xy 334.821465 -348.163733) (xy 334.919042 -348.122773) (xy 335.019437 -348.089311)
			(xy 335.122075 -348.063537) (xy 335.226368 -348.045599) (xy 335.331719 -348.0356) (xy 335.437525 -348.033597)
			(xy 335.543179 -348.039602) (xy 335.648076 -348.053581) (xy 335.751616 -348.075452) (xy 335.853205 -348.105092)
			(xy 335.952262 -348.14233) (xy 336.048219 -348.186952) (xy 336.140526 -348.238704) (xy 336.228655 -348.297289)
			(xy 336.312101 -348.362371) (xy 336.390385 -348.433577) (xy 336.46306 -348.5105) (xy 336.52971 -348.5927)
			(xy 336.589952 -348.679704) (xy 336.643441 -348.771015) (xy 336.689872 -348.86611) (xy 336.728977 -348.964444)
			(xy 336.760534 -349.065455) (xy 336.784361 -349.168562) (xy 336.800322 -349.273176) (xy 336.808326 -349.378698)
			(xy 336.808826 -349.43161) (xy 336.808326 -349.484522) (xy 336.800322 -349.590044) (xy 336.784361 -349.694658)
			(xy 336.760534 -349.797765) (xy 336.728977 -349.898776) (xy 336.689872 -349.99711) (xy 336.643441 -350.092205)
			(xy 336.589952 -350.183516) (xy 336.52971 -350.27052) (xy 336.46306 -350.35272) (xy 336.390385 -350.429643)
			(xy 336.312101 -350.500849) (xy 336.228655 -350.565931) (xy 336.140526 -350.624516) (xy 336.048219 -350.676268)
			(xy 335.952262 -350.72089) (xy 335.853205 -350.758128) (xy 335.751616 -350.787768) (xy 335.648076 -350.809639)
			(xy 335.543179 -350.823618) (xy 335.437525 -350.829623) (xy 335.331719 -350.82762) (xy 335.226368 -350.817621)
			(xy 335.122075 -350.799683) (xy 335.019437 -350.773909) (xy 334.919042 -350.740447) (xy 334.821465 -350.699487)
			(xy 334.727266 -350.651265) (xy 334.636983 -350.596058) (xy 334.551134 -350.53418) (xy 334.470211 -350.465987)
			(xy 334.394677 -350.391869) (xy 334.324965 -350.312251) (xy 334.261474 -350.227588) (xy 334.204567 -350.138367)
			(xy 334.154571 -350.045097) (xy 334.111773 -349.948313) (xy 334.076416 -349.848569) (xy 334.048705 -349.746437)
			(xy 334.028796 -349.642502) (xy 334.016806 -349.537359) (xy 334.012801 -349.43161) (xy 329.348846 -349.43161)
			(xy 329.348346 -349.484522) (xy 329.340342 -349.590044) (xy 329.324381 -349.694658) (xy 329.300554 -349.797765)
			(xy 329.268997 -349.898776) (xy 329.229892 -349.99711) (xy 329.183461 -350.092205) (xy 329.129972 -350.183516)
			(xy 329.06973 -350.27052) (xy 329.00308 -350.35272) (xy 328.930405 -350.429643) (xy 328.852121 -350.500849)
			(xy 328.768675 -350.565931) (xy 328.680546 -350.624516) (xy 328.588239 -350.676268) (xy 328.492282 -350.72089)
			(xy 328.393225 -350.758128) (xy 328.291636 -350.787768) (xy 328.188096 -350.809639) (xy 328.083199 -350.823618)
			(xy 327.977545 -350.829623) (xy 327.871739 -350.82762) (xy 327.766388 -350.817621) (xy 327.662095 -350.799683)
			(xy 327.559457 -350.773909) (xy 327.459062 -350.740447) (xy 327.361485 -350.699487) (xy 327.267286 -350.651265)
			(xy 327.177003 -350.596058) (xy 327.091154 -350.53418) (xy 327.010231 -350.465987) (xy 326.934697 -350.391869)
			(xy 326.864985 -350.312251) (xy 326.801494 -350.227588) (xy 326.744587 -350.138367) (xy 326.694591 -350.045097)
			(xy 326.651793 -349.948313) (xy 326.616436 -349.848569) (xy 326.588725 -349.746437) (xy 326.568816 -349.642502)
			(xy 326.556826 -349.537359) (xy 326.552821 -349.43161) (xy 313.291976 -349.43161) (xy 313.296254 -349.473962)
			(xy 313.296808 -349.518732) (xy 313.296242 -349.563502) (xy 313.287233 -349.652587) (xy 313.269329 -349.740318)
			(xy 313.242711 -349.825809) (xy 313.225688 -349.86722) (xy 313.222104 -349.876805) (xy 313.222115 -349.897253)
			(xy 313.225688 -349.906844) (xy 313.242711 -349.948256) (xy 313.269347 -350.033743) (xy 313.287256 -350.121474)
			(xy 313.296254 -350.210562) (xy 313.296808 -350.255332) (xy 313.296378 -350.296443) (xy 313.288787 -350.378314)
			(xy 313.273674 -350.459136) (xy 313.251166 -350.538217) (xy 313.221457 -350.614885) (xy 313.184799 -350.688483)
			(xy 313.141506 -350.758385) (xy 313.091947 -350.823993) (xy 313.036545 -350.884747) (xy 312.975772 -350.94013)
			(xy 312.910148 -350.989668) (xy 312.840233 -351.032938) (xy 312.766623 -351.069572) (xy 312.689946 -351.099257)
			(xy 312.610857 -351.121739) (xy 312.530031 -351.136827) (xy 312.448157 -351.144391) (xy 312.407046 -351.14484)
			(xy 312.365442 -351.14437) (xy 312.282594 -351.136637) (xy 312.200829 -351.121206) (xy 312.120862 -351.098211)
			(xy 312.043389 -351.067854) (xy 311.969088 -351.0304) (xy 311.93359 -351.008696) (xy 311.924458 -351.003521)
			(xy 311.903738 -351.00031) (xy 311.883461 -351.005649) (xy 311.874916 -351.011744) (xy 311.841266 -351.037664)
			(xy 311.769892 -351.083723) (xy 311.694453 -351.12277) (xy 311.615637 -351.15445) (xy 311.53416 -351.178473)
			(xy 311.450764 -351.194623) (xy 311.366208 -351.20275) (xy 311.323736 -351.20326) (xy 311.323482 -351.20326)
			(xy 311.282375 -351.202805) (xy 311.200511 -351.195219) (xy 311.119697 -351.180113) (xy 311.04062 -351.157617)
			(xy 310.963956 -351.127921) (xy 310.890359 -351.09128) (xy 310.820455 -351.048006) (xy 310.754841 -350.998468)
			(xy 310.694077 -350.943088) (xy 310.638682 -350.882339) (xy 310.589126 -350.816738) (xy 310.545833 -350.746846)
			(xy 310.509173 -350.673258) (xy 310.479458 -350.596602) (xy 310.456941 -350.517531) (xy 310.441814 -350.43672)
			(xy 310.434206 -350.354859) (xy 310.43372 -350.313752) (xy 310.434279 -350.268982) (xy 310.44329 -350.179897)
			(xy 310.461196 -350.092166) (xy 310.487816 -350.006675) (xy 310.50484 -349.965264) (xy 310.508432 -349.955681)
			(xy 310.508415 -349.935231) (xy 310.50484 -349.92564) (xy 310.487836 -349.884289) (xy 310.461225 -349.798927)
			(xy 310.443318 -349.711324) (xy 310.434296 -349.622367) (xy 310.43372 -349.57766) (xy 310.43372 -349.576644)
			(xy 310.433974 -349.565214) (xy 310.407495 -349.559269) (xy 310.35526 -349.544526) (xy 310.32958 -349.53575)
			(xy 310.321383 -349.533236) (xy 310.304249 -349.533236) (xy 310.296052 -349.53575) (xy 310.260836 -349.547697)
			(xy 310.188826 -349.566284) (xy 310.115503 -349.578724) (xy 310.041392 -349.584928) (xy 310.004206 -349.58528)
			(xy 309.967022 -349.584911) (xy 309.892914 -349.578689) (xy 309.819594 -349.566246) (xy 309.747583 -349.547672)
			(xy 309.71236 -349.53575) (xy 309.704163 -349.533236) (xy 309.687029 -349.533236) (xy 309.678832 -349.53575)
			(xy 309.64373 -349.547637) (xy 309.571974 -349.566187) (xy 309.498911 -349.578634) (xy 309.42506 -349.584887)
			(xy 309.388002 -349.58528) (xy 309.386986 -349.58528) (xy 309.345059 -349.584857) (xy 309.261586 -349.576885)
			(xy 309.179248 -349.561014) (xy 309.098792 -349.537389) (xy 309.020946 -349.506223) (xy 308.946414 -349.467798)
			(xy 308.875873 -349.422463) (xy 308.80996 -349.370628) (xy 308.749273 -349.312762) (xy 308.694361 -349.24939)
			(xy 308.645722 -349.181084) (xy 308.603796 -349.108465) (xy 308.568962 -349.032189) (xy 308.541537 -348.952948)
			(xy 308.521768 -348.871458) (xy 308.509834 -348.788458) (xy 308.505844 -348.7047) (xy 304.961745 -348.7047)
			(xy 304.965121 -348.741025) (xy 304.965608 -348.782132) (xy 304.965042 -348.826902) (xy 304.956033 -348.915987)
			(xy 304.938129 -349.003718) (xy 304.911511 -349.089209) (xy 304.894488 -349.13062) (xy 304.890904 -349.140205)
			(xy 304.890915 -349.160653) (xy 304.894488 -349.170244) (xy 304.911511 -349.211656) (xy 304.938147 -349.297143)
			(xy 304.956056 -349.384874) (xy 304.965054 -349.473962) (xy 304.965608 -349.518732) (xy 304.965042 -349.563502)
			(xy 304.956033 -349.652587) (xy 304.938129 -349.740318) (xy 304.911511 -349.825809) (xy 304.894488 -349.86722)
			(xy 304.890904 -349.876805) (xy 304.890915 -349.897253) (xy 304.894488 -349.906844) (xy 304.911511 -349.948256)
			(xy 304.938147 -350.033743) (xy 304.956056 -350.121474) (xy 304.965054 -350.210562) (xy 304.965608 -350.255332)
			(xy 304.965178 -350.296443) (xy 304.957587 -350.378314) (xy 304.942474 -350.459136) (xy 304.919966 -350.538217)
			(xy 304.890257 -350.614885) (xy 304.853599 -350.688483) (xy 304.810306 -350.758385) (xy 304.760747 -350.823993)
			(xy 304.705345 -350.884747) (xy 304.644572 -350.94013) (xy 304.578948 -350.989668) (xy 304.509033 -351.032938)
			(xy 304.435423 -351.069572) (xy 304.358746 -351.099257) (xy 304.279657 -351.121739) (xy 304.198831 -351.136827)
			(xy 304.116957 -351.144391) (xy 304.075846 -351.14484) (xy 304.034242 -351.14437) (xy 303.951394 -351.136637)
			(xy 303.869629 -351.121206) (xy 303.789662 -351.098211) (xy 303.712189 -351.067854) (xy 303.637888 -351.0304)
			(xy 303.60239 -351.008696) (xy 303.593258 -351.003521) (xy 303.572538 -351.00031) (xy 303.552261 -351.005649)
			(xy 303.543716 -351.011744) (xy 303.510066 -351.037664) (xy 303.438692 -351.083723) (xy 303.363253 -351.12277)
			(xy 303.284437 -351.15445) (xy 303.20296 -351.178473) (xy 303.119564 -351.194623) (xy 303.035008 -351.20275)
			(xy 302.992536 -351.20326) (xy 302.992282 -351.20326) (xy 302.951175 -351.202805) (xy 302.869311 -351.195219)
			(xy 302.788497 -351.180113) (xy 302.70942 -351.157617) (xy 302.632756 -351.127921) (xy 302.559159 -351.09128)
			(xy 302.489255 -351.048006) (xy 302.423641 -350.998468) (xy 302.362877 -350.943088) (xy 302.307482 -350.882339)
			(xy 302.257926 -350.816738) (xy 302.214633 -350.746846) (xy 302.177973 -350.673258) (xy 302.148258 -350.596602)
			(xy 302.125741 -350.517531) (xy 302.110614 -350.43672) (xy 302.103006 -350.354859) (xy 302.10252 -350.313752)
			(xy 302.103079 -350.268982) (xy 302.11209 -350.179897) (xy 302.129996 -350.092166) (xy 302.156616 -350.006675)
			(xy 302.17364 -349.965264) (xy 302.177232 -349.955681) (xy 302.177215 -349.935231) (xy 302.17364 -349.92564)
			(xy 302.156636 -349.884289) (xy 302.130025 -349.798927) (xy 302.112118 -349.711324) (xy 302.103096 -349.622367)
			(xy 302.10252 -349.57766) (xy 302.10252 -349.576644) (xy 302.102774 -349.565214) (xy 302.076295 -349.559269)
			(xy 302.02406 -349.544526) (xy 301.99838 -349.53575) (xy 301.990183 -349.533236) (xy 301.973049 -349.533236)
			(xy 301.964852 -349.53575) (xy 301.929636 -349.547697) (xy 301.857626 -349.566284) (xy 301.784303 -349.578724)
			(xy 301.710192 -349.584928) (xy 301.673006 -349.58528) (xy 301.635822 -349.584911) (xy 301.561714 -349.578689)
			(xy 301.488394 -349.566246) (xy 301.416383 -349.547672) (xy 301.38116 -349.53575) (xy 301.372963 -349.533236)
			(xy 301.355829 -349.533236) (xy 301.347632 -349.53575) (xy 301.31253 -349.547637) (xy 301.240774 -349.566187)
			(xy 301.167711 -349.578634) (xy 301.09386 -349.584887) (xy 301.056802 -349.58528) (xy 301.055786 -349.58528)
			(xy 301.013859 -349.584857) (xy 300.930386 -349.576885) (xy 300.848048 -349.561014) (xy 300.767592 -349.537389)
			(xy 300.689746 -349.506223) (xy 300.615214 -349.467798) (xy 300.544673 -349.422463) (xy 300.47876 -349.370628)
			(xy 300.418073 -349.312762) (xy 300.363161 -349.24939) (xy 300.314522 -349.181084) (xy 300.272596 -349.108465)
			(xy 300.237762 -349.032189) (xy 300.210337 -348.952948) (xy 300.190568 -348.871458) (xy 300.178634 -348.788458)
			(xy 300.174644 -348.7047) (xy 296.605145 -348.7047) (xy 296.608521 -348.741025) (xy 296.609008 -348.782132)
			(xy 296.608442 -348.826902) (xy 296.599433 -348.915987) (xy 296.581529 -349.003718) (xy 296.554911 -349.089209)
			(xy 296.537888 -349.13062) (xy 296.534304 -349.140205) (xy 296.534315 -349.160653) (xy 296.537888 -349.170244)
			(xy 296.554911 -349.211656) (xy 296.581547 -349.297143) (xy 296.599456 -349.384874) (xy 296.608454 -349.473962)
			(xy 296.609008 -349.518732) (xy 296.608442 -349.563502) (xy 296.599433 -349.652587) (xy 296.581529 -349.740318)
			(xy 296.554911 -349.825809) (xy 296.537888 -349.86722) (xy 296.534304 -349.876805) (xy 296.534315 -349.897253)
			(xy 296.537888 -349.906844) (xy 296.554911 -349.948256) (xy 296.581547 -350.033743) (xy 296.599456 -350.121474)
			(xy 296.608454 -350.210562) (xy 296.609008 -350.255332) (xy 296.608578 -350.296443) (xy 296.600987 -350.378314)
			(xy 296.585874 -350.459136) (xy 296.563366 -350.538217) (xy 296.533657 -350.614885) (xy 296.496999 -350.688483)
			(xy 296.453706 -350.758385) (xy 296.404147 -350.823993) (xy 296.348745 -350.884747) (xy 296.287972 -350.94013)
			(xy 296.222348 -350.989668) (xy 296.152433 -351.032938) (xy 296.078823 -351.069572) (xy 296.002146 -351.099257)
			(xy 295.923057 -351.121739) (xy 295.842231 -351.136827) (xy 295.760357 -351.144391) (xy 295.719246 -351.14484)
			(xy 295.677642 -351.14437) (xy 295.594794 -351.136637) (xy 295.513029 -351.121206) (xy 295.433062 -351.098211)
			(xy 295.355589 -351.067854) (xy 295.281288 -351.0304) (xy 295.24579 -351.008696) (xy 295.236658 -351.003521)
			(xy 295.215938 -351.00031) (xy 295.195661 -351.005649) (xy 295.187116 -351.011744) (xy 295.153466 -351.037664)
			(xy 295.082092 -351.083723) (xy 295.006653 -351.12277) (xy 294.927837 -351.15445) (xy 294.84636 -351.178473)
			(xy 294.762964 -351.194623) (xy 294.678408 -351.20275) (xy 294.635936 -351.20326) (xy 294.635682 -351.20326)
			(xy 294.594575 -351.202805) (xy 294.512711 -351.195219) (xy 294.431897 -351.180113) (xy 294.35282 -351.157617)
			(xy 294.276156 -351.127921) (xy 294.202559 -351.09128) (xy 294.132655 -351.048006) (xy 294.067041 -350.998468)
			(xy 294.006277 -350.943088) (xy 293.950882 -350.882339) (xy 293.901326 -350.816738) (xy 293.858033 -350.746846)
			(xy 293.821373 -350.673258) (xy 293.791658 -350.596602) (xy 293.769141 -350.517531) (xy 293.754014 -350.43672)
			(xy 293.746406 -350.354859) (xy 293.74592 -350.313752) (xy 293.746479 -350.268982) (xy 293.75549 -350.179897)
			(xy 293.773396 -350.092166) (xy 293.800016 -350.006675) (xy 293.81704 -349.965264) (xy 293.820632 -349.955681)
			(xy 293.820615 -349.935231) (xy 293.81704 -349.92564) (xy 293.800036 -349.884289) (xy 293.773425 -349.798927)
			(xy 293.755518 -349.711324) (xy 293.746496 -349.622367) (xy 293.74592 -349.57766) (xy 293.74592 -349.576644)
			(xy 293.746174 -349.565214) (xy 293.719695 -349.559269) (xy 293.66746 -349.544526) (xy 293.64178 -349.53575)
			(xy 293.633583 -349.533236) (xy 293.616449 -349.533236) (xy 293.608252 -349.53575) (xy 293.573036 -349.547697)
			(xy 293.501026 -349.566284) (xy 293.427703 -349.578724) (xy 293.353592 -349.584928) (xy 293.316406 -349.58528)
			(xy 293.279222 -349.584911) (xy 293.205114 -349.578689) (xy 293.131794 -349.566246) (xy 293.059783 -349.547672)
			(xy 293.02456 -349.53575) (xy 293.016363 -349.533236) (xy 292.999229 -349.533236) (xy 292.991032 -349.53575)
			(xy 292.95593 -349.547637) (xy 292.884174 -349.566187) (xy 292.811111 -349.578634) (xy 292.73726 -349.584887)
			(xy 292.700202 -349.58528) (xy 292.699186 -349.58528) (xy 292.657259 -349.584857) (xy 292.573786 -349.576885)
			(xy 292.491448 -349.561014) (xy 292.410992 -349.537389) (xy 292.333146 -349.506223) (xy 292.258614 -349.467798)
			(xy 292.188073 -349.422463) (xy 292.12216 -349.370628) (xy 292.061473 -349.312762) (xy 292.006561 -349.24939)
			(xy 291.957922 -349.181084) (xy 291.915996 -349.108465) (xy 291.881162 -349.032189) (xy 291.853737 -348.952948)
			(xy 291.833968 -348.871458) (xy 291.822034 -348.788458) (xy 291.818044 -348.7047) (xy 288.299345 -348.7047)
			(xy 288.302721 -348.741025) (xy 288.303208 -348.782132) (xy 288.302642 -348.826902) (xy 288.293633 -348.915987)
			(xy 288.275729 -349.003718) (xy 288.249111 -349.089209) (xy 288.232088 -349.13062) (xy 288.228504 -349.140205)
			(xy 288.228515 -349.160653) (xy 288.232088 -349.170244) (xy 288.249111 -349.211656) (xy 288.275747 -349.297143)
			(xy 288.293656 -349.384874) (xy 288.302654 -349.473962) (xy 288.303208 -349.518732) (xy 288.302642 -349.563502)
			(xy 288.293633 -349.652587) (xy 288.275729 -349.740318) (xy 288.249111 -349.825809) (xy 288.232088 -349.86722)
			(xy 288.228504 -349.876805) (xy 288.228515 -349.897253) (xy 288.232088 -349.906844) (xy 288.249111 -349.948256)
			(xy 288.275747 -350.033743) (xy 288.293656 -350.121474) (xy 288.302654 -350.210562) (xy 288.303208 -350.255332)
			(xy 288.302778 -350.296443) (xy 288.295187 -350.378314) (xy 288.280074 -350.459136) (xy 288.257566 -350.538217)
			(xy 288.227857 -350.614885) (xy 288.191199 -350.688483) (xy 288.147906 -350.758385) (xy 288.098347 -350.823993)
			(xy 288.042945 -350.884747) (xy 287.982172 -350.94013) (xy 287.916548 -350.989668) (xy 287.846633 -351.032938)
			(xy 287.773023 -351.069572) (xy 287.696346 -351.099257) (xy 287.617257 -351.121739) (xy 287.536431 -351.136827)
			(xy 287.454557 -351.144391) (xy 287.413446 -351.14484) (xy 287.371842 -351.14437) (xy 287.288994 -351.136637)
			(xy 287.207229 -351.121206) (xy 287.127262 -351.098211) (xy 287.049789 -351.067854) (xy 286.975488 -351.0304)
			(xy 286.93999 -351.008696) (xy 286.930858 -351.003521) (xy 286.910138 -351.00031) (xy 286.889861 -351.005649)
			(xy 286.881316 -351.011744) (xy 286.847666 -351.037664) (xy 286.776292 -351.083723) (xy 286.700853 -351.12277)
			(xy 286.622037 -351.15445) (xy 286.54056 -351.178473) (xy 286.457164 -351.194623) (xy 286.372608 -351.20275)
			(xy 286.330136 -351.20326) (xy 286.329882 -351.20326) (xy 286.288775 -351.202805) (xy 286.206911 -351.195219)
			(xy 286.126097 -351.180113) (xy 286.04702 -351.157617) (xy 285.970356 -351.127921) (xy 285.896759 -351.09128)
			(xy 285.826855 -351.048006) (xy 285.761241 -350.998468) (xy 285.700477 -350.943088) (xy 285.645082 -350.882339)
			(xy 285.595526 -350.816738) (xy 285.552233 -350.746846) (xy 285.515573 -350.673258) (xy 285.485858 -350.596602)
			(xy 285.463341 -350.517531) (xy 285.448214 -350.43672) (xy 285.440606 -350.354859) (xy 285.44012 -350.313752)
			(xy 285.440679 -350.268982) (xy 285.44969 -350.179897) (xy 285.467596 -350.092166) (xy 285.494216 -350.006675)
			(xy 285.51124 -349.965264) (xy 285.514832 -349.955681) (xy 285.514815 -349.935231) (xy 285.51124 -349.92564)
			(xy 285.494236 -349.884289) (xy 285.467625 -349.798927) (xy 285.449718 -349.711324) (xy 285.440696 -349.622367)
			(xy 285.44012 -349.57766) (xy 285.44012 -349.576644) (xy 285.440374 -349.565214) (xy 285.413895 -349.559269)
			(xy 285.36166 -349.544526) (xy 285.33598 -349.53575) (xy 285.327783 -349.533236) (xy 285.310649 -349.533236)
			(xy 285.302452 -349.53575) (xy 285.267236 -349.547697) (xy 285.195226 -349.566284) (xy 285.121903 -349.578724)
			(xy 285.047792 -349.584928) (xy 285.010606 -349.58528) (xy 284.973422 -349.584911) (xy 284.899314 -349.578689)
			(xy 284.825994 -349.566246) (xy 284.753983 -349.547672) (xy 284.71876 -349.53575) (xy 284.710563 -349.533236)
			(xy 284.693429 -349.533236) (xy 284.685232 -349.53575) (xy 284.65013 -349.547637) (xy 284.578374 -349.566187)
			(xy 284.505311 -349.578634) (xy 284.43146 -349.584887) (xy 284.394402 -349.58528) (xy 284.393386 -349.58528)
			(xy 284.351459 -349.584857) (xy 284.267986 -349.576885) (xy 284.185648 -349.561014) (xy 284.105192 -349.537389)
			(xy 284.027346 -349.506223) (xy 283.952814 -349.467798) (xy 283.882273 -349.422463) (xy 283.81636 -349.370628)
			(xy 283.755673 -349.312762) (xy 283.700761 -349.24939) (xy 283.652122 -349.181084) (xy 283.610196 -349.108465)
			(xy 283.575362 -349.032189) (xy 283.547937 -348.952948) (xy 283.528168 -348.871458) (xy 283.516234 -348.788458)
			(xy 283.512244 -348.7047) (xy 280.018945 -348.7047) (xy 280.022321 -348.741025) (xy 280.022808 -348.782132)
			(xy 280.022242 -348.826902) (xy 280.013233 -348.915987) (xy 279.995329 -349.003718) (xy 279.968711 -349.089209)
			(xy 279.951688 -349.13062) (xy 279.948104 -349.140205) (xy 279.948115 -349.160653) (xy 279.951688 -349.170244)
			(xy 279.968711 -349.211656) (xy 279.995347 -349.297143) (xy 280.013256 -349.384874) (xy 280.022254 -349.473962)
			(xy 280.022808 -349.518732) (xy 280.022242 -349.563502) (xy 280.013233 -349.652587) (xy 279.995329 -349.740318)
			(xy 279.968711 -349.825809) (xy 279.951688 -349.86722) (xy 279.948104 -349.876805) (xy 279.948115 -349.897253)
			(xy 279.951688 -349.906844) (xy 279.968711 -349.948256) (xy 279.995347 -350.033743) (xy 280.013256 -350.121474)
			(xy 280.022254 -350.210562) (xy 280.022808 -350.255332) (xy 280.022378 -350.296443) (xy 280.014787 -350.378314)
			(xy 279.999674 -350.459136) (xy 279.977166 -350.538217) (xy 279.947457 -350.614885) (xy 279.910799 -350.688483)
			(xy 279.867506 -350.758385) (xy 279.817947 -350.823993) (xy 279.762545 -350.884747) (xy 279.701772 -350.94013)
			(xy 279.636148 -350.989668) (xy 279.566233 -351.032938) (xy 279.492623 -351.069572) (xy 279.415946 -351.099257)
			(xy 279.336857 -351.121739) (xy 279.256031 -351.136827) (xy 279.174157 -351.144391) (xy 279.133046 -351.14484)
			(xy 279.091442 -351.14437) (xy 279.008594 -351.136637) (xy 278.926829 -351.121206) (xy 278.846862 -351.098211)
			(xy 278.769389 -351.067854) (xy 278.695088 -351.0304) (xy 278.65959 -351.008696) (xy 278.650458 -351.003521)
			(xy 278.629738 -351.00031) (xy 278.609461 -351.005649) (xy 278.600916 -351.011744) (xy 278.567266 -351.037664)
			(xy 278.495892 -351.083723) (xy 278.420453 -351.12277) (xy 278.341637 -351.15445) (xy 278.26016 -351.178473)
			(xy 278.176764 -351.194623) (xy 278.092208 -351.20275) (xy 278.049736 -351.20326) (xy 278.049482 -351.20326)
			(xy 278.008375 -351.202805) (xy 277.926511 -351.195219) (xy 277.845697 -351.180113) (xy 277.76662 -351.157617)
			(xy 277.689956 -351.127921) (xy 277.616359 -351.09128) (xy 277.546455 -351.048006) (xy 277.480841 -350.998468)
			(xy 277.420077 -350.943088) (xy 277.364682 -350.882339) (xy 277.315126 -350.816738) (xy 277.271833 -350.746846)
			(xy 277.235173 -350.673258) (xy 277.205458 -350.596602) (xy 277.182941 -350.517531) (xy 277.167814 -350.43672)
			(xy 277.160206 -350.354859) (xy 277.15972 -350.313752) (xy 277.160279 -350.268982) (xy 277.16929 -350.179897)
			(xy 277.187196 -350.092166) (xy 277.213816 -350.006675) (xy 277.23084 -349.965264) (xy 277.234432 -349.955681)
			(xy 277.234415 -349.935231) (xy 277.23084 -349.92564) (xy 277.213836 -349.884289) (xy 277.187225 -349.798927)
			(xy 277.169318 -349.711324) (xy 277.160296 -349.622367) (xy 277.15972 -349.57766) (xy 277.15972 -349.576644)
			(xy 277.159974 -349.565214) (xy 277.133495 -349.559269) (xy 277.08126 -349.544526) (xy 277.05558 -349.53575)
			(xy 277.047383 -349.533236) (xy 277.030249 -349.533236) (xy 277.022052 -349.53575) (xy 276.986836 -349.547697)
			(xy 276.914826 -349.566284) (xy 276.841503 -349.578724) (xy 276.767392 -349.584928) (xy 276.730206 -349.58528)
			(xy 276.693022 -349.584911) (xy 276.618914 -349.578689) (xy 276.545594 -349.566246) (xy 276.473583 -349.547672)
			(xy 276.43836 -349.53575) (xy 276.430163 -349.533236) (xy 276.413029 -349.533236) (xy 276.404832 -349.53575)
			(xy 276.36973 -349.547637) (xy 276.297974 -349.566187) (xy 276.224911 -349.578634) (xy 276.15106 -349.584887)
			(xy 276.114002 -349.58528) (xy 276.112986 -349.58528) (xy 276.071059 -349.584857) (xy 275.987586 -349.576885)
			(xy 275.905248 -349.561014) (xy 275.824792 -349.537389) (xy 275.746946 -349.506223) (xy 275.672414 -349.467798)
			(xy 275.601873 -349.422463) (xy 275.53596 -349.370628) (xy 275.475273 -349.312762) (xy 275.420361 -349.24939)
			(xy 275.371722 -349.181084) (xy 275.329796 -349.108465) (xy 275.294962 -349.032189) (xy 275.267537 -348.952948)
			(xy 275.247768 -348.871458) (xy 275.235834 -348.788458) (xy 275.231844 -348.7047) (xy 85.721282 -348.7047)
			(xy 85.724562 -348.719921) (xy 85.734552 -348.813881) (xy 85.73516 -348.861126) (xy 85.734613 -348.906766)
			(xy 85.725307 -348.997569) (xy 85.706754 -349.086942) (xy 85.693504 -349.13062) (xy 85.691044 -349.139629)
			(xy 85.692095 -349.15826) (xy 85.695536 -349.166942) (xy 85.714247 -349.210016) (xy 85.743525 -349.299254)
			(xy 85.763232 -349.391081) (xy 85.77315 -349.484473) (xy 85.773768 -349.531432) (xy 85.77323 -349.574377)
			(xy 85.764932 -349.659867) (xy 85.748446 -349.744161) (xy 85.723925 -349.826477) (xy 85.708236 -349.866458)
			(xy 85.704966 -349.875707) (xy 85.704968 -349.895308) (xy 85.708236 -349.904558) (xy 85.723933 -349.944537)
			(xy 85.748482 -350.026848) (xy 85.764973 -350.111143) (xy 85.773254 -350.196637) (xy 85.773768 -350.239584)
			(xy 85.773768 -350.239838) (xy 85.773264 -350.282199) (xy 85.765211 -350.366536) (xy 85.749177 -350.449726)
			(xy 85.725309 -350.531016) (xy 85.693821 -350.609668) (xy 85.654999 -350.684971) (xy 85.609196 -350.756243)
			(xy 85.556825 -350.822839) (xy 85.49836 -350.884154) (xy 85.434332 -350.939635) (xy 85.36532 -350.988778)
			(xy 85.29195 -351.031138) (xy 85.214885 -351.066333) (xy 85.134823 -351.094042) (xy 85.05249 -351.114016)
			(xy 84.968631 -351.126073) (xy 84.884006 -351.130105) (xy 84.799381 -351.126073) (xy 84.715522 -351.114016)
			(xy 84.633189 -351.094042) (xy 84.553127 -351.066333) (xy 84.476062 -351.031138) (xy 84.402692 -350.988778)
			(xy 84.33368 -350.939635) (xy 84.269652 -350.884154) (xy 84.211187 -350.822839) (xy 84.158816 -350.756243)
			(xy 84.113013 -350.684971) (xy 84.074191 -350.609668) (xy 84.042703 -350.531016) (xy 84.018835 -350.449726)
			(xy 84.002801 -350.366536) (xy 83.994748 -350.282199) (xy 83.994244 -350.239838) (xy 83.994244 -350.239584)
			(xy 83.994787 -350.196639) (xy 84.003083 -350.111149) (xy 84.019568 -350.026855) (xy 84.044088 -349.944539)
			(xy 84.059776 -349.904558) (xy 84.063037 -349.895306) (xy 84.06304 -349.875708) (xy 84.059776 -349.866458)
			(xy 84.044053 -349.826489) (xy 84.019511 -349.744174) (xy 84.003027 -349.659876) (xy 83.994754 -349.57438)
			(xy 83.994244 -349.531432) (xy 83.994855 -349.485787) (xy 84.004246 -349.394981) (xy 84.022872 -349.305612)
			(xy 84.036154 -349.261938) (xy 84.038586 -349.252923) (xy 84.037555 -349.234298) (xy 84.034122 -349.225616)
			(xy 84.015469 -349.182525) (xy 83.98626 -349.093282) (xy 83.966612 -349.001459) (xy 83.956742 -348.908077)
			(xy 83.956144 -348.861126) (xy 83.073245 -348.861126) (xy 83.073748 -348.89948) (xy 83.073141 -348.945125)
			(xy 83.063748 -349.035931) (xy 83.045121 -349.1253) (xy 83.031838 -349.168974) (xy 83.0294 -349.177987)
			(xy 83.030435 -349.196614) (xy 83.03387 -349.205296) (xy 83.052527 -349.248385) (xy 83.081735 -349.337629)
			(xy 83.101382 -349.429453) (xy 83.111251 -349.522835) (xy 83.111848 -349.569786) (xy 83.111412 -349.610119)
			(xy 83.104141 -349.690457) (xy 83.08963 -349.769807) (xy 83.067997 -349.847519) (xy 83.039422 -349.922954)
			(xy 83.022186 -349.959422) (xy 83.017653 -349.970011) (xy 83.017661 -349.993024) (xy 83.022186 -350.003618)
			(xy 83.039387 -350.040045) (xy 83.067929 -350.115383) (xy 83.089551 -350.19299) (xy 83.104075 -350.272234)
			(xy 83.111383 -350.352465) (xy 83.111848 -350.392746) (xy 83.111848 -350.393) (xy 83.111344 -350.435361)
			(xy 83.103291 -350.519698) (xy 83.087257 -350.602888) (xy 83.063389 -350.684178) (xy 83.031901 -350.76283)
			(xy 82.993079 -350.838133) (xy 82.947276 -350.909405) (xy 82.894905 -350.976001) (xy 82.83644 -351.037316)
			(xy 82.772412 -351.092797) (xy 82.7034 -351.14194) (xy 82.63003 -351.1843) (xy 82.552965 -351.219495)
			(xy 82.472903 -351.247204) (xy 82.39057 -351.267178) (xy 82.306711 -351.279235) (xy 82.222086 -351.283267)
			(xy 82.137461 -351.279235) (xy 82.053602 -351.267178) (xy 81.971269 -351.247204) (xy 81.891207 -351.219495)
			(xy 81.814142 -351.1843) (xy 81.740772 -351.14194) (xy 81.67176 -351.092797) (xy 81.607732 -351.037316)
			(xy 81.549267 -350.976001) (xy 81.496896 -350.909405) (xy 81.451093 -350.838133) (xy 81.412271 -350.76283)
			(xy 81.380783 -350.684178) (xy 81.356915 -350.602888) (xy 81.340881 -350.519698) (xy 81.332828 -350.435361)
			(xy 81.332324 -350.393) (xy 81.332778 -350.35266) (xy 81.340081 -350.272312) (xy 81.354637 -350.192956)
			(xy 81.376326 -350.115246) (xy 81.404968 -350.039822) (xy 81.42224 -350.003364) (xy 81.426812 -349.992711)
			(xy 81.426828 -349.969558) (xy 81.42224 -349.958914) (xy 81.405059 -349.922483) (xy 81.376548 -349.847143)
			(xy 81.35497 -349.769534) (xy 81.340501 -349.69029) (xy 81.33326 -349.610063) (xy 81.332832 -349.569786)
			(xy 81.333382 -349.524146) (xy 81.342687 -349.433343) (xy 81.361239 -349.34397) (xy 81.374488 -349.300292)
			(xy 81.376942 -349.291282) (xy 81.375896 -349.272652) (xy 81.372456 -349.26397) (xy 81.353748 -349.220894)
			(xy 81.32447 -349.131657) (xy 81.304762 -349.039831) (xy 81.294843 -348.946439) (xy 81.294224 -348.89948)
			(xy 66.467942 -348.89948) (xy 66.465784 -348.920813) (xy 66.447878 -349.008544) (xy 66.421259 -349.094035)
			(xy 66.404236 -349.135446) (xy 66.400697 -349.145044) (xy 66.400681 -349.16548) (xy 66.404236 -349.17507)
			(xy 66.421263 -349.21648) (xy 66.4479 -349.301967) (xy 66.465806 -349.3897) (xy 66.474803 -349.478787)
			(xy 66.475356 -349.523558) (xy 66.474795 -349.568328) (xy 66.465784 -349.657413) (xy 66.447878 -349.745144)
			(xy 66.421259 -349.830635) (xy 66.404236 -349.872046) (xy 66.400697 -349.881644) (xy 66.400681 -349.90208)
			(xy 66.404236 -349.91167) (xy 66.421263 -349.95308) (xy 66.4479 -350.038567) (xy 66.465806 -350.1263)
			(xy 66.474803 -350.215387) (xy 66.475356 -350.260158) (xy 66.474861 -350.301272) (xy 66.467278 -350.383151)
			(xy 66.452172 -350.46398) (xy 66.429672 -350.54307) (xy 66.39997 -350.619748) (xy 66.36332 -350.693357)
			(xy 66.320034 -350.76327) (xy 66.270482 -350.828891) (xy 66.215086 -350.88966) (xy 66.154319 -350.945059)
			(xy 66.0887 -350.994614) (xy 66.018788 -351.037902) (xy 65.94518 -351.074555) (xy 65.868505 -351.10426)
			(xy 65.789415 -351.126764) (xy 65.708586 -351.141873) (xy 65.626708 -351.14946) (xy 65.585594 -351.14992)
			(xy 65.543984 -351.149442) (xy 65.461127 -351.141665) (xy 65.379358 -351.12619) (xy 65.299391 -351.10315)
			(xy 65.221922 -351.072748) (xy 65.147629 -351.035248) (xy 65.112138 -351.013522) (xy 65.10303 -351.008297)
			(xy 65.082293 -351.005101) (xy 65.062008 -351.010462) (xy 65.053464 -351.01657) (xy 65.019831 -351.042555)
			(xy 64.948437 -351.08868) (xy 64.872967 -351.127782) (xy 64.79411 -351.159503) (xy 64.712585 -351.183553)
			(xy 64.629138 -351.199714) (xy 64.544529 -351.207838) (xy 64.50203 -351.20834) (xy 64.460915 -351.207873)
			(xy 64.379035 -351.200288) (xy 64.298205 -351.185181) (xy 64.219114 -351.162679) (xy 64.142436 -351.132976)
			(xy 64.068826 -351.096324) (xy 63.998912 -351.053036) (xy 63.93329 -351.003482) (xy 63.872521 -350.948084)
			(xy 63.817123 -350.887316) (xy 63.767568 -350.821695) (xy 63.72428 -350.751781) (xy 63.687628 -350.678172)
			(xy 63.657923 -350.601494) (xy 63.635421 -350.522403) (xy 63.620313 -350.441573) (xy 63.612727 -350.359693)
			(xy 63.612268 -350.318578) (xy 63.61284 -350.273809) (xy 63.621847 -350.184724) (xy 63.63975 -350.096993)
			(xy 63.666366 -350.011501) (xy 63.683388 -349.97009) (xy 63.686968 -349.960503) (xy 63.68696 -349.940056)
			(xy 63.683388 -349.930466) (xy 63.666363 -349.889123) (xy 63.639757 -349.803758) (xy 63.621856 -349.716153)
			(xy 63.612841 -349.627193) (xy 63.612268 -349.582486) (xy 63.612268 -349.58147) (xy 63.612522 -349.57004)
			(xy 63.586044 -349.564091) (xy 63.533809 -349.54935) (xy 63.508128 -349.540576) (xy 63.499931 -349.538062)
			(xy 63.482797 -349.538062) (xy 63.4746 -349.540576) (xy 63.43938 -349.552528) (xy 63.367379 -349.571185)
			(xy 63.294059 -349.583696) (xy 63.219944 -349.589972) (xy 63.182754 -349.59036) (xy 63.145565 -349.589952)
			(xy 63.071452 -349.583667) (xy 62.998133 -349.571163) (xy 62.926126 -349.552528) (xy 62.890908 -349.540576)
			(xy 62.882711 -349.538062) (xy 62.865577 -349.538062) (xy 62.85738 -349.540576) (xy 62.822162 -349.552533)
			(xy 62.75016 -349.571189) (xy 62.676839 -349.583699) (xy 62.602724 -349.589973) (xy 62.565534 -349.59036)
			(xy 62.523594 -349.589902) (xy 62.440094 -349.581932) (xy 62.35773 -349.566061) (xy 62.277248 -349.542432)
			(xy 62.199376 -349.511259) (xy 62.12482 -349.472825) (xy 62.054255 -349.427478) (xy 61.98832 -349.375629)
			(xy 61.927613 -349.317747) (xy 61.872683 -349.254356) (xy 61.824027 -349.186031) (xy 61.782086 -349.11339)
			(xy 61.74724 -349.037091) (xy 61.719806 -348.957825) (xy 61.70003 -348.87631) (xy 61.688092 -348.793284)
			(xy 61.684101 -348.7095) (xy 58.14031 -348.7095) (xy 58.143679 -348.745845) (xy 58.144156 -348.786958)
			(xy 58.143595 -348.831728) (xy 58.134584 -348.920813) (xy 58.116678 -349.008544) (xy 58.090059 -349.094035)
			(xy 58.073036 -349.135446) (xy 58.069497 -349.145044) (xy 58.069481 -349.16548) (xy 58.073036 -349.17507)
			(xy 58.090063 -349.21648) (xy 58.1167 -349.301967) (xy 58.134606 -349.3897) (xy 58.143603 -349.478787)
			(xy 58.144156 -349.523558) (xy 58.143595 -349.568328) (xy 58.134584 -349.657413) (xy 58.116678 -349.745144)
			(xy 58.090059 -349.830635) (xy 58.073036 -349.872046) (xy 58.069497 -349.881644) (xy 58.069481 -349.90208)
			(xy 58.073036 -349.91167) (xy 58.090063 -349.95308) (xy 58.1167 -350.038567) (xy 58.134606 -350.1263)
			(xy 58.143603 -350.215387) (xy 58.144156 -350.260158) (xy 58.143661 -350.301272) (xy 58.136078 -350.383151)
			(xy 58.120972 -350.46398) (xy 58.098472 -350.54307) (xy 58.06877 -350.619748) (xy 58.03212 -350.693357)
			(xy 57.988834 -350.76327) (xy 57.939282 -350.828891) (xy 57.883886 -350.88966) (xy 57.823119 -350.945059)
			(xy 57.7575 -350.994614) (xy 57.687588 -351.037902) (xy 57.61398 -351.074555) (xy 57.537305 -351.10426)
			(xy 57.458215 -351.126764) (xy 57.377386 -351.141873) (xy 57.295508 -351.14946) (xy 57.254394 -351.14992)
			(xy 57.212784 -351.149442) (xy 57.129927 -351.141665) (xy 57.048158 -351.12619) (xy 56.968191 -351.10315)
			(xy 56.890722 -351.072748) (xy 56.816429 -351.035248) (xy 56.780938 -351.013522) (xy 56.77183 -351.008297)
			(xy 56.751093 -351.005101) (xy 56.730808 -351.010462) (xy 56.722264 -351.01657) (xy 56.688631 -351.042555)
			(xy 56.617237 -351.08868) (xy 56.541767 -351.127782) (xy 56.46291 -351.159503) (xy 56.381385 -351.183553)
			(xy 56.297938 -351.199714) (xy 56.213329 -351.207838) (xy 56.17083 -351.20834) (xy 56.129715 -351.207873)
			(xy 56.047835 -351.200288) (xy 55.967005 -351.185181) (xy 55.887914 -351.162679) (xy 55.811236 -351.132976)
			(xy 55.737626 -351.096324) (xy 55.667712 -351.053036) (xy 55.60209 -351.003482) (xy 55.541321 -350.948084)
			(xy 55.485923 -350.887316) (xy 55.436368 -350.821695) (xy 55.39308 -350.751781) (xy 55.356428 -350.678172)
			(xy 55.326723 -350.601494) (xy 55.304221 -350.522403) (xy 55.289113 -350.441573) (xy 55.281527 -350.359693)
			(xy 55.281068 -350.318578) (xy 55.28164 -350.273809) (xy 55.290647 -350.184724) (xy 55.30855 -350.096993)
			(xy 55.335166 -350.011501) (xy 55.352188 -349.97009) (xy 55.355768 -349.960503) (xy 55.35576 -349.940056)
			(xy 55.352188 -349.930466) (xy 55.335163 -349.889123) (xy 55.308557 -349.803758) (xy 55.290656 -349.716153)
			(xy 55.281641 -349.627193) (xy 55.281068 -349.582486) (xy 55.281068 -349.58147) (xy 55.281322 -349.57004)
			(xy 55.254844 -349.564091) (xy 55.202609 -349.54935) (xy 55.176928 -349.540576) (xy 55.168731 -349.538062)
			(xy 55.151597 -349.538062) (xy 55.1434 -349.540576) (xy 55.10818 -349.552528) (xy 55.036179 -349.571185)
			(xy 54.962859 -349.583696) (xy 54.888744 -349.589972) (xy 54.851554 -349.59036) (xy 54.814365 -349.589952)
			(xy 54.740252 -349.583667) (xy 54.666933 -349.571163) (xy 54.594926 -349.552528) (xy 54.559708 -349.540576)
			(xy 54.551511 -349.538062) (xy 54.534377 -349.538062) (xy 54.52618 -349.540576) (xy 54.490962 -349.552533)
			(xy 54.41896 -349.571189) (xy 54.345639 -349.583699) (xy 54.271524 -349.589973) (xy 54.234334 -349.59036)
			(xy 54.192394 -349.589902) (xy 54.108894 -349.581932) (xy 54.02653 -349.566061) (xy 53.946048 -349.542432)
			(xy 53.868176 -349.511259) (xy 53.79362 -349.472825) (xy 53.723055 -349.427478) (xy 53.65712 -349.375629)
			(xy 53.596413 -349.317747) (xy 53.541483 -349.254356) (xy 53.492827 -349.186031) (xy 53.450886 -349.11339)
			(xy 53.41604 -349.037091) (xy 53.388606 -348.957825) (xy 53.36883 -348.87631) (xy 53.356892 -348.793284)
			(xy 53.352901 -348.7095) (xy 49.78371 -348.7095) (xy 49.787079 -348.745845) (xy 49.787556 -348.786958)
			(xy 49.786995 -348.831728) (xy 49.777984 -348.920813) (xy 49.760078 -349.008544) (xy 49.733459 -349.094035)
			(xy 49.716436 -349.135446) (xy 49.712897 -349.145044) (xy 49.712881 -349.16548) (xy 49.716436 -349.17507)
			(xy 49.733463 -349.21648) (xy 49.7601 -349.301967) (xy 49.778006 -349.3897) (xy 49.787003 -349.478787)
			(xy 49.787556 -349.523558) (xy 49.786995 -349.568328) (xy 49.777984 -349.657413) (xy 49.760078 -349.745144)
			(xy 49.733459 -349.830635) (xy 49.716436 -349.872046) (xy 49.712897 -349.881644) (xy 49.712881 -349.90208)
			(xy 49.716436 -349.91167) (xy 49.733463 -349.95308) (xy 49.7601 -350.038567) (xy 49.778006 -350.1263)
			(xy 49.787003 -350.215387) (xy 49.787556 -350.260158) (xy 49.787061 -350.301272) (xy 49.779478 -350.383151)
			(xy 49.764372 -350.46398) (xy 49.741872 -350.54307) (xy 49.71217 -350.619748) (xy 49.67552 -350.693357)
			(xy 49.632234 -350.76327) (xy 49.582682 -350.828891) (xy 49.527286 -350.88966) (xy 49.466519 -350.945059)
			(xy 49.4009 -350.994614) (xy 49.330988 -351.037902) (xy 49.25738 -351.074555) (xy 49.180705 -351.10426)
			(xy 49.101615 -351.126764) (xy 49.020786 -351.141873) (xy 48.938908 -351.14946) (xy 48.897794 -351.14992)
			(xy 48.856184 -351.149442) (xy 48.773327 -351.141665) (xy 48.691558 -351.12619) (xy 48.611591 -351.10315)
			(xy 48.534122 -351.072748) (xy 48.459829 -351.035248) (xy 48.424338 -351.013522) (xy 48.41523 -351.008297)
			(xy 48.394493 -351.005101) (xy 48.374208 -351.010462) (xy 48.365664 -351.01657) (xy 48.332031 -351.042555)
			(xy 48.260637 -351.08868) (xy 48.185167 -351.127782) (xy 48.10631 -351.159503) (xy 48.024785 -351.183553)
			(xy 47.941338 -351.199714) (xy 47.856729 -351.207838) (xy 47.81423 -351.20834) (xy 47.773115 -351.207873)
			(xy 47.691235 -351.200288) (xy 47.610405 -351.185181) (xy 47.531314 -351.162679) (xy 47.454636 -351.132976)
			(xy 47.381026 -351.096324) (xy 47.311112 -351.053036) (xy 47.24549 -351.003482) (xy 47.184721 -350.948084)
			(xy 47.129323 -350.887316) (xy 47.079768 -350.821695) (xy 47.03648 -350.751781) (xy 46.999828 -350.678172)
			(xy 46.970123 -350.601494) (xy 46.947621 -350.522403) (xy 46.932513 -350.441573) (xy 46.924927 -350.359693)
			(xy 46.924468 -350.318578) (xy 46.92504 -350.273809) (xy 46.934047 -350.184724) (xy 46.95195 -350.096993)
			(xy 46.978566 -350.011501) (xy 46.995588 -349.97009) (xy 46.999168 -349.960503) (xy 46.99916 -349.940056)
			(xy 46.995588 -349.930466) (xy 46.978563 -349.889123) (xy 46.951957 -349.803758) (xy 46.934056 -349.716153)
			(xy 46.925041 -349.627193) (xy 46.924468 -349.582486) (xy 46.924468 -349.58147) (xy 46.924722 -349.57004)
			(xy 46.898244 -349.564091) (xy 46.846009 -349.54935) (xy 46.820328 -349.540576) (xy 46.812131 -349.538062)
			(xy 46.794997 -349.538062) (xy 46.7868 -349.540576) (xy 46.75158 -349.552528) (xy 46.679579 -349.571185)
			(xy 46.606259 -349.583696) (xy 46.532144 -349.589972) (xy 46.494954 -349.59036) (xy 46.457765 -349.589952)
			(xy 46.383652 -349.583667) (xy 46.310333 -349.571163) (xy 46.238326 -349.552528) (xy 46.203108 -349.540576)
			(xy 46.194911 -349.538062) (xy 46.177777 -349.538062) (xy 46.16958 -349.540576) (xy 46.134362 -349.552533)
			(xy 46.06236 -349.571189) (xy 45.989039 -349.583699) (xy 45.914924 -349.589973) (xy 45.877734 -349.59036)
			(xy 45.835794 -349.589902) (xy 45.752294 -349.581932) (xy 45.66993 -349.566061) (xy 45.589448 -349.542432)
			(xy 45.511576 -349.511259) (xy 45.43702 -349.472825) (xy 45.366455 -349.427478) (xy 45.30052 -349.375629)
			(xy 45.239813 -349.317747) (xy 45.184883 -349.254356) (xy 45.136227 -349.186031) (xy 45.094286 -349.11339)
			(xy 45.05944 -349.037091) (xy 45.032006 -348.957825) (xy 45.01223 -348.87631) (xy 45.000292 -348.793284)
			(xy 44.996301 -348.7095) (xy 41.47791 -348.7095) (xy 41.481279 -348.745845) (xy 41.481756 -348.786958)
			(xy 41.481195 -348.831728) (xy 41.472184 -348.920813) (xy 41.454278 -349.008544) (xy 41.427659 -349.094035)
			(xy 41.410636 -349.135446) (xy 41.407097 -349.145044) (xy 41.407081 -349.16548) (xy 41.410636 -349.17507)
			(xy 41.427663 -349.21648) (xy 41.4543 -349.301967) (xy 41.472206 -349.3897) (xy 41.481203 -349.478787)
			(xy 41.481756 -349.523558) (xy 41.481195 -349.568328) (xy 41.472184 -349.657413) (xy 41.454278 -349.745144)
			(xy 41.427659 -349.830635) (xy 41.410636 -349.872046) (xy 41.407097 -349.881644) (xy 41.407081 -349.90208)
			(xy 41.410636 -349.91167) (xy 41.427663 -349.95308) (xy 41.4543 -350.038567) (xy 41.472206 -350.1263)
			(xy 41.481203 -350.215387) (xy 41.481756 -350.260158) (xy 41.481261 -350.301272) (xy 41.473678 -350.383151)
			(xy 41.458572 -350.46398) (xy 41.436072 -350.54307) (xy 41.40637 -350.619748) (xy 41.36972 -350.693357)
			(xy 41.326434 -350.76327) (xy 41.276882 -350.828891) (xy 41.221486 -350.88966) (xy 41.160719 -350.945059)
			(xy 41.0951 -350.994614) (xy 41.025188 -351.037902) (xy 40.95158 -351.074555) (xy 40.874905 -351.10426)
			(xy 40.795815 -351.126764) (xy 40.714986 -351.141873) (xy 40.633108 -351.14946) (xy 40.591994 -351.14992)
			(xy 40.550384 -351.149442) (xy 40.467527 -351.141665) (xy 40.385758 -351.12619) (xy 40.305791 -351.10315)
			(xy 40.228322 -351.072748) (xy 40.154029 -351.035248) (xy 40.118538 -351.013522) (xy 40.10943 -351.008297)
			(xy 40.088693 -351.005101) (xy 40.068408 -351.010462) (xy 40.059864 -351.01657) (xy 40.026231 -351.042555)
			(xy 39.954837 -351.08868) (xy 39.879367 -351.127782) (xy 39.80051 -351.159503) (xy 39.718985 -351.183553)
			(xy 39.635538 -351.199714) (xy 39.550929 -351.207838) (xy 39.50843 -351.20834) (xy 39.467315 -351.207873)
			(xy 39.385435 -351.200288) (xy 39.304605 -351.185181) (xy 39.225514 -351.162679) (xy 39.148836 -351.132976)
			(xy 39.075226 -351.096324) (xy 39.005312 -351.053036) (xy 38.93969 -351.003482) (xy 38.878921 -350.948084)
			(xy 38.823523 -350.887316) (xy 38.773968 -350.821695) (xy 38.73068 -350.751781) (xy 38.694028 -350.678172)
			(xy 38.664323 -350.601494) (xy 38.641821 -350.522403) (xy 38.626713 -350.441573) (xy 38.619127 -350.359693)
			(xy 38.618668 -350.318578) (xy 38.61924 -350.273809) (xy 38.628247 -350.184724) (xy 38.64615 -350.096993)
			(xy 38.672766 -350.011501) (xy 38.689788 -349.97009) (xy 38.693368 -349.960503) (xy 38.69336 -349.940056)
			(xy 38.689788 -349.930466) (xy 38.672763 -349.889123) (xy 38.646157 -349.803758) (xy 38.628256 -349.716153)
			(xy 38.619241 -349.627193) (xy 38.618668 -349.582486) (xy 38.618668 -349.58147) (xy 38.618922 -349.57004)
			(xy 38.592444 -349.564091) (xy 38.540209 -349.54935) (xy 38.514528 -349.540576) (xy 38.506331 -349.538062)
			(xy 38.489197 -349.538062) (xy 38.481 -349.540576) (xy 38.44578 -349.552528) (xy 38.373779 -349.571185)
			(xy 38.300459 -349.583696) (xy 38.226344 -349.589972) (xy 38.189154 -349.59036) (xy 38.151965 -349.589952)
			(xy 38.077852 -349.583667) (xy 38.004533 -349.571163) (xy 37.932526 -349.552528) (xy 37.897308 -349.540576)
			(xy 37.889111 -349.538062) (xy 37.871977 -349.538062) (xy 37.86378 -349.540576) (xy 37.828562 -349.552533)
			(xy 37.75656 -349.571189) (xy 37.683239 -349.583699) (xy 37.609124 -349.589973) (xy 37.571934 -349.59036)
			(xy 37.529996 -349.589881) (xy 37.446499 -349.581908) (xy 37.364138 -349.566035) (xy 37.283659 -349.542404)
			(xy 37.20579 -349.511231) (xy 37.131238 -349.472797) (xy 37.060676 -349.42745) (xy 36.994745 -349.375601)
			(xy 36.93404 -349.317719) (xy 36.879112 -349.25433) (xy 36.830459 -349.186006) (xy 36.788521 -349.113367)
			(xy 36.753677 -349.03707) (xy 36.726244 -348.957807) (xy 36.706469 -348.876294) (xy 36.694532 -348.793272)
			(xy 36.690541 -348.70949) (xy 33.197509 -348.70949) (xy 33.200879 -348.745845) (xy 33.201356 -348.786958)
			(xy 33.200795 -348.831728) (xy 33.191784 -348.920813) (xy 33.173878 -349.008544) (xy 33.147259 -349.094035)
			(xy 33.130236 -349.135446) (xy 33.126697 -349.145044) (xy 33.126681 -349.16548) (xy 33.130236 -349.17507)
			(xy 33.147263 -349.21648) (xy 33.1739 -349.301967) (xy 33.191806 -349.3897) (xy 33.200803 -349.478787)
			(xy 33.201356 -349.523558) (xy 33.200795 -349.568328) (xy 33.191784 -349.657413) (xy 33.173878 -349.745144)
			(xy 33.147259 -349.830635) (xy 33.130236 -349.872046) (xy 33.126697 -349.881644) (xy 33.126681 -349.90208)
			(xy 33.130236 -349.91167) (xy 33.147263 -349.95308) (xy 33.1739 -350.038567) (xy 33.191806 -350.1263)
			(xy 33.200803 -350.215387) (xy 33.201356 -350.260158) (xy 33.200861 -350.301272) (xy 33.193278 -350.383151)
			(xy 33.178172 -350.46398) (xy 33.155672 -350.54307) (xy 33.12597 -350.619748) (xy 33.08932 -350.693357)
			(xy 33.046034 -350.76327) (xy 32.996482 -350.828891) (xy 32.941086 -350.88966) (xy 32.880319 -350.945059)
			(xy 32.8147 -350.994614) (xy 32.744788 -351.037902) (xy 32.67118 -351.074555) (xy 32.594505 -351.10426)
			(xy 32.515415 -351.126764) (xy 32.434586 -351.141873) (xy 32.352708 -351.14946) (xy 32.311594 -351.14992)
			(xy 32.269984 -351.149442) (xy 32.187127 -351.141665) (xy 32.105358 -351.12619) (xy 32.025391 -351.10315)
			(xy 31.947922 -351.072748) (xy 31.873629 -351.035248) (xy 31.838138 -351.013522) (xy 31.82903 -351.008297)
			(xy 31.808293 -351.005101) (xy 31.788008 -351.010462) (xy 31.779464 -351.01657) (xy 31.745831 -351.042555)
			(xy 31.674437 -351.08868) (xy 31.598967 -351.127782) (xy 31.52011 -351.159503) (xy 31.438585 -351.183553)
			(xy 31.355138 -351.199714) (xy 31.270529 -351.207838) (xy 31.22803 -351.20834) (xy 31.186915 -351.207873)
			(xy 31.105035 -351.200288) (xy 31.024205 -351.185181) (xy 30.945114 -351.162679) (xy 30.868436 -351.132976)
			(xy 30.794826 -351.096324) (xy 30.724912 -351.053036) (xy 30.65929 -351.003482) (xy 30.598521 -350.948084)
			(xy 30.543123 -350.887316) (xy 30.493568 -350.821695) (xy 30.45028 -350.751781) (xy 30.413628 -350.678172)
			(xy 30.383923 -350.601494) (xy 30.361421 -350.522403) (xy 30.346313 -350.441573) (xy 30.338727 -350.359693)
			(xy 30.338268 -350.318578) (xy 30.33884 -350.273809) (xy 30.347847 -350.184724) (xy 30.36575 -350.096993)
			(xy 30.392366 -350.011501) (xy 30.409388 -349.97009) (xy 30.412968 -349.960503) (xy 30.41296 -349.940056)
			(xy 30.409388 -349.930466) (xy 30.392363 -349.889123) (xy 30.365757 -349.803758) (xy 30.347856 -349.716153)
			(xy 30.338841 -349.627193) (xy 30.338268 -349.582486) (xy 30.338268 -349.58147) (xy 30.338522 -349.57004)
			(xy 30.312044 -349.564091) (xy 30.259809 -349.54935) (xy 30.234128 -349.540576) (xy 30.225931 -349.538062)
			(xy 30.208797 -349.538062) (xy 30.2006 -349.540576) (xy 30.16538 -349.552528) (xy 30.093379 -349.571185)
			(xy 30.020059 -349.583696) (xy 29.945944 -349.589972) (xy 29.908754 -349.59036) (xy 29.871565 -349.589952)
			(xy 29.797452 -349.583667) (xy 29.724133 -349.571163) (xy 29.652126 -349.552528) (xy 29.616908 -349.540576)
			(xy 29.608711 -349.538062) (xy 29.591577 -349.538062) (xy 29.58338 -349.540576) (xy 29.548162 -349.552533)
			(xy 29.47616 -349.571189) (xy 29.402839 -349.583699) (xy 29.328724 -349.589973) (xy 29.291534 -349.59036)
			(xy 29.249596 -349.589881) (xy 29.166099 -349.581908) (xy 29.083738 -349.566035) (xy 29.003259 -349.542404)
			(xy 28.92539 -349.511231) (xy 28.850838 -349.472797) (xy 28.780276 -349.42745) (xy 28.714345 -349.375601)
			(xy 28.65364 -349.317719) (xy 28.598712 -349.25433) (xy 28.550059 -349.186006) (xy 28.508121 -349.113367)
			(xy 28.473277 -349.03707) (xy 28.445844 -348.957807) (xy 28.426069 -348.876294) (xy 28.414132 -348.793272)
			(xy 28.410141 -348.70949) (xy 2.509012 -348.70949) (xy 2.509012 -351.637854) (xy 73.92162 -351.637854)
			(xy 73.922073 -351.597287) (xy 73.929469 -351.516491) (xy 73.944194 -351.436705) (xy 73.966127 -351.358593)
			(xy 73.995085 -351.282803) (xy 74.012552 -351.246186) (xy 74.016468 -351.237096) (xy 74.017766 -351.217362)
			(xy 74.015092 -351.207832) (xy 74.000912 -351.162806) (xy 73.981012 -351.070523) (xy 73.971009 -350.97665)
			(xy 73.970388 -350.929448) (xy 73.970892 -350.887087) (xy 73.978945 -350.80275) (xy 73.994979 -350.71956)
			(xy 74.018847 -350.63827) (xy 74.050335 -350.559618) (xy 74.089157 -350.484315) (xy 74.13496 -350.413043)
			(xy 74.187331 -350.346447) (xy 74.245796 -350.285132) (xy 74.309824 -350.229651) (xy 74.378836 -350.180508)
			(xy 74.452206 -350.138148) (xy 74.529271 -350.102953) (xy 74.609333 -350.075244) (xy 74.691666 -350.05527)
			(xy 74.775525 -350.043213) (xy 74.86015 -350.039182) (xy 74.944775 -350.043213) (xy 75.028634 -350.05527)
			(xy 75.110967 -350.075244) (xy 75.191029 -350.102953) (xy 75.268094 -350.138148) (xy 75.341464 -350.180508)
			(xy 75.410476 -350.229651) (xy 75.474504 -350.285132) (xy 75.532969 -350.346447) (xy 75.58534 -350.413043)
			(xy 75.631143 -350.484315) (xy 75.669965 -350.559618) (xy 75.701453 -350.63827) (xy 75.725321 -350.71956)
			(xy 75.741355 -350.80275) (xy 75.749408 -350.887087) (xy 75.749912 -350.929448) (xy 75.749456 -350.970015)
			(xy 75.742061 -351.05081) (xy 75.727336 -351.130596) (xy 75.705403 -351.208709) (xy 75.676446 -351.284499)
			(xy 75.65898 -351.321116) (xy 75.655063 -351.330206) (xy 75.653765 -351.34994) (xy 75.65644 -351.35947)
			(xy 75.670621 -351.404496) (xy 75.69052 -351.496779) (xy 75.700524 -351.590652) (xy 75.70064 -351.5995)
			(xy 76.58354 -351.5995) (xy 76.583977 -351.558938) (xy 76.59131 -351.478148) (xy 76.605978 -351.398363)
			(xy 76.62786 -351.320247) (xy 76.656772 -351.244452) (xy 76.674218 -351.207832) (xy 76.67814 -351.198816)
			(xy 76.679575 -351.179224) (xy 76.677012 -351.169732) (xy 76.662856 -351.124831) (xy 76.642989 -351.0328)
			(xy 76.632962 -350.939185) (xy 76.632308 -350.89211) (xy 76.632308 -350.891094) (xy 76.632812 -350.848746)
			(xy 76.640863 -350.764432) (xy 76.656892 -350.681266) (xy 76.680753 -350.599999) (xy 76.712232 -350.521369)
			(xy 76.751043 -350.446088) (xy 76.796833 -350.374836) (xy 76.849189 -350.30826) (xy 76.907637 -350.246962)
			(xy 76.971647 -350.191497) (xy 77.040639 -350.142368) (xy 77.113989 -350.100019) (xy 77.191032 -350.064835)
			(xy 77.271071 -350.037133) (xy 77.35338 -350.017165) (xy 77.437215 -350.005112) (xy 77.521816 -350.001082)
			(xy 77.606417 -350.005112) (xy 77.690252 -350.017165) (xy 77.772561 -350.037133) (xy 77.8526 -350.064835)
			(xy 77.929643 -350.100019) (xy 78.002993 -350.142368) (xy 78.071985 -350.191497) (xy 78.135995 -350.246962)
			(xy 78.194443 -350.30826) (xy 78.246799 -350.374836) (xy 78.292589 -350.446088) (xy 78.3314 -350.521369)
			(xy 78.362879 -350.599999) (xy 78.38674 -350.681266) (xy 78.402769 -350.764432) (xy 78.41082 -350.848746)
			(xy 78.411324 -350.891094) (xy 78.411324 -350.891602) (xy 78.410897 -350.932113) (xy 78.403528 -351.0128)
			(xy 78.388844 -351.09248) (xy 78.366965 -351.170492) (xy 78.338074 -351.246189) (xy 78.320646 -351.282762)
			(xy 78.316728 -351.291779) (xy 78.315288 -351.31137) (xy 78.317852 -351.320862) (xy 78.33205 -351.365927)
			(xy 78.351954 -351.458296) (xy 78.361947 -351.552255) (xy 78.362556 -351.5995) (xy 78.362003 -351.645139)
			(xy 78.352699 -351.735943) (xy 78.334149 -351.825316) (xy 78.3209 -351.868994) (xy 78.318454 -351.878006)
			(xy 78.319496 -351.896634) (xy 78.322932 -351.905316) (xy 78.341634 -351.948394) (xy 78.370914 -352.03763)
			(xy 78.390624 -352.129456) (xy 78.400545 -352.222848) (xy 78.401164 -352.269806) (xy 78.401164 -352.27006)
			(xy 78.400635 -352.313006) (xy 78.392335 -352.398495) (xy 78.375846 -352.482789) (xy 78.351322 -352.565106)
			(xy 78.335632 -352.605086) (xy 78.332346 -352.614331) (xy 78.332359 -352.633935) (xy 78.335632 -352.643186)
			(xy 78.351338 -352.683162) (xy 78.375884 -352.765474) (xy 78.392373 -352.84977) (xy 78.400651 -352.935265)
			(xy 78.401164 -352.978212) (xy 78.40066 -353.020573) (xy 78.392607 -353.10491) (xy 78.376573 -353.1881)
			(xy 78.352705 -353.26939) (xy 78.346936 -353.2838) (xy 182.729656 -353.2838) (xy 182.733646 -353.200045)
			(xy 182.745579 -353.117047) (xy 182.765347 -353.035561) (xy 182.792771 -352.956321) (xy 182.827603 -352.880048)
			(xy 182.869527 -352.807431) (xy 182.918163 -352.739127) (xy 182.973072 -352.675756) (xy 183.033756 -352.617891)
			(xy 183.099666 -352.566056) (xy 183.170204 -352.520721) (xy 183.244732 -352.482296) (xy 183.322575 -352.451129)
			(xy 183.403028 -352.427503) (xy 183.485362 -352.411631) (xy 183.568833 -352.403656) (xy 183.610758 -352.403156)
			(xy 183.611774 -352.403156) (xy 183.648831 -352.403571) (xy 183.72268 -352.409833) (xy 183.795742 -352.422272)
			(xy 183.867502 -352.440802) (xy 183.902604 -352.452686) (xy 183.910801 -352.4552) (xy 183.927935 -352.4552)
			(xy 183.936132 -352.452686) (xy 183.964337 -352.443048) (xy 184.021791 -352.42716) (xy 184.05094 -352.420936)
			(xy 184.060579 -352.41851) (xy 184.077071 -352.407448) (xy 184.088123 -352.390948) (xy 184.090564 -352.381312)
			(xy 184.100088 -352.337416) (xy 184.126813 -352.251655) (xy 184.143904 -352.210116) (xy 184.147468 -352.200525)
			(xy 184.147469 -352.180082) (xy 184.143904 -352.170492) (xy 184.126892 -352.12911) (xy 184.100271 -352.043685)
			(xy 184.082363 -351.956018) (xy 184.073351 -351.866996) (xy 184.072784 -351.822258) (xy 184.072784 -351.822004)
			(xy 184.073288 -351.779656) (xy 184.081339 -351.695342) (xy 184.097368 -351.612176) (xy 184.121229 -351.530909)
			(xy 184.152708 -351.452279) (xy 184.191519 -351.376998) (xy 184.237309 -351.305746) (xy 184.289665 -351.23917)
			(xy 184.348113 -351.177872) (xy 184.412123 -351.122407) (xy 184.481115 -351.073278) (xy 184.554465 -351.030929)
			(xy 184.631508 -350.995745) (xy 184.711547 -350.968043) (xy 184.793856 -350.948075) (xy 184.877691 -350.936022)
			(xy 184.962292 -350.931992) (xy 185.046893 -350.936022) (xy 185.130728 -350.948075) (xy 185.213037 -350.968043)
			(xy 185.293076 -350.995745) (xy 185.370119 -351.030929) (xy 185.443469 -351.073278) (xy 185.512461 -351.122407)
			(xy 185.576471 -351.177872) (xy 185.634919 -351.23917) (xy 185.687275 -351.305746) (xy 185.733065 -351.376998)
			(xy 185.771876 -351.452279) (xy 185.803355 -351.530909) (xy 185.827216 -351.612176) (xy 185.843245 -351.695342)
			(xy 185.851296 -351.779656) (xy 185.8518 -351.822004) (xy 185.8518 -351.822258) (xy 185.851234 -351.866996)
			(xy 185.842218 -351.956018) (xy 185.824312 -352.043685) (xy 185.797698 -352.129113) (xy 185.78068 -352.170492)
			(xy 185.777112 -352.180082) (xy 185.777113 -352.200525) (xy 185.78068 -352.210116) (xy 185.797704 -352.251527)
			(xy 185.824339 -352.337015) (xy 185.842246 -352.424746) (xy 185.851245 -352.513834) (xy 185.8518 -352.558604)
			(xy 185.85116 -352.609084) (xy 185.839825 -352.709404) (xy 185.829194 -352.758756) (xy 185.826997 -352.771225)
			(xy 185.833664 -352.795617) (xy 185.841894 -352.805238) (xy 185.882534 -352.847656) (xy 185.889646 -352.846132)
			(xy 185.898412 -352.843862) (xy 185.913646 -352.834103) (xy 185.919364 -352.827082) (xy 185.944527 -352.794419)
			(xy 185.999939 -352.733355) (xy 186.060764 -352.67768) (xy 186.126478 -352.627872) (xy 186.196519 -352.584357)
			(xy 186.270286 -352.547509) (xy 186.347146 -352.517645) (xy 186.426439 -352.49502) (xy 186.507485 -352.479828)
			(xy 186.589589 -352.472201) (xy 186.630818 -352.471736) (xy 186.671925 -352.472195) (xy 186.753788 -352.479781)
			(xy 186.834603 -352.494887) (xy 186.913679 -352.517383) (xy 186.990343 -352.547078) (xy 187.06394 -352.583719)
			(xy 187.133844 -352.626993) (xy 187.199457 -352.676531) (xy 187.260221 -352.73191) (xy 187.315617 -352.792659)
			(xy 187.365173 -352.85826) (xy 187.408465 -352.928152) (xy 187.445126 -353.001739) (xy 187.474841 -353.078395)
			(xy 187.497359 -353.157466) (xy 187.512486 -353.238276) (xy 187.519078 -353.3092) (xy 191.056256 -353.3092)
			(xy 191.060246 -353.225443) (xy 191.07218 -353.142444) (xy 191.091948 -353.060956) (xy 191.119373 -352.981715)
			(xy 191.154206 -352.90544) (xy 191.196132 -352.832822) (xy 191.244771 -352.764518) (xy 191.299682 -352.701146)
			(xy 191.360368 -352.643281) (xy 191.42628 -352.591447) (xy 191.49682 -352.546112) (xy 191.57135 -352.507688)
			(xy 191.649196 -352.476522) (xy 191.729651 -352.452897) (xy 191.811988 -352.437027) (xy 191.89546 -352.429055)
			(xy 191.937386 -352.428556) (xy 191.938402 -352.428556) (xy 191.975459 -352.428963) (xy 192.049308 -352.435227)
			(xy 192.12237 -352.447669) (xy 192.194131 -352.466201) (xy 192.229232 -352.478086) (xy 192.237429 -352.4806)
			(xy 192.254563 -352.4806) (xy 192.26276 -352.478086) (xy 192.290041 -352.468747) (xy 192.345585 -352.453243)
			(xy 192.373758 -352.447098) (xy 192.383527 -352.444576) (xy 192.400163 -352.433196) (xy 192.411142 -352.416293)
			(xy 192.413382 -352.406458) (xy 192.422838 -352.357349) (xy 192.451357 -352.261489) (xy 192.470278 -352.215196)
			(xy 192.473919 -352.205632) (xy 192.474045 -352.185185) (xy 192.470532 -352.175572) (xy 192.453515 -352.134192)
			(xy 192.426895 -352.048766) (xy 192.408989 -351.961099) (xy 192.399978 -351.872077) (xy 192.399412 -351.827338)
			(xy 192.399412 -351.827084) (xy 192.399916 -351.784736) (xy 192.407967 -351.700422) (xy 192.423996 -351.617256)
			(xy 192.447857 -351.535989) (xy 192.479336 -351.457359) (xy 192.518147 -351.382078) (xy 192.563937 -351.310826)
			(xy 192.616293 -351.24425) (xy 192.674741 -351.182952) (xy 192.738751 -351.127487) (xy 192.807743 -351.078358)
			(xy 192.881093 -351.036009) (xy 192.958136 -351.000825) (xy 193.038175 -350.973123) (xy 193.120484 -350.953155)
			(xy 193.204319 -350.941102) (xy 193.28892 -350.937072) (xy 193.373521 -350.941102) (xy 193.457356 -350.953155)
			(xy 193.539665 -350.973123) (xy 193.619704 -351.000825) (xy 193.696747 -351.036009) (xy 193.770097 -351.078358)
			(xy 193.839089 -351.127487) (xy 193.903099 -351.182952) (xy 193.961547 -351.24425) (xy 194.013903 -351.310826)
			(xy 194.059693 -351.382078) (xy 194.098504 -351.457359) (xy 194.129983 -351.535989) (xy 194.153844 -351.617256)
			(xy 194.169873 -351.700422) (xy 194.177924 -351.784736) (xy 194.178428 -351.827084) (xy 194.178428 -351.827338)
			(xy 194.177853 -351.872076) (xy 194.168839 -351.961098) (xy 194.150936 -352.048765) (xy 194.124325 -352.134193)
			(xy 194.107308 -352.175572) (xy 194.10375 -352.185165) (xy 194.103744 -352.205606) (xy 194.107308 -352.215196)
			(xy 194.12436 -352.256596) (xy 194.150986 -352.342088) (xy 194.165052 -352.41103) (xy 206.449676 -352.41103)
			(xy 206.449676 -351.54743) (xy 206.450162 -351.520179) (xy 206.457918 -351.466231) (xy 206.473273 -351.413936)
			(xy 206.495915 -351.364359) (xy 206.525381 -351.318509) (xy 206.561072 -351.277318) (xy 206.602263 -351.241627)
			(xy 206.648113 -351.212161) (xy 206.69769 -351.189519) (xy 206.749985 -351.174164) (xy 206.803933 -351.166408)
			(xy 206.858435 -351.166408) (xy 206.912383 -351.174164) (xy 206.964678 -351.189519) (xy 207.014255 -351.212161)
			(xy 207.060105 -351.241627) (xy 207.101296 -351.277318) (xy 207.136987 -351.318509) (xy 207.166453 -351.364359)
			(xy 207.189095 -351.413936) (xy 207.20445 -351.466231) (xy 207.212206 -351.520179) (xy 207.212692 -351.54743)
			(xy 207.212692 -352.41103) (xy 207.212206 -352.438281) (xy 207.20445 -352.492229) (xy 207.189095 -352.544524)
			(xy 207.166453 -352.594101) (xy 207.136987 -352.639951) (xy 207.101296 -352.681142) (xy 207.060105 -352.716833)
			(xy 207.014255 -352.746299) (xy 206.964678 -352.768941) (xy 206.912383 -352.784296) (xy 206.858435 -352.792052)
			(xy 206.803933 -352.792052) (xy 206.749985 -352.784296) (xy 206.69769 -352.768941) (xy 206.648113 -352.746299)
			(xy 206.602263 -352.716833) (xy 206.561072 -352.681142) (xy 206.525381 -352.639951) (xy 206.495915 -352.594101)
			(xy 206.473273 -352.544524) (xy 206.457918 -352.492229) (xy 206.450162 -352.438281) (xy 206.449676 -352.41103)
			(xy 194.165052 -352.41103) (xy 194.168886 -352.429823) (xy 194.177877 -352.518913) (xy 194.178428 -352.563684)
			(xy 194.178055 -352.600778) (xy 194.171875 -352.674709) (xy 194.159556 -352.747868) (xy 194.150742 -352.783902)
			(xy 194.149 -352.792252) (xy 194.15051 -352.809229) (xy 194.157543 -352.824754) (xy 194.163188 -352.831146)
			(xy 194.203574 -352.874326) (xy 194.216274 -352.871532) (xy 194.225043 -352.869274) (xy 194.240276 -352.859506)
			(xy 194.245992 -352.852482) (xy 194.271138 -352.819805) (xy 194.326552 -352.758742) (xy 194.387379 -352.703068)
			(xy 194.453095 -352.65326) (xy 194.523138 -352.609746) (xy 194.596907 -352.5729) (xy 194.673768 -352.543037)
			(xy 194.753063 -352.520414) (xy 194.834111 -352.505225) (xy 194.916217 -352.4976) (xy 194.957446 -352.497136)
			(xy 194.998553 -352.497569) (xy 195.080417 -352.505157) (xy 195.161232 -352.520265) (xy 195.240309 -352.542764)
			(xy 195.316973 -352.572461) (xy 195.390571 -352.609104) (xy 195.460474 -352.652379) (xy 195.526087 -352.701919)
			(xy 195.586851 -352.757301) (xy 195.642247 -352.818051) (xy 195.691802 -352.883653) (xy 195.735094 -352.953546)
			(xy 195.744851 -352.973132) (xy 338.849208 -352.973132) (xy 338.849825 -352.926972) (xy 338.859426 -352.835153)
			(xy 338.878488 -352.744823) (xy 338.906804 -352.656953) (xy 338.9249 -352.614484) (xy 338.928699 -352.60454)
			(xy 338.928703 -352.583278) (xy 338.9249 -352.573336) (xy 338.90688 -352.530918) (xy 338.878719 -352.443158)
			(xy 338.859786 -352.352956) (xy 338.850284 -352.26128) (xy 338.849716 -352.215196) (xy 338.850295 -352.1688)
			(xy 338.859941 -352.076512) (xy 338.879138 -351.985728) (xy 338.907678 -351.897435) (xy 338.925916 -351.85477)
			(xy 338.929722 -351.844828) (xy 338.929721 -351.823565) (xy 338.925916 -351.813622) (xy 338.907694 -351.771019)
			(xy 338.879176 -351.682852) (xy 338.859983 -351.592196) (xy 338.850324 -351.500036) (xy 338.849716 -351.453704)
			(xy 338.849716 -351.453196) (xy 338.850148 -351.412092) (xy 338.857734 -351.330235) (xy 338.87284 -351.249427)
			(xy 338.895338 -351.170357) (xy 338.925036 -351.093701) (xy 338.96168 -351.020112) (xy 339.004958 -350.950218)
			(xy 339.0545 -350.884616) (xy 339.109884 -350.823864) (xy 339.170637 -350.768482) (xy 339.236241 -350.718942)
			(xy 339.306137 -350.675666) (xy 339.379727 -350.639025) (xy 339.456384 -350.609329) (xy 339.535454 -350.586834)
			(xy 339.616263 -350.57173) (xy 339.69812 -350.564147) (xy 339.739224 -350.563688) (xy 339.739732 -350.563688)
			(xy 339.786063 -350.564321) (xy 339.87822 -350.573985) (xy 339.968874 -350.593172) (xy 340.057044 -350.621677)
			(xy 340.09965 -350.639888) (xy 340.109592 -350.643694) (xy 340.130856 -350.643694) (xy 340.140798 -350.639888)
			(xy 340.183427 -350.621646) (xy 340.271658 -350.593118) (xy 340.36238 -350.573927) (xy 340.454606 -350.564283)
			(xy 340.50097 -350.563688) (xy 340.501478 -350.563688) (xy 340.547841 -350.56431) (xy 340.640063 -350.57396)
			(xy 340.730782 -350.593148) (xy 340.819014 -350.621665) (xy 340.86165 -350.639888) (xy 340.871592 -350.643694)
			(xy 340.892856 -350.643694) (xy 340.902798 -350.639888) (xy 340.945427 -350.621646) (xy 341.033658 -350.593118)
			(xy 341.12438 -350.573927) (xy 341.216606 -350.564283) (xy 341.26297 -350.563688) (xy 341.263478 -350.563688)
			(xy 341.309841 -350.56431) (xy 341.402063 -350.57396) (xy 341.492782 -350.593148) (xy 341.581014 -350.621665)
			(xy 341.62365 -350.639888) (xy 341.633592 -350.643694) (xy 341.654856 -350.643694) (xy 341.664798 -350.639888)
			(xy 341.707427 -350.621646) (xy 341.795658 -350.593118) (xy 341.88638 -350.573927) (xy 341.978606 -350.564283)
			(xy 342.02497 -350.563688) (xy 342.025478 -350.563688) (xy 342.071841 -350.56431) (xy 342.164063 -350.57396)
			(xy 342.254782 -350.593148) (xy 342.343014 -350.621665) (xy 342.38565 -350.639888) (xy 342.395592 -350.643694)
			(xy 342.416856 -350.643694) (xy 342.426798 -350.639888) (xy 342.469427 -350.621646) (xy 342.557658 -350.593118)
			(xy 342.64838 -350.573927) (xy 342.740606 -350.564283) (xy 342.78697 -350.563688) (xy 342.787478 -350.563688)
			(xy 342.833911 -350.564319) (xy 342.926269 -350.574013) (xy 343.017117 -350.593266) (xy 343.105468 -350.621869)
			(xy 343.148158 -350.640142) (xy 343.156911 -350.643584) (xy 343.175683 -350.644482) (xy 343.184734 -350.64192)
			(xy 343.229904 -350.627586) (xy 343.322519 -350.607479) (xy 343.416748 -350.597344) (xy 343.464134 -350.596708)
			(xy 343.465404 -350.596708) (xy 343.506508 -350.597148) (xy 343.588364 -350.604734) (xy 343.669172 -350.61984)
			(xy 343.748241 -350.642338) (xy 343.824897 -350.672035) (xy 343.898486 -350.708679) (xy 343.968379 -350.751956)
			(xy 344.033982 -350.801498) (xy 344.094733 -350.856881) (xy 344.150115 -350.917634) (xy 344.199655 -350.983237)
			(xy 344.242931 -351.053132) (xy 344.279573 -351.126721) (xy 344.309269 -351.203378) (xy 344.331765 -351.282448)
			(xy 344.346869 -351.363255) (xy 344.354453 -351.445112) (xy 344.354912 -351.486216) (xy 344.354912 -351.486724)
			(xy 344.354311 -351.533056) (xy 344.344638 -351.625214) (xy 344.325441 -351.715868) (xy 344.296928 -351.804037)
			(xy 344.278712 -351.846642) (xy 344.274897 -351.856581) (xy 344.274903 -351.877848) (xy 344.278712 -351.88779)
			(xy 344.296962 -351.93045) (xy 344.325505 -352.018743) (xy 344.344696 -352.109529) (xy 344.354328 -352.20182)
			(xy 344.354912 -352.248216) (xy 344.354328 -352.294369) (xy 344.344776 -352.386179) (xy 344.325776 -352.476508)
			(xy 344.297531 -352.564386) (xy 344.279474 -352.606864) (xy 344.275648 -352.6168) (xy 344.275662 -352.638069)
			(xy 344.279474 -352.648012) (xy 344.29749 -352.690438) (xy 344.325707 -352.77819) (xy 344.344711 -352.868387)
			(xy 344.354297 -352.960064) (xy 344.354912 -353.006152) (xy 344.354402 -353.047262) (xy 344.34922 -353.1032)
			(xy 423.453493 -353.1032) (xy 423.457484 -353.019415) (xy 423.469422 -352.936388) (xy 423.489198 -352.854872)
			(xy 423.516634 -352.775605) (xy 423.55148 -352.699305) (xy 423.593421 -352.626663) (xy 423.642078 -352.558337)
			(xy 423.697009 -352.494945) (xy 423.757718 -352.437063) (xy 423.823654 -352.385213) (xy 423.89422 -352.339866)
			(xy 423.968777 -352.301432) (xy 424.04665 -352.270259) (xy 424.127133 -352.24663) (xy 424.209499 -352.230759)
			(xy 424.293 -352.222789) (xy 424.33494 -352.222308) (xy 424.372129 -352.222714) (xy 424.446242 -352.228999)
			(xy 424.519562 -352.241503) (xy 424.591568 -352.260139) (xy 424.626786 -352.272092) (xy 424.634983 -352.274606)
			(xy 424.652117 -352.274606) (xy 424.660314 -352.272092) (xy 424.687596 -352.262757) (xy 424.74314 -352.24725)
			(xy 424.771312 -352.241104) (xy 424.781089 -352.238609) (xy 424.797722 -352.227214) (xy 424.808697 -352.210302)
			(xy 424.810936 -352.200464) (xy 424.820391 -352.151355) (xy 424.84891 -352.055495) (xy 424.867832 -352.009202)
			(xy 424.871403 -351.999613) (xy 424.871399 -351.979169) (xy 424.867832 -351.969578) (xy 424.850786 -351.928175)
			(xy 424.824155 -351.842685) (xy 424.806254 -351.754951) (xy 424.797263 -351.665861) (xy 424.796712 -351.62109)
			(xy 424.797216 -351.578729) (xy 424.805269 -351.494392) (xy 424.821303 -351.411202) (xy 424.845171 -351.329912)
			(xy 424.876659 -351.25126) (xy 424.915481 -351.175957) (xy 424.961284 -351.104685) (xy 425.013655 -351.038089)
			(xy 425.07212 -350.976774) (xy 425.136148 -350.921293) (xy 425.20516 -350.87215) (xy 425.27853 -350.82979)
			(xy 425.355595 -350.794595) (xy 425.435657 -350.766886) (xy 425.51799 -350.746912) (xy 425.601849 -350.734855)
			(xy 425.686474 -350.730824) (xy 425.771099 -350.734855) (xy 425.854958 -350.746912) (xy 425.937291 -350.766886)
			(xy 426.017353 -350.794595) (xy 426.094418 -350.82979) (xy 426.167788 -350.87215) (xy 426.2368 -350.921293)
			(xy 426.300828 -350.976774) (xy 426.359293 -351.038089) (xy 426.411664 -351.104685) (xy 426.457467 -351.175957)
			(xy 426.496289 -351.25126) (xy 426.527777 -351.329912) (xy 426.551645 -351.411202) (xy 426.567679 -351.494392)
			(xy 426.575732 -351.578729) (xy 426.576236 -351.62109) (xy 426.575653 -351.665859) (xy 426.566649 -351.754944)
			(xy 426.548749 -351.842675) (xy 426.522136 -351.928167) (xy 426.505116 -351.969578) (xy 426.501559 -351.979171)
			(xy 426.501555 -351.999611) (xy 426.505116 -352.009202) (xy 426.522153 -352.050608) (xy 426.548787 -352.136097)
			(xy 426.566691 -352.22383) (xy 426.575684 -352.312919) (xy 426.576236 -352.35769) (xy 426.575843 -352.394784)
			(xy 426.569667 -352.468714) (xy 426.557358 -352.541873) (xy 426.54855 -352.577908) (xy 426.5467 -352.586267)
			(xy 426.54815 -352.603318) (xy 426.55512 -352.618947) (xy 426.560742 -352.625406) (xy 426.601128 -352.668332)
			(xy 426.613574 -352.665538) (xy 426.622391 -352.663274) (xy 426.637739 -352.653501) (xy 426.643546 -352.646488)
			(xy 426.66867 -352.613784) (xy 426.724067 -352.552685) (xy 426.784882 -352.496976) (xy 426.850593 -352.447136)
			(xy 426.920635 -352.403592) (xy 426.994408 -352.366719) (xy 427.071277 -352.336834) (xy 427.150582 -352.314192)
			(xy 427.231643 -352.298989) (xy 427.313763 -352.291354) (xy 427.355 -352.290888) (xy 427.396095 -352.291366)
			(xy 427.477934 -352.298948) (xy 427.558725 -352.314048) (xy 427.637779 -352.336536) (xy 427.71442 -352.366221)
			(xy 427.787997 -352.40285) (xy 427.85788 -352.44611) (xy 427.923475 -352.495633) (xy 427.984222 -352.550996)
			(xy 428.039602 -352.611726) (xy 428.089144 -352.677307) (xy 428.132424 -352.747178) (xy 428.169074 -352.820744)
			(xy 428.198782 -352.897377) (xy 428.221293 -352.976424) (xy 428.236416 -353.05721) (xy 428.243051 -353.1286)
			(xy 431.780208 -353.1286) (xy 431.784199 -353.04482) (xy 431.796136 -352.961799) (xy 431.815909 -352.880289)
			(xy 431.843342 -352.801027) (xy 431.878184 -352.724732) (xy 431.92012 -352.652094) (xy 431.968771 -352.583771)
			(xy 432.023696 -352.520381) (xy 432.084398 -352.4625) (xy 432.150327 -352.410651) (xy 432.220886 -352.365303)
			(xy 432.295436 -352.326868) (xy 432.373301 -352.295693) (xy 432.453778 -352.27206) (xy 432.536136 -352.256184)
			(xy 432.619631 -352.248208) (xy 432.661568 -352.247708) (xy 432.698757 -352.248106) (xy 432.77287 -352.254393)
			(xy 432.84619 -352.2669) (xy 432.918196 -352.285538) (xy 432.953414 -352.297492) (xy 432.961611 -352.300006)
			(xy 432.978745 -352.300006) (xy 432.986942 -352.297492) (xy 433.014223 -352.288155) (xy 433.069768 -352.27265)
			(xy 433.09794 -352.266504) (xy 433.107722 -352.264025) (xy 433.124353 -352.252622) (xy 433.135327 -352.235704)
			(xy 433.137564 -352.225864) (xy 433.147017 -352.176755) (xy 433.175537 -352.080895) (xy 433.19446 -352.034602)
			(xy 433.19803 -352.025013) (xy 433.198026 -352.004569) (xy 433.19446 -351.994978) (xy 433.177416 -351.953575)
			(xy 433.150784 -351.868085) (xy 433.132882 -351.780351) (xy 433.123891 -351.691261) (xy 433.12334 -351.64649)
			(xy 433.123844 -351.604129) (xy 433.131897 -351.519792) (xy 433.147931 -351.436602) (xy 433.171799 -351.355312)
			(xy 433.203287 -351.27666) (xy 433.242109 -351.201357) (xy 433.287912 -351.130085) (xy 433.340283 -351.063489)
			(xy 433.398748 -351.002174) (xy 433.462776 -350.946693) (xy 433.531788 -350.89755) (xy 433.605158 -350.85519)
			(xy 433.682223 -350.819995) (xy 433.762285 -350.792286) (xy 433.844618 -350.772312) (xy 433.928477 -350.760255)
			(xy 434.013102 -350.756224) (xy 434.097727 -350.760255) (xy 434.181586 -350.772312) (xy 434.263919 -350.792286)
			(xy 434.343981 -350.819995) (xy 434.421046 -350.85519) (xy 434.494416 -350.89755) (xy 434.563428 -350.946693)
			(xy 434.627456 -351.002174) (xy 434.685921 -351.063489) (xy 434.738292 -351.130085) (xy 434.784095 -351.201357)
			(xy 434.822917 -351.27666) (xy 434.854405 -351.355312) (xy 434.878273 -351.436602) (xy 434.894307 -351.519792)
			(xy 434.90236 -351.604129) (xy 434.902864 -351.64649) (xy 434.902279 -351.691259) (xy 434.893275 -351.780343)
			(xy 434.875376 -351.868074) (xy 434.848764 -351.953566) (xy 434.831744 -351.994978) (xy 434.828186 -352.00457)
			(xy 434.828182 -352.025011) (xy 434.831744 -352.034602) (xy 434.848782 -352.076008) (xy 434.875415 -352.161497)
			(xy 434.893319 -352.24923) (xy 434.902312 -352.338319) (xy 434.902864 -352.38309) (xy 434.90247 -352.420184)
			(xy 434.896295 -352.494114) (xy 434.883986 -352.567273) (xy 434.875178 -352.603308) (xy 434.873347 -352.611669)
			(xy 434.874795 -352.628716) (xy 434.881755 -352.644345) (xy 434.88737 -352.650806) (xy 434.927756 -352.693732)
			(xy 434.940202 -352.690938) (xy 434.94901 -352.688645) (xy 434.964363 -352.678893) (xy 434.970174 -352.671888)
			(xy 434.995281 -352.639171) (xy 435.05068 -352.578072) (xy 435.111497 -352.522364) (xy 435.17721 -352.472524)
			(xy 435.247255 -352.428982) (xy 435.321029 -352.39211) (xy 435.3979 -352.362226) (xy 435.477207 -352.339586)
			(xy 435.558269 -352.324385) (xy 435.64039 -352.316753) (xy 435.681628 -352.316288) (xy 435.722723 -352.31674)
			(xy 435.804563 -352.324324) (xy 435.885355 -352.339426) (xy 435.964409 -352.361917) (xy 436.04105 -352.391604)
			(xy 436.114627 -352.428235) (xy 436.18451 -352.471497) (xy 436.250105 -352.521022) (xy 436.310851 -352.576386)
			(xy 436.366231 -352.637118) (xy 436.415773 -352.7027) (xy 436.459053 -352.772572) (xy 436.495703 -352.846139)
			(xy 436.52541 -352.922773) (xy 436.547921 -353.001821) (xy 436.563044 -353.082609) (xy 436.57065 -353.164447)
			(xy 436.571136 -353.205542) (xy 436.571136 -353.20605) (xy 436.570568 -353.25082) (xy 436.561569 -353.339906)
			(xy 436.543667 -353.427639) (xy 436.517044 -353.513129) (xy 436.500016 -353.554538) (xy 436.496425 -353.564121)
			(xy 436.496444 -353.58457) (xy 436.500016 -353.594162) (xy 436.517052 -353.635569) (xy 436.543684 -353.721058)
			(xy 436.561588 -353.808791) (xy 436.570583 -353.897879) (xy 436.571136 -353.94265) (xy 436.570568 -353.98742)
			(xy 436.561569 -354.076506) (xy 436.543667 -354.164239) (xy 436.517044 -354.249729) (xy 436.500016 -354.291138)
			(xy 436.496425 -354.300721) (xy 436.496444 -354.32117) (xy 436.500016 -354.330762) (xy 436.517046 -354.372136)
			(xy 436.543663 -354.457564) (xy 436.561565 -354.545233) (xy 436.570572 -354.634257) (xy 436.571136 -354.678996)
			(xy 436.571136 -354.67925) (xy 436.57064 -354.720357) (xy 436.56306 -354.80222) (xy 436.547959 -354.883035)
			(xy 436.525468 -354.962112) (xy 436.495777 -355.038776) (xy 436.45914 -355.112375) (xy 436.415869 -355.18228)
			(xy 436.366333 -355.247894) (xy 436.310956 -355.308659) (xy 436.250208 -355.364056) (xy 436.184609 -355.413612)
			(xy 436.114718 -355.456904) (xy 436.041131 -355.493565) (xy 435.964475 -355.523279) (xy 435.885405 -355.545796)
			(xy 435.804595 -355.560921) (xy 435.722735 -355.568527) (xy 435.681628 -355.569012) (xy 435.640018 -355.568519)
			(xy 435.557162 -355.560745) (xy 435.475393 -355.545272) (xy 435.395426 -355.522236) (xy 435.317957 -355.491836)
			(xy 435.243663 -355.454339) (xy 435.208172 -355.432614) (xy 435.199049 -355.42742) (xy 435.178322 -355.424214)
			(xy 435.158043 -355.429561) (xy 435.149498 -355.435662) (xy 435.115852 -355.46163) (xy 435.044461 -355.507757)
			(xy 434.968993 -355.546861) (xy 434.890138 -355.578584) (xy 434.808616 -355.602638) (xy 434.72517 -355.618802)
			(xy 434.640562 -355.626929) (xy 434.598064 -355.627432) (xy 434.556969 -355.626968) (xy 434.47513 -355.619383)
			(xy 434.39434 -355.604281) (xy 434.315287 -355.58179) (xy 434.238646 -355.552103) (xy 434.16507 -355.515472)
			(xy 434.095187 -355.472211) (xy 434.029593 -355.422687) (xy 433.968847 -355.367324) (xy 433.913467 -355.306593)
			(xy 433.863926 -355.241013) (xy 433.820645 -355.171141) (xy 433.783995 -355.097576) (xy 433.754287 -355.020943)
			(xy 433.731775 -354.941896) (xy 433.71665 -354.86111) (xy 433.709043 -354.779273) (xy 433.708556 -354.738178)
			(xy 433.708556 -354.73767) (xy 433.709098 -354.692899) (xy 433.718104 -354.603812) (xy 433.736014 -354.51608)
			(xy 433.762645 -354.430591) (xy 433.779676 -354.389182) (xy 433.783256 -354.379596) (xy 433.783245 -354.359149)
			(xy 433.779676 -354.349558) (xy 433.762646 -354.308149) (xy 433.736013 -354.222661) (xy 433.718107 -354.134928)
			(xy 433.70911 -354.045841) (xy 433.708556 -354.00107) (xy 433.708556 -353.989132) (xy 433.682076 -353.983189)
			(xy 433.629842 -353.968444) (xy 433.604162 -353.959668) (xy 433.595965 -353.957154) (xy 433.578831 -353.957154)
			(xy 433.570634 -353.959668) (xy 433.535422 -353.971642) (xy 433.463417 -353.990292) (xy 433.390095 -354.002797)
			(xy 433.315979 -354.009067) (xy 433.278788 -354.009452) (xy 433.241598 -354.009064) (xy 433.167486 -354.002773)
			(xy 433.094166 -353.990263) (xy 433.02216 -353.971623) (xy 432.986942 -353.959668) (xy 432.978745 -353.957154)
			(xy 432.961611 -353.957154) (xy 432.953414 -353.959668) (xy 432.918203 -353.971647) (xy 432.846198 -353.990296)
			(xy 432.772875 -354.0028) (xy 432.698759 -354.009068) (xy 432.661568 -354.009452) (xy 432.619631 -354.008992)
			(xy 432.536136 -354.001016) (xy 432.453778 -353.98514) (xy 432.373301 -353.961507) (xy 432.295436 -353.930332)
			(xy 432.220886 -353.891897) (xy 432.150327 -353.846549) (xy 432.084398 -353.7947) (xy 432.023696 -353.736819)
			(xy 431.968771 -353.673429) (xy 431.92012 -353.605106) (xy 431.878184 -353.532468) (xy 431.843342 -353.456173)
			(xy 431.815909 -353.376911) (xy 431.796136 -353.295401) (xy 431.784199 -353.21238) (xy 431.780208 -353.1286)
			(xy 428.243051 -353.1286) (xy 428.244022 -353.139047) (xy 428.244508 -353.180142) (xy 428.244508 -353.18065)
			(xy 428.243935 -353.22542) (xy 428.234936 -353.314506) (xy 428.217036 -353.402238) (xy 428.190415 -353.487729)
			(xy 428.173388 -353.529138) (xy 428.169793 -353.53872) (xy 428.169812 -353.559171) (xy 428.173388 -353.568762)
			(xy 428.190428 -353.610167) (xy 428.217058 -353.695657) (xy 428.23496 -353.783391) (xy 428.243955 -353.872479)
			(xy 428.244508 -353.91725) (xy 428.243935 -353.96202) (xy 428.234936 -354.051106) (xy 428.217036 -354.138838)
			(xy 428.190415 -354.224329) (xy 428.173388 -354.265738) (xy 428.169793 -354.27532) (xy 428.169812 -354.295771)
			(xy 428.173388 -354.305362) (xy 428.190417 -354.346737) (xy 428.217034 -354.432165) (xy 428.234937 -354.519833)
			(xy 428.243944 -354.608857) (xy 428.244508 -354.653596) (xy 428.244508 -354.65385) (xy 428.24394 -354.694955)
			(xy 428.23636 -354.776814) (xy 428.221262 -354.857624) (xy 428.198773 -354.936698) (xy 428.169085 -355.013359)
			(xy 428.132451 -355.086955) (xy 428.089184 -355.156857) (xy 428.039654 -355.22247) (xy 427.984281 -355.283233)
			(xy 427.923539 -355.33863) (xy 427.857946 -355.388186) (xy 427.788061 -355.431481) (xy 427.714479 -355.468143)
			(xy 427.63783 -355.497861) (xy 427.558765 -355.520382) (xy 427.47796 -355.535512) (xy 427.396104 -355.543124)
			(xy 427.355 -355.543612) (xy 427.31339 -355.543132) (xy 427.230533 -355.535356) (xy 427.148764 -355.519881)
			(xy 427.068797 -355.496842) (xy 426.991328 -355.46644) (xy 426.917035 -355.42894) (xy 426.881544 -355.407214)
			(xy 426.872433 -355.401996) (xy 426.851698 -355.398798) (xy 426.831415 -355.404156) (xy 426.82287 -355.410262)
			(xy 426.789234 -355.436243) (xy 426.717841 -355.482369) (xy 426.642371 -355.521471) (xy 426.563514 -355.553192)
			(xy 426.481991 -355.577244) (xy 426.398543 -355.593405) (xy 426.313935 -355.60153) (xy 426.271436 -355.602032)
			(xy 426.230342 -355.601499) (xy 426.148505 -355.593921) (xy 426.067716 -355.578825) (xy 425.988664 -355.55634)
			(xy 425.912023 -355.526659) (xy 425.838448 -355.490033) (xy 425.768565 -355.446777) (xy 425.70297 -355.397258)
			(xy 425.642223 -355.341899) (xy 425.586843 -355.281172) (xy 425.537301 -355.215595) (xy 425.49402 -355.145727)
			(xy 425.457368 -355.072164) (xy 425.42766 -354.995534) (xy 425.405147 -354.91649) (xy 425.390023 -354.835706)
			(xy 425.382415 -354.753872) (xy 425.381928 -354.712778) (xy 425.381928 -354.71227) (xy 425.382471 -354.667499)
			(xy 425.391478 -354.578412) (xy 425.409387 -354.49068) (xy 425.436017 -354.40519) (xy 425.453048 -354.363782)
			(xy 425.45663 -354.354196) (xy 425.456619 -354.333749) (xy 425.453048 -354.324158) (xy 425.436017 -354.28275)
			(xy 425.409384 -354.197261) (xy 425.391479 -354.109528) (xy 425.382482 -354.020441) (xy 425.381928 -353.97567)
			(xy 425.381928 -353.963732) (xy 425.35545 -353.957782) (xy 425.303215 -353.943042) (xy 425.277534 -353.934268)
			(xy 425.269337 -353.931754) (xy 425.252203 -353.931754) (xy 425.244006 -353.934268) (xy 425.208787 -353.946222)
			(xy 425.136785 -353.964878) (xy 425.063465 -353.977388) (xy 424.98935 -353.983664) (xy 424.95216 -353.984052)
			(xy 424.914971 -353.983643) (xy 424.840858 -353.977359) (xy 424.767539 -353.964855) (xy 424.695532 -353.94622)
			(xy 424.660314 -353.934268) (xy 424.652117 -353.931754) (xy 424.634983 -353.931754) (xy 424.626786 -353.934268)
			(xy 424.591569 -353.946227) (xy 424.519566 -353.964882) (xy 424.446245 -353.977391) (xy 424.37213 -353.983665)
			(xy 424.33494 -353.984052) (xy 424.293 -353.983611) (xy 424.209499 -353.975641) (xy 424.127133 -353.95977)
			(xy 424.04665 -353.936141) (xy 423.968777 -353.904968) (xy 423.89422 -353.866534) (xy 423.823654 -353.821187)
			(xy 423.757718 -353.769337) (xy 423.697009 -353.711455) (xy 423.642078 -353.648063) (xy 423.593421 -353.579737)
			(xy 423.55148 -353.507095) (xy 423.516634 -353.430795) (xy 423.489198 -353.351528) (xy 423.469422 -353.270012)
			(xy 423.457484 -353.186985) (xy 423.453493 -353.1032) (xy 344.34922 -353.1032) (xy 344.346818 -353.129131)
			(xy 344.331712 -353.20995) (xy 344.309211 -353.289031) (xy 344.279508 -353.365698) (xy 344.242856 -353.439296)
			(xy 344.199569 -353.509197) (xy 344.150015 -353.574806) (xy 344.094618 -353.635561) (xy 344.03385 -353.690944)
			(xy 343.968231 -353.740483) (xy 343.898319 -353.783755) (xy 343.824713 -353.82039) (xy 343.748039 -353.850075)
			(xy 343.668954 -353.872558) (xy 343.58813 -353.887646) (xy 343.50626 -353.895211) (xy 343.46515 -353.89566)
			(xy 343.421566 -353.895134) (xy 343.334811 -353.886653) (xy 343.249302 -353.869729) (xy 343.165858 -353.844524)
			(xy 343.085279 -353.81128) (xy 343.046558 -353.791266) (xy 343.035092 -353.785848) (xy 343.009764 -353.785848)
			(xy 342.998298 -353.791266) (xy 342.959077 -353.812027) (xy 342.877306 -353.846516) (xy 342.792508 -353.872694)
			(xy 342.705525 -353.890299) (xy 342.617221 -353.899159) (xy 342.572848 -353.899724) (xy 342.571578 -353.899724)
			(xy 342.533421 -353.899288) (xy 342.457393 -353.892705) (xy 342.382209 -353.879623) (xy 342.308424 -353.86014)
			(xy 342.272366 -353.847654) (xy 342.26405 -353.845068) (xy 342.246646 -353.845068) (xy 342.23833 -353.847654)
			(xy 342.202121 -353.860189) (xy 342.128019 -353.879707) (xy 342.052513 -353.892787) (xy 341.976163 -353.899332)
			(xy 341.937848 -353.899724) (xy 341.899532 -353.899341) (xy 341.823179 -353.892813) (xy 341.747672 -353.879733)
			(xy 341.673573 -353.860197) (xy 341.637366 -353.847654) (xy 341.62905 -353.845068) (xy 341.611646 -353.845068)
			(xy 341.60333 -353.847654) (xy 341.567121 -353.860189) (xy 341.493019 -353.879707) (xy 341.417513 -353.892787)
			(xy 341.341163 -353.899332) (xy 341.302848 -353.899724) (xy 341.264532 -353.899341) (xy 341.188179 -353.892813)
			(xy 341.112672 -353.879733) (xy 341.038573 -353.860197) (xy 341.002366 -353.847654) (xy 340.99405 -353.845068)
			(xy 340.976646 -353.845068) (xy 340.96833 -353.847654) (xy 340.932121 -353.860189) (xy 340.858019 -353.879707)
			(xy 340.782513 -353.892787) (xy 340.706163 -353.899332) (xy 340.667848 -353.899724) (xy 340.626539 -353.899263)
			(xy 340.544274 -353.89164) (xy 340.463071 -353.876418) (xy 340.38363 -353.853729) (xy 340.306637 -353.823768)
			(xy 340.232755 -353.786793) (xy 340.19744 -353.765358) (xy 340.189803 -353.761082) (xy 340.172701 -353.75742)
			(xy 340.155358 -353.759679) (xy 340.147402 -353.763326) (xy 340.109501 -353.782381) (xy 340.030769 -353.813979)
			(xy 339.949386 -353.837938) (xy 339.866091 -353.85404) (xy 339.781642 -353.862138) (xy 339.739224 -353.86264)
			(xy 339.73897 -353.86264) (xy 339.697862 -353.862216) (xy 339.615997 -353.854629) (xy 339.535181 -353.839522)
			(xy 339.456103 -353.817024) (xy 339.379438 -353.787327) (xy 339.30584 -353.750684) (xy 339.235936 -353.707408)
			(xy 339.170322 -353.657867) (xy 339.109558 -353.602485) (xy 339.054162 -353.541734) (xy 339.004606 -353.476131)
			(xy 338.961314 -353.406237) (xy 338.924655 -353.332646) (xy 338.89494 -353.255988) (xy 338.872425 -353.176916)
			(xy 338.857299 -353.096103) (xy 338.849693 -353.01424) (xy 338.849208 -352.973132) (xy 195.744851 -352.973132)
			(xy 195.771754 -353.027135) (xy 195.80147 -353.103792) (xy 195.823987 -353.182863) (xy 195.839114 -353.263674)
			(xy 195.846722 -353.345537) (xy 195.847208 -353.386644) (xy 195.846646 -353.431414) (xy 195.837635 -353.520499)
			(xy 195.81973 -353.60823) (xy 195.793111 -353.693721) (xy 195.776088 -353.735132) (xy 195.772497 -353.744715)
			(xy 195.772513 -353.765165) (xy 195.776088 -353.774756) (xy 195.793114 -353.816166) (xy 195.81975 -353.901654)
			(xy 195.837657 -353.989386) (xy 195.846654 -354.078474) (xy 195.847208 -354.123244) (xy 195.846646 -354.168014)
			(xy 195.837635 -354.257099) (xy 195.81973 -354.34483) (xy 195.793111 -354.430321) (xy 195.776088 -354.471732)
			(xy 195.772497 -354.481315) (xy 195.772513 -354.501765) (xy 195.776088 -354.511356) (xy 195.793114 -354.552766)
			(xy 195.81975 -354.638254) (xy 195.837657 -354.725986) (xy 195.846654 -354.815074) (xy 195.847208 -354.859844)
			(xy 195.84679 -354.900955) (xy 195.839198 -354.982827) (xy 195.824083 -355.063648) (xy 195.801575 -355.14273)
			(xy 195.771864 -355.219398) (xy 195.742079 -355.279198) (xy 285.476188 -355.279198) (xy 285.476597 -355.238082)
			(xy 285.484185 -355.1562) (xy 285.499295 -355.075367) (xy 285.5218 -354.996274) (xy 285.551507 -354.919594)
			(xy 285.588163 -354.845983) (xy 285.631455 -354.776069) (xy 285.681013 -354.710447) (xy 285.736414 -354.649677)
			(xy 285.797187 -354.594279) (xy 285.862811 -354.544725) (xy 285.932729 -354.501438) (xy 286.006342 -354.464786)
			(xy 286.083023 -354.435084) (xy 286.162118 -354.412584) (xy 286.242951 -354.397477) (xy 286.324834 -354.389894)
			(xy 286.36595 -354.389436) (xy 286.404239 -354.389856) (xy 286.480533 -354.39646) (xy 286.555976 -354.409605)
			(xy 286.630007 -354.429194) (xy 286.666178 -354.44176) (xy 286.674615 -354.444411) (xy 286.692285 -354.444411)
			(xy 286.700722 -354.44176) (xy 286.736903 -354.429226) (xy 286.810935 -354.409651) (xy 286.886373 -354.396501)
			(xy 286.962662 -354.389874) (xy 287.00095 -354.389436) (xy 287.039239 -354.389856) (xy 287.115533 -354.39646)
			(xy 287.190976 -354.409605) (xy 287.265007 -354.429194) (xy 287.301178 -354.44176) (xy 287.309615 -354.444411)
			(xy 287.327285 -354.444411) (xy 287.335722 -354.44176) (xy 287.371903 -354.429226) (xy 287.445935 -354.409651)
			(xy 287.521373 -354.396501) (xy 287.597662 -354.389874) (xy 287.63595 -354.389436) (xy 287.674239 -354.389856)
			(xy 287.750533 -354.39646) (xy 287.825976 -354.409605) (xy 287.900007 -354.429194) (xy 287.936178 -354.44176)
			(xy 287.944615 -354.444411) (xy 287.962285 -354.444411) (xy 287.970722 -354.44176) (xy 288.006903 -354.429226)
			(xy 288.080935 -354.409651) (xy 288.156373 -354.396501) (xy 288.232662 -354.389874) (xy 288.27095 -354.389436)
			(xy 288.309239 -354.389856) (xy 288.385533 -354.39646) (xy 288.460976 -354.409605) (xy 288.535007 -354.429194)
			(xy 288.571178 -354.44176) (xy 288.579615 -354.444411) (xy 288.597285 -354.444411) (xy 288.605722 -354.44176)
			(xy 288.641903 -354.429226) (xy 288.715935 -354.409651) (xy 288.791373 -354.396501) (xy 288.867662 -354.389874)
			(xy 288.90595 -354.389436) (xy 288.947064 -354.389946) (xy 289.028942 -354.397529) (xy 289.10977 -354.412634)
			(xy 289.18886 -354.435133) (xy 289.265537 -354.464834) (xy 289.339146 -354.501483) (xy 289.409059 -354.544768)
			(xy 289.47468 -354.594319) (xy 289.535449 -354.649714) (xy 289.590847 -354.71048) (xy 289.640402 -354.776098)
			(xy 289.683691 -354.846009) (xy 289.720345 -354.919615) (xy 289.75005 -354.99629) (xy 289.772554 -355.075379)
			(xy 289.787664 -355.156207) (xy 289.795251 -355.238084) (xy 289.795712 -355.279198) (xy 289.795298 -355.318061)
			(xy 289.788487 -355.395488) (xy 289.77495 -355.472025) (xy 289.75479 -355.547092) (xy 289.741864 -355.583744)
			(xy 289.739034 -355.592628) (xy 289.739308 -355.611259) (xy 289.742372 -355.620066) (xy 289.757559 -355.659473)
			(xy 289.781314 -355.740522) (xy 289.797291 -355.823456) (xy 289.805346 -355.907529) (xy 289.805872 -355.949758)
			(xy 289.805454 -355.988048) (xy 289.79885 -356.064341) (xy 289.785704 -356.139784) (xy 289.766114 -356.213815)
			(xy 289.753548 -356.249986) (xy 289.750918 -356.258428) (xy 289.750905 -356.276094) (xy 289.753548 -356.28453)
			(xy 289.766084 -356.32071) (xy 289.785659 -356.394742) (xy 289.798808 -356.470181) (xy 289.805435 -356.54647)
			(xy 289.805872 -356.584758) (xy 289.805362 -356.625872) (xy 289.797778 -356.707749) (xy 289.782672 -356.788578)
			(xy 289.760173 -356.867667) (xy 289.730472 -356.944344) (xy 289.693822 -357.017952) (xy 289.650537 -357.087865)
			(xy 289.600986 -357.153486) (xy 289.545592 -357.214255) (xy 289.484826 -357.269653) (xy 289.419208 -357.319208)
			(xy 289.349298 -357.362497) (xy 289.275691 -357.399151) (xy 289.199017 -357.428856) (xy 289.119928 -357.45136)
			(xy 289.039101 -357.466471) (xy 288.957224 -357.474059) (xy 288.91611 -357.47452) (xy 288.87782 -357.474114)
			(xy 288.801526 -357.467506) (xy 288.726084 -357.454357) (xy 288.652053 -357.434764) (xy 288.615882 -357.422196)
			(xy 288.607445 -357.419545) (xy 288.589775 -357.419545) (xy 288.581338 -357.422196) (xy 288.54516 -357.434739)
			(xy 288.471127 -357.454312) (xy 288.395688 -357.46746) (xy 288.319398 -357.474084) (xy 288.28111 -357.47452)
			(xy 288.24282 -357.474114) (xy 288.166526 -357.467506) (xy 288.091084 -357.454357) (xy 288.017053 -357.434764)
			(xy 287.980882 -357.422196) (xy 287.972445 -357.419545) (xy 287.954775 -357.419545) (xy 287.946338 -357.422196)
			(xy 287.91016 -357.434739) (xy 287.836127 -357.454312) (xy 287.760688 -357.46746) (xy 287.684398 -357.474084)
			(xy 287.64611 -357.47452) (xy 287.60782 -357.474114) (xy 287.531526 -357.467506) (xy 287.456084 -357.454357)
			(xy 287.382053 -357.434764) (xy 287.345882 -357.422196) (xy 287.337445 -357.419545) (xy 287.319775 -357.419545)
			(xy 287.311338 -357.422196) (xy 287.27516 -357.434739) (xy 287.201127 -357.454312) (xy 287.125688 -357.46746)
			(xy 287.049398 -357.474084) (xy 287.01111 -357.47452) (xy 286.97282 -357.474114) (xy 286.896526 -357.467506)
			(xy 286.821084 -357.454357) (xy 286.747053 -357.434764) (xy 286.710882 -357.422196) (xy 286.702445 -357.419545)
			(xy 286.684775 -357.419545) (xy 286.676338 -357.422196) (xy 286.64016 -357.434739) (xy 286.566127 -357.454312)
			(xy 286.490688 -357.46746) (xy 286.414398 -357.474084) (xy 286.37611 -357.47452) (xy 286.334994 -357.474092)
			(xy 286.253113 -357.466505) (xy 286.172281 -357.451395) (xy 286.093188 -357.428892) (xy 286.016509 -357.399186)
			(xy 285.942899 -357.362532) (xy 285.872984 -357.319241) (xy 285.807362 -357.269685) (xy 285.746593 -357.214284)
			(xy 285.691195 -357.153513) (xy 285.641641 -357.08789) (xy 285.598353 -357.017973) (xy 285.561701 -356.944361)
			(xy 285.531998 -356.867681) (xy 285.509497 -356.788588) (xy 285.49439 -356.707755) (xy 285.486807 -356.625874)
			(xy 285.486348 -356.584758) (xy 285.48677 -356.546469) (xy 285.493373 -356.470175) (xy 285.506518 -356.394732)
			(xy 285.526107 -356.320701) (xy 285.538672 -356.28453) (xy 285.541343 -356.276098) (xy 285.541329 -356.258423)
			(xy 285.538672 -356.249986) (xy 285.526141 -356.213804) (xy 285.506565 -356.139773) (xy 285.493414 -356.064334)
			(xy 285.486786 -355.988046) (xy 285.486348 -355.949758) (xy 285.486781 -355.910896) (xy 285.493587 -355.833469)
			(xy 285.507119 -355.756932) (xy 285.527272 -355.681865) (xy 285.540196 -355.645212) (xy 285.542998 -355.636321)
			(xy 285.542744 -355.617697) (xy 285.539688 -355.60889) (xy 285.524486 -355.569489) (xy 285.500735 -355.488437)
			(xy 285.484763 -355.405502) (xy 285.476712 -355.321427) (xy 285.476188 -355.279198) (xy 195.742079 -355.279198)
			(xy 195.735206 -355.292996) (xy 195.691912 -355.362897) (xy 195.642352 -355.428505) (xy 195.586949 -355.48926)
			(xy 195.526176 -355.544642) (xy 195.460551 -355.59418) (xy 195.390636 -355.637451) (xy 195.317025 -355.674085)
			(xy 195.240348 -355.703769) (xy 195.161258 -355.726251) (xy 195.080432 -355.741339) (xy 194.998557 -355.748903)
			(xy 194.957446 -355.749352) (xy 194.915842 -355.74888) (xy 194.832994 -355.741147) (xy 194.75123 -355.725716)
			(xy 194.671262 -355.702722) (xy 194.593789 -355.672366) (xy 194.519488 -355.634911) (xy 194.48399 -355.613208)
			(xy 194.474858 -355.608031) (xy 194.454138 -355.60482) (xy 194.433861 -355.61016) (xy 194.425316 -355.616256)
			(xy 194.391667 -355.642178) (xy 194.320293 -355.688236) (xy 194.244854 -355.727283) (xy 194.166037 -355.758962)
			(xy 194.08456 -355.782986) (xy 194.001164 -355.799135) (xy 193.916608 -355.807262) (xy 193.874136 -355.807772)
			(xy 193.873882 -355.807772) (xy 193.832775 -355.807305) (xy 193.750912 -355.799719) (xy 193.670098 -355.784614)
			(xy 193.591023 -355.762118) (xy 193.514359 -355.732423) (xy 193.440762 -355.695782) (xy 193.370859 -355.652509)
			(xy 193.305245 -355.602971) (xy 193.244482 -355.547592) (xy 193.189086 -355.486844) (xy 193.13953 -355.421244)
			(xy 193.096237 -355.351353) (xy 193.059577 -355.277766) (xy 193.029861 -355.201111) (xy 193.007343 -355.122041)
			(xy 192.992215 -355.041231) (xy 192.984607 -354.959371) (xy 192.98412 -354.918264) (xy 192.984683 -354.873494)
			(xy 192.993693 -354.784409) (xy 193.011598 -354.696678) (xy 193.038217 -354.611187) (xy 193.05524 -354.569776)
			(xy 193.058825 -354.560191) (xy 193.058812 -354.539743) (xy 193.05524 -354.530152) (xy 193.03824 -354.4888)
			(xy 193.011628 -354.403438) (xy 192.99372 -354.315836) (xy 192.984697 -354.226879) (xy 192.98412 -354.182172)
			(xy 192.98412 -354.181156) (xy 192.984374 -354.169726) (xy 192.957895 -354.163781) (xy 192.90566 -354.149038)
			(xy 192.87998 -354.140262) (xy 192.871783 -354.137748) (xy 192.854649 -354.137748) (xy 192.846452 -354.140262)
			(xy 192.811236 -354.152209) (xy 192.739226 -354.170796) (xy 192.665903 -354.183236) (xy 192.591792 -354.18944)
			(xy 192.554606 -354.189792) (xy 192.517422 -354.189422) (xy 192.443314 -354.1832) (xy 192.369994 -354.170758)
			(xy 192.297983 -354.152184) (xy 192.26276 -354.140262) (xy 192.254563 -354.137748) (xy 192.237429 -354.137748)
			(xy 192.229232 -354.140262) (xy 192.19413 -354.15215) (xy 192.122374 -354.1707) (xy 192.049311 -354.183146)
			(xy 191.97546 -354.189399) (xy 191.938402 -354.189792) (xy 191.937386 -354.189792) (xy 191.89546 -354.189345)
			(xy 191.811988 -354.181373) (xy 191.729651 -354.165503) (xy 191.649196 -354.141878) (xy 191.57135 -354.110712)
			(xy 191.49682 -354.072288) (xy 191.42628 -354.026953) (xy 191.360368 -353.975119) (xy 191.299682 -353.917254)
			(xy 191.244771 -353.853882) (xy 191.196132 -353.785578) (xy 191.154206 -353.71296) (xy 191.119373 -353.636685)
			(xy 191.091948 -353.557444) (xy 191.07218 -353.475956) (xy 191.060246 -353.392957) (xy 191.056256 -353.3092)
			(xy 187.519078 -353.3092) (xy 187.520094 -353.320137) (xy 187.52058 -353.361244) (xy 187.52002 -353.406014)
			(xy 187.511009 -353.495099) (xy 187.493104 -353.58283) (xy 187.466484 -353.668321) (xy 187.44946 -353.709732)
			(xy 187.44587 -353.719315) (xy 187.445886 -353.739765) (xy 187.44946 -353.749356) (xy 187.466484 -353.790767)
			(xy 187.493121 -353.876254) (xy 187.511029 -353.963986) (xy 187.520026 -354.053074) (xy 187.52058 -354.097844)
			(xy 187.52002 -354.142614) (xy 187.511009 -354.231699) (xy 187.493104 -354.31943) (xy 187.466484 -354.404921)
			(xy 187.44946 -354.446332) (xy 187.44587 -354.455915) (xy 187.445886 -354.476365) (xy 187.44946 -354.485956)
			(xy 187.466484 -354.527367) (xy 187.493121 -354.612854) (xy 187.511029 -354.700586) (xy 187.520026 -354.789674)
			(xy 187.52058 -354.834444) (xy 187.520189 -354.875556) (xy 187.512597 -354.957429) (xy 187.497482 -355.038252)
			(xy 187.474973 -355.117336) (xy 187.445261 -355.194004) (xy 187.408601 -355.267604) (xy 187.365306 -355.337506)
			(xy 187.315744 -355.403115) (xy 187.260339 -355.46387) (xy 187.199564 -355.519252) (xy 187.133937 -355.56879)
			(xy 187.064019 -355.61206) (xy 186.990406 -355.648693) (xy 186.913727 -355.678376) (xy 186.834635 -355.700857)
			(xy 186.753806 -355.715942) (xy 186.67193 -355.723505) (xy 186.630818 -355.723952) (xy 186.589214 -355.723494)
			(xy 186.506365 -355.715758) (xy 186.424601 -355.700325) (xy 186.344633 -355.677328) (xy 186.267161 -355.646969)
			(xy 186.192859 -355.609513) (xy 186.157362 -355.587808) (xy 186.148243 -355.582606) (xy 186.127514 -355.579404)
			(xy 186.107233 -355.584754) (xy 186.098688 -355.590856) (xy 186.065049 -355.616791) (xy 185.993673 -355.662848)
			(xy 185.918232 -355.701893) (xy 185.839413 -355.73357) (xy 185.757935 -355.757592) (xy 185.674537 -355.773739)
			(xy 185.589981 -355.781864) (xy 185.547508 -355.782372) (xy 185.547254 -355.782372) (xy 185.506147 -355.781931)
			(xy 185.424283 -355.774343) (xy 185.343469 -355.759235) (xy 185.264393 -355.736737) (xy 185.187729 -355.70704)
			(xy 185.114132 -355.670398) (xy 185.044229 -355.627122) (xy 184.978615 -355.577583) (xy 184.917852 -355.522202)
			(xy 184.862456 -355.461452) (xy 184.812901 -355.395851) (xy 184.769609 -355.325959) (xy 184.732948 -355.252371)
			(xy 184.703232 -355.175714) (xy 184.680715 -355.096644) (xy 184.665587 -355.015833) (xy 184.657979 -354.933971)
			(xy 184.657492 -354.892864) (xy 184.658057 -354.848094) (xy 184.667066 -354.759009) (xy 184.684971 -354.671278)
			(xy 184.711589 -354.585787) (xy 184.728612 -354.544376) (xy 184.732199 -354.534792) (xy 184.732185 -354.514343)
			(xy 184.728612 -354.504752) (xy 184.711616 -354.463398) (xy 184.685002 -354.378037) (xy 184.667093 -354.290435)
			(xy 184.658069 -354.201478) (xy 184.657492 -354.156772) (xy 184.657492 -354.155756) (xy 184.657746 -354.144326)
			(xy 184.631266 -354.138384) (xy 184.579032 -354.123639) (xy 184.553352 -354.114862) (xy 184.545155 -354.112348)
			(xy 184.528021 -354.112348) (xy 184.519824 -354.114862) (xy 184.484602 -354.126789) (xy 184.412594 -354.145381)
			(xy 184.339273 -354.157827) (xy 184.265163 -354.164037) (xy 184.227978 -354.164392) (xy 184.190794 -354.16403)
			(xy 184.116686 -354.157806) (xy 184.043366 -354.145361) (xy 183.971355 -354.126785) (xy 183.936132 -354.114862)
			(xy 183.927935 -354.112348) (xy 183.910801 -354.112348) (xy 183.902604 -354.114862) (xy 183.867505 -354.126757)
			(xy 183.795747 -354.145305) (xy 183.722684 -354.157749) (xy 183.648832 -354.164001) (xy 183.611774 -354.164392)
			(xy 183.610758 -354.164392) (xy 183.568833 -354.163944) (xy 183.485362 -354.155969) (xy 183.403028 -354.140097)
			(xy 183.322575 -354.11647) (xy 183.244732 -354.085304) (xy 183.170204 -354.046879) (xy 183.099666 -354.001544)
			(xy 183.033756 -353.949709) (xy 182.973072 -353.891844) (xy 182.918163 -353.828473) (xy 182.869527 -353.760169)
			(xy 182.827603 -353.687552) (xy 182.792771 -353.611278) (xy 182.765347 -353.532039) (xy 182.745579 -353.450553)
			(xy 182.733646 -353.367555) (xy 182.729656 -353.2838) (xy 78.346936 -353.2838) (xy 78.321217 -353.348042)
			(xy 78.282395 -353.423345) (xy 78.236592 -353.494617) (xy 78.184221 -353.561213) (xy 78.125756 -353.622528)
			(xy 78.061728 -353.678009) (xy 77.992716 -353.727152) (xy 77.919346 -353.769512) (xy 77.842281 -353.804707)
			(xy 77.762219 -353.832416) (xy 77.679886 -353.85239) (xy 77.596027 -353.864447) (xy 77.511402 -353.868479)
			(xy 77.426777 -353.864447) (xy 77.342918 -353.85239) (xy 77.260585 -353.832416) (xy 77.180523 -353.804707)
			(xy 77.103458 -353.769512) (xy 77.030088 -353.727152) (xy 76.961076 -353.678009) (xy 76.897048 -353.622528)
			(xy 76.838583 -353.561213) (xy 76.786212 -353.494617) (xy 76.740409 -353.423345) (xy 76.701587 -353.348042)
			(xy 76.670099 -353.26939) (xy 76.646231 -353.1881) (xy 76.630197 -353.10491) (xy 76.622144 -353.020573)
			(xy 76.62164 -352.978212) (xy 76.622159 -352.935266) (xy 76.630462 -352.849776) (xy 76.646954 -352.765482)
			(xy 76.671481 -352.683166) (xy 76.687172 -352.643186) (xy 76.690418 -352.63393) (xy 76.690431 -352.614336)
			(xy 76.687172 -352.605086) (xy 76.671458 -352.565114) (xy 76.646914 -352.4828) (xy 76.630427 -352.398503)
			(xy 76.622152 -352.313007) (xy 76.62164 -352.27006) (xy 76.62164 -352.269806) (xy 76.622244 -352.224161)
			(xy 76.631638 -352.133355) (xy 76.650266 -352.043985) (xy 76.66355 -352.000312) (xy 76.665996 -351.9913)
			(xy 76.664956 -351.972672) (xy 76.661518 -351.96399) (xy 76.642856 -351.920903) (xy 76.61365 -351.831658)
			(xy 76.594004 -351.739834) (xy 76.584137 -351.646451) (xy 76.58354 -351.5995) (xy 75.70064 -351.5995)
			(xy 75.701144 -351.637854) (xy 75.70053 -351.683499) (xy 75.691141 -351.774304) (xy 75.672516 -351.863674)
			(xy 75.659234 -351.907348) (xy 75.65681 -351.916364) (xy 75.657836 -351.934988) (xy 75.661266 -351.94367)
			(xy 75.679947 -351.986749) (xy 75.709149 -352.075997) (xy 75.728789 -352.167824) (xy 75.738651 -352.261208)
			(xy 75.739244 -352.30816) (xy 75.738798 -352.348493) (xy 75.731529 -352.428831) (xy 75.71702 -352.508181)
			(xy 75.69539 -352.585893) (xy 75.666817 -352.661328) (xy 75.649582 -352.697796) (xy 75.645066 -352.708391)
			(xy 75.645063 -352.731399) (xy 75.649582 -352.741992) (xy 75.666809 -352.778407) (xy 75.695346 -352.853748)
			(xy 75.716963 -352.931359) (xy 75.731481 -353.010605) (xy 75.738782 -353.090838) (xy 75.739244 -353.13112)
			(xy 75.739244 -353.131374) (xy 75.73874 -353.173735) (xy 75.730687 -353.258072) (xy 75.714653 -353.341262)
			(xy 75.690785 -353.422552) (xy 75.659297 -353.501204) (xy 75.620475 -353.576507) (xy 75.574672 -353.647779)
			(xy 75.522301 -353.714375) (xy 75.463836 -353.77569) (xy 75.399808 -353.831171) (xy 75.330796 -353.880314)
			(xy 75.257426 -353.922674) (xy 75.180361 -353.957869) (xy 75.100299 -353.985578) (xy 75.017966 -354.005552)
			(xy 74.934107 -354.017609) (xy 74.849482 -354.021641) (xy 74.764857 -354.017609) (xy 74.680998 -354.005552)
			(xy 74.598665 -353.985578) (xy 74.518603 -353.957869) (xy 74.441538 -353.922674) (xy 74.368168 -353.880314)
			(xy 74.299156 -353.831171) (xy 74.235128 -353.77569) (xy 74.176663 -353.714375) (xy 74.124292 -353.647779)
			(xy 74.078489 -353.576507) (xy 74.039667 -353.501204) (xy 74.008179 -353.422552) (xy 73.984311 -353.341262)
			(xy 73.968277 -353.258072) (xy 73.960224 -353.173735) (xy 73.95972 -353.131374) (xy 73.960164 -353.091034)
			(xy 73.96747 -353.010685) (xy 73.982028 -352.931329) (xy 74.003719 -352.85362) (xy 74.032363 -352.778196)
			(xy 74.049636 -352.741738) (xy 74.054225 -352.731091) (xy 74.054231 -352.707932) (xy 74.049636 -352.697288)
			(xy 74.032445 -352.660861) (xy 74.003936 -352.58552) (xy 73.98236 -352.50791) (xy 73.967893 -352.428665)
			(xy 73.960655 -352.348437) (xy 73.960228 -352.30816) (xy 73.960797 -352.262521) (xy 73.970094 -352.171718)
			(xy 73.988639 -352.082344) (xy 74.001884 -352.038666) (xy 74.004352 -352.029659) (xy 74.003297 -352.011026)
			(xy 73.999852 -352.002344) (xy 73.981136 -351.959272) (xy 73.95186 -351.870033) (xy 73.932154 -351.778206)
			(xy 73.922237 -351.684813) (xy 73.92162 -351.637854) (xy 2.509012 -351.637854) (xy 2.509012 -358.071674)
			(xy 14.438884 -358.071674) (xy 14.438884 -357.208074) (xy 14.43937 -357.180805) (xy 14.447132 -357.126821)
			(xy 14.462497 -357.074491) (xy 14.485154 -357.024881) (xy 14.51464 -356.979) (xy 14.550355 -356.937783)
			(xy 14.591572 -356.902068) (xy 14.637453 -356.872582) (xy 14.687063 -356.849925) (xy 14.739393 -356.83456)
			(xy 14.793377 -356.826798) (xy 14.847915 -356.826798) (xy 14.901899 -356.83456) (xy 14.954229 -356.849925)
			(xy 15.003839 -356.872582) (xy 15.04972 -356.902068) (xy 15.090937 -356.937783) (xy 15.126652 -356.979)
			(xy 15.156138 -357.024881) (xy 15.178795 -357.074491) (xy 15.19416 -357.126821) (xy 15.201922 -357.180805)
			(xy 15.202408 -357.208074) (xy 15.202408 -358.071674) (xy 15.201922 -358.098943) (xy 15.19416 -358.152927)
			(xy 15.178795 -358.205257) (xy 15.156138 -358.254867) (xy 15.126652 -358.300748) (xy 15.090937 -358.341965)
			(xy 15.04972 -358.37768) (xy 15.003839 -358.407166) (xy 14.954229 -358.429823) (xy 14.901899 -358.445188)
			(xy 14.847915 -358.45295) (xy 14.793377 -358.45295) (xy 14.739393 -358.445188) (xy 14.687063 -358.429823)
			(xy 14.637453 -358.407166) (xy 14.591572 -358.37768) (xy 14.550355 -358.341965) (xy 14.51464 -358.300748)
			(xy 14.485154 -358.254867) (xy 14.462497 -358.205257) (xy 14.447132 -358.152927) (xy 14.43937 -358.098943)
			(xy 14.438884 -358.071674) (xy 2.509012 -358.071674) (xy 2.509012 -358.549194) (xy 40.47998 -358.549194)
			(xy 40.47998 -358.548686) (xy 40.480371 -358.510677) (xy 40.486871 -358.434938) (xy 40.499812 -358.36003)
			(xy 40.519101 -358.286501) (xy 40.544596 -358.214886) (xy 40.55999 -358.180132) (xy 40.563435 -358.171803)
			(xy 40.56487 -358.153848) (xy 40.562784 -358.14508) (xy 40.551663 -358.104882) (xy 40.536092 -358.022938)
			(xy 40.528245 -357.939897) (xy 40.527732 -357.898192) (xy 40.528135 -357.859902) (xy 40.534744 -357.783608)
			(xy 40.547894 -357.708165) (xy 40.567488 -357.634135) (xy 40.580056 -357.597964) (xy 40.58271 -357.589528)
			(xy 40.582708 -357.571857) (xy 40.580056 -357.56342) (xy 40.567506 -357.527245) (xy 40.547935 -357.453211)
			(xy 40.53479 -357.37777) (xy 40.528167 -357.30148) (xy 40.527732 -357.263192) (xy 40.528236 -357.220831)
			(xy 40.536289 -357.136494) (xy 40.552323 -357.053304) (xy 40.576191 -356.972014) (xy 40.607679 -356.893362)
			(xy 40.646501 -356.818059) (xy 40.692304 -356.746787) (xy 40.744675 -356.680191) (xy 40.80314 -356.618876)
			(xy 40.867168 -356.563395) (xy 40.93618 -356.514252) (xy 41.00955 -356.471892) (xy 41.086615 -356.436697)
			(xy 41.166677 -356.408988) (xy 41.24901 -356.389014) (xy 41.332869 -356.376957) (xy 41.417494 -356.372926)
			(xy 41.502119 -356.376957) (xy 41.585978 -356.389014) (xy 41.668311 -356.408988) (xy 41.748373 -356.436697)
			(xy 41.825438 -356.471892) (xy 41.898808 -356.514252) (xy 41.96782 -356.563395) (xy 42.031848 -356.618876)
			(xy 42.090313 -356.680191) (xy 42.142684 -356.746787) (xy 42.188487 -356.818059) (xy 42.227309 -356.893362)
			(xy 42.258797 -356.972014) (xy 42.282665 -357.053304) (xy 42.298699 -357.136494) (xy 42.306752 -357.220831)
			(xy 42.307256 -357.263192) (xy 42.306849 -357.301482) (xy 42.300241 -357.377776) (xy 42.287093 -357.453218)
			(xy 42.2675 -357.527249) (xy 42.254932 -357.56342) (xy 42.252286 -357.571858) (xy 42.252283 -357.589527)
			(xy 42.254932 -357.597964) (xy 42.267477 -357.634141) (xy 42.28705 -357.708174) (xy 42.300196 -357.783614)
			(xy 42.30682 -357.859904) (xy 42.307256 -357.898192) (xy 42.307256 -357.8987) (xy 42.306856 -357.936708)
			(xy 42.300359 -358.012447) (xy 42.287419 -358.087355) (xy 42.268132 -358.160885) (xy 42.242639 -358.2325)
			(xy 42.227246 -358.267254) (xy 42.223809 -358.275586) (xy 42.222368 -358.293538) (xy 42.224452 -358.302306)
			(xy 42.23557 -358.342505) (xy 42.251142 -358.424449) (xy 42.258991 -358.507489) (xy 42.259032 -358.51084)
			(xy 43.046396 -358.51084) (xy 43.046759 -358.47278) (xy 43.053225 -358.396935) (xy 43.066156 -358.321921)
			(xy 43.085458 -358.248289) (xy 43.110988 -358.176577) (xy 43.126406 -358.141778) (xy 43.129746 -358.133421)
			(xy 43.131033 -358.115482) (xy 43.128946 -358.106726) (xy 43.117873 -358.066521) (xy 43.102375 -357.984574)
			(xy 43.094614 -357.901538) (xy 43.094148 -357.859838) (xy 43.094524 -357.821522) (xy 43.101053 -357.745169)
			(xy 43.114136 -357.669662) (xy 43.133673 -357.595562) (xy 43.146218 -357.559356) (xy 43.148787 -357.551035)
			(xy 43.148799 -357.533636) (xy 43.146218 -357.52532) (xy 43.13374 -357.489193) (xy 43.114246 -357.415282)
			(xy 43.101158 -357.339973) (xy 43.094573 -357.263819) (xy 43.094148 -357.2256) (xy 43.094148 -357.224838)
			(xy 43.094652 -357.18249) (xy 43.102703 -357.098176) (xy 43.118732 -357.01501) (xy 43.142593 -356.933743)
			(xy 43.174072 -356.855113) (xy 43.212883 -356.779832) (xy 43.258673 -356.70858) (xy 43.311029 -356.642004)
			(xy 43.369477 -356.580706) (xy 43.433487 -356.525241) (xy 43.502479 -356.476112) (xy 43.575829 -356.433763)
			(xy 43.652872 -356.398579) (xy 43.732911 -356.370877) (xy 43.81522 -356.350909) (xy 43.899055 -356.338856)
			(xy 43.983656 -356.334826) (xy 44.068257 -356.338856) (xy 44.152092 -356.350909) (xy 44.234401 -356.370877)
			(xy 44.31444 -356.398579) (xy 44.391483 -356.433763) (xy 44.464833 -356.476112) (xy 44.533825 -356.525241)
			(xy 44.597835 -356.580706) (xy 44.656283 -356.642004) (xy 44.708639 -356.70858) (xy 44.754429 -356.779832)
			(xy 44.79324 -356.855113) (xy 44.824719 -356.933743) (xy 44.84858 -357.01501) (xy 44.864609 -357.098176)
			(xy 44.87266 -357.18249) (xy 44.873164 -357.224838) (xy 44.873164 -357.2256) (xy 44.87277 -357.263821)
			(xy 44.866201 -357.339979) (xy 44.853113 -357.415292) (xy 44.833602 -357.489202) (xy 44.821094 -357.52532)
			(xy 44.818487 -357.533631) (xy 44.818499 -357.55104) (xy 44.821094 -357.559356) (xy 44.833623 -357.595567)
			(xy 44.853143 -357.669669) (xy 44.866225 -357.745173) (xy 44.872771 -357.821523) (xy 44.873164 -357.859838)
			(xy 44.872788 -357.897898) (xy 44.866324 -357.973742) (xy 44.853395 -358.048756) (xy 44.837736 -358.108504)
			(xy 46.991016 -358.108504) (xy 46.991016 -358.107996) (xy 46.991417 -358.069988) (xy 46.997915 -357.994249)
			(xy 47.010854 -357.919341) (xy 47.030141 -357.845811) (xy 47.055634 -357.774197) (xy 47.071026 -357.739442)
			(xy 47.074466 -357.731111) (xy 47.075906 -357.713158) (xy 47.07382 -357.70439) (xy 47.0627 -357.664192)
			(xy 47.047129 -357.582247) (xy 47.039281 -357.499207) (xy 47.038768 -357.457502) (xy 47.039173 -357.419212)
			(xy 47.045781 -357.342918) (xy 47.05893 -357.267476) (xy 47.078524 -357.193445) (xy 47.091092 -357.157274)
			(xy 47.09374 -357.148837) (xy 47.093741 -357.131167) (xy 47.091092 -357.12273) (xy 47.078546 -357.086553)
			(xy 47.058974 -357.01252) (xy 47.045827 -356.93708) (xy 47.039204 -356.86079) (xy 47.038768 -356.822502)
			(xy 47.0392 -356.781386) (xy 47.046788 -356.699506) (xy 47.061898 -356.618674) (xy 47.084402 -356.539582)
			(xy 47.114108 -356.462904) (xy 47.150762 -356.389293) (xy 47.194052 -356.319379) (xy 47.243609 -356.253758)
			(xy 47.299008 -356.192989) (xy 47.359779 -356.137591) (xy 47.425402 -356.088036) (xy 47.495318 -356.044749)
			(xy 47.568929 -356.008097) (xy 47.645609 -355.978393) (xy 47.724702 -355.955891) (xy 47.805533 -355.940784)
			(xy 47.887414 -355.933199) (xy 47.92853 -355.93274) (xy 47.969637 -355.933252) (xy 48.051499 -355.940877)
			(xy 48.132307 -355.956023) (xy 48.211373 -355.97856) (xy 48.288023 -356.008296) (xy 48.325024 -356.026212)
			(xy 48.335846 -356.030917) (xy 48.359414 -356.030917) (xy 48.370236 -356.026212) (xy 48.407247 -356.008316)
			(xy 48.483894 -355.978575) (xy 48.562957 -355.956031) (xy 48.643763 -355.940876) (xy 48.725623 -355.93324)
			(xy 48.76673 -355.93274) (xy 48.80502 -355.933136) (xy 48.881314 -355.939747) (xy 48.956757 -355.952899)
			(xy 49.030787 -355.972495) (xy 49.066958 -355.985064) (xy 49.075395 -355.987715) (xy 49.093065 -355.987715)
			(xy 49.101502 -355.985064) (xy 49.137675 -355.972508) (xy 49.21171 -355.952938) (xy 49.287151 -355.939795)
			(xy 49.363442 -355.933174) (xy 49.40173 -355.93274) (xy 49.44002 -355.933136) (xy 49.516314 -355.939747)
			(xy 49.591757 -355.952899) (xy 49.665787 -355.972495) (xy 49.701958 -355.985064) (xy 49.710395 -355.987715)
			(xy 49.728065 -355.987715) (xy 49.736502 -355.985064) (xy 49.772675 -355.972508) (xy 49.84671 -355.952938)
			(xy 49.922151 -355.939795) (xy 49.998442 -355.933174) (xy 50.03673 -355.93274) (xy 50.07502 -355.933136)
			(xy 50.151314 -355.939747) (xy 50.226757 -355.952899) (xy 50.300787 -355.972495) (xy 50.336958 -355.985064)
			(xy 50.345395 -355.987715) (xy 50.363065 -355.987715) (xy 50.371502 -355.985064) (xy 50.407675 -355.972508)
			(xy 50.48171 -355.952938) (xy 50.557151 -355.939795) (xy 50.633442 -355.933174) (xy 50.67173 -355.93274)
			(xy 50.712845 -355.933184) (xy 50.794723 -355.940774) (xy 50.875552 -355.955886) (xy 50.954642 -355.978392)
			(xy 51.031318 -356.008098) (xy 51.104926 -356.044753) (xy 51.174838 -356.088043) (xy 51.240458 -356.137599)
			(xy 51.301225 -356.192997) (xy 51.356622 -356.253767) (xy 51.406175 -356.319388) (xy 51.449463 -356.389302)
			(xy 51.486115 -356.462911) (xy 51.515819 -356.539588) (xy 51.538321 -356.618679) (xy 51.55343 -356.699508)
			(xy 51.561017 -356.781387) (xy 51.561492 -356.822502) (xy 51.561091 -356.860792) (xy 51.554482 -356.937086)
			(xy 51.541332 -357.012529) (xy 51.521737 -357.086559) (xy 51.509168 -357.12273) (xy 51.506515 -357.131166)
			(xy 51.506516 -357.148837) (xy 51.509168 -357.157274) (xy 51.521713 -357.193451) (xy 51.541286 -357.267484)
			(xy 51.554433 -357.342924) (xy 51.561057 -357.419214) (xy 51.561492 -357.457502) (xy 51.561492 -357.45801)
			(xy 51.561093 -357.496018) (xy 51.554594 -357.571757) (xy 51.541655 -357.646665) (xy 51.522368 -357.720195)
			(xy 51.496874 -357.791809) (xy 51.481482 -357.826564) (xy 51.478039 -357.834894) (xy 51.476603 -357.852848)
			(xy 51.478688 -357.861616) (xy 51.48981 -357.901814) (xy 51.50538 -357.983758) (xy 51.513227 -358.066799)
			(xy 51.51374 -358.108504) (xy 51.513251 -358.149614) (xy 51.505664 -358.231482) (xy 51.490553 -358.312301)
			(xy 51.468049 -358.391381) (xy 51.438343 -358.468047) (xy 51.401689 -358.541644) (xy 51.3584 -358.611544)
			(xy 51.308844 -358.677152) (xy 51.253446 -358.737906) (xy 51.192678 -358.793289) (xy 51.127058 -358.842827)
			(xy 51.057146 -358.886099) (xy 50.98354 -358.922734) (xy 50.906867 -358.952421) (xy 50.827781 -358.974905)
			(xy 50.746958 -358.989995) (xy 50.665088 -358.997562) (xy 50.623978 -358.998012) (xy 50.585661 -358.99765)
			(xy 50.509308 -358.991116) (xy 50.433801 -358.97803) (xy 50.359702 -358.958488) (xy 50.323496 -358.945942)
			(xy 50.31518 -358.943356) (xy 50.297776 -358.943356) (xy 50.28946 -358.945942) (xy 50.253248 -358.958468)
			(xy 50.179147 -358.977989) (xy 50.103642 -358.991071) (xy 50.027293 -358.997619) (xy 49.988978 -358.998012)
			(xy 49.950661 -358.99765) (xy 49.874308 -358.991116) (xy 49.798801 -358.97803) (xy 49.724702 -358.958488)
			(xy 49.688496 -358.945942) (xy 49.68018 -358.943356) (xy 49.662776 -358.943356) (xy 49.65446 -358.945942)
			(xy 49.618248 -358.958468) (xy 49.544147 -358.977989) (xy 49.468642 -358.991071) (xy 49.392293 -358.997619)
			(xy 49.353978 -358.998012) (xy 49.315661 -358.99765) (xy 49.239308 -358.991116) (xy 49.163801 -358.97803)
			(xy 49.089702 -358.958488) (xy 49.053496 -358.945942) (xy 49.04518 -358.943356) (xy 49.027776 -358.943356)
			(xy 49.01946 -358.945942) (xy 48.983339 -358.95844) (xy 48.909426 -358.977928) (xy 48.834115 -358.99101)
			(xy 48.757959 -358.99759) (xy 48.71974 -358.998012) (xy 48.718978 -358.998012) (xy 48.677876 -358.99753)
			(xy 48.596022 -358.989953) (xy 48.515216 -358.974857) (xy 48.436148 -358.95237) (xy 48.359491 -358.922685)
			(xy 48.322484 -358.904794) (xy 48.311662 -358.900089) (xy 48.288094 -358.900089) (xy 48.277272 -358.904794)
			(xy 48.240271 -358.922698) (xy 48.163612 -358.952379) (xy 48.084542 -358.974864) (xy 48.003735 -358.98996)
			(xy 47.92188 -358.997539) (xy 47.880778 -358.998012) (xy 47.839669 -358.997608) (xy 47.757803 -358.990022)
			(xy 47.676986 -358.974915) (xy 47.597907 -358.952416) (xy 47.52124 -358.922719) (xy 47.447641 -358.886075)
			(xy 47.377735 -358.842798) (xy 47.312121 -358.793256) (xy 47.251356 -358.737873) (xy 47.19596 -358.677119)
			(xy 47.146405 -358.611515) (xy 47.103114 -358.541618) (xy 47.066455 -358.468026) (xy 47.036742 -358.391366)
			(xy 47.014227 -358.312292) (xy 46.999104 -358.231477) (xy 46.9915 -358.149612) (xy 46.991016 -358.108504)
			(xy 44.837736 -358.108504) (xy 44.834097 -358.122388) (xy 44.808571 -358.1941) (xy 44.793154 -358.2289)
			(xy 44.789778 -358.237249) (xy 44.788481 -358.255202) (xy 44.790614 -358.263952) (xy 44.801704 -358.304153)
			(xy 44.817195 -358.386101) (xy 44.82495 -358.46914) (xy 44.825412 -358.51084) (xy 44.824852 -358.556303)
			(xy 44.815599 -358.646758) (xy 44.797171 -358.735798) (xy 44.78401 -358.779318) (xy 44.78146 -358.788893)
			(xy 44.783017 -358.808626) (xy 44.787058 -358.817672) (xy 44.805431 -358.855048) (xy 44.835897 -358.932566)
			(xy 44.858991 -359.012591) (xy 44.87451 -359.094423) (xy 44.882318 -359.177347) (xy 44.882816 -359.218992)
			(xy 44.882816 -359.219246) (xy 44.882312 -359.261594) (xy 44.874261 -359.345908) (xy 44.858232 -359.429074)
			(xy 44.834371 -359.510341) (xy 44.802892 -359.588971) (xy 44.764081 -359.664252) (xy 44.718291 -359.735504)
			(xy 44.665935 -359.80208) (xy 44.607487 -359.863378) (xy 44.543477 -359.918843) (xy 44.474485 -359.967972)
			(xy 44.401135 -360.010321) (xy 44.324092 -360.045505) (xy 44.244053 -360.073207) (xy 44.161744 -360.093175)
			(xy 44.077909 -360.105228) (xy 43.993308 -360.109259) (xy 43.908707 -360.105228) (xy 43.824872 -360.093175)
			(xy 43.742563 -360.073207) (xy 43.662524 -360.045505) (xy 43.585481 -360.010321) (xy 43.512131 -359.967972)
			(xy 43.443139 -359.918843) (xy 43.379129 -359.863378) (xy 43.320681 -359.80208) (xy 43.268325 -359.735504)
			(xy 43.222535 -359.664252) (xy 43.183724 -359.588971) (xy 43.152245 -359.510341) (xy 43.128384 -359.429074)
			(xy 43.112355 -359.345908) (xy 43.104304 -359.261594) (xy 43.1038 -359.219246) (xy 43.1038 -359.218738)
			(xy 43.104382 -359.17336) (xy 43.113653 -359.083077) (xy 43.132063 -358.994207) (xy 43.145202 -358.950768)
			(xy 43.147759 -358.941194) (xy 43.146197 -358.921461) (xy 43.142154 -358.912414) (xy 43.123767 -358.875016)
			(xy 43.093286 -358.797449) (xy 43.070189 -358.717372) (xy 43.054676 -358.635487) (xy 43.046883 -358.552511)
			(xy 43.046396 -358.51084) (xy 42.259032 -358.51084) (xy 42.259504 -358.549194) (xy 42.258889 -358.594663)
			(xy 42.249552 -358.685121) (xy 42.231047 -358.774157) (xy 42.217848 -358.817672) (xy 42.215273 -358.827242)
			(xy 42.216849 -358.846979) (xy 42.220896 -358.856026) (xy 42.239309 -358.893418) (xy 42.269845 -358.970977)
			(xy 42.292996 -359.051051) (xy 42.308559 -359.132939) (xy 42.316398 -359.215923) (xy 42.316908 -359.2576)
			(xy 42.316404 -359.299961) (xy 42.308351 -359.384298) (xy 42.292317 -359.467488) (xy 42.268449 -359.548778)
			(xy 42.236961 -359.62743) (xy 42.198139 -359.702733) (xy 42.152336 -359.774005) (xy 42.099965 -359.840601)
			(xy 42.0415 -359.901916) (xy 41.977472 -359.957397) (xy 41.90846 -360.00654) (xy 41.83509 -360.0489)
			(xy 41.758025 -360.084095) (xy 41.677963 -360.111804) (xy 41.59563 -360.131778) (xy 41.511771 -360.143835)
			(xy 41.427146 -360.147867) (xy 41.342521 -360.143835) (xy 41.258662 -360.131778) (xy 41.176329 -360.111804)
			(xy 41.096267 -360.084095) (xy 41.019202 -360.0489) (xy 40.945832 -360.00654) (xy 40.87682 -359.957397)
			(xy 40.812792 -359.901916) (xy 40.754327 -359.840601) (xy 40.701956 -359.774005) (xy 40.656153 -359.702733)
			(xy 40.617331 -359.62743) (xy 40.585843 -359.548778) (xy 40.561975 -359.467488) (xy 40.545941 -359.384298)
			(xy 40.537888 -359.299961) (xy 40.537384 -359.2576) (xy 40.537998 -359.212131) (xy 40.547335 -359.121673)
			(xy 40.565841 -359.032637) (xy 40.57904 -358.989122) (xy 40.581619 -358.979553) (xy 40.580041 -358.959815)
			(xy 40.575992 -358.950768) (xy 40.557613 -358.91336) (xy 40.527071 -358.835806) (xy 40.503913 -358.755736)
			(xy 40.488342 -358.673851) (xy 40.480494 -358.59087) (xy 40.47998 -358.549194) (xy 2.509012 -358.549194)
			(xy 2.509012 -361.825848) (xy 5.986007 -361.825848) (xy 5.986007 -361.696708) (xy 5.993957 -361.567813)
			(xy 6.009827 -361.439653) (xy 6.033556 -361.312712) (xy 6.065055 -361.187473) (xy 6.104204 -361.06441)
			(xy 6.150855 -360.943991) (xy 6.20483 -360.826672) (xy 6.265925 -360.712898) (xy 6.333908 -360.603101)
			(xy 6.408522 -360.497698) (xy 6.489483 -360.397088) (xy 6.576483 -360.301653) (xy 6.669194 -360.211754)
			(xy 6.767264 -360.127733) (xy 6.870319 -360.049909) (xy 6.97797 -359.978577) (xy 7.089809 -359.914007)
			(xy 7.20541 -359.856445) (xy 7.324335 -359.806108) (xy 7.446134 -359.763188) (xy 7.570344 -359.727847)
			(xy 7.696493 -359.70022) (xy 7.824105 -359.680411) (xy 7.952694 -359.668495) (xy 8.081772 -359.664519)
			(xy 8.21085 -359.668495) (xy 8.339439 -359.680411) (xy 8.467051 -359.70022) (xy 8.5932 -359.727847)
			(xy 8.71741 -359.763188) (xy 8.839209 -359.806108) (xy 8.958134 -359.856445) (xy 9.073735 -359.914007)
			(xy 9.185574 -359.978577) (xy 9.293225 -360.049909) (xy 9.39628 -360.127733) (xy 9.49435 -360.211754)
			(xy 9.587061 -360.301653) (xy 9.674061 -360.397088) (xy 9.689764 -360.416602) (xy 12.542012 -360.416602)
			(xy 12.542012 -359.553002) (xy 12.542498 -359.525751) (xy 12.550254 -359.471803) (xy 12.565609 -359.419508)
			(xy 12.588251 -359.369931) (xy 12.617717 -359.324081) (xy 12.653408 -359.28289) (xy 12.694599 -359.247199)
			(xy 12.740449 -359.217733) (xy 12.790026 -359.195091) (xy 12.842321 -359.179736) (xy 12.896269 -359.17198)
			(xy 12.950771 -359.17198) (xy 13.004719 -359.179736) (xy 13.057014 -359.195091) (xy 13.106591 -359.217733)
			(xy 13.152441 -359.247199) (xy 13.193632 -359.28289) (xy 13.229323 -359.324081) (xy 13.258789 -359.369931)
			(xy 13.281431 -359.419508) (xy 13.296786 -359.471803) (xy 13.304542 -359.525751) (xy 13.305028 -359.553002)
			(xy 13.305028 -360.416602) (xy 13.304542 -360.443853) (xy 13.296786 -360.497801) (xy 13.281431 -360.550096)
			(xy 13.258789 -360.599673) (xy 13.229323 -360.645523) (xy 13.193632 -360.686714) (xy 13.152441 -360.722405)
			(xy 13.106591 -360.751871) (xy 13.057014 -360.774513) (xy 13.004719 -360.789868) (xy 12.950771 -360.797624)
			(xy 12.896269 -360.797624) (xy 12.842321 -360.789868) (xy 12.790026 -360.774513) (xy 12.740449 -360.751871)
			(xy 12.694599 -360.722405) (xy 12.653408 -360.686714) (xy 12.617717 -360.645523) (xy 12.588251 -360.599673)
			(xy 12.565609 -360.550096) (xy 12.550254 -360.497801) (xy 12.542498 -360.443853) (xy 12.542012 -360.416602)
			(xy 9.689764 -360.416602) (xy 9.755022 -360.497698) (xy 9.829636 -360.603101) (xy 9.897619 -360.712898)
			(xy 9.958714 -360.826672) (xy 10.012689 -360.943991) (xy 10.05934 -361.06441) (xy 10.098489 -361.187473)
			(xy 10.129988 -361.312712) (xy 10.153717 -361.439653) (xy 10.169587 -361.567813) (xy 10.177537 -361.696708)
			(xy 10.178034 -361.761278) (xy 10.177537 -361.825848) (xy 10.169587 -361.954743) (xy 10.153717 -362.082903)
			(xy 10.129988 -362.209844) (xy 10.098489 -362.335083) (xy 10.079022 -362.396278) (xy 165.733984 -362.396278)
			(xy 165.733984 -361.532678) (xy 165.73447 -361.505409) (xy 165.742232 -361.451425) (xy 165.757597 -361.399095)
			(xy 165.780254 -361.349485) (xy 165.80974 -361.303604) (xy 165.845455 -361.262387) (xy 165.886672 -361.226672)
			(xy 165.932553 -361.197186) (xy 165.982163 -361.174529) (xy 166.034493 -361.159164) (xy 166.088477 -361.151402)
			(xy 166.143015 -361.151402) (xy 166.196999 -361.159164) (xy 166.249329 -361.174529) (xy 166.298939 -361.197186)
			(xy 166.34482 -361.226672) (xy 166.386037 -361.262387) (xy 166.421752 -361.303604) (xy 166.451238 -361.349485)
			(xy 166.473895 -361.399095) (xy 166.48926 -361.451425) (xy 166.497022 -361.505409) (xy 166.497508 -361.532678)
			(xy 166.497508 -362.234988) (xy 185.144664 -362.234988) (xy 185.144664 -362.23448) (xy 185.145268 -362.188148)
			(xy 185.154941 -362.09599) (xy 185.174137 -362.005336) (xy 185.202649 -361.917167) (xy 185.220864 -361.874562)
			(xy 185.224678 -361.864622) (xy 185.224673 -361.843356) (xy 185.220864 -361.833414) (xy 185.202614 -361.790754)
			(xy 185.174071 -361.702461) (xy 185.15488 -361.611675) (xy 185.145248 -361.519384) (xy 185.144664 -361.472988)
			(xy 185.145245 -361.426592) (xy 185.154891 -361.334304) (xy 185.174088 -361.24352) (xy 185.202626 -361.155227)
			(xy 185.220864 -361.112562) (xy 185.224678 -361.102622) (xy 185.224673 -361.081356) (xy 185.220864 -361.071414)
			(xy 185.202636 -361.028813) (xy 185.17412 -360.940645) (xy 185.154929 -360.849989) (xy 185.145271 -360.757828)
			(xy 185.144664 -360.711496) (xy 185.144664 -360.710988) (xy 185.145155 -360.669886) (xy 185.152741 -360.588033)
			(xy 185.167846 -360.507229) (xy 185.190343 -360.428164) (xy 185.220039 -360.351511) (xy 185.25668 -360.277925)
			(xy 185.299955 -360.208034) (xy 185.349493 -360.142434) (xy 185.404873 -360.081684) (xy 185.465622 -360.026303)
			(xy 185.531221 -359.976764) (xy 185.601111 -359.933488) (xy 185.674696 -359.896845) (xy 185.751348 -359.867148)
			(xy 185.830414 -359.84465) (xy 185.911217 -359.829543) (xy 185.99307 -359.821956) (xy 186.034172 -359.82148)
			(xy 186.03468 -359.82148) (xy 186.081011 -359.822097) (xy 186.173169 -359.831765) (xy 186.263823 -359.850958)
			(xy 186.351992 -359.879466) (xy 186.394598 -359.89768) (xy 186.40454 -359.901486) (xy 186.425804 -359.901486)
			(xy 186.435746 -359.89768) (xy 186.478352 -359.879466) (xy 186.566519 -359.850947) (xy 186.657173 -359.831752)
			(xy 186.749332 -359.822089) (xy 186.795664 -359.82148) (xy 186.796172 -359.82148) (xy 186.837274 -359.821979)
			(xy 186.919129 -359.829561) (xy 186.999934 -359.844664) (xy 187.079001 -359.867158) (xy 187.155656 -359.896852)
			(xy 187.229243 -359.933492) (xy 187.299136 -359.976765) (xy 187.364738 -360.026303) (xy 187.425489 -360.081682)
			(xy 187.480872 -360.142431) (xy 187.530412 -360.208031) (xy 187.573689 -360.277922) (xy 187.610332 -360.351508)
			(xy 187.640029 -360.428161) (xy 187.662527 -360.507227) (xy 187.677633 -360.588032) (xy 187.685219 -360.669886)
			(xy 187.68568 -360.710988) (xy 187.68568 -360.711496) (xy 187.685072 -360.757828) (xy 187.684417 -360.764074)
			(xy 211.161635 -360.764074) (xy 211.16566 -360.621882) (xy 211.177723 -360.480146) (xy 211.197786 -360.33932)
			(xy 211.225784 -360.199854) (xy 211.261628 -360.062195) (xy 211.305202 -359.926785) (xy 211.356367 -359.794057)
			(xy 211.41496 -359.664436) (xy 211.480791 -359.538338) (xy 211.553652 -359.416166) (xy 211.633307 -359.298312)
			(xy 211.719503 -359.185153) (xy 211.811962 -359.077051) (xy 211.91039 -358.974354) (xy 212.014469 -358.87739)
			(xy 212.123868 -358.78647) (xy 212.238236 -358.701884) (xy 212.357205 -358.623904) (xy 212.480396 -358.55278)
			(xy 212.607413 -358.488739) (xy 212.73785 -358.431987) (xy 212.871289 -358.382705) (xy 213.007302 -358.341051)
			(xy 213.145454 -358.307159) (xy 213.285303 -358.281138) (xy 213.426399 -358.26307) (xy 213.568291 -358.253013)
			(xy 213.710526 -358.251) (xy 213.852646 -358.257037) (xy 213.994197 -358.271105) (xy 214.134726 -358.293159)
			(xy 214.273781 -358.323128) (xy 214.410919 -358.360916) (xy 214.545699 -358.406402) (xy 214.67769 -358.45944)
			(xy 214.806469 -358.519861) (xy 214.931623 -358.58747) (xy 215.052751 -358.662052) (xy 215.169467 -358.743368)
			(xy 215.281395 -358.831156) (xy 215.388177 -358.925136) (xy 215.489471 -359.025006) (xy 215.584952 -359.130448)
			(xy 215.674316 -359.241122) (xy 215.757274 -359.356675) (xy 215.833563 -359.476736) (xy 215.902937 -359.600921)
			(xy 215.965174 -359.728832) (xy 216.020075 -359.860059) (xy 216.067463 -359.994182) (xy 216.107188 -360.130771)
			(xy 216.139121 -360.269389) (xy 216.163162 -360.409591) (xy 216.179231 -360.550929) (xy 216.187279 -360.69295)
			(xy 216.187782 -360.764074) (xy 255.611635 -360.764074) (xy 255.61566 -360.621882) (xy 255.627723 -360.480146)
			(xy 255.647786 -360.33932) (xy 255.675784 -360.199854) (xy 255.711628 -360.062195) (xy 255.755202 -359.926785)
			(xy 255.806367 -359.794057) (xy 255.86496 -359.664436) (xy 255.930791 -359.538338) (xy 256.003652 -359.416166)
			(xy 256.083307 -359.298312) (xy 256.169503 -359.185153) (xy 256.261962 -359.077051) (xy 256.36039 -358.974354)
			(xy 256.464469 -358.87739) (xy 256.573868 -358.78647) (xy 256.688236 -358.701884) (xy 256.807205 -358.623904)
			(xy 256.930396 -358.55278) (xy 257.057413 -358.488739) (xy 257.18785 -358.431987) (xy 257.321289 -358.382705)
			(xy 257.457302 -358.341051) (xy 257.595454 -358.307159) (xy 257.735303 -358.281138) (xy 257.876399 -358.26307)
			(xy 258.018291 -358.253013) (xy 258.160526 -358.251) (xy 258.302646 -358.257037) (xy 258.444197 -358.271105)
			(xy 258.584726 -358.293159) (xy 258.723781 -358.323128) (xy 258.860919 -358.360916) (xy 258.995699 -358.406402)
			(xy 259.12769 -358.45944) (xy 259.256469 -358.519861) (xy 259.381623 -358.58747) (xy 259.502751 -358.662052)
			(xy 259.619467 -358.743368) (xy 259.652996 -358.769666) (xy 294.901627 -358.769666) (xy 294.905632 -358.663917)
			(xy 294.917622 -358.558774) (xy 294.937531 -358.454839) (xy 294.965242 -358.352707) (xy 295.000599 -358.252963)
			(xy 295.043397 -358.156179) (xy 295.093393 -358.062909) (xy 295.1503 -357.973688) (xy 295.213791 -357.889025)
			(xy 295.283503 -357.809407) (xy 295.359037 -357.735289) (xy 295.43996 -357.667096) (xy 295.525809 -357.605218)
			(xy 295.616092 -357.550011) (xy 295.710291 -357.501789) (xy 295.807868 -357.460829) (xy 295.908263 -357.427367)
			(xy 296.010901 -357.401593) (xy 296.115194 -357.383655) (xy 296.220545 -357.373656) (xy 296.326351 -357.371653)
			(xy 296.432005 -357.377658) (xy 296.536902 -357.391637) (xy 296.640442 -357.413508) (xy 296.742031 -357.443148)
			(xy 296.841088 -357.480386) (xy 296.937045 -357.525008) (xy 297.029352 -357.57676) (xy 297.117481 -357.635345)
			(xy 297.200927 -357.700427) (xy 297.279211 -357.771633) (xy 297.351886 -357.848556) (xy 297.418536 -357.930756)
			(xy 297.478778 -358.01776) (xy 297.532267 -358.109071) (xy 297.578698 -358.204166) (xy 297.617803 -358.3025)
			(xy 297.64936 -358.403511) (xy 297.673187 -358.506618) (xy 297.689148 -358.611232) (xy 297.697152 -358.716754)
			(xy 297.697652 -358.769666) (xy 297.697152 -358.822578) (xy 297.689148 -358.9281) (xy 297.673187 -359.032714)
			(xy 297.64936 -359.135821) (xy 297.617803 -359.236832) (xy 297.578698 -359.335166) (xy 297.532267 -359.430261)
			(xy 297.478778 -359.521572) (xy 297.418536 -359.608576) (xy 297.351886 -359.690776) (xy 297.279211 -359.767699)
			(xy 297.200927 -359.838905) (xy 297.117481 -359.903987) (xy 297.029352 -359.962572) (xy 296.937045 -360.014324)
			(xy 296.841088 -360.058946) (xy 296.742031 -360.096184) (xy 296.640442 -360.125824) (xy 296.536902 -360.147695)
			(xy 296.432005 -360.161674) (xy 296.326351 -360.167679) (xy 296.220545 -360.165676) (xy 296.115194 -360.155677)
			(xy 296.010901 -360.137739) (xy 295.908263 -360.111965) (xy 295.807868 -360.078503) (xy 295.710291 -360.037543)
			(xy 295.616092 -359.989321) (xy 295.525809 -359.934114) (xy 295.43996 -359.872236) (xy 295.359037 -359.804043)
			(xy 295.283503 -359.729925) (xy 295.213791 -359.650307) (xy 295.1503 -359.565644) (xy 295.093393 -359.476423)
			(xy 295.043397 -359.383153) (xy 295.000599 -359.286369) (xy 294.965242 -359.186625) (xy 294.937531 -359.084493)
			(xy 294.917622 -358.980558) (xy 294.905632 -358.875415) (xy 294.901627 -358.769666) (xy 259.652996 -358.769666)
			(xy 259.731395 -358.831156) (xy 259.838177 -358.925136) (xy 259.939471 -359.025006) (xy 260.034952 -359.130448)
			(xy 260.124316 -359.241122) (xy 260.207274 -359.356675) (xy 260.283563 -359.476736) (xy 260.352937 -359.600921)
			(xy 260.415174 -359.728832) (xy 260.470075 -359.860059) (xy 260.517463 -359.994182) (xy 260.557188 -360.130771)
			(xy 260.589121 -360.269389) (xy 260.613162 -360.409591) (xy 260.629231 -360.550929) (xy 260.637279 -360.69295)
			(xy 260.637782 -360.764074) (xy 260.637279 -360.835198) (xy 260.629231 -360.977219) (xy 260.613162 -361.118557)
			(xy 260.589121 -361.258759) (xy 260.557188 -361.397377) (xy 260.517463 -361.533966) (xy 260.470075 -361.668089)
			(xy 260.415174 -361.799316) (xy 260.401302 -361.827826) (xy 430.615097 -361.827826) (xy 430.619102 -361.722077)
			(xy 430.631092 -361.616934) (xy 430.651001 -361.512999) (xy 430.678712 -361.410867) (xy 430.714069 -361.311123)
			(xy 430.756867 -361.214339) (xy 430.806863 -361.121069) (xy 430.86377 -361.031848) (xy 430.927261 -360.947185)
			(xy 430.996973 -360.867567) (xy 431.072507 -360.793449) (xy 431.15343 -360.725256) (xy 431.239279 -360.663378)
			(xy 431.329562 -360.608171) (xy 431.423761 -360.559949) (xy 431.521338 -360.518989) (xy 431.621733 -360.485527)
			(xy 431.724371 -360.459753) (xy 431.828664 -360.441815) (xy 431.934015 -360.431816) (xy 432.039821 -360.429813)
			(xy 432.145475 -360.435818) (xy 432.250372 -360.449797) (xy 432.353912 -360.471668) (xy 432.455501 -360.501308)
			(xy 432.554558 -360.538546) (xy 432.650515 -360.583168) (xy 432.742822 -360.63492) (xy 432.830951 -360.693505)
			(xy 432.914397 -360.758587) (xy 432.992681 -360.829793) (xy 433.065356 -360.906716) (xy 433.132006 -360.988916)
			(xy 433.192248 -361.07592) (xy 433.245737 -361.167231) (xy 433.292168 -361.262326) (xy 433.331273 -361.36066)
			(xy 433.36283 -361.461671) (xy 433.370787 -361.496102) (xy 434.579776 -361.496102) (xy 434.580404 -361.4497)
			(xy 434.590093 -361.357403) (xy 434.609347 -361.266617) (xy 434.637954 -361.178332) (xy 434.65623 -361.135676)
			(xy 434.660038 -361.125734) (xy 434.660039 -361.10447) (xy 434.65623 -361.094528) (xy 434.637968 -361.051867)
			(xy 434.609375 -360.963579) (xy 434.590118 -360.872796) (xy 434.580405 -360.780503) (xy 434.579776 -360.734102)
			(xy 434.580404 -360.6877) (xy 434.590093 -360.595403) (xy 434.609347 -360.504617) (xy 434.637954 -360.416332)
			(xy 434.65623 -360.373676) (xy 434.660038 -360.363734) (xy 434.660039 -360.34247) (xy 434.65623 -360.332528)
			(xy 434.637968 -360.289867) (xy 434.609375 -360.201579) (xy 434.590118 -360.110796) (xy 434.580405 -360.018503)
			(xy 434.579776 -359.972102) (xy 434.5802 -359.930986) (xy 434.587788 -359.849105) (xy 434.602898 -359.768273)
			(xy 434.625402 -359.68918) (xy 434.655109 -359.612502) (xy 434.691763 -359.538891) (xy 434.735054 -359.468977)
			(xy 434.784611 -359.403355) (xy 434.840011 -359.342586) (xy 434.900783 -359.287188) (xy 434.966406 -359.237634)
			(xy 435.036323 -359.194346) (xy 435.109935 -359.157694) (xy 435.186615 -359.127991) (xy 435.265708 -359.10549)
			(xy 435.346541 -359.090383) (xy 435.428422 -359.082799) (xy 435.469538 -359.08234) (xy 435.51594 -359.082957)
			(xy 435.608238 -359.09265) (xy 435.699023 -359.111907) (xy 435.787308 -359.140517) (xy 435.829964 -359.158794)
			(xy 435.839906 -359.1626) (xy 435.86117 -359.1626) (xy 435.871112 -359.158794) (xy 435.913767 -359.140517)
			(xy 436.002057 -359.111928) (xy 436.092842 -359.092675) (xy 436.185137 -359.082967) (xy 436.231538 -359.08234)
			(xy 436.272653 -359.082777) (xy 436.354532 -359.090367) (xy 436.435361 -359.10548) (xy 436.514451 -359.127986)
			(xy 436.591127 -359.157693) (xy 436.664735 -359.194349) (xy 436.734647 -359.237639) (xy 436.800266 -359.287195)
			(xy 436.861034 -359.342595) (xy 436.91643 -359.403364) (xy 436.965984 -359.468986) (xy 437.009271 -359.5389)
			(xy 437.045923 -359.61251) (xy 437.075627 -359.689187) (xy 437.098129 -359.768278) (xy 437.113238 -359.849108)
			(xy 437.120825 -359.930987) (xy 437.1213 -359.972102) (xy 437.120676 -360.018504) (xy 437.110985 -360.110802)
			(xy 437.091731 -360.201587) (xy 437.063122 -360.289872) (xy 437.044846 -360.332528) (xy 437.041037 -360.34247)
			(xy 437.041038 -360.363734) (xy 437.044846 -360.373676) (xy 437.063108 -360.416337) (xy 437.091701 -360.504625)
			(xy 437.110959 -360.595408) (xy 437.120671 -360.687701) (xy 437.1213 -360.734102) (xy 437.120676 -360.780504)
			(xy 437.110985 -360.872802) (xy 437.091731 -360.963587) (xy 437.063122 -361.051872) (xy 437.044846 -361.094528)
			(xy 437.041037 -361.10447) (xy 437.041038 -361.125734) (xy 437.044846 -361.135676) (xy 437.063108 -361.178337)
			(xy 437.091701 -361.266625) (xy 437.110959 -361.357408) (xy 437.120671 -361.449701) (xy 437.1213 -361.496102)
			(xy 437.120789 -361.537215) (xy 437.113202 -361.619091) (xy 437.098093 -361.699917) (xy 437.075592 -361.779004)
			(xy 437.045889 -361.855678) (xy 437.009238 -361.929285) (xy 436.965952 -361.999196) (xy 436.916401 -362.064814)
			(xy 436.861007 -362.125581) (xy 436.800242 -362.180978) (xy 436.734625 -362.230532) (xy 436.664716 -362.273821)
			(xy 436.591111 -362.310474) (xy 436.514439 -362.34018) (xy 436.435352 -362.362685) (xy 436.354526 -362.377797)
			(xy 436.272651 -362.385387) (xy 436.231538 -362.385864) (xy 436.185135 -362.385256) (xy 436.092838 -362.37556)
			(xy 436.002052 -362.356301) (xy 435.913768 -362.327688) (xy 435.871112 -362.30941) (xy 435.86117 -362.305604)
			(xy 435.839906 -362.305604) (xy 435.829964 -362.30941) (xy 435.787299 -362.327662) (xy 435.699012 -362.356257)
			(xy 435.608231 -362.375517) (xy 435.515939 -362.385233) (xy 435.469538 -362.385864) (xy 435.428424 -362.385365)
			(xy 435.346546 -362.377782) (xy 435.265717 -362.362675) (xy 435.186627 -362.340175) (xy 435.10995 -362.310473)
			(xy 435.036341 -362.273823) (xy 434.966428 -362.230538) (xy 434.900807 -362.180986) (xy 434.840038 -362.12559)
			(xy 434.78464 -362.064824) (xy 434.735085 -361.999205) (xy 434.691796 -361.929294) (xy 434.655143 -361.855686)
			(xy 434.625438 -361.779011) (xy 434.602934 -361.699922) (xy 434.587824 -361.619094) (xy 434.580237 -361.537216)
			(xy 434.579776 -361.496102) (xy 433.370787 -361.496102) (xy 433.386657 -361.564778) (xy 433.402618 -361.669392)
			(xy 433.410622 -361.774914) (xy 433.411122 -361.827826) (xy 433.410622 -361.880738) (xy 433.402618 -361.98626)
			(xy 433.386657 -362.090874) (xy 433.36283 -362.193981) (xy 433.331273 -362.294992) (xy 433.292168 -362.393326)
			(xy 433.245737 -362.488421) (xy 433.192248 -362.579732) (xy 433.132006 -362.666736) (xy 433.065356 -362.748936)
			(xy 432.992681 -362.825859) (xy 432.914397 -362.897065) (xy 432.830951 -362.962147) (xy 432.742822 -363.020732)
			(xy 432.650515 -363.072484) (xy 432.554558 -363.117106) (xy 432.455501 -363.154344) (xy 432.353912 -363.183984)
			(xy 432.250372 -363.205855) (xy 432.145475 -363.219834) (xy 432.039821 -363.225839) (xy 431.934015 -363.223836)
			(xy 431.828664 -363.213837) (xy 431.724371 -363.195899) (xy 431.621733 -363.170125) (xy 431.521338 -363.136663)
			(xy 431.423761 -363.095703) (xy 431.329562 -363.047481) (xy 431.239279 -362.992274) (xy 431.15343 -362.930396)
			(xy 431.072507 -362.862203) (xy 430.996973 -362.788085) (xy 430.927261 -362.708467) (xy 430.86377 -362.623804)
			(xy 430.806863 -362.534583) (xy 430.756867 -362.441313) (xy 430.714069 -362.344529) (xy 430.678712 -362.244785)
			(xy 430.651001 -362.142653) (xy 430.631092 -362.038718) (xy 430.619102 -361.933575) (xy 430.615097 -361.827826)
			(xy 260.401302 -361.827826) (xy 260.352937 -361.927227) (xy 260.283563 -362.051412) (xy 260.207274 -362.171473)
			(xy 260.124316 -362.287026) (xy 260.034952 -362.3977) (xy 259.939471 -362.503142) (xy 259.838177 -362.603012)
			(xy 259.731395 -362.696992) (xy 259.619467 -362.78478) (xy 259.502751 -362.866096) (xy 259.381623 -362.940678)
			(xy 259.256469 -363.008287) (xy 259.12769 -363.068708) (xy 258.995699 -363.121746) (xy 258.860919 -363.167232)
			(xy 258.723781 -363.20502) (xy 258.584726 -363.234989) (xy 258.444197 -363.257043) (xy 258.302646 -363.271111)
			(xy 258.160526 -363.277148) (xy 258.018291 -363.275135) (xy 257.876399 -363.265078) (xy 257.735303 -363.24701)
			(xy 257.595454 -363.220989) (xy 257.457302 -363.187097) (xy 257.321289 -363.145443) (xy 257.18785 -363.096161)
			(xy 257.057413 -363.039409) (xy 256.930396 -362.975368) (xy 256.807205 -362.904244) (xy 256.688236 -362.826264)
			(xy 256.573868 -362.741678) (xy 256.464469 -362.650758) (xy 256.36039 -362.553794) (xy 256.261962 -362.451097)
			(xy 256.169503 -362.342995) (xy 256.083307 -362.229836) (xy 256.003652 -362.111982) (xy 255.930791 -361.98981)
			(xy 255.86496 -361.863712) (xy 255.806367 -361.734091) (xy 255.755202 -361.601363) (xy 255.711628 -361.465953)
			(xy 255.675784 -361.328294) (xy 255.647786 -361.188828) (xy 255.627723 -361.048002) (xy 255.61566 -360.906266)
			(xy 255.611635 -360.764074) (xy 216.187782 -360.764074) (xy 216.187279 -360.835198) (xy 216.179231 -360.977219)
			(xy 216.163162 -361.118557) (xy 216.139121 -361.258759) (xy 216.107188 -361.397377) (xy 216.067463 -361.533966)
			(xy 216.020075 -361.668089) (xy 215.965174 -361.799316) (xy 215.902937 -361.927227) (xy 215.833563 -362.051412)
			(xy 215.757274 -362.171473) (xy 215.674316 -362.287026) (xy 215.584952 -362.3977) (xy 215.489471 -362.503142)
			(xy 215.388177 -362.603012) (xy 215.281395 -362.696992) (xy 215.169467 -362.78478) (xy 215.052751 -362.866096)
			(xy 214.931623 -362.940678) (xy 214.806469 -363.008287) (xy 214.67769 -363.068708) (xy 214.545699 -363.121746)
			(xy 214.410919 -363.167232) (xy 214.273781 -363.20502) (xy 214.134726 -363.234989) (xy 213.994197 -363.257043)
			(xy 213.852646 -363.271111) (xy 213.710526 -363.277148) (xy 213.568291 -363.275135) (xy 213.426399 -363.265078)
			(xy 213.285303 -363.24701) (xy 213.145454 -363.220989) (xy 213.007302 -363.187097) (xy 212.871289 -363.145443)
			(xy 212.73785 -363.096161) (xy 212.607413 -363.039409) (xy 212.480396 -362.975368) (xy 212.357205 -362.904244)
			(xy 212.238236 -362.826264) (xy 212.123868 -362.741678) (xy 212.014469 -362.650758) (xy 211.91039 -362.553794)
			(xy 211.811962 -362.451097) (xy 211.719503 -362.342995) (xy 211.633307 -362.229836) (xy 211.553652 -362.111982)
			(xy 211.480791 -361.98981) (xy 211.41496 -361.863712) (xy 211.356367 -361.734091) (xy 211.305202 -361.601363)
			(xy 211.261628 -361.465953) (xy 211.225784 -361.328294) (xy 211.197786 -361.188828) (xy 211.177723 -361.048002)
			(xy 211.16566 -360.906266) (xy 211.161635 -360.764074) (xy 187.684417 -360.764074) (xy 187.675402 -360.849986)
			(xy 187.656207 -360.94064) (xy 187.627695 -361.028809) (xy 187.60948 -361.071414) (xy 187.605683 -361.081359)
			(xy 187.605679 -361.10262) (xy 187.60948 -361.112562) (xy 187.627719 -361.155227) (xy 187.656265 -361.243518)
			(xy 187.67546 -361.334302) (xy 187.685094 -361.426592) (xy 187.68568 -361.472988) (xy 187.685095 -361.519384)
			(xy 187.675451 -361.611672) (xy 187.656256 -361.702456) (xy 187.627718 -361.790749) (xy 187.60948 -361.833414)
			(xy 187.605683 -361.843359) (xy 187.605679 -361.86462) (xy 187.60948 -361.874562) (xy 187.627696 -361.917167)
			(xy 187.656216 -362.005334) (xy 187.67541 -362.095988) (xy 187.685071 -362.188148) (xy 187.68568 -362.23448)
			(xy 187.68568 -362.234988) (xy 187.685236 -362.276092) (xy 187.677652 -362.357949) (xy 187.664078 -362.430568)
			(xy 190.281567 -362.430568) (xy 190.285572 -362.324819) (xy 190.297562 -362.219676) (xy 190.317471 -362.115741)
			(xy 190.345182 -362.013609) (xy 190.380539 -361.913865) (xy 190.423337 -361.817081) (xy 190.473333 -361.723811)
			(xy 190.53024 -361.63459) (xy 190.593731 -361.549927) (xy 190.663443 -361.470309) (xy 190.738977 -361.396191)
			(xy 190.8199 -361.327998) (xy 190.905749 -361.26612) (xy 190.996032 -361.210913) (xy 191.090231 -361.162691)
			(xy 191.187808 -361.121731) (xy 191.288203 -361.088269) (xy 191.390841 -361.062495) (xy 191.495134 -361.044557)
			(xy 191.600485 -361.034558) (xy 191.706291 -361.032555) (xy 191.811945 -361.03856) (xy 191.916842 -361.052539)
			(xy 192.020382 -361.07441) (xy 192.121971 -361.10405) (xy 192.221028 -361.141288) (xy 192.316985 -361.18591)
			(xy 192.409292 -361.237662) (xy 192.497421 -361.296247) (xy 192.580867 -361.361329) (xy 192.659151 -361.432535)
			(xy 192.731826 -361.509458) (xy 192.798476 -361.591658) (xy 192.858718 -361.678662) (xy 192.912207 -361.769973)
			(xy 192.958638 -361.865068) (xy 192.997743 -361.963402) (xy 193.0293 -362.064413) (xy 193.053127 -362.16752)
			(xy 193.069088 -362.272134) (xy 193.077092 -362.377656) (xy 193.077592 -362.430568) (xy 193.077092 -362.48348)
			(xy 193.069088 -362.589002) (xy 193.053127 -362.693616) (xy 193.0293 -362.796723) (xy 192.997743 -362.897734)
			(xy 192.958638 -362.996068) (xy 192.912207 -363.091163) (xy 192.858718 -363.182474) (xy 192.798476 -363.269478)
			(xy 192.731826 -363.351678) (xy 192.659151 -363.428601) (xy 192.580867 -363.499807) (xy 192.497421 -363.564889)
			(xy 192.409292 -363.623474) (xy 192.316985 -363.675226) (xy 192.221028 -363.719848) (xy 192.121971 -363.757086)
			(xy 192.020382 -363.786726) (xy 191.916842 -363.808597) (xy 191.811945 -363.822576) (xy 191.706291 -363.828581)
			(xy 191.600485 -363.826578) (xy 191.495134 -363.816579) (xy 191.390841 -363.798641) (xy 191.288203 -363.772867)
			(xy 191.187808 -363.739405) (xy 191.090231 -363.698445) (xy 190.996032 -363.650223) (xy 190.905749 -363.595016)
			(xy 190.8199 -363.533138) (xy 190.738977 -363.464945) (xy 190.663443 -363.390827) (xy 190.593731 -363.311209)
			(xy 190.53024 -363.226546) (xy 190.473333 -363.137325) (xy 190.423337 -363.044055) (xy 190.380539 -362.947271)
			(xy 190.345182 -362.847527) (xy 190.317471 -362.745395) (xy 190.297562 -362.64146) (xy 190.285572 -362.536317)
			(xy 190.281567 -362.430568) (xy 187.664078 -362.430568) (xy 187.662547 -362.438757) (xy 187.64005 -362.517826)
			(xy 187.610354 -362.594483) (xy 187.573711 -362.668072) (xy 187.530434 -362.737966) (xy 187.480892 -362.803569)
			(xy 187.425509 -362.86432) (xy 187.364756 -362.919703) (xy 187.299153 -362.969243) (xy 187.229258 -363.012519)
			(xy 187.155668 -363.04916) (xy 187.079011 -363.078856) (xy 186.999941 -363.101351) (xy 186.919133 -363.116454)
			(xy 186.837276 -363.124037) (xy 186.796172 -363.124496) (xy 186.795664 -363.124496) (xy 186.749333 -363.123866)
			(xy 186.657176 -363.114202) (xy 186.566521 -363.095013) (xy 186.478352 -363.066508) (xy 186.435746 -363.048296)
			(xy 186.425804 -363.04449) (xy 186.40454 -363.04449) (xy 186.394598 -363.048296) (xy 186.351999 -363.066527)
			(xy 186.26383 -363.095042) (xy 186.173173 -363.114232) (xy 186.081013 -363.123889) (xy 186.03468 -363.124496)
			(xy 186.034172 -363.124496) (xy 185.993069 -363.12406) (xy 185.911213 -363.116473) (xy 185.830407 -363.101365)
			(xy 185.751339 -363.078866) (xy 185.674684 -363.049167) (xy 185.601097 -363.012522) (xy 185.531204 -362.969244)
			(xy 185.465603 -362.919702) (xy 185.404853 -362.864319) (xy 185.349472 -362.803566) (xy 185.299933 -362.737963)
			(xy 185.256658 -362.668068) (xy 185.220017 -362.594479) (xy 185.190322 -362.517823) (xy 185.167826 -362.438755)
			(xy 185.152722 -362.357947) (xy 185.145138 -362.276091) (xy 185.144664 -362.234988) (xy 166.497508 -362.234988)
			(xy 166.497508 -362.396278) (xy 166.497022 -362.423547) (xy 166.48926 -362.477531) (xy 166.473895 -362.529861)
			(xy 166.451238 -362.579471) (xy 166.421752 -362.625352) (xy 166.386037 -362.666569) (xy 166.34482 -362.702284)
			(xy 166.298939 -362.73177) (xy 166.249329 -362.754427) (xy 166.196999 -362.769792) (xy 166.143015 -362.777554)
			(xy 166.088477 -362.777554) (xy 166.034493 -362.769792) (xy 165.982163 -362.754427) (xy 165.932553 -362.73177)
			(xy 165.886672 -362.702284) (xy 165.845455 -362.666569) (xy 165.80974 -362.625352) (xy 165.780254 -362.579471)
			(xy 165.757597 -362.529861) (xy 165.742232 -362.477531) (xy 165.73447 -362.423547) (xy 165.733984 -362.396278)
			(xy 10.079022 -362.396278) (xy 10.05934 -362.458146) (xy 10.012689 -362.578565) (xy 9.958714 -362.695884)
			(xy 9.897619 -362.809658) (xy 9.829636 -362.919455) (xy 9.755022 -363.024858) (xy 9.674061 -363.125468)
			(xy 9.587061 -363.220903) (xy 9.49435 -363.310802) (xy 9.39628 -363.394823) (xy 9.293225 -363.472647)
			(xy 9.185574 -363.543979) (xy 9.073735 -363.608549) (xy 8.958134 -363.666111) (xy 8.839209 -363.716448)
			(xy 8.71741 -363.759368) (xy 8.5932 -363.794709) (xy 8.467051 -363.822336) (xy 8.339439 -363.842145)
			(xy 8.21085 -363.854061) (xy 8.081772 -363.858038) (xy 7.952694 -363.854061) (xy 7.824105 -363.842145)
			(xy 7.696493 -363.822336) (xy 7.570344 -363.794709) (xy 7.446134 -363.759368) (xy 7.324335 -363.716448)
			(xy 7.20541 -363.666111) (xy 7.089809 -363.608549) (xy 6.97797 -363.543979) (xy 6.870319 -363.472647)
			(xy 6.767264 -363.394823) (xy 6.669194 -363.310802) (xy 6.576483 -363.220903) (xy 6.489483 -363.125468)
			(xy 6.408522 -363.024858) (xy 6.333908 -362.919455) (xy 6.265925 -362.809658) (xy 6.20483 -362.695884)
			(xy 6.150855 -362.578565) (xy 6.104204 -362.458146) (xy 6.065055 -362.335083) (xy 6.033556 -362.209844)
			(xy 6.009827 -362.082903) (xy 5.993957 -361.954743) (xy 5.986007 -361.825848) (xy 2.509012 -361.825848)
			(xy 2.509012 -369.062565) (xy 44.335754 -369.062565) (xy 44.335754 -369.008035) (xy 44.343514 -368.95406)
			(xy 44.358876 -368.901738) (xy 44.381527 -368.852135) (xy 44.411006 -368.806259) (xy 44.446714 -368.765046)
			(xy 44.487923 -368.729334) (xy 44.533794 -368.699849) (xy 44.583395 -368.677192) (xy 44.635715 -368.661824)
			(xy 44.689689 -368.654057) (xy 44.716954 -368.653568) (xy 45.580554 -368.653568) (xy 45.607829 -368.653968)
			(xy 45.661825 -368.661726) (xy 45.714168 -368.677089) (xy 45.763791 -368.699746) (xy 45.809684 -368.729235)
			(xy 45.850912 -368.764955) (xy 45.886638 -368.80618) (xy 45.916132 -368.852069) (xy 45.938795 -368.901689)
			(xy 45.954164 -368.95403) (xy 45.961928 -369.008025) (xy 45.961928 -369.062565) (xy 51.142954 -369.062565)
			(xy 51.142954 -369.008035) (xy 51.150714 -368.95406) (xy 51.166076 -368.901738) (xy 51.188727 -368.852135)
			(xy 51.218206 -368.806259) (xy 51.253914 -368.765046) (xy 51.295123 -368.729334) (xy 51.340994 -368.699849)
			(xy 51.390595 -368.677192) (xy 51.442915 -368.661824) (xy 51.496889 -368.654057) (xy 51.524154 -368.653568)
			(xy 52.387754 -368.653568) (xy 52.415029 -368.653968) (xy 52.469025 -368.661726) (xy 52.521368 -368.677089)
			(xy 52.570991 -368.699746) (xy 52.616884 -368.729235) (xy 52.658112 -368.764955) (xy 52.693838 -368.80618)
			(xy 52.723332 -368.852069) (xy 52.745995 -368.901689) (xy 52.761364 -368.95403) (xy 52.769128 -369.008025)
			(xy 52.769128 -369.062565) (xy 57.950154 -369.062565) (xy 57.950154 -369.008035) (xy 57.957914 -368.95406)
			(xy 57.973276 -368.901738) (xy 57.995927 -368.852135) (xy 58.025406 -368.806259) (xy 58.061114 -368.765046)
			(xy 58.102323 -368.729334) (xy 58.148194 -368.699849) (xy 58.197795 -368.677192) (xy 58.250115 -368.661824)
			(xy 58.304089 -368.654057) (xy 58.331354 -368.653568) (xy 59.194954 -368.653568) (xy 59.222229 -368.653968)
			(xy 59.276225 -368.661726) (xy 59.328568 -368.677089) (xy 59.378191 -368.699746) (xy 59.424084 -368.729235)
			(xy 59.465312 -368.764955) (xy 59.501038 -368.80618) (xy 59.530532 -368.852069) (xy 59.553195 -368.901689)
			(xy 59.568564 -368.95403) (xy 59.576328 -369.008025) (xy 59.576328 -369.062565) (xy 64.757354 -369.062565)
			(xy 64.757354 -369.008035) (xy 64.765114 -368.95406) (xy 64.780476 -368.901738) (xy 64.803127 -368.852135)
			(xy 64.832606 -368.806259) (xy 64.868314 -368.765046) (xy 64.909523 -368.729334) (xy 64.955394 -368.699849)
			(xy 65.004995 -368.677192) (xy 65.057315 -368.661824) (xy 65.111289 -368.654057) (xy 65.138554 -368.653568)
			(xy 66.002154 -368.653568) (xy 66.029429 -368.653968) (xy 66.083425 -368.661726) (xy 66.135768 -368.677089)
			(xy 66.185391 -368.699746) (xy 66.231284 -368.729235) (xy 66.272512 -368.764955) (xy 66.308238 -368.80618)
			(xy 66.337732 -368.852069) (xy 66.360395 -368.901689) (xy 66.375764 -368.95403) (xy 66.383528 -369.008025)
			(xy 66.383528 -369.062565) (xy 68.160954 -369.062565) (xy 68.160954 -369.008035) (xy 68.168714 -368.95406)
			(xy 68.184076 -368.901738) (xy 68.206727 -368.852135) (xy 68.236206 -368.806259) (xy 68.271914 -368.765046)
			(xy 68.313123 -368.729334) (xy 68.358994 -368.699849) (xy 68.408595 -368.677192) (xy 68.460915 -368.661824)
			(xy 68.514889 -368.654057) (xy 68.542154 -368.653568) (xy 69.405754 -368.653568) (xy 69.433029 -368.653968)
			(xy 69.487025 -368.661726) (xy 69.539368 -368.677089) (xy 69.588991 -368.699746) (xy 69.634884 -368.729235)
			(xy 69.676112 -368.764955) (xy 69.711838 -368.80618) (xy 69.741332 -368.852069) (xy 69.763995 -368.901689)
			(xy 69.779364 -368.95403) (xy 69.787128 -369.008025) (xy 69.787128 -369.062569) (xy 76.863431 -369.062569)
			(xy 76.863431 -369.008031) (xy 76.871193 -368.954048) (xy 76.886558 -368.90172) (xy 76.909214 -368.85211)
			(xy 76.9387 -368.80623) (xy 76.974414 -368.765013) (xy 77.015632 -368.729298) (xy 77.061512 -368.699813)
			(xy 77.111121 -368.677157) (xy 77.16345 -368.661793) (xy 77.217433 -368.654031) (xy 77.244702 -368.653568)
			(xy 78.108302 -368.653568) (xy 78.135573 -368.653995) (xy 78.189561 -368.661757) (xy 78.241894 -368.677124)
			(xy 78.291508 -368.699782) (xy 78.337393 -368.72927) (xy 78.378613 -368.764988) (xy 78.414331 -368.806209)
			(xy 78.443819 -368.852093) (xy 78.466477 -368.901707) (xy 78.481843 -368.954041) (xy 78.489606 -369.008029)
			(xy 78.489606 -369.062569) (xy 83.670631 -369.062569) (xy 83.670631 -369.008031) (xy 83.678393 -368.954048)
			(xy 83.693758 -368.90172) (xy 83.716414 -368.85211) (xy 83.7459 -368.80623) (xy 83.781614 -368.765013)
			(xy 83.822832 -368.729298) (xy 83.868712 -368.699813) (xy 83.918321 -368.677157) (xy 83.97065 -368.661793)
			(xy 84.024633 -368.654031) (xy 84.051902 -368.653568) (xy 84.915502 -368.653568) (xy 84.942773 -368.653995)
			(xy 84.996761 -368.661757) (xy 85.049094 -368.677124) (xy 85.098708 -368.699782) (xy 85.144593 -368.72927)
			(xy 85.185813 -368.764988) (xy 85.221531 -368.806209) (xy 85.251019 -368.852093) (xy 85.273677 -368.901707)
			(xy 85.289043 -368.954041) (xy 85.296806 -369.008029) (xy 85.296806 -369.062569) (xy 90.477831 -369.062569)
			(xy 90.477831 -369.008031) (xy 90.485593 -368.954048) (xy 90.500958 -368.90172) (xy 90.523614 -368.85211)
			(xy 90.5531 -368.80623) (xy 90.588814 -368.765013) (xy 90.630032 -368.729298) (xy 90.675912 -368.699813)
			(xy 90.725521 -368.677157) (xy 90.77785 -368.661793) (xy 90.831833 -368.654031) (xy 90.859102 -368.653568)
			(xy 91.722702 -368.653568) (xy 91.749973 -368.653995) (xy 91.803961 -368.661757) (xy 91.856294 -368.677124)
			(xy 91.905908 -368.699782) (xy 91.951793 -368.72927) (xy 91.993013 -368.764988) (xy 92.028731 -368.806209)
			(xy 92.058219 -368.852093) (xy 92.080877 -368.901707) (xy 92.096243 -368.954041) (xy 92.104006 -369.008029)
			(xy 92.104006 -369.062569) (xy 97.285031 -369.062569) (xy 97.285031 -369.008031) (xy 97.292793 -368.954048)
			(xy 97.308158 -368.90172) (xy 97.330814 -368.85211) (xy 97.3603 -368.80623) (xy 97.396014 -368.765013)
			(xy 97.437232 -368.729298) (xy 97.483112 -368.699813) (xy 97.532721 -368.677157) (xy 97.58505 -368.661793)
			(xy 97.639033 -368.654031) (xy 97.666302 -368.653568) (xy 98.529902 -368.653568) (xy 98.557173 -368.653995)
			(xy 98.611161 -368.661757) (xy 98.663494 -368.677124) (xy 98.713108 -368.699782) (xy 98.758993 -368.72927)
			(xy 98.800213 -368.764988) (xy 98.835931 -368.806209) (xy 98.865419 -368.852093) (xy 98.888077 -368.901707)
			(xy 98.903443 -368.954041) (xy 98.911206 -369.008029) (xy 98.911206 -369.062569) (xy 100.688631 -369.062569)
			(xy 100.688631 -369.008031) (xy 100.696393 -368.954048) (xy 100.711758 -368.90172) (xy 100.734414 -368.85211)
			(xy 100.7639 -368.80623) (xy 100.799614 -368.765013) (xy 100.840832 -368.729298) (xy 100.886712 -368.699813)
			(xy 100.936321 -368.677157) (xy 100.98865 -368.661793) (xy 101.042633 -368.654031) (xy 101.069902 -368.653568)
			(xy 101.933502 -368.653568) (xy 101.960773 -368.653995) (xy 102.014761 -368.661757) (xy 102.067094 -368.677124)
			(xy 102.116708 -368.699782) (xy 102.162593 -368.72927) (xy 102.203813 -368.764988) (xy 102.239531 -368.806209)
			(xy 102.269019 -368.852093) (xy 102.291677 -368.901707) (xy 102.307043 -368.954041) (xy 102.314806 -369.008029)
			(xy 102.314806 -369.062567) (xy 111.435654 -369.062567) (xy 111.435654 -369.008033) (xy 111.443415 -368.954054)
			(xy 111.458779 -368.901729) (xy 111.481433 -368.852123) (xy 111.510917 -368.806246) (xy 111.546629 -368.765031)
			(xy 111.587842 -368.729319) (xy 111.633719 -368.699835) (xy 111.683325 -368.677181) (xy 111.73565 -368.661816)
			(xy 111.789629 -368.654055) (xy 111.816896 -368.653568) (xy 112.680496 -368.653568) (xy 112.707769 -368.653971)
			(xy 112.761761 -368.661734) (xy 112.814098 -368.677101) (xy 112.863716 -368.69976) (xy 112.909603 -368.72925)
			(xy 112.950827 -368.76497) (xy 112.986548 -368.806193) (xy 113.016038 -368.852081) (xy 113.038698 -368.901698)
			(xy 113.054066 -368.954035) (xy 113.061828 -369.008027) (xy 113.061828 -369.062567) (xy 118.242854 -369.062567)
			(xy 118.242854 -369.008033) (xy 118.250615 -368.954054) (xy 118.265979 -368.901729) (xy 118.288633 -368.852123)
			(xy 118.318117 -368.806246) (xy 118.353829 -368.765031) (xy 118.395042 -368.729319) (xy 118.440919 -368.699835)
			(xy 118.490525 -368.677181) (xy 118.54285 -368.661816) (xy 118.596829 -368.654055) (xy 118.624096 -368.653568)
			(xy 119.487696 -368.653568) (xy 119.514969 -368.653971) (xy 119.568961 -368.661734) (xy 119.621298 -368.677101)
			(xy 119.670916 -368.69976) (xy 119.716803 -368.72925) (xy 119.758027 -368.76497) (xy 119.793748 -368.806193)
			(xy 119.823238 -368.852081) (xy 119.845898 -368.901698) (xy 119.861266 -368.954035) (xy 119.869028 -369.008027)
			(xy 119.869028 -369.062567) (xy 125.050054 -369.062567) (xy 125.050054 -369.008033) (xy 125.057815 -368.954054)
			(xy 125.073179 -368.901729) (xy 125.095833 -368.852123) (xy 125.125317 -368.806246) (xy 125.161029 -368.765031)
			(xy 125.202242 -368.729319) (xy 125.248119 -368.699835) (xy 125.297725 -368.677181) (xy 125.35005 -368.661816)
			(xy 125.404029 -368.654055) (xy 125.431296 -368.653568) (xy 126.294896 -368.653568) (xy 126.322169 -368.653971)
			(xy 126.376161 -368.661734) (xy 126.428498 -368.677101) (xy 126.478116 -368.69976) (xy 126.524003 -368.72925)
			(xy 126.565227 -368.76497) (xy 126.600948 -368.806193) (xy 126.630438 -368.852081) (xy 126.653098 -368.901698)
			(xy 126.668466 -368.954035) (xy 126.676228 -369.008027) (xy 126.676228 -369.062567) (xy 131.857254 -369.062567)
			(xy 131.857254 -369.008033) (xy 131.865015 -368.954054) (xy 131.880379 -368.901729) (xy 131.903033 -368.852123)
			(xy 131.932517 -368.806246) (xy 131.968229 -368.765031) (xy 132.009442 -368.729319) (xy 132.055319 -368.699835)
			(xy 132.104925 -368.677181) (xy 132.15725 -368.661816) (xy 132.211229 -368.654055) (xy 132.238496 -368.653568)
			(xy 133.102096 -368.653568) (xy 133.129369 -368.653971) (xy 133.183361 -368.661734) (xy 133.235698 -368.677101)
			(xy 133.285316 -368.69976) (xy 133.331203 -368.72925) (xy 133.372427 -368.76497) (xy 133.408148 -368.806193)
			(xy 133.437638 -368.852081) (xy 133.460298 -368.901698) (xy 133.475666 -368.954035) (xy 133.483428 -369.008027)
			(xy 133.483428 -369.062567) (xy 135.260854 -369.062567) (xy 135.260854 -369.008033) (xy 135.268615 -368.954054)
			(xy 135.283979 -368.901729) (xy 135.306633 -368.852123) (xy 135.336117 -368.806246) (xy 135.371829 -368.765031)
			(xy 135.413042 -368.729319) (xy 135.458919 -368.699835) (xy 135.508525 -368.677181) (xy 135.56085 -368.661816)
			(xy 135.614829 -368.654055) (xy 135.642096 -368.653568) (xy 136.505696 -368.653568) (xy 136.532969 -368.653971)
			(xy 136.586961 -368.661734) (xy 136.639298 -368.677101) (xy 136.688916 -368.69976) (xy 136.734803 -368.72925)
			(xy 136.776027 -368.76497) (xy 136.811748 -368.806193) (xy 136.841238 -368.852081) (xy 136.863898 -368.901698)
			(xy 136.879266 -368.954035) (xy 136.887028 -369.008027) (xy 136.887028 -369.062573) (xy 136.879266 -369.116565)
			(xy 136.863898 -369.168902) (xy 136.841238 -369.218519) (xy 136.811748 -369.264407) (xy 136.776027 -369.30563)
			(xy 136.734803 -369.34135) (xy 136.688916 -369.37084) (xy 136.639298 -369.393499) (xy 136.586961 -369.408866)
			(xy 136.532969 -369.416629) (xy 136.505696 -369.417092) (xy 135.642096 -369.417092) (xy 135.614829 -369.416545)
			(xy 135.56085 -369.408784) (xy 135.508525 -369.393419) (xy 135.458919 -369.370765) (xy 135.413042 -369.341281)
			(xy 135.371829 -369.305569) (xy 135.336117 -369.264354) (xy 135.306633 -369.218477) (xy 135.283979 -369.168871)
			(xy 135.268615 -369.116546) (xy 135.260854 -369.062567) (xy 133.483428 -369.062567) (xy 133.483428 -369.062573)
			(xy 133.475666 -369.116565) (xy 133.460298 -369.168902) (xy 133.437638 -369.218519) (xy 133.408148 -369.264407)
			(xy 133.372427 -369.30563) (xy 133.331203 -369.34135) (xy 133.285316 -369.37084) (xy 133.235698 -369.393499)
			(xy 133.183361 -369.408866) (xy 133.129369 -369.416629) (xy 133.102096 -369.417092) (xy 132.238496 -369.417092)
			(xy 132.211229 -369.416545) (xy 132.15725 -369.408784) (xy 132.104925 -369.393419) (xy 132.055319 -369.370765)
			(xy 132.009442 -369.341281) (xy 131.968229 -369.305569) (xy 131.932517 -369.264354) (xy 131.903033 -369.218477)
			(xy 131.880379 -369.168871) (xy 131.865015 -369.116546) (xy 131.857254 -369.062567) (xy 126.676228 -369.062567)
			(xy 126.676228 -369.062573) (xy 126.668466 -369.116565) (xy 126.653098 -369.168902) (xy 126.630438 -369.218519)
			(xy 126.600948 -369.264407) (xy 126.565227 -369.30563) (xy 126.524003 -369.34135) (xy 126.478116 -369.37084)
			(xy 126.428498 -369.393499) (xy 126.376161 -369.408866) (xy 126.322169 -369.416629) (xy 126.294896 -369.417092)
			(xy 125.431296 -369.417092) (xy 125.404029 -369.416545) (xy 125.35005 -369.408784) (xy 125.297725 -369.393419)
			(xy 125.248119 -369.370765) (xy 125.202242 -369.341281) (xy 125.161029 -369.305569) (xy 125.125317 -369.264354)
			(xy 125.095833 -369.218477) (xy 125.073179 -369.168871) (xy 125.057815 -369.116546) (xy 125.050054 -369.062567)
			(xy 119.869028 -369.062567) (xy 119.869028 -369.062573) (xy 119.861266 -369.116565) (xy 119.845898 -369.168902)
			(xy 119.823238 -369.218519) (xy 119.793748 -369.264407) (xy 119.758027 -369.30563) (xy 119.716803 -369.34135)
			(xy 119.670916 -369.37084) (xy 119.621298 -369.393499) (xy 119.568961 -369.408866) (xy 119.514969 -369.416629)
			(xy 119.487696 -369.417092) (xy 118.624096 -369.417092) (xy 118.596829 -369.416545) (xy 118.54285 -369.408784)
			(xy 118.490525 -369.393419) (xy 118.440919 -369.370765) (xy 118.395042 -369.341281) (xy 118.353829 -369.305569)
			(xy 118.318117 -369.264354) (xy 118.288633 -369.218477) (xy 118.265979 -369.168871) (xy 118.250615 -369.116546)
			(xy 118.242854 -369.062567) (xy 113.061828 -369.062567) (xy 113.061828 -369.062573) (xy 113.054066 -369.116565)
			(xy 113.038698 -369.168902) (xy 113.016038 -369.218519) (xy 112.986548 -369.264407) (xy 112.950827 -369.30563)
			(xy 112.909603 -369.34135) (xy 112.863716 -369.37084) (xy 112.814098 -369.393499) (xy 112.761761 -369.408866)
			(xy 112.707769 -369.416629) (xy 112.680496 -369.417092) (xy 111.816896 -369.417092) (xy 111.789629 -369.416545)
			(xy 111.73565 -369.408784) (xy 111.683325 -369.393419) (xy 111.633719 -369.370765) (xy 111.587842 -369.341281)
			(xy 111.546629 -369.305569) (xy 111.510917 -369.264354) (xy 111.481433 -369.218477) (xy 111.458779 -369.168871)
			(xy 111.443415 -369.116546) (xy 111.435654 -369.062567) (xy 102.314806 -369.062567) (xy 102.314806 -369.062571)
			(xy 102.307043 -369.116559) (xy 102.291677 -369.168893) (xy 102.269019 -369.218507) (xy 102.239531 -369.264391)
			(xy 102.203813 -369.305612) (xy 102.162593 -369.34133) (xy 102.116708 -369.370818) (xy 102.067094 -369.393476)
			(xy 102.014761 -369.408843) (xy 101.960773 -369.416605) (xy 101.933502 -369.417092) (xy 101.069902 -369.417092)
			(xy 101.042633 -369.416569) (xy 100.98865 -369.408807) (xy 100.936321 -369.393443) (xy 100.886712 -369.370787)
			(xy 100.840832 -369.341302) (xy 100.799614 -369.305587) (xy 100.7639 -369.26437) (xy 100.734414 -369.21849)
			(xy 100.711758 -369.16888) (xy 100.696393 -369.116552) (xy 100.688631 -369.062569) (xy 98.911206 -369.062569)
			(xy 98.911206 -369.062571) (xy 98.903443 -369.116559) (xy 98.888077 -369.168893) (xy 98.865419 -369.218507)
			(xy 98.835931 -369.264391) (xy 98.800213 -369.305612) (xy 98.758993 -369.34133) (xy 98.713108 -369.370818)
			(xy 98.663494 -369.393476) (xy 98.611161 -369.408843) (xy 98.557173 -369.416605) (xy 98.529902 -369.417092)
			(xy 97.666302 -369.417092) (xy 97.639033 -369.416569) (xy 97.58505 -369.408807) (xy 97.532721 -369.393443)
			(xy 97.483112 -369.370787) (xy 97.437232 -369.341302) (xy 97.396014 -369.305587) (xy 97.3603 -369.26437)
			(xy 97.330814 -369.21849) (xy 97.308158 -369.16888) (xy 97.292793 -369.116552) (xy 97.285031 -369.062569)
			(xy 92.104006 -369.062569) (xy 92.104006 -369.062571) (xy 92.096243 -369.116559) (xy 92.080877 -369.168893)
			(xy 92.058219 -369.218507) (xy 92.028731 -369.264391) (xy 91.993013 -369.305612) (xy 91.951793 -369.34133)
			(xy 91.905908 -369.370818) (xy 91.856294 -369.393476) (xy 91.803961 -369.408843) (xy 91.749973 -369.416605)
			(xy 91.722702 -369.417092) (xy 90.859102 -369.417092) (xy 90.831833 -369.416569) (xy 90.77785 -369.408807)
			(xy 90.725521 -369.393443) (xy 90.675912 -369.370787) (xy 90.630032 -369.341302) (xy 90.588814 -369.305587)
			(xy 90.5531 -369.26437) (xy 90.523614 -369.21849) (xy 90.500958 -369.16888) (xy 90.485593 -369.116552)
			(xy 90.477831 -369.062569) (xy 85.296806 -369.062569) (xy 85.296806 -369.062571) (xy 85.289043 -369.116559)
			(xy 85.273677 -369.168893) (xy 85.251019 -369.218507) (xy 85.221531 -369.264391) (xy 85.185813 -369.305612)
			(xy 85.144593 -369.34133) (xy 85.098708 -369.370818) (xy 85.049094 -369.393476) (xy 84.996761 -369.408843)
			(xy 84.942773 -369.416605) (xy 84.915502 -369.417092) (xy 84.051902 -369.417092) (xy 84.024633 -369.416569)
			(xy 83.97065 -369.408807) (xy 83.918321 -369.393443) (xy 83.868712 -369.370787) (xy 83.822832 -369.341302)
			(xy 83.781614 -369.305587) (xy 83.7459 -369.26437) (xy 83.716414 -369.21849) (xy 83.693758 -369.16888)
			(xy 83.678393 -369.116552) (xy 83.670631 -369.062569) (xy 78.489606 -369.062569) (xy 78.489606 -369.062571)
			(xy 78.481843 -369.116559) (xy 78.466477 -369.168893) (xy 78.443819 -369.218507) (xy 78.414331 -369.264391)
			(xy 78.378613 -369.305612) (xy 78.337393 -369.34133) (xy 78.291508 -369.370818) (xy 78.241894 -369.393476)
			(xy 78.189561 -369.408843) (xy 78.135573 -369.416605) (xy 78.108302 -369.417092) (xy 77.244702 -369.417092)
			(xy 77.217433 -369.416569) (xy 77.16345 -369.408807) (xy 77.111121 -369.393443) (xy 77.061512 -369.370787)
			(xy 77.015632 -369.341302) (xy 76.974414 -369.305587) (xy 76.9387 -369.26437) (xy 76.909214 -369.21849)
			(xy 76.886558 -369.16888) (xy 76.871193 -369.116552) (xy 76.863431 -369.062569) (xy 69.787128 -369.062569)
			(xy 69.787128 -369.062575) (xy 69.779364 -369.11657) (xy 69.763995 -369.168911) (xy 69.741332 -369.218531)
			(xy 69.711838 -369.26442) (xy 69.676112 -369.305645) (xy 69.634884 -369.341365) (xy 69.588991 -369.370854)
			(xy 69.539368 -369.393511) (xy 69.487025 -369.408874) (xy 69.433029 -369.416632) (xy 69.405754 -369.417092)
			(xy 68.542154 -369.417092) (xy 68.514889 -369.416543) (xy 68.460915 -369.408776) (xy 68.408595 -369.393408)
			(xy 68.358994 -369.370751) (xy 68.313123 -369.341266) (xy 68.271914 -369.305554) (xy 68.236206 -369.264341)
			(xy 68.206727 -369.218465) (xy 68.184076 -369.168862) (xy 68.168714 -369.11654) (xy 68.160954 -369.062565)
			(xy 66.383528 -369.062565) (xy 66.383528 -369.062575) (xy 66.375764 -369.11657) (xy 66.360395 -369.168911)
			(xy 66.337732 -369.218531) (xy 66.308238 -369.26442) (xy 66.272512 -369.305645) (xy 66.231284 -369.341365)
			(xy 66.185391 -369.370854) (xy 66.135768 -369.393511) (xy 66.083425 -369.408874) (xy 66.029429 -369.416632)
			(xy 66.002154 -369.417092) (xy 65.138554 -369.417092) (xy 65.111289 -369.416543) (xy 65.057315 -369.408776)
			(xy 65.004995 -369.393408) (xy 64.955394 -369.370751) (xy 64.909523 -369.341266) (xy 64.868314 -369.305554)
			(xy 64.832606 -369.264341) (xy 64.803127 -369.218465) (xy 64.780476 -369.168862) (xy 64.765114 -369.11654)
			(xy 64.757354 -369.062565) (xy 59.576328 -369.062565) (xy 59.576328 -369.062575) (xy 59.568564 -369.11657)
			(xy 59.553195 -369.168911) (xy 59.530532 -369.218531) (xy 59.501038 -369.26442) (xy 59.465312 -369.305645)
			(xy 59.424084 -369.341365) (xy 59.378191 -369.370854) (xy 59.328568 -369.393511) (xy 59.276225 -369.408874)
			(xy 59.222229 -369.416632) (xy 59.194954 -369.417092) (xy 58.331354 -369.417092) (xy 58.304089 -369.416543)
			(xy 58.250115 -369.408776) (xy 58.197795 -369.393408) (xy 58.148194 -369.370751) (xy 58.102323 -369.341266)
			(xy 58.061114 -369.305554) (xy 58.025406 -369.264341) (xy 57.995927 -369.218465) (xy 57.973276 -369.168862)
			(xy 57.957914 -369.11654) (xy 57.950154 -369.062565) (xy 52.769128 -369.062565) (xy 52.769128 -369.062575)
			(xy 52.761364 -369.11657) (xy 52.745995 -369.168911) (xy 52.723332 -369.218531) (xy 52.693838 -369.26442)
			(xy 52.658112 -369.305645) (xy 52.616884 -369.341365) (xy 52.570991 -369.370854) (xy 52.521368 -369.393511)
			(xy 52.469025 -369.408874) (xy 52.415029 -369.416632) (xy 52.387754 -369.417092) (xy 51.524154 -369.417092)
			(xy 51.496889 -369.416543) (xy 51.442915 -369.408776) (xy 51.390595 -369.393408) (xy 51.340994 -369.370751)
			(xy 51.295123 -369.341266) (xy 51.253914 -369.305554) (xy 51.218206 -369.264341) (xy 51.188727 -369.218465)
			(xy 51.166076 -369.168862) (xy 51.150714 -369.11654) (xy 51.142954 -369.062565) (xy 45.961928 -369.062565)
			(xy 45.961928 -369.062575) (xy 45.954164 -369.11657) (xy 45.938795 -369.168911) (xy 45.916132 -369.218531)
			(xy 45.886638 -369.26442) (xy 45.850912 -369.305645) (xy 45.809684 -369.341365) (xy 45.763791 -369.370854)
			(xy 45.714168 -369.393511) (xy 45.661825 -369.408874) (xy 45.607829 -369.416632) (xy 45.580554 -369.417092)
			(xy 44.716954 -369.417092) (xy 44.689689 -369.416543) (xy 44.635715 -369.408776) (xy 44.583395 -369.393408)
			(xy 44.533794 -369.370751) (xy 44.487923 -369.341266) (xy 44.446714 -369.305554) (xy 44.411006 -369.264341)
			(xy 44.381527 -369.218465) (xy 44.358876 -369.168862) (xy 44.343514 -369.11654) (xy 44.335754 -369.062565)
			(xy 2.509012 -369.062565) (xy 2.509012 -370.206778) (xy 138.3665 -370.206778) (xy 138.3665 -369.343178)
			(xy 138.366986 -369.315909) (xy 138.374748 -369.261925) (xy 138.390113 -369.209595) (xy 138.41277 -369.159985)
			(xy 138.442256 -369.114104) (xy 138.477971 -369.072887) (xy 138.519188 -369.037172) (xy 138.565069 -369.007686)
			(xy 138.614679 -368.985029) (xy 138.667009 -368.969664) (xy 138.720993 -368.961902) (xy 138.775531 -368.961902)
			(xy 138.829515 -368.969664) (xy 138.881845 -368.985029) (xy 138.931455 -369.007686) (xy 138.977336 -369.037172)
			(xy 139.006648 -369.062571) (xy 143.963332 -369.062571) (xy 143.963332 -369.008029) (xy 143.971094 -368.954043)
			(xy 143.986461 -368.901711) (xy 144.009121 -368.852098) (xy 144.03861 -368.806216) (xy 144.074329 -368.764998)
			(xy 144.115551 -368.729284) (xy 144.161437 -368.699799) (xy 144.211052 -368.677146) (xy 144.263386 -368.661785)
			(xy 144.317373 -368.654028) (xy 144.344644 -368.653568) (xy 145.208244 -368.653568) (xy 145.235513 -368.653998)
			(xy 145.289497 -368.661765) (xy 145.341825 -368.677135) (xy 145.391433 -368.699796) (xy 145.437312 -368.729285)
			(xy 145.478528 -368.765003) (xy 145.514241 -368.806223) (xy 145.543725 -368.852105) (xy 145.56638 -368.901716)
			(xy 145.581744 -368.954047) (xy 145.589506 -369.00803) (xy 145.589506 -369.06257) (xy 145.589506 -369.062571)
			(xy 150.770532 -369.062571) (xy 150.770532 -369.008029) (xy 150.778294 -368.954043) (xy 150.793661 -368.901711)
			(xy 150.816321 -368.852098) (xy 150.84581 -368.806216) (xy 150.881529 -368.764998) (xy 150.922751 -368.729284)
			(xy 150.968637 -368.699799) (xy 151.018252 -368.677146) (xy 151.070586 -368.661785) (xy 151.124573 -368.654028)
			(xy 151.151844 -368.653568) (xy 152.015444 -368.653568) (xy 152.042713 -368.653998) (xy 152.096697 -368.661765)
			(xy 152.149025 -368.677135) (xy 152.198633 -368.699796) (xy 152.244512 -368.729285) (xy 152.285728 -368.765003)
			(xy 152.321441 -368.806223) (xy 152.350925 -368.852105) (xy 152.37358 -368.901716) (xy 152.388944 -368.954047)
			(xy 152.396706 -369.00803) (xy 152.396706 -369.06257) (xy 152.396706 -369.062571) (xy 157.577732 -369.062571)
			(xy 157.577732 -369.008029) (xy 157.585494 -368.954043) (xy 157.600861 -368.901711) (xy 157.623521 -368.852098)
			(xy 157.65301 -368.806216) (xy 157.688729 -368.764998) (xy 157.729951 -368.729284) (xy 157.775837 -368.699799)
			(xy 157.825452 -368.677146) (xy 157.877786 -368.661785) (xy 157.931773 -368.654028) (xy 157.959044 -368.653568)
			(xy 158.822644 -368.653568) (xy 158.849913 -368.653998) (xy 158.903897 -368.661765) (xy 158.956225 -368.677135)
			(xy 159.005833 -368.699796) (xy 159.051712 -368.729285) (xy 159.092928 -368.765003) (xy 159.128641 -368.806223)
			(xy 159.158125 -368.852105) (xy 159.18078 -368.901716) (xy 159.196144 -368.954047) (xy 159.203906 -369.00803)
			(xy 159.203906 -369.06257) (xy 159.203906 -369.062571) (xy 164.384932 -369.062571) (xy 164.384932 -369.008029)
			(xy 164.392694 -368.954043) (xy 164.408061 -368.901711) (xy 164.430721 -368.852098) (xy 164.46021 -368.806216)
			(xy 164.495929 -368.764998) (xy 164.537151 -368.729284) (xy 164.583037 -368.699799) (xy 164.632652 -368.677146)
			(xy 164.684986 -368.661785) (xy 164.738973 -368.654028) (xy 164.766244 -368.653568) (xy 165.629844 -368.653568)
			(xy 165.657113 -368.653998) (xy 165.711097 -368.661765) (xy 165.763425 -368.677135) (xy 165.813033 -368.699796)
			(xy 165.858912 -368.729285) (xy 165.900128 -368.765003) (xy 165.935841 -368.806223) (xy 165.965325 -368.852105)
			(xy 165.98798 -368.901716) (xy 166.003344 -368.954047) (xy 166.011106 -369.00803) (xy 166.011106 -369.06257)
			(xy 166.011106 -369.062571) (xy 167.788532 -369.062571) (xy 167.788532 -369.008029) (xy 167.796294 -368.954043)
			(xy 167.811661 -368.901711) (xy 167.834321 -368.852098) (xy 167.86381 -368.806216) (xy 167.899529 -368.764998)
			(xy 167.940751 -368.729284) (xy 167.986637 -368.699799) (xy 168.036252 -368.677146) (xy 168.088586 -368.661785)
			(xy 168.142573 -368.654028) (xy 168.169844 -368.653568) (xy 169.033444 -368.653568) (xy 169.060713 -368.653998)
			(xy 169.114697 -368.661765) (xy 169.167025 -368.677135) (xy 169.216633 -368.699796) (xy 169.262512 -368.729285)
			(xy 169.303728 -368.765003) (xy 169.339441 -368.806223) (xy 169.368925 -368.852105) (xy 169.39158 -368.901716)
			(xy 169.406944 -368.954047) (xy 169.414706 -369.00803) (xy 169.414706 -369.06257) (xy 169.406944 -369.116553)
			(xy 169.39158 -369.168884) (xy 169.368925 -369.218495) (xy 169.339441 -369.264377) (xy 169.303728 -369.305597)
			(xy 169.262512 -369.341315) (xy 169.216633 -369.370804) (xy 169.167025 -369.393465) (xy 169.114697 -369.408835)
			(xy 169.060713 -369.416602) (xy 169.033444 -369.417092) (xy 168.169844 -369.417092) (xy 168.142573 -369.416572)
			(xy 168.088586 -369.408815) (xy 168.036252 -369.393454) (xy 167.986637 -369.370801) (xy 167.940751 -369.341316)
			(xy 167.899529 -369.305602) (xy 167.86381 -369.264384) (xy 167.834321 -369.218502) (xy 167.811661 -369.168889)
			(xy 167.796294 -369.116557) (xy 167.788532 -369.062571) (xy 166.011106 -369.062571) (xy 166.003344 -369.116553)
			(xy 165.98798 -369.168884) (xy 165.965325 -369.218495) (xy 165.935841 -369.264377) (xy 165.900128 -369.305597)
			(xy 165.858912 -369.341315) (xy 165.813033 -369.370804) (xy 165.763425 -369.393465) (xy 165.711097 -369.408835)
			(xy 165.657113 -369.416602) (xy 165.629844 -369.417092) (xy 164.766244 -369.417092) (xy 164.738973 -369.416572)
			(xy 164.684986 -369.408815) (xy 164.632652 -369.393454) (xy 164.583037 -369.370801) (xy 164.537151 -369.341316)
			(xy 164.495929 -369.305602) (xy 164.46021 -369.264384) (xy 164.430721 -369.218502) (xy 164.408061 -369.168889)
			(xy 164.392694 -369.116557) (xy 164.384932 -369.062571) (xy 159.203906 -369.062571) (xy 159.196144 -369.116553)
			(xy 159.18078 -369.168884) (xy 159.158125 -369.218495) (xy 159.128641 -369.264377) (xy 159.092928 -369.305597)
			(xy 159.051712 -369.341315) (xy 159.005833 -369.370804) (xy 158.956225 -369.393465) (xy 158.903897 -369.408835)
			(xy 158.849913 -369.416602) (xy 158.822644 -369.417092) (xy 157.959044 -369.417092) (xy 157.931773 -369.416572)
			(xy 157.877786 -369.408815) (xy 157.825452 -369.393454) (xy 157.775837 -369.370801) (xy 157.729951 -369.341316)
			(xy 157.688729 -369.305602) (xy 157.65301 -369.264384) (xy 157.623521 -369.218502) (xy 157.600861 -369.168889)
			(xy 157.585494 -369.116557) (xy 157.577732 -369.062571) (xy 152.396706 -369.062571) (xy 152.388944 -369.116553)
			(xy 152.37358 -369.168884) (xy 152.350925 -369.218495) (xy 152.321441 -369.264377) (xy 152.285728 -369.305597)
			(xy 152.244512 -369.341315) (xy 152.198633 -369.370804) (xy 152.149025 -369.393465) (xy 152.096697 -369.408835)
			(xy 152.042713 -369.416602) (xy 152.015444 -369.417092) (xy 151.151844 -369.417092) (xy 151.124573 -369.416572)
			(xy 151.070586 -369.408815) (xy 151.018252 -369.393454) (xy 150.968637 -369.370801) (xy 150.922751 -369.341316)
			(xy 150.881529 -369.305602) (xy 150.84581 -369.264384) (xy 150.816321 -369.218502) (xy 150.793661 -369.168889)
			(xy 150.778294 -369.116557) (xy 150.770532 -369.062571) (xy 145.589506 -369.062571) (xy 145.581744 -369.116553)
			(xy 145.56638 -369.168884) (xy 145.543725 -369.218495) (xy 145.514241 -369.264377) (xy 145.478528 -369.305597)
			(xy 145.437312 -369.341315) (xy 145.391433 -369.370804) (xy 145.341825 -369.393465) (xy 145.289497 -369.408835)
			(xy 145.235513 -369.416602) (xy 145.208244 -369.417092) (xy 144.344644 -369.417092) (xy 144.317373 -369.416572)
			(xy 144.263386 -369.408815) (xy 144.211052 -369.393454) (xy 144.161437 -369.370801) (xy 144.115551 -369.341316)
			(xy 144.074329 -369.305602) (xy 144.03861 -369.264384) (xy 144.009121 -369.218502) (xy 143.986461 -369.168889)
			(xy 143.971094 -369.116557) (xy 143.963332 -369.062571) (xy 139.006648 -369.062571) (xy 139.018553 -369.072887)
			(xy 139.054268 -369.114104) (xy 139.083754 -369.159985) (xy 139.106411 -369.209595) (xy 139.121776 -369.261925)
			(xy 139.129538 -369.315909) (xy 139.130024 -369.343178) (xy 139.130024 -370.206778) (xy 139.129538 -370.234047)
			(xy 139.121776 -370.288031) (xy 139.106411 -370.340361) (xy 139.083754 -370.389971) (xy 139.071223 -370.40947)
			(xy 141.572996 -370.40947) (xy 141.572996 -369.54587) (xy 141.573482 -369.518619) (xy 141.581238 -369.464671)
			(xy 141.596593 -369.412376) (xy 141.619235 -369.362799) (xy 141.648701 -369.316949) (xy 141.684392 -369.275758)
			(xy 141.725583 -369.240067) (xy 141.771433 -369.210601) (xy 141.82101 -369.187959) (xy 141.873305 -369.172604)
			(xy 141.927253 -369.164848) (xy 141.981755 -369.164848) (xy 142.035703 -369.172604) (xy 142.087998 -369.187959)
			(xy 142.137575 -369.210601) (xy 142.183425 -369.240067) (xy 142.224616 -369.275758) (xy 142.260307 -369.316949)
			(xy 142.289773 -369.362799) (xy 142.312415 -369.412376) (xy 142.32777 -369.464671) (xy 142.335526 -369.518619)
			(xy 142.336012 -369.54587) (xy 142.336012 -369.62565) (xy 175.203103 -369.62565) (xy 175.203103 -369.57115)
			(xy 175.210859 -369.517206) (xy 175.226214 -369.464914) (xy 175.248854 -369.41534) (xy 175.278318 -369.369493)
			(xy 175.314008 -369.328305) (xy 175.355196 -369.292616) (xy 175.401044 -369.263152) (xy 175.450618 -369.240512)
			(xy 175.50291 -369.225158) (xy 175.556854 -369.217403) (xy 175.584104 -369.21694) (xy 176.447704 -369.21694)
			(xy 176.474958 -369.21733) (xy 176.528913 -369.225088) (xy 176.581213 -369.240446) (xy 176.630796 -369.26309)
			(xy 176.676652 -369.29256) (xy 176.717847 -369.328256) (xy 176.753543 -369.369451) (xy 176.783012 -369.415307)
			(xy 176.805656 -369.46489) (xy 176.821013 -369.517191) (xy 176.82877 -369.571146) (xy 176.82877 -369.625654)
			(xy 176.821013 -369.679609) (xy 176.805656 -369.73191) (xy 176.783012 -369.781493) (xy 176.753543 -369.827349)
			(xy 176.717847 -369.868544) (xy 176.676652 -369.90424) (xy 176.630796 -369.93371) (xy 176.581213 -369.956354)
			(xy 176.528913 -369.971712) (xy 176.474958 -369.97947) (xy 176.447704 -369.979956) (xy 175.584104 -369.979956)
			(xy 175.556854 -369.979397) (xy 175.50291 -369.971642) (xy 175.450618 -369.956288) (xy 175.401044 -369.933648)
			(xy 175.355196 -369.904184) (xy 175.314008 -369.868495) (xy 175.278318 -369.827307) (xy 175.248854 -369.78146)
			(xy 175.226214 -369.731886) (xy 175.210859 -369.679594) (xy 175.203103 -369.62565) (xy 142.336012 -369.62565)
			(xy 142.336012 -370.40947) (xy 142.335526 -370.436721) (xy 142.32777 -370.490669) (xy 142.312415 -370.542964)
			(xy 142.289773 -370.592541) (xy 142.260307 -370.638391) (xy 142.224616 -370.679582) (xy 142.183425 -370.715273)
			(xy 142.137575 -370.744739) (xy 142.087998 -370.767381) (xy 142.035703 -370.782736) (xy 141.981755 -370.790492)
			(xy 141.927253 -370.790492) (xy 141.873305 -370.782736) (xy 141.82101 -370.767381) (xy 141.771433 -370.744739)
			(xy 141.725583 -370.715273) (xy 141.684392 -370.679582) (xy 141.648701 -370.638391) (xy 141.619235 -370.592541)
			(xy 141.596593 -370.542964) (xy 141.581238 -370.490669) (xy 141.573482 -370.436721) (xy 141.572996 -370.40947)
			(xy 139.071223 -370.40947) (xy 139.054268 -370.435852) (xy 139.018553 -370.477069) (xy 138.977336 -370.512784)
			(xy 138.931455 -370.54227) (xy 138.881845 -370.564927) (xy 138.829515 -370.580292) (xy 138.775531 -370.588054)
			(xy 138.720993 -370.588054) (xy 138.667009 -370.580292) (xy 138.614679 -370.564927) (xy 138.565069 -370.54227)
			(xy 138.519188 -370.512784) (xy 138.477971 -370.477069) (xy 138.442256 -370.435852) (xy 138.41277 -370.389971)
			(xy 138.390113 -370.340361) (xy 138.374748 -370.288031) (xy 138.366986 -370.234047) (xy 138.3665 -370.206778)
			(xy 2.509012 -370.206778) (xy 2.509012 -371.526365) (xy 42.633954 -371.526365) (xy 42.633954 -371.471835)
			(xy 42.641714 -371.41786) (xy 42.657076 -371.365538) (xy 42.679727 -371.315935) (xy 42.709206 -371.270059)
			(xy 42.744914 -371.228846) (xy 42.786123 -371.193134) (xy 42.831994 -371.163649) (xy 42.881595 -371.140992)
			(xy 42.933915 -371.125624) (xy 42.987889 -371.117857) (xy 43.015154 -371.117368) (xy 43.878754 -371.117368)
			(xy 43.906029 -371.117768) (xy 43.960025 -371.125526) (xy 44.012368 -371.140889) (xy 44.061991 -371.163546)
			(xy 44.107884 -371.193035) (xy 44.149112 -371.228755) (xy 44.184838 -371.26998) (xy 44.214332 -371.315869)
			(xy 44.236995 -371.365489) (xy 44.252364 -371.41783) (xy 44.260128 -371.471825) (xy 44.260128 -371.526365)
			(xy 49.441154 -371.526365) (xy 49.441154 -371.471835) (xy 49.448914 -371.41786) (xy 49.464276 -371.365538)
			(xy 49.486927 -371.315935) (xy 49.516406 -371.270059) (xy 49.552114 -371.228846) (xy 49.593323 -371.193134)
			(xy 49.639194 -371.163649) (xy 49.688795 -371.140992) (xy 49.741115 -371.125624) (xy 49.795089 -371.117857)
			(xy 49.822354 -371.117368) (xy 50.685954 -371.117368) (xy 50.713229 -371.117768) (xy 50.767225 -371.125526)
			(xy 50.819568 -371.140889) (xy 50.869191 -371.163546) (xy 50.915084 -371.193035) (xy 50.956312 -371.228755)
			(xy 50.992038 -371.26998) (xy 51.021532 -371.315869) (xy 51.044195 -371.365489) (xy 51.059564 -371.41783)
			(xy 51.067328 -371.471825) (xy 51.067328 -371.526365) (xy 56.248354 -371.526365) (xy 56.248354 -371.471835)
			(xy 56.256114 -371.41786) (xy 56.271476 -371.365538) (xy 56.294127 -371.315935) (xy 56.323606 -371.270059)
			(xy 56.359314 -371.228846) (xy 56.400523 -371.193134) (xy 56.446394 -371.163649) (xy 56.495995 -371.140992)
			(xy 56.548315 -371.125624) (xy 56.602289 -371.117857) (xy 56.629554 -371.117368) (xy 57.493154 -371.117368)
			(xy 57.520429 -371.117768) (xy 57.574425 -371.125526) (xy 57.626768 -371.140889) (xy 57.676391 -371.163546)
			(xy 57.722284 -371.193035) (xy 57.763512 -371.228755) (xy 57.799238 -371.26998) (xy 57.828732 -371.315869)
			(xy 57.851395 -371.365489) (xy 57.866764 -371.41783) (xy 57.874528 -371.471825) (xy 57.874528 -371.526365)
			(xy 63.055554 -371.526365) (xy 63.055554 -371.471835) (xy 63.063314 -371.41786) (xy 63.078676 -371.365538)
			(xy 63.101327 -371.315935) (xy 63.130806 -371.270059) (xy 63.166514 -371.228846) (xy 63.207723 -371.193134)
			(xy 63.253594 -371.163649) (xy 63.303195 -371.140992) (xy 63.355515 -371.125624) (xy 63.409489 -371.117857)
			(xy 63.436754 -371.117368) (xy 64.300354 -371.117368) (xy 64.327629 -371.117768) (xy 64.381625 -371.125526)
			(xy 64.433968 -371.140889) (xy 64.483591 -371.163546) (xy 64.529484 -371.193035) (xy 64.570712 -371.228755)
			(xy 64.606438 -371.26998) (xy 64.635932 -371.315869) (xy 64.658595 -371.365489) (xy 64.673964 -371.41783)
			(xy 64.681728 -371.471825) (xy 64.681728 -371.526369) (xy 75.161631 -371.526369) (xy 75.161631 -371.471831)
			(xy 75.169393 -371.417848) (xy 75.184758 -371.36552) (xy 75.207414 -371.31591) (xy 75.2369 -371.27003)
			(xy 75.272614 -371.228813) (xy 75.313832 -371.193098) (xy 75.359712 -371.163613) (xy 75.409321 -371.140957)
			(xy 75.46165 -371.125593) (xy 75.515633 -371.117831) (xy 75.542902 -371.117368) (xy 76.406502 -371.117368)
			(xy 76.433773 -371.117795) (xy 76.487761 -371.125557) (xy 76.540094 -371.140924) (xy 76.589708 -371.163582)
			(xy 76.635593 -371.19307) (xy 76.676813 -371.228788) (xy 76.712531 -371.270009) (xy 76.742019 -371.315893)
			(xy 76.764677 -371.365507) (xy 76.780043 -371.417841) (xy 76.787806 -371.471829) (xy 76.787806 -371.526369)
			(xy 81.968831 -371.526369) (xy 81.968831 -371.471831) (xy 81.976593 -371.417848) (xy 81.991958 -371.36552)
			(xy 82.014614 -371.31591) (xy 82.0441 -371.27003) (xy 82.079814 -371.228813) (xy 82.121032 -371.193098)
			(xy 82.166912 -371.163613) (xy 82.216521 -371.140957) (xy 82.26885 -371.125593) (xy 82.322833 -371.117831)
			(xy 82.350102 -371.117368) (xy 83.213702 -371.117368) (xy 83.240973 -371.117795) (xy 83.294961 -371.125557)
			(xy 83.347294 -371.140924) (xy 83.396908 -371.163582) (xy 83.442793 -371.19307) (xy 83.484013 -371.228788)
			(xy 83.519731 -371.270009) (xy 83.549219 -371.315893) (xy 83.571877 -371.365507) (xy 83.587243 -371.417841)
			(xy 83.595006 -371.471829) (xy 83.595006 -371.526369) (xy 88.776031 -371.526369) (xy 88.776031 -371.471831)
			(xy 88.783793 -371.417848) (xy 88.799158 -371.36552) (xy 88.821814 -371.31591) (xy 88.8513 -371.27003)
			(xy 88.887014 -371.228813) (xy 88.928232 -371.193098) (xy 88.974112 -371.163613) (xy 89.023721 -371.140957)
			(xy 89.07605 -371.125593) (xy 89.130033 -371.117831) (xy 89.157302 -371.117368) (xy 90.020902 -371.117368)
			(xy 90.048173 -371.117795) (xy 90.102161 -371.125557) (xy 90.154494 -371.140924) (xy 90.204108 -371.163582)
			(xy 90.249993 -371.19307) (xy 90.291213 -371.228788) (xy 90.326931 -371.270009) (xy 90.356419 -371.315893)
			(xy 90.379077 -371.365507) (xy 90.394443 -371.417841) (xy 90.402206 -371.471829) (xy 90.402206 -371.526369)
			(xy 95.583231 -371.526369) (xy 95.583231 -371.471831) (xy 95.590993 -371.417848) (xy 95.606358 -371.36552)
			(xy 95.629014 -371.31591) (xy 95.6585 -371.27003) (xy 95.694214 -371.228813) (xy 95.735432 -371.193098)
			(xy 95.781312 -371.163613) (xy 95.830921 -371.140957) (xy 95.88325 -371.125593) (xy 95.937233 -371.117831)
			(xy 95.964502 -371.117368) (xy 96.828102 -371.117368) (xy 96.855373 -371.117795) (xy 96.909361 -371.125557)
			(xy 96.961694 -371.140924) (xy 97.011308 -371.163582) (xy 97.057193 -371.19307) (xy 97.098413 -371.228788)
			(xy 97.134131 -371.270009) (xy 97.163619 -371.315893) (xy 97.186277 -371.365507) (xy 97.201643 -371.417841)
			(xy 97.209406 -371.471829) (xy 97.209406 -371.526367) (xy 109.733854 -371.526367) (xy 109.733854 -371.471833)
			(xy 109.741615 -371.417854) (xy 109.756979 -371.365529) (xy 109.779633 -371.315923) (xy 109.809117 -371.270046)
			(xy 109.844829 -371.228831) (xy 109.886042 -371.193119) (xy 109.931919 -371.163635) (xy 109.981525 -371.140981)
			(xy 110.03385 -371.125616) (xy 110.087829 -371.117855) (xy 110.115096 -371.117368) (xy 110.978696 -371.117368)
			(xy 111.005969 -371.117771) (xy 111.059961 -371.125534) (xy 111.112298 -371.140901) (xy 111.161916 -371.16356)
			(xy 111.207803 -371.19305) (xy 111.249027 -371.22877) (xy 111.284748 -371.269993) (xy 111.314238 -371.315881)
			(xy 111.336898 -371.365498) (xy 111.352266 -371.417835) (xy 111.360028 -371.471827) (xy 111.360028 -371.526367)
			(xy 116.541054 -371.526367) (xy 116.541054 -371.471833) (xy 116.548815 -371.417854) (xy 116.564179 -371.365529)
			(xy 116.586833 -371.315923) (xy 116.616317 -371.270046) (xy 116.652029 -371.228831) (xy 116.693242 -371.193119)
			(xy 116.739119 -371.163635) (xy 116.788725 -371.140981) (xy 116.84105 -371.125616) (xy 116.895029 -371.117855)
			(xy 116.922296 -371.117368) (xy 117.785896 -371.117368) (xy 117.813169 -371.117771) (xy 117.867161 -371.125534)
			(xy 117.919498 -371.140901) (xy 117.969116 -371.16356) (xy 118.015003 -371.19305) (xy 118.056227 -371.22877)
			(xy 118.091948 -371.269993) (xy 118.121438 -371.315881) (xy 118.144098 -371.365498) (xy 118.159466 -371.417835)
			(xy 118.167228 -371.471827) (xy 118.167228 -371.526367) (xy 123.348254 -371.526367) (xy 123.348254 -371.471833)
			(xy 123.356015 -371.417854) (xy 123.371379 -371.365529) (xy 123.394033 -371.315923) (xy 123.423517 -371.270046)
			(xy 123.459229 -371.228831) (xy 123.500442 -371.193119) (xy 123.546319 -371.163635) (xy 123.595925 -371.140981)
			(xy 123.64825 -371.125616) (xy 123.702229 -371.117855) (xy 123.729496 -371.117368) (xy 124.593096 -371.117368)
			(xy 124.620369 -371.117771) (xy 124.674361 -371.125534) (xy 124.726698 -371.140901) (xy 124.776316 -371.16356)
			(xy 124.822203 -371.19305) (xy 124.863427 -371.22877) (xy 124.899148 -371.269993) (xy 124.928638 -371.315881)
			(xy 124.951298 -371.365498) (xy 124.966666 -371.417835) (xy 124.974428 -371.471827) (xy 124.974428 -371.526367)
			(xy 130.155454 -371.526367) (xy 130.155454 -371.471833) (xy 130.163215 -371.417854) (xy 130.178579 -371.365529)
			(xy 130.201233 -371.315923) (xy 130.230717 -371.270046) (xy 130.266429 -371.228831) (xy 130.307642 -371.193119)
			(xy 130.353519 -371.163635) (xy 130.403125 -371.140981) (xy 130.45545 -371.125616) (xy 130.509429 -371.117855)
			(xy 130.536696 -371.117368) (xy 131.400296 -371.117368) (xy 131.427569 -371.117771) (xy 131.481561 -371.125534)
			(xy 131.533898 -371.140901) (xy 131.583516 -371.16356) (xy 131.629403 -371.19305) (xy 131.670627 -371.22877)
			(xy 131.706348 -371.269993) (xy 131.735838 -371.315881) (xy 131.758498 -371.365498) (xy 131.773866 -371.417835)
			(xy 131.781628 -371.471827) (xy 131.781628 -371.526371) (xy 142.261532 -371.526371) (xy 142.261532 -371.471829)
			(xy 142.269294 -371.417843) (xy 142.284661 -371.365511) (xy 142.307321 -371.315898) (xy 142.33681 -371.270016)
			(xy 142.372529 -371.228798) (xy 142.413751 -371.193084) (xy 142.459637 -371.163599) (xy 142.509252 -371.140946)
			(xy 142.561586 -371.125585) (xy 142.615573 -371.117828) (xy 142.642844 -371.117368) (xy 143.506444 -371.117368)
			(xy 143.533713 -371.117798) (xy 143.587697 -371.125565) (xy 143.640025 -371.140935) (xy 143.689633 -371.163596)
			(xy 143.735512 -371.193085) (xy 143.776728 -371.228803) (xy 143.812441 -371.270023) (xy 143.841925 -371.315905)
			(xy 143.86458 -371.365516) (xy 143.879944 -371.417847) (xy 143.887706 -371.47183) (xy 143.887706 -371.52637)
			(xy 143.887706 -371.526371) (xy 149.068732 -371.526371) (xy 149.068732 -371.471829) (xy 149.076494 -371.417843)
			(xy 149.091861 -371.365511) (xy 149.114521 -371.315898) (xy 149.14401 -371.270016) (xy 149.179729 -371.228798)
			(xy 149.220951 -371.193084) (xy 149.266837 -371.163599) (xy 149.316452 -371.140946) (xy 149.368786 -371.125585)
			(xy 149.422773 -371.117828) (xy 149.450044 -371.117368) (xy 150.313644 -371.117368) (xy 150.340913 -371.117798)
			(xy 150.394897 -371.125565) (xy 150.447225 -371.140935) (xy 150.496833 -371.163596) (xy 150.542712 -371.193085)
			(xy 150.583928 -371.228803) (xy 150.619641 -371.270023) (xy 150.649125 -371.315905) (xy 150.67178 -371.365516)
			(xy 150.687144 -371.417847) (xy 150.694906 -371.47183) (xy 150.694906 -371.52637) (xy 150.694906 -371.526371)
			(xy 155.875932 -371.526371) (xy 155.875932 -371.471829) (xy 155.883694 -371.417843) (xy 155.899061 -371.365511)
			(xy 155.921721 -371.315898) (xy 155.95121 -371.270016) (xy 155.986929 -371.228798) (xy 156.028151 -371.193084)
			(xy 156.074037 -371.163599) (xy 156.123652 -371.140946) (xy 156.175986 -371.125585) (xy 156.229973 -371.117828)
			(xy 156.257244 -371.117368) (xy 157.120844 -371.117368) (xy 157.148113 -371.117798) (xy 157.202097 -371.125565)
			(xy 157.254425 -371.140935) (xy 157.304033 -371.163596) (xy 157.349912 -371.193085) (xy 157.391128 -371.228803)
			(xy 157.426841 -371.270023) (xy 157.456325 -371.315905) (xy 157.47898 -371.365516) (xy 157.494344 -371.417847)
			(xy 157.502106 -371.47183) (xy 157.502106 -371.52637) (xy 157.502106 -371.526371) (xy 162.683132 -371.526371)
			(xy 162.683132 -371.471829) (xy 162.690894 -371.417843) (xy 162.706261 -371.365511) (xy 162.728921 -371.315898)
			(xy 162.75841 -371.270016) (xy 162.794129 -371.228798) (xy 162.835351 -371.193084) (xy 162.881237 -371.163599)
			(xy 162.930852 -371.140946) (xy 162.983186 -371.125585) (xy 163.037173 -371.117828) (xy 163.064444 -371.117368)
			(xy 163.928044 -371.117368) (xy 163.955313 -371.117798) (xy 164.009297 -371.125565) (xy 164.061625 -371.140935)
			(xy 164.111233 -371.163596) (xy 164.157112 -371.193085) (xy 164.198328 -371.228803) (xy 164.234041 -371.270023)
			(xy 164.263525 -371.315905) (xy 164.28618 -371.365516) (xy 164.301544 -371.417847) (xy 164.309306 -371.47183)
			(xy 164.309306 -371.52637) (xy 164.301544 -371.580353) (xy 164.28618 -371.632684) (xy 164.263525 -371.682295)
			(xy 164.234041 -371.728177) (xy 164.198328 -371.769397) (xy 164.157112 -371.805115) (xy 164.111233 -371.834604)
			(xy 164.061625 -371.857265) (xy 164.009297 -371.872635) (xy 163.955313 -371.880402) (xy 163.928044 -371.880892)
			(xy 163.064444 -371.880892) (xy 163.037173 -371.880372) (xy 162.983186 -371.872615) (xy 162.930852 -371.857254)
			(xy 162.881237 -371.834601) (xy 162.835351 -371.805116) (xy 162.794129 -371.769402) (xy 162.75841 -371.728184)
			(xy 162.728921 -371.682302) (xy 162.706261 -371.632689) (xy 162.690894 -371.580357) (xy 162.683132 -371.526371)
			(xy 157.502106 -371.526371) (xy 157.494344 -371.580353) (xy 157.47898 -371.632684) (xy 157.456325 -371.682295)
			(xy 157.426841 -371.728177) (xy 157.391128 -371.769397) (xy 157.349912 -371.805115) (xy 157.304033 -371.834604)
			(xy 157.254425 -371.857265) (xy 157.202097 -371.872635) (xy 157.148113 -371.880402) (xy 157.120844 -371.880892)
			(xy 156.257244 -371.880892) (xy 156.229973 -371.880372) (xy 156.175986 -371.872615) (xy 156.123652 -371.857254)
			(xy 156.074037 -371.834601) (xy 156.028151 -371.805116) (xy 155.986929 -371.769402) (xy 155.95121 -371.728184)
			(xy 155.921721 -371.682302) (xy 155.899061 -371.632689) (xy 155.883694 -371.580357) (xy 155.875932 -371.526371)
			(xy 150.694906 -371.526371) (xy 150.687144 -371.580353) (xy 150.67178 -371.632684) (xy 150.649125 -371.682295)
			(xy 150.619641 -371.728177) (xy 150.583928 -371.769397) (xy 150.542712 -371.805115) (xy 150.496833 -371.834604)
			(xy 150.447225 -371.857265) (xy 150.394897 -371.872635) (xy 150.340913 -371.880402) (xy 150.313644 -371.880892)
			(xy 149.450044 -371.880892) (xy 149.422773 -371.880372) (xy 149.368786 -371.872615) (xy 149.316452 -371.857254)
			(xy 149.266837 -371.834601) (xy 149.220951 -371.805116) (xy 149.179729 -371.769402) (xy 149.14401 -371.728184)
			(xy 149.114521 -371.682302) (xy 149.091861 -371.632689) (xy 149.076494 -371.580357) (xy 149.068732 -371.526371)
			(xy 143.887706 -371.526371) (xy 143.879944 -371.580353) (xy 143.86458 -371.632684) (xy 143.841925 -371.682295)
			(xy 143.812441 -371.728177) (xy 143.776728 -371.769397) (xy 143.735512 -371.805115) (xy 143.689633 -371.834604)
			(xy 143.640025 -371.857265) (xy 143.587697 -371.872635) (xy 143.533713 -371.880402) (xy 143.506444 -371.880892)
			(xy 142.642844 -371.880892) (xy 142.615573 -371.880372) (xy 142.561586 -371.872615) (xy 142.509252 -371.857254)
			(xy 142.459637 -371.834601) (xy 142.413751 -371.805116) (xy 142.372529 -371.769402) (xy 142.33681 -371.728184)
			(xy 142.307321 -371.682302) (xy 142.284661 -371.632689) (xy 142.269294 -371.580357) (xy 142.261532 -371.526371)
			(xy 131.781628 -371.526371) (xy 131.781628 -371.526373) (xy 131.773866 -371.580365) (xy 131.758498 -371.632702)
			(xy 131.735838 -371.682319) (xy 131.706348 -371.728207) (xy 131.670627 -371.76943) (xy 131.629403 -371.80515)
			(xy 131.583516 -371.83464) (xy 131.533898 -371.857299) (xy 131.481561 -371.872666) (xy 131.427569 -371.880429)
			(xy 131.400296 -371.880892) (xy 130.536696 -371.880892) (xy 130.509429 -371.880345) (xy 130.45545 -371.872584)
			(xy 130.403125 -371.857219) (xy 130.353519 -371.834565) (xy 130.307642 -371.805081) (xy 130.266429 -371.769369)
			(xy 130.230717 -371.728154) (xy 130.201233 -371.682277) (xy 130.178579 -371.632671) (xy 130.163215 -371.580346)
			(xy 130.155454 -371.526367) (xy 124.974428 -371.526367) (xy 124.974428 -371.526373) (xy 124.966666 -371.580365)
			(xy 124.951298 -371.632702) (xy 124.928638 -371.682319) (xy 124.899148 -371.728207) (xy 124.863427 -371.76943)
			(xy 124.822203 -371.80515) (xy 124.776316 -371.83464) (xy 124.726698 -371.857299) (xy 124.674361 -371.872666)
			(xy 124.620369 -371.880429) (xy 124.593096 -371.880892) (xy 123.729496 -371.880892) (xy 123.702229 -371.880345)
			(xy 123.64825 -371.872584) (xy 123.595925 -371.857219) (xy 123.546319 -371.834565) (xy 123.500442 -371.805081)
			(xy 123.459229 -371.769369) (xy 123.423517 -371.728154) (xy 123.394033 -371.682277) (xy 123.371379 -371.632671)
			(xy 123.356015 -371.580346) (xy 123.348254 -371.526367) (xy 118.167228 -371.526367) (xy 118.167228 -371.526373)
			(xy 118.159466 -371.580365) (xy 118.144098 -371.632702) (xy 118.121438 -371.682319) (xy 118.091948 -371.728207)
			(xy 118.056227 -371.76943) (xy 118.015003 -371.80515) (xy 117.969116 -371.83464) (xy 117.919498 -371.857299)
			(xy 117.867161 -371.872666) (xy 117.813169 -371.880429) (xy 117.785896 -371.880892) (xy 116.922296 -371.880892)
			(xy 116.895029 -371.880345) (xy 116.84105 -371.872584) (xy 116.788725 -371.857219) (xy 116.739119 -371.834565)
			(xy 116.693242 -371.805081) (xy 116.652029 -371.769369) (xy 116.616317 -371.728154) (xy 116.586833 -371.682277)
			(xy 116.564179 -371.632671) (xy 116.548815 -371.580346) (xy 116.541054 -371.526367) (xy 111.360028 -371.526367)
			(xy 111.360028 -371.526373) (xy 111.352266 -371.580365) (xy 111.336898 -371.632702) (xy 111.314238 -371.682319)
			(xy 111.284748 -371.728207) (xy 111.249027 -371.76943) (xy 111.207803 -371.80515) (xy 111.161916 -371.83464)
			(xy 111.112298 -371.857299) (xy 111.059961 -371.872666) (xy 111.005969 -371.880429) (xy 110.978696 -371.880892)
			(xy 110.115096 -371.880892) (xy 110.087829 -371.880345) (xy 110.03385 -371.872584) (xy 109.981525 -371.857219)
			(xy 109.931919 -371.834565) (xy 109.886042 -371.805081) (xy 109.844829 -371.769369) (xy 109.809117 -371.728154)
			(xy 109.779633 -371.682277) (xy 109.756979 -371.632671) (xy 109.741615 -371.580346) (xy 109.733854 -371.526367)
			(xy 97.209406 -371.526367) (xy 97.209406 -371.526371) (xy 97.201643 -371.580359) (xy 97.186277 -371.632693)
			(xy 97.163619 -371.682307) (xy 97.134131 -371.728191) (xy 97.098413 -371.769412) (xy 97.057193 -371.80513)
			(xy 97.011308 -371.834618) (xy 96.961694 -371.857276) (xy 96.909361 -371.872643) (xy 96.855373 -371.880405)
			(xy 96.828102 -371.880892) (xy 95.964502 -371.880892) (xy 95.937233 -371.880369) (xy 95.88325 -371.872607)
			(xy 95.830921 -371.857243) (xy 95.781312 -371.834587) (xy 95.735432 -371.805102) (xy 95.694214 -371.769387)
			(xy 95.6585 -371.72817) (xy 95.629014 -371.68229) (xy 95.606358 -371.63268) (xy 95.590993 -371.580352)
			(xy 95.583231 -371.526369) (xy 90.402206 -371.526369) (xy 90.402206 -371.526371) (xy 90.394443 -371.580359)
			(xy 90.379077 -371.632693) (xy 90.356419 -371.682307) (xy 90.326931 -371.728191) (xy 90.291213 -371.769412)
			(xy 90.249993 -371.80513) (xy 90.204108 -371.834618) (xy 90.154494 -371.857276) (xy 90.102161 -371.872643)
			(xy 90.048173 -371.880405) (xy 90.020902 -371.880892) (xy 89.157302 -371.880892) (xy 89.130033 -371.880369)
			(xy 89.07605 -371.872607) (xy 89.023721 -371.857243) (xy 88.974112 -371.834587) (xy 88.928232 -371.805102)
			(xy 88.887014 -371.769387) (xy 88.8513 -371.72817) (xy 88.821814 -371.68229) (xy 88.799158 -371.63268)
			(xy 88.783793 -371.580352) (xy 88.776031 -371.526369) (xy 83.595006 -371.526369) (xy 83.595006 -371.526371)
			(xy 83.587243 -371.580359) (xy 83.571877 -371.632693) (xy 83.549219 -371.682307) (xy 83.519731 -371.728191)
			(xy 83.484013 -371.769412) (xy 83.442793 -371.80513) (xy 83.396908 -371.834618) (xy 83.347294 -371.857276)
			(xy 83.294961 -371.872643) (xy 83.240973 -371.880405) (xy 83.213702 -371.880892) (xy 82.350102 -371.880892)
			(xy 82.322833 -371.880369) (xy 82.26885 -371.872607) (xy 82.216521 -371.857243) (xy 82.166912 -371.834587)
			(xy 82.121032 -371.805102) (xy 82.079814 -371.769387) (xy 82.0441 -371.72817) (xy 82.014614 -371.68229)
			(xy 81.991958 -371.63268) (xy 81.976593 -371.580352) (xy 81.968831 -371.526369) (xy 76.787806 -371.526369)
			(xy 76.787806 -371.526371) (xy 76.780043 -371.580359) (xy 76.764677 -371.632693) (xy 76.742019 -371.682307)
			(xy 76.712531 -371.728191) (xy 76.676813 -371.769412) (xy 76.635593 -371.80513) (xy 76.589708 -371.834618)
			(xy 76.540094 -371.857276) (xy 76.487761 -371.872643) (xy 76.433773 -371.880405) (xy 76.406502 -371.880892)
			(xy 75.542902 -371.880892) (xy 75.515633 -371.880369) (xy 75.46165 -371.872607) (xy 75.409321 -371.857243)
			(xy 75.359712 -371.834587) (xy 75.313832 -371.805102) (xy 75.272614 -371.769387) (xy 75.2369 -371.72817)
			(xy 75.207414 -371.68229) (xy 75.184758 -371.63268) (xy 75.169393 -371.580352) (xy 75.161631 -371.526369)
			(xy 64.681728 -371.526369) (xy 64.681728 -371.526375) (xy 64.673964 -371.58037) (xy 64.658595 -371.632711)
			(xy 64.635932 -371.682331) (xy 64.606438 -371.72822) (xy 64.570712 -371.769445) (xy 64.529484 -371.805165)
			(xy 64.483591 -371.834654) (xy 64.433968 -371.857311) (xy 64.381625 -371.872674) (xy 64.327629 -371.880432)
			(xy 64.300354 -371.880892) (xy 63.436754 -371.880892) (xy 63.409489 -371.880343) (xy 63.355515 -371.872576)
			(xy 63.303195 -371.857208) (xy 63.253594 -371.834551) (xy 63.207723 -371.805066) (xy 63.166514 -371.769354)
			(xy 63.130806 -371.728141) (xy 63.101327 -371.682265) (xy 63.078676 -371.632662) (xy 63.063314 -371.58034)
			(xy 63.055554 -371.526365) (xy 57.874528 -371.526365) (xy 57.874528 -371.526375) (xy 57.866764 -371.58037)
			(xy 57.851395 -371.632711) (xy 57.828732 -371.682331) (xy 57.799238 -371.72822) (xy 57.763512 -371.769445)
			(xy 57.722284 -371.805165) (xy 57.676391 -371.834654) (xy 57.626768 -371.857311) (xy 57.574425 -371.872674)
			(xy 57.520429 -371.880432) (xy 57.493154 -371.880892) (xy 56.629554 -371.880892) (xy 56.602289 -371.880343)
			(xy 56.548315 -371.872576) (xy 56.495995 -371.857208) (xy 56.446394 -371.834551) (xy 56.400523 -371.805066)
			(xy 56.359314 -371.769354) (xy 56.323606 -371.728141) (xy 56.294127 -371.682265) (xy 56.271476 -371.632662)
			(xy 56.256114 -371.58034) (xy 56.248354 -371.526365) (xy 51.067328 -371.526365) (xy 51.067328 -371.526375)
			(xy 51.059564 -371.58037) (xy 51.044195 -371.632711) (xy 51.021532 -371.682331) (xy 50.992038 -371.72822)
			(xy 50.956312 -371.769445) (xy 50.915084 -371.805165) (xy 50.869191 -371.834654) (xy 50.819568 -371.857311)
			(xy 50.767225 -371.872674) (xy 50.713229 -371.880432) (xy 50.685954 -371.880892) (xy 49.822354 -371.880892)
			(xy 49.795089 -371.880343) (xy 49.741115 -371.872576) (xy 49.688795 -371.857208) (xy 49.639194 -371.834551)
			(xy 49.593323 -371.805066) (xy 49.552114 -371.769354) (xy 49.516406 -371.728141) (xy 49.486927 -371.682265)
			(xy 49.464276 -371.632662) (xy 49.448914 -371.58034) (xy 49.441154 -371.526365) (xy 44.260128 -371.526365)
			(xy 44.260128 -371.526375) (xy 44.252364 -371.58037) (xy 44.236995 -371.632711) (xy 44.214332 -371.682331)
			(xy 44.184838 -371.72822) (xy 44.149112 -371.769445) (xy 44.107884 -371.805165) (xy 44.061991 -371.834654)
			(xy 44.012368 -371.857311) (xy 43.960025 -371.872674) (xy 43.906029 -371.880432) (xy 43.878754 -371.880892)
			(xy 43.015154 -371.880892) (xy 42.987889 -371.880343) (xy 42.933915 -371.872576) (xy 42.881595 -371.857208)
			(xy 42.831994 -371.834551) (xy 42.786123 -371.805066) (xy 42.744914 -371.769354) (xy 42.709206 -371.728141)
			(xy 42.679727 -371.682265) (xy 42.657076 -371.632662) (xy 42.641714 -371.58034) (xy 42.633954 -371.526365)
			(xy 2.509012 -371.526365) (xy 2.509012 -376.489976) (xy 31.068784 -376.489976) (xy 31.072756 -376.311733)
			(xy 31.084664 -376.133844) (xy 31.104485 -375.956662) (xy 31.132179 -375.780538) (xy 31.167691 -375.605823)
			(xy 31.210951 -375.432864) (xy 31.261873 -375.262003) (xy 31.320356 -375.093581) (xy 31.386283 -374.927931)
			(xy 31.459524 -374.765382) (xy 31.539934 -374.606257) (xy 31.627352 -374.450872) (xy 31.721605 -374.299536)
			(xy 31.822506 -374.152548) (xy 31.929855 -374.010201) (xy 32.043438 -373.872778) (xy 32.163031 -373.740551)
			(xy 32.288395 -373.613782) (xy 32.419282 -373.492724) (xy 32.555431 -373.377617) (xy 32.696573 -373.268689)
			(xy 32.842428 -373.166157) (xy 32.992705 -373.070223) (xy 33.147106 -372.98108) (xy 33.305325 -372.898903)
			(xy 33.467048 -372.823855) (xy 33.631953 -372.756087) (xy 33.799714 -372.695731) (xy 33.969997 -372.642909)
			(xy 34.142464 -372.597725) (xy 34.316772 -372.560268) (xy 34.492576 -372.530614) (xy 34.669526 -372.508821)
			(xy 34.847272 -372.494931) (xy 35.025459 -372.488974) (xy 35.203736 -372.49096) (xy 35.381747 -372.500886)
			(xy 35.559139 -372.518732) (xy 35.735559 -372.544462) (xy 35.910659 -372.578026) (xy 36.08409 -372.619356)
			(xy 36.255507 -372.668372) (xy 36.42457 -372.724974) (xy 36.590945 -372.789052) (xy 36.754299 -372.860478)
			(xy 36.91431 -372.93911) (xy 37.070659 -373.024791) (xy 37.223036 -373.117353) (xy 37.371139 -373.21661)
			(xy 37.514673 -373.322367) (xy 37.653353 -373.434412) (xy 37.786904 -373.552524) (xy 37.915061 -373.676468)
			(xy 38.03757 -373.805998) (xy 38.154187 -373.940857) (xy 38.193125 -373.990165) (xy 47.739354 -373.990165)
			(xy 47.739354 -373.935635) (xy 47.747114 -373.88166) (xy 47.762476 -373.829338) (xy 47.785127 -373.779735)
			(xy 47.814606 -373.733859) (xy 47.850314 -373.692646) (xy 47.891523 -373.656934) (xy 47.937394 -373.627449)
			(xy 47.986995 -373.604792) (xy 48.039315 -373.589424) (xy 48.093289 -373.581657) (xy 48.120554 -373.581168)
			(xy 48.984154 -373.581168) (xy 49.011429 -373.581568) (xy 49.065425 -373.589326) (xy 49.117768 -373.604689)
			(xy 49.167391 -373.627346) (xy 49.213284 -373.656835) (xy 49.254512 -373.692555) (xy 49.290238 -373.73378)
			(xy 49.319732 -373.779669) (xy 49.342395 -373.829289) (xy 49.357764 -373.88163) (xy 49.365528 -373.935625)
			(xy 49.365528 -373.990165) (xy 54.546554 -373.990165) (xy 54.546554 -373.935635) (xy 54.554314 -373.88166)
			(xy 54.569676 -373.829338) (xy 54.592327 -373.779735) (xy 54.621806 -373.733859) (xy 54.657514 -373.692646)
			(xy 54.698723 -373.656934) (xy 54.744594 -373.627449) (xy 54.794195 -373.604792) (xy 54.846515 -373.589424)
			(xy 54.900489 -373.581657) (xy 54.927754 -373.581168) (xy 55.791354 -373.581168) (xy 55.818629 -373.581568)
			(xy 55.872625 -373.589326) (xy 55.924968 -373.604689) (xy 55.974591 -373.627346) (xy 56.020484 -373.656835)
			(xy 56.061712 -373.692555) (xy 56.097438 -373.73378) (xy 56.126932 -373.779669) (xy 56.149595 -373.829289)
			(xy 56.164964 -373.88163) (xy 56.172728 -373.935625) (xy 56.172728 -373.990165) (xy 61.353754 -373.990165)
			(xy 61.353754 -373.935635) (xy 61.361514 -373.88166) (xy 61.376876 -373.829338) (xy 61.399527 -373.779735)
			(xy 61.429006 -373.733859) (xy 61.464714 -373.692646) (xy 61.505923 -373.656934) (xy 61.551794 -373.627449)
			(xy 61.601395 -373.604792) (xy 61.653715 -373.589424) (xy 61.707689 -373.581657) (xy 61.734954 -373.581168)
			(xy 62.598554 -373.581168) (xy 62.625829 -373.581568) (xy 62.679825 -373.589326) (xy 62.732168 -373.604689)
			(xy 62.781791 -373.627346) (xy 62.827684 -373.656835) (xy 62.868912 -373.692555) (xy 62.904638 -373.73378)
			(xy 62.934132 -373.779669) (xy 62.956795 -373.829289) (xy 62.972164 -373.88163) (xy 62.979928 -373.935625)
			(xy 62.979928 -373.990169) (xy 80.267031 -373.990169) (xy 80.267031 -373.935631) (xy 80.274793 -373.881648)
			(xy 80.290158 -373.82932) (xy 80.312814 -373.77971) (xy 80.3423 -373.73383) (xy 80.378014 -373.692613)
			(xy 80.419232 -373.656898) (xy 80.465112 -373.627413) (xy 80.514721 -373.604757) (xy 80.56705 -373.589393)
			(xy 80.621033 -373.581631) (xy 80.648302 -373.581168) (xy 81.511902 -373.581168) (xy 81.539173 -373.581595)
			(xy 81.593161 -373.589357) (xy 81.645494 -373.604724) (xy 81.695108 -373.627382) (xy 81.740993 -373.65687)
			(xy 81.782213 -373.692588) (xy 81.817931 -373.733809) (xy 81.847419 -373.779693) (xy 81.870077 -373.829307)
			(xy 81.885443 -373.881641) (xy 81.893206 -373.935629) (xy 81.893206 -373.990169) (xy 87.074231 -373.990169)
			(xy 87.074231 -373.935631) (xy 87.081993 -373.881648) (xy 87.097358 -373.82932) (xy 87.120014 -373.77971)
			(xy 87.1495 -373.73383) (xy 87.185214 -373.692613) (xy 87.226432 -373.656898) (xy 87.272312 -373.627413)
			(xy 87.321921 -373.604757) (xy 87.37425 -373.589393) (xy 87.428233 -373.581631) (xy 87.455502 -373.581168)
			(xy 88.319102 -373.581168) (xy 88.346373 -373.581595) (xy 88.400361 -373.589357) (xy 88.452694 -373.604724)
			(xy 88.502308 -373.627382) (xy 88.548193 -373.65687) (xy 88.589413 -373.692588) (xy 88.625131 -373.733809)
			(xy 88.654619 -373.779693) (xy 88.677277 -373.829307) (xy 88.692643 -373.881641) (xy 88.700406 -373.935629)
			(xy 88.700406 -373.990169) (xy 93.881431 -373.990169) (xy 93.881431 -373.935631) (xy 93.889193 -373.881648)
			(xy 93.904558 -373.82932) (xy 93.927214 -373.77971) (xy 93.9567 -373.73383) (xy 93.992414 -373.692613)
			(xy 94.033632 -373.656898) (xy 94.079512 -373.627413) (xy 94.129121 -373.604757) (xy 94.18145 -373.589393)
			(xy 94.235433 -373.581631) (xy 94.262702 -373.581168) (xy 95.126302 -373.581168) (xy 95.153573 -373.581595)
			(xy 95.207561 -373.589357) (xy 95.259894 -373.604724) (xy 95.309508 -373.627382) (xy 95.355393 -373.65687)
			(xy 95.396613 -373.692588) (xy 95.432331 -373.733809) (xy 95.461819 -373.779693) (xy 95.484477 -373.829307)
			(xy 95.499843 -373.881641) (xy 95.507606 -373.935629) (xy 95.507606 -373.990167) (xy 114.839254 -373.990167)
			(xy 114.839254 -373.935633) (xy 114.847015 -373.881654) (xy 114.862379 -373.829329) (xy 114.885033 -373.779723)
			(xy 114.914517 -373.733846) (xy 114.950229 -373.692631) (xy 114.991442 -373.656919) (xy 115.037319 -373.627435)
			(xy 115.086925 -373.604781) (xy 115.13925 -373.589416) (xy 115.193229 -373.581655) (xy 115.220496 -373.581168)
			(xy 116.084096 -373.581168) (xy 116.111369 -373.581571) (xy 116.165361 -373.589334) (xy 116.217698 -373.604701)
			(xy 116.267316 -373.62736) (xy 116.313203 -373.65685) (xy 116.354427 -373.69257) (xy 116.390148 -373.733793)
			(xy 116.419638 -373.779681) (xy 116.442298 -373.829298) (xy 116.457666 -373.881635) (xy 116.465428 -373.935627)
			(xy 116.465428 -373.990167) (xy 121.646454 -373.990167) (xy 121.646454 -373.935633) (xy 121.654215 -373.881654)
			(xy 121.669579 -373.829329) (xy 121.692233 -373.779723) (xy 121.721717 -373.733846) (xy 121.757429 -373.692631)
			(xy 121.798642 -373.656919) (xy 121.844519 -373.627435) (xy 121.894125 -373.604781) (xy 121.94645 -373.589416)
			(xy 122.000429 -373.581655) (xy 122.027696 -373.581168) (xy 122.891296 -373.581168) (xy 122.918569 -373.581571)
			(xy 122.972561 -373.589334) (xy 123.024898 -373.604701) (xy 123.074516 -373.62736) (xy 123.120403 -373.65685)
			(xy 123.161627 -373.69257) (xy 123.197348 -373.733793) (xy 123.226838 -373.779681) (xy 123.249498 -373.829298)
			(xy 123.264866 -373.881635) (xy 123.272628 -373.935627) (xy 123.272628 -373.990167) (xy 128.453654 -373.990167)
			(xy 128.453654 -373.935633) (xy 128.461415 -373.881654) (xy 128.476779 -373.829329) (xy 128.499433 -373.779723)
			(xy 128.528917 -373.733846) (xy 128.564629 -373.692631) (xy 128.605842 -373.656919) (xy 128.651719 -373.627435)
			(xy 128.701325 -373.604781) (xy 128.75365 -373.589416) (xy 128.807629 -373.581655) (xy 128.834896 -373.581168)
			(xy 129.698496 -373.581168) (xy 129.725769 -373.581571) (xy 129.779761 -373.589334) (xy 129.832098 -373.604701)
			(xy 129.881716 -373.62736) (xy 129.927603 -373.65685) (xy 129.968827 -373.69257) (xy 130.004548 -373.733793)
			(xy 130.034038 -373.779681) (xy 130.056698 -373.829298) (xy 130.072066 -373.881635) (xy 130.079828 -373.935627)
			(xy 130.079828 -373.990171) (xy 147.366932 -373.990171) (xy 147.366932 -373.935629) (xy 147.374694 -373.881643)
			(xy 147.390061 -373.829311) (xy 147.412721 -373.779698) (xy 147.44221 -373.733816) (xy 147.477929 -373.692598)
			(xy 147.519151 -373.656884) (xy 147.565037 -373.627399) (xy 147.614652 -373.604746) (xy 147.666986 -373.589385)
			(xy 147.720973 -373.581628) (xy 147.748244 -373.581168) (xy 148.611844 -373.581168) (xy 148.639113 -373.581598)
			(xy 148.693097 -373.589365) (xy 148.745425 -373.604735) (xy 148.795033 -373.627396) (xy 148.840912 -373.656885)
			(xy 148.882128 -373.692603) (xy 148.917841 -373.733823) (xy 148.947325 -373.779705) (xy 148.96998 -373.829316)
			(xy 148.985344 -373.881647) (xy 148.993106 -373.93563) (xy 148.993106 -373.99017) (xy 148.993106 -373.990171)
			(xy 154.174132 -373.990171) (xy 154.174132 -373.935629) (xy 154.181894 -373.881643) (xy 154.197261 -373.829311)
			(xy 154.219921 -373.779698) (xy 154.24941 -373.733816) (xy 154.285129 -373.692598) (xy 154.326351 -373.656884)
			(xy 154.372237 -373.627399) (xy 154.421852 -373.604746) (xy 154.474186 -373.589385) (xy 154.528173 -373.581628)
			(xy 154.555444 -373.581168) (xy 155.419044 -373.581168) (xy 155.446313 -373.581598) (xy 155.500297 -373.589365)
			(xy 155.552625 -373.604735) (xy 155.602233 -373.627396) (xy 155.648112 -373.656885) (xy 155.689328 -373.692603)
			(xy 155.725041 -373.733823) (xy 155.754525 -373.779705) (xy 155.77718 -373.829316) (xy 155.792544 -373.881647)
			(xy 155.800306 -373.93563) (xy 155.800306 -373.99017) (xy 155.800306 -373.990171) (xy 160.981332 -373.990171)
			(xy 160.981332 -373.935629) (xy 160.989094 -373.881643) (xy 161.004461 -373.829311) (xy 161.027121 -373.779698)
			(xy 161.05661 -373.733816) (xy 161.092329 -373.692598) (xy 161.133551 -373.656884) (xy 161.179437 -373.627399)
			(xy 161.229052 -373.604746) (xy 161.281386 -373.589385) (xy 161.335373 -373.581628) (xy 161.362644 -373.581168)
			(xy 162.226244 -373.581168) (xy 162.253513 -373.581598) (xy 162.307497 -373.589365) (xy 162.359825 -373.604735)
			(xy 162.409433 -373.627396) (xy 162.455312 -373.656885) (xy 162.496528 -373.692603) (xy 162.532241 -373.733823)
			(xy 162.561725 -373.779705) (xy 162.58438 -373.829316) (xy 162.599744 -373.881647) (xy 162.607506 -373.93563)
			(xy 162.607506 -373.99017) (xy 162.599744 -374.044153) (xy 162.58438 -374.096484) (xy 162.561725 -374.146095)
			(xy 162.532241 -374.191977) (xy 162.496528 -374.233197) (xy 162.455312 -374.268915) (xy 162.409433 -374.298404)
			(xy 162.359825 -374.321065) (xy 162.307497 -374.336435) (xy 162.253513 -374.344202) (xy 162.226244 -374.344692)
			(xy 161.362644 -374.344692) (xy 161.335373 -374.344172) (xy 161.281386 -374.336415) (xy 161.229052 -374.321054)
			(xy 161.179437 -374.298401) (xy 161.133551 -374.268916) (xy 161.092329 -374.233202) (xy 161.05661 -374.191984)
			(xy 161.027121 -374.146102) (xy 161.004461 -374.096489) (xy 160.989094 -374.044157) (xy 160.981332 -373.990171)
			(xy 155.800306 -373.990171) (xy 155.792544 -374.044153) (xy 155.77718 -374.096484) (xy 155.754525 -374.146095)
			(xy 155.725041 -374.191977) (xy 155.689328 -374.233197) (xy 155.648112 -374.268915) (xy 155.602233 -374.298404)
			(xy 155.552625 -374.321065) (xy 155.500297 -374.336435) (xy 155.446313 -374.344202) (xy 155.419044 -374.344692)
			(xy 154.555444 -374.344692) (xy 154.528173 -374.344172) (xy 154.474186 -374.336415) (xy 154.421852 -374.321054)
			(xy 154.372237 -374.298401) (xy 154.326351 -374.268916) (xy 154.285129 -374.233202) (xy 154.24941 -374.191984)
			(xy 154.219921 -374.146102) (xy 154.197261 -374.096489) (xy 154.181894 -374.044157) (xy 154.174132 -373.990171)
			(xy 148.993106 -373.990171) (xy 148.985344 -374.044153) (xy 148.96998 -374.096484) (xy 148.947325 -374.146095)
			(xy 148.917841 -374.191977) (xy 148.882128 -374.233197) (xy 148.840912 -374.268915) (xy 148.795033 -374.298404)
			(xy 148.745425 -374.321065) (xy 148.693097 -374.336435) (xy 148.639113 -374.344202) (xy 148.611844 -374.344692)
			(xy 147.748244 -374.344692) (xy 147.720973 -374.344172) (xy 147.666986 -374.336415) (xy 147.614652 -374.321054)
			(xy 147.565037 -374.298401) (xy 147.519151 -374.268916) (xy 147.477929 -374.233202) (xy 147.44221 -374.191984)
			(xy 147.412721 -374.146102) (xy 147.390061 -374.096489) (xy 147.374694 -374.044157) (xy 147.366932 -373.990171)
			(xy 130.079828 -373.990171) (xy 130.079828 -373.990173) (xy 130.072066 -374.044165) (xy 130.056698 -374.096502)
			(xy 130.034038 -374.146119) (xy 130.004548 -374.192007) (xy 129.968827 -374.23323) (xy 129.927603 -374.26895)
			(xy 129.881716 -374.29844) (xy 129.832098 -374.321099) (xy 129.779761 -374.336466) (xy 129.725769 -374.344229)
			(xy 129.698496 -374.344692) (xy 128.834896 -374.344692) (xy 128.807629 -374.344145) (xy 128.75365 -374.336384)
			(xy 128.701325 -374.321019) (xy 128.651719 -374.298365) (xy 128.605842 -374.268881) (xy 128.564629 -374.233169)
			(xy 128.528917 -374.191954) (xy 128.499433 -374.146077) (xy 128.476779 -374.096471) (xy 128.461415 -374.044146)
			(xy 128.453654 -373.990167) (xy 123.272628 -373.990167) (xy 123.272628 -373.990173) (xy 123.264866 -374.044165)
			(xy 123.249498 -374.096502) (xy 123.226838 -374.146119) (xy 123.197348 -374.192007) (xy 123.161627 -374.23323)
			(xy 123.120403 -374.26895) (xy 123.074516 -374.29844) (xy 123.024898 -374.321099) (xy 122.972561 -374.336466)
			(xy 122.918569 -374.344229) (xy 122.891296 -374.344692) (xy 122.027696 -374.344692) (xy 122.000429 -374.344145)
			(xy 121.94645 -374.336384) (xy 121.894125 -374.321019) (xy 121.844519 -374.298365) (xy 121.798642 -374.268881)
			(xy 121.757429 -374.233169) (xy 121.721717 -374.191954) (xy 121.692233 -374.146077) (xy 121.669579 -374.096471)
			(xy 121.654215 -374.044146) (xy 121.646454 -373.990167) (xy 116.465428 -373.990167) (xy 116.465428 -373.990173)
			(xy 116.457666 -374.044165) (xy 116.442298 -374.096502) (xy 116.419638 -374.146119) (xy 116.390148 -374.192007)
			(xy 116.354427 -374.23323) (xy 116.313203 -374.26895) (xy 116.267316 -374.29844) (xy 116.217698 -374.321099)
			(xy 116.165361 -374.336466) (xy 116.111369 -374.344229) (xy 116.084096 -374.344692) (xy 115.220496 -374.344692)
			(xy 115.193229 -374.344145) (xy 115.13925 -374.336384) (xy 115.086925 -374.321019) (xy 115.037319 -374.298365)
			(xy 114.991442 -374.268881) (xy 114.950229 -374.233169) (xy 114.914517 -374.191954) (xy 114.885033 -374.146077)
			(xy 114.862379 -374.096471) (xy 114.847015 -374.044146) (xy 114.839254 -373.990167) (xy 95.507606 -373.990167)
			(xy 95.507606 -373.990171) (xy 95.499843 -374.044159) (xy 95.484477 -374.096493) (xy 95.461819 -374.146107)
			(xy 95.432331 -374.191991) (xy 95.396613 -374.233212) (xy 95.355393 -374.26893) (xy 95.309508 -374.298418)
			(xy 95.259894 -374.321076) (xy 95.207561 -374.336443) (xy 95.153573 -374.344205) (xy 95.126302 -374.344692)
			(xy 94.262702 -374.344692) (xy 94.235433 -374.344169) (xy 94.18145 -374.336407) (xy 94.129121 -374.321043)
			(xy 94.079512 -374.298387) (xy 94.033632 -374.268902) (xy 93.992414 -374.233187) (xy 93.9567 -374.19197)
			(xy 93.927214 -374.14609) (xy 93.904558 -374.09648) (xy 93.889193 -374.044152) (xy 93.881431 -373.990169)
			(xy 88.700406 -373.990169) (xy 88.700406 -373.990171) (xy 88.692643 -374.044159) (xy 88.677277 -374.096493)
			(xy 88.654619 -374.146107) (xy 88.625131 -374.191991) (xy 88.589413 -374.233212) (xy 88.548193 -374.26893)
			(xy 88.502308 -374.298418) (xy 88.452694 -374.321076) (xy 88.400361 -374.336443) (xy 88.346373 -374.344205)
			(xy 88.319102 -374.344692) (xy 87.455502 -374.344692) (xy 87.428233 -374.344169) (xy 87.37425 -374.336407)
			(xy 87.321921 -374.321043) (xy 87.272312 -374.298387) (xy 87.226432 -374.268902) (xy 87.185214 -374.233187)
			(xy 87.1495 -374.19197) (xy 87.120014 -374.14609) (xy 87.097358 -374.09648) (xy 87.081993 -374.044152)
			(xy 87.074231 -373.990169) (xy 81.893206 -373.990169) (xy 81.893206 -373.990171) (xy 81.885443 -374.044159)
			(xy 81.870077 -374.096493) (xy 81.847419 -374.146107) (xy 81.817931 -374.191991) (xy 81.782213 -374.233212)
			(xy 81.740993 -374.26893) (xy 81.695108 -374.298418) (xy 81.645494 -374.321076) (xy 81.593161 -374.336443)
			(xy 81.539173 -374.344205) (xy 81.511902 -374.344692) (xy 80.648302 -374.344692) (xy 80.621033 -374.344169)
			(xy 80.56705 -374.336407) (xy 80.514721 -374.321043) (xy 80.465112 -374.298387) (xy 80.419232 -374.268902)
			(xy 80.378014 -374.233187) (xy 80.3423 -374.19197) (xy 80.312814 -374.14609) (xy 80.290158 -374.09648)
			(xy 80.274793 -374.044152) (xy 80.267031 -373.990169) (xy 62.979928 -373.990169) (xy 62.979928 -373.990175)
			(xy 62.972164 -374.04417) (xy 62.956795 -374.096511) (xy 62.934132 -374.146131) (xy 62.904638 -374.19202)
			(xy 62.868912 -374.233245) (xy 62.827684 -374.268965) (xy 62.781791 -374.298454) (xy 62.732168 -374.321111)
			(xy 62.679825 -374.336474) (xy 62.625829 -374.344232) (xy 62.598554 -374.344692) (xy 61.734954 -374.344692)
			(xy 61.707689 -374.344143) (xy 61.653715 -374.336376) (xy 61.601395 -374.321008) (xy 61.551794 -374.298351)
			(xy 61.505923 -374.268866) (xy 61.464714 -374.233154) (xy 61.429006 -374.191941) (xy 61.399527 -374.146065)
			(xy 61.376876 -374.096462) (xy 61.361514 -374.04414) (xy 61.353754 -373.990165) (xy 56.172728 -373.990165)
			(xy 56.172728 -373.990175) (xy 56.164964 -374.04417) (xy 56.149595 -374.096511) (xy 56.126932 -374.146131)
			(xy 56.097438 -374.19202) (xy 56.061712 -374.233245) (xy 56.020484 -374.268965) (xy 55.974591 -374.298454)
			(xy 55.924968 -374.321111) (xy 55.872625 -374.336474) (xy 55.818629 -374.344232) (xy 55.791354 -374.344692)
			(xy 54.927754 -374.344692) (xy 54.900489 -374.344143) (xy 54.846515 -374.336376) (xy 54.794195 -374.321008)
			(xy 54.744594 -374.298351) (xy 54.698723 -374.268866) (xy 54.657514 -374.233154) (xy 54.621806 -374.191941)
			(xy 54.592327 -374.146065) (xy 54.569676 -374.096462) (xy 54.554314 -374.04414) (xy 54.546554 -373.990165)
			(xy 49.365528 -373.990165) (xy 49.365528 -373.990175) (xy 49.357764 -374.04417) (xy 49.342395 -374.096511)
			(xy 49.319732 -374.146131) (xy 49.290238 -374.19202) (xy 49.254512 -374.233245) (xy 49.213284 -374.268965)
			(xy 49.167391 -374.298454) (xy 49.117768 -374.321111) (xy 49.065425 -374.336474) (xy 49.011429 -374.344232)
			(xy 48.984154 -374.344692) (xy 48.120554 -374.344692) (xy 48.093289 -374.344143) (xy 48.039315 -374.336376)
			(xy 47.986995 -374.321008) (xy 47.937394 -374.298351) (xy 47.891523 -374.268866) (xy 47.850314 -374.233154)
			(xy 47.814606 -374.191941) (xy 47.785127 -374.146065) (xy 47.762476 -374.096462) (xy 47.747114 -374.04414)
			(xy 47.739354 -373.990165) (xy 38.193125 -373.990165) (xy 38.26468 -374.080777) (xy 38.368831 -374.22548)
			(xy 38.466433 -374.374679) (xy 38.557291 -374.528078) (xy 38.641225 -374.685372) (xy 38.71807 -374.846248)
			(xy 38.787671 -375.010389) (xy 38.849892 -375.177466) (xy 38.904608 -375.34715) (xy 38.95171 -375.519103)
			(xy 38.991106 -375.692983) (xy 39.022717 -375.868446) (xy 39.046481 -376.045142) (xy 39.062349 -376.222722)
			(xy 39.070291 -376.400832) (xy 39.070788 -376.489976) (xy 39.070291 -376.57912) (xy 39.062349 -376.75723)
			(xy 39.05568 -376.83186) (xy 41.04894 -376.83186) (xy 41.04894 -375.96826) (xy 41.049426 -375.940991)
			(xy 41.057188 -375.887007) (xy 41.072553 -375.834677) (xy 41.09521 -375.785067) (xy 41.124696 -375.739186)
			(xy 41.160411 -375.697969) (xy 41.201628 -375.662254) (xy 41.247509 -375.632768) (xy 41.297119 -375.610111)
			(xy 41.349449 -375.594746) (xy 41.403433 -375.586984) (xy 41.457971 -375.586984) (xy 41.511955 -375.594746)
			(xy 41.564285 -375.610111) (xy 41.613895 -375.632768) (xy 41.659776 -375.662254) (xy 41.700993 -375.697969)
			(xy 41.736708 -375.739186) (xy 41.766194 -375.785067) (xy 41.788851 -375.834677) (xy 41.804216 -375.887007)
			(xy 41.811978 -375.940991) (xy 41.812464 -375.96826) (xy 41.812464 -376.83186) (xy 41.811978 -376.859129)
			(xy 41.804216 -376.913113) (xy 41.791381 -376.956828) (xy 70.895972 -376.956828) (xy 70.895972 -376.093228)
			(xy 70.896458 -376.065959) (xy 70.90422 -376.011975) (xy 70.919585 -375.959645) (xy 70.942242 -375.910035)
			(xy 70.971728 -375.864154) (xy 71.007443 -375.822937) (xy 71.04866 -375.787222) (xy 71.094541 -375.757736)
			(xy 71.144151 -375.735079) (xy 71.196481 -375.719714) (xy 71.250465 -375.711952) (xy 71.305003 -375.711952)
			(xy 71.358987 -375.719714) (xy 71.411317 -375.735079) (xy 71.460927 -375.757736) (xy 71.506808 -375.787222)
			(xy 71.548025 -375.822937) (xy 71.58374 -375.864154) (xy 71.613226 -375.910035) (xy 71.635883 -375.959645)
			(xy 71.651248 -376.011975) (xy 71.65901 -376.065959) (xy 71.659496 -376.093228) (xy 71.659496 -376.83186)
			(xy 73.576688 -376.83186) (xy 73.576688 -375.96826) (xy 73.577174 -375.940991) (xy 73.584936 -375.887007)
			(xy 73.600301 -375.834677) (xy 73.622958 -375.785067) (xy 73.652444 -375.739186) (xy 73.688159 -375.697969)
			(xy 73.729376 -375.662254) (xy 73.775257 -375.632768) (xy 73.824867 -375.610111) (xy 73.877197 -375.594746)
			(xy 73.931181 -375.586984) (xy 73.985719 -375.586984) (xy 74.039703 -375.594746) (xy 74.092033 -375.610111)
			(xy 74.141643 -375.632768) (xy 74.187524 -375.662254) (xy 74.228741 -375.697969) (xy 74.264456 -375.739186)
			(xy 74.293942 -375.785067) (xy 74.316599 -375.834677) (xy 74.331964 -375.887007) (xy 74.339726 -375.940991)
			(xy 74.340212 -375.96826) (xy 74.340212 -376.83186) (xy 74.339726 -376.859129) (xy 74.331964 -376.913113)
			(xy 74.319129 -376.956828) (xy 103.42372 -376.956828) (xy 103.42372 -376.093228) (xy 103.424206 -376.065959)
			(xy 103.431968 -376.011975) (xy 103.447333 -375.959645) (xy 103.46999 -375.910035) (xy 103.499476 -375.864154)
			(xy 103.535191 -375.822937) (xy 103.576408 -375.787222) (xy 103.622289 -375.757736) (xy 103.671899 -375.735079)
			(xy 103.724229 -375.719714) (xy 103.778213 -375.711952) (xy 103.832751 -375.711952) (xy 103.886735 -375.719714)
			(xy 103.939065 -375.735079) (xy 103.988675 -375.757736) (xy 104.034556 -375.787222) (xy 104.075773 -375.822937)
			(xy 104.111488 -375.864154) (xy 104.140974 -375.910035) (xy 104.163631 -375.959645) (xy 104.178996 -376.011975)
			(xy 104.186758 -376.065959) (xy 104.187244 -376.093228) (xy 104.187244 -376.83186) (xy 108.149136 -376.83186)
			(xy 108.149136 -375.96826) (xy 108.149622 -375.941009) (xy 108.157378 -375.887061) (xy 108.172733 -375.834766)
			(xy 108.195375 -375.785189) (xy 108.224841 -375.739339) (xy 108.260532 -375.698148) (xy 108.301723 -375.662457)
			(xy 108.347573 -375.632991) (xy 108.39715 -375.610349) (xy 108.449445 -375.594994) (xy 108.503393 -375.587238)
			(xy 108.557895 -375.587238) (xy 108.611843 -375.594994) (xy 108.664138 -375.610349) (xy 108.713715 -375.632991)
			(xy 108.759565 -375.662457) (xy 108.800756 -375.698148) (xy 108.836447 -375.739339) (xy 108.865913 -375.785189)
			(xy 108.888555 -375.834766) (xy 108.90391 -375.887061) (xy 108.911666 -375.941009) (xy 108.912152 -375.96826)
			(xy 108.912152 -376.83186) (xy 108.911666 -376.859111) (xy 108.90391 -376.913059) (xy 108.891058 -376.956828)
			(xy 137.996168 -376.956828) (xy 137.996168 -376.093228) (xy 137.996654 -376.065977) (xy 138.00441 -376.012029)
			(xy 138.019765 -375.959734) (xy 138.042407 -375.910157) (xy 138.071873 -375.864307) (xy 138.107564 -375.823116)
			(xy 138.148755 -375.787425) (xy 138.194605 -375.757959) (xy 138.244182 -375.735317) (xy 138.296477 -375.719962)
			(xy 138.350425 -375.712206) (xy 138.404927 -375.712206) (xy 138.458875 -375.719962) (xy 138.51117 -375.735317)
			(xy 138.560747 -375.757959) (xy 138.606597 -375.787425) (xy 138.647788 -375.823116) (xy 138.683479 -375.864307)
			(xy 138.712945 -375.910157) (xy 138.735587 -375.959734) (xy 138.750942 -376.012029) (xy 138.758698 -376.065977)
			(xy 138.759184 -376.093228) (xy 138.759184 -376.83186) (xy 140.676884 -376.83186) (xy 140.676884 -375.96826)
			(xy 140.67737 -375.941009) (xy 140.685126 -375.887061) (xy 140.700481 -375.834766) (xy 140.723123 -375.785189)
			(xy 140.752589 -375.739339) (xy 140.78828 -375.698148) (xy 140.829471 -375.662457) (xy 140.875321 -375.632991)
			(xy 140.924898 -375.610349) (xy 140.977193 -375.594994) (xy 141.031141 -375.587238) (xy 141.085643 -375.587238)
			(xy 141.139591 -375.594994) (xy 141.191886 -375.610349) (xy 141.241463 -375.632991) (xy 141.287313 -375.662457)
			(xy 141.328504 -375.698148) (xy 141.364195 -375.739339) (xy 141.393661 -375.785189) (xy 141.416303 -375.834766)
			(xy 141.431658 -375.887061) (xy 141.439414 -375.941009) (xy 141.4399 -375.96826) (xy 141.4399 -376.83186)
			(xy 141.439414 -376.859111) (xy 141.431658 -376.913059) (xy 141.418806 -376.956828) (xy 170.523916 -376.956828)
			(xy 170.523916 -376.093228) (xy 170.524402 -376.065977) (xy 170.532158 -376.012029) (xy 170.547513 -375.959734)
			(xy 170.570155 -375.910157) (xy 170.599621 -375.864307) (xy 170.635312 -375.823116) (xy 170.676503 -375.787425)
			(xy 170.722353 -375.757959) (xy 170.77193 -375.735317) (xy 170.824225 -375.719962) (xy 170.878173 -375.712206)
			(xy 170.932675 -375.712206) (xy 170.986623 -375.719962) (xy 171.038918 -375.735317) (xy 171.088495 -375.757959)
			(xy 171.134345 -375.787425) (xy 171.175536 -375.823116) (xy 171.211227 -375.864307) (xy 171.240693 -375.910157)
			(xy 171.263335 -375.959734) (xy 171.27869 -376.012029) (xy 171.286446 -376.065977) (xy 171.286932 -376.093228)
			(xy 171.286932 -376.489976) (xy 173.498776 -376.489976) (xy 173.502748 -376.311733) (xy 173.514656 -376.133844)
			(xy 173.534477 -375.956662) (xy 173.562171 -375.780538) (xy 173.597683 -375.605823) (xy 173.640943 -375.432864)
			(xy 173.691865 -375.262003) (xy 173.750348 -375.093581) (xy 173.816275 -374.927931) (xy 173.889516 -374.765382)
			(xy 173.969926 -374.606257) (xy 174.057344 -374.450872) (xy 174.151597 -374.299536) (xy 174.252498 -374.152548)
			(xy 174.359847 -374.010201) (xy 174.47343 -373.872778) (xy 174.593023 -373.740551) (xy 174.718387 -373.613782)
			(xy 174.849274 -373.492724) (xy 174.985423 -373.377617) (xy 175.126565 -373.268689) (xy 175.27242 -373.166157)
			(xy 175.422697 -373.070223) (xy 175.577098 -372.98108) (xy 175.735317 -372.898903) (xy 175.89704 -372.823855)
			(xy 176.061945 -372.756087) (xy 176.229706 -372.695731) (xy 176.399989 -372.642909) (xy 176.572456 -372.597725)
			(xy 176.746764 -372.560268) (xy 176.922568 -372.530614) (xy 177.099518 -372.508821) (xy 177.277264 -372.494931)
			(xy 177.455451 -372.488974) (xy 177.633728 -372.49096) (xy 177.811739 -372.500886) (xy 177.989131 -372.518732)
			(xy 178.165551 -372.544462) (xy 178.340651 -372.578026) (xy 178.514082 -372.619356) (xy 178.685499 -372.668372)
			(xy 178.854562 -372.724974) (xy 179.020937 -372.789052) (xy 179.184291 -372.860478) (xy 179.344302 -372.93911)
			(xy 179.500651 -373.024791) (xy 179.653028 -373.117353) (xy 179.801131 -373.21661) (xy 179.944665 -373.322367)
			(xy 180.083345 -373.434412) (xy 180.216896 -373.552524) (xy 180.345053 -373.676468) (xy 180.467562 -373.805998)
			(xy 180.584179 -373.940857) (xy 180.596796 -373.956834) (xy 282.853384 -373.956834) (xy 282.853384 -373.093234)
			(xy 282.85387 -373.065983) (xy 282.861626 -373.012035) (xy 282.876981 -372.95974) (xy 282.899623 -372.910163)
			(xy 282.929089 -372.864313) (xy 282.96478 -372.823122) (xy 283.005971 -372.787431) (xy 283.051821 -372.757965)
			(xy 283.101398 -372.735323) (xy 283.153693 -372.719968) (xy 283.207641 -372.712212) (xy 283.262143 -372.712212)
			(xy 283.316091 -372.719968) (xy 283.368386 -372.735323) (xy 283.417963 -372.757965) (xy 283.463813 -372.787431)
			(xy 283.505004 -372.823122) (xy 283.540695 -372.864313) (xy 283.570161 -372.910163) (xy 283.592803 -372.95974)
			(xy 283.608158 -373.012035) (xy 283.615914 -373.065983) (xy 283.6164 -373.093234) (xy 283.6164 -373.956834)
			(xy 283.615914 -373.984085) (xy 283.608158 -374.038033) (xy 283.592803 -374.090328) (xy 283.570161 -374.139905)
			(xy 283.540695 -374.185755) (xy 283.505004 -374.226946) (xy 283.463813 -374.262637) (xy 283.417963 -374.292103)
			(xy 283.368386 -374.314745) (xy 283.316091 -374.3301) (xy 283.262143 -374.337856) (xy 283.207641 -374.337856)
			(xy 283.153693 -374.3301) (xy 283.101398 -374.314745) (xy 283.051821 -374.292103) (xy 283.005971 -374.262637)
			(xy 282.96478 -374.226946) (xy 282.929089 -374.185755) (xy 282.899623 -374.139905) (xy 282.876981 -374.090328)
			(xy 282.861626 -374.038033) (xy 282.85387 -373.984085) (xy 282.853384 -373.956834) (xy 180.596796 -373.956834)
			(xy 180.694672 -374.080777) (xy 180.798823 -374.22548) (xy 180.896425 -374.374679) (xy 180.987283 -374.528078)
			(xy 181.071217 -374.685372) (xy 181.148062 -374.846248) (xy 181.217663 -375.010389) (xy 181.279884 -375.177466)
			(xy 181.3346 -375.34715) (xy 181.381702 -375.519103) (xy 181.421098 -375.692983) (xy 181.452709 -375.868446)
			(xy 181.476473 -376.045142) (xy 181.492341 -376.222722) (xy 181.500283 -376.400832) (xy 181.50078 -376.489976)
			(xy 181.500283 -376.57912) (xy 181.492341 -376.75723) (xy 181.476473 -376.93481) (xy 181.452709 -377.111506)
			(xy 181.421098 -377.286969) (xy 181.381702 -377.460849) (xy 181.3346 -377.632802) (xy 181.319901 -377.678385)
			(xy 193.900548 -377.678385) (xy 193.900548 -377.593663) (xy 193.908601 -377.509326) (xy 193.924635 -377.426136)
			(xy 193.948503 -377.344846) (xy 193.979991 -377.266194) (xy 194.018813 -377.190891) (xy 194.064616 -377.119619)
			(xy 194.116987 -377.053023) (xy 194.175452 -376.991708) (xy 194.23948 -376.936227) (xy 194.308492 -376.887084)
			(xy 194.381862 -376.844724) (xy 194.458927 -376.809529) (xy 194.538989 -376.78182) (xy 194.621322 -376.761846)
			(xy 194.705181 -376.749789) (xy 194.789806 -376.745758) (xy 194.874431 -376.749789) (xy 194.95829 -376.761846)
			(xy 195.040623 -376.78182) (xy 195.120685 -376.809529) (xy 195.19775 -376.844724) (xy 195.27112 -376.887084)
			(xy 195.340132 -376.936227) (xy 195.40416 -376.991708) (xy 195.462625 -377.053023) (xy 195.514996 -377.119619)
			(xy 195.560799 -377.190891) (xy 195.599621 -377.266194) (xy 195.631109 -377.344846) (xy 195.654977 -377.426136)
			(xy 195.671011 -377.509326) (xy 195.679064 -377.593663) (xy 195.679568 -377.636024) (xy 195.679064 -377.678385)
			(xy 195.671011 -377.762722) (xy 195.654977 -377.845912) (xy 195.631109 -377.927202) (xy 195.599621 -378.005854)
			(xy 195.560799 -378.081157) (xy 195.514996 -378.152429) (xy 195.47531 -378.202895) (xy 199.443082 -378.202895)
			(xy 199.443082 -378.118173) (xy 199.451135 -378.033836) (xy 199.467169 -377.950646) (xy 199.491037 -377.869356)
			(xy 199.522525 -377.790704) (xy 199.561347 -377.715401) (xy 199.60715 -377.644129) (xy 199.659521 -377.577533)
			(xy 199.717986 -377.516218) (xy 199.782014 -377.460737) (xy 199.851026 -377.411594) (xy 199.924396 -377.369234)
			(xy 200.001461 -377.334039) (xy 200.081523 -377.30633) (xy 200.163856 -377.286356) (xy 200.247715 -377.274299)
			(xy 200.33234 -377.270268) (xy 200.416965 -377.274299) (xy 200.500824 -377.286356) (xy 200.583157 -377.30633)
			(xy 200.663219 -377.334039) (xy 200.740284 -377.369234) (xy 200.813654 -377.411594) (xy 200.859958 -377.444567)
			(xy 300.335454 -377.444567) (xy 300.335454 -377.390033) (xy 300.343215 -377.336054) (xy 300.358579 -377.283729)
			(xy 300.381233 -377.234123) (xy 300.410717 -377.188246) (xy 300.446429 -377.147031) (xy 300.487642 -377.111319)
			(xy 300.533519 -377.081835) (xy 300.583125 -377.059181) (xy 300.63545 -377.043816) (xy 300.689429 -377.036055)
			(xy 300.716696 -377.035568) (xy 301.580296 -377.035568) (xy 301.607569 -377.035971) (xy 301.661561 -377.043734)
			(xy 301.713898 -377.059101) (xy 301.763516 -377.08176) (xy 301.809403 -377.11125) (xy 301.850627 -377.14697)
			(xy 301.886348 -377.188193) (xy 301.915838 -377.234081) (xy 301.938498 -377.283698) (xy 301.953866 -377.336035)
			(xy 301.961628 -377.390027) (xy 301.961628 -377.444567) (xy 307.142654 -377.444567) (xy 307.142654 -377.390033)
			(xy 307.150415 -377.336054) (xy 307.165779 -377.283729) (xy 307.188433 -377.234123) (xy 307.217917 -377.188246)
			(xy 307.253629 -377.147031) (xy 307.294842 -377.111319) (xy 307.340719 -377.081835) (xy 307.390325 -377.059181)
			(xy 307.44265 -377.043816) (xy 307.496629 -377.036055) (xy 307.523896 -377.035568) (xy 308.387496 -377.035568)
			(xy 308.414769 -377.035971) (xy 308.468761 -377.043734) (xy 308.521098 -377.059101) (xy 308.570716 -377.08176)
			(xy 308.616603 -377.11125) (xy 308.657827 -377.14697) (xy 308.693548 -377.188193) (xy 308.723038 -377.234081)
			(xy 308.745698 -377.283698) (xy 308.761066 -377.336035) (xy 308.768828 -377.390027) (xy 308.768828 -377.444567)
			(xy 313.949854 -377.444567) (xy 313.949854 -377.390033) (xy 313.957615 -377.336054) (xy 313.972979 -377.283729)
			(xy 313.995633 -377.234123) (xy 314.025117 -377.188246) (xy 314.060829 -377.147031) (xy 314.102042 -377.111319)
			(xy 314.147919 -377.081835) (xy 314.197525 -377.059181) (xy 314.24985 -377.043816) (xy 314.303829 -377.036055)
			(xy 314.331096 -377.035568) (xy 315.194696 -377.035568) (xy 315.221969 -377.035971) (xy 315.275961 -377.043734)
			(xy 315.328298 -377.059101) (xy 315.377916 -377.08176) (xy 315.423803 -377.11125) (xy 315.465027 -377.14697)
			(xy 315.500748 -377.188193) (xy 315.530238 -377.234081) (xy 315.552898 -377.283698) (xy 315.568266 -377.336035)
			(xy 315.576028 -377.390027) (xy 315.576028 -377.444567) (xy 320.757054 -377.444567) (xy 320.757054 -377.390033)
			(xy 320.764815 -377.336054) (xy 320.780179 -377.283729) (xy 320.802833 -377.234123) (xy 320.832317 -377.188246)
			(xy 320.868029 -377.147031) (xy 320.909242 -377.111319) (xy 320.955119 -377.081835) (xy 321.004725 -377.059181)
			(xy 321.05705 -377.043816) (xy 321.111029 -377.036055) (xy 321.138296 -377.035568) (xy 322.001896 -377.035568)
			(xy 322.029169 -377.035971) (xy 322.083161 -377.043734) (xy 322.135498 -377.059101) (xy 322.185116 -377.08176)
			(xy 322.231003 -377.11125) (xy 322.272227 -377.14697) (xy 322.307948 -377.188193) (xy 322.337438 -377.234081)
			(xy 322.360098 -377.283698) (xy 322.375466 -377.336035) (xy 322.383228 -377.390027) (xy 322.383228 -377.444567)
			(xy 324.160654 -377.444567) (xy 324.160654 -377.390033) (xy 324.168415 -377.336054) (xy 324.183779 -377.283729)
			(xy 324.206433 -377.234123) (xy 324.235917 -377.188246) (xy 324.271629 -377.147031) (xy 324.312842 -377.111319)
			(xy 324.358719 -377.081835) (xy 324.408325 -377.059181) (xy 324.46065 -377.043816) (xy 324.514629 -377.036055)
			(xy 324.541896 -377.035568) (xy 325.405496 -377.035568) (xy 325.432769 -377.035971) (xy 325.486761 -377.043734)
			(xy 325.539098 -377.059101) (xy 325.588716 -377.08176) (xy 325.634603 -377.11125) (xy 325.675827 -377.14697)
			(xy 325.711548 -377.188193) (xy 325.741038 -377.234081) (xy 325.763698 -377.283698) (xy 325.779066 -377.336035)
			(xy 325.786828 -377.390027) (xy 325.786828 -377.444571) (xy 332.863132 -377.444571) (xy 332.863132 -377.390029)
			(xy 332.870894 -377.336043) (xy 332.886261 -377.283711) (xy 332.908921 -377.234098) (xy 332.93841 -377.188216)
			(xy 332.974129 -377.146998) (xy 333.015351 -377.111284) (xy 333.061237 -377.081799) (xy 333.110852 -377.059146)
			(xy 333.163186 -377.043785) (xy 333.217173 -377.036028) (xy 333.244444 -377.035568) (xy 334.108044 -377.035568)
			(xy 334.135313 -377.035998) (xy 334.189297 -377.043765) (xy 334.241625 -377.059135) (xy 334.291233 -377.081796)
			(xy 334.337112 -377.111285) (xy 334.378328 -377.147003) (xy 334.414041 -377.188223) (xy 334.443525 -377.234105)
			(xy 334.46618 -377.283716) (xy 334.481544 -377.336047) (xy 334.489306 -377.39003) (xy 334.489306 -377.44457)
			(xy 334.489306 -377.444571) (xy 339.670332 -377.444571) (xy 339.670332 -377.390029) (xy 339.678094 -377.336043)
			(xy 339.693461 -377.283711) (xy 339.716121 -377.234098) (xy 339.74561 -377.188216) (xy 339.781329 -377.146998)
			(xy 339.822551 -377.111284) (xy 339.868437 -377.081799) (xy 339.918052 -377.059146) (xy 339.970386 -377.043785)
			(xy 340.024373 -377.036028) (xy 340.051644 -377.035568) (xy 340.915244 -377.035568) (xy 340.942513 -377.035998)
			(xy 340.996497 -377.043765) (xy 341.048825 -377.059135) (xy 341.098433 -377.081796) (xy 341.144312 -377.111285)
			(xy 341.185528 -377.147003) (xy 341.221241 -377.188223) (xy 341.250725 -377.234105) (xy 341.27338 -377.283716)
			(xy 341.288744 -377.336047) (xy 341.296506 -377.39003) (xy 341.296506 -377.44457) (xy 341.296506 -377.444571)
			(xy 346.477532 -377.444571) (xy 346.477532 -377.390029) (xy 346.485294 -377.336043) (xy 346.500661 -377.283711)
			(xy 346.523321 -377.234098) (xy 346.55281 -377.188216) (xy 346.588529 -377.146998) (xy 346.629751 -377.111284)
			(xy 346.675637 -377.081799) (xy 346.725252 -377.059146) (xy 346.777586 -377.043785) (xy 346.831573 -377.036028)
			(xy 346.858844 -377.035568) (xy 347.722444 -377.035568) (xy 347.749713 -377.035998) (xy 347.803697 -377.043765)
			(xy 347.856025 -377.059135) (xy 347.905633 -377.081796) (xy 347.951512 -377.111285) (xy 347.992728 -377.147003)
			(xy 348.028441 -377.188223) (xy 348.057925 -377.234105) (xy 348.08058 -377.283716) (xy 348.095944 -377.336047)
			(xy 348.103706 -377.39003) (xy 348.103706 -377.44457) (xy 348.103706 -377.444571) (xy 353.284732 -377.444571)
			(xy 353.284732 -377.390029) (xy 353.292494 -377.336043) (xy 353.307861 -377.283711) (xy 353.330521 -377.234098)
			(xy 353.36001 -377.188216) (xy 353.395729 -377.146998) (xy 353.436951 -377.111284) (xy 353.482837 -377.081799)
			(xy 353.532452 -377.059146) (xy 353.584786 -377.043785) (xy 353.638773 -377.036028) (xy 353.666044 -377.035568)
			(xy 354.529644 -377.035568) (xy 354.556913 -377.035998) (xy 354.610897 -377.043765) (xy 354.663225 -377.059135)
			(xy 354.712833 -377.081796) (xy 354.758712 -377.111285) (xy 354.799928 -377.147003) (xy 354.835641 -377.188223)
			(xy 354.865125 -377.234105) (xy 354.88778 -377.283716) (xy 354.903144 -377.336047) (xy 354.910906 -377.39003)
			(xy 354.910906 -377.44457) (xy 354.910906 -377.444571) (xy 356.688332 -377.444571) (xy 356.688332 -377.390029)
			(xy 356.696094 -377.336043) (xy 356.711461 -377.283711) (xy 356.734121 -377.234098) (xy 356.76361 -377.188216)
			(xy 356.799329 -377.146998) (xy 356.840551 -377.111284) (xy 356.886437 -377.081799) (xy 356.936052 -377.059146)
			(xy 356.988386 -377.043785) (xy 357.042373 -377.036028) (xy 357.069644 -377.035568) (xy 357.933244 -377.035568)
			(xy 357.960513 -377.035998) (xy 358.014497 -377.043765) (xy 358.066825 -377.059135) (xy 358.116433 -377.081796)
			(xy 358.162312 -377.111285) (xy 358.203528 -377.147003) (xy 358.239241 -377.188223) (xy 358.268725 -377.234105)
			(xy 358.29138 -377.283716) (xy 358.306744 -377.336047) (xy 358.314506 -377.39003) (xy 358.314506 -377.444567)
			(xy 367.435654 -377.444567) (xy 367.435654 -377.390033) (xy 367.443415 -377.336054) (xy 367.458779 -377.28373)
			(xy 367.481433 -377.234124) (xy 367.510916 -377.188247) (xy 367.546627 -377.147033) (xy 367.587841 -377.11132)
			(xy 367.633717 -377.081837) (xy 367.683322 -377.059182) (xy 367.735647 -377.043817) (xy 367.789625 -377.036055)
			(xy 367.816892 -377.035568) (xy 368.680492 -377.035568) (xy 368.707766 -377.035971) (xy 368.761757 -377.043733)
			(xy 368.814095 -377.0591) (xy 368.863713 -377.081759) (xy 368.909602 -377.111248) (xy 368.950826 -377.146968)
			(xy 368.986547 -377.188192) (xy 369.016038 -377.23408) (xy 369.038698 -377.283697) (xy 369.054065 -377.336035)
			(xy 369.061828 -377.390026) (xy 369.061828 -377.444567) (xy 374.242854 -377.444567) (xy 374.242854 -377.390033)
			(xy 374.250615 -377.336054) (xy 374.265979 -377.28373) (xy 374.288633 -377.234124) (xy 374.318116 -377.188247)
			(xy 374.353827 -377.147033) (xy 374.395041 -377.11132) (xy 374.440917 -377.081837) (xy 374.490522 -377.059182)
			(xy 374.542847 -377.043817) (xy 374.596825 -377.036055) (xy 374.624092 -377.035568) (xy 375.487692 -377.035568)
			(xy 375.514966 -377.035971) (xy 375.568957 -377.043733) (xy 375.621295 -377.0591) (xy 375.670913 -377.081759)
			(xy 375.716802 -377.111248) (xy 375.758026 -377.146968) (xy 375.793747 -377.188192) (xy 375.823238 -377.23408)
			(xy 375.845898 -377.283697) (xy 375.861265 -377.336035) (xy 375.869028 -377.390026) (xy 375.869028 -377.444567)
			(xy 381.050054 -377.444567) (xy 381.050054 -377.390033) (xy 381.057815 -377.336054) (xy 381.073179 -377.28373)
			(xy 381.095833 -377.234124) (xy 381.125316 -377.188247) (xy 381.161027 -377.147033) (xy 381.202241 -377.11132)
			(xy 381.248117 -377.081837) (xy 381.297722 -377.059182) (xy 381.350047 -377.043817) (xy 381.404025 -377.036055)
			(xy 381.431292 -377.035568) (xy 382.294892 -377.035568) (xy 382.322166 -377.035971) (xy 382.376157 -377.043733)
			(xy 382.428495 -377.0591) (xy 382.478113 -377.081759) (xy 382.524002 -377.111248) (xy 382.565226 -377.146968)
			(xy 382.600947 -377.188192) (xy 382.630438 -377.23408) (xy 382.653098 -377.283697) (xy 382.668465 -377.336035)
			(xy 382.676228 -377.390026) (xy 382.676228 -377.444567) (xy 387.857254 -377.444567) (xy 387.857254 -377.390033)
			(xy 387.865015 -377.336054) (xy 387.880379 -377.28373) (xy 387.903033 -377.234124) (xy 387.932516 -377.188247)
			(xy 387.968227 -377.147033) (xy 388.009441 -377.11132) (xy 388.055317 -377.081837) (xy 388.104922 -377.059182)
			(xy 388.157247 -377.043817) (xy 388.211225 -377.036055) (xy 388.238492 -377.035568) (xy 389.102092 -377.035568)
			(xy 389.129366 -377.035971) (xy 389.183357 -377.043733) (xy 389.235695 -377.0591) (xy 389.285313 -377.081759)
			(xy 389.331202 -377.111248) (xy 389.372426 -377.146968) (xy 389.408147 -377.188192) (xy 389.437638 -377.23408)
			(xy 389.460298 -377.283697) (xy 389.475665 -377.336035) (xy 389.483428 -377.390026) (xy 389.483428 -377.444567)
			(xy 391.260854 -377.444567) (xy 391.260854 -377.390033) (xy 391.268615 -377.336054) (xy 391.283979 -377.28373)
			(xy 391.306633 -377.234124) (xy 391.336116 -377.188247) (xy 391.371827 -377.147033) (xy 391.413041 -377.11132)
			(xy 391.458917 -377.081837) (xy 391.508522 -377.059182) (xy 391.560847 -377.043817) (xy 391.614825 -377.036055)
			(xy 391.642092 -377.035568) (xy 392.505692 -377.035568) (xy 392.532966 -377.035971) (xy 392.586957 -377.043733)
			(xy 392.639295 -377.0591) (xy 392.688913 -377.081759) (xy 392.734802 -377.111248) (xy 392.776026 -377.146968)
			(xy 392.811747 -377.188192) (xy 392.841238 -377.23408) (xy 392.863898 -377.283697) (xy 392.879265 -377.336035)
			(xy 392.887028 -377.390026) (xy 392.887028 -377.444571) (xy 399.963332 -377.444571) (xy 399.963332 -377.390029)
			(xy 399.971094 -377.336043) (xy 399.986461 -377.283711) (xy 400.00912 -377.234099) (xy 400.038609 -377.188217)
			(xy 400.074328 -377.147) (xy 400.11555 -377.111285) (xy 400.161435 -377.081801) (xy 400.211049 -377.059147)
			(xy 400.263382 -377.043786) (xy 400.317369 -377.036029) (xy 400.34464 -377.035568) (xy 401.20824 -377.035568)
			(xy 401.23551 -377.035997) (xy 401.289493 -377.043764) (xy 401.341822 -377.059134) (xy 401.391431 -377.081794)
			(xy 401.437311 -377.111284) (xy 401.478527 -377.147002) (xy 401.51424 -377.188222) (xy 401.543725 -377.234104)
			(xy 401.56638 -377.283716) (xy 401.581744 -377.336046) (xy 401.589506 -377.39003) (xy 401.589506 -377.44457)
			(xy 401.589506 -377.444571) (xy 406.770532 -377.444571) (xy 406.770532 -377.390029) (xy 406.778294 -377.336043)
			(xy 406.793661 -377.283711) (xy 406.81632 -377.234099) (xy 406.845809 -377.188217) (xy 406.881528 -377.147)
			(xy 406.92275 -377.111285) (xy 406.968635 -377.081801) (xy 407.018249 -377.059147) (xy 407.070582 -377.043786)
			(xy 407.124569 -377.036029) (xy 407.15184 -377.035568) (xy 408.01544 -377.035568) (xy 408.04271 -377.035997)
			(xy 408.096693 -377.043764) (xy 408.149022 -377.059134) (xy 408.198631 -377.081794) (xy 408.244511 -377.111284)
			(xy 408.285727 -377.147002) (xy 408.32144 -377.188222) (xy 408.350925 -377.234104) (xy 408.37358 -377.283716)
			(xy 408.388944 -377.336046) (xy 408.396706 -377.39003) (xy 408.396706 -377.44457) (xy 408.396706 -377.444571)
			(xy 413.577732 -377.444571) (xy 413.577732 -377.390029) (xy 413.585494 -377.336043) (xy 413.600861 -377.283711)
			(xy 413.62352 -377.234099) (xy 413.653009 -377.188217) (xy 413.688728 -377.147) (xy 413.72995 -377.111285)
			(xy 413.775835 -377.081801) (xy 413.825449 -377.059147) (xy 413.877782 -377.043786) (xy 413.931769 -377.036029)
			(xy 413.95904 -377.035568) (xy 414.82264 -377.035568) (xy 414.84991 -377.035997) (xy 414.903893 -377.043764)
			(xy 414.956222 -377.059134) (xy 415.005831 -377.081794) (xy 415.051711 -377.111284) (xy 415.092927 -377.147002)
			(xy 415.12864 -377.188222) (xy 415.158125 -377.234104) (xy 415.18078 -377.283716) (xy 415.196144 -377.336046)
			(xy 415.203906 -377.39003) (xy 415.203906 -377.44457) (xy 415.203906 -377.444571) (xy 420.384932 -377.444571)
			(xy 420.384932 -377.390029) (xy 420.392694 -377.336043) (xy 420.408061 -377.283711) (xy 420.43072 -377.234099)
			(xy 420.460209 -377.188217) (xy 420.495928 -377.147) (xy 420.53715 -377.111285) (xy 420.583035 -377.081801)
			(xy 420.632649 -377.059147) (xy 420.684982 -377.043786) (xy 420.738969 -377.036029) (xy 420.76624 -377.035568)
			(xy 421.62984 -377.035568) (xy 421.65711 -377.035997) (xy 421.711093 -377.043764) (xy 421.763422 -377.059134)
			(xy 421.813031 -377.081794) (xy 421.858911 -377.111284) (xy 421.900127 -377.147002) (xy 421.93584 -377.188222)
			(xy 421.965325 -377.234104) (xy 421.98798 -377.283716) (xy 422.003344 -377.336046) (xy 422.011106 -377.39003)
			(xy 422.011106 -377.44457) (xy 422.011106 -377.444571) (xy 423.788532 -377.444571) (xy 423.788532 -377.390029)
			(xy 423.796294 -377.336043) (xy 423.811661 -377.283711) (xy 423.83432 -377.234099) (xy 423.863809 -377.188217)
			(xy 423.899528 -377.147) (xy 423.94075 -377.111285) (xy 423.986635 -377.081801) (xy 424.036249 -377.059147)
			(xy 424.088582 -377.043786) (xy 424.142569 -377.036029) (xy 424.16984 -377.035568) (xy 425.03344 -377.035568)
			(xy 425.06071 -377.035997) (xy 425.114693 -377.043764) (xy 425.167022 -377.059134) (xy 425.216631 -377.081794)
			(xy 425.262511 -377.111284) (xy 425.303727 -377.147002) (xy 425.33944 -377.188222) (xy 425.368925 -377.234104)
			(xy 425.39158 -377.283716) (xy 425.406944 -377.336046) (xy 425.414706 -377.39003) (xy 425.414706 -377.44457)
			(xy 425.406944 -377.498554) (xy 425.39158 -377.550884) (xy 425.368925 -377.600496) (xy 425.33944 -377.646378)
			(xy 425.303727 -377.687598) (xy 425.262511 -377.723316) (xy 425.216631 -377.752806) (xy 425.167022 -377.775466)
			(xy 425.114693 -377.790836) (xy 425.06071 -377.798603) (xy 425.03344 -377.799092) (xy 424.16984 -377.799092)
			(xy 424.142569 -377.798571) (xy 424.088582 -377.790814) (xy 424.036249 -377.775453) (xy 423.986635 -377.752799)
			(xy 423.94075 -377.723315) (xy 423.899528 -377.6876) (xy 423.863809 -377.646383) (xy 423.83432 -377.600501)
			(xy 423.811661 -377.550889) (xy 423.796294 -377.498557) (xy 423.788532 -377.444571) (xy 422.011106 -377.444571)
			(xy 422.003344 -377.498554) (xy 421.98798 -377.550884) (xy 421.965325 -377.600496) (xy 421.93584 -377.646378)
			(xy 421.900127 -377.687598) (xy 421.858911 -377.723316) (xy 421.813031 -377.752806) (xy 421.763422 -377.775466)
			(xy 421.711093 -377.790836) (xy 421.65711 -377.798603) (xy 421.62984 -377.799092) (xy 420.76624 -377.799092)
			(xy 420.738969 -377.798571) (xy 420.684982 -377.790814) (xy 420.632649 -377.775453) (xy 420.583035 -377.752799)
			(xy 420.53715 -377.723315) (xy 420.495928 -377.6876) (xy 420.460209 -377.646383) (xy 420.43072 -377.600501)
			(xy 420.408061 -377.550889) (xy 420.392694 -377.498557) (xy 420.384932 -377.444571) (xy 415.203906 -377.444571)
			(xy 415.196144 -377.498554) (xy 415.18078 -377.550884) (xy 415.158125 -377.600496) (xy 415.12864 -377.646378)
			(xy 415.092927 -377.687598) (xy 415.051711 -377.723316) (xy 415.005831 -377.752806) (xy 414.956222 -377.775466)
			(xy 414.903893 -377.790836) (xy 414.84991 -377.798603) (xy 414.82264 -377.799092) (xy 413.95904 -377.799092)
			(xy 413.931769 -377.798571) (xy 413.877782 -377.790814) (xy 413.825449 -377.775453) (xy 413.775835 -377.752799)
			(xy 413.72995 -377.723315) (xy 413.688728 -377.6876) (xy 413.653009 -377.646383) (xy 413.62352 -377.600501)
			(xy 413.600861 -377.550889) (xy 413.585494 -377.498557) (xy 413.577732 -377.444571) (xy 408.396706 -377.444571)
			(xy 408.388944 -377.498554) (xy 408.37358 -377.550884) (xy 408.350925 -377.600496) (xy 408.32144 -377.646378)
			(xy 408.285727 -377.687598) (xy 408.244511 -377.723316) (xy 408.198631 -377.752806) (xy 408.149022 -377.775466)
			(xy 408.096693 -377.790836) (xy 408.04271 -377.798603) (xy 408.01544 -377.799092) (xy 407.15184 -377.799092)
			(xy 407.124569 -377.798571) (xy 407.070582 -377.790814) (xy 407.018249 -377.775453) (xy 406.968635 -377.752799)
			(xy 406.92275 -377.723315) (xy 406.881528 -377.6876) (xy 406.845809 -377.646383) (xy 406.81632 -377.600501)
			(xy 406.793661 -377.550889) (xy 406.778294 -377.498557) (xy 406.770532 -377.444571) (xy 401.589506 -377.444571)
			(xy 401.581744 -377.498554) (xy 401.56638 -377.550884) (xy 401.543725 -377.600496) (xy 401.51424 -377.646378)
			(xy 401.478527 -377.687598) (xy 401.437311 -377.723316) (xy 401.391431 -377.752806) (xy 401.341822 -377.775466)
			(xy 401.289493 -377.790836) (xy 401.23551 -377.798603) (xy 401.20824 -377.799092) (xy 400.34464 -377.799092)
			(xy 400.317369 -377.798571) (xy 400.263382 -377.790814) (xy 400.211049 -377.775453) (xy 400.161435 -377.752799)
			(xy 400.11555 -377.723315) (xy 400.074328 -377.6876) (xy 400.038609 -377.646383) (xy 400.00912 -377.600501)
			(xy 399.986461 -377.550889) (xy 399.971094 -377.498557) (xy 399.963332 -377.444571) (xy 392.887028 -377.444571)
			(xy 392.887028 -377.444574) (xy 392.879265 -377.498565) (xy 392.863898 -377.550903) (xy 392.841238 -377.60052)
			(xy 392.811747 -377.646408) (xy 392.776026 -377.687632) (xy 392.734802 -377.723352) (xy 392.688913 -377.752841)
			(xy 392.639295 -377.7755) (xy 392.586957 -377.790867) (xy 392.532966 -377.798629) (xy 392.505692 -377.799092)
			(xy 391.642092 -377.799092) (xy 391.614825 -377.798545) (xy 391.560847 -377.790783) (xy 391.508522 -377.775418)
			(xy 391.458917 -377.752763) (xy 391.413041 -377.72328) (xy 391.371827 -377.687567) (xy 391.336116 -377.646353)
			(xy 391.306633 -377.600476) (xy 391.283979 -377.55087) (xy 391.268615 -377.498546) (xy 391.260854 -377.444567)
			(xy 389.483428 -377.444567) (xy 389.483428 -377.444574) (xy 389.475665 -377.498565) (xy 389.460298 -377.550903)
			(xy 389.437638 -377.60052) (xy 389.408147 -377.646408) (xy 389.372426 -377.687632) (xy 389.331202 -377.723352)
			(xy 389.285313 -377.752841) (xy 389.235695 -377.7755) (xy 389.183357 -377.790867) (xy 389.129366 -377.798629)
			(xy 389.102092 -377.799092) (xy 388.238492 -377.799092) (xy 388.211225 -377.798545) (xy 388.157247 -377.790783)
			(xy 388.104922 -377.775418) (xy 388.055317 -377.752763) (xy 388.009441 -377.72328) (xy 387.968227 -377.687567)
			(xy 387.932516 -377.646353) (xy 387.903033 -377.600476) (xy 387.880379 -377.55087) (xy 387.865015 -377.498546)
			(xy 387.857254 -377.444567) (xy 382.676228 -377.444567) (xy 382.676228 -377.444574) (xy 382.668465 -377.498565)
			(xy 382.653098 -377.550903) (xy 382.630438 -377.60052) (xy 382.600947 -377.646408) (xy 382.565226 -377.687632)
			(xy 382.524002 -377.723352) (xy 382.478113 -377.752841) (xy 382.428495 -377.7755) (xy 382.376157 -377.790867)
			(xy 382.322166 -377.798629) (xy 382.294892 -377.799092) (xy 381.431292 -377.799092) (xy 381.404025 -377.798545)
			(xy 381.350047 -377.790783) (xy 381.297722 -377.775418) (xy 381.248117 -377.752763) (xy 381.202241 -377.72328)
			(xy 381.161027 -377.687567) (xy 381.125316 -377.646353) (xy 381.095833 -377.600476) (xy 381.073179 -377.55087)
			(xy 381.057815 -377.498546) (xy 381.050054 -377.444567) (xy 375.869028 -377.444567) (xy 375.869028 -377.444574)
			(xy 375.861265 -377.498565) (xy 375.845898 -377.550903) (xy 375.823238 -377.60052) (xy 375.793747 -377.646408)
			(xy 375.758026 -377.687632) (xy 375.716802 -377.723352) (xy 375.670913 -377.752841) (xy 375.621295 -377.7755)
			(xy 375.568957 -377.790867) (xy 375.514966 -377.798629) (xy 375.487692 -377.799092) (xy 374.624092 -377.799092)
			(xy 374.596825 -377.798545) (xy 374.542847 -377.790783) (xy 374.490522 -377.775418) (xy 374.440917 -377.752763)
			(xy 374.395041 -377.72328) (xy 374.353827 -377.687567) (xy 374.318116 -377.646353) (xy 374.288633 -377.600476)
			(xy 374.265979 -377.55087) (xy 374.250615 -377.498546) (xy 374.242854 -377.444567) (xy 369.061828 -377.444567)
			(xy 369.061828 -377.444574) (xy 369.054065 -377.498565) (xy 369.038698 -377.550903) (xy 369.016038 -377.60052)
			(xy 368.986547 -377.646408) (xy 368.950826 -377.687632) (xy 368.909602 -377.723352) (xy 368.863713 -377.752841)
			(xy 368.814095 -377.7755) (xy 368.761757 -377.790867) (xy 368.707766 -377.798629) (xy 368.680492 -377.799092)
			(xy 367.816892 -377.799092) (xy 367.789625 -377.798545) (xy 367.735647 -377.790783) (xy 367.683322 -377.775418)
			(xy 367.633717 -377.752763) (xy 367.587841 -377.72328) (xy 367.546627 -377.687567) (xy 367.510916 -377.646353)
			(xy 367.481433 -377.600476) (xy 367.458779 -377.55087) (xy 367.443415 -377.498546) (xy 367.435654 -377.444567)
			(xy 358.314506 -377.444567) (xy 358.314506 -377.44457) (xy 358.306744 -377.498553) (xy 358.29138 -377.550884)
			(xy 358.268725 -377.600495) (xy 358.239241 -377.646377) (xy 358.203528 -377.687597) (xy 358.162312 -377.723315)
			(xy 358.116433 -377.752804) (xy 358.066825 -377.775465) (xy 358.014497 -377.790835) (xy 357.960513 -377.798602)
			(xy 357.933244 -377.799092) (xy 357.069644 -377.799092) (xy 357.042373 -377.798572) (xy 356.988386 -377.790815)
			(xy 356.936052 -377.775454) (xy 356.886437 -377.752801) (xy 356.840551 -377.723316) (xy 356.799329 -377.687602)
			(xy 356.76361 -377.646384) (xy 356.734121 -377.600502) (xy 356.711461 -377.550889) (xy 356.696094 -377.498557)
			(xy 356.688332 -377.444571) (xy 354.910906 -377.444571) (xy 354.903144 -377.498553) (xy 354.88778 -377.550884)
			(xy 354.865125 -377.600495) (xy 354.835641 -377.646377) (xy 354.799928 -377.687597) (xy 354.758712 -377.723315)
			(xy 354.712833 -377.752804) (xy 354.663225 -377.775465) (xy 354.610897 -377.790835) (xy 354.556913 -377.798602)
			(xy 354.529644 -377.799092) (xy 353.666044 -377.799092) (xy 353.638773 -377.798572) (xy 353.584786 -377.790815)
			(xy 353.532452 -377.775454) (xy 353.482837 -377.752801) (xy 353.436951 -377.723316) (xy 353.395729 -377.687602)
			(xy 353.36001 -377.646384) (xy 353.330521 -377.600502) (xy 353.307861 -377.550889) (xy 353.292494 -377.498557)
			(xy 353.284732 -377.444571) (xy 348.103706 -377.444571) (xy 348.095944 -377.498553) (xy 348.08058 -377.550884)
			(xy 348.057925 -377.600495) (xy 348.028441 -377.646377) (xy 347.992728 -377.687597) (xy 347.951512 -377.723315)
			(xy 347.905633 -377.752804) (xy 347.856025 -377.775465) (xy 347.803697 -377.790835) (xy 347.749713 -377.798602)
			(xy 347.722444 -377.799092) (xy 346.858844 -377.799092) (xy 346.831573 -377.798572) (xy 346.777586 -377.790815)
			(xy 346.725252 -377.775454) (xy 346.675637 -377.752801) (xy 346.629751 -377.723316) (xy 346.588529 -377.687602)
			(xy 346.55281 -377.646384) (xy 346.523321 -377.600502) (xy 346.500661 -377.550889) (xy 346.485294 -377.498557)
			(xy 346.477532 -377.444571) (xy 341.296506 -377.444571) (xy 341.288744 -377.498553) (xy 341.27338 -377.550884)
			(xy 341.250725 -377.600495) (xy 341.221241 -377.646377) (xy 341.185528 -377.687597) (xy 341.144312 -377.723315)
			(xy 341.098433 -377.752804) (xy 341.048825 -377.775465) (xy 340.996497 -377.790835) (xy 340.942513 -377.798602)
			(xy 340.915244 -377.799092) (xy 340.051644 -377.799092) (xy 340.024373 -377.798572) (xy 339.970386 -377.790815)
			(xy 339.918052 -377.775454) (xy 339.868437 -377.752801) (xy 339.822551 -377.723316) (xy 339.781329 -377.687602)
			(xy 339.74561 -377.646384) (xy 339.716121 -377.600502) (xy 339.693461 -377.550889) (xy 339.678094 -377.498557)
			(xy 339.670332 -377.444571) (xy 334.489306 -377.444571) (xy 334.481544 -377.498553) (xy 334.46618 -377.550884)
			(xy 334.443525 -377.600495) (xy 334.414041 -377.646377) (xy 334.378328 -377.687597) (xy 334.337112 -377.723315)
			(xy 334.291233 -377.752804) (xy 334.241625 -377.775465) (xy 334.189297 -377.790835) (xy 334.135313 -377.798602)
			(xy 334.108044 -377.799092) (xy 333.244444 -377.799092) (xy 333.217173 -377.798572) (xy 333.163186 -377.790815)
			(xy 333.110852 -377.775454) (xy 333.061237 -377.752801) (xy 333.015351 -377.723316) (xy 332.974129 -377.687602)
			(xy 332.93841 -377.646384) (xy 332.908921 -377.600502) (xy 332.886261 -377.550889) (xy 332.870894 -377.498557)
			(xy 332.863132 -377.444571) (xy 325.786828 -377.444571) (xy 325.786828 -377.444573) (xy 325.779066 -377.498565)
			(xy 325.763698 -377.550902) (xy 325.741038 -377.600519) (xy 325.711548 -377.646407) (xy 325.675827 -377.68763)
			(xy 325.634603 -377.72335) (xy 325.588716 -377.75284) (xy 325.539098 -377.775499) (xy 325.486761 -377.790866)
			(xy 325.432769 -377.798629) (xy 325.405496 -377.799092) (xy 324.541896 -377.799092) (xy 324.514629 -377.798545)
			(xy 324.46065 -377.790784) (xy 324.408325 -377.775419) (xy 324.358719 -377.752765) (xy 324.312842 -377.723281)
			(xy 324.271629 -377.687569) (xy 324.235917 -377.646354) (xy 324.206433 -377.600477) (xy 324.183779 -377.550871)
			(xy 324.168415 -377.498546) (xy 324.160654 -377.444567) (xy 322.383228 -377.444567) (xy 322.383228 -377.444573)
			(xy 322.375466 -377.498565) (xy 322.360098 -377.550902) (xy 322.337438 -377.600519) (xy 322.307948 -377.646407)
			(xy 322.272227 -377.68763) (xy 322.231003 -377.72335) (xy 322.185116 -377.75284) (xy 322.135498 -377.775499)
			(xy 322.083161 -377.790866) (xy 322.029169 -377.798629) (xy 322.001896 -377.799092) (xy 321.138296 -377.799092)
			(xy 321.111029 -377.798545) (xy 321.05705 -377.790784) (xy 321.004725 -377.775419) (xy 320.955119 -377.752765)
			(xy 320.909242 -377.723281) (xy 320.868029 -377.687569) (xy 320.832317 -377.646354) (xy 320.802833 -377.600477)
			(xy 320.780179 -377.550871) (xy 320.764815 -377.498546) (xy 320.757054 -377.444567) (xy 315.576028 -377.444567)
			(xy 315.576028 -377.444573) (xy 315.568266 -377.498565) (xy 315.552898 -377.550902) (xy 315.530238 -377.600519)
			(xy 315.500748 -377.646407) (xy 315.465027 -377.68763) (xy 315.423803 -377.72335) (xy 315.377916 -377.75284)
			(xy 315.328298 -377.775499) (xy 315.275961 -377.790866) (xy 315.221969 -377.798629) (xy 315.194696 -377.799092)
			(xy 314.331096 -377.799092) (xy 314.303829 -377.798545) (xy 314.24985 -377.790784) (xy 314.197525 -377.775419)
			(xy 314.147919 -377.752765) (xy 314.102042 -377.723281) (xy 314.060829 -377.687569) (xy 314.025117 -377.646354)
			(xy 313.995633 -377.600477) (xy 313.972979 -377.550871) (xy 313.957615 -377.498546) (xy 313.949854 -377.444567)
			(xy 308.768828 -377.444567) (xy 308.768828 -377.444573) (xy 308.761066 -377.498565) (xy 308.745698 -377.550902)
			(xy 308.723038 -377.600519) (xy 308.693548 -377.646407) (xy 308.657827 -377.68763) (xy 308.616603 -377.72335)
			(xy 308.570716 -377.75284) (xy 308.521098 -377.775499) (xy 308.468761 -377.790866) (xy 308.414769 -377.798629)
			(xy 308.387496 -377.799092) (xy 307.523896 -377.799092) (xy 307.496629 -377.798545) (xy 307.44265 -377.790784)
			(xy 307.390325 -377.775419) (xy 307.340719 -377.752765) (xy 307.294842 -377.723281) (xy 307.253629 -377.687569)
			(xy 307.217917 -377.646354) (xy 307.188433 -377.600477) (xy 307.165779 -377.550871) (xy 307.150415 -377.498546)
			(xy 307.142654 -377.444567) (xy 301.961628 -377.444567) (xy 301.961628 -377.444573) (xy 301.953866 -377.498565)
			(xy 301.938498 -377.550902) (xy 301.915838 -377.600519) (xy 301.886348 -377.646407) (xy 301.850627 -377.68763)
			(xy 301.809403 -377.72335) (xy 301.763516 -377.75284) (xy 301.713898 -377.775499) (xy 301.661561 -377.790866)
			(xy 301.607569 -377.798629) (xy 301.580296 -377.799092) (xy 300.716696 -377.799092) (xy 300.689429 -377.798545)
			(xy 300.63545 -377.790784) (xy 300.583125 -377.775419) (xy 300.533519 -377.752765) (xy 300.487642 -377.723281)
			(xy 300.446429 -377.687569) (xy 300.410717 -377.646354) (xy 300.381233 -377.600477) (xy 300.358579 -377.550871)
			(xy 300.343215 -377.498546) (xy 300.335454 -377.444567) (xy 200.859958 -377.444567) (xy 200.882666 -377.460737)
			(xy 200.946694 -377.516218) (xy 201.005159 -377.577533) (xy 201.05753 -377.644129) (xy 201.103333 -377.715401)
			(xy 201.142155 -377.790704) (xy 201.173643 -377.869356) (xy 201.197511 -377.950646) (xy 201.213545 -378.033836)
			(xy 201.221598 -378.118173) (xy 201.222102 -378.160534) (xy 201.221598 -378.202895) (xy 201.213545 -378.287232)
			(xy 201.197511 -378.370422) (xy 201.173643 -378.451712) (xy 201.142155 -378.530364) (xy 201.103333 -378.605667)
			(xy 201.05753 -378.676939) (xy 201.005159 -378.743535) (xy 200.946694 -378.80485) (xy 200.882666 -378.860331)
			(xy 200.813654 -378.909474) (xy 200.740284 -378.951834) (xy 200.663219 -378.987029) (xy 200.583157 -379.014738)
			(xy 200.500824 -379.034712) (xy 200.416965 -379.046769) (xy 200.33234 -379.050801) (xy 200.247715 -379.046769)
			(xy 200.163856 -379.034712) (xy 200.081523 -379.014738) (xy 200.001461 -378.987029) (xy 199.924396 -378.951834)
			(xy 199.851026 -378.909474) (xy 199.782014 -378.860331) (xy 199.717986 -378.80485) (xy 199.659521 -378.743535)
			(xy 199.60715 -378.676939) (xy 199.561347 -378.605667) (xy 199.522525 -378.530364) (xy 199.491037 -378.451712)
			(xy 199.467169 -378.370422) (xy 199.451135 -378.287232) (xy 199.443082 -378.202895) (xy 195.47531 -378.202895)
			(xy 195.462625 -378.219025) (xy 195.40416 -378.28034) (xy 195.340132 -378.335821) (xy 195.27112 -378.384964)
			(xy 195.19775 -378.427324) (xy 195.120685 -378.462519) (xy 195.040623 -378.490228) (xy 194.95829 -378.510202)
			(xy 194.874431 -378.522259) (xy 194.789806 -378.526291) (xy 194.705181 -378.522259) (xy 194.621322 -378.510202)
			(xy 194.538989 -378.490228) (xy 194.458927 -378.462519) (xy 194.381862 -378.427324) (xy 194.308492 -378.384964)
			(xy 194.23948 -378.335821) (xy 194.175452 -378.28034) (xy 194.116987 -378.219025) (xy 194.064616 -378.152429)
			(xy 194.018813 -378.081157) (xy 193.979991 -378.005854) (xy 193.948503 -377.927202) (xy 193.924635 -377.845912)
			(xy 193.908601 -377.762722) (xy 193.900548 -377.678385) (xy 181.319901 -377.678385) (xy 181.279884 -377.802486)
			(xy 181.217663 -377.969563) (xy 181.148062 -378.133704) (xy 181.071217 -378.29458) (xy 180.987283 -378.451874)
			(xy 180.896425 -378.605273) (xy 180.798823 -378.754472) (xy 180.694672 -378.899175) (xy 180.584179 -379.039095)
			(xy 180.467562 -379.173954) (xy 180.345053 -379.303484) (xy 180.216896 -379.427428) (xy 180.083345 -379.54554)
			(xy 179.944665 -379.657585) (xy 179.801131 -379.763342) (xy 179.653028 -379.862599) (xy 179.577684 -379.908367)
			(xy 298.633654 -379.908367) (xy 298.633654 -379.853833) (xy 298.641415 -379.799854) (xy 298.656779 -379.747529)
			(xy 298.679433 -379.697923) (xy 298.708917 -379.652046) (xy 298.744629 -379.610831) (xy 298.785842 -379.575119)
			(xy 298.831719 -379.545635) (xy 298.881325 -379.522981) (xy 298.93365 -379.507616) (xy 298.987629 -379.499855)
			(xy 299.014896 -379.499368) (xy 299.878496 -379.499368) (xy 299.905769 -379.499771) (xy 299.959761 -379.507534)
			(xy 300.012098 -379.522901) (xy 300.061716 -379.54556) (xy 300.107603 -379.57505) (xy 300.148827 -379.61077)
			(xy 300.184548 -379.651993) (xy 300.214038 -379.697881) (xy 300.236698 -379.747498) (xy 300.252066 -379.799835)
			(xy 300.259828 -379.853827) (xy 300.259828 -379.908367) (xy 305.440854 -379.908367) (xy 305.440854 -379.853833)
			(xy 305.448615 -379.799854) (xy 305.463979 -379.747529) (xy 305.486633 -379.697923) (xy 305.516117 -379.652046)
			(xy 305.551829 -379.610831) (xy 305.593042 -379.575119) (xy 305.638919 -379.545635) (xy 305.688525 -379.522981)
			(xy 305.74085 -379.507616) (xy 305.794829 -379.499855) (xy 305.822096 -379.499368) (xy 306.685696 -379.499368)
			(xy 306.712969 -379.499771) (xy 306.766961 -379.507534) (xy 306.819298 -379.522901) (xy 306.868916 -379.54556)
			(xy 306.914803 -379.57505) (xy 306.956027 -379.61077) (xy 306.991748 -379.651993) (xy 307.021238 -379.697881)
			(xy 307.043898 -379.747498) (xy 307.059266 -379.799835) (xy 307.067028 -379.853827) (xy 307.067028 -379.908367)
			(xy 312.248054 -379.908367) (xy 312.248054 -379.853833) (xy 312.255815 -379.799854) (xy 312.271179 -379.747529)
			(xy 312.293833 -379.697923) (xy 312.323317 -379.652046) (xy 312.359029 -379.610831) (xy 312.400242 -379.575119)
			(xy 312.446119 -379.545635) (xy 312.495725 -379.522981) (xy 312.54805 -379.507616) (xy 312.602029 -379.499855)
			(xy 312.629296 -379.499368) (xy 313.492896 -379.499368) (xy 313.520169 -379.499771) (xy 313.574161 -379.507534)
			(xy 313.626498 -379.522901) (xy 313.676116 -379.54556) (xy 313.722003 -379.57505) (xy 313.763227 -379.61077)
			(xy 313.798948 -379.651993) (xy 313.828438 -379.697881) (xy 313.851098 -379.747498) (xy 313.866466 -379.799835)
			(xy 313.874228 -379.853827) (xy 313.874228 -379.908367) (xy 319.055254 -379.908367) (xy 319.055254 -379.853833)
			(xy 319.063015 -379.799854) (xy 319.078379 -379.747529) (xy 319.101033 -379.697923) (xy 319.130517 -379.652046)
			(xy 319.166229 -379.610831) (xy 319.207442 -379.575119) (xy 319.253319 -379.545635) (xy 319.302925 -379.522981)
			(xy 319.35525 -379.507616) (xy 319.409229 -379.499855) (xy 319.436496 -379.499368) (xy 320.300096 -379.499368)
			(xy 320.327369 -379.499771) (xy 320.381361 -379.507534) (xy 320.433698 -379.522901) (xy 320.483316 -379.54556)
			(xy 320.529203 -379.57505) (xy 320.570427 -379.61077) (xy 320.606148 -379.651993) (xy 320.635638 -379.697881)
			(xy 320.658298 -379.747498) (xy 320.673666 -379.799835) (xy 320.681428 -379.853827) (xy 320.681428 -379.908371)
			(xy 331.161332 -379.908371) (xy 331.161332 -379.853829) (xy 331.169094 -379.799843) (xy 331.184461 -379.747511)
			(xy 331.207121 -379.697898) (xy 331.23661 -379.652016) (xy 331.272329 -379.610798) (xy 331.313551 -379.575084)
			(xy 331.359437 -379.545599) (xy 331.409052 -379.522946) (xy 331.461386 -379.507585) (xy 331.515373 -379.499828)
			(xy 331.542644 -379.499368) (xy 332.406244 -379.499368) (xy 332.433513 -379.499798) (xy 332.487497 -379.507565)
			(xy 332.539825 -379.522935) (xy 332.589433 -379.545596) (xy 332.635312 -379.575085) (xy 332.676528 -379.610803)
			(xy 332.712241 -379.652023) (xy 332.741725 -379.697905) (xy 332.76438 -379.747516) (xy 332.779744 -379.799847)
			(xy 332.787506 -379.85383) (xy 332.787506 -379.90837) (xy 332.787506 -379.908371) (xy 337.968532 -379.908371)
			(xy 337.968532 -379.853829) (xy 337.976294 -379.799843) (xy 337.991661 -379.747511) (xy 338.014321 -379.697898)
			(xy 338.04381 -379.652016) (xy 338.079529 -379.610798) (xy 338.120751 -379.575084) (xy 338.166637 -379.545599)
			(xy 338.216252 -379.522946) (xy 338.268586 -379.507585) (xy 338.322573 -379.499828) (xy 338.349844 -379.499368)
			(xy 339.213444 -379.499368) (xy 339.240713 -379.499798) (xy 339.294697 -379.507565) (xy 339.347025 -379.522935)
			(xy 339.396633 -379.545596) (xy 339.442512 -379.575085) (xy 339.483728 -379.610803) (xy 339.519441 -379.652023)
			(xy 339.548925 -379.697905) (xy 339.57158 -379.747516) (xy 339.586944 -379.799847) (xy 339.594706 -379.85383)
			(xy 339.594706 -379.90837) (xy 339.594706 -379.908371) (xy 344.775732 -379.908371) (xy 344.775732 -379.853829)
			(xy 344.783494 -379.799843) (xy 344.798861 -379.747511) (xy 344.821521 -379.697898) (xy 344.85101 -379.652016)
			(xy 344.886729 -379.610798) (xy 344.927951 -379.575084) (xy 344.973837 -379.545599) (xy 345.023452 -379.522946)
			(xy 345.075786 -379.507585) (xy 345.129773 -379.499828) (xy 345.157044 -379.499368) (xy 346.020644 -379.499368)
			(xy 346.047913 -379.499798) (xy 346.101897 -379.507565) (xy 346.154225 -379.522935) (xy 346.203833 -379.545596)
			(xy 346.249712 -379.575085) (xy 346.290928 -379.610803) (xy 346.326641 -379.652023) (xy 346.356125 -379.697905)
			(xy 346.37878 -379.747516) (xy 346.394144 -379.799847) (xy 346.401906 -379.85383) (xy 346.401906 -379.90837)
			(xy 346.401906 -379.908371) (xy 351.582932 -379.908371) (xy 351.582932 -379.853829) (xy 351.590694 -379.799843)
			(xy 351.606061 -379.747511) (xy 351.628721 -379.697898) (xy 351.65821 -379.652016) (xy 351.693929 -379.610798)
			(xy 351.735151 -379.575084) (xy 351.781037 -379.545599) (xy 351.830652 -379.522946) (xy 351.882986 -379.507585)
			(xy 351.936973 -379.499828) (xy 351.964244 -379.499368) (xy 352.827844 -379.499368) (xy 352.855113 -379.499798)
			(xy 352.909097 -379.507565) (xy 352.961425 -379.522935) (xy 353.011033 -379.545596) (xy 353.056912 -379.575085)
			(xy 353.098128 -379.610803) (xy 353.133841 -379.652023) (xy 353.163325 -379.697905) (xy 353.18598 -379.747516)
			(xy 353.201344 -379.799847) (xy 353.209106 -379.85383) (xy 353.209106 -379.908367) (xy 365.733854 -379.908367)
			(xy 365.733854 -379.853833) (xy 365.741615 -379.799854) (xy 365.756979 -379.74753) (xy 365.779633 -379.697924)
			(xy 365.809116 -379.652047) (xy 365.844827 -379.610833) (xy 365.886041 -379.57512) (xy 365.931917 -379.545637)
			(xy 365.981522 -379.522982) (xy 366.033847 -379.507617) (xy 366.087825 -379.499855) (xy 366.115092 -379.499368)
			(xy 366.978692 -379.499368) (xy 367.005966 -379.499771) (xy 367.059957 -379.507533) (xy 367.112295 -379.5229)
			(xy 367.161913 -379.545559) (xy 367.207802 -379.575048) (xy 367.249026 -379.610768) (xy 367.284747 -379.651992)
			(xy 367.314238 -379.69788) (xy 367.336898 -379.747497) (xy 367.352265 -379.799835) (xy 367.360028 -379.853826)
			(xy 367.360028 -379.908367) (xy 372.541054 -379.908367) (xy 372.541054 -379.853833) (xy 372.548815 -379.799854)
			(xy 372.564179 -379.74753) (xy 372.586833 -379.697924) (xy 372.616316 -379.652047) (xy 372.652027 -379.610833)
			(xy 372.693241 -379.57512) (xy 372.739117 -379.545637) (xy 372.788722 -379.522982) (xy 372.841047 -379.507617)
			(xy 372.895025 -379.499855) (xy 372.922292 -379.499368) (xy 373.785892 -379.499368) (xy 373.813166 -379.499771)
			(xy 373.867157 -379.507533) (xy 373.919495 -379.5229) (xy 373.969113 -379.545559) (xy 374.015002 -379.575048)
			(xy 374.056226 -379.610768) (xy 374.091947 -379.651992) (xy 374.121438 -379.69788) (xy 374.144098 -379.747497)
			(xy 374.159465 -379.799835) (xy 374.167228 -379.853826) (xy 374.167228 -379.908367) (xy 379.348254 -379.908367)
			(xy 379.348254 -379.853833) (xy 379.356015 -379.799854) (xy 379.371379 -379.74753) (xy 379.394033 -379.697924)
			(xy 379.423516 -379.652047) (xy 379.459227 -379.610833) (xy 379.500441 -379.57512) (xy 379.546317 -379.545637)
			(xy 379.595922 -379.522982) (xy 379.648247 -379.507617) (xy 379.702225 -379.499855) (xy 379.729492 -379.499368)
			(xy 380.593092 -379.499368) (xy 380.620366 -379.499771) (xy 380.674357 -379.507533) (xy 380.726695 -379.5229)
			(xy 380.776313 -379.545559) (xy 380.822202 -379.575048) (xy 380.863426 -379.610768) (xy 380.899147 -379.651992)
			(xy 380.928638 -379.69788) (xy 380.951298 -379.747497) (xy 380.966665 -379.799835) (xy 380.974428 -379.853826)
			(xy 380.974428 -379.908367) (xy 386.155454 -379.908367) (xy 386.155454 -379.853833) (xy 386.163215 -379.799854)
			(xy 386.178579 -379.74753) (xy 386.201233 -379.697924) (xy 386.230716 -379.652047) (xy 386.266427 -379.610833)
			(xy 386.307641 -379.57512) (xy 386.353517 -379.545637) (xy 386.403122 -379.522982) (xy 386.455447 -379.507617)
			(xy 386.509425 -379.499855) (xy 386.536692 -379.499368) (xy 387.400292 -379.499368) (xy 387.427566 -379.499771)
			(xy 387.481557 -379.507533) (xy 387.533895 -379.5229) (xy 387.583513 -379.545559) (xy 387.629402 -379.575048)
			(xy 387.670626 -379.610768) (xy 387.706347 -379.651992) (xy 387.735838 -379.69788) (xy 387.758498 -379.747497)
			(xy 387.773865 -379.799835) (xy 387.781628 -379.853826) (xy 387.781628 -379.908371) (xy 398.261532 -379.908371)
			(xy 398.261532 -379.853829) (xy 398.269294 -379.799843) (xy 398.284661 -379.747511) (xy 398.30732 -379.697899)
			(xy 398.336809 -379.652017) (xy 398.372528 -379.6108) (xy 398.41375 -379.575085) (xy 398.459635 -379.545601)
			(xy 398.509249 -379.522947) (xy 398.561582 -379.507586) (xy 398.615569 -379.499829) (xy 398.64284 -379.499368)
			(xy 399.50644 -379.499368) (xy 399.53371 -379.499797) (xy 399.587693 -379.507564) (xy 399.640022 -379.522934)
			(xy 399.689631 -379.545594) (xy 399.735511 -379.575084) (xy 399.776727 -379.610802) (xy 399.81244 -379.652022)
			(xy 399.841925 -379.697904) (xy 399.86458 -379.747516) (xy 399.879944 -379.799846) (xy 399.887706 -379.85383)
			(xy 399.887706 -379.90837) (xy 399.887706 -379.908371) (xy 405.068732 -379.908371) (xy 405.068732 -379.853829)
			(xy 405.076494 -379.799843) (xy 405.091861 -379.747511) (xy 405.11452 -379.697899) (xy 405.144009 -379.652017)
			(xy 405.179728 -379.6108) (xy 405.22095 -379.575085) (xy 405.266835 -379.545601) (xy 405.316449 -379.522947)
			(xy 405.368782 -379.507586) (xy 405.422769 -379.499829) (xy 405.45004 -379.499368) (xy 406.31364 -379.499368)
			(xy 406.34091 -379.499797) (xy 406.394893 -379.507564) (xy 406.447222 -379.522934) (xy 406.496831 -379.545594)
			(xy 406.542711 -379.575084) (xy 406.583927 -379.610802) (xy 406.61964 -379.652022) (xy 406.649125 -379.697904)
			(xy 406.67178 -379.747516) (xy 406.687144 -379.799846) (xy 406.694906 -379.85383) (xy 406.694906 -379.90837)
			(xy 406.694906 -379.908371) (xy 411.875932 -379.908371) (xy 411.875932 -379.853829) (xy 411.883694 -379.799843)
			(xy 411.899061 -379.747511) (xy 411.92172 -379.697899) (xy 411.951209 -379.652017) (xy 411.986928 -379.6108)
			(xy 412.02815 -379.575085) (xy 412.074035 -379.545601) (xy 412.123649 -379.522947) (xy 412.175982 -379.507586)
			(xy 412.229969 -379.499829) (xy 412.25724 -379.499368) (xy 413.12084 -379.499368) (xy 413.14811 -379.499797)
			(xy 413.202093 -379.507564) (xy 413.254422 -379.522934) (xy 413.304031 -379.545594) (xy 413.349911 -379.575084)
			(xy 413.391127 -379.610802) (xy 413.42684 -379.652022) (xy 413.456325 -379.697904) (xy 413.47898 -379.747516)
			(xy 413.494344 -379.799846) (xy 413.502106 -379.85383) (xy 413.502106 -379.90837) (xy 413.502106 -379.908371)
			(xy 418.683132 -379.908371) (xy 418.683132 -379.853829) (xy 418.690894 -379.799843) (xy 418.706261 -379.747511)
			(xy 418.72892 -379.697899) (xy 418.758409 -379.652017) (xy 418.794128 -379.6108) (xy 418.83535 -379.575085)
			(xy 418.881235 -379.545601) (xy 418.930849 -379.522947) (xy 418.983182 -379.507586) (xy 419.037169 -379.499829)
			(xy 419.06444 -379.499368) (xy 419.92804 -379.499368) (xy 419.95531 -379.499797) (xy 420.009293 -379.507564)
			(xy 420.061622 -379.522934) (xy 420.111231 -379.545594) (xy 420.157111 -379.575084) (xy 420.198327 -379.610802)
			(xy 420.23404 -379.652022) (xy 420.263525 -379.697904) (xy 420.28618 -379.747516) (xy 420.301544 -379.799846)
			(xy 420.309306 -379.85383) (xy 420.309306 -379.90837) (xy 420.301544 -379.962354) (xy 420.28618 -380.014684)
			(xy 420.263525 -380.064296) (xy 420.23404 -380.110178) (xy 420.198327 -380.151398) (xy 420.157111 -380.187116)
			(xy 420.111231 -380.216606) (xy 420.061622 -380.239266) (xy 420.009293 -380.254636) (xy 419.95531 -380.262403)
			(xy 419.92804 -380.262892) (xy 419.06444 -380.262892) (xy 419.037169 -380.262371) (xy 418.983182 -380.254614)
			(xy 418.930849 -380.239253) (xy 418.881235 -380.216599) (xy 418.83535 -380.187115) (xy 418.794128 -380.1514)
			(xy 418.758409 -380.110183) (xy 418.72892 -380.064301) (xy 418.706261 -380.014689) (xy 418.690894 -379.962357)
			(xy 418.683132 -379.908371) (xy 413.502106 -379.908371) (xy 413.494344 -379.962354) (xy 413.47898 -380.014684)
			(xy 413.456325 -380.064296) (xy 413.42684 -380.110178) (xy 413.391127 -380.151398) (xy 413.349911 -380.187116)
			(xy 413.304031 -380.216606) (xy 413.254422 -380.239266) (xy 413.202093 -380.254636) (xy 413.14811 -380.262403)
			(xy 413.12084 -380.262892) (xy 412.25724 -380.262892) (xy 412.229969 -380.262371) (xy 412.175982 -380.254614)
			(xy 412.123649 -380.239253) (xy 412.074035 -380.216599) (xy 412.02815 -380.187115) (xy 411.986928 -380.1514)
			(xy 411.951209 -380.110183) (xy 411.92172 -380.064301) (xy 411.899061 -380.014689) (xy 411.883694 -379.962357)
			(xy 411.875932 -379.908371) (xy 406.694906 -379.908371) (xy 406.687144 -379.962354) (xy 406.67178 -380.014684)
			(xy 406.649125 -380.064296) (xy 406.61964 -380.110178) (xy 406.583927 -380.151398) (xy 406.542711 -380.187116)
			(xy 406.496831 -380.216606) (xy 406.447222 -380.239266) (xy 406.394893 -380.254636) (xy 406.34091 -380.262403)
			(xy 406.31364 -380.262892) (xy 405.45004 -380.262892) (xy 405.422769 -380.262371) (xy 405.368782 -380.254614)
			(xy 405.316449 -380.239253) (xy 405.266835 -380.216599) (xy 405.22095 -380.187115) (xy 405.179728 -380.1514)
			(xy 405.144009 -380.110183) (xy 405.11452 -380.064301) (xy 405.091861 -380.014689) (xy 405.076494 -379.962357)
			(xy 405.068732 -379.908371) (xy 399.887706 -379.908371) (xy 399.879944 -379.962354) (xy 399.86458 -380.014684)
			(xy 399.841925 -380.064296) (xy 399.81244 -380.110178) (xy 399.776727 -380.151398) (xy 399.735511 -380.187116)
			(xy 399.689631 -380.216606) (xy 399.640022 -380.239266) (xy 399.587693 -380.254636) (xy 399.53371 -380.262403)
			(xy 399.50644 -380.262892) (xy 398.64284 -380.262892) (xy 398.615569 -380.262371) (xy 398.561582 -380.254614)
			(xy 398.509249 -380.239253) (xy 398.459635 -380.216599) (xy 398.41375 -380.187115) (xy 398.372528 -380.1514)
			(xy 398.336809 -380.110183) (xy 398.30732 -380.064301) (xy 398.284661 -380.014689) (xy 398.269294 -379.962357)
			(xy 398.261532 -379.908371) (xy 387.781628 -379.908371) (xy 387.781628 -379.908374) (xy 387.773865 -379.962365)
			(xy 387.758498 -380.014703) (xy 387.735838 -380.06432) (xy 387.706347 -380.110208) (xy 387.670626 -380.151432)
			(xy 387.629402 -380.187152) (xy 387.583513 -380.216641) (xy 387.533895 -380.2393) (xy 387.481557 -380.254667)
			(xy 387.427566 -380.262429) (xy 387.400292 -380.262892) (xy 386.536692 -380.262892) (xy 386.509425 -380.262345)
			(xy 386.455447 -380.254583) (xy 386.403122 -380.239218) (xy 386.353517 -380.216563) (xy 386.307641 -380.18708)
			(xy 386.266427 -380.151367) (xy 386.230716 -380.110153) (xy 386.201233 -380.064276) (xy 386.178579 -380.01467)
			(xy 386.163215 -379.962346) (xy 386.155454 -379.908367) (xy 380.974428 -379.908367) (xy 380.974428 -379.908374)
			(xy 380.966665 -379.962365) (xy 380.951298 -380.014703) (xy 380.928638 -380.06432) (xy 380.899147 -380.110208)
			(xy 380.863426 -380.151432) (xy 380.822202 -380.187152) (xy 380.776313 -380.216641) (xy 380.726695 -380.2393)
			(xy 380.674357 -380.254667) (xy 380.620366 -380.262429) (xy 380.593092 -380.262892) (xy 379.729492 -380.262892)
			(xy 379.702225 -380.262345) (xy 379.648247 -380.254583) (xy 379.595922 -380.239218) (xy 379.546317 -380.216563)
			(xy 379.500441 -380.18708) (xy 379.459227 -380.151367) (xy 379.423516 -380.110153) (xy 379.394033 -380.064276)
			(xy 379.371379 -380.01467) (xy 379.356015 -379.962346) (xy 379.348254 -379.908367) (xy 374.167228 -379.908367)
			(xy 374.167228 -379.908374) (xy 374.159465 -379.962365) (xy 374.144098 -380.014703) (xy 374.121438 -380.06432)
			(xy 374.091947 -380.110208) (xy 374.056226 -380.151432) (xy 374.015002 -380.187152) (xy 373.969113 -380.216641)
			(xy 373.919495 -380.2393) (xy 373.867157 -380.254667) (xy 373.813166 -380.262429) (xy 373.785892 -380.262892)
			(xy 372.922292 -380.262892) (xy 372.895025 -380.262345) (xy 372.841047 -380.254583) (xy 372.788722 -380.239218)
			(xy 372.739117 -380.216563) (xy 372.693241 -380.18708) (xy 372.652027 -380.151367) (xy 372.616316 -380.110153)
			(xy 372.586833 -380.064276) (xy 372.564179 -380.01467) (xy 372.548815 -379.962346) (xy 372.541054 -379.908367)
			(xy 367.360028 -379.908367) (xy 367.360028 -379.908374) (xy 367.352265 -379.962365) (xy 367.336898 -380.014703)
			(xy 367.314238 -380.06432) (xy 367.284747 -380.110208) (xy 367.249026 -380.151432) (xy 367.207802 -380.187152)
			(xy 367.161913 -380.216641) (xy 367.112295 -380.2393) (xy 367.059957 -380.254667) (xy 367.005966 -380.262429)
			(xy 366.978692 -380.262892) (xy 366.115092 -380.262892) (xy 366.087825 -380.262345) (xy 366.033847 -380.254583)
			(xy 365.981522 -380.239218) (xy 365.931917 -380.216563) (xy 365.886041 -380.18708) (xy 365.844827 -380.151367)
			(xy 365.809116 -380.110153) (xy 365.779633 -380.064276) (xy 365.756979 -380.01467) (xy 365.741615 -379.962346)
			(xy 365.733854 -379.908367) (xy 353.209106 -379.908367) (xy 353.209106 -379.90837) (xy 353.201344 -379.962353)
			(xy 353.18598 -380.014684) (xy 353.163325 -380.064295) (xy 353.133841 -380.110177) (xy 353.098128 -380.151397)
			(xy 353.056912 -380.187115) (xy 353.011033 -380.216604) (xy 352.961425 -380.239265) (xy 352.909097 -380.254635)
			(xy 352.855113 -380.262402) (xy 352.827844 -380.262892) (xy 351.964244 -380.262892) (xy 351.936973 -380.262372)
			(xy 351.882986 -380.254615) (xy 351.830652 -380.239254) (xy 351.781037 -380.216601) (xy 351.735151 -380.187116)
			(xy 351.693929 -380.151402) (xy 351.65821 -380.110184) (xy 351.628721 -380.064302) (xy 351.606061 -380.014689)
			(xy 351.590694 -379.962357) (xy 351.582932 -379.908371) (xy 346.401906 -379.908371) (xy 346.394144 -379.962353)
			(xy 346.37878 -380.014684) (xy 346.356125 -380.064295) (xy 346.326641 -380.110177) (xy 346.290928 -380.151397)
			(xy 346.249712 -380.187115) (xy 346.203833 -380.216604) (xy 346.154225 -380.239265) (xy 346.101897 -380.254635)
			(xy 346.047913 -380.262402) (xy 346.020644 -380.262892) (xy 345.157044 -380.262892) (xy 345.129773 -380.262372)
			(xy 345.075786 -380.254615) (xy 345.023452 -380.239254) (xy 344.973837 -380.216601) (xy 344.927951 -380.187116)
			(xy 344.886729 -380.151402) (xy 344.85101 -380.110184) (xy 344.821521 -380.064302) (xy 344.798861 -380.014689)
			(xy 344.783494 -379.962357) (xy 344.775732 -379.908371) (xy 339.594706 -379.908371) (xy 339.586944 -379.962353)
			(xy 339.57158 -380.014684) (xy 339.548925 -380.064295) (xy 339.519441 -380.110177) (xy 339.483728 -380.151397)
			(xy 339.442512 -380.187115) (xy 339.396633 -380.216604) (xy 339.347025 -380.239265) (xy 339.294697 -380.254635)
			(xy 339.240713 -380.262402) (xy 339.213444 -380.262892) (xy 338.349844 -380.262892) (xy 338.322573 -380.262372)
			(xy 338.268586 -380.254615) (xy 338.216252 -380.239254) (xy 338.166637 -380.216601) (xy 338.120751 -380.187116)
			(xy 338.079529 -380.151402) (xy 338.04381 -380.110184) (xy 338.014321 -380.064302) (xy 337.991661 -380.014689)
			(xy 337.976294 -379.962357) (xy 337.968532 -379.908371) (xy 332.787506 -379.908371) (xy 332.779744 -379.962353)
			(xy 332.76438 -380.014684) (xy 332.741725 -380.064295) (xy 332.712241 -380.110177) (xy 332.676528 -380.151397)
			(xy 332.635312 -380.187115) (xy 332.589433 -380.216604) (xy 332.539825 -380.239265) (xy 332.487497 -380.254635)
			(xy 332.433513 -380.262402) (xy 332.406244 -380.262892) (xy 331.542644 -380.262892) (xy 331.515373 -380.262372)
			(xy 331.461386 -380.254615) (xy 331.409052 -380.239254) (xy 331.359437 -380.216601) (xy 331.313551 -380.187116)
			(xy 331.272329 -380.151402) (xy 331.23661 -380.110184) (xy 331.207121 -380.064302) (xy 331.184461 -380.014689)
			(xy 331.169094 -379.962357) (xy 331.161332 -379.908371) (xy 320.681428 -379.908371) (xy 320.681428 -379.908373)
			(xy 320.673666 -379.962365) (xy 320.658298 -380.014702) (xy 320.635638 -380.064319) (xy 320.606148 -380.110207)
			(xy 320.570427 -380.15143) (xy 320.529203 -380.18715) (xy 320.483316 -380.21664) (xy 320.433698 -380.239299)
			(xy 320.381361 -380.254666) (xy 320.327369 -380.262429) (xy 320.300096 -380.262892) (xy 319.436496 -380.262892)
			(xy 319.409229 -380.262345) (xy 319.35525 -380.254584) (xy 319.302925 -380.239219) (xy 319.253319 -380.216565)
			(xy 319.207442 -380.187081) (xy 319.166229 -380.151369) (xy 319.130517 -380.110154) (xy 319.101033 -380.064277)
			(xy 319.078379 -380.014671) (xy 319.063015 -379.962346) (xy 319.055254 -379.908367) (xy 313.874228 -379.908367)
			(xy 313.874228 -379.908373) (xy 313.866466 -379.962365) (xy 313.851098 -380.014702) (xy 313.828438 -380.064319)
			(xy 313.798948 -380.110207) (xy 313.763227 -380.15143) (xy 313.722003 -380.18715) (xy 313.676116 -380.21664)
			(xy 313.626498 -380.239299) (xy 313.574161 -380.254666) (xy 313.520169 -380.262429) (xy 313.492896 -380.262892)
			(xy 312.629296 -380.262892) (xy 312.602029 -380.262345) (xy 312.54805 -380.254584) (xy 312.495725 -380.239219)
			(xy 312.446119 -380.216565) (xy 312.400242 -380.187081) (xy 312.359029 -380.151369) (xy 312.323317 -380.110154)
			(xy 312.293833 -380.064277) (xy 312.271179 -380.014671) (xy 312.255815 -379.962346) (xy 312.248054 -379.908367)
			(xy 307.067028 -379.908367) (xy 307.067028 -379.908373) (xy 307.059266 -379.962365) (xy 307.043898 -380.014702)
			(xy 307.021238 -380.064319) (xy 306.991748 -380.110207) (xy 306.956027 -380.15143) (xy 306.914803 -380.18715)
			(xy 306.868916 -380.21664) (xy 306.819298 -380.239299) (xy 306.766961 -380.254666) (xy 306.712969 -380.262429)
			(xy 306.685696 -380.262892) (xy 305.822096 -380.262892) (xy 305.794829 -380.262345) (xy 305.74085 -380.254584)
			(xy 305.688525 -380.239219) (xy 305.638919 -380.216565) (xy 305.593042 -380.187081) (xy 305.551829 -380.151369)
			(xy 305.516117 -380.110154) (xy 305.486633 -380.064277) (xy 305.463979 -380.014671) (xy 305.448615 -379.962346)
			(xy 305.440854 -379.908367) (xy 300.259828 -379.908367) (xy 300.259828 -379.908373) (xy 300.252066 -379.962365)
			(xy 300.236698 -380.014702) (xy 300.214038 -380.064319) (xy 300.184548 -380.110207) (xy 300.148827 -380.15143)
			(xy 300.107603 -380.18715) (xy 300.061716 -380.21664) (xy 300.012098 -380.239299) (xy 299.959761 -380.254666)
			(xy 299.905769 -380.262429) (xy 299.878496 -380.262892) (xy 299.014896 -380.262892) (xy 298.987629 -380.262345)
			(xy 298.93365 -380.254584) (xy 298.881325 -380.239219) (xy 298.831719 -380.216565) (xy 298.785842 -380.187081)
			(xy 298.744629 -380.151369) (xy 298.708917 -380.110154) (xy 298.679433 -380.064277) (xy 298.656779 -380.014671)
			(xy 298.641415 -379.962346) (xy 298.633654 -379.908367) (xy 179.577684 -379.908367) (xy 179.500651 -379.955161)
			(xy 179.344302 -380.040842) (xy 179.184291 -380.119474) (xy 179.020937 -380.1909) (xy 178.854562 -380.254978)
			(xy 178.685499 -380.31158) (xy 178.514082 -380.360596) (xy 178.340651 -380.401926) (xy 178.165551 -380.43549)
			(xy 177.989131 -380.46122) (xy 177.811739 -380.479066) (xy 177.633728 -380.488992) (xy 177.455451 -380.490978)
			(xy 177.277264 -380.485021) (xy 177.099518 -380.471131) (xy 176.922568 -380.449338) (xy 176.746764 -380.419684)
			(xy 176.572456 -380.382227) (xy 176.399989 -380.337043) (xy 176.229706 -380.284221) (xy 176.061945 -380.223865)
			(xy 175.89704 -380.156097) (xy 175.735317 -380.081049) (xy 175.577098 -379.998872) (xy 175.422697 -379.909729)
			(xy 175.27242 -379.813795) (xy 175.126565 -379.711263) (xy 174.985423 -379.602335) (xy 174.849274 -379.487228)
			(xy 174.718387 -379.36617) (xy 174.593023 -379.239401) (xy 174.47343 -379.107174) (xy 174.359847 -378.969751)
			(xy 174.252498 -378.827404) (xy 174.151597 -378.680416) (xy 174.057344 -378.52908) (xy 173.969926 -378.373695)
			(xy 173.889516 -378.21457) (xy 173.816275 -378.052021) (xy 173.750348 -377.886371) (xy 173.691865 -377.717949)
			(xy 173.640943 -377.547088) (xy 173.597683 -377.374129) (xy 173.562171 -377.199414) (xy 173.534477 -377.02329)
			(xy 173.514656 -376.846108) (xy 173.502748 -376.668219) (xy 173.498776 -376.489976) (xy 171.286932 -376.489976)
			(xy 171.286932 -376.956828) (xy 171.286446 -376.984079) (xy 171.27869 -377.038027) (xy 171.263335 -377.090322)
			(xy 171.240693 -377.139899) (xy 171.211227 -377.185749) (xy 171.175536 -377.22694) (xy 171.134345 -377.262631)
			(xy 171.088495 -377.292097) (xy 171.038918 -377.314739) (xy 170.986623 -377.330094) (xy 170.932675 -377.33785)
			(xy 170.878173 -377.33785) (xy 170.824225 -377.330094) (xy 170.77193 -377.314739) (xy 170.722353 -377.292097)
			(xy 170.676503 -377.262631) (xy 170.635312 -377.22694) (xy 170.599621 -377.185749) (xy 170.570155 -377.139899)
			(xy 170.547513 -377.090322) (xy 170.532158 -377.038027) (xy 170.524402 -376.984079) (xy 170.523916 -376.956828)
			(xy 141.418806 -376.956828) (xy 141.416303 -376.965354) (xy 141.393661 -377.014931) (xy 141.364195 -377.060781)
			(xy 141.328504 -377.101972) (xy 141.287313 -377.137663) (xy 141.241463 -377.167129) (xy 141.191886 -377.189771)
			(xy 141.139591 -377.205126) (xy 141.085643 -377.212882) (xy 141.031141 -377.212882) (xy 140.977193 -377.205126)
			(xy 140.924898 -377.189771) (xy 140.875321 -377.167129) (xy 140.829471 -377.137663) (xy 140.78828 -377.101972)
			(xy 140.752589 -377.060781) (xy 140.723123 -377.014931) (xy 140.700481 -376.965354) (xy 140.685126 -376.913059)
			(xy 140.67737 -376.859111) (xy 140.676884 -376.83186) (xy 138.759184 -376.83186) (xy 138.759184 -376.956828)
			(xy 138.758698 -376.984079) (xy 138.750942 -377.038027) (xy 138.735587 -377.090322) (xy 138.712945 -377.139899)
			(xy 138.683479 -377.185749) (xy 138.647788 -377.22694) (xy 138.606597 -377.262631) (xy 138.560747 -377.292097)
			(xy 138.51117 -377.314739) (xy 138.458875 -377.330094) (xy 138.404927 -377.33785) (xy 138.350425 -377.33785)
			(xy 138.296477 -377.330094) (xy 138.244182 -377.314739) (xy 138.194605 -377.292097) (xy 138.148755 -377.262631)
			(xy 138.107564 -377.22694) (xy 138.071873 -377.185749) (xy 138.042407 -377.139899) (xy 138.019765 -377.090322)
			(xy 138.00441 -377.038027) (xy 137.996654 -376.984079) (xy 137.996168 -376.956828) (xy 108.891058 -376.956828)
			(xy 108.888555 -376.965354) (xy 108.865913 -377.014931) (xy 108.836447 -377.060781) (xy 108.800756 -377.101972)
			(xy 108.759565 -377.137663) (xy 108.713715 -377.167129) (xy 108.664138 -377.189771) (xy 108.611843 -377.205126)
			(xy 108.557895 -377.212882) (xy 108.503393 -377.212882) (xy 108.449445 -377.205126) (xy 108.39715 -377.189771)
			(xy 108.347573 -377.167129) (xy 108.301723 -377.137663) (xy 108.260532 -377.101972) (xy 108.224841 -377.060781)
			(xy 108.195375 -377.014931) (xy 108.172733 -376.965354) (xy 108.157378 -376.913059) (xy 108.149622 -376.859111)
			(xy 108.149136 -376.83186) (xy 104.187244 -376.83186) (xy 104.187244 -376.956828) (xy 104.186758 -376.984097)
			(xy 104.178996 -377.038081) (xy 104.163631 -377.090411) (xy 104.140974 -377.140021) (xy 104.111488 -377.185902)
			(xy 104.075773 -377.227119) (xy 104.034556 -377.262834) (xy 103.988675 -377.29232) (xy 103.939065 -377.314977)
			(xy 103.886735 -377.330342) (xy 103.832751 -377.338104) (xy 103.778213 -377.338104) (xy 103.724229 -377.330342)
			(xy 103.671899 -377.314977) (xy 103.622289 -377.29232) (xy 103.576408 -377.262834) (xy 103.535191 -377.227119)
			(xy 103.499476 -377.185902) (xy 103.46999 -377.140021) (xy 103.447333 -377.090411) (xy 103.431968 -377.038081)
			(xy 103.424206 -376.984097) (xy 103.42372 -376.956828) (xy 74.319129 -376.956828) (xy 74.316599 -376.965443)
			(xy 74.293942 -377.015053) (xy 74.264456 -377.060934) (xy 74.228741 -377.102151) (xy 74.187524 -377.137866)
			(xy 74.141643 -377.167352) (xy 74.092033 -377.190009) (xy 74.039703 -377.205374) (xy 73.985719 -377.213136)
			(xy 73.931181 -377.213136) (xy 73.877197 -377.205374) (xy 73.824867 -377.190009) (xy 73.775257 -377.167352)
			(xy 73.729376 -377.137866) (xy 73.688159 -377.102151) (xy 73.652444 -377.060934) (xy 73.622958 -377.015053)
			(xy 73.600301 -376.965443) (xy 73.584936 -376.913113) (xy 73.577174 -376.859129) (xy 73.576688 -376.83186)
			(xy 71.659496 -376.83186) (xy 71.659496 -376.956828) (xy 71.65901 -376.984097) (xy 71.651248 -377.038081)
			(xy 71.635883 -377.090411) (xy 71.613226 -377.140021) (xy 71.58374 -377.185902) (xy 71.548025 -377.227119)
			(xy 71.506808 -377.262834) (xy 71.460927 -377.29232) (xy 71.411317 -377.314977) (xy 71.358987 -377.330342)
			(xy 71.305003 -377.338104) (xy 71.250465 -377.338104) (xy 71.196481 -377.330342) (xy 71.144151 -377.314977)
			(xy 71.094541 -377.29232) (xy 71.04866 -377.262834) (xy 71.007443 -377.227119) (xy 70.971728 -377.185902)
			(xy 70.942242 -377.140021) (xy 70.919585 -377.090411) (xy 70.90422 -377.038081) (xy 70.896458 -376.984097)
			(xy 70.895972 -376.956828) (xy 41.791381 -376.956828) (xy 41.788851 -376.965443) (xy 41.766194 -377.015053)
			(xy 41.736708 -377.060934) (xy 41.700993 -377.102151) (xy 41.659776 -377.137866) (xy 41.613895 -377.167352)
			(xy 41.564285 -377.190009) (xy 41.511955 -377.205374) (xy 41.457971 -377.213136) (xy 41.403433 -377.213136)
			(xy 41.349449 -377.205374) (xy 41.297119 -377.190009) (xy 41.247509 -377.167352) (xy 41.201628 -377.137866)
			(xy 41.160411 -377.102151) (xy 41.124696 -377.060934) (xy 41.09521 -377.015053) (xy 41.072553 -376.965443)
			(xy 41.057188 -376.913113) (xy 41.049426 -376.859129) (xy 41.04894 -376.83186) (xy 39.05568 -376.83186)
			(xy 39.046481 -376.93481) (xy 39.022717 -377.111506) (xy 38.991106 -377.286969) (xy 38.95171 -377.460849)
			(xy 38.904608 -377.632802) (xy 38.849892 -377.802486) (xy 38.787671 -377.969563) (xy 38.71807 -378.133704)
			(xy 38.641225 -378.29458) (xy 38.557291 -378.451874) (xy 38.466433 -378.605273) (xy 38.368831 -378.754472)
			(xy 38.26468 -378.899175) (xy 38.154187 -379.039095) (xy 38.03757 -379.173954) (xy 37.915061 -379.303484)
			(xy 37.786904 -379.427428) (xy 37.653353 -379.54554) (xy 37.514673 -379.657585) (xy 37.371139 -379.763342)
			(xy 37.223036 -379.862599) (xy 37.070659 -379.955161) (xy 36.91431 -380.040842) (xy 36.754299 -380.119474)
			(xy 36.590945 -380.1909) (xy 36.42457 -380.254978) (xy 36.255507 -380.31158) (xy 36.084678 -380.360428)
			(xy 70.895972 -380.360428) (xy 70.895972 -379.496828) (xy 70.896458 -379.469559) (xy 70.90422 -379.415575)
			(xy 70.919585 -379.363245) (xy 70.942242 -379.313635) (xy 70.971728 -379.267754) (xy 71.007443 -379.226537)
			(xy 71.04866 -379.190822) (xy 71.094541 -379.161336) (xy 71.144151 -379.138679) (xy 71.196481 -379.123314)
			(xy 71.250465 -379.115552) (xy 71.305003 -379.115552) (xy 71.358987 -379.123314) (xy 71.411317 -379.138679)
			(xy 71.460927 -379.161336) (xy 71.506808 -379.190822) (xy 71.548025 -379.226537) (xy 71.58374 -379.267754)
			(xy 71.613226 -379.313635) (xy 71.635883 -379.363245) (xy 71.651248 -379.415575) (xy 71.65901 -379.469559)
			(xy 71.659496 -379.496828) (xy 71.659496 -380.360428) (xy 103.42372 -380.360428) (xy 103.42372 -379.496828)
			(xy 103.424206 -379.469559) (xy 103.431968 -379.415575) (xy 103.447333 -379.363245) (xy 103.46999 -379.313635)
			(xy 103.499476 -379.267754) (xy 103.535191 -379.226537) (xy 103.576408 -379.190822) (xy 103.622289 -379.161336)
			(xy 103.671899 -379.138679) (xy 103.724229 -379.123314) (xy 103.778213 -379.115552) (xy 103.832751 -379.115552)
			(xy 103.886735 -379.123314) (xy 103.939065 -379.138679) (xy 103.988675 -379.161336) (xy 104.034556 -379.190822)
			(xy 104.075773 -379.226537) (xy 104.111488 -379.267754) (xy 104.140974 -379.313635) (xy 104.163631 -379.363245)
			(xy 104.178996 -379.415575) (xy 104.186758 -379.469559) (xy 104.187244 -379.496828) (xy 104.187244 -380.360428)
			(xy 137.996168 -380.360428) (xy 137.996168 -379.496828) (xy 137.996654 -379.469577) (xy 138.00441 -379.415629)
			(xy 138.019765 -379.363334) (xy 138.042407 -379.313757) (xy 138.071873 -379.267907) (xy 138.107564 -379.226716)
			(xy 138.148755 -379.191025) (xy 138.194605 -379.161559) (xy 138.244182 -379.138917) (xy 138.296477 -379.123562)
			(xy 138.350425 -379.115806) (xy 138.404927 -379.115806) (xy 138.458875 -379.123562) (xy 138.51117 -379.138917)
			(xy 138.560747 -379.161559) (xy 138.606597 -379.191025) (xy 138.647788 -379.226716) (xy 138.683479 -379.267907)
			(xy 138.712945 -379.313757) (xy 138.735587 -379.363334) (xy 138.750942 -379.415629) (xy 138.758698 -379.469577)
			(xy 138.759184 -379.496828) (xy 138.759184 -380.360428) (xy 170.523916 -380.360428) (xy 170.523916 -379.496828)
			(xy 170.524402 -379.469577) (xy 170.532158 -379.415629) (xy 170.547513 -379.363334) (xy 170.570155 -379.313757)
			(xy 170.599621 -379.267907) (xy 170.635312 -379.226716) (xy 170.676503 -379.191025) (xy 170.722353 -379.161559)
			(xy 170.77193 -379.138917) (xy 170.824225 -379.123562) (xy 170.878173 -379.115806) (xy 170.932675 -379.115806)
			(xy 170.986623 -379.123562) (xy 171.038918 -379.138917) (xy 171.088495 -379.161559) (xy 171.134345 -379.191025)
			(xy 171.175536 -379.226716) (xy 171.211227 -379.267907) (xy 171.240693 -379.313757) (xy 171.263335 -379.363334)
			(xy 171.27869 -379.415629) (xy 171.286446 -379.469577) (xy 171.286932 -379.496828) (xy 171.286932 -380.360428)
			(xy 171.286446 -380.387679) (xy 171.27869 -380.441627) (xy 171.263335 -380.493922) (xy 171.240693 -380.543499)
			(xy 171.211227 -380.589349) (xy 171.175536 -380.63054) (xy 171.134345 -380.666231) (xy 171.088495 -380.695697)
			(xy 171.038918 -380.718339) (xy 170.986623 -380.733694) (xy 170.932675 -380.74145) (xy 170.878173 -380.74145)
			(xy 170.824225 -380.733694) (xy 170.77193 -380.718339) (xy 170.722353 -380.695697) (xy 170.676503 -380.666231)
			(xy 170.635312 -380.63054) (xy 170.599621 -380.589349) (xy 170.570155 -380.543499) (xy 170.547513 -380.493922)
			(xy 170.532158 -380.441627) (xy 170.524402 -380.387679) (xy 170.523916 -380.360428) (xy 138.759184 -380.360428)
			(xy 138.758698 -380.387679) (xy 138.750942 -380.441627) (xy 138.735587 -380.493922) (xy 138.712945 -380.543499)
			(xy 138.683479 -380.589349) (xy 138.647788 -380.63054) (xy 138.606597 -380.666231) (xy 138.560747 -380.695697)
			(xy 138.51117 -380.718339) (xy 138.458875 -380.733694) (xy 138.404927 -380.74145) (xy 138.350425 -380.74145)
			(xy 138.296477 -380.733694) (xy 138.244182 -380.718339) (xy 138.194605 -380.695697) (xy 138.148755 -380.666231)
			(xy 138.107564 -380.63054) (xy 138.071873 -380.589349) (xy 138.042407 -380.543499) (xy 138.019765 -380.493922)
			(xy 138.00441 -380.441627) (xy 137.996654 -380.387679) (xy 137.996168 -380.360428) (xy 104.187244 -380.360428)
			(xy 104.186758 -380.387697) (xy 104.178996 -380.441681) (xy 104.163631 -380.494011) (xy 104.140974 -380.543621)
			(xy 104.111488 -380.589502) (xy 104.075773 -380.630719) (xy 104.034556 -380.666434) (xy 103.988675 -380.69592)
			(xy 103.939065 -380.718577) (xy 103.886735 -380.733942) (xy 103.832751 -380.741704) (xy 103.778213 -380.741704)
			(xy 103.724229 -380.733942) (xy 103.671899 -380.718577) (xy 103.622289 -380.69592) (xy 103.576408 -380.666434)
			(xy 103.535191 -380.630719) (xy 103.499476 -380.589502) (xy 103.46999 -380.543621) (xy 103.447333 -380.494011)
			(xy 103.431968 -380.441681) (xy 103.424206 -380.387697) (xy 103.42372 -380.360428) (xy 71.659496 -380.360428)
			(xy 71.65901 -380.387697) (xy 71.651248 -380.441681) (xy 71.635883 -380.494011) (xy 71.613226 -380.543621)
			(xy 71.58374 -380.589502) (xy 71.548025 -380.630719) (xy 71.506808 -380.666434) (xy 71.460927 -380.69592)
			(xy 71.411317 -380.718577) (xy 71.358987 -380.733942) (xy 71.305003 -380.741704) (xy 71.250465 -380.741704)
			(xy 71.196481 -380.733942) (xy 71.144151 -380.718577) (xy 71.094541 -380.69592) (xy 71.04866 -380.666434)
			(xy 71.007443 -380.630719) (xy 70.971728 -380.589502) (xy 70.942242 -380.543621) (xy 70.919585 -380.494011)
			(xy 70.90422 -380.441681) (xy 70.896458 -380.387697) (xy 70.895972 -380.360428) (xy 36.084678 -380.360428)
			(xy 36.08409 -380.360596) (xy 35.910659 -380.401926) (xy 35.735559 -380.43549) (xy 35.559139 -380.46122)
			(xy 35.381747 -380.479066) (xy 35.203736 -380.488992) (xy 35.025459 -380.490978) (xy 34.847272 -380.485021)
			(xy 34.669526 -380.471131) (xy 34.492576 -380.449338) (xy 34.316772 -380.419684) (xy 34.142464 -380.382227)
			(xy 33.969997 -380.337043) (xy 33.799714 -380.284221) (xy 33.631953 -380.223865) (xy 33.467048 -380.156097)
			(xy 33.305325 -380.081049) (xy 33.147106 -379.998872) (xy 32.992705 -379.909729) (xy 32.842428 -379.813795)
			(xy 32.696573 -379.711263) (xy 32.555431 -379.602335) (xy 32.419282 -379.487228) (xy 32.288395 -379.36617)
			(xy 32.163031 -379.239401) (xy 32.043438 -379.107174) (xy 31.929855 -378.969751) (xy 31.822506 -378.827404)
			(xy 31.721605 -378.680416) (xy 31.627352 -378.52908) (xy 31.539934 -378.373695) (xy 31.459524 -378.21457)
			(xy 31.386283 -378.052021) (xy 31.320356 -377.886371) (xy 31.261873 -377.717949) (xy 31.210951 -377.547088)
			(xy 31.167691 -377.374129) (xy 31.132179 -377.199414) (xy 31.104485 -377.02329) (xy 31.084664 -376.846108)
			(xy 31.072756 -376.668219) (xy 31.068784 -376.489976) (xy 2.509012 -376.489976) (xy 2.509012 -382.36906)
			(xy 41.04894 -382.36906) (xy 41.04894 -381.50546) (xy 41.049426 -381.478191) (xy 41.057188 -381.424207)
			(xy 41.072553 -381.371877) (xy 41.09521 -381.322267) (xy 41.124696 -381.276386) (xy 41.160411 -381.235169)
			(xy 41.201628 -381.199454) (xy 41.247509 -381.169968) (xy 41.297119 -381.147311) (xy 41.349449 -381.131946)
			(xy 41.403433 -381.124184) (xy 41.457971 -381.124184) (xy 41.511955 -381.131946) (xy 41.564285 -381.147311)
			(xy 41.613895 -381.169968) (xy 41.659776 -381.199454) (xy 41.700993 -381.235169) (xy 41.736708 -381.276386)
			(xy 41.766194 -381.322267) (xy 41.788851 -381.371877) (xy 41.804216 -381.424207) (xy 41.811978 -381.478191)
			(xy 41.812464 -381.50546) (xy 41.812464 -382.36906) (xy 73.576688 -382.36906) (xy 73.576688 -381.50546)
			(xy 73.577174 -381.478191) (xy 73.584936 -381.424207) (xy 73.600301 -381.371877) (xy 73.622958 -381.322267)
			(xy 73.652444 -381.276386) (xy 73.688159 -381.235169) (xy 73.729376 -381.199454) (xy 73.775257 -381.169968)
			(xy 73.824867 -381.147311) (xy 73.877197 -381.131946) (xy 73.931181 -381.124184) (xy 73.985719 -381.124184)
			(xy 74.039703 -381.131946) (xy 74.092033 -381.147311) (xy 74.141643 -381.169968) (xy 74.187524 -381.199454)
			(xy 74.228741 -381.235169) (xy 74.264456 -381.276386) (xy 74.293942 -381.322267) (xy 74.316599 -381.371877)
			(xy 74.331964 -381.424207) (xy 74.339726 -381.478191) (xy 74.340212 -381.50546) (xy 74.340212 -382.36906)
			(xy 108.149136 -382.36906) (xy 108.149136 -381.50546) (xy 108.149622 -381.478209) (xy 108.157378 -381.424261)
			(xy 108.172733 -381.371966) (xy 108.195375 -381.322389) (xy 108.224841 -381.276539) (xy 108.260532 -381.235348)
			(xy 108.301723 -381.199657) (xy 108.347573 -381.170191) (xy 108.39715 -381.147549) (xy 108.449445 -381.132194)
			(xy 108.503393 -381.124438) (xy 108.557895 -381.124438) (xy 108.611843 -381.132194) (xy 108.664138 -381.147549)
			(xy 108.713715 -381.170191) (xy 108.759565 -381.199657) (xy 108.800756 -381.235348) (xy 108.836447 -381.276539)
			(xy 108.865913 -381.322389) (xy 108.888555 -381.371966) (xy 108.90391 -381.424261) (xy 108.911666 -381.478209)
			(xy 108.912152 -381.50546) (xy 108.912152 -382.36906) (xy 140.676884 -382.36906) (xy 140.676884 -381.50546)
			(xy 140.67737 -381.478209) (xy 140.685126 -381.424261) (xy 140.700481 -381.371966) (xy 140.723123 -381.322389)
			(xy 140.752589 -381.276539) (xy 140.78828 -381.235348) (xy 140.829471 -381.199657) (xy 140.875321 -381.170191)
			(xy 140.924898 -381.147549) (xy 140.977193 -381.132194) (xy 141.031141 -381.124438) (xy 141.085643 -381.124438)
			(xy 141.139591 -381.132194) (xy 141.191886 -381.147549) (xy 141.241463 -381.170191) (xy 141.287313 -381.199657)
			(xy 141.328504 -381.235348) (xy 141.364195 -381.276539) (xy 141.393661 -381.322389) (xy 141.416303 -381.371966)
			(xy 141.431658 -381.424261) (xy 141.439414 -381.478209) (xy 141.4399 -381.50546) (xy 141.4399 -382.36906)
			(xy 141.439414 -382.396311) (xy 141.431658 -382.450259) (xy 141.416303 -382.502554) (xy 141.393661 -382.552131)
			(xy 141.364195 -382.597981) (xy 141.328504 -382.639172) (xy 141.287313 -382.674863) (xy 141.241463 -382.704329)
			(xy 141.191886 -382.726971) (xy 141.139591 -382.742326) (xy 141.085643 -382.750082) (xy 141.031141 -382.750082)
			(xy 140.977193 -382.742326) (xy 140.924898 -382.726971) (xy 140.875321 -382.704329) (xy 140.829471 -382.674863)
			(xy 140.78828 -382.639172) (xy 140.752589 -382.597981) (xy 140.723123 -382.552131) (xy 140.700481 -382.502554)
			(xy 140.685126 -382.450259) (xy 140.67737 -382.396311) (xy 140.676884 -382.36906) (xy 108.912152 -382.36906)
			(xy 108.911666 -382.396311) (xy 108.90391 -382.450259) (xy 108.888555 -382.502554) (xy 108.865913 -382.552131)
			(xy 108.836447 -382.597981) (xy 108.800756 -382.639172) (xy 108.759565 -382.674863) (xy 108.713715 -382.704329)
			(xy 108.664138 -382.726971) (xy 108.611843 -382.742326) (xy 108.557895 -382.750082) (xy 108.503393 -382.750082)
			(xy 108.449445 -382.742326) (xy 108.39715 -382.726971) (xy 108.347573 -382.704329) (xy 108.301723 -382.674863)
			(xy 108.260532 -382.639172) (xy 108.224841 -382.597981) (xy 108.195375 -382.552131) (xy 108.172733 -382.502554)
			(xy 108.157378 -382.450259) (xy 108.149622 -382.396311) (xy 108.149136 -382.36906) (xy 74.340212 -382.36906)
			(xy 74.339726 -382.396329) (xy 74.331964 -382.450313) (xy 74.316599 -382.502643) (xy 74.293942 -382.552253)
			(xy 74.264456 -382.598134) (xy 74.228741 -382.639351) (xy 74.187524 -382.675066) (xy 74.141643 -382.704552)
			(xy 74.092033 -382.727209) (xy 74.039703 -382.742574) (xy 73.985719 -382.750336) (xy 73.931181 -382.750336)
			(xy 73.877197 -382.742574) (xy 73.824867 -382.727209) (xy 73.775257 -382.704552) (xy 73.729376 -382.675066)
			(xy 73.688159 -382.639351) (xy 73.652444 -382.598134) (xy 73.622958 -382.552253) (xy 73.600301 -382.502643)
			(xy 73.584936 -382.450313) (xy 73.577174 -382.396329) (xy 73.576688 -382.36906) (xy 41.812464 -382.36906)
			(xy 41.811978 -382.396329) (xy 41.804216 -382.450313) (xy 41.788851 -382.502643) (xy 41.766194 -382.552253)
			(xy 41.736708 -382.598134) (xy 41.700993 -382.639351) (xy 41.659776 -382.675066) (xy 41.613895 -382.704552)
			(xy 41.564285 -382.727209) (xy 41.511955 -382.742574) (xy 41.457971 -382.750336) (xy 41.403433 -382.750336)
			(xy 41.349449 -382.742574) (xy 41.297119 -382.727209) (xy 41.247509 -382.704552) (xy 41.201628 -382.675066)
			(xy 41.160411 -382.639351) (xy 41.124696 -382.598134) (xy 41.09521 -382.552253) (xy 41.072553 -382.502643)
			(xy 41.057188 -382.450313) (xy 41.049426 -382.396329) (xy 41.04894 -382.36906) (xy 2.509012 -382.36906)
			(xy 2.509012 -385.310888) (xy 47.485808 -385.310888) (xy 47.485808 -385.31038) (xy 47.486243 -385.2864)
			(xy 47.493745 -385.239031) (xy 47.508561 -385.193417) (xy 47.530326 -385.15068) (xy 47.558505 -385.111872)
			(xy 47.592406 -385.077947) (xy 47.631194 -385.04974) (xy 47.673915 -385.027944) (xy 47.719518 -385.013096)
			(xy 47.766882 -385.00556) (xy 47.790862 -385.005072) (xy 47.79137 -385.005072) (xy 47.815305 -385.005523)
			(xy 47.862591 -385.012984) (xy 47.908134 -385.027728) (xy 47.950821 -385.049394) (xy 47.989606 -385.077452)
			(xy 48.023541 -385.111216) (xy 48.051795 -385.149858) (xy 48.06315 -385.170934) (xy 48.063658 -385.17195)
			(xy 48.143964 -385.310888) (xy 48.685704 -385.310888) (xy 48.685704 -385.31038) (xy 48.686143 -385.2864)
			(xy 48.693645 -385.239031) (xy 48.70846 -385.193417) (xy 48.730225 -385.150681) (xy 48.758404 -385.111873)
			(xy 48.792304 -385.077949) (xy 48.831092 -385.049741) (xy 48.873812 -385.027945) (xy 48.919415 -385.013097)
			(xy 48.966779 -385.005561) (xy 48.990758 -385.005072) (xy 48.991266 -385.005072) (xy 49.015201 -385.005526)
			(xy 49.062486 -385.012986) (xy 49.10803 -385.02773) (xy 49.150716 -385.049395) (xy 49.189502 -385.077453)
			(xy 49.223437 -385.111216) (xy 49.251691 -385.149859) (xy 49.263046 -385.170934) (xy 49.263554 -385.17195)
			(xy 49.34386 -385.310888) (xy 49.8856 -385.310888) (xy 49.8856 -385.31038) (xy 49.886043 -385.286401)
			(xy 49.893545 -385.239032) (xy 49.90836 -385.193418) (xy 49.930124 -385.150682) (xy 49.958303 -385.111875)
			(xy 49.992203 -385.07795) (xy 50.030989 -385.049743) (xy 50.073709 -385.027946) (xy 50.119312 -385.013097)
			(xy 50.166675 -385.005561) (xy 50.190654 -385.005072) (xy 50.191162 -385.005072) (xy 50.215097 -385.005529)
			(xy 50.262382 -385.012989) (xy 50.307925 -385.027732) (xy 50.350612 -385.049397) (xy 50.389397 -385.077454)
			(xy 50.423333 -385.111217) (xy 50.451587 -385.149859) (xy 50.462942 -385.170934) (xy 50.46345 -385.17195)
			(xy 50.543756 -385.310888) (xy 51.086004 -385.310888) (xy 51.086004 -385.31038) (xy 51.086444 -385.286388)
			(xy 51.093954 -385.238994) (xy 51.108785 -385.193359) (xy 51.130572 -385.150605) (xy 51.158779 -385.111786)
			(xy 51.192711 -385.077858) (xy 51.231533 -385.049655) (xy 51.274288 -385.027872) (xy 51.319925 -385.013046)
			(xy 51.36732 -385.005542) (xy 51.391312 -385.005072) (xy 51.415246 -385.00557) (xy 51.462529 -385.013022)
			(xy 51.508071 -385.027757) (xy 51.550758 -385.049416) (xy 51.589544 -385.077467) (xy 51.62348 -385.111224)
			(xy 51.651736 -385.149861) (xy 51.663092 -385.170934) (xy 51.6636 -385.17195) (xy 51.743906 -385.310888)
			(xy 52.2859 -385.310888) (xy 52.2859 -385.31038) (xy 52.286344 -385.286388) (xy 52.293854 -385.238995)
			(xy 52.308684 -385.19336) (xy 52.330471 -385.150606) (xy 52.358677 -385.111788) (xy 52.392609 -385.077859)
			(xy 52.43143 -385.049656) (xy 52.474186 -385.027873) (xy 52.519822 -385.013047) (xy 52.567216 -385.005542)
			(xy 52.591208 -385.005072) (xy 52.615141 -385.005573) (xy 52.662424 -385.013024) (xy 52.707967 -385.027759)
			(xy 52.750653 -385.049417) (xy 52.789439 -385.077468) (xy 52.823376 -385.111224) (xy 52.851632 -385.149861)
			(xy 52.862988 -385.170934) (xy 52.863496 -385.17195) (xy 52.943802 -385.310888) (xy 53.485796 -385.310888)
			(xy 53.485796 -385.31038) (xy 53.486243 -385.286401) (xy 53.493744 -385.239032) (xy 53.508559 -385.193419)
			(xy 53.530324 -385.150684) (xy 53.558502 -385.111876) (xy 53.592401 -385.077951) (xy 53.631187 -385.049744)
			(xy 53.673907 -385.027948) (xy 53.719508 -385.013098) (xy 53.766871 -385.005561) (xy 53.79085 -385.005072)
			(xy 53.791358 -385.005072) (xy 53.815293 -385.005532) (xy 53.862578 -385.012992) (xy 53.908121 -385.027734)
			(xy 53.950807 -385.049398) (xy 53.989593 -385.077455) (xy 54.023528 -385.111217) (xy 54.051783 -385.149859)
			(xy 54.063138 -385.170934) (xy 54.063646 -385.17195) (xy 54.143952 -385.310888) (xy 54.685692 -385.310888)
			(xy 54.685692 -385.31038) (xy 54.686143 -385.286401) (xy 54.693644 -385.239033) (xy 54.708459 -385.19342)
			(xy 54.730223 -385.150685) (xy 54.758401 -385.111877) (xy 54.792299 -385.077953) (xy 54.831085 -385.049745)
			(xy 54.873804 -385.027949) (xy 54.919405 -385.013099) (xy 54.966767 -385.005562) (xy 54.990746 -385.005072)
			(xy 54.991254 -385.005072) (xy 55.015189 -385.005536) (xy 55.062474 -385.012994) (xy 55.108017 -385.027736)
			(xy 55.150703 -385.0494) (xy 55.189489 -385.077456) (xy 55.223424 -385.111218) (xy 55.251679 -385.149859)
			(xy 55.263034 -385.170934) (xy 55.263542 -385.17195) (xy 55.343848 -385.310888) (xy 55.885588 -385.310888)
			(xy 55.885588 -385.31038) (xy 55.886043 -385.286401) (xy 55.893544 -385.239034) (xy 55.908359 -385.193421)
			(xy 55.930122 -385.150686) (xy 55.958299 -385.111879) (xy 55.992198 -385.077954) (xy 56.030983 -385.049747)
			(xy 56.073701 -385.02795) (xy 56.119302 -385.0131) (xy 56.166663 -385.005562) (xy 56.190642 -385.005072)
			(xy 56.19115 -385.005072) (xy 56.215085 -385.005539) (xy 56.262369 -385.012997) (xy 56.307912 -385.027738)
			(xy 56.350599 -385.049401) (xy 56.389384 -385.077457) (xy 56.42332 -385.111218) (xy 56.451575 -385.149859)
			(xy 56.46293 -385.170934) (xy 56.463438 -385.17195) (xy 56.543744 -385.310888) (xy 57.085992 -385.310888)
			(xy 57.085992 -385.31038) (xy 57.086444 -385.286388) (xy 57.093953 -385.238996) (xy 57.108783 -385.193362)
			(xy 57.130569 -385.150609) (xy 57.158775 -385.11179) (xy 57.192706 -385.077862) (xy 57.231526 -385.049659)
			(xy 57.27428 -385.027876) (xy 57.319915 -385.013049) (xy 57.367308 -385.005543) (xy 57.3913 -385.005072)
			(xy 57.391554 -385.005072) (xy 57.415489 -385.005536) (xy 57.462774 -385.012994) (xy 57.508317 -385.027736)
			(xy 57.551003 -385.0494) (xy 57.589789 -385.077456) (xy 57.623724 -385.111218) (xy 57.651979 -385.149859)
			(xy 57.663334 -385.170934) (xy 57.663842 -385.17195) (xy 57.744148 -385.310888) (xy 58.285888 -385.310888)
			(xy 58.285888 -385.31038) (xy 58.286344 -385.286388) (xy 58.293853 -385.238996) (xy 58.308683 -385.193362)
			(xy 58.330469 -385.15061) (xy 58.358674 -385.111792) (xy 58.392604 -385.077863) (xy 58.431424 -385.04966)
			(xy 58.474177 -385.027877) (xy 58.519812 -385.013049) (xy 58.567204 -385.005543) (xy 58.591196 -385.005072)
			(xy 58.59145 -385.005072) (xy 58.615385 -385.005539) (xy 58.662669 -385.012997) (xy 58.708212 -385.027738)
			(xy 58.750899 -385.049401) (xy 58.789684 -385.077457) (xy 58.82362 -385.111218) (xy 58.851875 -385.149859)
			(xy 58.86323 -385.170934) (xy 58.863738 -385.17195) (xy 58.944044 -385.310888) (xy 59.485784 -385.310888)
			(xy 59.485784 -385.31038) (xy 59.486221 -385.286374) (xy 59.493738 -385.238954) (xy 59.508584 -385.193295)
			(xy 59.530394 -385.150522) (xy 59.558628 -385.11169) (xy 59.592593 -385.077755) (xy 59.63145 -385.049554)
			(xy 59.674241 -385.027782) (xy 59.719913 -385.012976) (xy 59.76734 -385.0055) (xy 59.791346 -385.005072)
			(xy 59.7916 -385.005072) (xy 59.815533 -385.00558) (xy 59.862816 -385.01303) (xy 59.908358 -385.027764)
			(xy 59.951044 -385.04942) (xy 59.989831 -385.07747) (xy 60.023768 -385.111226) (xy 60.052024 -385.149862)
			(xy 60.06338 -385.170934) (xy 60.063888 -385.17195) (xy 60.144194 -385.310888) (xy 60.68568 -385.310888)
			(xy 60.68568 -385.31038) (xy 60.686121 -385.286374) (xy 60.693638 -385.238955) (xy 60.708484 -385.193296)
			(xy 60.730293 -385.150524) (xy 60.758527 -385.111692) (xy 60.792491 -385.077757) (xy 60.831347 -385.049556)
			(xy 60.874139 -385.027783) (xy 60.91981 -385.012977) (xy 60.967236 -385.0055) (xy 60.991242 -385.005072)
			(xy 60.991496 -385.005072) (xy 61.015432 -385.005502) (xy 61.062718 -385.012966) (xy 61.108262 -385.027714)
			(xy 61.150949 -385.049384) (xy 61.189734 -385.077445) (xy 61.223668 -385.111212) (xy 61.251922 -385.149857)
			(xy 61.263276 -385.170934) (xy 61.263784 -385.17195) (xy 61.34409 -385.310888) (xy 61.885576 -385.310888)
			(xy 61.885576 -385.31038) (xy 61.886021 -385.286374) (xy 61.893538 -385.238955) (xy 61.908383 -385.193297)
			(xy 61.930192 -385.150525) (xy 61.958426 -385.111693) (xy 61.992389 -385.077758) (xy 62.031245 -385.049557)
			(xy 62.074036 -385.027785) (xy 62.119707 -385.012977) (xy 62.167132 -385.0055) (xy 62.191138 -385.005072)
			(xy 62.191392 -385.005072) (xy 62.215328 -385.005505) (xy 62.262614 -385.012969) (xy 62.308158 -385.027716)
			(xy 62.350844 -385.049385) (xy 62.38963 -385.077446) (xy 62.423564 -385.111212) (xy 62.451818 -385.149857)
			(xy 62.463172 -385.170934) (xy 62.46368 -385.17195) (xy 62.543986 -385.310888) (xy 63.08598 -385.310888)
			(xy 63.08598 -385.31038) (xy 63.086444 -385.286389) (xy 63.093953 -385.238998) (xy 63.108782 -385.193364)
			(xy 63.130567 -385.150612) (xy 63.158771 -385.111795) (xy 63.192701 -385.077866) (xy 63.231519 -385.049663)
			(xy 63.274272 -385.027879) (xy 63.319905 -385.013051) (xy 63.367297 -385.005543) (xy 63.391288 -385.005072)
			(xy 63.391542 -385.005072) (xy 63.415476 -385.005545) (xy 63.462761 -385.013002) (xy 63.508303 -385.027742)
			(xy 63.55099 -385.049404) (xy 63.589776 -385.077459) (xy 63.623712 -385.11122) (xy 63.651967 -385.14986)
			(xy 63.663322 -385.170934) (xy 63.66383 -385.17195) (xy 63.744136 -385.310888) (xy 64.285876 -385.310888)
			(xy 64.285876 -385.31038) (xy 64.286344 -385.286389) (xy 64.293853 -385.238998) (xy 64.308682 -385.193365)
			(xy 64.330467 -385.150614) (xy 64.35867 -385.111796) (xy 64.392599 -385.077868) (xy 64.431417 -385.049664)
			(xy 64.474169 -385.02788) (xy 64.519802 -385.013052) (xy 64.567193 -385.005544) (xy 64.591184 -385.005072)
			(xy 64.591438 -385.005072) (xy 64.615372 -385.005549) (xy 64.662656 -385.013005) (xy 64.708199 -385.027744)
			(xy 64.750886 -385.049406) (xy 64.789672 -385.07746) (xy 64.823607 -385.11122) (xy 64.851863 -385.14986)
			(xy 64.863218 -385.170934) (xy 64.863726 -385.17195) (xy 64.944032 -385.310888) (xy 65.485772 -385.310888)
			(xy 65.485772 -385.31038) (xy 65.486221 -385.286375) (xy 65.493738 -385.238956) (xy 65.508583 -385.193298)
			(xy 65.530391 -385.150526) (xy 65.558625 -385.111694) (xy 65.592588 -385.07776) (xy 65.631443 -385.049558)
			(xy 65.674233 -385.027786) (xy 65.719903 -385.012978) (xy 65.767328 -385.005501) (xy 65.791334 -385.005072)
			(xy 65.791588 -385.005072) (xy 65.815524 -385.005508) (xy 65.86281 -385.012972) (xy 65.908353 -385.027718)
			(xy 65.95104 -385.049387) (xy 65.989825 -385.077447) (xy 66.02376 -385.111213) (xy 66.052014 -385.149858)
			(xy 66.063368 -385.170934) (xy 66.063876 -385.17195) (xy 66.144182 -385.310888) (xy 80.013556 -385.310888)
			(xy 80.013556 -385.31038) (xy 80.014043 -385.286403) (xy 80.021543 -385.239038) (xy 80.036355 -385.193429)
			(xy 80.058116 -385.150695) (xy 80.08629 -385.11189) (xy 80.120184 -385.077966) (xy 80.158965 -385.049758)
			(xy 80.201679 -385.027959) (xy 80.247275 -385.013106) (xy 80.294633 -385.005564) (xy 80.31861 -385.005072)
			(xy 80.319118 -385.005072) (xy 80.343052 -385.005565) (xy 80.390335 -385.013018) (xy 80.435877 -385.027754)
			(xy 80.478564 -385.049413) (xy 80.51735 -385.077465) (xy 80.551287 -385.111223) (xy 80.579542 -385.149861)
			(xy 80.590898 -385.170934) (xy 80.591406 -385.17195) (xy 80.671712 -385.310888) (xy 81.213452 -385.310888)
			(xy 81.213452 -385.31038) (xy 81.213943 -385.286403) (xy 81.221443 -385.239039) (xy 81.236255 -385.193429)
			(xy 81.258015 -385.150697) (xy 81.286189 -385.111891) (xy 81.320082 -385.077967) (xy 81.358863 -385.049759)
			(xy 81.401576 -385.02796) (xy 81.447172 -385.013107) (xy 81.494529 -385.005565) (xy 81.518506 -385.005072)
			(xy 81.519014 -385.005072) (xy 81.542948 -385.005568) (xy 81.590231 -385.013021) (xy 81.635773 -385.027756)
			(xy 81.67846 -385.049415) (xy 81.717246 -385.077466) (xy 81.751182 -385.111224) (xy 81.779438 -385.149861)
			(xy 81.790794 -385.170934) (xy 81.791302 -385.17195) (xy 81.871608 -385.310888) (xy 82.413348 -385.310888)
			(xy 82.413348 -385.31038) (xy 82.413843 -385.286403) (xy 82.421343 -385.239039) (xy 82.436155 -385.19343)
			(xy 82.457915 -385.150698) (xy 82.486088 -385.111892) (xy 82.519981 -385.077969) (xy 82.55876 -385.04976)
			(xy 82.601473 -385.027961) (xy 82.647069 -385.013108) (xy 82.694426 -385.005565) (xy 82.718402 -385.005072)
			(xy 82.71891 -385.005072) (xy 82.742843 -385.005571) (xy 82.790127 -385.013023) (xy 82.835669 -385.027758)
			(xy 82.878355 -385.049416) (xy 82.917142 -385.077467) (xy 82.951078 -385.111224) (xy 82.979334 -385.149861)
			(xy 82.99069 -385.170934) (xy 82.991198 -385.17195) (xy 83.071504 -385.310888) (xy 83.613752 -385.310888)
			(xy 83.613752 -385.31038) (xy 83.614244 -385.28639) (xy 83.621752 -385.239002) (xy 83.63658 -385.193371)
			(xy 83.658362 -385.150621) (xy 83.686563 -385.111804) (xy 83.720489 -385.077876) (xy 83.759304 -385.049673)
			(xy 83.802052 -385.027887) (xy 83.847682 -385.013057) (xy 83.89507 -385.005546) (xy 83.91906 -385.005072)
			(xy 83.942995 -385.005531) (xy 83.99028 -385.01299) (xy 84.035823 -385.027733) (xy 84.07851 -385.049398)
			(xy 84.117295 -385.077455) (xy 84.151231 -385.111217) (xy 84.179485 -385.149859) (xy 84.19084 -385.170934)
			(xy 84.191348 -385.17195) (xy 84.271654 -385.310888) (xy 84.813648 -385.310888) (xy 84.813648 -385.31038)
			(xy 84.814144 -385.28639) (xy 84.821652 -385.239002) (xy 84.836479 -385.193372) (xy 84.858261 -385.150622)
			(xy 84.886462 -385.111805) (xy 84.920387 -385.077878) (xy 84.959201 -385.049674) (xy 85.001949 -385.027888)
			(xy 85.047579 -385.013057) (xy 85.094966 -385.005546) (xy 85.118956 -385.005072) (xy 85.142891 -385.005534)
			(xy 85.190176 -385.012993) (xy 85.235719 -385.027735) (xy 85.278405 -385.049399) (xy 85.317191 -385.077456)
			(xy 85.351126 -385.111218) (xy 85.379381 -385.149859) (xy 85.390736 -385.170934) (xy 85.391244 -385.17195)
			(xy 85.47155 -385.310888) (xy 86.013544 -385.310888) (xy 86.013544 -385.31038) (xy 86.014043 -385.286403)
			(xy 86.021543 -385.23904) (xy 86.036354 -385.193431) (xy 86.058114 -385.150699) (xy 86.086287 -385.111894)
			(xy 86.120179 -385.07797) (xy 86.158958 -385.049762) (xy 86.20167 -385.027962) (xy 86.247265 -385.013109)
			(xy 86.294622 -385.005565) (xy 86.318598 -385.005072) (xy 86.319106 -385.005072) (xy 86.343039 -385.005575)
			(xy 86.390322 -385.013026) (xy 86.435864 -385.02776) (xy 86.478551 -385.049418) (xy 86.517337 -385.077468)
			(xy 86.551274 -385.111225) (xy 86.57953 -385.149861) (xy 86.590886 -385.170934) (xy 86.591394 -385.17195)
			(xy 86.6717 -385.310888) (xy 87.21344 -385.310888) (xy 87.21344 -385.31038) (xy 87.213843 -385.286399)
			(xy 87.221346 -385.239026) (xy 87.236164 -385.193409) (xy 87.257932 -385.15067) (xy 87.286115 -385.111861)
			(xy 87.320019 -385.077936) (xy 87.358812 -385.049729) (xy 87.401537 -385.027935) (xy 87.447145 -385.013089)
			(xy 87.494513 -385.005558) (xy 87.518494 -385.005072) (xy 87.519002 -385.005072) (xy 87.542935 -385.005578)
			(xy 87.590218 -385.013028) (xy 87.63576 -385.027763) (xy 87.678447 -385.04942) (xy 87.717233 -385.077469)
			(xy 87.75117 -385.111225) (xy 87.779426 -385.149861) (xy 87.790782 -385.170934) (xy 87.79129 -385.17195)
			(xy 87.871596 -385.310888) (xy 88.413336 -385.310888) (xy 88.413336 -385.31038) (xy 88.413743 -385.286399)
			(xy 88.421246 -385.239027) (xy 88.436063 -385.19341) (xy 88.457831 -385.150672) (xy 88.486013 -385.111862)
			(xy 88.519918 -385.077937) (xy 88.558709 -385.04973) (xy 88.601434 -385.027936) (xy 88.647041 -385.01309)
			(xy 88.694409 -385.005558) (xy 88.71839 -385.005072) (xy 88.718898 -385.005072) (xy 88.742834 -385.0055)
			(xy 88.790121 -385.012965) (xy 88.835664 -385.027713) (xy 88.878351 -385.049383) (xy 88.917136 -385.077445)
			(xy 88.95107 -385.111212) (xy 88.979324 -385.149857) (xy 88.990678 -385.170934) (xy 88.991186 -385.17195)
			(xy 89.071492 -385.310888) (xy 89.61374 -385.310888) (xy 89.61374 -385.31038) (xy 89.61412 -385.286384)
			(xy 89.621631 -385.238983) (xy 89.636465 -385.193341) (xy 89.658257 -385.150582) (xy 89.68647 -385.111758)
			(xy 89.72041 -385.077826) (xy 89.75924 -385.049622) (xy 89.802004 -385.027839) (xy 89.847649 -385.013015)
			(xy 89.895052 -385.005515) (xy 89.919048 -385.005072) (xy 89.942983 -385.005541) (xy 89.990267 -385.012998)
			(xy 90.03581 -385.027739) (xy 90.078497 -385.049402) (xy 90.117282 -385.077458) (xy 90.151218 -385.111219)
			(xy 90.179473 -385.149859) (xy 90.190828 -385.170934) (xy 90.191336 -385.17195) (xy 90.271642 -385.310888)
			(xy 90.813636 -385.310888) (xy 90.813636 -385.31038) (xy 90.81402 -385.286384) (xy 90.821531 -385.238984)
			(xy 90.836365 -385.193342) (xy 90.858157 -385.150583) (xy 90.886369 -385.111759) (xy 90.920308 -385.077828)
			(xy 90.959138 -385.049623) (xy 91.001901 -385.02784) (xy 91.047546 -385.013016) (xy 91.094948 -385.005515)
			(xy 91.118944 -385.005072) (xy 91.142878 -385.005544) (xy 91.190163 -385.013001) (xy 91.235706 -385.027741)
			(xy 91.278392 -385.049404) (xy 91.317178 -385.077459) (xy 91.351114 -385.111219) (xy 91.379369 -385.14986)
			(xy 91.390724 -385.170934) (xy 91.391232 -385.17195) (xy 91.471538 -385.310888) (xy 92.013532 -385.310888)
			(xy 92.013532 -385.31038) (xy 92.013943 -385.286399) (xy 92.021446 -385.239027) (xy 92.036263 -385.193411)
			(xy 92.05803 -385.150673) (xy 92.086212 -385.111864) (xy 92.120116 -385.077939) (xy 92.158907 -385.049732)
			(xy 92.201632 -385.027937) (xy 92.247238 -385.013091) (xy 92.294605 -385.005559) (xy 92.318586 -385.005072)
			(xy 92.319094 -385.005072) (xy 92.34303 -385.005503) (xy 92.390316 -385.012968) (xy 92.43586 -385.027715)
			(xy 92.478547 -385.049385) (xy 92.517332 -385.077446) (xy 92.551266 -385.111212) (xy 92.57952 -385.149857)
			(xy 92.590874 -385.170934) (xy 92.591382 -385.17195) (xy 92.671688 -385.310888) (xy 93.213428 -385.310888)
			(xy 93.213428 -385.31038) (xy 93.213843 -385.286399) (xy 93.221346 -385.239028) (xy 93.236162 -385.193412)
			(xy 93.257929 -385.150674) (xy 93.286111 -385.111865) (xy 93.320014 -385.07794) (xy 93.358805 -385.049733)
			(xy 93.401529 -385.027938) (xy 93.447135 -385.013092) (xy 93.494501 -385.005559) (xy 93.518482 -385.005072)
			(xy 93.51899 -385.005072) (xy 93.542926 -385.005506) (xy 93.590212 -385.01297) (xy 93.635756 -385.027717)
			(xy 93.678442 -385.049386) (xy 93.717227 -385.077447) (xy 93.751162 -385.111213) (xy 93.779416 -385.149857)
			(xy 93.79077 -385.170934) (xy 93.791278 -385.17195) (xy 93.871584 -385.310888) (xy 94.413324 -385.310888)
			(xy 94.413324 -385.31038) (xy 94.413743 -385.286399) (xy 94.421245 -385.239028) (xy 94.436062 -385.193413)
			(xy 94.457829 -385.150675) (xy 94.48601 -385.111866) (xy 94.519913 -385.077941) (xy 94.558703 -385.049734)
			(xy 94.601426 -385.02794) (xy 94.647032 -385.013093) (xy 94.694398 -385.005559) (xy 94.718378 -385.005072)
			(xy 94.718886 -385.005072) (xy 94.742822 -385.00551) (xy 94.790108 -385.012973) (xy 94.835651 -385.027719)
			(xy 94.878338 -385.049388) (xy 94.917123 -385.077448) (xy 94.951058 -385.111213) (xy 94.979312 -385.149858)
			(xy 94.990666 -385.170934) (xy 94.991174 -385.17195) (xy 95.07148 -385.310888) (xy 95.613728 -385.310888)
			(xy 95.613728 -385.31038) (xy 95.61412 -385.286385) (xy 95.621631 -385.238985) (xy 95.636464 -385.193344)
			(xy 95.658255 -385.150585) (xy 95.686467 -385.111762) (xy 95.720405 -385.07783) (xy 95.759233 -385.049626)
			(xy 95.801996 -385.027843) (xy 95.847639 -385.013018) (xy 95.89504 -385.005515) (xy 95.919036 -385.005072)
			(xy 95.94297 -385.00555) (xy 95.990254 -385.013006) (xy 96.035797 -385.027745) (xy 96.078484 -385.049407)
			(xy 96.117269 -385.077461) (xy 96.151205 -385.11122) (xy 96.179461 -385.14986) (xy 96.190816 -385.170934)
			(xy 96.191324 -385.17195) (xy 96.27163 -385.310888) (xy 96.813624 -385.310888) (xy 96.813624 -385.31038)
			(xy 96.81402 -385.286385) (xy 96.821531 -385.238985) (xy 96.836364 -385.193345) (xy 96.858154 -385.150586)
			(xy 96.886366 -385.111764) (xy 96.920303 -385.077832) (xy 96.959131 -385.049627) (xy 97.001893 -385.027844)
			(xy 97.047536 -385.013018) (xy 97.094937 -385.005516) (xy 97.118932 -385.005072) (xy 97.142866 -385.005554)
			(xy 97.19015 -385.013009) (xy 97.235693 -385.027747) (xy 97.278379 -385.049408) (xy 97.317165 -385.077462)
			(xy 97.351101 -385.111221) (xy 97.379357 -385.14986) (xy 97.390712 -385.170934) (xy 97.39122 -385.17195)
			(xy 97.471526 -385.310888) (xy 98.01352 -385.310888) (xy 98.01352 -385.31038) (xy 98.013943 -385.2864)
			(xy 98.021445 -385.239029) (xy 98.036262 -385.193414) (xy 98.058028 -385.150676) (xy 98.086209 -385.111868)
			(xy 98.120111 -385.077943) (xy 98.1589 -385.049736) (xy 98.201623 -385.027941) (xy 98.247228 -385.013093)
			(xy 98.294594 -385.005559) (xy 98.318574 -385.005072) (xy 98.319082 -385.005072) (xy 98.343018 -385.005513)
			(xy 98.390303 -385.012976) (xy 98.435847 -385.027721) (xy 98.478534 -385.049389) (xy 98.517319 -385.077449)
			(xy 98.551254 -385.111214) (xy 98.579508 -385.149858) (xy 98.590862 -385.170934) (xy 98.59137 -385.17195)
			(xy 98.671676 -385.310888) (xy 114.586004 -385.310888) (xy 114.586004 -385.31038) (xy 114.586444 -385.286388)
			(xy 114.593954 -385.238994) (xy 114.608785 -385.193359) (xy 114.630572 -385.150605) (xy 114.658779 -385.111786)
			(xy 114.692711 -385.077858) (xy 114.731533 -385.049655) (xy 114.774288 -385.027872) (xy 114.819925 -385.013046)
			(xy 114.86732 -385.005542) (xy 114.891312 -385.005072) (xy 114.915246 -385.00557) (xy 114.962529 -385.013022)
			(xy 115.008071 -385.027757) (xy 115.050758 -385.049416) (xy 115.089544 -385.077467) (xy 115.12348 -385.111224)
			(xy 115.151736 -385.149861) (xy 115.163092 -385.170934) (xy 115.1636 -385.17195) (xy 115.243906 -385.310888)
			(xy 115.7859 -385.310888) (xy 115.7859 -385.31038) (xy 115.786344 -385.286388) (xy 115.793854 -385.238995)
			(xy 115.808684 -385.19336) (xy 115.830471 -385.150606) (xy 115.858677 -385.111788) (xy 115.892609 -385.077859)
			(xy 115.93143 -385.049656) (xy 115.974186 -385.027873) (xy 116.019822 -385.013047) (xy 116.067216 -385.005542)
			(xy 116.091208 -385.005072) (xy 116.115141 -385.005573) (xy 116.162424 -385.013024) (xy 116.207967 -385.027759)
			(xy 116.250653 -385.049417) (xy 116.289439 -385.077468) (xy 116.323376 -385.111224) (xy 116.351632 -385.149861)
			(xy 116.362988 -385.170934) (xy 116.363496 -385.17195) (xy 116.443802 -385.310888) (xy 116.985796 -385.310888)
			(xy 116.985796 -385.31038) (xy 116.986244 -385.286388) (xy 116.993753 -385.238995) (xy 117.008584 -385.193361)
			(xy 117.03037 -385.150608) (xy 117.058576 -385.111789) (xy 117.092507 -385.077861) (xy 117.131328 -385.049658)
			(xy 117.174083 -385.027875) (xy 117.219719 -385.013048) (xy 117.267112 -385.005542) (xy 117.291104 -385.005072)
			(xy 117.315037 -385.005576) (xy 117.36232 -385.013027) (xy 117.407862 -385.027762) (xy 117.450549 -385.049419)
			(xy 117.489335 -385.077469) (xy 117.523272 -385.111225) (xy 117.551528 -385.149861) (xy 117.562884 -385.170934)
			(xy 117.563392 -385.17195) (xy 117.643698 -385.310888) (xy 118.185692 -385.310888) (xy 118.185692 -385.31038)
			(xy 118.186143 -385.286401) (xy 118.193644 -385.239033) (xy 118.208459 -385.19342) (xy 118.230223 -385.150685)
			(xy 118.258401 -385.111877) (xy 118.292299 -385.077953) (xy 118.331085 -385.049745) (xy 118.373804 -385.027949)
			(xy 118.419405 -385.013099) (xy 118.466767 -385.005562) (xy 118.490746 -385.005072) (xy 118.491254 -385.005072)
			(xy 118.515189 -385.005536) (xy 118.562474 -385.012994) (xy 118.608017 -385.027736) (xy 118.650703 -385.0494)
			(xy 118.689489 -385.077456) (xy 118.723424 -385.111218) (xy 118.751679 -385.149859) (xy 118.763034 -385.170934)
			(xy 118.763542 -385.17195) (xy 118.843848 -385.310888) (xy 119.385588 -385.310888) (xy 119.385588 -385.31038)
			(xy 119.386043 -385.286401) (xy 119.393544 -385.239034) (xy 119.408359 -385.193421) (xy 119.430122 -385.150686)
			(xy 119.458299 -385.111879) (xy 119.492198 -385.077954) (xy 119.530983 -385.049747) (xy 119.573701 -385.02795)
			(xy 119.619302 -385.0131) (xy 119.666663 -385.005562) (xy 119.690642 -385.005072) (xy 119.69115 -385.005072)
			(xy 119.715085 -385.005539) (xy 119.762369 -385.012997) (xy 119.807912 -385.027738) (xy 119.850599 -385.049401)
			(xy 119.889384 -385.077457) (xy 119.92332 -385.111218) (xy 119.951575 -385.149859) (xy 119.96293 -385.170934)
			(xy 119.963438 -385.17195) (xy 120.043744 -385.310888) (xy 120.585992 -385.310888) (xy 120.585992 -385.31038)
			(xy 120.586444 -385.286388) (xy 120.593953 -385.238996) (xy 120.608783 -385.193362) (xy 120.630569 -385.150609)
			(xy 120.658775 -385.11179) (xy 120.692706 -385.077862) (xy 120.731526 -385.049659) (xy 120.77428 -385.027876)
			(xy 120.819915 -385.013049) (xy 120.867308 -385.005543) (xy 120.8913 -385.005072) (xy 120.915233 -385.00558)
			(xy 120.962516 -385.01303) (xy 121.008058 -385.027764) (xy 121.050744 -385.04942) (xy 121.089531 -385.07747)
			(xy 121.123468 -385.111226) (xy 121.151724 -385.149862) (xy 121.16308 -385.170934) (xy 121.163588 -385.17195)
			(xy 121.243894 -385.310888) (xy 121.785888 -385.310888) (xy 121.785888 -385.31038) (xy 121.786344 -385.286388)
			(xy 121.793853 -385.238996) (xy 121.808683 -385.193362) (xy 121.830469 -385.15061) (xy 121.858674 -385.111792)
			(xy 121.892604 -385.077863) (xy 121.931424 -385.04966) (xy 121.974177 -385.027877) (xy 122.019812 -385.013049)
			(xy 122.067204 -385.005543) (xy 122.091196 -385.005072) (xy 122.115132 -385.005502) (xy 122.162418 -385.012966)
			(xy 122.207962 -385.027714) (xy 122.250649 -385.049384) (xy 122.289434 -385.077445) (xy 122.323368 -385.111212)
			(xy 122.351622 -385.149857) (xy 122.362976 -385.170934) (xy 122.363484 -385.17195) (xy 122.44379 -385.310888)
			(xy 122.985784 -385.310888) (xy 122.985784 -385.31038) (xy 122.986244 -385.286389) (xy 122.993753 -385.238997)
			(xy 123.008583 -385.193363) (xy 123.030368 -385.150611) (xy 123.058573 -385.111793) (xy 123.092502 -385.077865)
			(xy 123.131321 -385.049662) (xy 123.174074 -385.027878) (xy 123.219709 -385.01305) (xy 123.267101 -385.005543)
			(xy 123.291092 -385.005072) (xy 123.315028 -385.005505) (xy 123.362314 -385.012969) (xy 123.407858 -385.027716)
			(xy 123.450544 -385.049385) (xy 123.48933 -385.077446) (xy 123.523264 -385.111212) (xy 123.551518 -385.149857)
			(xy 123.562872 -385.170934) (xy 123.56338 -385.17195) (xy 123.643686 -385.310888) (xy 124.18568 -385.310888)
			(xy 124.18568 -385.31038) (xy 124.186143 -385.286402) (xy 124.193644 -385.239035) (xy 124.208458 -385.193423)
			(xy 124.230221 -385.150688) (xy 124.258397 -385.111882) (xy 124.292294 -385.077957) (xy 124.331078 -385.049749)
			(xy 124.373795 -385.027952) (xy 124.419395 -385.013101) (xy 124.466756 -385.005562) (xy 124.490734 -385.005072)
			(xy 124.491242 -385.005072) (xy 124.515176 -385.005545) (xy 124.562461 -385.013002) (xy 124.608003 -385.027742)
			(xy 124.65069 -385.049404) (xy 124.689476 -385.077459) (xy 124.723412 -385.11122) (xy 124.751667 -385.14986)
			(xy 124.763022 -385.170934) (xy 124.76353 -385.17195) (xy 124.843836 -385.310888) (xy 125.385576 -385.310888)
			(xy 125.385576 -385.31038) (xy 125.386043 -385.286402) (xy 125.393544 -385.239035) (xy 125.408357 -385.193424)
			(xy 125.43012 -385.150689) (xy 125.458296 -385.111883) (xy 125.492192 -385.077959) (xy 125.530976 -385.049751)
			(xy 125.573693 -385.027953) (xy 125.619292 -385.013102) (xy 125.666652 -385.005563) (xy 125.69063 -385.005072)
			(xy 125.691138 -385.005072) (xy 125.715072 -385.005549) (xy 125.762356 -385.013005) (xy 125.807899 -385.027744)
			(xy 125.850586 -385.049406) (xy 125.889372 -385.07746) (xy 125.923307 -385.11122) (xy 125.951563 -385.14986)
			(xy 125.962918 -385.170934) (xy 125.963426 -385.17195) (xy 126.043732 -385.310888) (xy 126.58598 -385.310888)
			(xy 126.58598 -385.31038) (xy 126.586444 -385.286389) (xy 126.593953 -385.238998) (xy 126.608782 -385.193364)
			(xy 126.630567 -385.150612) (xy 126.658771 -385.111795) (xy 126.692701 -385.077866) (xy 126.731519 -385.049663)
			(xy 126.774272 -385.027879) (xy 126.819905 -385.013051) (xy 126.867297 -385.005543) (xy 126.891288 -385.005072)
			(xy 126.915224 -385.005508) (xy 126.96251 -385.012972) (xy 127.008053 -385.027718) (xy 127.05074 -385.049387)
			(xy 127.089525 -385.077447) (xy 127.12346 -385.111213) (xy 127.151714 -385.149858) (xy 127.163068 -385.170934)
			(xy 127.163576 -385.17195) (xy 127.243882 -385.310888) (xy 127.785876 -385.310888) (xy 127.785876 -385.31038)
			(xy 127.786344 -385.286389) (xy 127.793853 -385.238998) (xy 127.808682 -385.193365) (xy 127.830467 -385.150614)
			(xy 127.85867 -385.111796) (xy 127.892599 -385.077868) (xy 127.931417 -385.049664) (xy 127.974169 -385.02788)
			(xy 128.019802 -385.013052) (xy 128.067193 -385.005544) (xy 128.091184 -385.005072) (xy 128.11512 -385.005511)
			(xy 128.162406 -385.012974) (xy 128.207949 -385.02772) (xy 128.250636 -385.049388) (xy 128.289421 -385.077448)
			(xy 128.323356 -385.111214) (xy 128.35161 -385.149858) (xy 128.362964 -385.170934) (xy 128.363472 -385.17195)
			(xy 128.443778 -385.310888) (xy 128.985772 -385.310888) (xy 128.985772 -385.31038) (xy 128.986244 -385.286389)
			(xy 128.993753 -385.238999) (xy 129.008581 -385.193366) (xy 129.030366 -385.150615) (xy 129.058569 -385.111797)
			(xy 129.092497 -385.077869) (xy 129.131315 -385.049666) (xy 129.174066 -385.027881) (xy 129.219699 -385.013053)
			(xy 129.267089 -385.005544) (xy 129.29108 -385.005072) (xy 129.315016 -385.005515) (xy 129.362301 -385.012977)
			(xy 129.407845 -385.027722) (xy 129.450531 -385.04939) (xy 129.489317 -385.077449) (xy 129.523252 -385.111214)
			(xy 129.551506 -385.149858) (xy 129.56286 -385.170934) (xy 129.563368 -385.17195) (xy 129.643674 -385.310888)
			(xy 130.185668 -385.310888) (xy 130.185668 -385.31038) (xy 130.186143 -385.286402) (xy 130.193643 -385.239036)
			(xy 130.208457 -385.193426) (xy 130.230218 -385.150692) (xy 130.258394 -385.111886) (xy 130.292289 -385.077961)
			(xy 130.331072 -385.049753) (xy 130.373787 -385.027956) (xy 130.419385 -385.013104) (xy 130.466745 -385.005563)
			(xy 130.490722 -385.005072) (xy 130.49123 -385.005072) (xy 130.515164 -385.005555) (xy 130.562448 -385.01301)
			(xy 130.60799 -385.027748) (xy 130.650677 -385.049409) (xy 130.689463 -385.077462) (xy 130.723399 -385.111221)
			(xy 130.751655 -385.14986) (xy 130.76301 -385.170934) (xy 130.763518 -385.17195) (xy 130.843824 -385.310888)
			(xy 131.385564 -385.310888) (xy 131.385564 -385.31038) (xy 131.386043 -385.286402) (xy 131.393543 -385.239037)
			(xy 131.408356 -385.193427) (xy 131.430118 -385.150693) (xy 131.458292 -385.111887) (xy 131.492187 -385.077963)
			(xy 131.530969 -385.049755) (xy 131.573684 -385.027957) (xy 131.619282 -385.013105) (xy 131.666641 -385.005564)
			(xy 131.690618 -385.005072) (xy 131.691126 -385.005072) (xy 131.71506 -385.005558) (xy 131.762344 -385.013013)
			(xy 131.807886 -385.02775) (xy 131.850573 -385.04941) (xy 131.889359 -385.077463) (xy 131.923295 -385.111222)
			(xy 131.951551 -385.14986) (xy 131.962906 -385.170934) (xy 131.963414 -385.17195) (xy 132.04372 -385.310888)
			(xy 132.585968 -385.310888) (xy 132.585968 -385.31038) (xy 132.586444 -385.286389) (xy 132.593952 -385.238999)
			(xy 132.608781 -385.193367) (xy 132.630565 -385.150616) (xy 132.658768 -385.111799) (xy 132.692696 -385.077871)
			(xy 132.731513 -385.049667) (xy 132.774263 -385.027883) (xy 132.819895 -385.013053) (xy 132.867285 -385.005544)
			(xy 132.891276 -385.005072) (xy 132.915211 -385.005518) (xy 132.962497 -385.01298) (xy 133.00804 -385.027724)
			(xy 133.050727 -385.049391) (xy 133.089512 -385.07745) (xy 133.123447 -385.111215) (xy 133.151701 -385.149858)
			(xy 133.163056 -385.170934) (xy 133.163564 -385.17195) (xy 133.24387 -385.310888) (xy 147.113752 -385.310888)
			(xy 147.113752 -385.31038) (xy 147.114244 -385.28639) (xy 147.121752 -385.239002) (xy 147.13658 -385.193371)
			(xy 147.158362 -385.150621) (xy 147.186563 -385.111804) (xy 147.220489 -385.077876) (xy 147.259304 -385.049673)
			(xy 147.302052 -385.027887) (xy 147.347682 -385.013057) (xy 147.39507 -385.005546) (xy 147.41906 -385.005072)
			(xy 147.442995 -385.005531) (xy 147.49028 -385.01299) (xy 147.535823 -385.027733) (xy 147.57851 -385.049398)
			(xy 147.617295 -385.077455) (xy 147.651231 -385.111217) (xy 147.679485 -385.149859) (xy 147.69084 -385.170934)
			(xy 147.691348 -385.17195) (xy 147.771654 -385.310888) (xy 148.313648 -385.310888) (xy 148.313648 -385.31038)
			(xy 148.314144 -385.28639) (xy 148.321652 -385.239002) (xy 148.336479 -385.193372) (xy 148.358261 -385.150622)
			(xy 148.386462 -385.111805) (xy 148.420387 -385.077878) (xy 148.459201 -385.049674) (xy 148.501949 -385.027888)
			(xy 148.547579 -385.013057) (xy 148.594966 -385.005546) (xy 148.618956 -385.005072) (xy 148.642891 -385.005534)
			(xy 148.690176 -385.012993) (xy 148.735719 -385.027735) (xy 148.778405 -385.049399) (xy 148.817191 -385.077456)
			(xy 148.851126 -385.111218) (xy 148.879381 -385.149859) (xy 148.890736 -385.170934) (xy 148.891244 -385.17195)
			(xy 148.97155 -385.310888) (xy 149.513544 -385.310888) (xy 149.513544 -385.31038) (xy 149.514044 -385.286391)
			(xy 149.521552 -385.239003) (xy 149.536379 -385.193373) (xy 149.558161 -385.150623) (xy 149.586361 -385.111807)
			(xy 149.620286 -385.077879) (xy 149.659099 -385.049675) (xy 149.701847 -385.02789) (xy 149.747476 -385.013058)
			(xy 149.794863 -385.005546) (xy 149.818852 -385.005072) (xy 149.842787 -385.005537) (xy 149.890071 -385.012995)
			(xy 149.935614 -385.027737) (xy 149.978301 -385.049401) (xy 150.017087 -385.077457) (xy 150.051022 -385.111218)
			(xy 150.079277 -385.149859) (xy 150.090632 -385.170934) (xy 150.09114 -385.17195) (xy 150.171446 -385.310888)
			(xy 150.71344 -385.310888) (xy 150.71344 -385.31038) (xy 150.713843 -385.286399) (xy 150.721346 -385.239026)
			(xy 150.736164 -385.193409) (xy 150.757932 -385.15067) (xy 150.786115 -385.111861) (xy 150.820019 -385.077936)
			(xy 150.858812 -385.049729) (xy 150.901537 -385.027935) (xy 150.947145 -385.013089) (xy 150.994513 -385.005558)
			(xy 151.018494 -385.005072) (xy 151.019002 -385.005072) (xy 151.042935 -385.005578) (xy 151.090218 -385.013028)
			(xy 151.13576 -385.027763) (xy 151.178447 -385.04942) (xy 151.217233 -385.077469) (xy 151.25117 -385.111225)
			(xy 151.279426 -385.149861) (xy 151.290782 -385.170934) (xy 151.29129 -385.17195) (xy 151.371596 -385.310888)
			(xy 151.913336 -385.310888) (xy 151.913336 -385.31038) (xy 151.913743 -385.286399) (xy 151.921246 -385.239027)
			(xy 151.936063 -385.19341) (xy 151.957831 -385.150672) (xy 151.986013 -385.111862) (xy 152.019918 -385.077937)
			(xy 152.058709 -385.04973) (xy 152.101434 -385.027936) (xy 152.147041 -385.01309) (xy 152.194409 -385.005558)
			(xy 152.21839 -385.005072) (xy 152.218898 -385.005072) (xy 152.242834 -385.0055) (xy 152.290121 -385.012965)
			(xy 152.335664 -385.027713) (xy 152.378351 -385.049383) (xy 152.417136 -385.077445) (xy 152.45107 -385.111212)
			(xy 152.479324 -385.149857) (xy 152.490678 -385.170934) (xy 152.491186 -385.17195) (xy 152.571492 -385.310888)
			(xy 153.11374 -385.310888) (xy 153.11374 -385.31038) (xy 153.11412 -385.286384) (xy 153.121631 -385.238983)
			(xy 153.136465 -385.193341) (xy 153.158257 -385.150582) (xy 153.18647 -385.111758) (xy 153.22041 -385.077826)
			(xy 153.25924 -385.049622) (xy 153.302004 -385.027839) (xy 153.347649 -385.013015) (xy 153.395052 -385.005515)
			(xy 153.419048 -385.005072) (xy 153.442983 -385.005541) (xy 153.490267 -385.012998) (xy 153.53581 -385.027739)
			(xy 153.578497 -385.049402) (xy 153.617282 -385.077458) (xy 153.651218 -385.111219) (xy 153.679473 -385.149859)
			(xy 153.690828 -385.170934) (xy 153.691336 -385.17195) (xy 153.771642 -385.310888) (xy 154.313636 -385.310888)
			(xy 154.313636 -385.31038) (xy 154.31402 -385.286384) (xy 154.321531 -385.238984) (xy 154.336365 -385.193342)
			(xy 154.358157 -385.150583) (xy 154.386369 -385.111759) (xy 154.420308 -385.077828) (xy 154.459138 -385.049623)
			(xy 154.501901 -385.02784) (xy 154.547546 -385.013016) (xy 154.594948 -385.005515) (xy 154.618944 -385.005072)
			(xy 154.642878 -385.005544) (xy 154.690163 -385.013001) (xy 154.735706 -385.027741) (xy 154.778392 -385.049404)
			(xy 154.817178 -385.077459) (xy 154.851114 -385.111219) (xy 154.879369 -385.14986) (xy 154.890724 -385.170934)
			(xy 154.891232 -385.17195) (xy 154.971538 -385.310888) (xy 155.513532 -385.310888) (xy 155.513532 -385.31038)
			(xy 155.51392 -385.286384) (xy 155.521431 -385.238984) (xy 155.536265 -385.193343) (xy 155.558056 -385.150584)
			(xy 155.586268 -385.111761) (xy 155.620206 -385.077829) (xy 155.659035 -385.049624) (xy 155.701798 -385.027842)
			(xy 155.747443 -385.013017) (xy 155.794844 -385.005515) (xy 155.81884 -385.005072) (xy 155.842774 -385.005547)
			(xy 155.890059 -385.013003) (xy 155.935601 -385.027743) (xy 155.978288 -385.049405) (xy 156.017074 -385.07746)
			(xy 156.05101 -385.11122) (xy 156.079265 -385.14986) (xy 156.09062 -385.170934) (xy 156.091128 -385.17195)
			(xy 156.171434 -385.310888) (xy 156.713428 -385.310888) (xy 156.713428 -385.31038) (xy 156.713843 -385.286399)
			(xy 156.721346 -385.239028) (xy 156.736162 -385.193412) (xy 156.757929 -385.150674) (xy 156.786111 -385.111865)
			(xy 156.820014 -385.07794) (xy 156.858805 -385.049733) (xy 156.901529 -385.027938) (xy 156.947135 -385.013092)
			(xy 156.994501 -385.005559) (xy 157.018482 -385.005072) (xy 157.01899 -385.005072) (xy 157.042926 -385.005506)
			(xy 157.090212 -385.01297) (xy 157.135756 -385.027717) (xy 157.178442 -385.049386) (xy 157.217227 -385.077447)
			(xy 157.251162 -385.111213) (xy 157.279416 -385.149857) (xy 157.29077 -385.170934) (xy 157.291278 -385.17195)
			(xy 157.371584 -385.310888) (xy 157.913324 -385.310888) (xy 157.913324 -385.31038) (xy 157.913743 -385.286399)
			(xy 157.921245 -385.239028) (xy 157.936062 -385.193413) (xy 157.957829 -385.150675) (xy 157.98601 -385.111866)
			(xy 158.019913 -385.077941) (xy 158.058703 -385.049734) (xy 158.101426 -385.02794) (xy 158.147032 -385.013093)
			(xy 158.194398 -385.005559) (xy 158.218378 -385.005072) (xy 158.218886 -385.005072) (xy 158.242822 -385.00551)
			(xy 158.290108 -385.012973) (xy 158.335651 -385.027719) (xy 158.378338 -385.049388) (xy 158.417123 -385.077448)
			(xy 158.451058 -385.111213) (xy 158.479312 -385.149858) (xy 158.490666 -385.170934) (xy 158.491174 -385.17195)
			(xy 158.57148 -385.310888) (xy 159.113728 -385.310888) (xy 159.113728 -385.31038) (xy 159.11412 -385.286385)
			(xy 159.121631 -385.238985) (xy 159.136464 -385.193344) (xy 159.158255 -385.150585) (xy 159.186467 -385.111762)
			(xy 159.220405 -385.07783) (xy 159.259233 -385.049626) (xy 159.301996 -385.027843) (xy 159.347639 -385.013018)
			(xy 159.39504 -385.005515) (xy 159.419036 -385.005072) (xy 159.44297 -385.00555) (xy 159.490254 -385.013006)
			(xy 159.535797 -385.027745) (xy 159.578484 -385.049407) (xy 159.617269 -385.077461) (xy 159.651205 -385.11122)
			(xy 159.679461 -385.14986) (xy 159.690816 -385.170934) (xy 159.691324 -385.17195) (xy 159.77163 -385.310888)
			(xy 160.313624 -385.310888) (xy 160.313624 -385.31038) (xy 160.31402 -385.286385) (xy 160.321531 -385.238985)
			(xy 160.336364 -385.193345) (xy 160.358154 -385.150586) (xy 160.386366 -385.111764) (xy 160.420303 -385.077832)
			(xy 160.459131 -385.049627) (xy 160.501893 -385.027844) (xy 160.547536 -385.013018) (xy 160.594937 -385.005516)
			(xy 160.618932 -385.005072) (xy 160.642866 -385.005554) (xy 160.69015 -385.013009) (xy 160.735693 -385.027747)
			(xy 160.778379 -385.049408) (xy 160.817165 -385.077462) (xy 160.851101 -385.111221) (xy 160.879357 -385.14986)
			(xy 160.890712 -385.170934) (xy 160.89122 -385.17195) (xy 160.971526 -385.310888) (xy 161.51352 -385.310888)
			(xy 161.51352 -385.31038) (xy 161.51392 -385.286385) (xy 161.52143 -385.238986) (xy 161.536263 -385.193346)
			(xy 161.558054 -385.150588) (xy 161.586265 -385.111765) (xy 161.620201 -385.077833) (xy 161.659029 -385.049629)
			(xy 161.70179 -385.027845) (xy 161.747433 -385.013019) (xy 161.794833 -385.005516) (xy 161.818828 -385.005072)
			(xy 161.842762 -385.005557) (xy 161.890046 -385.013011) (xy 161.935588 -385.027749) (xy 161.978275 -385.04941)
			(xy 162.017061 -385.077463) (xy 162.050997 -385.111222) (xy 162.079253 -385.14986) (xy 162.090608 -385.170934)
			(xy 162.091116 -385.17195) (xy 162.171422 -385.310888) (xy 162.713416 -385.310888) (xy 162.713416 -385.31038)
			(xy 162.713843 -385.2864) (xy 162.721345 -385.239029) (xy 162.736161 -385.193415) (xy 162.757927 -385.150678)
			(xy 162.786108 -385.111869) (xy 162.820009 -385.077944) (xy 162.858798 -385.049737) (xy 162.90152 -385.027942)
			(xy 162.947125 -385.013094) (xy 162.99449 -385.00556) (xy 163.01847 -385.005072) (xy 163.018978 -385.005072)
			(xy 163.042913 -385.005516) (xy 163.090199 -385.012978) (xy 163.135743 -385.027723) (xy 163.178429 -385.049391)
			(xy 163.217215 -385.07745) (xy 163.251149 -385.111214) (xy 163.279404 -385.149858) (xy 163.290758 -385.170934)
			(xy 163.291266 -385.17195) (xy 163.371572 -385.310888) (xy 163.913312 -385.310888) (xy 163.913312 -385.31038)
			(xy 163.913743 -385.2864) (xy 163.921245 -385.23903) (xy 163.936061 -385.193416) (xy 163.957827 -385.150679)
			(xy 163.986006 -385.111871) (xy 164.019908 -385.077946) (xy 164.058696 -385.049739) (xy 164.101418 -385.027943)
			(xy 164.147022 -385.013095) (xy 164.194386 -385.00556) (xy 164.218366 -385.005072) (xy 164.218874 -385.005072)
			(xy 164.242809 -385.005519) (xy 164.290095 -385.012981) (xy 164.335638 -385.027726) (xy 164.378325 -385.049392)
			(xy 164.41711 -385.077451) (xy 164.451045 -385.111215) (xy 164.479299 -385.149858) (xy 164.490654 -385.170934)
			(xy 164.491162 -385.17195) (xy 164.571468 -385.310888) (xy 165.113716 -385.310888) (xy 165.113716 -385.31038)
			(xy 165.11412 -385.286385) (xy 165.12163 -385.238987) (xy 165.136463 -385.193347) (xy 165.158253 -385.150589)
			(xy 165.186463 -385.111766) (xy 165.2204 -385.077835) (xy 165.259226 -385.04963) (xy 165.301987 -385.027846)
			(xy 165.347629 -385.01302) (xy 165.395029 -385.005516) (xy 165.419024 -385.005072) (xy 165.442958 -385.00556)
			(xy 165.490242 -385.013014) (xy 165.535784 -385.027751) (xy 165.578471 -385.049411) (xy 165.617257 -385.077464)
			(xy 165.651193 -385.111222) (xy 165.679449 -385.14986) (xy 165.690804 -385.170934) (xy 165.691312 -385.17195)
			(xy 166.083742 -385.850892) (xy 166.096567 -385.874224) (xy 166.114787 -385.924247) (xy 166.124047 -385.976673)
			(xy 166.124636 -386.003292) (xy 166.124131 -386.027269) (xy 166.116635 -386.074633) (xy 166.101826 -386.120243)
			(xy 166.080068 -386.162977) (xy 166.051896 -386.201783) (xy 166.018004 -386.235708) (xy 165.979224 -386.263916)
			(xy 165.936511 -386.285715) (xy 165.890916 -386.300567) (xy 165.843558 -386.308108) (xy 165.819582 -386.3086)
			(xy 165.819074 -386.3086) (xy 165.795499 -386.308227) (xy 165.74891 -386.300982) (xy 165.703991 -386.286652)
			(xy 165.661813 -386.26558) (xy 165.62338 -386.238267) (xy 165.589609 -386.205365) (xy 165.561304 -386.167657)
			(xy 165.549834 -386.147056) (xy 165.549326 -386.146294) (xy 165.151562 -385.457954) (xy 165.139704 -385.435268)
			(xy 165.122846 -385.38694) (xy 165.114266 -385.33648) (xy 165.113716 -385.310888) (xy 164.571468 -385.310888)
			(xy 164.883592 -385.850892) (xy 164.896324 -385.87421) (xy 164.914419 -385.924158) (xy 164.923635 -385.976477)
			(xy 164.924232 -386.003038) (xy 164.924232 -386.003292) (xy 164.92373 -386.027282) (xy 164.916226 -386.074671)
			(xy 164.901401 -386.120303) (xy 164.879621 -386.163054) (xy 164.851421 -386.201871) (xy 164.817496 -386.2358)
			(xy 164.778681 -386.264004) (xy 164.735932 -386.285789) (xy 164.690302 -386.300618) (xy 164.642914 -386.308128)
			(xy 164.618924 -386.3086) (xy 164.595351 -386.308187) (xy 164.548763 -386.300949) (xy 164.503845 -386.286627)
			(xy 164.461667 -386.265561) (xy 164.423233 -386.238255) (xy 164.389461 -386.205358) (xy 164.361155 -386.167655)
			(xy 164.349684 -386.147056) (xy 164.349176 -386.146294) (xy 163.951412 -385.457954) (xy 163.939479 -385.435295)
			(xy 163.922547 -385.386965) (xy 163.913895 -385.336491) (xy 163.913312 -385.310888) (xy 163.371572 -385.310888)
			(xy 163.683696 -385.850892) (xy 163.696428 -385.87421) (xy 163.714523 -385.924158) (xy 163.723739 -385.976477)
			(xy 163.724336 -386.003038) (xy 163.724336 -386.003292) (xy 163.72383 -386.027282) (xy 163.716326 -386.07467)
			(xy 163.701501 -386.120302) (xy 163.679721 -386.163053) (xy 163.651522 -386.20187) (xy 163.617597 -386.235798)
			(xy 163.578783 -386.264002) (xy 163.536035 -386.285788) (xy 163.490405 -386.300618) (xy 163.443018 -386.308127)
			(xy 163.419028 -386.3086) (xy 163.395455 -386.308184) (xy 163.348868 -386.300946) (xy 163.30395 -386.286625)
			(xy 163.261771 -386.26556) (xy 163.223338 -386.238254) (xy 163.189565 -386.205357) (xy 163.161259 -386.167654)
			(xy 163.149788 -386.147056) (xy 163.14928 -386.146294) (xy 162.751516 -385.457954) (xy 162.739583 -385.435294)
			(xy 162.722652 -385.386965) (xy 162.713999 -385.336491) (xy 162.713416 -385.310888) (xy 162.171422 -385.310888)
			(xy 162.483546 -385.850892) (xy 162.496371 -385.874224) (xy 162.514591 -385.924247) (xy 162.523851 -385.976673)
			(xy 162.52444 -386.003292) (xy 162.523931 -386.027269) (xy 162.516435 -386.074633) (xy 162.501626 -386.120242)
			(xy 162.479869 -386.162976) (xy 162.451698 -386.201782) (xy 162.417806 -386.235706) (xy 162.379027 -386.263915)
			(xy 162.336314 -386.285714) (xy 162.290719 -386.300566) (xy 162.243362 -386.308108) (xy 162.219386 -386.3086)
			(xy 162.218878 -386.3086) (xy 162.195303 -386.308224) (xy 162.148714 -386.300979) (xy 162.103795 -386.28665)
			(xy 162.061617 -386.265579) (xy 162.023184 -386.238266) (xy 161.989413 -386.205364) (xy 161.961108 -386.167657)
			(xy 161.949638 -386.147056) (xy 161.94913 -386.146294) (xy 161.551366 -385.457954) (xy 161.539508 -385.435268)
			(xy 161.52265 -385.38694) (xy 161.51407 -385.33648) (xy 161.51352 -385.310888) (xy 160.971526 -385.310888)
			(xy 161.28365 -385.850892) (xy 161.296476 -385.874224) (xy 161.314695 -385.924247) (xy 161.323955 -385.976673)
			(xy 161.324544 -386.003292) (xy 161.324031 -386.027269) (xy 161.316535 -386.074632) (xy 161.301727 -386.120241)
			(xy 161.279969 -386.162974) (xy 161.251799 -386.20178) (xy 161.217907 -386.235705) (xy 161.179129 -386.263913)
			(xy 161.136417 -386.285712) (xy 161.090822 -386.300566) (xy 161.043466 -386.308108) (xy 161.01949 -386.3086)
			(xy 161.018982 -386.3086) (xy 160.995407 -386.308221) (xy 160.948819 -386.300977) (xy 160.9039 -386.286648)
			(xy 160.861721 -386.265577) (xy 160.823288 -386.238265) (xy 160.789517 -386.205364) (xy 160.761212 -386.167657)
			(xy 160.749742 -386.147056) (xy 160.749234 -386.146294) (xy 160.35147 -385.457954) (xy 160.339612 -385.435268)
			(xy 160.322755 -385.386939) (xy 160.314174 -385.33648) (xy 160.313624 -385.310888) (xy 159.77163 -385.310888)
			(xy 160.083754 -385.850892) (xy 160.09658 -385.874224) (xy 160.114799 -385.924247) (xy 160.124059 -385.976673)
			(xy 160.124648 -386.003292) (xy 160.124131 -386.027268) (xy 160.116636 -386.074632) (xy 160.101827 -386.12024)
			(xy 160.08007 -386.162973) (xy 160.0519 -386.201779) (xy 160.018009 -386.235703) (xy 159.979231 -386.263912)
			(xy 159.93652 -386.285711) (xy 159.890926 -386.300565) (xy 159.84357 -386.308107) (xy 159.819594 -386.3086)
			(xy 159.819086 -386.3086) (xy 159.795512 -386.308217) (xy 159.748923 -386.300974) (xy 159.704004 -386.286646)
			(xy 159.661826 -386.265576) (xy 159.623393 -386.238264) (xy 159.589621 -386.205363) (xy 159.561316 -386.167656)
			(xy 159.549846 -386.147056) (xy 159.549338 -386.146294) (xy 159.151574 -385.457954) (xy 159.139717 -385.435268)
			(xy 159.122859 -385.386939) (xy 159.114278 -385.336479) (xy 159.113728 -385.310888) (xy 158.57148 -385.310888)
			(xy 158.883604 -385.850892) (xy 158.896337 -385.87421) (xy 158.914431 -385.924158) (xy 158.923647 -385.976477)
			(xy 158.924244 -386.003038) (xy 158.924244 -386.003292) (xy 158.92373 -386.027281) (xy 158.916226 -386.074669)
			(xy 158.901402 -386.1203) (xy 158.879623 -386.16305) (xy 158.851424 -386.201867) (xy 158.817501 -386.235796)
			(xy 158.778688 -386.264) (xy 158.735941 -386.285785) (xy 158.690312 -386.300616) (xy 158.642925 -386.308127)
			(xy 158.618936 -386.3086) (xy 158.595363 -386.308177) (xy 158.548776 -386.300941) (xy 158.503858 -386.286621)
			(xy 158.46168 -386.265557) (xy 158.423246 -386.238252) (xy 158.389474 -386.205356) (xy 158.361167 -386.167654)
			(xy 158.349696 -386.147056) (xy 158.349188 -386.146294) (xy 157.951424 -385.457954) (xy 157.939492 -385.435294)
			(xy 157.92256 -385.386965) (xy 157.913907 -385.336491) (xy 157.913324 -385.310888) (xy 157.371584 -385.310888)
			(xy 157.683708 -385.850892) (xy 157.696441 -385.87421) (xy 157.714535 -385.924158) (xy 157.723751 -385.976477)
			(xy 157.724348 -386.003038) (xy 157.724348 -386.003292) (xy 157.72383 -386.027281) (xy 157.716326 -386.074669)
			(xy 157.701503 -386.120299) (xy 157.679724 -386.163049) (xy 157.651525 -386.201866) (xy 157.617603 -386.235794)
			(xy 157.57879 -386.263998) (xy 157.536043 -386.285784) (xy 157.490415 -386.300615) (xy 157.443029 -386.308126)
			(xy 157.41904 -386.3086) (xy 157.395467 -386.308174) (xy 157.34888 -386.300939) (xy 157.303963 -386.286618)
			(xy 157.261784 -386.265555) (xy 157.223351 -386.238251) (xy 157.189578 -386.205355) (xy 157.161271 -386.167654)
			(xy 157.1498 -386.147056) (xy 157.149292 -386.146294) (xy 156.751528 -385.457954) (xy 156.739596 -385.435294)
			(xy 156.722664 -385.386965) (xy 156.714011 -385.336491) (xy 156.713428 -385.310888) (xy 156.171434 -385.310888)
			(xy 156.483558 -385.850892) (xy 156.496384 -385.874224) (xy 156.514604 -385.924247) (xy 156.523863 -385.976673)
			(xy 156.524452 -386.003292) (xy 156.523931 -386.027268) (xy 156.516436 -386.074631) (xy 156.501627 -386.120239)
			(xy 156.479871 -386.162972) (xy 156.451701 -386.201778) (xy 156.417811 -386.235702) (xy 156.379033 -386.263911)
			(xy 156.336323 -386.28571) (xy 156.290729 -386.300564) (xy 156.243374 -386.308107) (xy 156.219398 -386.3086)
			(xy 156.21889 -386.3086) (xy 156.195316 -386.308214) (xy 156.148727 -386.300971) (xy 156.103808 -386.286644)
			(xy 156.06163 -386.265574) (xy 156.023197 -386.238263) (xy 155.989426 -386.205363) (xy 155.96112 -386.167656)
			(xy 155.94965 -386.147056) (xy 155.949142 -386.146294) (xy 155.551378 -385.457954) (xy 155.539521 -385.435268)
			(xy 155.522663 -385.386939) (xy 155.514082 -385.336479) (xy 155.513532 -385.310888) (xy 154.971538 -385.310888)
			(xy 155.283662 -385.850892) (xy 155.296489 -385.874224) (xy 155.314708 -385.924247) (xy 155.323967 -385.976673)
			(xy 155.324556 -386.003292) (xy 155.324031 -386.027268) (xy 155.316536 -386.07463) (xy 155.301728 -386.120239)
			(xy 155.279972 -386.162971) (xy 155.251802 -386.201776) (xy 155.217912 -386.235701) (xy 155.179135 -386.263909)
			(xy 155.136425 -386.285709) (xy 155.090832 -386.300563) (xy 155.043477 -386.308107) (xy 155.019502 -386.3086)
			(xy 155.018994 -386.3086) (xy 154.99542 -386.308211) (xy 154.948831 -386.300969) (xy 154.903913 -386.286642)
			(xy 154.861734 -386.265573) (xy 154.823301 -386.238262) (xy 154.78953 -386.205362) (xy 154.761224 -386.167656)
			(xy 154.749754 -386.147056) (xy 154.749246 -386.146294) (xy 154.351482 -385.457954) (xy 154.339625 -385.435268)
			(xy 154.322767 -385.386939) (xy 154.314186 -385.336479) (xy 154.313636 -385.310888) (xy 153.771642 -385.310888)
			(xy 154.083766 -385.850892) (xy 154.096593 -385.874223) (xy 154.114812 -385.924247) (xy 154.124071 -385.976673)
			(xy 154.12466 -386.003292) (xy 154.124231 -386.027273) (xy 154.116732 -386.074644) (xy 154.101919 -386.120261)
			(xy 154.080154 -386.162999) (xy 154.051974 -386.201809) (xy 154.018072 -386.235735) (xy 153.979282 -386.263942)
			(xy 153.936559 -386.285737) (xy 153.890953 -386.300582) (xy 153.843586 -386.308114) (xy 153.819606 -386.3086)
			(xy 153.819098 -386.3086) (xy 153.795524 -386.308208) (xy 153.748936 -386.300966) (xy 153.704017 -386.28664)
			(xy 153.661839 -386.265571) (xy 153.623406 -386.238261) (xy 153.589634 -386.205361) (xy 153.561328 -386.167656)
			(xy 153.549858 -386.147056) (xy 153.54935 -386.146294) (xy 153.151586 -385.457954) (xy 153.13973 -385.435267)
			(xy 153.122871 -385.386939) (xy 153.11429 -385.336479) (xy 153.11374 -385.310888) (xy 152.571492 -385.310888)
			(xy 152.883616 -385.850892) (xy 152.89635 -385.874209) (xy 152.914443 -385.924158) (xy 152.923659 -385.976477)
			(xy 152.924256 -386.003038) (xy 152.924256 -386.003292) (xy 152.92373 -386.027281) (xy 152.916227 -386.074667)
			(xy 152.901403 -386.120297) (xy 152.879625 -386.163047) (xy 152.851428 -386.201863) (xy 152.817506 -386.235791)
			(xy 152.778694 -386.263996) (xy 152.735949 -386.285782) (xy 152.690322 -386.300614) (xy 152.642937 -386.308126)
			(xy 152.618948 -386.3086) (xy 152.595375 -386.308168) (xy 152.548789 -386.300933) (xy 152.503871 -386.286614)
			(xy 152.461693 -386.265552) (xy 152.423259 -386.238248) (xy 152.389486 -386.205354) (xy 152.361179 -386.167654)
			(xy 152.349708 -386.147056) (xy 152.3492 -386.146294) (xy 151.951436 -385.457954) (xy 151.939505 -385.435294)
			(xy 151.922572 -385.386964) (xy 151.913919 -385.336491) (xy 151.913336 -385.310888) (xy 151.371596 -385.310888)
			(xy 151.68372 -385.850892) (xy 151.696454 -385.874209) (xy 151.714548 -385.924158) (xy 151.723763 -385.976476)
			(xy 151.72436 -386.003038) (xy 151.72436 -386.003292) (xy 151.723954 -386.027287) (xy 151.716447 -386.074687)
			(xy 151.701617 -386.120329) (xy 151.679828 -386.163088) (xy 151.651618 -386.201912) (xy 151.617682 -386.235844)
			(xy 151.578854 -386.264049) (xy 151.536092 -386.285832) (xy 151.490448 -386.300657) (xy 151.443047 -386.308157)
			(xy 151.419052 -386.3086) (xy 151.395479 -386.308164) (xy 151.348893 -386.300931) (xy 151.303976 -386.286612)
			(xy 151.261797 -386.265551) (xy 151.223364 -386.238247) (xy 151.189591 -386.205354) (xy 151.161283 -386.167653)
			(xy 151.149812 -386.147056) (xy 151.149304 -386.146294) (xy 150.75154 -385.457954) (xy 150.739609 -385.435293)
			(xy 150.722676 -385.386964) (xy 150.714023 -385.336491) (xy 150.71344 -385.310888) (xy 150.171446 -385.310888)
			(xy 150.48357 -385.850892) (xy 150.496397 -385.874223) (xy 150.514616 -385.924247) (xy 150.523875 -385.976673)
			(xy 150.524464 -386.003292) (xy 150.524031 -386.027273) (xy 150.516533 -386.074644) (xy 150.501719 -386.12026)
			(xy 150.479955 -386.162998) (xy 150.451775 -386.201808) (xy 150.417874 -386.235733) (xy 150.379084 -386.263941)
			(xy 150.336361 -386.285735) (xy 150.290756 -386.300581) (xy 150.24339 -386.308114) (xy 150.21941 -386.3086)
			(xy 150.218902 -386.3086) (xy 150.195328 -386.308205) (xy 150.14874 -386.300963) (xy 150.103821 -386.286638)
			(xy 150.061643 -386.26557) (xy 150.02321 -386.23826) (xy 149.989438 -386.205361) (xy 149.961133 -386.167656)
			(xy 149.949662 -386.147056) (xy 149.949154 -386.146294) (xy 149.55139 -385.457954) (xy 149.539534 -385.435267)
			(xy 149.522675 -385.386939) (xy 149.514094 -385.336479) (xy 149.513544 -385.310888) (xy 148.97155 -385.310888)
			(xy 149.283674 -385.850892) (xy 149.296501 -385.874223) (xy 149.31472 -385.924247) (xy 149.323979 -385.976673)
			(xy 149.324568 -386.003292) (xy 149.324131 -386.027272) (xy 149.316633 -386.074643) (xy 149.301819 -386.120259)
			(xy 149.280055 -386.162997) (xy 149.251876 -386.201806) (xy 149.217975 -386.235732) (xy 149.179187 -386.263939)
			(xy 149.136464 -386.285734) (xy 149.090859 -386.300581) (xy 149.043494 -386.308113) (xy 149.019514 -386.3086)
			(xy 149.019006 -386.3086) (xy 148.995432 -386.308201) (xy 148.948844 -386.300961) (xy 148.903926 -386.286636)
			(xy 148.861747 -386.265568) (xy 148.823314 -386.238259) (xy 148.789542 -386.20536) (xy 148.761237 -386.167655)
			(xy 148.749766 -386.147056) (xy 148.749258 -386.146294) (xy 148.351494 -385.457954) (xy 148.339638 -385.435267)
			(xy 148.322779 -385.386939) (xy 148.314198 -385.336479) (xy 148.313648 -385.310888) (xy 147.771654 -385.310888)
			(xy 148.083778 -385.850892) (xy 148.096606 -385.874223) (xy 148.114824 -385.924247) (xy 148.124083 -385.976673)
			(xy 148.124672 -386.003292) (xy 148.124231 -386.027272) (xy 148.116733 -386.074643) (xy 148.10192 -386.120258)
			(xy 148.080156 -386.162996) (xy 148.051978 -386.201805) (xy 148.018077 -386.235731) (xy 147.979289 -386.263938)
			(xy 147.936567 -386.285733) (xy 147.890963 -386.30058) (xy 147.843598 -386.308113) (xy 147.819618 -386.3086)
			(xy 147.81911 -386.3086) (xy 147.795536 -386.308198) (xy 147.748948 -386.300958) (xy 147.70403 -386.286634)
			(xy 147.661852 -386.265566) (xy 147.623418 -386.238258) (xy 147.589647 -386.20536) (xy 147.561341 -386.167655)
			(xy 147.54987 -386.147056) (xy 147.549362 -386.146294) (xy 147.151598 -385.457954) (xy 147.139742 -385.435267)
			(xy 147.122883 -385.386939) (xy 147.114302 -385.336479) (xy 147.113752 -385.310888) (xy 133.24387 -385.310888)
			(xy 133.555994 -385.850892) (xy 133.568823 -385.874222) (xy 133.587041 -385.924246) (xy 133.596299 -385.976673)
			(xy 133.596888 -386.003292) (xy 133.596431 -386.027271) (xy 133.588933 -386.07464) (xy 133.574121 -386.120254)
			(xy 133.552359 -386.162991) (xy 133.524182 -386.2018) (xy 133.490284 -386.235725) (xy 133.451498 -386.263932)
			(xy 133.408778 -386.285728) (xy 133.363176 -386.300577) (xy 133.315813 -386.308112) (xy 133.291834 -386.3086)
			(xy 133.291326 -386.3086) (xy 133.267753 -386.308185) (xy 133.221165 -386.300948) (xy 133.176247 -386.286626)
			(xy 133.134069 -386.26556) (xy 133.095636 -386.238254) (xy 133.061863 -386.205357) (xy 133.033557 -386.167655)
			(xy 133.022086 -386.147056) (xy 133.021578 -386.146294) (xy 132.623814 -385.457954) (xy 132.611952 -385.43527)
			(xy 132.595097 -385.38694) (xy 132.586517 -385.33648) (xy 132.585968 -385.310888) (xy 132.04372 -385.310888)
			(xy 132.355844 -385.850892) (xy 132.36858 -385.874208) (xy 132.386672 -385.924157) (xy 132.395888 -385.976476)
			(xy 132.396484 -386.003038) (xy 132.396484 -386.003292) (xy 132.396054 -386.027286) (xy 132.388548 -386.074684)
			(xy 132.373719 -386.120323) (xy 132.351933 -386.163081) (xy 132.323725 -386.201904) (xy 132.289792 -386.235836)
			(xy 132.250967 -386.264041) (xy 132.208208 -386.285825) (xy 132.162568 -386.300652) (xy 132.11517 -386.308156)
			(xy 132.091176 -386.3086) (xy 132.067601 -386.308226) (xy 132.021012 -386.30098) (xy 131.976093 -386.286651)
			(xy 131.933915 -386.265579) (xy 131.895482 -386.238267) (xy 131.861711 -386.205365) (xy 131.833406 -386.167657)
			(xy 131.821936 -386.147056) (xy 131.821428 -386.146294) (xy 131.423664 -385.457954) (xy 131.411735 -385.435292)
			(xy 131.394801 -385.386964) (xy 131.386148 -385.336491) (xy 131.385564 -385.310888) (xy 130.843824 -385.310888)
			(xy 131.155948 -385.850892) (xy 131.168685 -385.874208) (xy 131.186776 -385.924157) (xy 131.195992 -385.976476)
			(xy 131.196588 -386.003038) (xy 131.196588 -386.003292) (xy 131.196154 -386.027286) (xy 131.188648 -386.074683)
			(xy 131.17382 -386.120322) (xy 131.152033 -386.16308) (xy 131.123826 -386.201902) (xy 131.089893 -386.235834)
			(xy 131.05107 -386.26404) (xy 131.008311 -386.285824) (xy 130.962671 -386.300651) (xy 130.915274 -386.308155)
			(xy 130.89128 -386.3086) (xy 130.867705 -386.308222) (xy 130.821116 -386.300978) (xy 130.776197 -386.286649)
			(xy 130.734019 -386.265578) (xy 130.695586 -386.238266) (xy 130.661815 -386.205364) (xy 130.63351 -386.167657)
			(xy 130.62204 -386.147056) (xy 130.621532 -386.146294) (xy 130.223768 -385.457954) (xy 130.211839 -385.435292)
			(xy 130.194906 -385.386964) (xy 130.186252 -385.336491) (xy 130.185668 -385.310888) (xy 129.643674 -385.310888)
			(xy 129.955798 -385.850892) (xy 129.968619 -385.874226) (xy 129.986842 -385.924248) (xy 129.996103 -385.976674)
			(xy 129.996692 -386.003292) (xy 129.996231 -386.027271) (xy 129.988734 -386.07464) (xy 129.973922 -386.120253)
			(xy 129.95216 -386.16299) (xy 129.923983 -386.201798) (xy 129.890086 -386.235723) (xy 129.8513 -386.263931)
			(xy 129.808581 -386.285727) (xy 129.762979 -386.300576) (xy 129.715617 -386.308112) (xy 129.691638 -386.3086)
			(xy 129.69113 -386.3086) (xy 129.667557 -386.308182) (xy 129.62097 -386.300945) (xy 129.576052 -386.286624)
			(xy 129.533873 -386.265559) (xy 129.49544 -386.238253) (xy 129.461668 -386.205357) (xy 129.433361 -386.167654)
			(xy 129.42189 -386.147056) (xy 129.421382 -386.146294) (xy 129.023618 -385.457954) (xy 129.011756 -385.43527)
			(xy 128.994901 -385.38694) (xy 128.986321 -385.33648) (xy 128.985772 -385.310888) (xy 128.443778 -385.310888)
			(xy 128.755902 -385.850892) (xy 128.768724 -385.874226) (xy 128.786946 -385.924248) (xy 128.796207 -385.976674)
			(xy 128.796796 -386.003292) (xy 128.796331 -386.027271) (xy 128.788834 -386.074639) (xy 128.774022 -386.120252)
			(xy 128.752261 -386.162989) (xy 128.724085 -386.201797) (xy 128.690187 -386.235722) (xy 128.651402 -386.26393)
			(xy 128.608684 -386.285726) (xy 128.563083 -386.300575) (xy 128.515721 -386.308111) (xy 128.491742 -386.3086)
			(xy 128.491234 -386.3086) (xy 128.467661 -386.308179) (xy 128.421074 -386.300942) (xy 128.376156 -386.286622)
			(xy 128.333978 -386.265557) (xy 128.295544 -386.238252) (xy 128.261772 -386.205356) (xy 128.233465 -386.167654)
			(xy 128.221994 -386.147056) (xy 128.221486 -386.146294) (xy 127.823722 -385.457954) (xy 127.811861 -385.43527)
			(xy 127.795005 -385.38694) (xy 127.786426 -385.33648) (xy 127.785876 -385.310888) (xy 127.243882 -385.310888)
			(xy 127.556006 -385.850892) (xy 127.568828 -385.874226) (xy 127.58705 -385.924248) (xy 127.596311 -385.976674)
			(xy 127.5969 -386.003292) (xy 127.596431 -386.027271) (xy 127.588934 -386.074639) (xy 127.574122 -386.120251)
			(xy 127.552361 -386.162988) (xy 127.524186 -386.201795) (xy 127.490289 -386.235721) (xy 127.451504 -386.263928)
			(xy 127.408786 -386.285725) (xy 127.363186 -386.300574) (xy 127.315824 -386.308111) (xy 127.291846 -386.3086)
			(xy 127.291338 -386.3086) (xy 127.267765 -386.308176) (xy 127.221178 -386.30094) (xy 127.17626 -386.28662)
			(xy 127.134082 -386.265556) (xy 127.095648 -386.238251) (xy 127.061876 -386.205356) (xy 127.033569 -386.167654)
			(xy 127.022098 -386.147056) (xy 127.02159 -386.146294) (xy 126.623826 -385.457954) (xy 126.611965 -385.43527)
			(xy 126.595109 -385.38694) (xy 126.58653 -385.33648) (xy 126.58598 -385.310888) (xy 126.043732 -385.310888)
			(xy 126.355856 -385.850892) (xy 126.368593 -385.874208) (xy 126.386685 -385.924157) (xy 126.3959 -385.976476)
			(xy 126.396496 -386.003038) (xy 126.396496 -386.003292) (xy 126.396054 -386.027286) (xy 126.388548 -386.074682)
			(xy 126.37372 -386.12032) (xy 126.351935 -386.163077) (xy 126.323729 -386.2019) (xy 126.289797 -386.235831)
			(xy 126.250974 -386.264037) (xy 126.208217 -386.285822) (xy 126.162578 -386.300649) (xy 126.115182 -386.308155)
			(xy 126.091188 -386.3086) (xy 126.067614 -386.308216) (xy 126.021025 -386.300973) (xy 125.976106 -386.286645)
			(xy 125.933928 -386.265575) (xy 125.895495 -386.238264) (xy 125.861723 -386.205363) (xy 125.833418 -386.167656)
			(xy 125.821948 -386.147056) (xy 125.82144 -386.146294) (xy 125.423676 -385.457954) (xy 125.41174 -385.435296)
			(xy 125.39481 -385.386965) (xy 125.386159 -385.336492) (xy 125.385576 -385.310888) (xy 124.843836 -385.310888)
			(xy 125.15596 -385.850892) (xy 125.168698 -385.874207) (xy 125.186789 -385.924157) (xy 125.196004 -385.976476)
			(xy 125.1966 -386.003038) (xy 125.1966 -386.003292) (xy 125.196154 -386.027285) (xy 125.188649 -386.074681)
			(xy 125.173821 -386.12032) (xy 125.152036 -386.163076) (xy 125.12383 -386.201898) (xy 125.089898 -386.23583)
			(xy 125.051076 -386.264036) (xy 125.00832 -386.285821) (xy 124.962681 -386.300649) (xy 124.915285 -386.308154)
			(xy 124.891292 -386.3086) (xy 124.867718 -386.308213) (xy 124.821129 -386.30097) (xy 124.77621 -386.286643)
			(xy 124.734032 -386.265573) (xy 124.695599 -386.238263) (xy 124.661828 -386.205362) (xy 124.633522 -386.167656)
			(xy 124.622052 -386.147056) (xy 124.621544 -386.146294) (xy 124.22378 -385.457954) (xy 124.211844 -385.435296)
			(xy 124.194915 -385.386965) (xy 124.186263 -385.336492) (xy 124.18568 -385.310888) (xy 123.643686 -385.310888)
			(xy 123.95581 -385.850892) (xy 123.968632 -385.874226) (xy 123.986854 -385.924248) (xy 123.996115 -385.976673)
			(xy 123.996704 -386.003292) (xy 123.996231 -386.027271) (xy 123.988734 -386.074638) (xy 123.973923 -386.120251)
			(xy 123.952162 -386.162986) (xy 123.923987 -386.201794) (xy 123.890091 -386.235719) (xy 123.851307 -386.263927)
			(xy 123.808589 -386.285724) (xy 123.762989 -386.300574) (xy 123.715628 -386.308111) (xy 123.69165 -386.3086)
			(xy 123.691142 -386.3086) (xy 123.667569 -386.308172) (xy 123.620983 -386.300937) (xy 123.576065 -386.286617)
			(xy 123.533886 -386.265554) (xy 123.495453 -386.23825) (xy 123.46168 -386.205355) (xy 123.433373 -386.167654)
			(xy 123.421902 -386.147056) (xy 123.421394 -386.146294) (xy 123.02363 -385.457954) (xy 123.011769 -385.43527)
			(xy 122.994913 -385.38694) (xy 122.986334 -385.33648) (xy 122.985784 -385.310888) (xy 122.44379 -385.310888)
			(xy 122.755914 -385.850892) (xy 122.768737 -385.874226) (xy 122.786958 -385.924248) (xy 122.796219 -385.976673)
			(xy 122.796808 -386.003292) (xy 122.796331 -386.02727) (xy 122.788834 -386.074637) (xy 122.774023 -386.12025)
			(xy 122.752263 -386.162985) (xy 122.724088 -386.201793) (xy 122.690192 -386.235718) (xy 122.651409 -386.263926)
			(xy 122.608692 -386.285723) (xy 122.563092 -386.300573) (xy 122.515732 -386.30811) (xy 122.491754 -386.3086)
			(xy 122.491246 -386.3086) (xy 122.467673 -386.308169) (xy 122.421087 -386.300935) (xy 122.376169 -386.286615)
			(xy 122.333991 -386.265553) (xy 122.295557 -386.238249) (xy 122.261784 -386.205355) (xy 122.233477 -386.167654)
			(xy 122.222006 -386.147056) (xy 122.221498 -386.146294) (xy 121.823734 -385.457954) (xy 121.811874 -385.43527)
			(xy 121.795018 -385.38694) (xy 121.786438 -385.33648) (xy 121.785888 -385.310888) (xy 121.243894 -385.310888)
			(xy 121.556018 -385.850892) (xy 121.568841 -385.874226) (xy 121.587062 -385.924248) (xy 121.596323 -385.976673)
			(xy 121.596912 -386.003292) (xy 121.596431 -386.02727) (xy 121.588934 -386.074637) (xy 121.574124 -386.120249)
			(xy 121.552364 -386.162984) (xy 121.524189 -386.201791) (xy 121.490294 -386.235716) (xy 121.451511 -386.263924)
			(xy 121.408795 -386.285722) (xy 121.363196 -386.300572) (xy 121.315836 -386.30811) (xy 121.291858 -386.3086)
			(xy 121.29135 -386.3086) (xy 121.267777 -386.308166) (xy 121.221191 -386.300932) (xy 121.176273 -386.286613)
			(xy 121.134095 -386.265551) (xy 121.095661 -386.238248) (xy 121.061888 -386.205354) (xy 121.033581 -386.167653)
			(xy 121.02211 -386.147056) (xy 121.021602 -386.146294) (xy 120.623838 -385.457954) (xy 120.611978 -385.435269)
			(xy 120.595122 -385.38694) (xy 120.586542 -385.33648) (xy 120.585992 -385.310888) (xy 120.043744 -385.310888)
			(xy 120.355868 -385.850892) (xy 120.368606 -385.874207) (xy 120.386697 -385.924157) (xy 120.395912 -385.976476)
			(xy 120.396508 -386.003038) (xy 120.396508 -386.003292) (xy 120.396054 -386.027285) (xy 120.388549 -386.07468)
			(xy 120.373721 -386.120318) (xy 120.351937 -386.163074) (xy 120.323732 -386.201896) (xy 120.289802 -386.235827)
			(xy 120.250981 -386.264033) (xy 120.208225 -386.285818) (xy 120.162588 -386.300647) (xy 120.115193 -386.308154)
			(xy 120.0912 -386.3086) (xy 120.067626 -386.308206) (xy 120.021038 -386.300965) (xy 119.976119 -386.286639)
			(xy 119.933941 -386.26557) (xy 119.895508 -386.238261) (xy 119.861736 -386.205361) (xy 119.83343 -386.167656)
			(xy 119.82196 -386.147056) (xy 119.821452 -386.146294) (xy 119.423688 -385.457954) (xy 119.411753 -385.435296)
			(xy 119.394823 -385.386965) (xy 119.386171 -385.336491) (xy 119.385588 -385.310888) (xy 118.843848 -385.310888)
			(xy 119.155972 -385.850892) (xy 119.168711 -385.874207) (xy 119.186801 -385.924157) (xy 119.196016 -385.976476)
			(xy 119.196612 -386.003038) (xy 119.196612 -386.003292) (xy 119.196154 -386.027285) (xy 119.188649 -386.07468)
			(xy 119.173822 -386.120317) (xy 119.152038 -386.163073) (xy 119.123834 -386.201894) (xy 119.089903 -386.235826)
			(xy 119.051083 -386.264032) (xy 119.008328 -386.285817) (xy 118.962691 -386.300646) (xy 118.915297 -386.308154)
			(xy 118.891304 -386.3086) (xy 118.86773 -386.308203) (xy 118.821142 -386.300962) (xy 118.776223 -386.286637)
			(xy 118.734045 -386.265569) (xy 118.695612 -386.23826) (xy 118.66184 -386.205361) (xy 118.633535 -386.167656)
			(xy 118.622064 -386.147056) (xy 118.621556 -386.146294) (xy 118.223792 -385.457954) (xy 118.211857 -385.435295)
			(xy 118.194927 -385.386965) (xy 118.186275 -385.336491) (xy 118.185692 -385.310888) (xy 117.643698 -385.310888)
			(xy 117.955822 -385.850892) (xy 117.968645 -385.874225) (xy 117.986866 -385.924248) (xy 117.996127 -385.976673)
			(xy 117.996716 -386.003292) (xy 117.996231 -386.02727) (xy 117.988734 -386.074636) (xy 117.973924 -386.120248)
			(xy 117.952164 -386.162983) (xy 117.92399 -386.20179) (xy 117.890096 -386.235715) (xy 117.851313 -386.263923)
			(xy 117.808598 -386.28572) (xy 117.762999 -386.300571) (xy 117.71564 -386.30811) (xy 117.691662 -386.3086)
			(xy 117.691154 -386.3086) (xy 117.667582 -386.308163) (xy 117.620995 -386.300929) (xy 117.576078 -386.286611)
			(xy 117.533899 -386.26555) (xy 117.495466 -386.238247) (xy 117.461693 -386.205353) (xy 117.433385 -386.167653)
			(xy 117.421914 -386.147056) (xy 117.421406 -386.146294) (xy 117.023642 -385.457954) (xy 117.011782 -385.435269)
			(xy 116.994926 -385.38694) (xy 116.986346 -385.33648) (xy 116.985796 -385.310888) (xy 116.443802 -385.310888)
			(xy 116.755926 -385.850892) (xy 116.76875 -385.874225) (xy 116.786971 -385.924247) (xy 116.796231 -385.976673)
			(xy 116.79682 -386.003292) (xy 116.796331 -386.02727) (xy 116.788835 -386.074636) (xy 116.774024 -386.120247)
			(xy 116.752265 -386.162982) (xy 116.724092 -386.201789) (xy 116.690197 -386.235713) (xy 116.651416 -386.263922)
			(xy 116.6087 -386.285719) (xy 116.563102 -386.30057) (xy 116.515743 -386.30811) (xy 116.491766 -386.3086)
			(xy 116.491258 -386.3086) (xy 116.467686 -386.308159) (xy 116.4211 -386.300927) (xy 116.376182 -386.286609)
			(xy 116.334004 -386.265548) (xy 116.29557 -386.238246) (xy 116.261797 -386.205353) (xy 116.23349 -386.167653)
			(xy 116.222018 -386.147056) (xy 116.22151 -386.146294) (xy 115.823746 -385.457954) (xy 115.811886 -385.435269)
			(xy 115.79503 -385.38694) (xy 115.78645 -385.33648) (xy 115.7859 -385.310888) (xy 115.243906 -385.310888)
			(xy 115.55603 -385.850892) (xy 115.568854 -385.874225) (xy 115.587075 -385.924247) (xy 115.596335 -385.976673)
			(xy 115.596924 -386.003292) (xy 115.596431 -386.02727) (xy 115.588935 -386.074635) (xy 115.574125 -386.120246)
			(xy 115.552366 -386.16298) (xy 115.524193 -386.201787) (xy 115.490299 -386.235712) (xy 115.451518 -386.26392)
			(xy 115.408803 -386.285718) (xy 115.363206 -386.30057) (xy 115.315847 -386.308109) (xy 115.29187 -386.3086)
			(xy 115.291362 -386.3086) (xy 115.26779 -386.308156) (xy 115.221204 -386.300924) (xy 115.176286 -386.286607)
			(xy 115.134108 -386.265547) (xy 115.095674 -386.238245) (xy 115.061901 -386.205352) (xy 115.033594 -386.167653)
			(xy 115.022122 -386.147056) (xy 115.021614 -386.146294) (xy 114.62385 -385.457954) (xy 114.611991 -385.435269)
			(xy 114.595134 -385.38694) (xy 114.586554 -385.33648) (xy 114.586004 -385.310888) (xy 98.671676 -385.310888)
			(xy 98.9838 -385.850892) (xy 98.996533 -385.87421) (xy 99.014627 -385.924158) (xy 99.023843 -385.976477)
			(xy 99.02444 -386.003038) (xy 99.02444 -386.003292) (xy 99.02393 -386.027281) (xy 99.016426 -386.07467)
			(xy 99.001602 -386.120301) (xy 98.979822 -386.163051) (xy 98.951623 -386.201869) (xy 98.917699 -386.235797)
			(xy 98.878886 -386.264001) (xy 98.836138 -386.285787) (xy 98.790509 -386.300617) (xy 98.743121 -386.308127)
			(xy 98.719132 -386.3086) (xy 98.695559 -386.30818) (xy 98.648972 -386.300944) (xy 98.604054 -386.286623)
			(xy 98.561875 -386.265558) (xy 98.523442 -386.238253) (xy 98.48967 -386.205357) (xy 98.461363 -386.167654)
			(xy 98.449892 -386.147056) (xy 98.449384 -386.146294) (xy 98.05162 -385.457954) (xy 98.039687 -385.435294)
			(xy 98.022756 -385.386965) (xy 98.014103 -385.336491) (xy 98.01352 -385.310888) (xy 97.471526 -385.310888)
			(xy 97.78365 -385.850892) (xy 97.796476 -385.874224) (xy 97.814695 -385.924247) (xy 97.823955 -385.976673)
			(xy 97.824544 -386.003292) (xy 97.824031 -386.027269) (xy 97.816535 -386.074632) (xy 97.801727 -386.120241)
			(xy 97.779969 -386.162974) (xy 97.751799 -386.20178) (xy 97.717907 -386.235705) (xy 97.679129 -386.263913)
			(xy 97.636417 -386.285712) (xy 97.590822 -386.300566) (xy 97.543466 -386.308108) (xy 97.51949 -386.3086)
			(xy 97.518982 -386.3086) (xy 97.495407 -386.308221) (xy 97.448819 -386.300977) (xy 97.4039 -386.286648)
			(xy 97.361721 -386.265577) (xy 97.323288 -386.238265) (xy 97.289517 -386.205364) (xy 97.261212 -386.167657)
			(xy 97.249742 -386.147056) (xy 97.249234 -386.146294) (xy 96.85147 -385.457954) (xy 96.839612 -385.435268)
			(xy 96.822755 -385.386939) (xy 96.814174 -385.33648) (xy 96.813624 -385.310888) (xy 96.27163 -385.310888)
			(xy 96.583754 -385.850892) (xy 96.59658 -385.874224) (xy 96.614799 -385.924247) (xy 96.624059 -385.976673)
			(xy 96.624648 -386.003292) (xy 96.624131 -386.027268) (xy 96.616636 -386.074632) (xy 96.601827 -386.12024)
			(xy 96.58007 -386.162973) (xy 96.5519 -386.201779) (xy 96.518009 -386.235703) (xy 96.479231 -386.263912)
			(xy 96.43652 -386.285711) (xy 96.390926 -386.300565) (xy 96.34357 -386.308107) (xy 96.319594 -386.3086)
			(xy 96.319086 -386.3086) (xy 96.295512 -386.308217) (xy 96.248923 -386.300974) (xy 96.204004 -386.286646)
			(xy 96.161826 -386.265576) (xy 96.123393 -386.238264) (xy 96.089621 -386.205363) (xy 96.061316 -386.167656)
			(xy 96.049846 -386.147056) (xy 96.049338 -386.146294) (xy 95.651574 -385.457954) (xy 95.639717 -385.435268)
			(xy 95.622859 -385.386939) (xy 95.614278 -385.336479) (xy 95.613728 -385.310888) (xy 95.07148 -385.310888)
			(xy 95.383604 -385.850892) (xy 95.396337 -385.87421) (xy 95.414431 -385.924158) (xy 95.423647 -385.976477)
			(xy 95.424244 -386.003038) (xy 95.424244 -386.003292) (xy 95.42373 -386.027281) (xy 95.416226 -386.074669)
			(xy 95.401402 -386.1203) (xy 95.379623 -386.16305) (xy 95.351424 -386.201867) (xy 95.317501 -386.235796)
			(xy 95.278688 -386.264) (xy 95.235941 -386.285785) (xy 95.190312 -386.300616) (xy 95.142925 -386.308127)
			(xy 95.118936 -386.3086) (xy 95.095363 -386.308177) (xy 95.048776 -386.300941) (xy 95.003858 -386.286621)
			(xy 94.96168 -386.265557) (xy 94.923246 -386.238252) (xy 94.889474 -386.205356) (xy 94.861167 -386.167654)
			(xy 94.849696 -386.147056) (xy 94.849188 -386.146294) (xy 94.451424 -385.457954) (xy 94.439492 -385.435294)
			(xy 94.42256 -385.386965) (xy 94.413907 -385.336491) (xy 94.413324 -385.310888) (xy 93.871584 -385.310888)
			(xy 94.183708 -385.850892) (xy 94.196441 -385.87421) (xy 94.214535 -385.924158) (xy 94.223751 -385.976477)
			(xy 94.224348 -386.003038) (xy 94.224348 -386.003292) (xy 94.22383 -386.027281) (xy 94.216326 -386.074669)
			(xy 94.201503 -386.120299) (xy 94.179724 -386.163049) (xy 94.151525 -386.201866) (xy 94.117603 -386.235794)
			(xy 94.07879 -386.263998) (xy 94.036043 -386.285784) (xy 93.990415 -386.300615) (xy 93.943029 -386.308126)
			(xy 93.91904 -386.3086) (xy 93.895467 -386.308174) (xy 93.84888 -386.300939) (xy 93.803963 -386.286618)
			(xy 93.761784 -386.265555) (xy 93.723351 -386.238251) (xy 93.689578 -386.205355) (xy 93.661271 -386.167654)
			(xy 93.6498 -386.147056) (xy 93.649292 -386.146294) (xy 93.251528 -385.457954) (xy 93.239596 -385.435294)
			(xy 93.222664 -385.386965) (xy 93.214011 -385.336491) (xy 93.213428 -385.310888) (xy 92.671688 -385.310888)
			(xy 92.983812 -385.850892) (xy 92.996546 -385.87421) (xy 93.014639 -385.924158) (xy 93.023855 -385.976477)
			(xy 93.024452 -386.003038) (xy 93.024452 -386.003292) (xy 93.02393 -386.027281) (xy 93.016427 -386.074668)
			(xy 93.001603 -386.120298) (xy 92.979824 -386.163048) (xy 92.951627 -386.201865) (xy 92.917704 -386.235793)
			(xy 92.878892 -386.263997) (xy 92.836146 -386.285783) (xy 92.790519 -386.300614) (xy 92.743133 -386.308126)
			(xy 92.719144 -386.3086) (xy 92.695571 -386.308171) (xy 92.648985 -386.300936) (xy 92.604067 -386.286616)
			(xy 92.561889 -386.265554) (xy 92.523455 -386.238249) (xy 92.489682 -386.205355) (xy 92.461375 -386.167654)
			(xy 92.449904 -386.147056) (xy 92.449396 -386.146294) (xy 92.051632 -385.457954) (xy 92.0397 -385.435294)
			(xy 92.022768 -385.386965) (xy 92.014115 -385.336491) (xy 92.013532 -385.310888) (xy 91.471538 -385.310888)
			(xy 91.783662 -385.850892) (xy 91.796489 -385.874224) (xy 91.814708 -385.924247) (xy 91.823967 -385.976673)
			(xy 91.824556 -386.003292) (xy 91.824031 -386.027268) (xy 91.816536 -386.07463) (xy 91.801728 -386.120239)
			(xy 91.779972 -386.162971) (xy 91.751802 -386.201776) (xy 91.717912 -386.235701) (xy 91.679135 -386.263909)
			(xy 91.636425 -386.285709) (xy 91.590832 -386.300563) (xy 91.543477 -386.308107) (xy 91.519502 -386.3086)
			(xy 91.518994 -386.3086) (xy 91.49542 -386.308211) (xy 91.448831 -386.300969) (xy 91.403913 -386.286642)
			(xy 91.361734 -386.265573) (xy 91.323301 -386.238262) (xy 91.28953 -386.205362) (xy 91.261224 -386.167656)
			(xy 91.249754 -386.147056) (xy 91.249246 -386.146294) (xy 90.851482 -385.457954) (xy 90.839625 -385.435268)
			(xy 90.822767 -385.386939) (xy 90.814186 -385.336479) (xy 90.813636 -385.310888) (xy 90.271642 -385.310888)
			(xy 90.583766 -385.850892) (xy 90.596593 -385.874223) (xy 90.614812 -385.924247) (xy 90.624071 -385.976673)
			(xy 90.62466 -386.003292) (xy 90.624231 -386.027273) (xy 90.616732 -386.074644) (xy 90.601919 -386.120261)
			(xy 90.580154 -386.162999) (xy 90.551974 -386.201809) (xy 90.518072 -386.235735) (xy 90.479282 -386.263942)
			(xy 90.436559 -386.285737) (xy 90.390953 -386.300582) (xy 90.343586 -386.308114) (xy 90.319606 -386.3086)
			(xy 90.319098 -386.3086) (xy 90.295524 -386.308208) (xy 90.248936 -386.300966) (xy 90.204017 -386.28664)
			(xy 90.161839 -386.265571) (xy 90.123406 -386.238261) (xy 90.089634 -386.205361) (xy 90.061328 -386.167656)
			(xy 90.049858 -386.147056) (xy 90.04935 -386.146294) (xy 89.651586 -385.457954) (xy 89.63973 -385.435267)
			(xy 89.622871 -385.386939) (xy 89.61429 -385.336479) (xy 89.61374 -385.310888) (xy 89.071492 -385.310888)
			(xy 89.383616 -385.850892) (xy 89.39635 -385.874209) (xy 89.414443 -385.924158) (xy 89.423659 -385.976477)
			(xy 89.424256 -386.003038) (xy 89.424256 -386.003292) (xy 89.42373 -386.027281) (xy 89.416227 -386.074667)
			(xy 89.401403 -386.120297) (xy 89.379625 -386.163047) (xy 89.351428 -386.201863) (xy 89.317506 -386.235791)
			(xy 89.278694 -386.263996) (xy 89.235949 -386.285782) (xy 89.190322 -386.300614) (xy 89.142937 -386.308126)
			(xy 89.118948 -386.3086) (xy 89.095375 -386.308168) (xy 89.048789 -386.300933) (xy 89.003871 -386.286614)
			(xy 88.961693 -386.265552) (xy 88.923259 -386.238248) (xy 88.889486 -386.205354) (xy 88.861179 -386.167654)
			(xy 88.849708 -386.147056) (xy 88.8492 -386.146294) (xy 88.451436 -385.457954) (xy 88.439505 -385.435294)
			(xy 88.422572 -385.386964) (xy 88.413919 -385.336491) (xy 88.413336 -385.310888) (xy 87.871596 -385.310888)
			(xy 88.18372 -385.850892) (xy 88.196454 -385.874209) (xy 88.214548 -385.924158) (xy 88.223763 -385.976476)
			(xy 88.22436 -386.003038) (xy 88.22436 -386.003292) (xy 88.223954 -386.027287) (xy 88.216447 -386.074687)
			(xy 88.201617 -386.120329) (xy 88.179828 -386.163088) (xy 88.151618 -386.201912) (xy 88.117682 -386.235844)
			(xy 88.078854 -386.264049) (xy 88.036092 -386.285832) (xy 87.990448 -386.300657) (xy 87.943047 -386.308157)
			(xy 87.919052 -386.3086) (xy 87.895479 -386.308164) (xy 87.848893 -386.300931) (xy 87.803976 -386.286612)
			(xy 87.761797 -386.265551) (xy 87.723364 -386.238247) (xy 87.689591 -386.205354) (xy 87.661283 -386.167653)
			(xy 87.649812 -386.147056) (xy 87.649304 -386.146294) (xy 87.25154 -385.457954) (xy 87.239609 -385.435293)
			(xy 87.222676 -385.386964) (xy 87.214023 -385.336491) (xy 87.21344 -385.310888) (xy 86.6717 -385.310888)
			(xy 86.983824 -385.850892) (xy 86.996559 -385.874209) (xy 87.014652 -385.924158) (xy 87.023867 -385.976476)
			(xy 87.024464 -386.003038) (xy 87.024464 -386.003292) (xy 87.024054 -386.027287) (xy 87.016547 -386.074687)
			(xy 87.001717 -386.120328) (xy 86.979929 -386.163087) (xy 86.951719 -386.201911) (xy 86.917783 -386.235843)
			(xy 86.878956 -386.264048) (xy 86.836195 -386.285831) (xy 86.790552 -386.300656) (xy 86.743151 -386.308157)
			(xy 86.719156 -386.3086) (xy 86.695584 -386.308161) (xy 86.648997 -386.300928) (xy 86.60408 -386.28661)
			(xy 86.561902 -386.265549) (xy 86.523468 -386.238246) (xy 86.489695 -386.205353) (xy 86.461387 -386.167653)
			(xy 86.449916 -386.147056) (xy 86.449408 -386.146294) (xy 86.051644 -385.457954) (xy 86.039713 -385.435293)
			(xy 86.02278 -385.386964) (xy 86.014127 -385.336491) (xy 86.013544 -385.310888) (xy 85.47155 -385.310888)
			(xy 85.783674 -385.850892) (xy 85.796501 -385.874223) (xy 85.81472 -385.924247) (xy 85.823979 -385.976673)
			(xy 85.824568 -386.003292) (xy 85.824131 -386.027272) (xy 85.816633 -386.074643) (xy 85.801819 -386.120259)
			(xy 85.780055 -386.162997) (xy 85.751876 -386.201806) (xy 85.717975 -386.235732) (xy 85.679187 -386.263939)
			(xy 85.636464 -386.285734) (xy 85.590859 -386.300581) (xy 85.543494 -386.308113) (xy 85.519514 -386.3086)
			(xy 85.519006 -386.3086) (xy 85.495432 -386.308201) (xy 85.448844 -386.300961) (xy 85.403926 -386.286636)
			(xy 85.361747 -386.265568) (xy 85.323314 -386.238259) (xy 85.289542 -386.20536) (xy 85.261237 -386.167655)
			(xy 85.249766 -386.147056) (xy 85.249258 -386.146294) (xy 84.851494 -385.457954) (xy 84.839638 -385.435267)
			(xy 84.822779 -385.386939) (xy 84.814198 -385.336479) (xy 84.813648 -385.310888) (xy 84.271654 -385.310888)
			(xy 84.583778 -385.850892) (xy 84.596606 -385.874223) (xy 84.614824 -385.924247) (xy 84.624083 -385.976673)
			(xy 84.624672 -386.003292) (xy 84.624231 -386.027272) (xy 84.616733 -386.074643) (xy 84.60192 -386.120258)
			(xy 84.580156 -386.162996) (xy 84.551978 -386.201805) (xy 84.518077 -386.235731) (xy 84.479289 -386.263938)
			(xy 84.436567 -386.285733) (xy 84.390963 -386.30058) (xy 84.343598 -386.308113) (xy 84.319618 -386.3086)
			(xy 84.31911 -386.3086) (xy 84.295536 -386.308198) (xy 84.248948 -386.300958) (xy 84.20403 -386.286634)
			(xy 84.161852 -386.265566) (xy 84.123418 -386.238258) (xy 84.089647 -386.20536) (xy 84.061341 -386.167655)
			(xy 84.04987 -386.147056) (xy 84.049362 -386.146294) (xy 83.651598 -385.457954) (xy 83.639742 -385.435267)
			(xy 83.622883 -385.386939) (xy 83.614302 -385.336479) (xy 83.613752 -385.310888) (xy 83.071504 -385.310888)
			(xy 83.383628 -385.850892) (xy 83.396363 -385.874209) (xy 83.414456 -385.924157) (xy 83.423671 -385.976476)
			(xy 83.424268 -386.003038) (xy 83.424268 -386.003292) (xy 83.423854 -386.027287) (xy 83.416348 -386.074686)
			(xy 83.401518 -386.120327) (xy 83.37973 -386.163086) (xy 83.351521 -386.201909) (xy 83.317585 -386.235841)
			(xy 83.278758 -386.264047) (xy 83.235997 -386.28583) (xy 83.190355 -386.300655) (xy 83.142955 -386.308157)
			(xy 83.11896 -386.3086) (xy 83.095388 -386.308158) (xy 83.048802 -386.300925) (xy 83.003884 -386.286608)
			(xy 82.961706 -386.265548) (xy 82.923272 -386.238245) (xy 82.889499 -386.205353) (xy 82.861192 -386.167653)
			(xy 82.84972 -386.147056) (xy 82.849212 -386.146294) (xy 82.451448 -385.457954) (xy 82.439517 -385.435293)
			(xy 82.422585 -385.386964) (xy 82.413931 -385.336491) (xy 82.413348 -385.310888) (xy 81.871608 -385.310888)
			(xy 82.183732 -385.850892) (xy 82.196467 -385.874209) (xy 82.21456 -385.924157) (xy 82.223775 -385.976476)
			(xy 82.224372 -386.003038) (xy 82.224372 -386.003292) (xy 82.223954 -386.027287) (xy 82.216448 -386.074685)
			(xy 82.201618 -386.120326) (xy 82.179831 -386.163085) (xy 82.151622 -386.201908) (xy 82.117687 -386.23584)
			(xy 82.078861 -386.264045) (xy 82.0361 -386.285829) (xy 81.990458 -386.300654) (xy 81.943059 -386.308156)
			(xy 81.919064 -386.3086) (xy 81.895492 -386.308155) (xy 81.848906 -386.300923) (xy 81.803989 -386.286606)
			(xy 81.76181 -386.265546) (xy 81.723376 -386.238244) (xy 81.689603 -386.205352) (xy 81.661296 -386.167653)
			(xy 81.649824 -386.147056) (xy 81.649316 -386.146294) (xy 81.251552 -385.457954) (xy 81.239622 -385.435293)
			(xy 81.222689 -385.386964) (xy 81.214035 -385.336491) (xy 81.213452 -385.310888) (xy 80.671712 -385.310888)
			(xy 80.983836 -385.850892) (xy 80.996572 -385.874209) (xy 81.014664 -385.924157) (xy 81.023879 -385.976476)
			(xy 81.024476 -386.003038) (xy 81.024476 -386.003292) (xy 81.024054 -386.027287) (xy 81.016548 -386.074685)
			(xy 81.001718 -386.120325) (xy 80.979931 -386.163083) (xy 80.951723 -386.201907) (xy 80.917788 -386.235839)
			(xy 80.878963 -386.264044) (xy 80.836203 -386.285828) (xy 80.790561 -386.300653) (xy 80.743163 -386.308156)
			(xy 80.719168 -386.3086) (xy 80.695596 -386.308151) (xy 80.64901 -386.30092) (xy 80.604093 -386.286604)
			(xy 80.561915 -386.265545) (xy 80.523481 -386.238243) (xy 80.489707 -386.205351) (xy 80.4614 -386.167653)
			(xy 80.449928 -386.147056) (xy 80.44942 -386.146294) (xy 80.051656 -385.457954) (xy 80.039726 -385.435293)
			(xy 80.022793 -385.386964) (xy 80.014139 -385.336491) (xy 80.013556 -385.310888) (xy 66.144182 -385.310888)
			(xy 66.456306 -385.850892) (xy 66.469128 -385.874226) (xy 66.48735 -385.924248) (xy 66.496611 -385.976674)
			(xy 66.4972 -386.003292) (xy 66.496754 -386.027298) (xy 66.48924 -386.074718) (xy 66.474396 -386.120378)
			(xy 66.452589 -386.163152) (xy 66.424356 -386.201985) (xy 66.390392 -386.235921) (xy 66.351535 -386.264122)
			(xy 66.308743 -386.285894) (xy 66.263071 -386.300699) (xy 66.215644 -386.308173) (xy 66.191638 -386.3086)
			(xy 66.191384 -386.3086) (xy 66.16781 -386.308219) (xy 66.121221 -386.300975) (xy 66.076302 -386.286647)
			(xy 66.034123 -386.265576) (xy 65.995691 -386.238265) (xy 65.961919 -386.205363) (xy 65.933614 -386.167656)
			(xy 65.922144 -386.147056) (xy 65.921636 -386.146294) (xy 65.523872 -385.457954) (xy 65.511936 -385.435296)
			(xy 65.495006 -385.386965) (xy 65.486355 -385.336492) (xy 65.485772 -385.310888) (xy 64.944032 -385.310888)
			(xy 65.256156 -385.850892) (xy 65.268893 -385.874208) (xy 65.286985 -385.924157) (xy 65.2962 -385.976476)
			(xy 65.296796 -386.003038) (xy 65.296796 -386.003292) (xy 65.296354 -386.027286) (xy 65.288848 -386.074682)
			(xy 65.27402 -386.12032) (xy 65.252235 -386.163077) (xy 65.224029 -386.2019) (xy 65.190097 -386.235831)
			(xy 65.151274 -386.264037) (xy 65.108517 -386.285822) (xy 65.062878 -386.300649) (xy 65.015482 -386.308155)
			(xy 64.991488 -386.3086) (xy 64.991234 -386.3086) (xy 64.967661 -386.308179) (xy 64.921074 -386.300942)
			(xy 64.876156 -386.286622) (xy 64.833978 -386.265557) (xy 64.795544 -386.238252) (xy 64.761772 -386.205356)
			(xy 64.733465 -386.167654) (xy 64.721994 -386.147056) (xy 64.721486 -386.146294) (xy 64.323722 -385.457954)
			(xy 64.311861 -385.43527) (xy 64.295005 -385.38694) (xy 64.286426 -385.33648) (xy 64.285876 -385.310888)
			(xy 63.744136 -385.310888) (xy 64.05626 -385.850892) (xy 64.068998 -385.874207) (xy 64.087089 -385.924157)
			(xy 64.096304 -385.976476) (xy 64.0969 -386.003038) (xy 64.0969 -386.003292) (xy 64.096454 -386.027285)
			(xy 64.088949 -386.074681) (xy 64.074121 -386.12032) (xy 64.052336 -386.163076) (xy 64.02413 -386.201898)
			(xy 63.990198 -386.23583) (xy 63.951376 -386.264036) (xy 63.90862 -386.285821) (xy 63.862981 -386.300649)
			(xy 63.815585 -386.308154) (xy 63.791592 -386.3086) (xy 63.791338 -386.3086) (xy 63.767765 -386.308176)
			(xy 63.721178 -386.30094) (xy 63.67626 -386.28662) (xy 63.634082 -386.265556) (xy 63.595648 -386.238251)
			(xy 63.561876 -386.205356) (xy 63.533569 -386.167654) (xy 63.522098 -386.147056) (xy 63.52159 -386.146294)
			(xy 63.123826 -385.457954) (xy 63.111965 -385.43527) (xy 63.095109 -385.38694) (xy 63.08653 -385.33648)
			(xy 63.08598 -385.310888) (xy 62.543986 -385.310888) (xy 62.85611 -385.850892) (xy 62.868932 -385.874226)
			(xy 62.887154 -385.924248) (xy 62.896415 -385.976673) (xy 62.897004 -386.003292) (xy 62.896554 -386.027298)
			(xy 62.88904 -386.074718) (xy 62.874197 -386.120377) (xy 62.85239 -386.163151) (xy 62.824157 -386.201984)
			(xy 62.790194 -386.23592) (xy 62.751337 -386.264121) (xy 62.708546 -386.285893) (xy 62.662874 -386.300698)
			(xy 62.615448 -386.308173) (xy 62.591442 -386.3086) (xy 62.591188 -386.3086) (xy 62.567614 -386.308216)
			(xy 62.521025 -386.300973) (xy 62.476106 -386.286645) (xy 62.433928 -386.265575) (xy 62.395495 -386.238264)
			(xy 62.361723 -386.205363) (xy 62.333418 -386.167656) (xy 62.321948 -386.147056) (xy 62.32144 -386.146294)
			(xy 61.923676 -385.457954) (xy 61.91174 -385.435296) (xy 61.89481 -385.386965) (xy 61.886159 -385.336492)
			(xy 61.885576 -385.310888) (xy 61.34409 -385.310888) (xy 61.656214 -385.850892) (xy 61.669037 -385.874226)
			(xy 61.687258 -385.924248) (xy 61.696519 -385.976673) (xy 61.697108 -386.003292) (xy 61.696654 -386.027298)
			(xy 61.68914 -386.074717) (xy 61.674297 -386.120377) (xy 61.652491 -386.16315) (xy 61.624258 -386.201983)
			(xy 61.590295 -386.235918) (xy 61.55144 -386.264119) (xy 61.508649 -386.285891) (xy 61.462978 -386.300698)
			(xy 61.415552 -386.308173) (xy 61.391546 -386.3086) (xy 61.391292 -386.3086) (xy 61.367718 -386.308213)
			(xy 61.321129 -386.30097) (xy 61.27621 -386.286643) (xy 61.234032 -386.265573) (xy 61.195599 -386.238263)
			(xy 61.161828 -386.205362) (xy 61.133522 -386.167656) (xy 61.122052 -386.147056) (xy 61.121544 -386.146294)
			(xy 60.72378 -385.457954) (xy 60.711844 -385.435296) (xy 60.694915 -385.386965) (xy 60.686263 -385.336492)
			(xy 60.68568 -385.310888) (xy 60.144194 -385.310888) (xy 60.456318 -385.850892) (xy 60.469141 -385.874226)
			(xy 60.487362 -385.924248) (xy 60.496623 -385.976673) (xy 60.497212 -386.003292) (xy 60.496754 -386.027297)
			(xy 60.48924 -386.074717) (xy 60.474398 -386.120376) (xy 60.452591 -386.163149) (xy 60.424359 -386.201981)
			(xy 60.390397 -386.235917) (xy 60.351542 -386.264118) (xy 60.308752 -386.28589) (xy 60.263081 -386.300697)
			(xy 60.215656 -386.308172) (xy 60.19165 -386.3086) (xy 60.191396 -386.3086) (xy 60.167822 -386.308209)
			(xy 60.121233 -386.300967) (xy 60.076315 -386.286641) (xy 60.034136 -386.265572) (xy 59.995703 -386.238262)
			(xy 59.961932 -386.205362) (xy 59.933626 -386.167656) (xy 59.922156 -386.147056) (xy 59.921648 -386.146294)
			(xy 59.523884 -385.457954) (xy 59.511948 -385.435296) (xy 59.495019 -385.386965) (xy 59.486367 -385.336492)
			(xy 59.485784 -385.310888) (xy 58.944044 -385.310888) (xy 59.256168 -385.850892) (xy 59.268906 -385.874207)
			(xy 59.286997 -385.924157) (xy 59.296212 -385.976476) (xy 59.296808 -386.003038) (xy 59.296808 -386.003292)
			(xy 59.296354 -386.027285) (xy 59.288849 -386.07468) (xy 59.274021 -386.120318) (xy 59.252237 -386.163074)
			(xy 59.224032 -386.201896) (xy 59.190102 -386.235827) (xy 59.151281 -386.264033) (xy 59.108525 -386.285818)
			(xy 59.062888 -386.300647) (xy 59.015493 -386.308154) (xy 58.9915 -386.3086) (xy 58.991246 -386.3086)
			(xy 58.967673 -386.308169) (xy 58.921087 -386.300935) (xy 58.876169 -386.286615) (xy 58.833991 -386.265553)
			(xy 58.795557 -386.238249) (xy 58.761784 -386.205355) (xy 58.733477 -386.167654) (xy 58.722006 -386.147056)
			(xy 58.721498 -386.146294) (xy 58.323734 -385.457954) (xy 58.311874 -385.43527) (xy 58.295018 -385.38694)
			(xy 58.286438 -385.33648) (xy 58.285888 -385.310888) (xy 57.744148 -385.310888) (xy 58.056272 -385.850892)
			(xy 58.069011 -385.874207) (xy 58.087101 -385.924157) (xy 58.096316 -385.976476) (xy 58.096912 -386.003038)
			(xy 58.096912 -386.003292) (xy 58.096454 -386.027285) (xy 58.088949 -386.07468) (xy 58.074122 -386.120317)
			(xy 58.052338 -386.163073) (xy 58.024134 -386.201894) (xy 57.990203 -386.235826) (xy 57.951383 -386.264032)
			(xy 57.908628 -386.285817) (xy 57.862991 -386.300646) (xy 57.815597 -386.308154) (xy 57.791604 -386.3086)
			(xy 57.79135 -386.3086) (xy 57.767777 -386.308166) (xy 57.721191 -386.300932) (xy 57.676273 -386.286613)
			(xy 57.634095 -386.265551) (xy 57.595661 -386.238248) (xy 57.561888 -386.205354) (xy 57.533581 -386.167653)
			(xy 57.52211 -386.147056) (xy 57.521602 -386.146294) (xy 57.123838 -385.457954) (xy 57.111978 -385.435269)
			(xy 57.095122 -385.38694) (xy 57.086542 -385.33648) (xy 57.085992 -385.310888) (xy 56.543744 -385.310888)
			(xy 56.855868 -385.850892) (xy 56.868606 -385.874207) (xy 56.886697 -385.924157) (xy 56.895912 -385.976476)
			(xy 56.896508 -386.003038) (xy 56.896508 -386.003292) (xy 56.896054 -386.027285) (xy 56.888549 -386.07468)
			(xy 56.873721 -386.120318) (xy 56.851937 -386.163074) (xy 56.823732 -386.201896) (xy 56.789802 -386.235827)
			(xy 56.750981 -386.264033) (xy 56.708225 -386.285818) (xy 56.662588 -386.300647) (xy 56.615193 -386.308154)
			(xy 56.5912 -386.3086) (xy 56.567626 -386.308206) (xy 56.521038 -386.300965) (xy 56.476119 -386.286639)
			(xy 56.433941 -386.26557) (xy 56.395508 -386.238261) (xy 56.361736 -386.205361) (xy 56.33343 -386.167656)
			(xy 56.32196 -386.147056) (xy 56.321452 -386.146294) (xy 55.923688 -385.457954) (xy 55.911753 -385.435296)
			(xy 55.894823 -385.386965) (xy 55.886171 -385.336491) (xy 55.885588 -385.310888) (xy 55.343848 -385.310888)
			(xy 55.655972 -385.850892) (xy 55.668711 -385.874207) (xy 55.686801 -385.924157) (xy 55.696016 -385.976476)
			(xy 55.696612 -386.003038) (xy 55.696612 -386.003292) (xy 55.696154 -386.027285) (xy 55.688649 -386.07468)
			(xy 55.673822 -386.120317) (xy 55.652038 -386.163073) (xy 55.623834 -386.201894) (xy 55.589903 -386.235826)
			(xy 55.551083 -386.264032) (xy 55.508328 -386.285817) (xy 55.462691 -386.300646) (xy 55.415297 -386.308154)
			(xy 55.391304 -386.3086) (xy 55.36773 -386.308203) (xy 55.321142 -386.300962) (xy 55.276223 -386.286637)
			(xy 55.234045 -386.265569) (xy 55.195612 -386.23826) (xy 55.16184 -386.205361) (xy 55.133535 -386.167656)
			(xy 55.122064 -386.147056) (xy 55.121556 -386.146294) (xy 54.723792 -385.457954) (xy 54.711857 -385.435295)
			(xy 54.694927 -385.386965) (xy 54.686275 -385.336491) (xy 54.685692 -385.310888) (xy 54.143952 -385.310888)
			(xy 54.456076 -385.850892) (xy 54.468815 -385.874207) (xy 54.486905 -385.924157) (xy 54.49612 -385.976476)
			(xy 54.496716 -386.003038) (xy 54.496716 -386.003292) (xy 54.49623 -386.027283) (xy 54.488725 -386.074673)
			(xy 54.4739 -386.120306) (xy 54.452118 -386.163059) (xy 54.423916 -386.201877) (xy 54.389989 -386.235806)
			(xy 54.351172 -386.264009) (xy 54.308421 -386.285793) (xy 54.262789 -386.300622) (xy 54.215399 -386.308129)
			(xy 54.191408 -386.3086) (xy 54.167834 -386.3082) (xy 54.121246 -386.30096) (xy 54.076328 -386.286635)
			(xy 54.034149 -386.265567) (xy 53.995716 -386.238259) (xy 53.961944 -386.20536) (xy 53.933639 -386.167655)
			(xy 53.922168 -386.147056) (xy 53.92166 -386.146294) (xy 53.523896 -385.457954) (xy 53.511961 -385.435295)
			(xy 53.495031 -385.386965) (xy 53.486379 -385.336491) (xy 53.485796 -385.310888) (xy 52.943802 -385.310888)
			(xy 53.255926 -385.850892) (xy 53.26875 -385.874225) (xy 53.286971 -385.924247) (xy 53.296231 -385.976673)
			(xy 53.29682 -386.003292) (xy 53.296331 -386.02727) (xy 53.288835 -386.074636) (xy 53.274024 -386.120247)
			(xy 53.252265 -386.162982) (xy 53.224092 -386.201789) (xy 53.190197 -386.235713) (xy 53.151416 -386.263922)
			(xy 53.1087 -386.285719) (xy 53.063102 -386.30057) (xy 53.015743 -386.30811) (xy 52.991766 -386.3086)
			(xy 52.991258 -386.3086) (xy 52.967686 -386.308159) (xy 52.9211 -386.300927) (xy 52.876182 -386.286609)
			(xy 52.834004 -386.265548) (xy 52.79557 -386.238246) (xy 52.761797 -386.205353) (xy 52.73349 -386.167653)
			(xy 52.722018 -386.147056) (xy 52.72151 -386.146294) (xy 52.323746 -385.457954) (xy 52.311886 -385.435269)
			(xy 52.29503 -385.38694) (xy 52.28645 -385.33648) (xy 52.2859 -385.310888) (xy 51.743906 -385.310888)
			(xy 52.05603 -385.850892) (xy 52.068854 -385.874225) (xy 52.087075 -385.924247) (xy 52.096335 -385.976673)
			(xy 52.096924 -386.003292) (xy 52.096431 -386.02727) (xy 52.088935 -386.074635) (xy 52.074125 -386.120246)
			(xy 52.052366 -386.16298) (xy 52.024193 -386.201787) (xy 51.990299 -386.235712) (xy 51.951518 -386.26392)
			(xy 51.908803 -386.285718) (xy 51.863206 -386.30057) (xy 51.815847 -386.308109) (xy 51.79187 -386.3086)
			(xy 51.791362 -386.3086) (xy 51.76779 -386.308156) (xy 51.721204 -386.300924) (xy 51.676286 -386.286607)
			(xy 51.634108 -386.265547) (xy 51.595674 -386.238245) (xy 51.561901 -386.205352) (xy 51.533594 -386.167653)
			(xy 51.522122 -386.147056) (xy 51.521614 -386.146294) (xy 51.12385 -385.457954) (xy 51.111991 -385.435269)
			(xy 51.095134 -385.38694) (xy 51.086554 -385.33648) (xy 51.086004 -385.310888) (xy 50.543756 -385.310888)
			(xy 50.85588 -385.850892) (xy 50.868619 -385.874207) (xy 50.886709 -385.924157) (xy 50.895924 -385.976476)
			(xy 50.89652 -386.003038) (xy 50.89652 -386.003292) (xy 50.89603 -386.027282) (xy 50.888526 -386.074673)
			(xy 50.8737 -386.120306) (xy 50.851918 -386.163057) (xy 50.823717 -386.201876) (xy 50.789791 -386.235804)
			(xy 50.750974 -386.264008) (xy 50.708224 -386.285792) (xy 50.662592 -386.300621) (xy 50.615202 -386.308128)
			(xy 50.591212 -386.3086) (xy 50.567638 -386.308197) (xy 50.521051 -386.300957) (xy 50.476132 -386.286633)
			(xy 50.433954 -386.265566) (xy 50.395521 -386.238258) (xy 50.361749 -386.205359) (xy 50.333443 -386.167655)
			(xy 50.321972 -386.147056) (xy 50.321464 -386.146294) (xy 49.9237 -385.457954) (xy 49.911766 -385.435295)
			(xy 49.894835 -385.386965) (xy 49.886183 -385.336491) (xy 49.8856 -385.310888) (xy 49.34386 -385.310888)
			(xy 49.655984 -385.850892) (xy 49.668715 -385.874211) (xy 49.68681 -385.924158) (xy 49.696027 -385.976477)
			(xy 49.696624 -386.003038) (xy 49.696624 -386.003292) (xy 49.69613 -386.027282) (xy 49.688626 -386.074672)
			(xy 49.6738 -386.120305) (xy 49.652019 -386.163056) (xy 49.623818 -386.201874) (xy 49.589892 -386.235803)
			(xy 49.551077 -386.264007) (xy 49.508327 -386.285791) (xy 49.462695 -386.30062) (xy 49.415306 -386.308128)
			(xy 49.391316 -386.3086) (xy 49.367742 -386.308193) (xy 49.321155 -386.300954) (xy 49.276236 -386.286631)
			(xy 49.234058 -386.265564) (xy 49.195625 -386.238257) (xy 49.161853 -386.205359) (xy 49.133547 -386.167655)
			(xy 49.122076 -386.147056) (xy 49.121568 -386.146294) (xy 48.723804 -385.457954) (xy 48.71187 -385.435295)
			(xy 48.694939 -385.386965) (xy 48.686287 -385.336491) (xy 48.685704 -385.310888) (xy 48.143964 -385.310888)
			(xy 48.456088 -385.850892) (xy 48.46882 -385.874211) (xy 48.486915 -385.924158) (xy 48.496131 -385.976477)
			(xy 48.496728 -386.003038) (xy 48.496728 -386.003292) (xy 48.49623 -386.027282) (xy 48.488726 -386.074672)
			(xy 48.473901 -386.120304) (xy 48.45212 -386.163055) (xy 48.42392 -386.201873) (xy 48.389994 -386.235801)
			(xy 48.351179 -386.264005) (xy 48.30843 -386.28579) (xy 48.262799 -386.300619) (xy 48.21541 -386.308128)
			(xy 48.19142 -386.3086) (xy 48.167847 -386.30819) (xy 48.121259 -386.300952) (xy 48.076341 -386.286629)
			(xy 48.034162 -386.265563) (xy 47.995729 -386.238256) (xy 47.961957 -386.205358) (xy 47.933651 -386.167655)
			(xy 47.92218 -386.147056) (xy 47.921672 -386.146294) (xy 47.523908 -385.457954) (xy 47.511974 -385.435295)
			(xy 47.495043 -385.386965) (xy 47.486391 -385.336491) (xy 47.485808 -385.310888) (xy 2.509012 -385.310888)
			(xy 2.509012 -387.789674) (xy 40.901112 -387.789674) (xy 40.901112 -386.926074) (xy 40.901598 -386.898805)
			(xy 40.90936 -386.844821) (xy 40.924725 -386.792491) (xy 40.947382 -386.742881) (xy 40.976868 -386.697)
			(xy 41.012583 -386.655783) (xy 41.0538 -386.620068) (xy 41.099681 -386.590582) (xy 41.149291 -386.567925)
			(xy 41.201621 -386.55256) (xy 41.255605 -386.544798) (xy 41.310143 -386.544798) (xy 41.364127 -386.55256)
			(xy 41.416457 -386.567925) (xy 41.466067 -386.590582) (xy 41.511948 -386.620068) (xy 41.553165 -386.655783)
			(xy 41.58888 -386.697) (xy 41.618366 -386.742881) (xy 41.641023 -386.792491) (xy 41.656388 -386.844821)
			(xy 41.66415 -386.898805) (xy 41.664636 -386.926074) (xy 41.664636 -387.789674) (xy 73.42886 -387.789674)
			(xy 73.42886 -386.926074) (xy 73.429346 -386.898805) (xy 73.437108 -386.844821) (xy 73.452473 -386.792491)
			(xy 73.47513 -386.742881) (xy 73.504616 -386.697) (xy 73.540331 -386.655783) (xy 73.581548 -386.620068)
			(xy 73.627429 -386.590582) (xy 73.677039 -386.567925) (xy 73.729369 -386.55256) (xy 73.783353 -386.544798)
			(xy 73.837891 -386.544798) (xy 73.891875 -386.55256) (xy 73.944205 -386.567925) (xy 73.993815 -386.590582)
			(xy 74.039696 -386.620068) (xy 74.080913 -386.655783) (xy 74.116628 -386.697) (xy 74.146114 -386.742881)
			(xy 74.168771 -386.792491) (xy 74.184136 -386.844821) (xy 74.191898 -386.898805) (xy 74.192384 -386.926074)
			(xy 74.192384 -387.789674) (xy 108.001308 -387.789674) (xy 108.001308 -386.926074) (xy 108.001794 -386.898823)
			(xy 108.00955 -386.844875) (xy 108.024905 -386.79258) (xy 108.047547 -386.743003) (xy 108.077013 -386.697153)
			(xy 108.112704 -386.655962) (xy 108.153895 -386.620271) (xy 108.199745 -386.590805) (xy 108.249322 -386.568163)
			(xy 108.301617 -386.552808) (xy 108.355565 -386.545052) (xy 108.410067 -386.545052) (xy 108.464015 -386.552808)
			(xy 108.51631 -386.568163) (xy 108.565887 -386.590805) (xy 108.611737 -386.620271) (xy 108.652928 -386.655962)
			(xy 108.688619 -386.697153) (xy 108.718085 -386.743003) (xy 108.740727 -386.79258) (xy 108.756082 -386.844875)
			(xy 108.763838 -386.898823) (xy 108.764324 -386.926074) (xy 108.764324 -387.789674) (xy 140.529056 -387.789674)
			(xy 140.529056 -386.926074) (xy 140.529542 -386.898823) (xy 140.537298 -386.844875) (xy 140.552653 -386.79258)
			(xy 140.575295 -386.743003) (xy 140.604761 -386.697153) (xy 140.640452 -386.655962) (xy 140.681643 -386.620271)
			(xy 140.727493 -386.590805) (xy 140.77707 -386.568163) (xy 140.829365 -386.552808) (xy 140.883313 -386.545052)
			(xy 140.937815 -386.545052) (xy 140.991763 -386.552808) (xy 141.044058 -386.568163) (xy 141.093635 -386.590805)
			(xy 141.139485 -386.620271) (xy 141.180676 -386.655962) (xy 141.216367 -386.697153) (xy 141.245833 -386.743003)
			(xy 141.268475 -386.79258) (xy 141.28383 -386.844875) (xy 141.291586 -386.898823) (xy 141.292072 -386.926074)
			(xy 141.292072 -387.789674) (xy 141.291586 -387.816925) (xy 141.28383 -387.870873) (xy 141.268475 -387.923168)
			(xy 141.245833 -387.972745) (xy 141.216367 -388.018595) (xy 141.180676 -388.059786) (xy 141.139485 -388.095477)
			(xy 141.093635 -388.124943) (xy 141.044058 -388.147585) (xy 140.991763 -388.16294) (xy 140.937815 -388.170696)
			(xy 140.883313 -388.170696) (xy 140.829365 -388.16294) (xy 140.77707 -388.147585) (xy 140.727493 -388.124943)
			(xy 140.681643 -388.095477) (xy 140.640452 -388.059786) (xy 140.604761 -388.018595) (xy 140.575295 -387.972745)
			(xy 140.552653 -387.923168) (xy 140.537298 -387.870873) (xy 140.529542 -387.816925) (xy 140.529056 -387.789674)
			(xy 108.764324 -387.789674) (xy 108.763838 -387.816925) (xy 108.756082 -387.870873) (xy 108.740727 -387.923168)
			(xy 108.718085 -387.972745) (xy 108.688619 -388.018595) (xy 108.652928 -388.059786) (xy 108.611737 -388.095477)
			(xy 108.565887 -388.124943) (xy 108.51631 -388.147585) (xy 108.464015 -388.16294) (xy 108.410067 -388.170696)
			(xy 108.355565 -388.170696) (xy 108.301617 -388.16294) (xy 108.249322 -388.147585) (xy 108.199745 -388.124943)
			(xy 108.153895 -388.095477) (xy 108.112704 -388.059786) (xy 108.077013 -388.018595) (xy 108.047547 -387.972745)
			(xy 108.024905 -387.923168) (xy 108.00955 -387.870873) (xy 108.001794 -387.816925) (xy 108.001308 -387.789674)
			(xy 74.192384 -387.789674) (xy 74.191898 -387.816943) (xy 74.184136 -387.870927) (xy 74.168771 -387.923257)
			(xy 74.146114 -387.972867) (xy 74.116628 -388.018748) (xy 74.080913 -388.059965) (xy 74.039696 -388.09568)
			(xy 73.993815 -388.125166) (xy 73.944205 -388.147823) (xy 73.891875 -388.163188) (xy 73.837891 -388.17095)
			(xy 73.783353 -388.17095) (xy 73.729369 -388.163188) (xy 73.677039 -388.147823) (xy 73.627429 -388.125166)
			(xy 73.581548 -388.09568) (xy 73.540331 -388.059965) (xy 73.504616 -388.018748) (xy 73.47513 -387.972867)
			(xy 73.452473 -387.923257) (xy 73.437108 -387.870927) (xy 73.429346 -387.816943) (xy 73.42886 -387.789674)
			(xy 41.664636 -387.789674) (xy 41.66415 -387.816943) (xy 41.656388 -387.870927) (xy 41.641023 -387.923257)
			(xy 41.618366 -387.972867) (xy 41.58888 -388.018748) (xy 41.553165 -388.059965) (xy 41.511948 -388.09568)
			(xy 41.466067 -388.125166) (xy 41.416457 -388.147823) (xy 41.364127 -388.163188) (xy 41.310143 -388.17095)
			(xy 41.255605 -388.17095) (xy 41.201621 -388.163188) (xy 41.149291 -388.147823) (xy 41.099681 -388.125166)
			(xy 41.0538 -388.09568) (xy 41.012583 -388.059965) (xy 40.976868 -388.018748) (xy 40.947382 -387.972867)
			(xy 40.924725 -387.923257) (xy 40.90936 -387.870927) (xy 40.901598 -387.816943) (xy 40.901112 -387.789674)
			(xy 2.509012 -387.789674) (xy 2.509012 -388.797976) (xy 47.486325 -388.797976) (xy 47.486573 -388.747043)
			(xy 47.495267 -388.696858) (xy 47.512163 -388.648809) (xy 47.536795 -388.604229) (xy 47.56848 -388.564351)
			(xy 47.60634 -388.530281) (xy 47.649327 -388.502963) (xy 47.696249 -388.483153) (xy 47.745807 -388.471399)
			(xy 47.796628 -388.468029) (xy 47.847305 -388.473134) (xy 47.896432 -388.486573) (xy 47.942651 -388.507975)
			(xy 47.984679 -388.536747) (xy 48.021353 -388.57209) (xy 48.051657 -388.613027) (xy 48.063658 -388.635494)
			(xy 48.064166 -388.636764) (xy 48.15733 -388.797975) (xy 48.686228 -388.797975) (xy 48.686477 -388.747043)
			(xy 48.69517 -388.696859) (xy 48.712067 -388.648811) (xy 48.736698 -388.604231) (xy 48.768383 -388.564354)
			(xy 48.806242 -388.530284) (xy 48.849228 -388.502966) (xy 48.89615 -388.483156) (xy 48.945707 -388.471403)
			(xy 48.996528 -388.468032) (xy 49.047203 -388.473137) (xy 49.09633 -388.486576) (xy 49.142548 -388.507978)
			(xy 49.184575 -388.536748) (xy 49.221249 -388.572091) (xy 49.251553 -388.613027) (xy 49.263554 -388.635494)
			(xy 49.264062 -388.636764) (xy 49.330245 -388.751287) (xy 49.885901 -388.751287) (xy 49.893233 -388.703732)
			(xy 49.907928 -388.657914) (xy 49.929622 -388.614966) (xy 49.95778 -388.575949) (xy 49.991706 -388.541827)
			(xy 50.03056 -388.513445) (xy 50.073382 -388.491502) (xy 50.119114 -388.476543) (xy 50.166626 -388.468937)
			(xy 50.214742 -388.468871) (xy 50.262274 -388.476348) (xy 50.308047 -388.491183) (xy 50.350929 -388.513008)
			(xy 50.389861 -388.541284) (xy 50.423879 -388.575313) (xy 50.452143 -388.614254) (xy 50.46345 -388.635494)
			(xy 50.463958 -388.636764) (xy 50.53014 -388.751285) (xy 51.086146 -388.751285) (xy 51.093477 -388.703739)
			(xy 51.10817 -388.657929) (xy 51.129861 -388.614989) (xy 51.158013 -388.575979) (xy 51.191932 -388.541863)
			(xy 51.230779 -388.513485) (xy 51.273593 -388.491546) (xy 51.319317 -388.476589) (xy 51.366819 -388.468982)
			(xy 51.414927 -388.468915) (xy 51.462451 -388.476388) (xy 51.508216 -388.491218) (xy 51.551092 -388.513037)
			(xy 51.590018 -388.541306) (xy 51.624032 -388.575327) (xy 51.652294 -388.614258) (xy 51.6636 -388.635494)
			(xy 51.664108 -388.636764) (xy 51.730289 -388.751284) (xy 52.286049 -388.751284) (xy 52.293381 -388.703739)
			(xy 52.308073 -388.65793) (xy 52.329764 -388.614991) (xy 52.357916 -388.575981) (xy 52.391834 -388.541866)
			(xy 52.43068 -388.513488) (xy 52.473494 -388.49155) (xy 52.519217 -388.476592) (xy 52.566719 -388.468986)
			(xy 52.614826 -388.468918) (xy 52.662349 -388.476392) (xy 52.708114 -388.491221) (xy 52.750989 -388.513039)
			(xy 52.789914 -388.541308) (xy 52.823928 -388.575328) (xy 52.85219 -388.614259) (xy 52.863496 -388.635494)
			(xy 52.864004 -388.636764) (xy 52.930187 -388.751287) (xy 53.486104 -388.751287) (xy 53.493436 -388.703733)
			(xy 53.508131 -388.657915) (xy 53.529825 -388.614968) (xy 53.557983 -388.575951) (xy 53.591908 -388.54183)
			(xy 53.630761 -388.513448) (xy 53.673583 -388.491506) (xy 53.719314 -388.476547) (xy 53.766825 -388.468941)
			(xy 53.814941 -388.468875) (xy 53.862473 -388.476351) (xy 53.908245 -388.491185) (xy 53.951126 -388.51301)
			(xy 53.990057 -388.541286) (xy 54.024075 -388.575314) (xy 54.052339 -388.614254) (xy 54.063646 -388.635494)
			(xy 54.064154 -388.636764) (xy 54.130337 -388.751286) (xy 54.686008 -388.751286) (xy 54.69334 -388.703733)
			(xy 54.708035 -388.657917) (xy 54.729728 -388.61497) (xy 54.757886 -388.575954) (xy 54.79181 -388.541833)
			(xy 54.830663 -388.513451) (xy 54.873484 -388.491509) (xy 54.919215 -388.476551) (xy 54.966725 -388.468944)
			(xy 55.01484 -388.468878) (xy 55.062371 -388.476355) (xy 55.108142 -388.491188) (xy 55.151023 -388.513012)
			(xy 55.189954 -388.541288) (xy 55.223971 -388.575315) (xy 55.252235 -388.614254) (xy 55.263542 -388.635494)
			(xy 55.26405 -388.636764) (xy 55.330233 -388.751286) (xy 55.885912 -388.751286) (xy 55.893244 -388.703734)
			(xy 55.907938 -388.657918) (xy 55.929632 -388.614971) (xy 55.957788 -388.575956) (xy 55.991712 -388.541836)
			(xy 56.030564 -388.513454) (xy 56.073385 -388.491513) (xy 56.119115 -388.476554) (xy 56.166624 -388.468948)
			(xy 56.214739 -388.468882) (xy 56.262269 -388.476358) (xy 56.30804 -388.491191) (xy 56.35092 -388.513015)
			(xy 56.38985 -388.54129) (xy 56.423868 -388.575317) (xy 56.452131 -388.614255) (xy 56.463438 -388.635494)
			(xy 56.463946 -388.636764) (xy 56.530127 -388.751284) (xy 57.086156 -388.751284) (xy 57.093488 -388.70374)
			(xy 57.10818 -388.657933) (xy 57.12987 -388.614994) (xy 57.158021 -388.575986) (xy 57.191939 -388.541872)
			(xy 57.230784 -388.513495) (xy 57.273596 -388.491557) (xy 57.319317 -388.476599) (xy 57.366818 -388.468993)
			(xy 57.414924 -388.468925) (xy 57.462446 -388.476398) (xy 57.508209 -388.491226) (xy 57.551083 -388.513044)
			(xy 57.590007 -388.541311) (xy 57.624021 -388.57533) (xy 57.652282 -388.614259) (xy 57.663588 -388.635494)
			(xy 57.664096 -388.636764) (xy 57.730277 -388.751284) (xy 58.28606 -388.751284) (xy 58.293391 -388.703741)
			(xy 58.308083 -388.657934) (xy 58.329773 -388.614996) (xy 58.357924 -388.575988) (xy 58.391841 -388.541874)
			(xy 58.430685 -388.513498) (xy 58.473497 -388.49156) (xy 58.519217 -388.476603) (xy 58.566717 -388.468997)
			(xy 58.614822 -388.468929) (xy 58.662344 -388.476401) (xy 58.708107 -388.491229) (xy 58.75098 -388.513046)
			(xy 58.789904 -388.541313) (xy 58.823917 -388.575331) (xy 58.852178 -388.61426) (xy 58.863484 -388.635494)
			(xy 58.863992 -388.636764) (xy 58.930175 -388.751286) (xy 59.486115 -388.751286) (xy 59.493447 -388.703734)
			(xy 59.508141 -388.657919) (xy 59.529835 -388.614973) (xy 59.557991 -388.575958) (xy 59.591914 -388.541839)
			(xy 59.630766 -388.513457) (xy 59.673585 -388.491516) (xy 59.719315 -388.476558) (xy 59.766824 -388.468952)
			(xy 59.814937 -388.468885) (xy 59.862467 -388.476361) (xy 59.908237 -388.491194) (xy 59.951117 -388.513017)
			(xy 59.990047 -388.541291) (xy 60.024064 -388.575318) (xy 60.052327 -388.614255) (xy 60.063634 -388.635494)
			(xy 60.064142 -388.636764) (xy 60.130325 -388.751286) (xy 60.686019 -388.751286) (xy 60.693351 -388.703735)
			(xy 60.708045 -388.65792) (xy 60.729738 -388.614975) (xy 60.757893 -388.575961) (xy 60.791816 -388.541841)
			(xy 60.830667 -388.513461) (xy 60.873486 -388.49152) (xy 60.919215 -388.476561) (xy 60.966723 -388.468955)
			(xy 61.014836 -388.468889) (xy 61.062365 -388.476364) (xy 61.108135 -388.491197) (xy 61.151014 -388.513019)
			(xy 61.189943 -388.541293) (xy 61.22396 -388.575319) (xy 61.252223 -388.614255) (xy 61.26353 -388.635494)
			(xy 61.264038 -388.636764) (xy 61.330221 -388.751286) (xy 61.885922 -388.751286) (xy 61.893254 -388.703735)
			(xy 61.907948 -388.657921) (xy 61.929641 -388.614977) (xy 61.957796 -388.575963) (xy 61.991718 -388.541844)
			(xy 62.030569 -388.513464) (xy 62.073387 -388.491523) (xy 62.119115 -388.476565) (xy 62.166623 -388.468959)
			(xy 62.214735 -388.468892) (xy 62.262263 -388.476368) (xy 62.308032 -388.4912) (xy 62.350911 -388.513022)
			(xy 62.38984 -388.541295) (xy 62.423856 -388.57532) (xy 62.452119 -388.614256) (xy 62.463426 -388.635494)
			(xy 62.463934 -388.636764) (xy 62.530115 -388.751284) (xy 63.086167 -388.751284) (xy 63.093498 -388.703742)
			(xy 63.10819 -388.657936) (xy 63.129879 -388.615) (xy 63.158029 -388.575993) (xy 63.191945 -388.54188)
			(xy 63.230788 -388.513504) (xy 63.273598 -388.491567) (xy 63.319318 -388.47661) (xy 63.366816 -388.469004)
			(xy 63.41492 -388.468936) (xy 63.46244 -388.476408) (xy 63.508202 -388.491235) (xy 63.551074 -388.513051)
			(xy 63.589997 -388.541317) (xy 63.624009 -388.575333) (xy 63.65227 -388.61426) (xy 63.663576 -388.635494)
			(xy 63.664084 -388.636764) (xy 63.757251 -388.797979) (xy 64.286112 -388.797979) (xy 64.286361 -388.747044)
			(xy 64.295054 -388.696856) (xy 64.311952 -388.648805) (xy 64.336585 -388.604222) (xy 64.368271 -388.564342)
			(xy 64.406133 -388.530271) (xy 64.449122 -388.502951) (xy 64.496047 -388.48314) (xy 64.545608 -388.471387)
			(xy 64.596432 -388.468016) (xy 64.647111 -388.473122) (xy 64.696241 -388.486563) (xy 64.742461 -388.507967)
			(xy 64.784491 -388.53674) (xy 64.821166 -388.572086) (xy 64.851471 -388.613026) (xy 64.863472 -388.635494)
			(xy 64.86398 -388.636764) (xy 64.930163 -388.751286) (xy 65.486126 -388.751286) (xy 65.493458 -388.703736)
			(xy 65.508151 -388.657923) (xy 65.529844 -388.614979) (xy 65.557999 -388.575966) (xy 65.59192 -388.541847)
			(xy 65.63077 -388.513467) (xy 65.673588 -388.491527) (xy 65.719316 -388.476569) (xy 65.766822 -388.468962)
			(xy 65.814934 -388.468896) (xy 65.862461 -388.476371) (xy 65.90823 -388.491202) (xy 65.951108 -388.513024)
			(xy 65.990037 -388.541297) (xy 66.024053 -388.575321) (xy 66.052315 -388.614256) (xy 66.063622 -388.635494)
			(xy 66.06413 -388.636764) (xy 66.130312 -388.751285) (xy 80.01394 -388.751285) (xy 80.021272 -388.703738)
			(xy 80.035965 -388.657927) (xy 80.057656 -388.614986) (xy 80.085809 -388.575975) (xy 80.119729 -388.541859)
			(xy 80.158577 -388.51348) (xy 80.201392 -388.491541) (xy 80.247116 -388.476583) (xy 80.29462 -388.468977)
			(xy 80.342729 -388.46891) (xy 80.390254 -388.476384) (xy 80.43602 -388.491214) (xy 80.478896 -388.513033)
			(xy 80.517823 -388.541304) (xy 80.551837 -388.575325) (xy 80.5801 -388.614258) (xy 80.591406 -388.635494)
			(xy 80.591914 -388.636764) (xy 80.658096 -388.751285) (xy 81.213844 -388.751285) (xy 81.221175 -388.703738)
			(xy 81.235868 -388.657929) (xy 81.257559 -388.614988) (xy 81.285712 -388.575977) (xy 81.319631 -388.541862)
			(xy 81.358478 -388.513483) (xy 81.401293 -388.491544) (xy 81.447017 -388.476587) (xy 81.49452 -388.46898)
			(xy 81.542628 -388.468913) (xy 81.590152 -388.476387) (xy 81.635918 -388.491217) (xy 81.678793 -388.513036)
			(xy 81.717719 -388.541305) (xy 81.751734 -388.575326) (xy 81.779996 -388.614258) (xy 81.791302 -388.635494)
			(xy 81.79181 -388.636764) (xy 81.857992 -388.751285) (xy 82.413748 -388.751285) (xy 82.421079 -388.703739)
			(xy 82.435771 -388.65793) (xy 82.457462 -388.61499) (xy 82.485615 -388.57598) (xy 82.519533 -388.541864)
			(xy 82.55838 -388.513487) (xy 82.601194 -388.491548) (xy 82.646917 -388.47659) (xy 82.694419 -388.468984)
			(xy 82.742527 -388.468917) (xy 82.79005 -388.47639) (xy 82.835815 -388.491219) (xy 82.87869 -388.513038)
			(xy 82.917616 -388.541307) (xy 82.95163 -388.575327) (xy 82.979892 -388.614258) (xy 82.991198 -388.635494)
			(xy 82.991706 -388.636764) (xy 83.057889 -388.751287) (xy 83.613803 -388.751287) (xy 83.621135 -388.703732)
			(xy 83.635829 -388.657915) (xy 83.657524 -388.614967) (xy 83.685682 -388.57595) (xy 83.719607 -388.541829)
			(xy 83.75846 -388.513446) (xy 83.801282 -388.491504) (xy 83.847014 -388.476545) (xy 83.894525 -388.468939)
			(xy 83.942642 -388.468873) (xy 83.990174 -388.47635) (xy 84.035946 -388.491184) (xy 84.078828 -388.513009)
			(xy 84.117759 -388.541285) (xy 84.151777 -388.575314) (xy 84.180041 -388.614254) (xy 84.191348 -388.635494)
			(xy 84.191856 -388.636764) (xy 84.258039 -388.751287) (xy 84.813706 -388.751287) (xy 84.821038 -388.703733)
			(xy 84.835733 -388.657916) (xy 84.857427 -388.614969) (xy 84.885584 -388.575952) (xy 84.919509 -388.541831)
			(xy 84.958362 -388.513449) (xy 85.001183 -388.491508) (xy 85.046914 -388.476549) (xy 85.094425 -388.468942)
			(xy 85.14254 -388.468877) (xy 85.190072 -388.476353) (xy 85.235844 -388.491187) (xy 85.278725 -388.513011)
			(xy 85.317655 -388.541287) (xy 85.351673 -388.575315) (xy 85.379937 -388.614254) (xy 85.391244 -388.635494)
			(xy 85.391752 -388.636764) (xy 85.457933 -388.751284) (xy 86.013951 -388.751284) (xy 86.021282 -388.703739)
			(xy 86.035975 -388.657931) (xy 86.057665 -388.614992) (xy 86.085817 -388.575982) (xy 86.119735 -388.541867)
			(xy 86.158581 -388.51349) (xy 86.201394 -388.491551) (xy 86.247117 -388.476594) (xy 86.294619 -388.468988)
			(xy 86.342725 -388.46892) (xy 86.390248 -388.476393) (xy 86.436013 -388.491222) (xy 86.478887 -388.513041)
			(xy 86.517813 -388.541309) (xy 86.551826 -388.575329) (xy 86.580088 -388.614259) (xy 86.591394 -388.635494)
			(xy 86.591902 -388.636764) (xy 86.658083 -388.751284) (xy 87.213855 -388.751284) (xy 87.221186 -388.70374)
			(xy 87.235878 -388.657932) (xy 87.257568 -388.614993) (xy 87.28572 -388.575985) (xy 87.319638 -388.54187)
			(xy 87.358483 -388.513493) (xy 87.401295 -388.491555) (xy 87.447017 -388.476598) (xy 87.494518 -388.468991)
			(xy 87.542624 -388.468924) (xy 87.590147 -388.476397) (xy 87.63591 -388.491225) (xy 87.678784 -388.513043)
			(xy 87.717709 -388.541311) (xy 87.751722 -388.57533) (xy 87.779984 -388.614259) (xy 87.79129 -388.635494)
			(xy 87.791798 -388.636764) (xy 87.857979 -388.751284) (xy 88.413758 -388.751284) (xy 88.42109 -388.70374)
			(xy 88.435782 -388.657933) (xy 88.457471 -388.614995) (xy 88.485623 -388.575987) (xy 88.51954 -388.541873)
			(xy 88.558384 -388.513496) (xy 88.601196 -388.491558) (xy 88.646917 -388.476601) (xy 88.694418 -388.468995)
			(xy 88.742523 -388.468927) (xy 88.790045 -388.4764) (xy 88.835808 -388.491228) (xy 88.878681 -388.513045)
			(xy 88.917606 -388.541312) (xy 88.951619 -388.575331) (xy 88.97988 -388.614259) (xy 88.991186 -388.635494)
			(xy 88.991694 -388.636764) (xy 89.057877 -388.751286) (xy 89.613813 -388.751286) (xy 89.621145 -388.703734)
			(xy 89.63584 -388.657918) (xy 89.657533 -388.614972) (xy 89.68569 -388.575957) (xy 89.719613 -388.541837)
			(xy 89.758465 -388.513456) (xy 89.801285 -388.491515) (xy 89.847015 -388.476556) (xy 89.894524 -388.46895)
			(xy 89.942638 -388.468884) (xy 89.990168 -388.476359) (xy 90.035939 -388.491192) (xy 90.078819 -388.513016)
			(xy 90.117749 -388.54129) (xy 90.151766 -388.575317) (xy 90.180029 -388.614255) (xy 90.191336 -388.635494)
			(xy 90.191844 -388.636764) (xy 90.258027 -388.751286) (xy 90.813717 -388.751286) (xy 90.821049 -388.703734)
			(xy 90.835743 -388.65792) (xy 90.857436 -388.614974) (xy 90.885592 -388.57596) (xy 90.919515 -388.54184)
			(xy 90.958366 -388.513459) (xy 91.001186 -388.491518) (xy 91.046915 -388.47656) (xy 91.094423 -388.468953)
			(xy 91.142537 -388.468887) (xy 91.190066 -388.476363) (xy 91.235836 -388.491195) (xy 91.278716 -388.513018)
			(xy 91.317645 -388.541292) (xy 91.351662 -388.575318) (xy 91.379925 -388.614255) (xy 91.391232 -388.635494)
			(xy 91.39174 -388.636764) (xy 91.457921 -388.751284) (xy 92.013962 -388.751284) (xy 92.021293 -388.703741)
			(xy 92.035985 -388.657935) (xy 92.057674 -388.614997) (xy 92.085825 -388.575989) (xy 92.119742 -388.541876)
			(xy 92.158586 -388.5135) (xy 92.201397 -388.491562) (xy 92.247118 -388.476605) (xy 92.294617 -388.468999)
			(xy 92.342722 -388.468931) (xy 92.390243 -388.476403) (xy 92.436005 -388.491231) (xy 92.478878 -388.513048)
			(xy 92.517802 -388.541314) (xy 92.551815 -388.575332) (xy 92.580076 -388.61426) (xy 92.591382 -388.635494)
			(xy 92.59189 -388.636764) (xy 92.658071 -388.751284) (xy 93.213865 -388.751284) (xy 93.221197 -388.703741)
			(xy 93.235888 -388.657936) (xy 93.257577 -388.614999) (xy 93.285728 -388.575992) (xy 93.319644 -388.541879)
			(xy 93.358487 -388.513503) (xy 93.401298 -388.491565) (xy 93.447018 -388.476609) (xy 93.494517 -388.469002)
			(xy 93.542621 -388.468934) (xy 93.590141 -388.476406) (xy 93.635903 -388.491234) (xy 93.678775 -388.51305)
			(xy 93.717699 -388.541316) (xy 93.751711 -388.575333) (xy 93.779972 -388.61426) (xy 93.791278 -388.635494)
			(xy 93.791786 -388.636764) (xy 93.884953 -388.797979) (xy 94.413811 -388.797979) (xy 94.414059 -388.747044)
			(xy 94.422753 -388.696855) (xy 94.43965 -388.648804) (xy 94.464283 -388.604221) (xy 94.49597 -388.564341)
			(xy 94.533833 -388.530269) (xy 94.576822 -388.502949) (xy 94.623747 -388.483138) (xy 94.673308 -388.471385)
			(xy 94.724132 -388.468014) (xy 94.774811 -388.47312) (xy 94.823942 -388.486562) (xy 94.870162 -388.507966)
			(xy 94.912192 -388.536739) (xy 94.948868 -388.572086) (xy 94.979173 -388.613025) (xy 94.991174 -388.635494)
			(xy 94.991682 -388.636764) (xy 95.057865 -388.751286) (xy 95.613824 -388.751286) (xy 95.621156 -388.703735)
			(xy 95.63585 -388.657922) (xy 95.657542 -388.614978) (xy 95.685697 -388.575964) (xy 95.719619 -388.541846)
			(xy 95.75847 -388.513466) (xy 95.801288 -388.491525) (xy 95.847015 -388.476567) (xy 95.894522 -388.468961)
			(xy 95.942634 -388.468894) (xy 95.990162 -388.476369) (xy 96.035931 -388.491201) (xy 96.07881 -388.513023)
			(xy 96.117738 -388.541296) (xy 96.151754 -388.57532) (xy 96.180017 -388.614256) (xy 96.191324 -388.635494)
			(xy 96.191832 -388.636764) (xy 96.258014 -388.751285) (xy 96.813728 -388.751285) (xy 96.821059 -388.703736)
			(xy 96.835753 -388.657923) (xy 96.857445 -388.61498) (xy 96.8856 -388.575967) (xy 96.919522 -388.541849)
			(xy 96.958371 -388.513469) (xy 97.001189 -388.491529) (xy 97.046916 -388.476571) (xy 97.094422 -388.468964)
			(xy 97.142533 -388.468898) (xy 97.19006 -388.476372) (xy 97.235829 -388.491204) (xy 97.278707 -388.513025)
			(xy 97.317635 -388.541297) (xy 97.351651 -388.575321) (xy 97.379913 -388.614256) (xy 97.39122 -388.635494)
			(xy 97.391728 -388.636764) (xy 97.484894 -388.797978) (xy 98.014014 -388.797978) (xy 98.014263 -388.747044)
			(xy 98.022956 -388.696856) (xy 98.039853 -388.648805) (xy 98.064486 -388.604223) (xy 98.096173 -388.564344)
			(xy 98.134034 -388.530272) (xy 98.177023 -388.502953) (xy 98.223948 -388.483142) (xy 98.273508 -388.471388)
			(xy 98.324331 -388.468018) (xy 98.37501 -388.473124) (xy 98.424139 -388.486565) (xy 98.470359 -388.507968)
			(xy 98.512389 -388.536741) (xy 98.549064 -388.572087) (xy 98.579369 -388.613026) (xy 98.59137 -388.635494)
			(xy 98.591878 -388.636764) (xy 98.65806 -388.751285) (xy 114.586146 -388.751285) (xy 114.593477 -388.703739)
			(xy 114.60817 -388.657929) (xy 114.629861 -388.614989) (xy 114.658013 -388.575979) (xy 114.691932 -388.541863)
			(xy 114.730779 -388.513485) (xy 114.773593 -388.491546) (xy 114.819317 -388.476589) (xy 114.866819 -388.468982)
			(xy 114.914927 -388.468915) (xy 114.962451 -388.476388) (xy 115.008216 -388.491218) (xy 115.051092 -388.513037)
			(xy 115.090018 -388.541306) (xy 115.124032 -388.575327) (xy 115.152294 -388.614258) (xy 115.1636 -388.635494)
			(xy 115.164108 -388.636764) (xy 115.230289 -388.751284) (xy 115.786049 -388.751284) (xy 115.793381 -388.703739)
			(xy 115.808073 -388.65793) (xy 115.829764 -388.614991) (xy 115.857916 -388.575981) (xy 115.891834 -388.541866)
			(xy 115.93068 -388.513488) (xy 115.973494 -388.49155) (xy 116.019217 -388.476592) (xy 116.066719 -388.468986)
			(xy 116.114826 -388.468918) (xy 116.162349 -388.476392) (xy 116.208114 -388.491221) (xy 116.250989 -388.513039)
			(xy 116.289914 -388.541308) (xy 116.323928 -388.575328) (xy 116.35219 -388.614259) (xy 116.363496 -388.635494)
			(xy 116.364004 -388.636764) (xy 116.430185 -388.751284) (xy 116.985953 -388.751284) (xy 116.993284 -388.70374)
			(xy 117.007977 -388.657932) (xy 117.029667 -388.614992) (xy 117.057819 -388.575983) (xy 117.091737 -388.541869)
			(xy 117.130582 -388.513491) (xy 117.173395 -388.491553) (xy 117.219117 -388.476596) (xy 117.266618 -388.468989)
			(xy 117.314725 -388.468922) (xy 117.362247 -388.476395) (xy 117.408011 -388.491224) (xy 117.450886 -388.513042)
			(xy 117.489811 -388.54131) (xy 117.523824 -388.575329) (xy 117.552086 -388.614259) (xy 117.563392 -388.635494)
			(xy 117.5639 -388.636764) (xy 117.630083 -388.751286) (xy 118.186008 -388.751286) (xy 118.19334 -388.703733)
			(xy 118.208035 -388.657917) (xy 118.229728 -388.61497) (xy 118.257886 -388.575954) (xy 118.29181 -388.541833)
			(xy 118.330663 -388.513451) (xy 118.373484 -388.491509) (xy 118.419215 -388.476551) (xy 118.466725 -388.468944)
			(xy 118.51484 -388.468878) (xy 118.562371 -388.476355) (xy 118.608142 -388.491188) (xy 118.651023 -388.513012)
			(xy 118.689954 -388.541288) (xy 118.723971 -388.575315) (xy 118.752235 -388.614254) (xy 118.763542 -388.635494)
			(xy 118.76405 -388.636764) (xy 118.830233 -388.751286) (xy 119.385912 -388.751286) (xy 119.393244 -388.703734)
			(xy 119.407938 -388.657918) (xy 119.429632 -388.614971) (xy 119.457788 -388.575956) (xy 119.491712 -388.541836)
			(xy 119.530564 -388.513454) (xy 119.573385 -388.491513) (xy 119.619115 -388.476554) (xy 119.666624 -388.468948)
			(xy 119.714739 -388.468882) (xy 119.762269 -388.476358) (xy 119.80804 -388.491191) (xy 119.85092 -388.513015)
			(xy 119.88985 -388.54129) (xy 119.923868 -388.575317) (xy 119.952131 -388.614255) (xy 119.963438 -388.635494)
			(xy 119.963946 -388.636764) (xy 120.030127 -388.751284) (xy 120.586156 -388.751284) (xy 120.593488 -388.70374)
			(xy 120.60818 -388.657933) (xy 120.62987 -388.614994) (xy 120.658021 -388.575986) (xy 120.691939 -388.541872)
			(xy 120.730784 -388.513495) (xy 120.773596 -388.491557) (xy 120.819317 -388.476599) (xy 120.866818 -388.468993)
			(xy 120.914924 -388.468925) (xy 120.962446 -388.476398) (xy 121.008209 -388.491226) (xy 121.051083 -388.513044)
			(xy 121.090007 -388.541311) (xy 121.124021 -388.57533) (xy 121.152282 -388.614259) (xy 121.163588 -388.635494)
			(xy 121.164096 -388.636764) (xy 121.230277 -388.751284) (xy 121.78606 -388.751284) (xy 121.793391 -388.703741)
			(xy 121.808083 -388.657934) (xy 121.829773 -388.614996) (xy 121.857924 -388.575988) (xy 121.891841 -388.541874)
			(xy 121.930685 -388.513498) (xy 121.973497 -388.49156) (xy 122.019217 -388.476603) (xy 122.066717 -388.468997)
			(xy 122.114822 -388.468929) (xy 122.162344 -388.476401) (xy 122.208107 -388.491229) (xy 122.25098 -388.513046)
			(xy 122.289904 -388.541313) (xy 122.323917 -388.575331) (xy 122.352178 -388.61426) (xy 122.363484 -388.635494)
			(xy 122.363992 -388.636764) (xy 122.430173 -388.751284) (xy 122.985964 -388.751284) (xy 122.993295 -388.703741)
			(xy 123.007987 -388.657935) (xy 123.029676 -388.614998) (xy 123.057827 -388.575991) (xy 123.091743 -388.541877)
			(xy 123.130587 -388.513501) (xy 123.173398 -388.491564) (xy 123.219118 -388.476607) (xy 123.266617 -388.469)
			(xy 123.314721 -388.468932) (xy 123.362242 -388.476405) (xy 123.408004 -388.491232) (xy 123.450877 -388.513049)
			(xy 123.4898 -388.541315) (xy 123.523813 -388.575332) (xy 123.552074 -388.61426) (xy 123.56338 -388.635494)
			(xy 123.563888 -388.636764) (xy 123.630071 -388.751286) (xy 124.186019 -388.751286) (xy 124.193351 -388.703735)
			(xy 124.208045 -388.65792) (xy 124.229738 -388.614975) (xy 124.257893 -388.575961) (xy 124.291816 -388.541841)
			(xy 124.330667 -388.513461) (xy 124.373486 -388.49152) (xy 124.419215 -388.476561) (xy 124.466723 -388.468955)
			(xy 124.514836 -388.468889) (xy 124.562365 -388.476364) (xy 124.608135 -388.491197) (xy 124.651014 -388.513019)
			(xy 124.689943 -388.541293) (xy 124.72396 -388.575319) (xy 124.752223 -388.614255) (xy 124.76353 -388.635494)
			(xy 124.764038 -388.636764) (xy 124.830221 -388.751286) (xy 125.385922 -388.751286) (xy 125.393254 -388.703735)
			(xy 125.407948 -388.657921) (xy 125.429641 -388.614977) (xy 125.457796 -388.575963) (xy 125.491718 -388.541844)
			(xy 125.530569 -388.513464) (xy 125.573387 -388.491523) (xy 125.619115 -388.476565) (xy 125.666623 -388.468959)
			(xy 125.714735 -388.468892) (xy 125.762263 -388.476368) (xy 125.808032 -388.4912) (xy 125.850911 -388.513022)
			(xy 125.88984 -388.541295) (xy 125.923856 -388.57532) (xy 125.952119 -388.614256) (xy 125.963426 -388.635494)
			(xy 125.963934 -388.636764) (xy 126.030115 -388.751284) (xy 126.586167 -388.751284) (xy 126.593498 -388.703742)
			(xy 126.60819 -388.657936) (xy 126.629879 -388.615) (xy 126.658029 -388.575993) (xy 126.691945 -388.54188)
			(xy 126.730788 -388.513504) (xy 126.773598 -388.491567) (xy 126.819318 -388.47661) (xy 126.866816 -388.469004)
			(xy 126.91492 -388.468936) (xy 126.96244 -388.476408) (xy 127.008202 -388.491235) (xy 127.051074 -388.513051)
			(xy 127.089997 -388.541317) (xy 127.124009 -388.575333) (xy 127.15227 -388.61426) (xy 127.163576 -388.635494)
			(xy 127.164084 -388.636764) (xy 127.257251 -388.797979) (xy 127.786112 -388.797979) (xy 127.786361 -388.747044)
			(xy 127.795054 -388.696856) (xy 127.811952 -388.648805) (xy 127.836585 -388.604222) (xy 127.868271 -388.564342)
			(xy 127.906133 -388.530271) (xy 127.949122 -388.502951) (xy 127.996047 -388.48314) (xy 128.045608 -388.471387)
			(xy 128.096432 -388.468016) (xy 128.147111 -388.473122) (xy 128.196241 -388.486563) (xy 128.242461 -388.507967)
			(xy 128.284491 -388.53674) (xy 128.321166 -388.572086) (xy 128.351471 -388.613026) (xy 128.363472 -388.635494)
			(xy 128.36398 -388.636764) (xy 128.457146 -388.797978) (xy 128.986016 -388.797978) (xy 128.986265 -388.747044)
			(xy 128.994958 -388.696856) (xy 129.011855 -388.648806) (xy 129.036488 -388.604224) (xy 129.068174 -388.564345)
			(xy 129.106035 -388.530274) (xy 129.149024 -388.502955) (xy 129.195948 -388.483144) (xy 129.245508 -388.47139)
			(xy 129.296331 -388.46802) (xy 129.347009 -388.473125) (xy 129.396138 -388.486566) (xy 129.442358 -388.507969)
			(xy 129.484387 -388.536742) (xy 129.521062 -388.572087) (xy 129.551367 -388.613026) (xy 129.563368 -388.635494)
			(xy 129.563876 -388.636764) (xy 129.630058 -388.751285) (xy 130.18603 -388.751285) (xy 130.193361 -388.703736)
			(xy 130.208055 -388.657924) (xy 130.229747 -388.614981) (xy 130.257901 -388.575968) (xy 130.291823 -388.54185)
			(xy 130.330672 -388.51347) (xy 130.373489 -388.49153) (xy 130.419216 -388.476572) (xy 130.466722 -388.468966)
			(xy 130.514833 -388.468899) (xy 130.56236 -388.476374) (xy 130.608128 -388.491205) (xy 130.651005 -388.513026)
			(xy 130.689933 -388.541298) (xy 130.723949 -388.575322) (xy 130.752211 -388.614256) (xy 130.763518 -388.635494)
			(xy 130.764026 -388.636764) (xy 130.830208 -388.751285) (xy 131.385933 -388.751285) (xy 131.393265 -388.703737)
			(xy 131.407958 -388.657925) (xy 131.42965 -388.614982) (xy 131.457804 -388.57597) (xy 131.491725 -388.541853)
			(xy 131.530573 -388.513474) (xy 131.57339 -388.491534) (xy 131.619116 -388.476576) (xy 131.666621 -388.46897)
			(xy 131.714731 -388.468903) (xy 131.762258 -388.476377) (xy 131.808025 -388.491208) (xy 131.850902 -388.513029)
			(xy 131.88983 -388.5413) (xy 131.923845 -388.575323) (xy 131.952107 -388.614257) (xy 131.963414 -388.635494)
			(xy 131.963922 -388.636764) (xy 132.057087 -388.797977) (xy 132.586219 -388.797977) (xy 132.586468 -388.747044)
			(xy 132.595161 -388.696857) (xy 132.612058 -388.648807) (xy 132.636691 -388.604226) (xy 132.668376 -388.564348)
			(xy 132.706237 -388.530277) (xy 132.749225 -388.502958) (xy 132.796148 -388.483147) (xy 132.845708 -388.471394)
			(xy 132.89653 -388.468023) (xy 132.947207 -388.473129) (xy 132.996336 -388.486569) (xy 133.042555 -388.507972)
			(xy 133.084584 -388.536744) (xy 133.121258 -388.572088) (xy 133.151563 -388.613026) (xy 133.163564 -388.635494)
			(xy 133.164072 -388.636764) (xy 133.243924 -388.77494) (xy 147.113752 -388.77494) (xy 147.113752 -388.774432)
			(xy 147.114292 -388.750444) (xy 147.121792 -388.703057) (xy 147.136613 -388.657427) (xy 147.158389 -388.614677)
			(xy 147.186584 -388.57586) (xy 147.220505 -388.541931) (xy 147.259315 -388.513726) (xy 147.30206 -388.49194)
			(xy 147.347687 -388.477109) (xy 147.395072 -388.469598) (xy 147.41906 -388.469124) (xy 147.442996 -388.469555)
			(xy 147.490284 -388.477016) (xy 147.535829 -388.491761) (xy 147.578517 -388.51343) (xy 147.617303 -388.541492)
			(xy 147.651236 -388.57526) (xy 147.679488 -388.613908) (xy 147.69084 -388.634986) (xy 147.691348 -388.636002)
			(xy 147.771654 -388.77494) (xy 148.313648 -388.77494) (xy 148.313648 -388.774432) (xy 148.314192 -388.750444)
			(xy 148.321692 -388.703057) (xy 148.336512 -388.657428) (xy 148.358288 -388.614678) (xy 148.386483 -388.575861)
			(xy 148.420403 -388.541933) (xy 148.459213 -388.513728) (xy 148.501957 -388.491941) (xy 148.547583 -388.47711)
			(xy 148.594968 -388.469598) (xy 148.618956 -388.469124) (xy 148.642892 -388.469558) (xy 148.69018 -388.477018)
			(xy 148.735725 -388.491763) (xy 148.778413 -388.513431) (xy 148.817198 -388.541493) (xy 148.851132 -388.575261)
			(xy 148.879383 -388.613908) (xy 148.890736 -388.634986) (xy 148.891244 -388.636002) (xy 148.97155 -388.77494)
			(xy 149.513544 -388.77494) (xy 149.513544 -388.774432) (xy 149.514092 -388.750444) (xy 149.521592 -388.703058)
			(xy 149.536412 -388.657429) (xy 149.558187 -388.614679) (xy 149.586382 -388.575862) (xy 149.620301 -388.541934)
			(xy 149.659111 -388.513729) (xy 149.701855 -388.491943) (xy 149.74748 -388.477111) (xy 149.794864 -388.469598)
			(xy 149.818852 -388.469124) (xy 149.842788 -388.469561) (xy 149.890076 -388.477021) (xy 149.935621 -388.491765)
			(xy 149.978308 -388.513433) (xy 150.017094 -388.541494) (xy 150.051028 -388.575261) (xy 150.079279 -388.613908)
			(xy 150.090632 -388.634986) (xy 150.09114 -388.636002) (xy 150.171446 -388.77494) (xy 150.71344 -388.77494)
			(xy 150.71344 -388.774432) (xy 150.713891 -388.750452) (xy 150.721386 -388.703081) (xy 150.736197 -388.657465)
			(xy 150.757958 -388.614726) (xy 150.786136 -388.575917) (xy 150.820035 -388.54199) (xy 150.858823 -388.513783)
			(xy 150.901545 -388.491988) (xy 150.947149 -388.477142) (xy 150.994514 -388.46961) (xy 151.018494 -388.469124)
			(xy 151.019002 -388.469124) (xy 151.042937 -388.469602) (xy 151.090222 -388.477054) (xy 151.135766 -388.491791)
			(xy 151.178454 -388.513452) (xy 151.21724 -388.541507) (xy 151.251175 -388.575268) (xy 151.279429 -388.61391)
			(xy 151.290782 -388.634986) (xy 151.29129 -388.636002) (xy 151.371596 -388.77494) (xy 151.913336 -388.77494)
			(xy 151.913336 -388.774432) (xy 151.913791 -388.750452) (xy 151.921286 -388.703082) (xy 151.936096 -388.657466)
			(xy 151.957858 -388.614728) (xy 151.986034 -388.575918) (xy 152.019934 -388.541992) (xy 152.058721 -388.513784)
			(xy 152.101442 -388.491989) (xy 152.147046 -388.477143) (xy 152.19441 -388.46961) (xy 152.21839 -388.469124)
			(xy 152.218898 -388.469124) (xy 152.242835 -388.469524) (xy 152.290125 -388.476991) (xy 152.335671 -388.491741)
			(xy 152.378358 -388.513415) (xy 152.417143 -388.541482) (xy 152.451076 -388.575255) (xy 152.479326 -388.613906)
			(xy 152.490678 -388.634986) (xy 152.491186 -388.636002) (xy 152.571492 -388.77494) (xy 153.11374 -388.77494)
			(xy 153.11374 -388.774432) (xy 153.114168 -388.750437) (xy 153.121671 -388.703038) (xy 153.136498 -388.657397)
			(xy 153.158284 -388.614638) (xy 153.186491 -388.575814) (xy 153.220426 -388.541881) (xy 153.259251 -388.513676)
			(xy 153.302012 -388.491892) (xy 153.347654 -388.477068) (xy 153.395053 -388.469567) (xy 153.419048 -388.469124)
			(xy 153.442984 -388.469565) (xy 153.490271 -388.477024) (xy 153.535816 -388.491767) (xy 153.578504 -388.513434)
			(xy 153.61729 -388.541495) (xy 153.651224 -388.575262) (xy 153.679475 -388.613908) (xy 153.690828 -388.634986)
			(xy 153.691336 -388.636002) (xy 153.771642 -388.77494) (xy 154.313636 -388.77494) (xy 154.313636 -388.774432)
			(xy 154.314068 -388.750438) (xy 154.321571 -388.703039) (xy 154.336398 -388.657398) (xy 154.358183 -388.614639)
			(xy 154.38639 -388.575815) (xy 154.420324 -388.541882) (xy 154.459149 -388.513677) (xy 154.501909 -388.491893)
			(xy 154.547551 -388.477068) (xy 154.59495 -388.469567) (xy 154.618944 -388.469124) (xy 154.64288 -388.469568)
			(xy 154.690167 -388.477026) (xy 154.735712 -388.491769) (xy 154.7784 -388.513436) (xy 154.817185 -388.541496)
			(xy 154.851119 -388.575262) (xy 154.879371 -388.613909) (xy 154.890724 -388.634986) (xy 154.891232 -388.636002)
			(xy 154.971538 -388.77494) (xy 155.513532 -388.77494) (xy 155.513532 -388.774432) (xy 155.513968 -388.750438)
			(xy 155.521471 -388.703039) (xy 155.536298 -388.657399) (xy 155.558083 -388.61464) (xy 155.586289 -388.575816)
			(xy 155.620222 -388.541884) (xy 155.659047 -388.513678) (xy 155.701806 -388.491895) (xy 155.747447 -388.477069)
			(xy 155.794846 -388.469567) (xy 155.81884 -388.469124) (xy 155.842776 -388.469571) (xy 155.890063 -388.477029)
			(xy 155.935608 -388.491771) (xy 155.978295 -388.513437) (xy 156.017081 -388.541497) (xy 156.051015 -388.575263)
			(xy 156.079267 -388.613909) (xy 156.09062 -388.634986) (xy 156.091128 -388.636002) (xy 156.171434 -388.77494)
			(xy 156.713428 -388.77494) (xy 156.713428 -388.774432) (xy 156.713891 -388.750453) (xy 156.721386 -388.703083)
			(xy 156.736196 -388.657468) (xy 156.757956 -388.61473) (xy 156.786132 -388.575921) (xy 156.82003 -388.541995)
			(xy 156.858817 -388.513787) (xy 156.901537 -388.491991) (xy 156.947139 -388.477144) (xy 156.994503 -388.469611)
			(xy 157.018482 -388.469124) (xy 157.01899 -388.469124) (xy 157.042927 -388.46953) (xy 157.090216 -388.476996)
			(xy 157.135762 -388.491746) (xy 157.17845 -388.513419) (xy 157.217235 -388.541484) (xy 157.251168 -388.575256)
			(xy 157.279418 -388.613907) (xy 157.29077 -388.634986) (xy 157.291278 -388.636002) (xy 157.371584 -388.77494)
			(xy 157.913324 -388.77494) (xy 157.913324 -388.774432) (xy 157.913791 -388.750453) (xy 157.921286 -388.703083)
			(xy 157.936095 -388.657469) (xy 157.957855 -388.614731) (xy 157.986031 -388.575922) (xy 158.019929 -388.541996)
			(xy 158.058714 -388.513788) (xy 158.101434 -388.491993) (xy 158.147036 -388.477145) (xy 158.194399 -388.469611)
			(xy 158.218378 -388.469124) (xy 158.218886 -388.469124) (xy 158.242823 -388.469534) (xy 158.290112 -388.476998)
			(xy 158.335657 -388.491748) (xy 158.378345 -388.51342) (xy 158.41713 -388.541485) (xy 158.451064 -388.575256)
			(xy 158.479314 -388.613907) (xy 158.490666 -388.634986) (xy 158.491174 -388.636002) (xy 158.57148 -388.77494)
			(xy 159.113728 -388.77494) (xy 159.113728 -388.774432) (xy 159.114168 -388.750438) (xy 159.121671 -388.70304)
			(xy 159.136497 -388.6574) (xy 159.158282 -388.614641) (xy 159.186488 -388.575818) (xy 159.220421 -388.541885)
			(xy 159.259245 -388.51368) (xy 159.302004 -388.491896) (xy 159.347644 -388.47707) (xy 159.395042 -388.469568)
			(xy 159.419036 -388.469124) (xy 159.442972 -388.469574) (xy 159.490258 -388.477031) (xy 159.535803 -388.491773)
			(xy 159.578491 -388.513439) (xy 159.617277 -388.541498) (xy 159.651211 -388.575264) (xy 159.679463 -388.613909)
			(xy 159.690816 -388.634986) (xy 159.691324 -388.636002) (xy 159.77163 -388.77494) (xy 160.313624 -388.77494)
			(xy 160.313624 -388.774432) (xy 160.314068 -388.750438) (xy 160.321571 -388.703041) (xy 160.336397 -388.657401)
			(xy 160.358181 -388.614643) (xy 160.386387 -388.575819) (xy 160.420319 -388.541887) (xy 160.459143 -388.513681)
			(xy 160.501901 -388.491897) (xy 160.547541 -388.477071) (xy 160.594938 -388.469568) (xy 160.618932 -388.469124)
			(xy 160.642868 -388.469578) (xy 160.690154 -388.477034) (xy 160.735699 -388.491775) (xy 160.778387 -388.51344)
			(xy 160.817172 -388.541499) (xy 160.851107 -388.575264) (xy 160.879359 -388.613909) (xy 160.890712 -388.634986)
			(xy 160.89122 -388.636002) (xy 160.971526 -388.77494) (xy 161.51352 -388.77494) (xy 161.51352 -388.774432)
			(xy 161.513968 -388.750438) (xy 161.521471 -388.703041) (xy 161.536297 -388.657402) (xy 161.55808 -388.614644)
			(xy 161.586286 -388.57582) (xy 161.620217 -388.541888) (xy 161.65904 -388.513682) (xy 161.701798 -388.491898)
			(xy 161.747437 -388.477072) (xy 161.794834 -388.469568) (xy 161.818828 -388.469124) (xy 161.842763 -388.469581)
			(xy 161.89005 -388.477037) (xy 161.935595 -388.491777) (xy 161.978282 -388.513442) (xy 162.017068 -388.5415)
			(xy 162.051003 -388.575265) (xy 162.079255 -388.613909) (xy 162.090608 -388.634986) (xy 162.091116 -388.636002)
			(xy 162.171422 -388.77494) (xy 162.713416 -388.77494) (xy 162.713416 -388.774432) (xy 162.713891 -388.750453)
			(xy 162.721385 -388.703085) (xy 162.736194 -388.657471) (xy 162.757954 -388.614734) (xy 162.786129 -388.575925)
			(xy 162.820025 -388.541999) (xy 162.85881 -388.513791) (xy 162.901528 -388.491995) (xy 162.947129 -388.477147)
			(xy 162.994492 -388.469612) (xy 163.01847 -388.469124) (xy 163.018978 -388.469124) (xy 163.042915 -388.46954)
			(xy 163.090203 -388.477004) (xy 163.135749 -388.491752) (xy 163.178437 -388.513423) (xy 163.217222 -388.541487)
			(xy 163.251155 -388.575258) (xy 163.279406 -388.613907) (xy 163.290758 -388.634986) (xy 163.291266 -388.636002)
			(xy 163.371572 -388.77494) (xy 163.913312 -388.77494) (xy 163.913312 -388.774432) (xy 163.913791 -388.750453)
			(xy 163.921285 -388.703085) (xy 163.936094 -388.657472) (xy 163.957853 -388.614735) (xy 163.986027 -388.575926)
			(xy 164.019924 -388.542) (xy 164.058708 -388.513792) (xy 164.101425 -388.491996) (xy 164.147026 -388.477147)
			(xy 164.194388 -388.469612) (xy 164.218366 -388.469124) (xy 164.218874 -388.469124) (xy 164.242811 -388.469543)
			(xy 164.290099 -388.477006) (xy 164.335644 -388.491754) (xy 164.378332 -388.513425) (xy 164.417118 -388.541488)
			(xy 164.451051 -388.575258) (xy 164.479302 -388.613907) (xy 164.490654 -388.634986) (xy 164.491162 -388.636002)
			(xy 164.571468 -388.77494) (xy 165.113716 -388.77494) (xy 165.113716 -388.774432) (xy 165.114168 -388.750439)
			(xy 165.121671 -388.703042) (xy 165.136496 -388.657403) (xy 165.15828 -388.614645) (xy 165.186484 -388.575822)
			(xy 165.220416 -388.54189) (xy 165.259238 -388.513684) (xy 165.301995 -388.491899) (xy 165.347634 -388.477072)
			(xy 165.395031 -388.469568) (xy 165.419024 -388.469124) (xy 165.442959 -388.469584) (xy 165.490246 -388.477039)
			(xy 165.53579 -388.491779) (xy 165.578478 -388.513444) (xy 165.617264 -388.541501) (xy 165.651198 -388.575265)
			(xy 165.679451 -388.61391) (xy 165.690804 -388.634986) (xy 165.691312 -388.636002) (xy 165.744132 -388.727385)
			(xy 193.900548 -388.727385) (xy 193.900548 -388.642663) (xy 193.908601 -388.558326) (xy 193.924635 -388.475136)
			(xy 193.948503 -388.393846) (xy 193.979991 -388.315194) (xy 194.018813 -388.239891) (xy 194.064616 -388.168619)
			(xy 194.116987 -388.102023) (xy 194.175452 -388.040708) (xy 194.23948 -387.985227) (xy 194.308492 -387.936084)
			(xy 194.381862 -387.893724) (xy 194.458927 -387.858529) (xy 194.538989 -387.83082) (xy 194.621322 -387.810846)
			(xy 194.705181 -387.798789) (xy 194.789806 -387.794758) (xy 194.874431 -387.798789) (xy 194.95829 -387.810846)
			(xy 195.040623 -387.83082) (xy 195.120685 -387.858529) (xy 195.19775 -387.893724) (xy 195.27112 -387.936084)
			(xy 195.340132 -387.985227) (xy 195.40416 -388.040708) (xy 195.462625 -388.102023) (xy 195.514996 -388.168619)
			(xy 195.560799 -388.239891) (xy 195.599621 -388.315194) (xy 195.631109 -388.393846) (xy 195.654977 -388.475136)
			(xy 195.671011 -388.558326) (xy 195.679064 -388.642663) (xy 195.679568 -388.685024) (xy 195.679064 -388.727385)
			(xy 195.671011 -388.811722) (xy 195.654977 -388.894912) (xy 195.631109 -388.976202) (xy 195.599621 -389.054854)
			(xy 195.560799 -389.130157) (xy 195.514996 -389.201429) (xy 195.462625 -389.268025) (xy 195.40416 -389.32934)
			(xy 195.340132 -389.384821) (xy 195.27112 -389.433964) (xy 195.19775 -389.476324) (xy 195.120685 -389.511519)
			(xy 195.040623 -389.539228) (xy 194.95829 -389.559202) (xy 194.874431 -389.571259) (xy 194.789806 -389.575291)
			(xy 194.705181 -389.571259) (xy 194.621322 -389.559202) (xy 194.538989 -389.539228) (xy 194.458927 -389.511519)
			(xy 194.381862 -389.476324) (xy 194.308492 -389.433964) (xy 194.23948 -389.384821) (xy 194.175452 -389.32934)
			(xy 194.116987 -389.268025) (xy 194.064616 -389.201429) (xy 194.018813 -389.130157) (xy 193.979991 -389.054854)
			(xy 193.948503 -388.976202) (xy 193.924635 -388.894912) (xy 193.908601 -388.811722) (xy 193.900548 -388.727385)
			(xy 165.744132 -388.727385) (xy 166.083742 -389.314944) (xy 166.096549 -389.338286) (xy 166.114776 -389.388304)
			(xy 166.124043 -389.440727) (xy 166.124636 -389.467344) (xy 166.124179 -389.491322) (xy 166.116675 -389.538688)
			(xy 166.101859 -389.584299) (xy 166.080095 -389.627033) (xy 166.051917 -389.665839) (xy 166.01802 -389.699762)
			(xy 165.979236 -389.72797) (xy 165.936519 -389.749768) (xy 165.89092 -389.76462) (xy 165.84356 -389.77216)
			(xy 165.819582 -389.772652) (xy 165.819074 -389.772652) (xy 165.795501 -389.772252) (xy 165.748914 -389.765008)
			(xy 165.703997 -389.750681) (xy 165.66182 -389.729613) (xy 165.623387 -389.702305) (xy 165.589614 -389.669408)
			(xy 165.561306 -389.631706) (xy 165.549834 -389.611108) (xy 165.549326 -389.610346) (xy 165.151562 -388.922006)
			(xy 165.139686 -388.899329) (xy 165.122835 -388.850996) (xy 165.114262 -388.800533) (xy 165.113716 -388.77494)
			(xy 164.571468 -388.77494) (xy 164.883592 -389.314944) (xy 164.896306 -389.338272) (xy 164.914407 -389.388215)
			(xy 164.923631 -389.44053) (xy 164.924232 -389.46709) (xy 164.924232 -389.467344) (xy 164.923778 -389.491335)
			(xy 164.916266 -389.538726) (xy 164.901434 -389.584359) (xy 164.879647 -389.62711) (xy 164.851442 -389.665927)
			(xy 164.817512 -389.699855) (xy 164.778693 -389.728058) (xy 164.73594 -389.749842) (xy 164.690307 -389.764671)
			(xy 164.642915 -389.77218) (xy 164.618924 -389.772652) (xy 164.595352 -389.772211) (xy 164.548767 -389.764975)
			(xy 164.503851 -389.750656) (xy 164.461674 -389.729594) (xy 164.423241 -389.702292) (xy 164.389467 -389.669401)
			(xy 164.361157 -389.631704) (xy 164.349684 -389.611108) (xy 164.349176 -389.610346) (xy 163.951412 -388.922006)
			(xy 163.939498 -388.899337) (xy 163.92256 -388.851012) (xy 163.9139 -388.800542) (xy 163.913312 -388.77494)
			(xy 163.371572 -388.77494) (xy 163.683696 -389.314944) (xy 163.69641 -389.338271) (xy 163.714511 -389.388215)
			(xy 163.723735 -389.44053) (xy 163.724336 -389.46709) (xy 163.724336 -389.467344) (xy 163.723878 -389.491335)
			(xy 163.716366 -389.538726) (xy 163.701535 -389.584358) (xy 163.679748 -389.627109) (xy 163.651543 -389.665926)
			(xy 163.617613 -389.699853) (xy 163.578795 -389.728056) (xy 163.536043 -389.749841) (xy 163.49041 -389.76467)
			(xy 163.443019 -389.772179) (xy 163.419028 -389.772652) (xy 163.395456 -389.772208) (xy 163.348872 -389.764972)
			(xy 163.303956 -389.750653) (xy 163.261778 -389.729592) (xy 163.223345 -389.702291) (xy 163.189571 -389.6694)
			(xy 163.161261 -389.631704) (xy 163.149788 -389.611108) (xy 163.14928 -389.610346) (xy 162.751516 -388.922006)
			(xy 162.739602 -388.899337) (xy 162.722664 -388.851012) (xy 162.714004 -388.800542) (xy 162.713416 -388.77494)
			(xy 162.171422 -388.77494) (xy 162.483546 -389.314944) (xy 162.496353 -389.338286) (xy 162.51458 -389.388304)
			(xy 162.523847 -389.440727) (xy 162.52444 -389.467344) (xy 162.523979 -389.491322) (xy 162.516475 -389.538688)
			(xy 162.501659 -389.584298) (xy 162.479895 -389.627032) (xy 162.451718 -389.665837) (xy 162.417822 -389.699761)
			(xy 162.379038 -389.727969) (xy 162.336322 -389.749767) (xy 162.290724 -389.764619) (xy 162.243364 -389.77216)
			(xy 162.219386 -389.772652) (xy 162.218878 -389.772652) (xy 162.195305 -389.772249) (xy 162.148718 -389.765005)
			(xy 162.103801 -389.750679) (xy 162.061624 -389.729611) (xy 162.023191 -389.702304) (xy 161.989418 -389.669408)
			(xy 161.96111 -389.631706) (xy 161.949638 -389.611108) (xy 161.94913 -389.610346) (xy 161.551366 -388.922006)
			(xy 161.539491 -388.899329) (xy 161.522639 -388.850996) (xy 161.514066 -388.800533) (xy 161.51352 -388.77494)
			(xy 160.971526 -388.77494) (xy 161.28365 -389.314944) (xy 161.296457 -389.338285) (xy 161.314684 -389.388304)
			(xy 161.323951 -389.440726) (xy 161.324544 -389.467344) (xy 161.324079 -389.491322) (xy 161.316576 -389.538687)
			(xy 161.30176 -389.584297) (xy 161.279996 -389.62703) (xy 161.25182 -389.665836) (xy 161.217923 -389.69976)
			(xy 161.17914 -389.727967) (xy 161.136425 -389.749765) (xy 161.090827 -389.764618) (xy 161.043468 -389.77216)
			(xy 161.01949 -389.772652) (xy 161.018982 -389.772652) (xy 160.995409 -389.772245) (xy 160.948822 -389.765003)
			(xy 160.903906 -389.750677) (xy 160.861728 -389.72961) (xy 160.823295 -389.702303) (xy 160.789523 -389.669407)
			(xy 160.761214 -389.631706) (xy 160.749742 -389.611108) (xy 160.749234 -389.610346) (xy 160.35147 -388.922006)
			(xy 160.339595 -388.899329) (xy 160.322743 -388.850996) (xy 160.31417 -388.800533) (xy 160.313624 -388.77494)
			(xy 159.77163 -388.77494) (xy 160.083754 -389.314944) (xy 160.096562 -389.338285) (xy 160.114788 -389.388304)
			(xy 160.124055 -389.440726) (xy 160.124648 -389.467344) (xy 160.124179 -389.491322) (xy 160.116676 -389.538687)
			(xy 160.10186 -389.584296) (xy 160.080097 -389.627029) (xy 160.051921 -389.665835) (xy 160.018025 -389.699758)
			(xy 159.979243 -389.727966) (xy 159.936528 -389.749764) (xy 159.89093 -389.764617) (xy 159.843571 -389.772159)
			(xy 159.819594 -389.772652) (xy 159.819086 -389.772652) (xy 159.795513 -389.772242) (xy 159.748927 -389.765)
			(xy 159.70401 -389.750675) (xy 159.661833 -389.729608) (xy 159.6234 -389.702302) (xy 159.589627 -389.669406)
			(xy 159.561319 -389.631705) (xy 159.549846 -389.611108) (xy 159.549338 -389.610346) (xy 159.151574 -388.922006)
			(xy 159.139699 -388.899329) (xy 159.122848 -388.850996) (xy 159.114274 -388.800533) (xy 159.113728 -388.77494)
			(xy 158.57148 -388.77494) (xy 158.883604 -389.314944) (xy 158.896319 -389.338271) (xy 158.91442 -389.388214)
			(xy 158.923643 -389.44053) (xy 158.924244 -389.46709) (xy 158.924244 -389.467344) (xy 158.923778 -389.491335)
			(xy 158.916267 -389.538724) (xy 158.901435 -389.584356) (xy 158.879649 -389.627106) (xy 158.851445 -389.665923)
			(xy 158.817517 -389.69985) (xy 158.778699 -389.728054) (xy 158.735949 -389.749838) (xy 158.690317 -389.764668)
			(xy 158.642927 -389.772179) (xy 158.618936 -389.772652) (xy 158.595364 -389.772202) (xy 158.54878 -389.764967)
			(xy 158.503864 -389.750649) (xy 158.461687 -389.729589) (xy 158.423253 -389.702289) (xy 158.389479 -389.669399)
			(xy 158.361169 -389.631703) (xy 158.349696 -389.611108) (xy 158.349188 -389.610346) (xy 157.951424 -388.922006)
			(xy 157.939511 -388.899337) (xy 157.922572 -388.851012) (xy 157.913912 -388.800542) (xy 157.913324 -388.77494)
			(xy 157.371584 -388.77494) (xy 157.683708 -389.314944) (xy 157.696423 -389.338271) (xy 157.714524 -389.388214)
			(xy 157.723747 -389.44053) (xy 157.724348 -389.46709) (xy 157.724348 -389.467344) (xy 157.723878 -389.491334)
			(xy 157.716367 -389.538724) (xy 157.701536 -389.584355) (xy 157.67975 -389.627105) (xy 157.651546 -389.665922)
			(xy 157.617618 -389.699849) (xy 157.578802 -389.728052) (xy 157.536051 -389.749837) (xy 157.49042 -389.764668)
			(xy 157.44303 -389.772178) (xy 157.41904 -389.772652) (xy 157.395469 -389.772199) (xy 157.348884 -389.764965)
			(xy 157.303969 -389.750647) (xy 157.261791 -389.729588) (xy 157.223358 -389.702288) (xy 157.189583 -389.669399)
			(xy 157.161273 -389.631703) (xy 157.1498 -389.611108) (xy 157.149292 -389.610346) (xy 156.751528 -388.922006)
			(xy 156.739615 -388.899337) (xy 156.722676 -388.851012) (xy 156.714016 -388.800542) (xy 156.713428 -388.77494)
			(xy 156.171434 -388.77494) (xy 156.483558 -389.314944) (xy 156.496366 -389.338285) (xy 156.514592 -389.388304)
			(xy 156.523859 -389.440726) (xy 156.524452 -389.467344) (xy 156.523979 -389.491322) (xy 156.516476 -389.538686)
			(xy 156.501661 -389.584295) (xy 156.479898 -389.627028) (xy 156.451722 -389.665833) (xy 156.417827 -389.699757)
			(xy 156.379045 -389.727965) (xy 156.33633 -389.749763) (xy 156.290733 -389.764616) (xy 156.243375 -389.772159)
			(xy 156.219398 -389.772652) (xy 156.21889 -389.772652) (xy 156.195317 -389.772239) (xy 156.148731 -389.764997)
			(xy 156.103814 -389.750673) (xy 156.061637 -389.729607) (xy 156.023204 -389.702301) (xy 155.989431 -389.669406)
			(xy 155.961123 -389.631705) (xy 155.94965 -389.611108) (xy 155.949142 -389.610346) (xy 155.551378 -388.922006)
			(xy 155.539503 -388.899328) (xy 155.522652 -388.850996) (xy 155.514078 -388.800533) (xy 155.513532 -388.77494)
			(xy 154.971538 -388.77494) (xy 155.283662 -389.314944) (xy 155.29647 -389.338285) (xy 155.314696 -389.388304)
			(xy 155.323963 -389.440726) (xy 155.324556 -389.467344) (xy 155.324079 -389.491321) (xy 155.316576 -389.538686)
			(xy 155.301761 -389.584295) (xy 155.279998 -389.627027) (xy 155.251823 -389.665832) (xy 155.217928 -389.699755)
			(xy 155.179147 -389.727963) (xy 155.136433 -389.749762) (xy 155.090837 -389.764616) (xy 155.043479 -389.772159)
			(xy 155.019502 -389.772652) (xy 155.018994 -389.772652) (xy 154.995421 -389.772236) (xy 154.948835 -389.764995)
			(xy 154.903919 -389.750671) (xy 154.861741 -389.729605) (xy 154.823308 -389.7023) (xy 154.789535 -389.669405)
			(xy 154.761227 -389.631705) (xy 154.749754 -389.611108) (xy 154.749246 -389.610346) (xy 154.351482 -388.922006)
			(xy 154.339608 -388.899328) (xy 154.322756 -388.850996) (xy 154.314182 -388.800533) (xy 154.313636 -388.77494)
			(xy 153.771642 -388.77494) (xy 154.083766 -389.314944) (xy 154.096575 -389.338285) (xy 154.1148 -389.388303)
			(xy 154.124067 -389.440726) (xy 154.12466 -389.467344) (xy 154.124279 -389.491326) (xy 154.116773 -389.5387)
			(xy 154.101952 -389.584317) (xy 154.080181 -389.627055) (xy 154.051995 -389.665865) (xy 154.018088 -389.69979)
			(xy 153.979294 -389.727996) (xy 153.936567 -389.74979) (xy 153.890957 -389.764635) (xy 153.843588 -389.772166)
			(xy 153.819606 -389.772652) (xy 153.819098 -389.772652) (xy 153.795525 -389.772232) (xy 153.74894 -389.764992)
			(xy 153.704023 -389.750669) (xy 153.661846 -389.729604) (xy 153.623413 -389.702299) (xy 153.589639 -389.669405)
			(xy 153.561331 -389.631705) (xy 153.549858 -389.611108) (xy 153.54935 -389.610346) (xy 153.151586 -388.922006)
			(xy 153.139712 -388.899328) (xy 153.12286 -388.850996) (xy 153.114286 -388.800533) (xy 153.11374 -388.77494)
			(xy 152.571492 -388.77494) (xy 152.883616 -389.314944) (xy 152.896332 -389.338271) (xy 152.914432 -389.388214)
			(xy 152.923655 -389.44053) (xy 152.924256 -389.46709) (xy 152.924256 -389.467344) (xy 152.923778 -389.491334)
			(xy 152.916267 -389.538723) (xy 152.901436 -389.584353) (xy 152.879652 -389.627103) (xy 152.851449 -389.665919)
			(xy 152.817522 -389.699846) (xy 152.778706 -389.72805) (xy 152.735957 -389.749835) (xy 152.690327 -389.764666)
			(xy 152.642938 -389.772178) (xy 152.618948 -389.772652) (xy 152.595377 -389.772192) (xy 152.548793 -389.764959)
			(xy 152.503877 -389.750643) (xy 152.4617 -389.729585) (xy 152.423266 -389.702286) (xy 152.389492 -389.669398)
			(xy 152.361182 -389.631703) (xy 152.349708 -389.611108) (xy 152.3492 -389.610346) (xy 151.951436 -388.922006)
			(xy 151.939523 -388.899336) (xy 151.922584 -388.851012) (xy 151.913924 -388.800542) (xy 151.913336 -388.77494)
			(xy 151.371596 -388.77494) (xy 151.68372 -389.314944) (xy 151.696436 -389.33827) (xy 151.714536 -389.388214)
			(xy 151.723759 -389.44053) (xy 151.72436 -389.46709) (xy 151.72436 -389.467344) (xy 151.724002 -389.491341)
			(xy 151.716487 -389.538742) (xy 151.70165 -389.584385) (xy 151.679855 -389.627144) (xy 151.651639 -389.665968)
			(xy 151.617698 -389.699899) (xy 151.578866 -389.728103) (xy 151.5361 -389.749885) (xy 151.490453 -389.764709)
			(xy 151.443049 -389.772209) (xy 151.419052 -389.772652) (xy 151.395481 -389.772189) (xy 151.348897 -389.764957)
			(xy 151.303982 -389.750641) (xy 151.261804 -389.729583) (xy 151.223371 -389.702285) (xy 151.189596 -389.669397)
			(xy 151.161286 -389.631703) (xy 151.149812 -389.611108) (xy 151.149304 -389.610346) (xy 150.75154 -388.922006)
			(xy 150.739628 -388.899336) (xy 150.722688 -388.851012) (xy 150.714028 -388.800542) (xy 150.71344 -388.77494)
			(xy 150.171446 -388.77494) (xy 150.48357 -389.314944) (xy 150.496379 -389.338285) (xy 150.514604 -389.388303)
			(xy 150.523871 -389.440726) (xy 150.524464 -389.467344) (xy 150.524079 -389.491326) (xy 150.516573 -389.538699)
			(xy 150.501752 -389.584316) (xy 150.479981 -389.627054) (xy 150.451796 -389.665863) (xy 150.41789 -389.699788)
			(xy 150.379096 -389.727994) (xy 150.336369 -389.749788) (xy 150.290761 -389.764634) (xy 150.243392 -389.772166)
			(xy 150.21941 -389.772652) (xy 150.218902 -389.772652) (xy 150.195329 -389.772229) (xy 150.148744 -389.76499)
			(xy 150.103827 -389.750667) (xy 150.06165 -389.729602) (xy 150.023217 -389.702298) (xy 149.989444 -389.669404)
			(xy 149.961135 -389.631705) (xy 149.949662 -389.611108) (xy 149.949154 -389.610346) (xy 149.55139 -388.922006)
			(xy 149.539516 -388.899328) (xy 149.522664 -388.850995) (xy 149.51409 -388.800533) (xy 149.513544 -388.77494)
			(xy 148.97155 -388.77494) (xy 149.283674 -389.314944) (xy 149.296483 -389.338284) (xy 149.314708 -389.388303)
			(xy 149.323975 -389.440726) (xy 149.324568 -389.467344) (xy 149.324179 -389.491326) (xy 149.316673 -389.538698)
			(xy 149.301852 -389.584315) (xy 149.280082 -389.627053) (xy 149.251897 -389.665862) (xy 149.217991 -389.699787)
			(xy 149.179198 -389.727993) (xy 149.136472 -389.749787) (xy 149.090864 -389.764633) (xy 149.043495 -389.772165)
			(xy 149.019514 -389.772652) (xy 149.019006 -389.772652) (xy 148.995434 -389.772226) (xy 148.948848 -389.764987)
			(xy 148.903932 -389.750665) (xy 148.861754 -389.729601) (xy 148.823321 -389.702297) (xy 148.789548 -389.669404)
			(xy 148.761239 -389.631705) (xy 148.749766 -389.611108) (xy 148.749258 -389.610346) (xy 148.351494 -388.922006)
			(xy 148.339621 -388.899328) (xy 148.322768 -388.850995) (xy 148.314194 -388.800532) (xy 148.313648 -388.77494)
			(xy 147.771654 -388.77494) (xy 148.083778 -389.314944) (xy 148.096588 -389.338284) (xy 148.114813 -389.388303)
			(xy 148.124079 -389.440726) (xy 148.124672 -389.467344) (xy 148.124279 -389.491326) (xy 148.116773 -389.538698)
			(xy 148.101953 -389.584314) (xy 148.080183 -389.627052) (xy 148.051999 -389.665861) (xy 148.018093 -389.699785)
			(xy 147.9793 -389.727992) (xy 147.936575 -389.749786) (xy 147.890967 -389.764632) (xy 147.843599 -389.772165)
			(xy 147.819618 -389.772652) (xy 147.81911 -389.772652) (xy 147.795538 -389.772223) (xy 147.748952 -389.764984)
			(xy 147.704036 -389.750663) (xy 147.661859 -389.729599) (xy 147.623425 -389.702296) (xy 147.589652 -389.669403)
			(xy 147.561343 -389.631704) (xy 147.54987 -389.611108) (xy 147.549362 -389.610346) (xy 147.151598 -388.922006)
			(xy 147.139725 -388.899328) (xy 147.122872 -388.850995) (xy 147.114298 -388.800532) (xy 147.113752 -388.77494)
			(xy 133.243924 -388.77494) (xy 133.555994 -389.314944) (xy 133.556248 -389.315452) (xy 133.556502 -389.315452)
			(xy 133.557772 -389.317992) (xy 133.570041 -389.340909) (xy 133.587449 -389.389886) (xy 133.596324 -389.441102)
			(xy 133.596888 -389.46709) (xy 133.596888 -389.467344) (xy 133.596479 -389.491325) (xy 133.588974 -389.538695)
			(xy 133.574154 -389.58431) (xy 133.552386 -389.627047) (xy 133.524203 -389.665855) (xy 133.4903 -389.69978)
			(xy 133.451509 -389.727986) (xy 133.408786 -389.749782) (xy 133.36318 -389.764629) (xy 133.315814 -389.772164)
			(xy 133.291834 -389.772652) (xy 133.291326 -389.772652) (xy 133.267662 -389.772192) (xy 133.220902 -389.764885)
			(xy 133.175827 -389.750458) (xy 133.133515 -389.729255) (xy 133.094977 -389.701783) (xy 133.061134 -389.6687)
			(xy 133.032795 -389.630795) (xy 133.021324 -389.610092) (xy 133.02107 -389.60933) (xy 132.623814 -388.922006)
			(xy 132.611633 -388.89879) (xy 132.59452 -388.849239) (xy 132.589778 -388.823454) (xy 132.589778 -388.8232)
			(xy 132.586219 -388.797977) (xy 132.057087 -388.797977) (xy 132.355844 -389.314944) (xy 132.356098 -389.315452)
			(xy 132.356352 -389.315452) (xy 132.357622 -389.317992) (xy 132.369855 -389.340916) (xy 132.387175 -389.389902)
			(xy 132.395962 -389.441111) (xy 132.396484 -389.46709) (xy 132.396484 -389.467344) (xy 132.396078 -389.491338)
			(xy 132.388564 -389.538733) (xy 132.37373 -389.58437) (xy 132.351938 -389.627124) (xy 132.323728 -389.665943)
			(xy 132.289792 -389.699872) (xy 132.250966 -389.728074) (xy 132.208207 -389.749856) (xy 132.162567 -389.76468)
			(xy 132.11517 -389.772183) (xy 132.091176 -389.772652) (xy 132.067511 -389.772232) (xy 132.020749 -389.764918)
			(xy 131.975673 -389.750483) (xy 131.933361 -389.729274) (xy 131.894823 -389.701796) (xy 131.860981 -389.668707)
			(xy 131.832644 -389.630797) (xy 131.821174 -389.610092) (xy 131.82092 -389.60933) (xy 131.423664 -388.922006)
			(xy 131.411486 -388.898789) (xy 131.39437 -388.849239) (xy 131.389628 -388.823454) (xy 131.389628 -388.8232)
			(xy 131.386145 -388.799395) (xy 131.385933 -388.751285) (xy 130.830208 -388.751285) (xy 131.155948 -389.314944)
			(xy 131.156202 -389.315452) (xy 131.156456 -389.315452) (xy 131.157726 -389.317992) (xy 131.16996 -389.340916)
			(xy 131.187279 -389.389902) (xy 131.196066 -389.441111) (xy 131.196588 -389.46709) (xy 131.196588 -389.467344)
			(xy 131.196178 -389.491337) (xy 131.188665 -389.538733) (xy 131.17383 -389.584369) (xy 131.152039 -389.627123)
			(xy 131.123829 -389.665942) (xy 131.089893 -389.69987) (xy 131.051068 -389.728073) (xy 131.00831 -389.749854)
			(xy 130.96267 -389.76468) (xy 130.915274 -389.772183) (xy 130.89128 -389.772652) (xy 130.867615 -389.772229)
			(xy 130.820853 -389.764915) (xy 130.775777 -389.750481) (xy 130.733465 -389.729272) (xy 130.694927 -389.701795)
			(xy 130.661085 -389.668706) (xy 130.632748 -389.630797) (xy 130.621278 -389.610092) (xy 130.621024 -389.60933)
			(xy 130.223768 -388.922006) (xy 130.21159 -388.898789) (xy 130.194475 -388.849239) (xy 130.189732 -388.823454)
			(xy 130.189732 -388.8232) (xy 130.186241 -388.799396) (xy 130.18603 -388.751285) (xy 129.630058 -388.751285)
			(xy 129.955798 -389.314944) (xy 129.956052 -389.315452) (xy 129.956306 -389.315452) (xy 129.957576 -389.317992)
			(xy 129.969845 -389.340909) (xy 129.987253 -389.389886) (xy 129.996128 -389.441102) (xy 129.996692 -389.46709)
			(xy 129.996692 -389.467344) (xy 129.996279 -389.491325) (xy 129.988774 -389.538695) (xy 129.973955 -389.584309)
			(xy 129.952187 -389.627046) (xy 129.924004 -389.665854) (xy 129.890101 -389.699778) (xy 129.851312 -389.727985)
			(xy 129.808589 -389.74978) (xy 129.762984 -389.764628) (xy 129.715618 -389.772164) (xy 129.691638 -389.772652)
			(xy 129.69113 -389.772652) (xy 129.667466 -389.772188) (xy 129.620707 -389.764882) (xy 129.575632 -389.750456)
			(xy 129.533319 -389.729254) (xy 129.494781 -389.701782) (xy 129.460938 -389.668699) (xy 129.432599 -389.630794)
			(xy 129.421128 -389.610092) (xy 129.420874 -389.60933) (xy 129.023618 -388.922006) (xy 129.011437 -388.89879)
			(xy 128.994324 -388.849239) (xy 128.989582 -388.823454) (xy 128.989582 -388.8232) (xy 128.986016 -388.797978)
			(xy 128.457146 -388.797978) (xy 128.755902 -389.314944) (xy 128.756156 -389.315452) (xy 128.75641 -389.315452)
			(xy 128.75768 -389.317992) (xy 128.769949 -389.340909) (xy 128.787357 -389.389886) (xy 128.796232 -389.441102)
			(xy 128.796796 -389.46709) (xy 128.796796 -389.467344) (xy 128.796379 -389.491324) (xy 128.788874 -389.538694)
			(xy 128.774055 -389.584308) (xy 128.752287 -389.627045) (xy 128.724106 -389.665852) (xy 128.690203 -389.699777)
			(xy 128.651414 -389.727984) (xy 128.608692 -389.749779) (xy 128.563087 -389.764628) (xy 128.515722 -389.772163)
			(xy 128.491742 -389.772652) (xy 128.491234 -389.772652) (xy 128.467571 -389.772185) (xy 128.420811 -389.76488)
			(xy 128.375736 -389.750454) (xy 128.333424 -389.729252) (xy 128.294885 -389.701781) (xy 128.261042 -389.668699)
			(xy 128.232703 -389.630794) (xy 128.221232 -389.610092) (xy 128.220978 -389.60933) (xy 127.823722 -388.922006)
			(xy 127.811541 -388.89879) (xy 127.794428 -388.849239) (xy 127.789686 -388.823454) (xy 127.789686 -388.8232)
			(xy 127.786112 -388.797979) (xy 127.257251 -388.797979) (xy 127.556006 -389.314944) (xy 127.55626 -389.315452)
			(xy 127.556514 -389.315452) (xy 127.557784 -389.317992) (xy 127.570054 -389.340909) (xy 127.587461 -389.389886)
			(xy 127.596336 -389.441101) (xy 127.5969 -389.46709) (xy 127.5969 -389.467344) (xy 127.596479 -389.491324)
			(xy 127.588974 -389.538694) (xy 127.574156 -389.584307) (xy 127.552388 -389.627044) (xy 127.524207 -389.665851)
			(xy 127.490305 -389.699775) (xy 127.451516 -389.727982) (xy 127.408794 -389.749778) (xy 127.36319 -389.764627)
			(xy 127.315826 -389.772163) (xy 127.291846 -389.772652) (xy 127.291338 -389.772652) (xy 127.267675 -389.772182)
			(xy 127.220915 -389.764877) (xy 127.17584 -389.750452) (xy 127.133528 -389.729251) (xy 127.094989 -389.70178)
			(xy 127.061146 -389.668698) (xy 127.032807 -389.630794) (xy 127.021336 -389.610092) (xy 127.021082 -389.60933)
			(xy 126.623826 -388.922006) (xy 126.611646 -388.89879) (xy 126.594532 -388.849239) (xy 126.58979 -388.823454)
			(xy 126.58979 -388.8232) (xy 126.586378 -388.799387) (xy 126.586167 -388.751284) (xy 126.030115 -388.751284)
			(xy 126.355856 -389.314944) (xy 126.35611 -389.315452) (xy 126.356364 -389.315452) (xy 126.357634 -389.317992)
			(xy 126.369868 -389.340915) (xy 126.387188 -389.389902) (xy 126.395975 -389.441111) (xy 126.396496 -389.46709)
			(xy 126.396496 -389.467344) (xy 126.396078 -389.491337) (xy 126.388565 -389.538731) (xy 126.373731 -389.584367)
			(xy 126.351941 -389.627121) (xy 126.323731 -389.665939) (xy 126.289797 -389.699868) (xy 126.250973 -389.72807)
			(xy 126.208215 -389.749852) (xy 126.162577 -389.764678) (xy 126.115181 -389.772182) (xy 126.091188 -389.772652)
			(xy 126.067523 -389.772222) (xy 126.020762 -389.76491) (xy 125.975686 -389.750477) (xy 125.933374 -389.729269)
			(xy 125.894836 -389.701793) (xy 125.860994 -389.668705) (xy 125.832656 -389.630796) (xy 125.821186 -389.610092)
			(xy 125.820932 -389.60933) (xy 125.423676 -388.922006) (xy 125.411499 -388.898788) (xy 125.394383 -388.849238)
			(xy 125.38964 -388.823454) (xy 125.38964 -388.8232) (xy 125.386134 -388.799398) (xy 125.385922 -388.751286)
			(xy 124.830221 -388.751286) (xy 125.15596 -389.314944) (xy 125.156214 -389.315452) (xy 125.156468 -389.315452)
			(xy 125.157738 -389.317992) (xy 125.169973 -389.340915) (xy 125.187292 -389.389902) (xy 125.196079 -389.441111)
			(xy 125.1966 -389.46709) (xy 125.1966 -389.467344) (xy 125.196178 -389.491337) (xy 125.188665 -389.538731)
			(xy 125.173831 -389.584366) (xy 125.152041 -389.627119) (xy 125.123832 -389.665938) (xy 125.089898 -389.699866)
			(xy 125.051075 -389.728069) (xy 125.008318 -389.749851) (xy 124.96268 -389.764677) (xy 124.915285 -389.772182)
			(xy 124.891292 -389.772652) (xy 124.867627 -389.772219) (xy 124.820866 -389.764907) (xy 124.77579 -389.750475)
			(xy 124.733478 -389.729268) (xy 124.69494 -389.701792) (xy 124.661098 -389.668705) (xy 124.63276 -389.630796)
			(xy 124.62129 -389.610092) (xy 124.621036 -389.60933) (xy 124.22378 -388.922006) (xy 124.211603 -388.898788)
			(xy 124.194487 -388.849238) (xy 124.189744 -388.823454) (xy 124.189744 -388.8232) (xy 124.186231 -388.799399)
			(xy 124.186019 -388.751286) (xy 123.630071 -388.751286) (xy 123.95581 -389.314944) (xy 123.956064 -389.315452)
			(xy 123.956318 -389.315452) (xy 123.957588 -389.317992) (xy 123.969858 -389.340908) (xy 123.987265 -389.389886)
			(xy 123.99614 -389.441101) (xy 123.996704 -389.46709) (xy 123.996704 -389.467344) (xy 123.996279 -389.491324)
			(xy 123.988774 -389.538693) (xy 123.973956 -389.584307) (xy 123.952189 -389.627042) (xy 123.924008 -389.66585)
			(xy 123.890106 -389.699774) (xy 123.851318 -389.727981) (xy 123.808597 -389.749777) (xy 123.762994 -389.764626)
			(xy 123.71563 -389.772163) (xy 123.69165 -389.772652) (xy 123.691142 -389.772652) (xy 123.667479 -389.772179)
			(xy 123.620719 -389.764875) (xy 123.575645 -389.75045) (xy 123.533332 -389.729249) (xy 123.494794 -389.701779)
			(xy 123.46095 -389.668697) (xy 123.432611 -389.630794) (xy 123.42114 -389.610092) (xy 123.420886 -389.60933)
			(xy 123.02363 -388.922006) (xy 123.01145 -388.89879) (xy 122.994336 -388.849239) (xy 122.989594 -388.823454)
			(xy 122.989594 -388.8232) (xy 122.986174 -388.799388) (xy 122.985964 -388.751284) (xy 122.430173 -388.751284)
			(xy 122.755914 -389.314944) (xy 122.756168 -389.315452) (xy 122.756422 -389.315452) (xy 122.757692 -389.317992)
			(xy 122.769962 -389.340908) (xy 122.787369 -389.389886) (xy 122.796244 -389.441101) (xy 122.796808 -389.46709)
			(xy 122.796808 -389.467344) (xy 122.796379 -389.491324) (xy 122.788874 -389.538693) (xy 122.774056 -389.584306)
			(xy 122.752289 -389.627041) (xy 122.724109 -389.665848) (xy 122.690208 -389.699772) (xy 122.65142 -389.72798)
			(xy 122.6087 -389.749776) (xy 122.563097 -389.764625) (xy 122.515733 -389.772162) (xy 122.491754 -389.772652)
			(xy 122.491246 -389.772652) (xy 122.467583 -389.772176) (xy 122.420824 -389.764872) (xy 122.375749 -389.750448)
			(xy 122.333437 -389.729248) (xy 122.294898 -389.701778) (xy 122.261054 -389.668697) (xy 122.232715 -389.630794)
			(xy 122.221244 -389.610092) (xy 122.22099 -389.60933) (xy 121.823734 -388.922006) (xy 121.811554 -388.89879)
			(xy 121.79444 -388.849239) (xy 121.789698 -388.823454) (xy 121.789698 -388.8232) (xy 121.786271 -388.799389)
			(xy 121.78606 -388.751284) (xy 121.230277 -388.751284) (xy 121.556018 -389.314944) (xy 121.556272 -389.315452)
			(xy 121.556526 -389.315452) (xy 121.557796 -389.317992) (xy 121.570067 -389.340908) (xy 121.587474 -389.389886)
			(xy 121.596348 -389.441101) (xy 121.596912 -389.46709) (xy 121.596912 -389.467344) (xy 121.596479 -389.491324)
			(xy 121.588974 -389.538692) (xy 121.574157 -389.584305) (xy 121.55239 -389.62704) (xy 121.52421 -389.665847)
			(xy 121.49031 -389.699771) (xy 121.451523 -389.727978) (xy 121.408803 -389.749775) (xy 121.3632 -389.764624)
			(xy 121.315837 -389.772162) (xy 121.291858 -389.772652) (xy 121.29135 -389.772652) (xy 121.267687 -389.772172)
			(xy 121.220928 -389.764869) (xy 121.175853 -389.750446) (xy 121.133541 -389.729246) (xy 121.095002 -389.701777)
			(xy 121.061159 -389.668696) (xy 121.032819 -389.630793) (xy 121.021348 -389.610092) (xy 121.021094 -389.60933)
			(xy 120.623838 -388.922006) (xy 120.611658 -388.89879) (xy 120.594544 -388.849239) (xy 120.589802 -388.823454)
			(xy 120.589802 -388.8232) (xy 120.586367 -388.799389) (xy 120.586156 -388.751284) (xy 120.030127 -388.751284)
			(xy 120.355868 -389.314944) (xy 120.356122 -389.315452) (xy 120.356376 -389.315452) (xy 120.357646 -389.317992)
			(xy 120.369881 -389.340915) (xy 120.3872 -389.389902) (xy 120.395987 -389.441111) (xy 120.396508 -389.46709)
			(xy 120.396508 -389.467344) (xy 120.396078 -389.491336) (xy 120.388565 -389.53873) (xy 120.373732 -389.584364)
			(xy 120.351943 -389.627117) (xy 120.323735 -389.665935) (xy 120.289802 -389.699863) (xy 120.250979 -389.728066)
			(xy 120.208224 -389.749849) (xy 120.162587 -389.764676) (xy 120.115192 -389.772181) (xy 120.0912 -389.772652)
			(xy 120.067536 -389.772213) (xy 120.020775 -389.764902) (xy 119.975699 -389.750471) (xy 119.933387 -389.729265)
			(xy 119.894849 -389.70179) (xy 119.861006 -389.668703) (xy 119.832668 -389.630796) (xy 119.821198 -389.610092)
			(xy 119.820944 -389.60933) (xy 119.423688 -388.922006) (xy 119.411512 -388.898788) (xy 119.394395 -388.849238)
			(xy 119.389652 -388.823454) (xy 119.389652 -388.8232) (xy 119.386123 -388.7994) (xy 119.385912 -388.751286)
			(xy 118.830233 -388.751286) (xy 119.155972 -389.314944) (xy 119.156226 -389.315452) (xy 119.15648 -389.315452)
			(xy 119.15775 -389.317992) (xy 119.169986 -389.340915) (xy 119.187304 -389.389901) (xy 119.196091 -389.441111)
			(xy 119.196612 -389.46709) (xy 119.196612 -389.467344) (xy 119.196178 -389.491336) (xy 119.188665 -389.538729)
			(xy 119.173832 -389.584363) (xy 119.152044 -389.627116) (xy 119.123836 -389.665934) (xy 119.089903 -389.699862)
			(xy 119.051082 -389.728065) (xy 119.008326 -389.749848) (xy 118.96269 -389.764675) (xy 118.915296 -389.772181)
			(xy 118.891304 -389.772652) (xy 118.86764 -389.772209) (xy 118.820879 -389.764899) (xy 118.775803 -389.750469)
			(xy 118.733491 -389.729263) (xy 118.694953 -389.701789) (xy 118.66111 -389.668703) (xy 118.632772 -389.630796)
			(xy 118.621302 -389.610092) (xy 118.621048 -389.60933) (xy 118.223792 -388.922006) (xy 118.211609 -388.898791)
			(xy 118.194497 -388.849239) (xy 118.189756 -388.823454) (xy 118.189756 -388.8232) (xy 118.18622 -388.799401)
			(xy 118.186008 -388.751286) (xy 117.630083 -388.751286) (xy 117.955822 -389.314944) (xy 117.956076 -389.315452)
			(xy 117.95633 -389.315452) (xy 117.9576 -389.317992) (xy 117.969871 -389.340908) (xy 117.987278 -389.389886)
			(xy 117.996152 -389.441101) (xy 117.996716 -389.46709) (xy 117.996716 -389.467344) (xy 117.996279 -389.491323)
			(xy 117.988775 -389.538691) (xy 117.973957 -389.584304) (xy 117.952191 -389.627039) (xy 117.924011 -389.665846)
			(xy 117.890112 -389.69977) (xy 117.851325 -389.727977) (xy 117.808605 -389.749773) (xy 117.763004 -389.764624)
			(xy 117.715641 -389.772162) (xy 117.691662 -389.772652) (xy 117.691154 -389.772652) (xy 117.667491 -389.772169)
			(xy 117.620732 -389.764867) (xy 117.575658 -389.750444) (xy 117.533345 -389.729245) (xy 117.494807 -389.701776)
			(xy 117.460963 -389.668696) (xy 117.432623 -389.630793) (xy 117.421152 -389.610092) (xy 117.420898 -389.60933)
			(xy 117.023642 -388.922006) (xy 117.011463 -388.898789) (xy 116.994348 -388.849239) (xy 116.989606 -388.823454)
			(xy 116.989606 -388.8232) (xy 116.986164 -388.79939) (xy 116.985953 -388.751284) (xy 116.430185 -388.751284)
			(xy 116.755926 -389.314944) (xy 116.75618 -389.315452) (xy 116.756434 -389.315452) (xy 116.757704 -389.317992)
			(xy 116.769975 -389.340908) (xy 116.787382 -389.389886) (xy 116.796256 -389.441101) (xy 116.79682 -389.46709)
			(xy 116.79682 -389.467344) (xy 116.796379 -389.491323) (xy 116.788875 -389.538691) (xy 116.774057 -389.584303)
			(xy 116.752292 -389.627038) (xy 116.724113 -389.665844) (xy 116.690213 -389.699768) (xy 116.651427 -389.727975)
			(xy 116.608708 -389.749772) (xy 116.563107 -389.764623) (xy 116.515745 -389.772162) (xy 116.491766 -389.772652)
			(xy 116.491258 -389.772652) (xy 116.467595 -389.772166) (xy 116.420836 -389.764864) (xy 116.375762 -389.750442)
			(xy 116.33345 -389.729243) (xy 116.294911 -389.701775) (xy 116.261067 -389.668695) (xy 116.232727 -389.630793)
			(xy 116.221256 -389.610092) (xy 116.221002 -389.60933) (xy 115.823746 -388.922006) (xy 115.811567 -388.898789)
			(xy 115.794452 -388.849239) (xy 115.78971 -388.823454) (xy 115.78971 -388.8232) (xy 115.78626 -388.799391)
			(xy 115.786049 -388.751284) (xy 115.230289 -388.751284) (xy 115.55603 -389.314944) (xy 115.556284 -389.315452)
			(xy 115.556538 -389.315452) (xy 115.557808 -389.317992) (xy 115.57008 -389.340908) (xy 115.587486 -389.389886)
			(xy 115.59636 -389.441101) (xy 115.596924 -389.46709) (xy 115.596924 -389.467344) (xy 115.596479 -389.491323)
			(xy 115.588975 -389.53869) (xy 115.574158 -389.584302) (xy 115.552392 -389.627036) (xy 115.524214 -389.665843)
			(xy 115.490315 -389.699767) (xy 115.451529 -389.727974) (xy 115.408811 -389.749771) (xy 115.36321 -389.764622)
			(xy 115.315849 -389.772161) (xy 115.29187 -389.772652) (xy 115.291362 -389.772652) (xy 115.267699 -389.772163)
			(xy 115.220941 -389.764861) (xy 115.175866 -389.750439) (xy 115.133554 -389.729241) (xy 115.095015 -389.701774)
			(xy 115.061171 -389.668695) (xy 115.032831 -389.630793) (xy 115.02136 -389.610092) (xy 115.021106 -389.60933)
			(xy 114.62385 -388.922006) (xy 114.611671 -388.898789) (xy 114.594556 -388.849239) (xy 114.589814 -388.823454)
			(xy 114.589814 -388.8232) (xy 114.586357 -388.799392) (xy 114.586146 -388.751285) (xy 98.65806 -388.751285)
			(xy 98.9838 -389.314944) (xy 98.984054 -389.315452) (xy 98.984308 -389.315452) (xy 98.985578 -389.317992)
			(xy 98.997808 -389.340918) (xy 99.01513 -389.389903) (xy 99.023918 -389.441111) (xy 99.02444 -389.46709)
			(xy 99.02444 -389.467344) (xy 99.023978 -389.491335) (xy 99.016466 -389.538725) (xy 99.001635 -389.584357)
			(xy 98.979849 -389.627107) (xy 98.951644 -389.665924) (xy 98.917715 -389.699852) (xy 98.878897 -389.728055)
			(xy 98.836146 -389.74984) (xy 98.790513 -389.764669) (xy 98.743123 -389.772179) (xy 98.719132 -389.772652)
			(xy 98.695469 -389.772187) (xy 98.648709 -389.764881) (xy 98.603634 -389.750455) (xy 98.561321 -389.729253)
			(xy 98.522783 -389.701782) (xy 98.48894 -389.668699) (xy 98.460601 -389.630794) (xy 98.44913 -389.610092)
			(xy 98.448876 -389.60933) (xy 98.05162 -388.922006) (xy 98.039439 -388.89879) (xy 98.022326 -388.849239)
			(xy 98.017584 -388.823454) (xy 98.017584 -388.8232) (xy 98.014014 -388.797978) (xy 97.484894 -388.797978)
			(xy 97.78365 -389.314944) (xy 97.783904 -389.315452) (xy 97.784158 -389.315452) (xy 97.785428 -389.317992)
			(xy 97.797701 -389.340907) (xy 97.815106 -389.389885) (xy 97.82398 -389.441101) (xy 97.824544 -389.46709)
			(xy 97.824544 -389.467344) (xy 97.824079 -389.491322) (xy 97.816576 -389.538687) (xy 97.80176 -389.584297)
			(xy 97.779996 -389.62703) (xy 97.75182 -389.665836) (xy 97.717923 -389.69976) (xy 97.67914 -389.727967)
			(xy 97.636425 -389.749765) (xy 97.590827 -389.764618) (xy 97.543468 -389.77216) (xy 97.51949 -389.772652)
			(xy 97.518982 -389.772652) (xy 97.495317 -389.772227) (xy 97.448555 -389.764914) (xy 97.40348 -389.75048)
			(xy 97.361167 -389.729272) (xy 97.322629 -389.701795) (xy 97.288787 -389.668706) (xy 97.26045 -389.630797)
			(xy 97.24898 -389.610092) (xy 97.248726 -389.60933) (xy 96.85147 -388.922006) (xy 96.839293 -388.898789)
			(xy 96.822177 -388.849238) (xy 96.817434 -388.823454) (xy 96.817434 -388.8232) (xy 96.813939 -388.799396)
			(xy 96.813728 -388.751285) (xy 96.258014 -388.751285) (xy 96.583754 -389.314944) (xy 96.584008 -389.315452)
			(xy 96.584262 -389.315452) (xy 96.585532 -389.317992) (xy 96.597806 -389.340907) (xy 96.615211 -389.389885)
			(xy 96.624084 -389.441101) (xy 96.624648 -389.46709) (xy 96.624648 -389.467344) (xy 96.624179 -389.491322)
			(xy 96.616676 -389.538687) (xy 96.60186 -389.584296) (xy 96.580097 -389.627029) (xy 96.551921 -389.665835)
			(xy 96.518025 -389.699758) (xy 96.479243 -389.727966) (xy 96.436528 -389.749764) (xy 96.39093 -389.764617)
			(xy 96.343571 -389.772159) (xy 96.319594 -389.772652) (xy 96.319086 -389.772652) (xy 96.295421 -389.772224)
			(xy 96.24866 -389.764911) (xy 96.203584 -389.750478) (xy 96.161272 -389.72927) (xy 96.122734 -389.701794)
			(xy 96.088892 -389.668705) (xy 96.060554 -389.630796) (xy 96.049084 -389.610092) (xy 96.04883 -389.60933)
			(xy 95.651574 -388.922006) (xy 95.639397 -388.898788) (xy 95.622281 -388.849238) (xy 95.617538 -388.823454)
			(xy 95.617538 -388.8232) (xy 95.614036 -388.799397) (xy 95.613824 -388.751286) (xy 95.057865 -388.751286)
			(xy 95.383604 -389.314944) (xy 95.383858 -389.315452) (xy 95.384112 -389.315452) (xy 95.385382 -389.317992)
			(xy 95.397612 -389.340918) (xy 95.414934 -389.389903) (xy 95.423722 -389.441111) (xy 95.424244 -389.46709)
			(xy 95.424244 -389.467344) (xy 95.423778 -389.491335) (xy 95.416267 -389.538724) (xy 95.401435 -389.584356)
			(xy 95.379649 -389.627106) (xy 95.351445 -389.665923) (xy 95.317517 -389.69985) (xy 95.278699 -389.728054)
			(xy 95.235949 -389.749838) (xy 95.190317 -389.764668) (xy 95.142927 -389.772179) (xy 95.118936 -389.772652)
			(xy 95.095273 -389.772184) (xy 95.048513 -389.764878) (xy 95.003438 -389.750453) (xy 94.961126 -389.729251)
			(xy 94.922587 -389.701781) (xy 94.888744 -389.668698) (xy 94.860405 -389.630794) (xy 94.848934 -389.610092)
			(xy 94.84868 -389.60933) (xy 94.451424 -388.922006) (xy 94.439244 -388.89879) (xy 94.42213 -388.849239)
			(xy 94.417388 -388.823454) (xy 94.417388 -388.8232) (xy 94.413811 -388.797979) (xy 93.884953 -388.797979)
			(xy 94.183708 -389.314944) (xy 94.183962 -389.315452) (xy 94.184216 -389.315452) (xy 94.185486 -389.317992)
			(xy 94.197717 -389.340917) (xy 94.215038 -389.389902) (xy 94.223826 -389.441111) (xy 94.224348 -389.46709)
			(xy 94.224348 -389.467344) (xy 94.223878 -389.491334) (xy 94.216367 -389.538724) (xy 94.201536 -389.584355)
			(xy 94.17975 -389.627105) (xy 94.151546 -389.665922) (xy 94.117618 -389.699849) (xy 94.078802 -389.728052)
			(xy 94.036051 -389.749837) (xy 93.99042 -389.764668) (xy 93.94303 -389.772178) (xy 93.91904 -389.772652)
			(xy 93.895377 -389.77218) (xy 93.848617 -389.764876) (xy 93.803542 -389.750451) (xy 93.76123 -389.72925)
			(xy 93.722692 -389.70178) (xy 93.688848 -389.668698) (xy 93.660509 -389.630794) (xy 93.649038 -389.610092)
			(xy 93.648784 -389.60933) (xy 93.251528 -388.922006) (xy 93.239348 -388.89879) (xy 93.222234 -388.849239)
			(xy 93.217492 -388.823454) (xy 93.217492 -388.8232) (xy 93.214076 -388.799387) (xy 93.213865 -388.751284)
			(xy 92.658071 -388.751284) (xy 92.983812 -389.314944) (xy 92.984066 -389.315452) (xy 92.98432 -389.315452)
			(xy 92.98559 -389.317992) (xy 92.997821 -389.340917) (xy 93.015142 -389.389902) (xy 93.02393 -389.441111)
			(xy 93.024452 -389.46709) (xy 93.024452 -389.467344) (xy 93.023978 -389.491334) (xy 93.016467 -389.538723)
			(xy 93.001636 -389.584354) (xy 92.979851 -389.627104) (xy 92.951648 -389.66592) (xy 92.91772 -389.699848)
			(xy 92.878904 -389.728051) (xy 92.836154 -389.749836) (xy 92.790523 -389.764667) (xy 92.743134 -389.772178)
			(xy 92.719144 -389.772652) (xy 92.695481 -389.772177) (xy 92.648721 -389.764873) (xy 92.603647 -389.750449)
			(xy 92.561334 -389.729248) (xy 92.522796 -389.701779) (xy 92.488952 -389.668697) (xy 92.460613 -389.630794)
			(xy 92.449142 -389.610092) (xy 92.448888 -389.60933) (xy 92.051632 -388.922006) (xy 92.039452 -388.89879)
			(xy 92.022338 -388.849239) (xy 92.017596 -388.823454) (xy 92.017596 -388.8232) (xy 92.014173 -388.799388)
			(xy 92.013962 -388.751284) (xy 91.457921 -388.751284) (xy 91.783662 -389.314944) (xy 91.783916 -389.315452)
			(xy 91.78417 -389.315452) (xy 91.78544 -389.317992) (xy 91.797714 -389.340906) (xy 91.815119 -389.389885)
			(xy 91.823992 -389.441101) (xy 91.824556 -389.46709) (xy 91.824556 -389.467344) (xy 91.824079 -389.491321)
			(xy 91.816576 -389.538686) (xy 91.801761 -389.584295) (xy 91.779998 -389.627027) (xy 91.751823 -389.665832)
			(xy 91.717928 -389.699755) (xy 91.679147 -389.727963) (xy 91.636433 -389.749762) (xy 91.590837 -389.764616)
			(xy 91.543479 -389.772159) (xy 91.519502 -389.772652) (xy 91.518994 -389.772652) (xy 91.495329 -389.772217)
			(xy 91.448568 -389.764906) (xy 91.403493 -389.750474) (xy 91.36118 -389.729267) (xy 91.322642 -389.701792)
			(xy 91.2888 -389.668704) (xy 91.260462 -389.630796) (xy 91.248992 -389.610092) (xy 91.248738 -389.60933)
			(xy 90.851482 -388.922006) (xy 90.839305 -388.898788) (xy 90.822189 -388.849238) (xy 90.817446 -388.823454)
			(xy 90.817446 -388.8232) (xy 90.813929 -388.799399) (xy 90.813717 -388.751286) (xy 90.258027 -388.751286)
			(xy 90.583766 -389.314944) (xy 90.58402 -389.315452) (xy 90.584274 -389.315452) (xy 90.585544 -389.317992)
			(xy 90.597819 -389.340906) (xy 90.615223 -389.389885) (xy 90.624096 -389.441101) (xy 90.62466 -389.46709)
			(xy 90.62466 -389.467344) (xy 90.624279 -389.491326) (xy 90.616773 -389.5387) (xy 90.601952 -389.584317)
			(xy 90.580181 -389.627055) (xy 90.551995 -389.665865) (xy 90.518088 -389.69979) (xy 90.479294 -389.727996)
			(xy 90.436567 -389.74979) (xy 90.390957 -389.764635) (xy 90.343588 -389.772166) (xy 90.319606 -389.772652)
			(xy 90.319098 -389.772652) (xy 90.295434 -389.772214) (xy 90.248672 -389.764903) (xy 90.203597 -389.750472)
			(xy 90.161285 -389.729266) (xy 90.122747 -389.701791) (xy 90.088904 -389.668704) (xy 90.060566 -389.630796)
			(xy 90.049096 -389.610092) (xy 90.048842 -389.60933) (xy 89.651586 -388.922006) (xy 89.63941 -388.898788)
			(xy 89.622293 -388.849238) (xy 89.61755 -388.823454) (xy 89.61755 -388.8232) (xy 89.614025 -388.7994)
			(xy 89.613813 -388.751286) (xy 89.057877 -388.751286) (xy 89.383616 -389.314944) (xy 89.38387 -389.315452)
			(xy 89.384124 -389.315452) (xy 89.385394 -389.317992) (xy 89.397625 -389.340917) (xy 89.414946 -389.389902)
			(xy 89.423734 -389.441111) (xy 89.424256 -389.46709) (xy 89.424256 -389.467344) (xy 89.423778 -389.491334)
			(xy 89.416267 -389.538723) (xy 89.401436 -389.584353) (xy 89.379652 -389.627103) (xy 89.351449 -389.665919)
			(xy 89.317522 -389.699846) (xy 89.278706 -389.72805) (xy 89.235957 -389.749835) (xy 89.190327 -389.764666)
			(xy 89.142938 -389.772178) (xy 89.118948 -389.772652) (xy 89.095285 -389.772174) (xy 89.048526 -389.764871)
			(xy 89.003451 -389.750447) (xy 88.961139 -389.729247) (xy 88.9226 -389.701778) (xy 88.888757 -389.668697)
			(xy 88.860417 -389.630794) (xy 88.848946 -389.610092) (xy 88.848692 -389.60933) (xy 88.451436 -388.922006)
			(xy 88.439256 -388.89879) (xy 88.422142 -388.849239) (xy 88.4174 -388.823454) (xy 88.4174 -388.8232)
			(xy 88.413969 -388.799389) (xy 88.413758 -388.751284) (xy 87.857979 -388.751284) (xy 88.18372 -389.314944)
			(xy 88.183974 -389.315452) (xy 88.184228 -389.315452) (xy 88.185498 -389.317992) (xy 88.197729 -389.340917)
			(xy 88.21505 -389.389902) (xy 88.223838 -389.441111) (xy 88.22436 -389.46709) (xy 88.22436 -389.467344)
			(xy 88.224002 -389.491341) (xy 88.216487 -389.538742) (xy 88.20165 -389.584385) (xy 88.179855 -389.627144)
			(xy 88.151639 -389.665968) (xy 88.117698 -389.699899) (xy 88.078866 -389.728103) (xy 88.0361 -389.749885)
			(xy 87.990453 -389.764709) (xy 87.943049 -389.772209) (xy 87.919052 -389.772652) (xy 87.895389 -389.772171)
			(xy 87.84863 -389.764868) (xy 87.803556 -389.750445) (xy 87.761243 -389.729245) (xy 87.722705 -389.701777)
			(xy 87.688861 -389.668696) (xy 87.660521 -389.630793) (xy 87.64905 -389.610092) (xy 87.648796 -389.60933)
			(xy 87.25154 -388.922006) (xy 87.239361 -388.89879) (xy 87.222246 -388.849239) (xy 87.217504 -388.823454)
			(xy 87.217504 -388.8232) (xy 87.214066 -388.79939) (xy 87.213855 -388.751284) (xy 86.658083 -388.751284)
			(xy 86.983824 -389.314944) (xy 86.984078 -389.315452) (xy 86.984332 -389.315452) (xy 86.985602 -389.317992)
			(xy 86.997834 -389.340917) (xy 87.015155 -389.389902) (xy 87.023942 -389.441111) (xy 87.024464 -389.46709)
			(xy 87.024464 -389.467344) (xy 87.024078 -389.491339) (xy 87.016564 -389.538736) (xy 87.001728 -389.584375)
			(xy 86.979935 -389.62713) (xy 86.951722 -389.66595) (xy 86.917783 -389.699879) (xy 86.878955 -389.728081)
			(xy 86.836193 -389.749861) (xy 86.79055 -389.764684) (xy 86.743151 -389.772185) (xy 86.719156 -389.772652)
			(xy 86.695493 -389.772167) (xy 86.648734 -389.764865) (xy 86.60366 -389.750443) (xy 86.561348 -389.729244)
			(xy 86.522809 -389.701776) (xy 86.488965 -389.668695) (xy 86.460625 -389.630793) (xy 86.449154 -389.610092)
			(xy 86.4489 -389.60933) (xy 86.051644 -388.922006) (xy 86.039465 -388.898789) (xy 86.02235 -388.849239)
			(xy 86.017608 -388.823454) (xy 86.017608 -388.8232) (xy 86.014162 -388.799391) (xy 86.013951 -388.751284)
			(xy 85.457933 -388.751284) (xy 85.783674 -389.314944) (xy 85.783928 -389.315452) (xy 85.784182 -389.315452)
			(xy 85.785452 -389.317992) (xy 85.797727 -389.340906) (xy 85.815131 -389.389885) (xy 85.824004 -389.441101)
			(xy 85.824568 -389.46709) (xy 85.824568 -389.467344) (xy 85.824179 -389.491326) (xy 85.816673 -389.538698)
			(xy 85.801852 -389.584315) (xy 85.780082 -389.627053) (xy 85.751897 -389.665862) (xy 85.717991 -389.699787)
			(xy 85.679198 -389.727993) (xy 85.636472 -389.749787) (xy 85.590864 -389.764633) (xy 85.543495 -389.772165)
			(xy 85.519514 -389.772652) (xy 85.519006 -389.772652) (xy 85.495342 -389.772208) (xy 85.448581 -389.764898)
			(xy 85.403506 -389.750468) (xy 85.361193 -389.729263) (xy 85.322655 -389.701789) (xy 85.288813 -389.668703)
			(xy 85.260474 -389.630795) (xy 85.249004 -389.610092) (xy 85.24875 -389.60933) (xy 84.851494 -388.922006)
			(xy 84.839312 -388.898791) (xy 84.822199 -388.849239) (xy 84.817458 -388.823454) (xy 84.817458 -388.8232)
			(xy 84.813918 -388.799402) (xy 84.813706 -388.751287) (xy 84.258039 -388.751287) (xy 84.583778 -389.314944)
			(xy 84.584032 -389.315452) (xy 84.584286 -389.315452) (xy 84.585556 -389.317992) (xy 84.597831 -389.340906)
			(xy 84.615235 -389.389885) (xy 84.624108 -389.441101) (xy 84.624672 -389.46709) (xy 84.624672 -389.467344)
			(xy 84.624279 -389.491326) (xy 84.616773 -389.538698) (xy 84.601953 -389.584314) (xy 84.580183 -389.627052)
			(xy 84.551999 -389.665861) (xy 84.518093 -389.699785) (xy 84.4793 -389.727992) (xy 84.436575 -389.749786)
			(xy 84.390967 -389.764632) (xy 84.343599 -389.772165) (xy 84.319618 -389.772652) (xy 84.31911 -389.772652)
			(xy 84.295446 -389.772205) (xy 84.248685 -389.764896) (xy 84.20361 -389.750466) (xy 84.161298 -389.729261)
			(xy 84.122759 -389.701788) (xy 84.088917 -389.668702) (xy 84.060578 -389.630795) (xy 84.049108 -389.610092)
			(xy 84.048854 -389.60933) (xy 83.651598 -388.922006) (xy 83.639416 -388.898791) (xy 83.622303 -388.849239)
			(xy 83.617562 -388.823454) (xy 83.617562 -388.8232) (xy 83.614015 -388.799402) (xy 83.613803 -388.751287)
			(xy 83.057889 -388.751287) (xy 83.383628 -389.314944) (xy 83.383882 -389.315452) (xy 83.384136 -389.315452)
			(xy 83.385406 -389.317992) (xy 83.397638 -389.340917) (xy 83.414959 -389.389902) (xy 83.423746 -389.441111)
			(xy 83.424268 -389.46709) (xy 83.424268 -389.467344) (xy 83.423878 -389.491338) (xy 83.416364 -389.538735)
			(xy 83.401528 -389.584374) (xy 83.379736 -389.627129) (xy 83.351523 -389.665949) (xy 83.317585 -389.699878)
			(xy 83.278757 -389.728079) (xy 83.235996 -389.74986) (xy 83.190354 -389.764684) (xy 83.142955 -389.772184)
			(xy 83.11896 -389.772652) (xy 83.095297 -389.772164) (xy 83.048539 -389.764863) (xy 83.003464 -389.75044)
			(xy 82.961152 -389.729242) (xy 82.922613 -389.701775) (xy 82.888769 -389.668695) (xy 82.860429 -389.630793)
			(xy 82.848958 -389.610092) (xy 82.848704 -389.60933) (xy 82.451448 -388.922006) (xy 82.439269 -388.898789)
			(xy 82.422154 -388.849239) (xy 82.417412 -388.823454) (xy 82.417412 -388.8232) (xy 82.413959 -388.799392)
			(xy 82.413748 -388.751285) (xy 81.857992 -388.751285) (xy 82.183732 -389.314944) (xy 82.183986 -389.315452)
			(xy 82.18424 -389.315452) (xy 82.18551 -389.317992) (xy 82.197742 -389.340916) (xy 82.215063 -389.389902)
			(xy 82.22385 -389.441111) (xy 82.224372 -389.46709) (xy 82.224372 -389.467344) (xy 82.223978 -389.491338)
			(xy 82.216464 -389.538735) (xy 82.201628 -389.584373) (xy 82.179836 -389.627128) (xy 82.151624 -389.665948)
			(xy 82.117687 -389.699876) (xy 82.078859 -389.728078) (xy 82.036099 -389.749859) (xy 81.990457 -389.764683)
			(xy 81.943058 -389.772184) (xy 81.919064 -389.772652) (xy 81.895401 -389.772161) (xy 81.848643 -389.76486)
			(xy 81.803569 -389.750438) (xy 81.761256 -389.729241) (xy 81.722717 -389.701774) (xy 81.688873 -389.668694)
			(xy 81.660533 -389.630793) (xy 81.649062 -389.610092) (xy 81.648808 -389.60933) (xy 81.251552 -388.922006)
			(xy 81.239373 -388.898789) (xy 81.222258 -388.849239) (xy 81.217516 -388.823454) (xy 81.217516 -388.8232)
			(xy 81.214055 -388.799392) (xy 81.213844 -388.751285) (xy 80.658096 -388.751285) (xy 80.983836 -389.314944)
			(xy 80.98409 -389.315452) (xy 80.984344 -389.315452) (xy 80.985614 -389.317992) (xy 80.997847 -389.340916)
			(xy 81.015167 -389.389902) (xy 81.023954 -389.441111) (xy 81.024476 -389.46709) (xy 81.024476 -389.467344)
			(xy 81.024078 -389.491338) (xy 81.016564 -389.538734) (xy 81.001729 -389.584372) (xy 80.979937 -389.627127)
			(xy 80.951725 -389.665946) (xy 80.917788 -389.699875) (xy 80.878962 -389.728077) (xy 80.836201 -389.749858)
			(xy 80.79056 -389.764682) (xy 80.743162 -389.772184) (xy 80.719168 -389.772652) (xy 80.695506 -389.772158)
			(xy 80.648747 -389.764857) (xy 80.603673 -389.750436) (xy 80.561361 -389.729239) (xy 80.522822 -389.701773)
			(xy 80.488978 -389.668694) (xy 80.460637 -389.630793) (xy 80.449166 -389.610092) (xy 80.448912 -389.60933)
			(xy 80.051656 -388.922006) (xy 80.039478 -388.898789) (xy 80.022362 -388.849239) (xy 80.01762 -388.823454)
			(xy 80.01762 -388.8232) (xy 80.014152 -388.799393) (xy 80.01394 -388.751285) (xy 66.130312 -388.751285)
			(xy 66.456052 -389.314944) (xy 66.456306 -389.315452) (xy 66.45656 -389.315452) (xy 66.45783 -389.317992)
			(xy 66.470064 -389.340916) (xy 66.487383 -389.389902) (xy 66.496171 -389.441111) (xy 66.496692 -389.46709)
			(xy 66.496692 -389.467344) (xy 66.496278 -389.491337) (xy 66.488765 -389.538732) (xy 66.47393 -389.584368)
			(xy 66.45214 -389.627122) (xy 66.42393 -389.665941) (xy 66.389995 -389.699869) (xy 66.351171 -389.728071)
			(xy 66.308412 -389.749853) (xy 66.262774 -389.764679) (xy 66.215377 -389.772183) (xy 66.191384 -389.772652)
			(xy 66.167719 -389.772226) (xy 66.120957 -389.764913) (xy 66.075882 -389.750479) (xy 66.033569 -389.729271)
			(xy 65.995032 -389.701794) (xy 65.961189 -389.668706) (xy 65.932852 -389.630796) (xy 65.921382 -389.610092)
			(xy 65.921128 -389.60933) (xy 65.523872 -388.922006) (xy 65.511695 -388.898788) (xy 65.494579 -388.849238)
			(xy 65.489836 -388.823454) (xy 65.489836 -388.8232) (xy 65.486338 -388.799397) (xy 65.486126 -388.751286)
			(xy 64.930163 -388.751286) (xy 65.255902 -389.314944) (xy 65.256156 -389.315452) (xy 65.25641 -389.315452)
			(xy 65.25768 -389.317992) (xy 65.269949 -389.340909) (xy 65.287357 -389.389886) (xy 65.296232 -389.441102)
			(xy 65.296796 -389.46709) (xy 65.296796 -389.467344) (xy 65.296379 -389.491324) (xy 65.288874 -389.538694)
			(xy 65.274055 -389.584308) (xy 65.252287 -389.627045) (xy 65.224106 -389.665852) (xy 65.190203 -389.699777)
			(xy 65.151414 -389.727984) (xy 65.108692 -389.749779) (xy 65.063087 -389.764628) (xy 65.015722 -389.772163)
			(xy 64.991742 -389.772652) (xy 64.991234 -389.772652) (xy 64.967571 -389.772185) (xy 64.920811 -389.76488)
			(xy 64.875736 -389.750454) (xy 64.833424 -389.729252) (xy 64.794885 -389.701781) (xy 64.761042 -389.668699)
			(xy 64.732703 -389.630794) (xy 64.721232 -389.610092) (xy 64.720978 -389.60933) (xy 64.323722 -388.922006)
			(xy 64.311541 -388.89879) (xy 64.294428 -388.849239) (xy 64.289686 -388.823454) (xy 64.289686 -388.8232)
			(xy 64.286112 -388.797979) (xy 63.757251 -388.797979) (xy 64.056006 -389.314944) (xy 64.05626 -389.315452)
			(xy 64.056514 -389.315452) (xy 64.057784 -389.317992) (xy 64.070054 -389.340909) (xy 64.087461 -389.389886)
			(xy 64.096336 -389.441101) (xy 64.0969 -389.46709) (xy 64.0969 -389.467344) (xy 64.096479 -389.491324)
			(xy 64.088974 -389.538694) (xy 64.074156 -389.584307) (xy 64.052388 -389.627044) (xy 64.024207 -389.665851)
			(xy 63.990305 -389.699775) (xy 63.951516 -389.727982) (xy 63.908794 -389.749778) (xy 63.86319 -389.764627)
			(xy 63.815826 -389.772163) (xy 63.791846 -389.772652) (xy 63.791338 -389.772652) (xy 63.767675 -389.772182)
			(xy 63.720915 -389.764877) (xy 63.67584 -389.750452) (xy 63.633528 -389.729251) (xy 63.594989 -389.70178)
			(xy 63.561146 -389.668698) (xy 63.532807 -389.630794) (xy 63.521336 -389.610092) (xy 63.521082 -389.60933)
			(xy 63.123826 -388.922006) (xy 63.111646 -388.89879) (xy 63.094532 -388.849239) (xy 63.08979 -388.823454)
			(xy 63.08979 -388.8232) (xy 63.086378 -388.799387) (xy 63.086167 -388.751284) (xy 62.530115 -388.751284)
			(xy 62.855856 -389.314944) (xy 62.85611 -389.315452) (xy 62.856364 -389.315452) (xy 62.857634 -389.317992)
			(xy 62.869868 -389.340915) (xy 62.887188 -389.389902) (xy 62.895975 -389.441111) (xy 62.896496 -389.46709)
			(xy 62.896496 -389.467344) (xy 62.896078 -389.491337) (xy 62.888565 -389.538731) (xy 62.873731 -389.584367)
			(xy 62.851941 -389.627121) (xy 62.823731 -389.665939) (xy 62.789797 -389.699868) (xy 62.750973 -389.72807)
			(xy 62.708215 -389.749852) (xy 62.662577 -389.764678) (xy 62.615181 -389.772182) (xy 62.591188 -389.772652)
			(xy 62.567523 -389.772222) (xy 62.520762 -389.76491) (xy 62.475686 -389.750477) (xy 62.433374 -389.729269)
			(xy 62.394836 -389.701793) (xy 62.360994 -389.668705) (xy 62.332656 -389.630796) (xy 62.321186 -389.610092)
			(xy 62.320932 -389.60933) (xy 61.923676 -388.922006) (xy 61.911499 -388.898788) (xy 61.894383 -388.849238)
			(xy 61.88964 -388.823454) (xy 61.88964 -388.8232) (xy 61.886134 -388.799398) (xy 61.885922 -388.751286)
			(xy 61.330221 -388.751286) (xy 61.65596 -389.314944) (xy 61.656214 -389.315452) (xy 61.656468 -389.315452)
			(xy 61.657738 -389.317992) (xy 61.669973 -389.340915) (xy 61.687292 -389.389902) (xy 61.696079 -389.441111)
			(xy 61.6966 -389.46709) (xy 61.6966 -389.467344) (xy 61.696178 -389.491337) (xy 61.688665 -389.538731)
			(xy 61.673831 -389.584366) (xy 61.652041 -389.627119) (xy 61.623832 -389.665938) (xy 61.589898 -389.699866)
			(xy 61.551075 -389.728069) (xy 61.508318 -389.749851) (xy 61.46268 -389.764677) (xy 61.415285 -389.772182)
			(xy 61.391292 -389.772652) (xy 61.367627 -389.772219) (xy 61.320866 -389.764907) (xy 61.27579 -389.750475)
			(xy 61.233478 -389.729268) (xy 61.19494 -389.701792) (xy 61.161098 -389.668705) (xy 61.13276 -389.630796)
			(xy 61.12129 -389.610092) (xy 61.121036 -389.60933) (xy 60.72378 -388.922006) (xy 60.711603 -388.898788)
			(xy 60.694487 -388.849238) (xy 60.689744 -388.823454) (xy 60.689744 -388.8232) (xy 60.686231 -388.799399)
			(xy 60.686019 -388.751286) (xy 60.130325 -388.751286) (xy 60.456064 -389.314944) (xy 60.456318 -389.315452)
			(xy 60.456572 -389.315452) (xy 60.457842 -389.317992) (xy 60.470077 -389.340915) (xy 60.487396 -389.389902)
			(xy 60.496183 -389.441111) (xy 60.496704 -389.46709) (xy 60.496704 -389.467344) (xy 60.496278 -389.491337)
			(xy 60.488765 -389.53873) (xy 60.473931 -389.584365) (xy 60.452142 -389.627118) (xy 60.423933 -389.665937)
			(xy 60.39 -389.699865) (xy 60.351177 -389.728067) (xy 60.308421 -389.74985) (xy 60.262783 -389.764676)
			(xy 60.215389 -389.772182) (xy 60.191396 -389.772652) (xy 60.167731 -389.772216) (xy 60.12097 -389.764905)
			(xy 60.075895 -389.750473) (xy 60.033582 -389.729266) (xy 59.995044 -389.701791) (xy 59.961202 -389.668704)
			(xy 59.932864 -389.630796) (xy 59.921394 -389.610092) (xy 59.92114 -389.60933) (xy 59.523884 -388.922006)
			(xy 59.511708 -388.898788) (xy 59.494591 -388.849238) (xy 59.489848 -388.823454) (xy 59.489848 -388.8232)
			(xy 59.486327 -388.799399) (xy 59.486115 -388.751286) (xy 58.930175 -388.751286) (xy 59.255914 -389.314944)
			(xy 59.256168 -389.315452) (xy 59.256422 -389.315452) (xy 59.257692 -389.317992) (xy 59.269962 -389.340908)
			(xy 59.287369 -389.389886) (xy 59.296244 -389.441101) (xy 59.296808 -389.46709) (xy 59.296808 -389.467344)
			(xy 59.296379 -389.491324) (xy 59.288874 -389.538693) (xy 59.274056 -389.584306) (xy 59.252289 -389.627041)
			(xy 59.224109 -389.665848) (xy 59.190208 -389.699772) (xy 59.15142 -389.72798) (xy 59.1087 -389.749776)
			(xy 59.063097 -389.764625) (xy 59.015733 -389.772162) (xy 58.991754 -389.772652) (xy 58.991246 -389.772652)
			(xy 58.967583 -389.772176) (xy 58.920824 -389.764872) (xy 58.875749 -389.750448) (xy 58.833437 -389.729248)
			(xy 58.794898 -389.701778) (xy 58.761054 -389.668697) (xy 58.732715 -389.630794) (xy 58.721244 -389.610092)
			(xy 58.72099 -389.60933) (xy 58.323734 -388.922006) (xy 58.311554 -388.89879) (xy 58.29444 -388.849239)
			(xy 58.289698 -388.823454) (xy 58.289698 -388.8232) (xy 58.286271 -388.799389) (xy 58.28606 -388.751284)
			(xy 57.730277 -388.751284) (xy 58.056018 -389.314944) (xy 58.056272 -389.315452) (xy 58.056526 -389.315452)
			(xy 58.057796 -389.317992) (xy 58.070067 -389.340908) (xy 58.087474 -389.389886) (xy 58.096348 -389.441101)
			(xy 58.096912 -389.46709) (xy 58.096912 -389.467344) (xy 58.096479 -389.491324) (xy 58.088974 -389.538692)
			(xy 58.074157 -389.584305) (xy 58.05239 -389.62704) (xy 58.02421 -389.665847) (xy 57.99031 -389.699771)
			(xy 57.951523 -389.727978) (xy 57.908803 -389.749775) (xy 57.8632 -389.764624) (xy 57.815837 -389.772162)
			(xy 57.791858 -389.772652) (xy 57.79135 -389.772652) (xy 57.767687 -389.772172) (xy 57.720928 -389.764869)
			(xy 57.675853 -389.750446) (xy 57.633541 -389.729246) (xy 57.595002 -389.701777) (xy 57.561159 -389.668696)
			(xy 57.532819 -389.630793) (xy 57.521348 -389.610092) (xy 57.521094 -389.60933) (xy 57.123838 -388.922006)
			(xy 57.111658 -388.89879) (xy 57.094544 -388.849239) (xy 57.089802 -388.823454) (xy 57.089802 -388.8232)
			(xy 57.086367 -388.799389) (xy 57.086156 -388.751284) (xy 56.530127 -388.751284) (xy 56.855868 -389.314944)
			(xy 56.856122 -389.315452) (xy 56.856376 -389.315452) (xy 56.857646 -389.317992) (xy 56.869881 -389.340915)
			(xy 56.8872 -389.389902) (xy 56.895987 -389.441111) (xy 56.896508 -389.46709) (xy 56.896508 -389.467344)
			(xy 56.896078 -389.491336) (xy 56.888565 -389.53873) (xy 56.873732 -389.584364) (xy 56.851943 -389.627117)
			(xy 56.823735 -389.665935) (xy 56.789802 -389.699863) (xy 56.750979 -389.728066) (xy 56.708224 -389.749849)
			(xy 56.662587 -389.764676) (xy 56.615192 -389.772181) (xy 56.5912 -389.772652) (xy 56.567536 -389.772213)
			(xy 56.520775 -389.764902) (xy 56.475699 -389.750471) (xy 56.433387 -389.729265) (xy 56.394849 -389.70179)
			(xy 56.361006 -389.668703) (xy 56.332668 -389.630796) (xy 56.321198 -389.610092) (xy 56.320944 -389.60933)
			(xy 55.923688 -388.922006) (xy 55.911512 -388.898788) (xy 55.894395 -388.849238) (xy 55.889652 -388.823454)
			(xy 55.889652 -388.8232) (xy 55.886123 -388.7994) (xy 55.885912 -388.751286) (xy 55.330233 -388.751286)
			(xy 55.655972 -389.314944) (xy 55.656226 -389.315452) (xy 55.65648 -389.315452) (xy 55.65775 -389.317992)
			(xy 55.669986 -389.340915) (xy 55.687304 -389.389901) (xy 55.696091 -389.441111) (xy 55.696612 -389.46709)
			(xy 55.696612 -389.467344) (xy 55.696178 -389.491336) (xy 55.688665 -389.538729) (xy 55.673832 -389.584363)
			(xy 55.652044 -389.627116) (xy 55.623836 -389.665934) (xy 55.589903 -389.699862) (xy 55.551082 -389.728065)
			(xy 55.508326 -389.749848) (xy 55.46269 -389.764675) (xy 55.415296 -389.772181) (xy 55.391304 -389.772652)
			(xy 55.36764 -389.772209) (xy 55.320879 -389.764899) (xy 55.275803 -389.750469) (xy 55.233491 -389.729263)
			(xy 55.194953 -389.701789) (xy 55.16111 -389.668703) (xy 55.132772 -389.630796) (xy 55.121302 -389.610092)
			(xy 55.121048 -389.60933) (xy 54.723792 -388.922006) (xy 54.711609 -388.898791) (xy 54.694497 -388.849239)
			(xy 54.689756 -388.823454) (xy 54.689756 -388.8232) (xy 54.68622 -388.799401) (xy 54.686008 -388.751286)
			(xy 54.130337 -388.751286) (xy 54.456076 -389.314944) (xy 54.45633 -389.315452) (xy 54.456584 -389.315452)
			(xy 54.457854 -389.317992) (xy 54.47009 -389.340915) (xy 54.487408 -389.389901) (xy 54.496195 -389.441111)
			(xy 54.496716 -389.46709) (xy 54.496716 -389.467344) (xy 54.496278 -389.491336) (xy 54.488766 -389.538728)
			(xy 54.473933 -389.584362) (xy 54.452144 -389.627115) (xy 54.423937 -389.665932) (xy 54.390005 -389.69986)
			(xy 54.351184 -389.728063) (xy 54.308429 -389.749846) (xy 54.262793 -389.764674) (xy 54.2154 -389.772181)
			(xy 54.191408 -389.772652) (xy 54.167744 -389.772206) (xy 54.120983 -389.764897) (xy 54.075908 -389.750467)
			(xy 54.033595 -389.729262) (xy 53.995057 -389.701788) (xy 53.961215 -389.668702) (xy 53.932876 -389.630795)
			(xy 53.921406 -389.610092) (xy 53.921152 -389.60933) (xy 53.523896 -388.922006) (xy 53.511714 -388.898791)
			(xy 53.494601 -388.849239) (xy 53.48986 -388.823454) (xy 53.48986 -388.8232) (xy 53.486316 -388.799402)
			(xy 53.486104 -388.751287) (xy 52.930187 -388.751287) (xy 53.255926 -389.314944) (xy 53.25618 -389.315452)
			(xy 53.256434 -389.315452) (xy 53.257704 -389.317992) (xy 53.269975 -389.340908) (xy 53.287382 -389.389886)
			(xy 53.296256 -389.441101) (xy 53.29682 -389.46709) (xy 53.29682 -389.467344) (xy 53.296379 -389.491323)
			(xy 53.288875 -389.538691) (xy 53.274057 -389.584303) (xy 53.252292 -389.627038) (xy 53.224113 -389.665844)
			(xy 53.190213 -389.699768) (xy 53.151427 -389.727975) (xy 53.108708 -389.749772) (xy 53.063107 -389.764623)
			(xy 53.015745 -389.772162) (xy 52.991766 -389.772652) (xy 52.991258 -389.772652) (xy 52.967595 -389.772166)
			(xy 52.920836 -389.764864) (xy 52.875762 -389.750442) (xy 52.83345 -389.729243) (xy 52.794911 -389.701775)
			(xy 52.761067 -389.668695) (xy 52.732727 -389.630793) (xy 52.721256 -389.610092) (xy 52.721002 -389.60933)
			(xy 52.323746 -388.922006) (xy 52.311567 -388.898789) (xy 52.294452 -388.849239) (xy 52.28971 -388.823454)
			(xy 52.28971 -388.8232) (xy 52.28626 -388.799391) (xy 52.286049 -388.751284) (xy 51.730289 -388.751284)
			(xy 52.05603 -389.314944) (xy 52.056284 -389.315452) (xy 52.056538 -389.315452) (xy 52.057808 -389.317992)
			(xy 52.07008 -389.340908) (xy 52.087486 -389.389886) (xy 52.09636 -389.441101) (xy 52.096924 -389.46709)
			(xy 52.096924 -389.467344) (xy 52.096479 -389.491323) (xy 52.088975 -389.53869) (xy 52.074158 -389.584302)
			(xy 52.052392 -389.627036) (xy 52.024214 -389.665843) (xy 51.990315 -389.699767) (xy 51.951529 -389.727974)
			(xy 51.908811 -389.749771) (xy 51.86321 -389.764622) (xy 51.815849 -389.772161) (xy 51.79187 -389.772652)
			(xy 51.791362 -389.772652) (xy 51.767699 -389.772163) (xy 51.720941 -389.764861) (xy 51.675866 -389.750439)
			(xy 51.633554 -389.729241) (xy 51.595015 -389.701774) (xy 51.561171 -389.668695) (xy 51.532831 -389.630793)
			(xy 51.52136 -389.610092) (xy 51.521106 -389.60933) (xy 51.12385 -388.922006) (xy 51.111671 -388.898789)
			(xy 51.094556 -388.849239) (xy 51.089814 -388.823454) (xy 51.089814 -388.8232) (xy 51.086357 -388.799392)
			(xy 51.086146 -388.751285) (xy 50.53014 -388.751285) (xy 50.85588 -389.314944) (xy 50.856134 -389.315452)
			(xy 50.856388 -389.315452) (xy 50.857658 -389.317992) (xy 50.869894 -389.340914) (xy 50.887212 -389.389901)
			(xy 50.895999 -389.441111) (xy 50.89652 -389.46709) (xy 50.89652 -389.467344) (xy 50.896078 -389.491336)
			(xy 50.888566 -389.538728) (xy 50.873733 -389.584362) (xy 50.851945 -389.627113) (xy 50.823738 -389.665931)
			(xy 50.789807 -389.699859) (xy 50.750986 -389.728062) (xy 50.708232 -389.749845) (xy 50.662597 -389.764673)
			(xy 50.615204 -389.772181) (xy 50.591212 -389.772652) (xy 50.567548 -389.772203) (xy 50.520787 -389.764894)
			(xy 50.475712 -389.750465) (xy 50.4334 -389.72926) (xy 50.394862 -389.701787) (xy 50.361019 -389.668702)
			(xy 50.33268 -389.630795) (xy 50.32121 -389.610092) (xy 50.320956 -389.60933) (xy 49.9237 -388.922006)
			(xy 49.911518 -388.898791) (xy 49.894405 -388.849239) (xy 49.889664 -388.823454) (xy 49.889664 -388.8232)
			(xy 49.886113 -388.799403) (xy 49.885901 -388.751287) (xy 49.330245 -388.751287) (xy 49.655984 -389.314944)
			(xy 49.656238 -389.315452) (xy 49.656492 -389.315452) (xy 49.657762 -389.317992) (xy 49.669999 -389.340914)
			(xy 49.687316 -389.389901) (xy 49.696103 -389.441111) (xy 49.696624 -389.46709) (xy 49.696624 -389.467344)
			(xy 49.696178 -389.491336) (xy 49.688666 -389.538727) (xy 49.673833 -389.584361) (xy 49.652046 -389.627112)
			(xy 49.623839 -389.66593) (xy 49.589908 -389.699858) (xy 49.551088 -389.72806) (xy 49.508335 -389.749844)
			(xy 49.4627 -389.764672) (xy 49.415308 -389.77218) (xy 49.391316 -389.772652) (xy 49.367652 -389.7722)
			(xy 49.320892 -389.764892) (xy 49.275816 -389.750463) (xy 49.233504 -389.729259) (xy 49.194966 -389.701786)
			(xy 49.161123 -389.668701) (xy 49.132784 -389.630795) (xy 49.121314 -389.610092) (xy 49.12106 -389.60933)
			(xy 48.723804 -388.922006) (xy 48.711622 -388.898791) (xy 48.694509 -388.849239) (xy 48.689768 -388.823454)
			(xy 48.689768 -388.8232) (xy 48.686228 -388.797975) (xy 48.15733 -388.797975) (xy 48.456088 -389.314944)
			(xy 48.456342 -389.315452) (xy 48.456596 -389.315452) (xy 48.457866 -389.317992) (xy 48.470103 -389.340914)
			(xy 48.48742 -389.389901) (xy 48.496207 -389.441111) (xy 48.496728 -389.46709) (xy 48.496728 -389.467344)
			(xy 48.496278 -389.491335) (xy 48.488766 -389.538727) (xy 48.473934 -389.58436) (xy 48.452147 -389.627111)
			(xy 48.423941 -389.665928) (xy 48.39001 -389.699856) (xy 48.351191 -389.728059) (xy 48.308437 -389.749843)
			(xy 48.262803 -389.764672) (xy 48.215411 -389.77218) (xy 48.19142 -389.772652) (xy 48.167756 -389.772196)
			(xy 48.120996 -389.764889) (xy 48.075921 -389.750461) (xy 48.033608 -389.729257) (xy 47.99507 -389.701785)
			(xy 47.961227 -389.668701) (xy 47.932888 -389.630795) (xy 47.921418 -389.610092) (xy 47.921164 -389.60933)
			(xy 47.523908 -388.922006) (xy 47.511727 -388.898791) (xy 47.494614 -388.849239) (xy 47.489872 -388.823454)
			(xy 47.489872 -388.8232) (xy 47.486325 -388.797976) (xy 2.509012 -388.797976) (xy 2.509012 -393.292838)
			(xy 47.435008 -393.292838) (xy 47.435008 -392.429238) (xy 47.435494 -392.401987) (xy 47.44325 -392.348039)
			(xy 47.458605 -392.295744) (xy 47.481247 -392.246167) (xy 47.510713 -392.200317) (xy 47.546404 -392.159126)
			(xy 47.587595 -392.123435) (xy 47.633445 -392.093969) (xy 47.683022 -392.071327) (xy 47.735317 -392.055972)
			(xy 47.789265 -392.048216) (xy 47.843767 -392.048216) (xy 47.897715 -392.055972) (xy 47.95001 -392.071327)
			(xy 47.999587 -392.093969) (xy 48.045437 -392.123435) (xy 48.086628 -392.159126) (xy 48.122319 -392.200317)
			(xy 48.151785 -392.246167) (xy 48.174427 -392.295744) (xy 48.189782 -392.348039) (xy 48.197538 -392.401987)
			(xy 48.198024 -392.429238) (xy 48.198024 -393.292838) (xy 48.634904 -393.292838) (xy 48.634904 -392.429238)
			(xy 48.63539 -392.401987) (xy 48.643146 -392.348039) (xy 48.658501 -392.295744) (xy 48.681143 -392.246167)
			(xy 48.710609 -392.200317) (xy 48.7463 -392.159126) (xy 48.787491 -392.123435) (xy 48.833341 -392.093969)
			(xy 48.882918 -392.071327) (xy 48.935213 -392.055972) (xy 48.989161 -392.048216) (xy 49.043663 -392.048216)
			(xy 49.097611 -392.055972) (xy 49.149906 -392.071327) (xy 49.199483 -392.093969) (xy 49.245333 -392.123435)
			(xy 49.286524 -392.159126) (xy 49.322215 -392.200317) (xy 49.351681 -392.246167) (xy 49.374323 -392.295744)
			(xy 49.389678 -392.348039) (xy 49.397434 -392.401987) (xy 49.39792 -392.429238) (xy 49.39792 -393.292838)
			(xy 49.8348 -393.292838) (xy 49.8348 -392.429238) (xy 49.835286 -392.401969) (xy 49.843048 -392.347985)
			(xy 49.858413 -392.295655) (xy 49.88107 -392.246045) (xy 49.910556 -392.200164) (xy 49.946271 -392.158947)
			(xy 49.987488 -392.123232) (xy 50.033369 -392.093746) (xy 50.082979 -392.071089) (xy 50.135309 -392.055724)
			(xy 50.189293 -392.047962) (xy 50.243831 -392.047962) (xy 50.297815 -392.055724) (xy 50.350145 -392.071089)
			(xy 50.399755 -392.093746) (xy 50.445636 -392.123232) (xy 50.486853 -392.158947) (xy 50.522568 -392.200164)
			(xy 50.552054 -392.246045) (xy 50.574711 -392.295655) (xy 50.590076 -392.347985) (xy 50.597838 -392.401969)
			(xy 50.598324 -392.429238) (xy 50.598324 -393.292838) (xy 51.034696 -393.292838) (xy 51.034696 -392.429238)
			(xy 51.035182 -392.401969) (xy 51.042944 -392.347985) (xy 51.058309 -392.295655) (xy 51.080966 -392.246045)
			(xy 51.110452 -392.200164) (xy 51.146167 -392.158947) (xy 51.187384 -392.123232) (xy 51.233265 -392.093746)
			(xy 51.282875 -392.071089) (xy 51.335205 -392.055724) (xy 51.389189 -392.047962) (xy 51.443727 -392.047962)
			(xy 51.497711 -392.055724) (xy 51.550041 -392.071089) (xy 51.599651 -392.093746) (xy 51.645532 -392.123232)
			(xy 51.686749 -392.158947) (xy 51.722464 -392.200164) (xy 51.75195 -392.246045) (xy 51.774607 -392.295655)
			(xy 51.789972 -392.347985) (xy 51.797734 -392.401969) (xy 51.79822 -392.429238) (xy 51.79822 -393.292838)
			(xy 52.2351 -393.292838) (xy 52.2351 -392.429238) (xy 52.235586 -392.401987) (xy 52.243342 -392.348039)
			(xy 52.258697 -392.295744) (xy 52.281339 -392.246167) (xy 52.310805 -392.200317) (xy 52.346496 -392.159126)
			(xy 52.387687 -392.123435) (xy 52.433537 -392.093969) (xy 52.483114 -392.071327) (xy 52.535409 -392.055972)
			(xy 52.589357 -392.048216) (xy 52.643859 -392.048216) (xy 52.697807 -392.055972) (xy 52.750102 -392.071327)
			(xy 52.799679 -392.093969) (xy 52.845529 -392.123435) (xy 52.88672 -392.159126) (xy 52.922411 -392.200317)
			(xy 52.951877 -392.246167) (xy 52.974519 -392.295744) (xy 52.989874 -392.348039) (xy 52.99763 -392.401987)
			(xy 52.998116 -392.429238) (xy 52.998116 -393.292838) (xy 53.434996 -393.292838) (xy 53.434996 -392.429238)
			(xy 53.435482 -392.401987) (xy 53.443238 -392.348039) (xy 53.458593 -392.295744) (xy 53.481235 -392.246167)
			(xy 53.510701 -392.200317) (xy 53.546392 -392.159126) (xy 53.587583 -392.123435) (xy 53.633433 -392.093969)
			(xy 53.68301 -392.071327) (xy 53.735305 -392.055972) (xy 53.789253 -392.048216) (xy 53.843755 -392.048216)
			(xy 53.897703 -392.055972) (xy 53.949998 -392.071327) (xy 53.999575 -392.093969) (xy 54.045425 -392.123435)
			(xy 54.086616 -392.159126) (xy 54.122307 -392.200317) (xy 54.151773 -392.246167) (xy 54.174415 -392.295744)
			(xy 54.18977 -392.348039) (xy 54.197526 -392.401987) (xy 54.198012 -392.429238) (xy 54.198012 -393.292838)
			(xy 54.634892 -393.292838) (xy 54.634892 -392.429238) (xy 54.635378 -392.401969) (xy 54.64314 -392.347985)
			(xy 54.658505 -392.295655) (xy 54.681162 -392.246045) (xy 54.710648 -392.200164) (xy 54.746363 -392.158947)
			(xy 54.78758 -392.123232) (xy 54.833461 -392.093746) (xy 54.883071 -392.071089) (xy 54.935401 -392.055724)
			(xy 54.989385 -392.047962) (xy 55.043923 -392.047962) (xy 55.097907 -392.055724) (xy 55.150237 -392.071089)
			(xy 55.199847 -392.093746) (xy 55.245728 -392.123232) (xy 55.286945 -392.158947) (xy 55.32266 -392.200164)
			(xy 55.352146 -392.246045) (xy 55.374803 -392.295655) (xy 55.390168 -392.347985) (xy 55.39793 -392.401969)
			(xy 55.398416 -392.429238) (xy 55.398416 -393.292838) (xy 55.834788 -393.292838) (xy 55.834788 -392.429238)
			(xy 55.835274 -392.401969) (xy 55.843036 -392.347985) (xy 55.858401 -392.295655) (xy 55.881058 -392.246045)
			(xy 55.910544 -392.200164) (xy 55.946259 -392.158947) (xy 55.987476 -392.123232) (xy 56.033357 -392.093746)
			(xy 56.082967 -392.071089) (xy 56.135297 -392.055724) (xy 56.189281 -392.047962) (xy 56.243819 -392.047962)
			(xy 56.297803 -392.055724) (xy 56.350133 -392.071089) (xy 56.399743 -392.093746) (xy 56.445624 -392.123232)
			(xy 56.486841 -392.158947) (xy 56.522556 -392.200164) (xy 56.552042 -392.246045) (xy 56.574699 -392.295655)
			(xy 56.590064 -392.347985) (xy 56.597826 -392.401969) (xy 56.598312 -392.429238) (xy 56.598312 -393.292838)
			(xy 57.035192 -393.292838) (xy 57.035192 -392.429238) (xy 57.035678 -392.401987) (xy 57.043434 -392.348039)
			(xy 57.058789 -392.295744) (xy 57.081431 -392.246167) (xy 57.110897 -392.200317) (xy 57.146588 -392.159126)
			(xy 57.187779 -392.123435) (xy 57.233629 -392.093969) (xy 57.283206 -392.071327) (xy 57.335501 -392.055972)
			(xy 57.389449 -392.048216) (xy 57.443951 -392.048216) (xy 57.497899 -392.055972) (xy 57.550194 -392.071327)
			(xy 57.599771 -392.093969) (xy 57.645621 -392.123435) (xy 57.686812 -392.159126) (xy 57.722503 -392.200317)
			(xy 57.751969 -392.246167) (xy 57.774611 -392.295744) (xy 57.789966 -392.348039) (xy 57.797722 -392.401987)
			(xy 57.798208 -392.429238) (xy 57.798208 -393.292838) (xy 58.235088 -393.292838) (xy 58.235088 -392.429238)
			(xy 58.235574 -392.401987) (xy 58.24333 -392.348039) (xy 58.258685 -392.295744) (xy 58.281327 -392.246167)
			(xy 58.310793 -392.200317) (xy 58.346484 -392.159126) (xy 58.387675 -392.123435) (xy 58.433525 -392.093969)
			(xy 58.483102 -392.071327) (xy 58.535397 -392.055972) (xy 58.589345 -392.048216) (xy 58.643847 -392.048216)
			(xy 58.697795 -392.055972) (xy 58.75009 -392.071327) (xy 58.799667 -392.093969) (xy 58.845517 -392.123435)
			(xy 58.886708 -392.159126) (xy 58.922399 -392.200317) (xy 58.951865 -392.246167) (xy 58.974507 -392.295744)
			(xy 58.989862 -392.348039) (xy 58.997618 -392.401987) (xy 58.998104 -392.429238) (xy 58.998104 -393.292838)
			(xy 59.434984 -393.292838) (xy 59.434984 -392.429238) (xy 59.43547 -392.401969) (xy 59.443232 -392.347985)
			(xy 59.458597 -392.295655) (xy 59.481254 -392.246045) (xy 59.51074 -392.200164) (xy 59.546455 -392.158947)
			(xy 59.587672 -392.123232) (xy 59.633553 -392.093746) (xy 59.683163 -392.071089) (xy 59.735493 -392.055724)
			(xy 59.789477 -392.047962) (xy 59.844015 -392.047962) (xy 59.897999 -392.055724) (xy 59.950329 -392.071089)
			(xy 59.999939 -392.093746) (xy 60.04582 -392.123232) (xy 60.087037 -392.158947) (xy 60.122752 -392.200164)
			(xy 60.152238 -392.246045) (xy 60.174895 -392.295655) (xy 60.19026 -392.347985) (xy 60.198022 -392.401969)
			(xy 60.198508 -392.429238) (xy 60.198508 -393.292838) (xy 60.63488 -393.292838) (xy 60.63488 -392.429238)
			(xy 60.635366 -392.401969) (xy 60.643128 -392.347985) (xy 60.658493 -392.295655) (xy 60.68115 -392.246045)
			(xy 60.710636 -392.200164) (xy 60.746351 -392.158947) (xy 60.787568 -392.123232) (xy 60.833449 -392.093746)
			(xy 60.883059 -392.071089) (xy 60.935389 -392.055724) (xy 60.989373 -392.047962) (xy 61.043911 -392.047962)
			(xy 61.097895 -392.055724) (xy 61.150225 -392.071089) (xy 61.199835 -392.093746) (xy 61.245716 -392.123232)
			(xy 61.286933 -392.158947) (xy 61.322648 -392.200164) (xy 61.352134 -392.246045) (xy 61.374791 -392.295655)
			(xy 61.390156 -392.347985) (xy 61.397918 -392.401969) (xy 61.398404 -392.429238) (xy 61.398404 -393.292838)
			(xy 61.834776 -393.292838) (xy 61.834776 -392.429238) (xy 61.835262 -392.401969) (xy 61.843024 -392.347985)
			(xy 61.858389 -392.295655) (xy 61.881046 -392.246045) (xy 61.910532 -392.200164) (xy 61.946247 -392.158947)
			(xy 61.987464 -392.123232) (xy 62.033345 -392.093746) (xy 62.082955 -392.071089) (xy 62.135285 -392.055724)
			(xy 62.189269 -392.047962) (xy 62.243807 -392.047962) (xy 62.297791 -392.055724) (xy 62.350121 -392.071089)
			(xy 62.399731 -392.093746) (xy 62.445612 -392.123232) (xy 62.486829 -392.158947) (xy 62.522544 -392.200164)
			(xy 62.55203 -392.246045) (xy 62.574687 -392.295655) (xy 62.590052 -392.347985) (xy 62.597814 -392.401969)
			(xy 62.5983 -392.429238) (xy 62.5983 -393.292838) (xy 63.034672 -393.292838) (xy 63.034672 -392.429238)
			(xy 63.035158 -392.401969) (xy 63.04292 -392.347985) (xy 63.058285 -392.295655) (xy 63.080942 -392.246045)
			(xy 63.110428 -392.200164) (xy 63.146143 -392.158947) (xy 63.18736 -392.123232) (xy 63.233241 -392.093746)
			(xy 63.282851 -392.071089) (xy 63.335181 -392.055724) (xy 63.389165 -392.047962) (xy 63.443703 -392.047962)
			(xy 63.497687 -392.055724) (xy 63.550017 -392.071089) (xy 63.599627 -392.093746) (xy 63.645508 -392.123232)
			(xy 63.686725 -392.158947) (xy 63.72244 -392.200164) (xy 63.751926 -392.246045) (xy 63.774583 -392.295655)
			(xy 63.789948 -392.347985) (xy 63.79771 -392.401969) (xy 63.798196 -392.429238) (xy 63.798196 -393.292838)
			(xy 64.235076 -393.292838) (xy 64.235076 -392.429238) (xy 64.235562 -392.401987) (xy 64.243318 -392.348039)
			(xy 64.258673 -392.295744) (xy 64.281315 -392.246167) (xy 64.310781 -392.200317) (xy 64.346472 -392.159126)
			(xy 64.387663 -392.123435) (xy 64.433513 -392.093969) (xy 64.48309 -392.071327) (xy 64.535385 -392.055972)
			(xy 64.589333 -392.048216) (xy 64.643835 -392.048216) (xy 64.697783 -392.055972) (xy 64.750078 -392.071327)
			(xy 64.799655 -392.093969) (xy 64.845505 -392.123435) (xy 64.886696 -392.159126) (xy 64.922387 -392.200317)
			(xy 64.951853 -392.246167) (xy 64.974495 -392.295744) (xy 64.98985 -392.348039) (xy 64.997606 -392.401987)
			(xy 64.998092 -392.429238) (xy 64.998092 -393.292838) (xy 65.434972 -393.292838) (xy 65.434972 -392.429238)
			(xy 65.435458 -392.401987) (xy 65.443214 -392.348039) (xy 65.458569 -392.295744) (xy 65.481211 -392.246167)
			(xy 65.510677 -392.200317) (xy 65.546368 -392.159126) (xy 65.587559 -392.123435) (xy 65.633409 -392.093969)
			(xy 65.682986 -392.071327) (xy 65.735281 -392.055972) (xy 65.789229 -392.048216) (xy 65.843731 -392.048216)
			(xy 65.897679 -392.055972) (xy 65.949974 -392.071327) (xy 65.999551 -392.093969) (xy 66.045401 -392.123435)
			(xy 66.086592 -392.159126) (xy 66.122283 -392.200317) (xy 66.151749 -392.246167) (xy 66.174391 -392.295744)
			(xy 66.189746 -392.348039) (xy 66.197502 -392.401987) (xy 66.197988 -392.429238) (xy 66.197988 -393.292838)
			(xy 79.962756 -393.292838) (xy 79.962756 -392.429238) (xy 79.963242 -392.401987) (xy 79.970998 -392.348039)
			(xy 79.986353 -392.295744) (xy 80.008995 -392.246167) (xy 80.038461 -392.200317) (xy 80.074152 -392.159126)
			(xy 80.115343 -392.123435) (xy 80.161193 -392.093969) (xy 80.21077 -392.071327) (xy 80.263065 -392.055972)
			(xy 80.317013 -392.048216) (xy 80.371515 -392.048216) (xy 80.425463 -392.055972) (xy 80.477758 -392.071327)
			(xy 80.527335 -392.093969) (xy 80.573185 -392.123435) (xy 80.614376 -392.159126) (xy 80.650067 -392.200317)
			(xy 80.679533 -392.246167) (xy 80.702175 -392.295744) (xy 80.71753 -392.348039) (xy 80.725286 -392.401987)
			(xy 80.725772 -392.429238) (xy 80.725772 -393.292838) (xy 81.162652 -393.292838) (xy 81.162652 -392.429238)
			(xy 81.163138 -392.401987) (xy 81.170894 -392.348039) (xy 81.186249 -392.295744) (xy 81.208891 -392.246167)
			(xy 81.238357 -392.200317) (xy 81.274048 -392.159126) (xy 81.315239 -392.123435) (xy 81.361089 -392.093969)
			(xy 81.410666 -392.071327) (xy 81.462961 -392.055972) (xy 81.516909 -392.048216) (xy 81.571411 -392.048216)
			(xy 81.625359 -392.055972) (xy 81.677654 -392.071327) (xy 81.727231 -392.093969) (xy 81.773081 -392.123435)
			(xy 81.814272 -392.159126) (xy 81.849963 -392.200317) (xy 81.879429 -392.246167) (xy 81.902071 -392.295744)
			(xy 81.917426 -392.348039) (xy 81.925182 -392.401987) (xy 81.925668 -392.429238) (xy 81.925668 -393.292838)
			(xy 82.362548 -393.292838) (xy 82.362548 -392.429238) (xy 82.363034 -392.401969) (xy 82.370796 -392.347985)
			(xy 82.386161 -392.295655) (xy 82.408818 -392.246045) (xy 82.438304 -392.200164) (xy 82.474019 -392.158947)
			(xy 82.515236 -392.123232) (xy 82.561117 -392.093746) (xy 82.610727 -392.071089) (xy 82.663057 -392.055724)
			(xy 82.717041 -392.047962) (xy 82.771579 -392.047962) (xy 82.825563 -392.055724) (xy 82.877893 -392.071089)
			(xy 82.927503 -392.093746) (xy 82.973384 -392.123232) (xy 83.014601 -392.158947) (xy 83.050316 -392.200164)
			(xy 83.079802 -392.246045) (xy 83.102459 -392.295655) (xy 83.117824 -392.347985) (xy 83.125586 -392.401969)
			(xy 83.126072 -392.429238) (xy 83.126072 -393.292838) (xy 83.562444 -393.292838) (xy 83.562444 -392.429238)
			(xy 83.56293 -392.401969) (xy 83.570692 -392.347985) (xy 83.586057 -392.295655) (xy 83.608714 -392.246045)
			(xy 83.6382 -392.200164) (xy 83.673915 -392.158947) (xy 83.715132 -392.123232) (xy 83.761013 -392.093746)
			(xy 83.810623 -392.071089) (xy 83.862953 -392.055724) (xy 83.916937 -392.047962) (xy 83.971475 -392.047962)
			(xy 84.025459 -392.055724) (xy 84.077789 -392.071089) (xy 84.127399 -392.093746) (xy 84.17328 -392.123232)
			(xy 84.214497 -392.158947) (xy 84.250212 -392.200164) (xy 84.279698 -392.246045) (xy 84.302355 -392.295655)
			(xy 84.31772 -392.347985) (xy 84.325482 -392.401969) (xy 84.325968 -392.429238) (xy 84.325968 -393.292838)
			(xy 84.762848 -393.292838) (xy 84.762848 -392.429238) (xy 84.763334 -392.401987) (xy 84.77109 -392.348039)
			(xy 84.786445 -392.295744) (xy 84.809087 -392.246167) (xy 84.838553 -392.200317) (xy 84.874244 -392.159126)
			(xy 84.915435 -392.123435) (xy 84.961285 -392.093969) (xy 85.010862 -392.071327) (xy 85.063157 -392.055972)
			(xy 85.117105 -392.048216) (xy 85.171607 -392.048216) (xy 85.225555 -392.055972) (xy 85.27785 -392.071327)
			(xy 85.327427 -392.093969) (xy 85.373277 -392.123435) (xy 85.414468 -392.159126) (xy 85.450159 -392.200317)
			(xy 85.479625 -392.246167) (xy 85.502267 -392.295744) (xy 85.517622 -392.348039) (xy 85.525378 -392.401987)
			(xy 85.525864 -392.429238) (xy 85.525864 -393.292838) (xy 85.962744 -393.292838) (xy 85.962744 -392.429238)
			(xy 85.96323 -392.401987) (xy 85.970986 -392.348039) (xy 85.986341 -392.295744) (xy 86.008983 -392.246167)
			(xy 86.038449 -392.200317) (xy 86.07414 -392.159126) (xy 86.115331 -392.123435) (xy 86.161181 -392.093969)
			(xy 86.210758 -392.071327) (xy 86.263053 -392.055972) (xy 86.317001 -392.048216) (xy 86.371503 -392.048216)
			(xy 86.425451 -392.055972) (xy 86.477746 -392.071327) (xy 86.527323 -392.093969) (xy 86.573173 -392.123435)
			(xy 86.614364 -392.159126) (xy 86.650055 -392.200317) (xy 86.679521 -392.246167) (xy 86.702163 -392.295744)
			(xy 86.717518 -392.348039) (xy 86.725274 -392.401987) (xy 86.72576 -392.429238) (xy 86.72576 -393.292838)
			(xy 87.16264 -393.292838) (xy 87.16264 -392.429238) (xy 87.163126 -392.401969) (xy 87.170888 -392.347985)
			(xy 87.186253 -392.295655) (xy 87.20891 -392.246045) (xy 87.238396 -392.200164) (xy 87.274111 -392.158947)
			(xy 87.315328 -392.123232) (xy 87.361209 -392.093746) (xy 87.410819 -392.071089) (xy 87.463149 -392.055724)
			(xy 87.517133 -392.047962) (xy 87.571671 -392.047962) (xy 87.625655 -392.055724) (xy 87.677985 -392.071089)
			(xy 87.727595 -392.093746) (xy 87.773476 -392.123232) (xy 87.814693 -392.158947) (xy 87.850408 -392.200164)
			(xy 87.879894 -392.246045) (xy 87.902551 -392.295655) (xy 87.917916 -392.347985) (xy 87.925678 -392.401969)
			(xy 87.926164 -392.429238) (xy 87.926164 -393.292838) (xy 88.362536 -393.292838) (xy 88.362536 -392.429238)
			(xy 88.363022 -392.401969) (xy 88.370784 -392.347985) (xy 88.386149 -392.295655) (xy 88.408806 -392.246045)
			(xy 88.438292 -392.200164) (xy 88.474007 -392.158947) (xy 88.515224 -392.123232) (xy 88.561105 -392.093746)
			(xy 88.610715 -392.071089) (xy 88.663045 -392.055724) (xy 88.717029 -392.047962) (xy 88.771567 -392.047962)
			(xy 88.825551 -392.055724) (xy 88.877881 -392.071089) (xy 88.927491 -392.093746) (xy 88.973372 -392.123232)
			(xy 89.014589 -392.158947) (xy 89.050304 -392.200164) (xy 89.07979 -392.246045) (xy 89.102447 -392.295655)
			(xy 89.117812 -392.347985) (xy 89.125574 -392.401969) (xy 89.12606 -392.429238) (xy 89.12606 -393.292838)
			(xy 89.56294 -393.292838) (xy 89.56294 -392.429238) (xy 89.563426 -392.401987) (xy 89.571182 -392.348039)
			(xy 89.586537 -392.295744) (xy 89.609179 -392.246167) (xy 89.638645 -392.200317) (xy 89.674336 -392.159126)
			(xy 89.715527 -392.123435) (xy 89.761377 -392.093969) (xy 89.810954 -392.071327) (xy 89.863249 -392.055972)
			(xy 89.917197 -392.048216) (xy 89.971699 -392.048216) (xy 90.025647 -392.055972) (xy 90.077942 -392.071327)
			(xy 90.127519 -392.093969) (xy 90.173369 -392.123435) (xy 90.21456 -392.159126) (xy 90.250251 -392.200317)
			(xy 90.279717 -392.246167) (xy 90.302359 -392.295744) (xy 90.317714 -392.348039) (xy 90.32547 -392.401987)
			(xy 90.325956 -392.429238) (xy 90.325956 -393.292838) (xy 90.762836 -393.292838) (xy 90.762836 -392.429238)
			(xy 90.763322 -392.401987) (xy 90.771078 -392.348039) (xy 90.786433 -392.295744) (xy 90.809075 -392.246167)
			(xy 90.838541 -392.200317) (xy 90.874232 -392.159126) (xy 90.915423 -392.123435) (xy 90.961273 -392.093969)
			(xy 91.01085 -392.071327) (xy 91.063145 -392.055972) (xy 91.117093 -392.048216) (xy 91.171595 -392.048216)
			(xy 91.225543 -392.055972) (xy 91.277838 -392.071327) (xy 91.327415 -392.093969) (xy 91.373265 -392.123435)
			(xy 91.414456 -392.159126) (xy 91.450147 -392.200317) (xy 91.479613 -392.246167) (xy 91.502255 -392.295744)
			(xy 91.51761 -392.348039) (xy 91.525366 -392.401987) (xy 91.525852 -392.429238) (xy 91.525852 -393.292838)
			(xy 91.962732 -393.292838) (xy 91.962732 -392.429238) (xy 91.963218 -392.401969) (xy 91.97098 -392.347985)
			(xy 91.986345 -392.295655) (xy 92.009002 -392.246045) (xy 92.038488 -392.200164) (xy 92.074203 -392.158947)
			(xy 92.11542 -392.123232) (xy 92.161301 -392.093746) (xy 92.210911 -392.071089) (xy 92.263241 -392.055724)
			(xy 92.317225 -392.047962) (xy 92.371763 -392.047962) (xy 92.425747 -392.055724) (xy 92.478077 -392.071089)
			(xy 92.527687 -392.093746) (xy 92.573568 -392.123232) (xy 92.614785 -392.158947) (xy 92.6505 -392.200164)
			(xy 92.679986 -392.246045) (xy 92.702643 -392.295655) (xy 92.718008 -392.347985) (xy 92.72577 -392.401969)
			(xy 92.726256 -392.429238) (xy 92.726256 -393.292838) (xy 93.162628 -393.292838) (xy 93.162628 -392.429238)
			(xy 93.163114 -392.401969) (xy 93.170876 -392.347985) (xy 93.186241 -392.295655) (xy 93.208898 -392.246045)
			(xy 93.238384 -392.200164) (xy 93.274099 -392.158947) (xy 93.315316 -392.123232) (xy 93.361197 -392.093746)
			(xy 93.410807 -392.071089) (xy 93.463137 -392.055724) (xy 93.517121 -392.047962) (xy 93.571659 -392.047962)
			(xy 93.625643 -392.055724) (xy 93.677973 -392.071089) (xy 93.727583 -392.093746) (xy 93.773464 -392.123232)
			(xy 93.814681 -392.158947) (xy 93.850396 -392.200164) (xy 93.879882 -392.246045) (xy 93.902539 -392.295655)
			(xy 93.917904 -392.347985) (xy 93.925666 -392.401969) (xy 93.926152 -392.429238) (xy 93.926152 -393.292838)
			(xy 94.362524 -393.292838) (xy 94.362524 -392.429238) (xy 94.36301 -392.401969) (xy 94.370772 -392.347985)
			(xy 94.386137 -392.295655) (xy 94.408794 -392.246045) (xy 94.43828 -392.200164) (xy 94.473995 -392.158947)
			(xy 94.515212 -392.123232) (xy 94.561093 -392.093746) (xy 94.610703 -392.071089) (xy 94.663033 -392.055724)
			(xy 94.717017 -392.047962) (xy 94.771555 -392.047962) (xy 94.825539 -392.055724) (xy 94.877869 -392.071089)
			(xy 94.927479 -392.093746) (xy 94.97336 -392.123232) (xy 95.014577 -392.158947) (xy 95.050292 -392.200164)
			(xy 95.079778 -392.246045) (xy 95.102435 -392.295655) (xy 95.1178 -392.347985) (xy 95.125562 -392.401969)
			(xy 95.126048 -392.429238) (xy 95.126048 -393.292838) (xy 95.56242 -393.292838) (xy 95.56242 -392.429238)
			(xy 95.562906 -392.401969) (xy 95.570668 -392.347985) (xy 95.586033 -392.295655) (xy 95.60869 -392.246045)
			(xy 95.638176 -392.200164) (xy 95.673891 -392.158947) (xy 95.715108 -392.123232) (xy 95.760989 -392.093746)
			(xy 95.810599 -392.071089) (xy 95.862929 -392.055724) (xy 95.916913 -392.047962) (xy 95.971451 -392.047962)
			(xy 96.025435 -392.055724) (xy 96.077765 -392.071089) (xy 96.127375 -392.093746) (xy 96.173256 -392.123232)
			(xy 96.214473 -392.158947) (xy 96.250188 -392.200164) (xy 96.279674 -392.246045) (xy 96.302331 -392.295655)
			(xy 96.317696 -392.347985) (xy 96.325458 -392.401969) (xy 96.325944 -392.429238) (xy 96.325944 -393.292838)
			(xy 96.762824 -393.292838) (xy 96.762824 -392.429238) (xy 96.76331 -392.401987) (xy 96.771066 -392.348039)
			(xy 96.786421 -392.295744) (xy 96.809063 -392.246167) (xy 96.838529 -392.200317) (xy 96.87422 -392.159126)
			(xy 96.915411 -392.123435) (xy 96.961261 -392.093969) (xy 97.010838 -392.071327) (xy 97.063133 -392.055972)
			(xy 97.117081 -392.048216) (xy 97.171583 -392.048216) (xy 97.225531 -392.055972) (xy 97.277826 -392.071327)
			(xy 97.327403 -392.093969) (xy 97.373253 -392.123435) (xy 97.414444 -392.159126) (xy 97.450135 -392.200317)
			(xy 97.479601 -392.246167) (xy 97.502243 -392.295744) (xy 97.517598 -392.348039) (xy 97.525354 -392.401987)
			(xy 97.52584 -392.429238) (xy 97.52584 -393.292838) (xy 97.96272 -393.292838) (xy 97.96272 -392.429238)
			(xy 97.963206 -392.401987) (xy 97.970962 -392.348039) (xy 97.986317 -392.295744) (xy 98.008959 -392.246167)
			(xy 98.038425 -392.200317) (xy 98.074116 -392.159126) (xy 98.115307 -392.123435) (xy 98.161157 -392.093969)
			(xy 98.210734 -392.071327) (xy 98.263029 -392.055972) (xy 98.316977 -392.048216) (xy 98.371479 -392.048216)
			(xy 98.425427 -392.055972) (xy 98.477722 -392.071327) (xy 98.527299 -392.093969) (xy 98.573149 -392.123435)
			(xy 98.61434 -392.159126) (xy 98.650031 -392.200317) (xy 98.679497 -392.246167) (xy 98.702139 -392.295744)
			(xy 98.717494 -392.348039) (xy 98.72525 -392.401987) (xy 98.725736 -392.429238) (xy 98.725736 -393.292838)
			(xy 114.534696 -393.292838) (xy 114.534696 -392.429238) (xy 114.535182 -392.401969) (xy 114.542944 -392.347985)
			(xy 114.558309 -392.295655) (xy 114.580966 -392.246045) (xy 114.610452 -392.200164) (xy 114.646167 -392.158947)
			(xy 114.687384 -392.123232) (xy 114.733265 -392.093746) (xy 114.782875 -392.071089) (xy 114.835205 -392.055724)
			(xy 114.889189 -392.047962) (xy 114.943727 -392.047962) (xy 114.997711 -392.055724) (xy 115.050041 -392.071089)
			(xy 115.099651 -392.093746) (xy 115.145532 -392.123232) (xy 115.186749 -392.158947) (xy 115.222464 -392.200164)
			(xy 115.25195 -392.246045) (xy 115.274607 -392.295655) (xy 115.289972 -392.347985) (xy 115.297734 -392.401969)
			(xy 115.29822 -392.429238) (xy 115.29822 -393.292838) (xy 115.734592 -393.292838) (xy 115.734592 -392.429238)
			(xy 115.735078 -392.401969) (xy 115.74284 -392.347985) (xy 115.758205 -392.295655) (xy 115.780862 -392.246045)
			(xy 115.810348 -392.200164) (xy 115.846063 -392.158947) (xy 115.88728 -392.123232) (xy 115.933161 -392.093746)
			(xy 115.982771 -392.071089) (xy 116.035101 -392.055724) (xy 116.089085 -392.047962) (xy 116.143623 -392.047962)
			(xy 116.197607 -392.055724) (xy 116.249937 -392.071089) (xy 116.299547 -392.093746) (xy 116.345428 -392.123232)
			(xy 116.386645 -392.158947) (xy 116.42236 -392.200164) (xy 116.451846 -392.246045) (xy 116.474503 -392.295655)
			(xy 116.489868 -392.347985) (xy 116.49763 -392.401969) (xy 116.498116 -392.429238) (xy 116.498116 -393.292838)
			(xy 116.934996 -393.292838) (xy 116.934996 -392.429238) (xy 116.935482 -392.401987) (xy 116.943238 -392.348039)
			(xy 116.958593 -392.295744) (xy 116.981235 -392.246167) (xy 117.010701 -392.200317) (xy 117.046392 -392.159126)
			(xy 117.087583 -392.123435) (xy 117.133433 -392.093969) (xy 117.18301 -392.071327) (xy 117.235305 -392.055972)
			(xy 117.289253 -392.048216) (xy 117.343755 -392.048216) (xy 117.397703 -392.055972) (xy 117.449998 -392.071327)
			(xy 117.499575 -392.093969) (xy 117.545425 -392.123435) (xy 117.586616 -392.159126) (xy 117.622307 -392.200317)
			(xy 117.651773 -392.246167) (xy 117.674415 -392.295744) (xy 117.68977 -392.348039) (xy 117.697526 -392.401987)
			(xy 117.698012 -392.429238) (xy 117.698012 -393.292838) (xy 118.134892 -393.292838) (xy 118.134892 -392.429238)
			(xy 118.135378 -392.401987) (xy 118.143134 -392.348039) (xy 118.158489 -392.295744) (xy 118.181131 -392.246167)
			(xy 118.210597 -392.200317) (xy 118.246288 -392.159126) (xy 118.287479 -392.123435) (xy 118.333329 -392.093969)
			(xy 118.382906 -392.071327) (xy 118.435201 -392.055972) (xy 118.489149 -392.048216) (xy 118.543651 -392.048216)
			(xy 118.597599 -392.055972) (xy 118.649894 -392.071327) (xy 118.699471 -392.093969) (xy 118.745321 -392.123435)
			(xy 118.786512 -392.159126) (xy 118.822203 -392.200317) (xy 118.851669 -392.246167) (xy 118.874311 -392.295744)
			(xy 118.889666 -392.348039) (xy 118.897422 -392.401987) (xy 118.897908 -392.429238) (xy 118.897908 -393.292838)
			(xy 119.334788 -393.292838) (xy 119.334788 -392.429238) (xy 119.335274 -392.401969) (xy 119.343036 -392.347985)
			(xy 119.358401 -392.295655) (xy 119.381058 -392.246045) (xy 119.410544 -392.200164) (xy 119.446259 -392.158947)
			(xy 119.487476 -392.123232) (xy 119.533357 -392.093746) (xy 119.582967 -392.071089) (xy 119.635297 -392.055724)
			(xy 119.689281 -392.047962) (xy 119.743819 -392.047962) (xy 119.797803 -392.055724) (xy 119.850133 -392.071089)
			(xy 119.899743 -392.093746) (xy 119.945624 -392.123232) (xy 119.986841 -392.158947) (xy 120.022556 -392.200164)
			(xy 120.052042 -392.246045) (xy 120.074699 -392.295655) (xy 120.090064 -392.347985) (xy 120.097826 -392.401969)
			(xy 120.098312 -392.429238) (xy 120.098312 -393.292838) (xy 120.534684 -393.292838) (xy 120.534684 -392.429238)
			(xy 120.53517 -392.401969) (xy 120.542932 -392.347985) (xy 120.558297 -392.295655) (xy 120.580954 -392.246045)
			(xy 120.61044 -392.200164) (xy 120.646155 -392.158947) (xy 120.687372 -392.123232) (xy 120.733253 -392.093746)
			(xy 120.782863 -392.071089) (xy 120.835193 -392.055724) (xy 120.889177 -392.047962) (xy 120.943715 -392.047962)
			(xy 120.997699 -392.055724) (xy 121.050029 -392.071089) (xy 121.099639 -392.093746) (xy 121.14552 -392.123232)
			(xy 121.186737 -392.158947) (xy 121.222452 -392.200164) (xy 121.251938 -392.246045) (xy 121.274595 -392.295655)
			(xy 121.28996 -392.347985) (xy 121.297722 -392.401969) (xy 121.298208 -392.429238) (xy 121.298208 -393.292838)
			(xy 121.735088 -393.292838) (xy 121.735088 -392.429238) (xy 121.735574 -392.401987) (xy 121.74333 -392.348039)
			(xy 121.758685 -392.295744) (xy 121.781327 -392.246167) (xy 121.810793 -392.200317) (xy 121.846484 -392.159126)
			(xy 121.887675 -392.123435) (xy 121.933525 -392.093969) (xy 121.983102 -392.071327) (xy 122.035397 -392.055972)
			(xy 122.089345 -392.048216) (xy 122.143847 -392.048216) (xy 122.197795 -392.055972) (xy 122.25009 -392.071327)
			(xy 122.299667 -392.093969) (xy 122.345517 -392.123435) (xy 122.386708 -392.159126) (xy 122.422399 -392.200317)
			(xy 122.451865 -392.246167) (xy 122.474507 -392.295744) (xy 122.489862 -392.348039) (xy 122.497618 -392.401987)
			(xy 122.498104 -392.429238) (xy 122.498104 -393.292838) (xy 122.934984 -393.292838) (xy 122.934984 -392.429238)
			(xy 122.93547 -392.401987) (xy 122.943226 -392.348039) (xy 122.958581 -392.295744) (xy 122.981223 -392.246167)
			(xy 123.010689 -392.200317) (xy 123.04638 -392.159126) (xy 123.087571 -392.123435) (xy 123.133421 -392.093969)
			(xy 123.182998 -392.071327) (xy 123.235293 -392.055972) (xy 123.289241 -392.048216) (xy 123.343743 -392.048216)
			(xy 123.397691 -392.055972) (xy 123.449986 -392.071327) (xy 123.499563 -392.093969) (xy 123.545413 -392.123435)
			(xy 123.586604 -392.159126) (xy 123.622295 -392.200317) (xy 123.651761 -392.246167) (xy 123.674403 -392.295744)
			(xy 123.689758 -392.348039) (xy 123.697514 -392.401987) (xy 123.698 -392.429238) (xy 123.698 -393.292838)
			(xy 124.13488 -393.292838) (xy 124.13488 -392.429238) (xy 124.135366 -392.401969) (xy 124.143128 -392.347985)
			(xy 124.158493 -392.295655) (xy 124.18115 -392.246045) (xy 124.210636 -392.200164) (xy 124.246351 -392.158947)
			(xy 124.287568 -392.123232) (xy 124.333449 -392.093746) (xy 124.383059 -392.071089) (xy 124.435389 -392.055724)
			(xy 124.489373 -392.047962) (xy 124.543911 -392.047962) (xy 124.597895 -392.055724) (xy 124.650225 -392.071089)
			(xy 124.699835 -392.093746) (xy 124.745716 -392.123232) (xy 124.786933 -392.158947) (xy 124.822648 -392.200164)
			(xy 124.852134 -392.246045) (xy 124.874791 -392.295655) (xy 124.890156 -392.347985) (xy 124.897918 -392.401969)
			(xy 124.898404 -392.429238) (xy 124.898404 -393.292838) (xy 125.334776 -393.292838) (xy 125.334776 -392.429238)
			(xy 125.335262 -392.401969) (xy 125.343024 -392.347985) (xy 125.358389 -392.295655) (xy 125.381046 -392.246045)
			(xy 125.410532 -392.200164) (xy 125.446247 -392.158947) (xy 125.487464 -392.123232) (xy 125.533345 -392.093746)
			(xy 125.582955 -392.071089) (xy 125.635285 -392.055724) (xy 125.689269 -392.047962) (xy 125.743807 -392.047962)
			(xy 125.797791 -392.055724) (xy 125.850121 -392.071089) (xy 125.899731 -392.093746) (xy 125.945612 -392.123232)
			(xy 125.986829 -392.158947) (xy 126.022544 -392.200164) (xy 126.05203 -392.246045) (xy 126.074687 -392.295655)
			(xy 126.090052 -392.347985) (xy 126.097814 -392.401969) (xy 126.0983 -392.429238) (xy 126.0983 -393.292838)
			(xy 126.53518 -393.292838) (xy 126.53518 -392.429238) (xy 126.535666 -392.401987) (xy 126.543422 -392.348039)
			(xy 126.558777 -392.295744) (xy 126.581419 -392.246167) (xy 126.610885 -392.200317) (xy 126.646576 -392.159126)
			(xy 126.687767 -392.123435) (xy 126.733617 -392.093969) (xy 126.783194 -392.071327) (xy 126.835489 -392.055972)
			(xy 126.889437 -392.048216) (xy 126.943939 -392.048216) (xy 126.997887 -392.055972) (xy 127.050182 -392.071327)
			(xy 127.099759 -392.093969) (xy 127.145609 -392.123435) (xy 127.1868 -392.159126) (xy 127.222491 -392.200317)
			(xy 127.251957 -392.246167) (xy 127.274599 -392.295744) (xy 127.289954 -392.348039) (xy 127.29771 -392.401987)
			(xy 127.298196 -392.429238) (xy 127.298196 -393.292838) (xy 127.735076 -393.292838) (xy 127.735076 -392.429238)
			(xy 127.735562 -392.401987) (xy 127.743318 -392.348039) (xy 127.758673 -392.295744) (xy 127.781315 -392.246167)
			(xy 127.810781 -392.200317) (xy 127.846472 -392.159126) (xy 127.887663 -392.123435) (xy 127.933513 -392.093969)
			(xy 127.98309 -392.071327) (xy 128.035385 -392.055972) (xy 128.089333 -392.048216) (xy 128.143835 -392.048216)
			(xy 128.197783 -392.055972) (xy 128.250078 -392.071327) (xy 128.299655 -392.093969) (xy 128.345505 -392.123435)
			(xy 128.386696 -392.159126) (xy 128.422387 -392.200317) (xy 128.451853 -392.246167) (xy 128.474495 -392.295744)
			(xy 128.48985 -392.348039) (xy 128.497606 -392.401987) (xy 128.498092 -392.429238) (xy 128.498092 -393.292838)
			(xy 128.934972 -393.292838) (xy 128.934972 -392.429238) (xy 128.935458 -392.401987) (xy 128.943214 -392.348039)
			(xy 128.958569 -392.295744) (xy 128.981211 -392.246167) (xy 129.010677 -392.200317) (xy 129.046368 -392.159126)
			(xy 129.087559 -392.123435) (xy 129.133409 -392.093969) (xy 129.182986 -392.071327) (xy 129.235281 -392.055972)
			(xy 129.289229 -392.048216) (xy 129.343731 -392.048216) (xy 129.397679 -392.055972) (xy 129.449974 -392.071327)
			(xy 129.499551 -392.093969) (xy 129.545401 -392.123435) (xy 129.586592 -392.159126) (xy 129.622283 -392.200317)
			(xy 129.651749 -392.246167) (xy 129.674391 -392.295744) (xy 129.689746 -392.348039) (xy 129.697502 -392.401987)
			(xy 129.697988 -392.429238) (xy 129.697988 -393.292838) (xy 130.134868 -393.292838) (xy 130.134868 -392.429238)
			(xy 130.135354 -392.401987) (xy 130.14311 -392.348039) (xy 130.158465 -392.295744) (xy 130.181107 -392.246167)
			(xy 130.210573 -392.200317) (xy 130.246264 -392.159126) (xy 130.287455 -392.123435) (xy 130.333305 -392.093969)
			(xy 130.382882 -392.071327) (xy 130.435177 -392.055972) (xy 130.489125 -392.048216) (xy 130.543627 -392.048216)
			(xy 130.597575 -392.055972) (xy 130.64987 -392.071327) (xy 130.699447 -392.093969) (xy 130.745297 -392.123435)
			(xy 130.786488 -392.159126) (xy 130.822179 -392.200317) (xy 130.851645 -392.246167) (xy 130.874287 -392.295744)
			(xy 130.889642 -392.348039) (xy 130.897398 -392.401987) (xy 130.897884 -392.429238) (xy 130.897884 -393.292838)
			(xy 131.334764 -393.292838) (xy 131.334764 -392.429238) (xy 131.33525 -392.401969) (xy 131.343012 -392.347985)
			(xy 131.358377 -392.295655) (xy 131.381034 -392.246045) (xy 131.41052 -392.200164) (xy 131.446235 -392.158947)
			(xy 131.487452 -392.123232) (xy 131.533333 -392.093746) (xy 131.582943 -392.071089) (xy 131.635273 -392.055724)
			(xy 131.689257 -392.047962) (xy 131.743795 -392.047962) (xy 131.797779 -392.055724) (xy 131.850109 -392.071089)
			(xy 131.899719 -392.093746) (xy 131.9456 -392.123232) (xy 131.986817 -392.158947) (xy 132.022532 -392.200164)
			(xy 132.052018 -392.246045) (xy 132.074675 -392.295655) (xy 132.09004 -392.347985) (xy 132.097802 -392.401969)
			(xy 132.098288 -392.429238) (xy 132.098288 -393.292838) (xy 132.53466 -393.292838) (xy 132.53466 -392.429238)
			(xy 132.535146 -392.401969) (xy 132.542908 -392.347985) (xy 132.558273 -392.295655) (xy 132.58093 -392.246045)
			(xy 132.610416 -392.200164) (xy 132.646131 -392.158947) (xy 132.687348 -392.123232) (xy 132.733229 -392.093746)
			(xy 132.782839 -392.071089) (xy 132.835169 -392.055724) (xy 132.889153 -392.047962) (xy 132.943691 -392.047962)
			(xy 132.997675 -392.055724) (xy 133.050005 -392.071089) (xy 133.099615 -392.093746) (xy 133.145496 -392.123232)
			(xy 133.186713 -392.158947) (xy 133.222428 -392.200164) (xy 133.251914 -392.246045) (xy 133.274571 -392.295655)
			(xy 133.289936 -392.347985) (xy 133.297698 -392.401969) (xy 133.298184 -392.429238) (xy 133.298184 -393.292838)
			(xy 147.062444 -393.292838) (xy 147.062444 -392.429238) (xy 147.06293 -392.401969) (xy 147.070692 -392.347985)
			(xy 147.086057 -392.295655) (xy 147.108714 -392.246045) (xy 147.1382 -392.200164) (xy 147.173915 -392.158947)
			(xy 147.215132 -392.123232) (xy 147.261013 -392.093746) (xy 147.310623 -392.071089) (xy 147.362953 -392.055724)
			(xy 147.416937 -392.047962) (xy 147.471475 -392.047962) (xy 147.525459 -392.055724) (xy 147.577789 -392.071089)
			(xy 147.627399 -392.093746) (xy 147.67328 -392.123232) (xy 147.714497 -392.158947) (xy 147.750212 -392.200164)
			(xy 147.779698 -392.246045) (xy 147.802355 -392.295655) (xy 147.81772 -392.347985) (xy 147.825482 -392.401969)
			(xy 147.825968 -392.429238) (xy 147.825968 -393.292838) (xy 148.26234 -393.292838) (xy 148.26234 -392.429238)
			(xy 148.262826 -392.401969) (xy 148.270588 -392.347985) (xy 148.285953 -392.295655) (xy 148.30861 -392.246045)
			(xy 148.338096 -392.200164) (xy 148.373811 -392.158947) (xy 148.415028 -392.123232) (xy 148.460909 -392.093746)
			(xy 148.510519 -392.071089) (xy 148.562849 -392.055724) (xy 148.616833 -392.047962) (xy 148.671371 -392.047962)
			(xy 148.725355 -392.055724) (xy 148.777685 -392.071089) (xy 148.827295 -392.093746) (xy 148.873176 -392.123232)
			(xy 148.914393 -392.158947) (xy 148.950108 -392.200164) (xy 148.979594 -392.246045) (xy 149.002251 -392.295655)
			(xy 149.017616 -392.347985) (xy 149.025378 -392.401969) (xy 149.025864 -392.429238) (xy 149.025864 -393.292838)
			(xy 149.462744 -393.292838) (xy 149.462744 -392.429238) (xy 149.46323 -392.401987) (xy 149.470986 -392.348039)
			(xy 149.486341 -392.295744) (xy 149.508983 -392.246167) (xy 149.538449 -392.200317) (xy 149.57414 -392.159126)
			(xy 149.615331 -392.123435) (xy 149.661181 -392.093969) (xy 149.710758 -392.071327) (xy 149.763053 -392.055972)
			(xy 149.817001 -392.048216) (xy 149.871503 -392.048216) (xy 149.925451 -392.055972) (xy 149.977746 -392.071327)
			(xy 150.027323 -392.093969) (xy 150.073173 -392.123435) (xy 150.114364 -392.159126) (xy 150.150055 -392.200317)
			(xy 150.179521 -392.246167) (xy 150.202163 -392.295744) (xy 150.217518 -392.348039) (xy 150.225274 -392.401987)
			(xy 150.22576 -392.429238) (xy 150.22576 -393.292838) (xy 150.66264 -393.292838) (xy 150.66264 -392.429238)
			(xy 150.663126 -392.401987) (xy 150.670882 -392.348039) (xy 150.686237 -392.295744) (xy 150.708879 -392.246167)
			(xy 150.738345 -392.200317) (xy 150.774036 -392.159126) (xy 150.815227 -392.123435) (xy 150.861077 -392.093969)
			(xy 150.910654 -392.071327) (xy 150.962949 -392.055972) (xy 151.016897 -392.048216) (xy 151.071399 -392.048216)
			(xy 151.125347 -392.055972) (xy 151.177642 -392.071327) (xy 151.227219 -392.093969) (xy 151.273069 -392.123435)
			(xy 151.31426 -392.159126) (xy 151.349951 -392.200317) (xy 151.379417 -392.246167) (xy 151.402059 -392.295744)
			(xy 151.417414 -392.348039) (xy 151.42517 -392.401987) (xy 151.425656 -392.429238) (xy 151.425656 -393.292838)
			(xy 151.862536 -393.292838) (xy 151.862536 -392.429238) (xy 151.863022 -392.401969) (xy 151.870784 -392.347985)
			(xy 151.886149 -392.295655) (xy 151.908806 -392.246045) (xy 151.938292 -392.200164) (xy 151.974007 -392.158947)
			(xy 152.015224 -392.123232) (xy 152.061105 -392.093746) (xy 152.110715 -392.071089) (xy 152.163045 -392.055724)
			(xy 152.217029 -392.047962) (xy 152.271567 -392.047962) (xy 152.325551 -392.055724) (xy 152.377881 -392.071089)
			(xy 152.427491 -392.093746) (xy 152.473372 -392.123232) (xy 152.514589 -392.158947) (xy 152.550304 -392.200164)
			(xy 152.57979 -392.246045) (xy 152.602447 -392.295655) (xy 152.617812 -392.347985) (xy 152.625574 -392.401969)
			(xy 152.62606 -392.429238) (xy 152.62606 -393.292838) (xy 153.062432 -393.292838) (xy 153.062432 -392.429238)
			(xy 153.062918 -392.401969) (xy 153.07068 -392.347985) (xy 153.086045 -392.295655) (xy 153.108702 -392.246045)
			(xy 153.138188 -392.200164) (xy 153.173903 -392.158947) (xy 153.21512 -392.123232) (xy 153.261001 -392.093746)
			(xy 153.310611 -392.071089) (xy 153.362941 -392.055724) (xy 153.416925 -392.047962) (xy 153.471463 -392.047962)
			(xy 153.525447 -392.055724) (xy 153.577777 -392.071089) (xy 153.627387 -392.093746) (xy 153.673268 -392.123232)
			(xy 153.714485 -392.158947) (xy 153.7502 -392.200164) (xy 153.779686 -392.246045) (xy 153.802343 -392.295655)
			(xy 153.817708 -392.347985) (xy 153.82547 -392.401969) (xy 153.825956 -392.429238) (xy 153.825956 -393.292838)
			(xy 154.262836 -393.292838) (xy 154.262836 -392.429238) (xy 154.263322 -392.401987) (xy 154.271078 -392.348039)
			(xy 154.286433 -392.295744) (xy 154.309075 -392.246167) (xy 154.338541 -392.200317) (xy 154.374232 -392.159126)
			(xy 154.415423 -392.123435) (xy 154.461273 -392.093969) (xy 154.51085 -392.071327) (xy 154.563145 -392.055972)
			(xy 154.617093 -392.048216) (xy 154.671595 -392.048216) (xy 154.725543 -392.055972) (xy 154.777838 -392.071327)
			(xy 154.827415 -392.093969) (xy 154.873265 -392.123435) (xy 154.914456 -392.159126) (xy 154.950147 -392.200317)
			(xy 154.979613 -392.246167) (xy 155.002255 -392.295744) (xy 155.01761 -392.348039) (xy 155.025366 -392.401987)
			(xy 155.025852 -392.429238) (xy 155.025852 -393.292838) (xy 155.462732 -393.292838) (xy 155.462732 -392.429238)
			(xy 155.463218 -392.401987) (xy 155.470974 -392.348039) (xy 155.486329 -392.295744) (xy 155.508971 -392.246167)
			(xy 155.538437 -392.200317) (xy 155.574128 -392.159126) (xy 155.615319 -392.123435) (xy 155.661169 -392.093969)
			(xy 155.710746 -392.071327) (xy 155.763041 -392.055972) (xy 155.816989 -392.048216) (xy 155.871491 -392.048216)
			(xy 155.925439 -392.055972) (xy 155.977734 -392.071327) (xy 156.027311 -392.093969) (xy 156.073161 -392.123435)
			(xy 156.114352 -392.159126) (xy 156.150043 -392.200317) (xy 156.179509 -392.246167) (xy 156.202151 -392.295744)
			(xy 156.217506 -392.348039) (xy 156.225262 -392.401987) (xy 156.225748 -392.429238) (xy 156.225748 -393.292838)
			(xy 156.662628 -393.292838) (xy 156.662628 -392.429238) (xy 156.663114 -392.401969) (xy 156.670876 -392.347985)
			(xy 156.686241 -392.295655) (xy 156.708898 -392.246045) (xy 156.738384 -392.200164) (xy 156.774099 -392.158947)
			(xy 156.815316 -392.123232) (xy 156.861197 -392.093746) (xy 156.910807 -392.071089) (xy 156.963137 -392.055724)
			(xy 157.017121 -392.047962) (xy 157.071659 -392.047962) (xy 157.125643 -392.055724) (xy 157.177973 -392.071089)
			(xy 157.227583 -392.093746) (xy 157.273464 -392.123232) (xy 157.314681 -392.158947) (xy 157.350396 -392.200164)
			(xy 157.379882 -392.246045) (xy 157.402539 -392.295655) (xy 157.417904 -392.347985) (xy 157.425666 -392.401969)
			(xy 157.426152 -392.429238) (xy 157.426152 -393.292838) (xy 157.862524 -393.292838) (xy 157.862524 -392.429238)
			(xy 157.86301 -392.401969) (xy 157.870772 -392.347985) (xy 157.886137 -392.295655) (xy 157.908794 -392.246045)
			(xy 157.93828 -392.200164) (xy 157.973995 -392.158947) (xy 158.015212 -392.123232) (xy 158.061093 -392.093746)
			(xy 158.110703 -392.071089) (xy 158.163033 -392.055724) (xy 158.217017 -392.047962) (xy 158.271555 -392.047962)
			(xy 158.325539 -392.055724) (xy 158.377869 -392.071089) (xy 158.427479 -392.093746) (xy 158.47336 -392.123232)
			(xy 158.514577 -392.158947) (xy 158.550292 -392.200164) (xy 158.579778 -392.246045) (xy 158.602435 -392.295655)
			(xy 158.6178 -392.347985) (xy 158.625562 -392.401969) (xy 158.626048 -392.429238) (xy 158.626048 -393.292838)
			(xy 159.062928 -393.292838) (xy 159.062928 -392.429238) (xy 159.063414 -392.401987) (xy 159.07117 -392.348039)
			(xy 159.086525 -392.295744) (xy 159.109167 -392.246167) (xy 159.138633 -392.200317) (xy 159.174324 -392.159126)
			(xy 159.215515 -392.123435) (xy 159.261365 -392.093969) (xy 159.310942 -392.071327) (xy 159.363237 -392.055972)
			(xy 159.417185 -392.048216) (xy 159.471687 -392.048216) (xy 159.525635 -392.055972) (xy 159.57793 -392.071327)
			(xy 159.627507 -392.093969) (xy 159.673357 -392.123435) (xy 159.714548 -392.159126) (xy 159.750239 -392.200317)
			(xy 159.779705 -392.246167) (xy 159.802347 -392.295744) (xy 159.817702 -392.348039) (xy 159.825458 -392.401987)
			(xy 159.825944 -392.429238) (xy 159.825944 -393.292838) (xy 160.262824 -393.292838) (xy 160.262824 -392.429238)
			(xy 160.26331 -392.401987) (xy 160.271066 -392.348039) (xy 160.286421 -392.295744) (xy 160.309063 -392.246167)
			(xy 160.338529 -392.200317) (xy 160.37422 -392.159126) (xy 160.415411 -392.123435) (xy 160.461261 -392.093969)
			(xy 160.510838 -392.071327) (xy 160.563133 -392.055972) (xy 160.617081 -392.048216) (xy 160.671583 -392.048216)
			(xy 160.725531 -392.055972) (xy 160.777826 -392.071327) (xy 160.827403 -392.093969) (xy 160.873253 -392.123435)
			(xy 160.914444 -392.159126) (xy 160.950135 -392.200317) (xy 160.979601 -392.246167) (xy 161.002243 -392.295744)
			(xy 161.017598 -392.348039) (xy 161.025354 -392.401987) (xy 161.02584 -392.429238) (xy 161.02584 -393.292838)
			(xy 161.46272 -393.292838) (xy 161.46272 -392.429238) (xy 161.463206 -392.401987) (xy 161.470962 -392.348039)
			(xy 161.486317 -392.295744) (xy 161.508959 -392.246167) (xy 161.538425 -392.200317) (xy 161.574116 -392.159126)
			(xy 161.615307 -392.123435) (xy 161.661157 -392.093969) (xy 161.710734 -392.071327) (xy 161.763029 -392.055972)
			(xy 161.816977 -392.048216) (xy 161.871479 -392.048216) (xy 161.925427 -392.055972) (xy 161.977722 -392.071327)
			(xy 162.027299 -392.093969) (xy 162.073149 -392.123435) (xy 162.11434 -392.159126) (xy 162.150031 -392.200317)
			(xy 162.179497 -392.246167) (xy 162.202139 -392.295744) (xy 162.217494 -392.348039) (xy 162.22525 -392.401987)
			(xy 162.225736 -392.429238) (xy 162.225736 -393.292838) (xy 162.662616 -393.292838) (xy 162.662616 -392.429238)
			(xy 162.663102 -392.401987) (xy 162.670858 -392.348039) (xy 162.686213 -392.295744) (xy 162.708855 -392.246167)
			(xy 162.738321 -392.200317) (xy 162.774012 -392.159126) (xy 162.815203 -392.123435) (xy 162.861053 -392.093969)
			(xy 162.91063 -392.071327) (xy 162.962925 -392.055972) (xy 163.016873 -392.048216) (xy 163.071375 -392.048216)
			(xy 163.125323 -392.055972) (xy 163.177618 -392.071327) (xy 163.227195 -392.093969) (xy 163.273045 -392.123435)
			(xy 163.314236 -392.159126) (xy 163.349927 -392.200317) (xy 163.379393 -392.246167) (xy 163.402035 -392.295744)
			(xy 163.41739 -392.348039) (xy 163.425146 -392.401987) (xy 163.425632 -392.429238) (xy 163.425632 -393.292838)
			(xy 163.862512 -393.292838) (xy 163.862512 -392.429238) (xy 163.862998 -392.401969) (xy 163.87076 -392.347985)
			(xy 163.886125 -392.295655) (xy 163.908782 -392.246045) (xy 163.938268 -392.200164) (xy 163.973983 -392.158947)
			(xy 164.0152 -392.123232) (xy 164.061081 -392.093746) (xy 164.110691 -392.071089) (xy 164.163021 -392.055724)
			(xy 164.217005 -392.047962) (xy 164.271543 -392.047962) (xy 164.325527 -392.055724) (xy 164.377857 -392.071089)
			(xy 164.427467 -392.093746) (xy 164.473348 -392.123232) (xy 164.514565 -392.158947) (xy 164.55028 -392.200164)
			(xy 164.579766 -392.246045) (xy 164.602423 -392.295655) (xy 164.617788 -392.347985) (xy 164.62555 -392.401969)
			(xy 164.626036 -392.429238) (xy 164.626036 -393.292838) (xy 165.062408 -393.292838) (xy 165.062408 -392.429238)
			(xy 165.062894 -392.401969) (xy 165.070656 -392.347985) (xy 165.086021 -392.295655) (xy 165.108678 -392.246045)
			(xy 165.138164 -392.200164) (xy 165.173879 -392.158947) (xy 165.215096 -392.123232) (xy 165.260977 -392.093746)
			(xy 165.310587 -392.071089) (xy 165.362917 -392.055724) (xy 165.416901 -392.047962) (xy 165.471439 -392.047962)
			(xy 165.525423 -392.055724) (xy 165.577753 -392.071089) (xy 165.627363 -392.093746) (xy 165.673244 -392.123232)
			(xy 165.714461 -392.158947) (xy 165.750176 -392.200164) (xy 165.779662 -392.246045) (xy 165.802319 -392.295655)
			(xy 165.817684 -392.347985) (xy 165.825446 -392.401969) (xy 165.825932 -392.429238) (xy 165.825932 -393.292838)
			(xy 165.825446 -393.320107) (xy 165.817684 -393.374091) (xy 165.802319 -393.426421) (xy 165.779662 -393.476031)
			(xy 165.750176 -393.521912) (xy 165.714461 -393.563129) (xy 165.673244 -393.598844) (xy 165.627363 -393.62833)
			(xy 165.577753 -393.650987) (xy 165.525423 -393.666352) (xy 165.471439 -393.674114) (xy 165.416901 -393.674114)
			(xy 165.362917 -393.666352) (xy 165.310587 -393.650987) (xy 165.260977 -393.62833) (xy 165.215096 -393.598844)
			(xy 165.173879 -393.563129) (xy 165.138164 -393.521912) (xy 165.108678 -393.476031) (xy 165.086021 -393.426421)
			(xy 165.070656 -393.374091) (xy 165.062894 -393.320107) (xy 165.062408 -393.292838) (xy 164.626036 -393.292838)
			(xy 164.62555 -393.320107) (xy 164.617788 -393.374091) (xy 164.602423 -393.426421) (xy 164.579766 -393.476031)
			(xy 164.55028 -393.521912) (xy 164.514565 -393.563129) (xy 164.473348 -393.598844) (xy 164.427467 -393.62833)
			(xy 164.377857 -393.650987) (xy 164.325527 -393.666352) (xy 164.271543 -393.674114) (xy 164.217005 -393.674114)
			(xy 164.163021 -393.666352) (xy 164.110691 -393.650987) (xy 164.061081 -393.62833) (xy 164.0152 -393.598844)
			(xy 163.973983 -393.563129) (xy 163.938268 -393.521912) (xy 163.908782 -393.476031) (xy 163.886125 -393.426421)
			(xy 163.87076 -393.374091) (xy 163.862998 -393.320107) (xy 163.862512 -393.292838) (xy 163.425632 -393.292838)
			(xy 163.425146 -393.320089) (xy 163.41739 -393.374037) (xy 163.402035 -393.426332) (xy 163.379393 -393.475909)
			(xy 163.349927 -393.521759) (xy 163.314236 -393.56295) (xy 163.273045 -393.598641) (xy 163.227195 -393.628107)
			(xy 163.177618 -393.650749) (xy 163.125323 -393.666104) (xy 163.071375 -393.67386) (xy 163.016873 -393.67386)
			(xy 162.962925 -393.666104) (xy 162.91063 -393.650749) (xy 162.861053 -393.628107) (xy 162.815203 -393.598641)
			(xy 162.774012 -393.56295) (xy 162.738321 -393.521759) (xy 162.708855 -393.475909) (xy 162.686213 -393.426332)
			(xy 162.670858 -393.374037) (xy 162.663102 -393.320089) (xy 162.662616 -393.292838) (xy 162.225736 -393.292838)
			(xy 162.22525 -393.320089) (xy 162.217494 -393.374037) (xy 162.202139 -393.426332) (xy 162.179497 -393.475909)
			(xy 162.150031 -393.521759) (xy 162.11434 -393.56295) (xy 162.073149 -393.598641) (xy 162.027299 -393.628107)
			(xy 161.977722 -393.650749) (xy 161.925427 -393.666104) (xy 161.871479 -393.67386) (xy 161.816977 -393.67386)
			(xy 161.763029 -393.666104) (xy 161.710734 -393.650749) (xy 161.661157 -393.628107) (xy 161.615307 -393.598641)
			(xy 161.574116 -393.56295) (xy 161.538425 -393.521759) (xy 161.508959 -393.475909) (xy 161.486317 -393.426332)
			(xy 161.470962 -393.374037) (xy 161.463206 -393.320089) (xy 161.46272 -393.292838) (xy 161.02584 -393.292838)
			(xy 161.025354 -393.320089) (xy 161.017598 -393.374037) (xy 161.002243 -393.426332) (xy 160.979601 -393.475909)
			(xy 160.950135 -393.521759) (xy 160.914444 -393.56295) (xy 160.873253 -393.598641) (xy 160.827403 -393.628107)
			(xy 160.777826 -393.650749) (xy 160.725531 -393.666104) (xy 160.671583 -393.67386) (xy 160.617081 -393.67386)
			(xy 160.563133 -393.666104) (xy 160.510838 -393.650749) (xy 160.461261 -393.628107) (xy 160.415411 -393.598641)
			(xy 160.37422 -393.56295) (xy 160.338529 -393.521759) (xy 160.309063 -393.475909) (xy 160.286421 -393.426332)
			(xy 160.271066 -393.374037) (xy 160.26331 -393.320089) (xy 160.262824 -393.292838) (xy 159.825944 -393.292838)
			(xy 159.825458 -393.320089) (xy 159.817702 -393.374037) (xy 159.802347 -393.426332) (xy 159.779705 -393.475909)
			(xy 159.750239 -393.521759) (xy 159.714548 -393.56295) (xy 159.673357 -393.598641) (xy 159.627507 -393.628107)
			(xy 159.57793 -393.650749) (xy 159.525635 -393.666104) (xy 159.471687 -393.67386) (xy 159.417185 -393.67386)
			(xy 159.363237 -393.666104) (xy 159.310942 -393.650749) (xy 159.261365 -393.628107) (xy 159.215515 -393.598641)
			(xy 159.174324 -393.56295) (xy 159.138633 -393.521759) (xy 159.109167 -393.475909) (xy 159.086525 -393.426332)
			(xy 159.07117 -393.374037) (xy 159.063414 -393.320089) (xy 159.062928 -393.292838) (xy 158.626048 -393.292838)
			(xy 158.625562 -393.320107) (xy 158.6178 -393.374091) (xy 158.602435 -393.426421) (xy 158.579778 -393.476031)
			(xy 158.550292 -393.521912) (xy 158.514577 -393.563129) (xy 158.47336 -393.598844) (xy 158.427479 -393.62833)
			(xy 158.377869 -393.650987) (xy 158.325539 -393.666352) (xy 158.271555 -393.674114) (xy 158.217017 -393.674114)
			(xy 158.163033 -393.666352) (xy 158.110703 -393.650987) (xy 158.061093 -393.62833) (xy 158.015212 -393.598844)
			(xy 157.973995 -393.563129) (xy 157.93828 -393.521912) (xy 157.908794 -393.476031) (xy 157.886137 -393.426421)
			(xy 157.870772 -393.374091) (xy 157.86301 -393.320107) (xy 157.862524 -393.292838) (xy 157.426152 -393.292838)
			(xy 157.425666 -393.320107) (xy 157.417904 -393.374091) (xy 157.402539 -393.426421) (xy 157.379882 -393.476031)
			(xy 157.350396 -393.521912) (xy 157.314681 -393.563129) (xy 157.273464 -393.598844) (xy 157.227583 -393.62833)
			(xy 157.177973 -393.650987) (xy 157.125643 -393.666352) (xy 157.071659 -393.674114) (xy 157.017121 -393.674114)
			(xy 156.963137 -393.666352) (xy 156.910807 -393.650987) (xy 156.861197 -393.62833) (xy 156.815316 -393.598844)
			(xy 156.774099 -393.563129) (xy 156.738384 -393.521912) (xy 156.708898 -393.476031) (xy 156.686241 -393.426421)
			(xy 156.670876 -393.374091) (xy 156.663114 -393.320107) (xy 156.662628 -393.292838) (xy 156.225748 -393.292838)
			(xy 156.225262 -393.320089) (xy 156.217506 -393.374037) (xy 156.202151 -393.426332) (xy 156.179509 -393.475909)
			(xy 156.150043 -393.521759) (xy 156.114352 -393.56295) (xy 156.073161 -393.598641) (xy 156.027311 -393.628107)
			(xy 155.977734 -393.650749) (xy 155.925439 -393.666104) (xy 155.871491 -393.67386) (xy 155.816989 -393.67386)
			(xy 155.763041 -393.666104) (xy 155.710746 -393.650749) (xy 155.661169 -393.628107) (xy 155.615319 -393.598641)
			(xy 155.574128 -393.56295) (xy 155.538437 -393.521759) (xy 155.508971 -393.475909) (xy 155.486329 -393.426332)
			(xy 155.470974 -393.374037) (xy 155.463218 -393.320089) (xy 155.462732 -393.292838) (xy 155.025852 -393.292838)
			(xy 155.025366 -393.320089) (xy 155.01761 -393.374037) (xy 155.002255 -393.426332) (xy 154.979613 -393.475909)
			(xy 154.950147 -393.521759) (xy 154.914456 -393.56295) (xy 154.873265 -393.598641) (xy 154.827415 -393.628107)
			(xy 154.777838 -393.650749) (xy 154.725543 -393.666104) (xy 154.671595 -393.67386) (xy 154.617093 -393.67386)
			(xy 154.563145 -393.666104) (xy 154.51085 -393.650749) (xy 154.461273 -393.628107) (xy 154.415423 -393.598641)
			(xy 154.374232 -393.56295) (xy 154.338541 -393.521759) (xy 154.309075 -393.475909) (xy 154.286433 -393.426332)
			(xy 154.271078 -393.374037) (xy 154.263322 -393.320089) (xy 154.262836 -393.292838) (xy 153.825956 -393.292838)
			(xy 153.82547 -393.320107) (xy 153.817708 -393.374091) (xy 153.802343 -393.426421) (xy 153.779686 -393.476031)
			(xy 153.7502 -393.521912) (xy 153.714485 -393.563129) (xy 153.673268 -393.598844) (xy 153.627387 -393.62833)
			(xy 153.577777 -393.650987) (xy 153.525447 -393.666352) (xy 153.471463 -393.674114) (xy 153.416925 -393.674114)
			(xy 153.362941 -393.666352) (xy 153.310611 -393.650987) (xy 153.261001 -393.62833) (xy 153.21512 -393.598844)
			(xy 153.173903 -393.563129) (xy 153.138188 -393.521912) (xy 153.108702 -393.476031) (xy 153.086045 -393.426421)
			(xy 153.07068 -393.374091) (xy 153.062918 -393.320107) (xy 153.062432 -393.292838) (xy 152.62606 -393.292838)
			(xy 152.625574 -393.320107) (xy 152.617812 -393.374091) (xy 152.602447 -393.426421) (xy 152.57979 -393.476031)
			(xy 152.550304 -393.521912) (xy 152.514589 -393.563129) (xy 152.473372 -393.598844) (xy 152.427491 -393.62833)
			(xy 152.377881 -393.650987) (xy 152.325551 -393.666352) (xy 152.271567 -393.674114) (xy 152.217029 -393.674114)
			(xy 152.163045 -393.666352) (xy 152.110715 -393.650987) (xy 152.061105 -393.62833) (xy 152.015224 -393.598844)
			(xy 151.974007 -393.563129) (xy 151.938292 -393.521912) (xy 151.908806 -393.476031) (xy 151.886149 -393.426421)
			(xy 151.870784 -393.374091) (xy 151.863022 -393.320107) (xy 151.862536 -393.292838) (xy 151.425656 -393.292838)
			(xy 151.42517 -393.320089) (xy 151.417414 -393.374037) (xy 151.402059 -393.426332) (xy 151.379417 -393.475909)
			(xy 151.349951 -393.521759) (xy 151.31426 -393.56295) (xy 151.273069 -393.598641) (xy 151.227219 -393.628107)
			(xy 151.177642 -393.650749) (xy 151.125347 -393.666104) (xy 151.071399 -393.67386) (xy 151.016897 -393.67386)
			(xy 150.962949 -393.666104) (xy 150.910654 -393.650749) (xy 150.861077 -393.628107) (xy 150.815227 -393.598641)
			(xy 150.774036 -393.56295) (xy 150.738345 -393.521759) (xy 150.708879 -393.475909) (xy 150.686237 -393.426332)
			(xy 150.670882 -393.374037) (xy 150.663126 -393.320089) (xy 150.66264 -393.292838) (xy 150.22576 -393.292838)
			(xy 150.225274 -393.320089) (xy 150.217518 -393.374037) (xy 150.202163 -393.426332) (xy 150.179521 -393.475909)
			(xy 150.150055 -393.521759) (xy 150.114364 -393.56295) (xy 150.073173 -393.598641) (xy 150.027323 -393.628107)
			(xy 149.977746 -393.650749) (xy 149.925451 -393.666104) (xy 149.871503 -393.67386) (xy 149.817001 -393.67386)
			(xy 149.763053 -393.666104) (xy 149.710758 -393.650749) (xy 149.661181 -393.628107) (xy 149.615331 -393.598641)
			(xy 149.57414 -393.56295) (xy 149.538449 -393.521759) (xy 149.508983 -393.475909) (xy 149.486341 -393.426332)
			(xy 149.470986 -393.374037) (xy 149.46323 -393.320089) (xy 149.462744 -393.292838) (xy 149.025864 -393.292838)
			(xy 149.025378 -393.320107) (xy 149.017616 -393.374091) (xy 149.002251 -393.426421) (xy 148.979594 -393.476031)
			(xy 148.950108 -393.521912) (xy 148.914393 -393.563129) (xy 148.873176 -393.598844) (xy 148.827295 -393.62833)
			(xy 148.777685 -393.650987) (xy 148.725355 -393.666352) (xy 148.671371 -393.674114) (xy 148.616833 -393.674114)
			(xy 148.562849 -393.666352) (xy 148.510519 -393.650987) (xy 148.460909 -393.62833) (xy 148.415028 -393.598844)
			(xy 148.373811 -393.563129) (xy 148.338096 -393.521912) (xy 148.30861 -393.476031) (xy 148.285953 -393.426421)
			(xy 148.270588 -393.374091) (xy 148.262826 -393.320107) (xy 148.26234 -393.292838) (xy 147.825968 -393.292838)
			(xy 147.825482 -393.320107) (xy 147.81772 -393.374091) (xy 147.802355 -393.426421) (xy 147.779698 -393.476031)
			(xy 147.750212 -393.521912) (xy 147.714497 -393.563129) (xy 147.67328 -393.598844) (xy 147.627399 -393.62833)
			(xy 147.577789 -393.650987) (xy 147.525459 -393.666352) (xy 147.471475 -393.674114) (xy 147.416937 -393.674114)
			(xy 147.362953 -393.666352) (xy 147.310623 -393.650987) (xy 147.261013 -393.62833) (xy 147.215132 -393.598844)
			(xy 147.173915 -393.563129) (xy 147.1382 -393.521912) (xy 147.108714 -393.476031) (xy 147.086057 -393.426421)
			(xy 147.070692 -393.374091) (xy 147.06293 -393.320107) (xy 147.062444 -393.292838) (xy 133.298184 -393.292838)
			(xy 133.297698 -393.320107) (xy 133.289936 -393.374091) (xy 133.274571 -393.426421) (xy 133.251914 -393.476031)
			(xy 133.222428 -393.521912) (xy 133.186713 -393.563129) (xy 133.145496 -393.598844) (xy 133.099615 -393.62833)
			(xy 133.050005 -393.650987) (xy 132.997675 -393.666352) (xy 132.943691 -393.674114) (xy 132.889153 -393.674114)
			(xy 132.835169 -393.666352) (xy 132.782839 -393.650987) (xy 132.733229 -393.62833) (xy 132.687348 -393.598844)
			(xy 132.646131 -393.563129) (xy 132.610416 -393.521912) (xy 132.58093 -393.476031) (xy 132.558273 -393.426421)
			(xy 132.542908 -393.374091) (xy 132.535146 -393.320107) (xy 132.53466 -393.292838) (xy 132.098288 -393.292838)
			(xy 132.097802 -393.320107) (xy 132.09004 -393.374091) (xy 132.074675 -393.426421) (xy 132.052018 -393.476031)
			(xy 132.022532 -393.521912) (xy 131.986817 -393.563129) (xy 131.9456 -393.598844) (xy 131.899719 -393.62833)
			(xy 131.850109 -393.650987) (xy 131.797779 -393.666352) (xy 131.743795 -393.674114) (xy 131.689257 -393.674114)
			(xy 131.635273 -393.666352) (xy 131.582943 -393.650987) (xy 131.533333 -393.62833) (xy 131.487452 -393.598844)
			(xy 131.446235 -393.563129) (xy 131.41052 -393.521912) (xy 131.381034 -393.476031) (xy 131.358377 -393.426421)
			(xy 131.343012 -393.374091) (xy 131.33525 -393.320107) (xy 131.334764 -393.292838) (xy 130.897884 -393.292838)
			(xy 130.897398 -393.320089) (xy 130.889642 -393.374037) (xy 130.874287 -393.426332) (xy 130.851645 -393.475909)
			(xy 130.822179 -393.521759) (xy 130.786488 -393.56295) (xy 130.745297 -393.598641) (xy 130.699447 -393.628107)
			(xy 130.64987 -393.650749) (xy 130.597575 -393.666104) (xy 130.543627 -393.67386) (xy 130.489125 -393.67386)
			(xy 130.435177 -393.666104) (xy 130.382882 -393.650749) (xy 130.333305 -393.628107) (xy 130.287455 -393.598641)
			(xy 130.246264 -393.56295) (xy 130.210573 -393.521759) (xy 130.181107 -393.475909) (xy 130.158465 -393.426332)
			(xy 130.14311 -393.374037) (xy 130.135354 -393.320089) (xy 130.134868 -393.292838) (xy 129.697988 -393.292838)
			(xy 129.697502 -393.320089) (xy 129.689746 -393.374037) (xy 129.674391 -393.426332) (xy 129.651749 -393.475909)
			(xy 129.622283 -393.521759) (xy 129.586592 -393.56295) (xy 129.545401 -393.598641) (xy 129.499551 -393.628107)
			(xy 129.449974 -393.650749) (xy 129.397679 -393.666104) (xy 129.343731 -393.67386) (xy 129.289229 -393.67386)
			(xy 129.235281 -393.666104) (xy 129.182986 -393.650749) (xy 129.133409 -393.628107) (xy 129.087559 -393.598641)
			(xy 129.046368 -393.56295) (xy 129.010677 -393.521759) (xy 128.981211 -393.475909) (xy 128.958569 -393.426332)
			(xy 128.943214 -393.374037) (xy 128.935458 -393.320089) (xy 128.934972 -393.292838) (xy 128.498092 -393.292838)
			(xy 128.497606 -393.320089) (xy 128.48985 -393.374037) (xy 128.474495 -393.426332) (xy 128.451853 -393.475909)
			(xy 128.422387 -393.521759) (xy 128.386696 -393.56295) (xy 128.345505 -393.598641) (xy 128.299655 -393.628107)
			(xy 128.250078 -393.650749) (xy 128.197783 -393.666104) (xy 128.143835 -393.67386) (xy 128.089333 -393.67386)
			(xy 128.035385 -393.666104) (xy 127.98309 -393.650749) (xy 127.933513 -393.628107) (xy 127.887663 -393.598641)
			(xy 127.846472 -393.56295) (xy 127.810781 -393.521759) (xy 127.781315 -393.475909) (xy 127.758673 -393.426332)
			(xy 127.743318 -393.374037) (xy 127.735562 -393.320089) (xy 127.735076 -393.292838) (xy 127.298196 -393.292838)
			(xy 127.29771 -393.320089) (xy 127.289954 -393.374037) (xy 127.274599 -393.426332) (xy 127.251957 -393.475909)
			(xy 127.222491 -393.521759) (xy 127.1868 -393.56295) (xy 127.145609 -393.598641) (xy 127.099759 -393.628107)
			(xy 127.050182 -393.650749) (xy 126.997887 -393.666104) (xy 126.943939 -393.67386) (xy 126.889437 -393.67386)
			(xy 126.835489 -393.666104) (xy 126.783194 -393.650749) (xy 126.733617 -393.628107) (xy 126.687767 -393.598641)
			(xy 126.646576 -393.56295) (xy 126.610885 -393.521759) (xy 126.581419 -393.475909) (xy 126.558777 -393.426332)
			(xy 126.543422 -393.374037) (xy 126.535666 -393.320089) (xy 126.53518 -393.292838) (xy 126.0983 -393.292838)
			(xy 126.097814 -393.320107) (xy 126.090052 -393.374091) (xy 126.074687 -393.426421) (xy 126.05203 -393.476031)
			(xy 126.022544 -393.521912) (xy 125.986829 -393.563129) (xy 125.945612 -393.598844) (xy 125.899731 -393.62833)
			(xy 125.850121 -393.650987) (xy 125.797791 -393.666352) (xy 125.743807 -393.674114) (xy 125.689269 -393.674114)
			(xy 125.635285 -393.666352) (xy 125.582955 -393.650987) (xy 125.533345 -393.62833) (xy 125.487464 -393.598844)
			(xy 125.446247 -393.563129) (xy 125.410532 -393.521912) (xy 125.381046 -393.476031) (xy 125.358389 -393.426421)
			(xy 125.343024 -393.374091) (xy 125.335262 -393.320107) (xy 125.334776 -393.292838) (xy 124.898404 -393.292838)
			(xy 124.897918 -393.320107) (xy 124.890156 -393.374091) (xy 124.874791 -393.426421) (xy 124.852134 -393.476031)
			(xy 124.822648 -393.521912) (xy 124.786933 -393.563129) (xy 124.745716 -393.598844) (xy 124.699835 -393.62833)
			(xy 124.650225 -393.650987) (xy 124.597895 -393.666352) (xy 124.543911 -393.674114) (xy 124.489373 -393.674114)
			(xy 124.435389 -393.666352) (xy 124.383059 -393.650987) (xy 124.333449 -393.62833) (xy 124.287568 -393.598844)
			(xy 124.246351 -393.563129) (xy 124.210636 -393.521912) (xy 124.18115 -393.476031) (xy 124.158493 -393.426421)
			(xy 124.143128 -393.374091) (xy 124.135366 -393.320107) (xy 124.13488 -393.292838) (xy 123.698 -393.292838)
			(xy 123.697514 -393.320089) (xy 123.689758 -393.374037) (xy 123.674403 -393.426332) (xy 123.651761 -393.475909)
			(xy 123.622295 -393.521759) (xy 123.586604 -393.56295) (xy 123.545413 -393.598641) (xy 123.499563 -393.628107)
			(xy 123.449986 -393.650749) (xy 123.397691 -393.666104) (xy 123.343743 -393.67386) (xy 123.289241 -393.67386)
			(xy 123.235293 -393.666104) (xy 123.182998 -393.650749) (xy 123.133421 -393.628107) (xy 123.087571 -393.598641)
			(xy 123.04638 -393.56295) (xy 123.010689 -393.521759) (xy 122.981223 -393.475909) (xy 122.958581 -393.426332)
			(xy 122.943226 -393.374037) (xy 122.93547 -393.320089) (xy 122.934984 -393.292838) (xy 122.498104 -393.292838)
			(xy 122.497618 -393.320089) (xy 122.489862 -393.374037) (xy 122.474507 -393.426332) (xy 122.451865 -393.475909)
			(xy 122.422399 -393.521759) (xy 122.386708 -393.56295) (xy 122.345517 -393.598641) (xy 122.299667 -393.628107)
			(xy 122.25009 -393.650749) (xy 122.197795 -393.666104) (xy 122.143847 -393.67386) (xy 122.089345 -393.67386)
			(xy 122.035397 -393.666104) (xy 121.983102 -393.650749) (xy 121.933525 -393.628107) (xy 121.887675 -393.598641)
			(xy 121.846484 -393.56295) (xy 121.810793 -393.521759) (xy 121.781327 -393.475909) (xy 121.758685 -393.426332)
			(xy 121.74333 -393.374037) (xy 121.735574 -393.320089) (xy 121.735088 -393.292838) (xy 121.298208 -393.292838)
			(xy 121.297722 -393.320107) (xy 121.28996 -393.374091) (xy 121.274595 -393.426421) (xy 121.251938 -393.476031)
			(xy 121.222452 -393.521912) (xy 121.186737 -393.563129) (xy 121.14552 -393.598844) (xy 121.099639 -393.62833)
			(xy 121.050029 -393.650987) (xy 120.997699 -393.666352) (xy 120.943715 -393.674114) (xy 120.889177 -393.674114)
			(xy 120.835193 -393.666352) (xy 120.782863 -393.650987) (xy 120.733253 -393.62833) (xy 120.687372 -393.598844)
			(xy 120.646155 -393.563129) (xy 120.61044 -393.521912) (xy 120.580954 -393.476031) (xy 120.558297 -393.426421)
			(xy 120.542932 -393.374091) (xy 120.53517 -393.320107) (xy 120.534684 -393.292838) (xy 120.098312 -393.292838)
			(xy 120.097826 -393.320107) (xy 120.090064 -393.374091) (xy 120.074699 -393.426421) (xy 120.052042 -393.476031)
			(xy 120.022556 -393.521912) (xy 119.986841 -393.563129) (xy 119.945624 -393.598844) (xy 119.899743 -393.62833)
			(xy 119.850133 -393.650987) (xy 119.797803 -393.666352) (xy 119.743819 -393.674114) (xy 119.689281 -393.674114)
			(xy 119.635297 -393.666352) (xy 119.582967 -393.650987) (xy 119.533357 -393.62833) (xy 119.487476 -393.598844)
			(xy 119.446259 -393.563129) (xy 119.410544 -393.521912) (xy 119.381058 -393.476031) (xy 119.358401 -393.426421)
			(xy 119.343036 -393.374091) (xy 119.335274 -393.320107) (xy 119.334788 -393.292838) (xy 118.897908 -393.292838)
			(xy 118.897422 -393.320089) (xy 118.889666 -393.374037) (xy 118.874311 -393.426332) (xy 118.851669 -393.475909)
			(xy 118.822203 -393.521759) (xy 118.786512 -393.56295) (xy 118.745321 -393.598641) (xy 118.699471 -393.628107)
			(xy 118.649894 -393.650749) (xy 118.597599 -393.666104) (xy 118.543651 -393.67386) (xy 118.489149 -393.67386)
			(xy 118.435201 -393.666104) (xy 118.382906 -393.650749) (xy 118.333329 -393.628107) (xy 118.287479 -393.598641)
			(xy 118.246288 -393.56295) (xy 118.210597 -393.521759) (xy 118.181131 -393.475909) (xy 118.158489 -393.426332)
			(xy 118.143134 -393.374037) (xy 118.135378 -393.320089) (xy 118.134892 -393.292838) (xy 117.698012 -393.292838)
			(xy 117.697526 -393.320089) (xy 117.68977 -393.374037) (xy 117.674415 -393.426332) (xy 117.651773 -393.475909)
			(xy 117.622307 -393.521759) (xy 117.586616 -393.56295) (xy 117.545425 -393.598641) (xy 117.499575 -393.628107)
			(xy 117.449998 -393.650749) (xy 117.397703 -393.666104) (xy 117.343755 -393.67386) (xy 117.289253 -393.67386)
			(xy 117.235305 -393.666104) (xy 117.18301 -393.650749) (xy 117.133433 -393.628107) (xy 117.087583 -393.598641)
			(xy 117.046392 -393.56295) (xy 117.010701 -393.521759) (xy 116.981235 -393.475909) (xy 116.958593 -393.426332)
			(xy 116.943238 -393.374037) (xy 116.935482 -393.320089) (xy 116.934996 -393.292838) (xy 116.498116 -393.292838)
			(xy 116.49763 -393.320107) (xy 116.489868 -393.374091) (xy 116.474503 -393.426421) (xy 116.451846 -393.476031)
			(xy 116.42236 -393.521912) (xy 116.386645 -393.563129) (xy 116.345428 -393.598844) (xy 116.299547 -393.62833)
			(xy 116.249937 -393.650987) (xy 116.197607 -393.666352) (xy 116.143623 -393.674114) (xy 116.089085 -393.674114)
			(xy 116.035101 -393.666352) (xy 115.982771 -393.650987) (xy 115.933161 -393.62833) (xy 115.88728 -393.598844)
			(xy 115.846063 -393.563129) (xy 115.810348 -393.521912) (xy 115.780862 -393.476031) (xy 115.758205 -393.426421)
			(xy 115.74284 -393.374091) (xy 115.735078 -393.320107) (xy 115.734592 -393.292838) (xy 115.29822 -393.292838)
			(xy 115.297734 -393.320107) (xy 115.289972 -393.374091) (xy 115.274607 -393.426421) (xy 115.25195 -393.476031)
			(xy 115.222464 -393.521912) (xy 115.186749 -393.563129) (xy 115.145532 -393.598844) (xy 115.099651 -393.62833)
			(xy 115.050041 -393.650987) (xy 114.997711 -393.666352) (xy 114.943727 -393.674114) (xy 114.889189 -393.674114)
			(xy 114.835205 -393.666352) (xy 114.782875 -393.650987) (xy 114.733265 -393.62833) (xy 114.687384 -393.598844)
			(xy 114.646167 -393.563129) (xy 114.610452 -393.521912) (xy 114.580966 -393.476031) (xy 114.558309 -393.426421)
			(xy 114.542944 -393.374091) (xy 114.535182 -393.320107) (xy 114.534696 -393.292838) (xy 98.725736 -393.292838)
			(xy 98.72525 -393.320089) (xy 98.717494 -393.374037) (xy 98.702139 -393.426332) (xy 98.679497 -393.475909)
			(xy 98.650031 -393.521759) (xy 98.61434 -393.56295) (xy 98.573149 -393.598641) (xy 98.527299 -393.628107)
			(xy 98.477722 -393.650749) (xy 98.425427 -393.666104) (xy 98.371479 -393.67386) (xy 98.316977 -393.67386)
			(xy 98.263029 -393.666104) (xy 98.210734 -393.650749) (xy 98.161157 -393.628107) (xy 98.115307 -393.598641)
			(xy 98.074116 -393.56295) (xy 98.038425 -393.521759) (xy 98.008959 -393.475909) (xy 97.986317 -393.426332)
			(xy 97.970962 -393.374037) (xy 97.963206 -393.320089) (xy 97.96272 -393.292838) (xy 97.52584 -393.292838)
			(xy 97.525354 -393.320089) (xy 97.517598 -393.374037) (xy 97.502243 -393.426332) (xy 97.479601 -393.475909)
			(xy 97.450135 -393.521759) (xy 97.414444 -393.56295) (xy 97.373253 -393.598641) (xy 97.327403 -393.628107)
			(xy 97.277826 -393.650749) (xy 97.225531 -393.666104) (xy 97.171583 -393.67386) (xy 97.117081 -393.67386)
			(xy 97.063133 -393.666104) (xy 97.010838 -393.650749) (xy 96.961261 -393.628107) (xy 96.915411 -393.598641)
			(xy 96.87422 -393.56295) (xy 96.838529 -393.521759) (xy 96.809063 -393.475909) (xy 96.786421 -393.426332)
			(xy 96.771066 -393.374037) (xy 96.76331 -393.320089) (xy 96.762824 -393.292838) (xy 96.325944 -393.292838)
			(xy 96.325458 -393.320107) (xy 96.317696 -393.374091) (xy 96.302331 -393.426421) (xy 96.279674 -393.476031)
			(xy 96.250188 -393.521912) (xy 96.214473 -393.563129) (xy 96.173256 -393.598844) (xy 96.127375 -393.62833)
			(xy 96.077765 -393.650987) (xy 96.025435 -393.666352) (xy 95.971451 -393.674114) (xy 95.916913 -393.674114)
			(xy 95.862929 -393.666352) (xy 95.810599 -393.650987) (xy 95.760989 -393.62833) (xy 95.715108 -393.598844)
			(xy 95.673891 -393.563129) (xy 95.638176 -393.521912) (xy 95.60869 -393.476031) (xy 95.586033 -393.426421)
			(xy 95.570668 -393.374091) (xy 95.562906 -393.320107) (xy 95.56242 -393.292838) (xy 95.126048 -393.292838)
			(xy 95.125562 -393.320107) (xy 95.1178 -393.374091) (xy 95.102435 -393.426421) (xy 95.079778 -393.476031)
			(xy 95.050292 -393.521912) (xy 95.014577 -393.563129) (xy 94.97336 -393.598844) (xy 94.927479 -393.62833)
			(xy 94.877869 -393.650987) (xy 94.825539 -393.666352) (xy 94.771555 -393.674114) (xy 94.717017 -393.674114)
			(xy 94.663033 -393.666352) (xy 94.610703 -393.650987) (xy 94.561093 -393.62833) (xy 94.515212 -393.598844)
			(xy 94.473995 -393.563129) (xy 94.43828 -393.521912) (xy 94.408794 -393.476031) (xy 94.386137 -393.426421)
			(xy 94.370772 -393.374091) (xy 94.36301 -393.320107) (xy 94.362524 -393.292838) (xy 93.926152 -393.292838)
			(xy 93.925666 -393.320107) (xy 93.917904 -393.374091) (xy 93.902539 -393.426421) (xy 93.879882 -393.476031)
			(xy 93.850396 -393.521912) (xy 93.814681 -393.563129) (xy 93.773464 -393.598844) (xy 93.727583 -393.62833)
			(xy 93.677973 -393.650987) (xy 93.625643 -393.666352) (xy 93.571659 -393.674114) (xy 93.517121 -393.674114)
			(xy 93.463137 -393.666352) (xy 93.410807 -393.650987) (xy 93.361197 -393.62833) (xy 93.315316 -393.598844)
			(xy 93.274099 -393.563129) (xy 93.238384 -393.521912) (xy 93.208898 -393.476031) (xy 93.186241 -393.426421)
			(xy 93.170876 -393.374091) (xy 93.163114 -393.320107) (xy 93.162628 -393.292838) (xy 92.726256 -393.292838)
			(xy 92.72577 -393.320107) (xy 92.718008 -393.374091) (xy 92.702643 -393.426421) (xy 92.679986 -393.476031)
			(xy 92.6505 -393.521912) (xy 92.614785 -393.563129) (xy 92.573568 -393.598844) (xy 92.527687 -393.62833)
			(xy 92.478077 -393.650987) (xy 92.425747 -393.666352) (xy 92.371763 -393.674114) (xy 92.317225 -393.674114)
			(xy 92.263241 -393.666352) (xy 92.210911 -393.650987) (xy 92.161301 -393.62833) (xy 92.11542 -393.598844)
			(xy 92.074203 -393.563129) (xy 92.038488 -393.521912) (xy 92.009002 -393.476031) (xy 91.986345 -393.426421)
			(xy 91.97098 -393.374091) (xy 91.963218 -393.320107) (xy 91.962732 -393.292838) (xy 91.525852 -393.292838)
			(xy 91.525366 -393.320089) (xy 91.51761 -393.374037) (xy 91.502255 -393.426332) (xy 91.479613 -393.475909)
			(xy 91.450147 -393.521759) (xy 91.414456 -393.56295) (xy 91.373265 -393.598641) (xy 91.327415 -393.628107)
			(xy 91.277838 -393.650749) (xy 91.225543 -393.666104) (xy 91.171595 -393.67386) (xy 91.117093 -393.67386)
			(xy 91.063145 -393.666104) (xy 91.01085 -393.650749) (xy 90.961273 -393.628107) (xy 90.915423 -393.598641)
			(xy 90.874232 -393.56295) (xy 90.838541 -393.521759) (xy 90.809075 -393.475909) (xy 90.786433 -393.426332)
			(xy 90.771078 -393.374037) (xy 90.763322 -393.320089) (xy 90.762836 -393.292838) (xy 90.325956 -393.292838)
			(xy 90.32547 -393.320089) (xy 90.317714 -393.374037) (xy 90.302359 -393.426332) (xy 90.279717 -393.475909)
			(xy 90.250251 -393.521759) (xy 90.21456 -393.56295) (xy 90.173369 -393.598641) (xy 90.127519 -393.628107)
			(xy 90.077942 -393.650749) (xy 90.025647 -393.666104) (xy 89.971699 -393.67386) (xy 89.917197 -393.67386)
			(xy 89.863249 -393.666104) (xy 89.810954 -393.650749) (xy 89.761377 -393.628107) (xy 89.715527 -393.598641)
			(xy 89.674336 -393.56295) (xy 89.638645 -393.521759) (xy 89.609179 -393.475909) (xy 89.586537 -393.426332)
			(xy 89.571182 -393.374037) (xy 89.563426 -393.320089) (xy 89.56294 -393.292838) (xy 89.12606 -393.292838)
			(xy 89.125574 -393.320107) (xy 89.117812 -393.374091) (xy 89.102447 -393.426421) (xy 89.07979 -393.476031)
			(xy 89.050304 -393.521912) (xy 89.014589 -393.563129) (xy 88.973372 -393.598844) (xy 88.927491 -393.62833)
			(xy 88.877881 -393.650987) (xy 88.825551 -393.666352) (xy 88.771567 -393.674114) (xy 88.717029 -393.674114)
			(xy 88.663045 -393.666352) (xy 88.610715 -393.650987) (xy 88.561105 -393.62833) (xy 88.515224 -393.598844)
			(xy 88.474007 -393.563129) (xy 88.438292 -393.521912) (xy 88.408806 -393.476031) (xy 88.386149 -393.426421)
			(xy 88.370784 -393.374091) (xy 88.363022 -393.320107) (xy 88.362536 -393.292838) (xy 87.926164 -393.292838)
			(xy 87.925678 -393.320107) (xy 87.917916 -393.374091) (xy 87.902551 -393.426421) (xy 87.879894 -393.476031)
			(xy 87.850408 -393.521912) (xy 87.814693 -393.563129) (xy 87.773476 -393.598844) (xy 87.727595 -393.62833)
			(xy 87.677985 -393.650987) (xy 87.625655 -393.666352) (xy 87.571671 -393.674114) (xy 87.517133 -393.674114)
			(xy 87.463149 -393.666352) (xy 87.410819 -393.650987) (xy 87.361209 -393.62833) (xy 87.315328 -393.598844)
			(xy 87.274111 -393.563129) (xy 87.238396 -393.521912) (xy 87.20891 -393.476031) (xy 87.186253 -393.426421)
			(xy 87.170888 -393.374091) (xy 87.163126 -393.320107) (xy 87.16264 -393.292838) (xy 86.72576 -393.292838)
			(xy 86.725274 -393.320089) (xy 86.717518 -393.374037) (xy 86.702163 -393.426332) (xy 86.679521 -393.475909)
			(xy 86.650055 -393.521759) (xy 86.614364 -393.56295) (xy 86.573173 -393.598641) (xy 86.527323 -393.628107)
			(xy 86.477746 -393.650749) (xy 86.425451 -393.666104) (xy 86.371503 -393.67386) (xy 86.317001 -393.67386)
			(xy 86.263053 -393.666104) (xy 86.210758 -393.650749) (xy 86.161181 -393.628107) (xy 86.115331 -393.598641)
			(xy 86.07414 -393.56295) (xy 86.038449 -393.521759) (xy 86.008983 -393.475909) (xy 85.986341 -393.426332)
			(xy 85.970986 -393.374037) (xy 85.96323 -393.320089) (xy 85.962744 -393.292838) (xy 85.525864 -393.292838)
			(xy 85.525378 -393.320089) (xy 85.517622 -393.374037) (xy 85.502267 -393.426332) (xy 85.479625 -393.475909)
			(xy 85.450159 -393.521759) (xy 85.414468 -393.56295) (xy 85.373277 -393.598641) (xy 85.327427 -393.628107)
			(xy 85.27785 -393.650749) (xy 85.225555 -393.666104) (xy 85.171607 -393.67386) (xy 85.117105 -393.67386)
			(xy 85.063157 -393.666104) (xy 85.010862 -393.650749) (xy 84.961285 -393.628107) (xy 84.915435 -393.598641)
			(xy 84.874244 -393.56295) (xy 84.838553 -393.521759) (xy 84.809087 -393.475909) (xy 84.786445 -393.426332)
			(xy 84.77109 -393.374037) (xy 84.763334 -393.320089) (xy 84.762848 -393.292838) (xy 84.325968 -393.292838)
			(xy 84.325482 -393.320107) (xy 84.31772 -393.374091) (xy 84.302355 -393.426421) (xy 84.279698 -393.476031)
			(xy 84.250212 -393.521912) (xy 84.214497 -393.563129) (xy 84.17328 -393.598844) (xy 84.127399 -393.62833)
			(xy 84.077789 -393.650987) (xy 84.025459 -393.666352) (xy 83.971475 -393.674114) (xy 83.916937 -393.674114)
			(xy 83.862953 -393.666352) (xy 83.810623 -393.650987) (xy 83.761013 -393.62833) (xy 83.715132 -393.598844)
			(xy 83.673915 -393.563129) (xy 83.6382 -393.521912) (xy 83.608714 -393.476031) (xy 83.586057 -393.426421)
			(xy 83.570692 -393.374091) (xy 83.56293 -393.320107) (xy 83.562444 -393.292838) (xy 83.126072 -393.292838)
			(xy 83.125586 -393.320107) (xy 83.117824 -393.374091) (xy 83.102459 -393.426421) (xy 83.079802 -393.476031)
			(xy 83.050316 -393.521912) (xy 83.014601 -393.563129) (xy 82.973384 -393.598844) (xy 82.927503 -393.62833)
			(xy 82.877893 -393.650987) (xy 82.825563 -393.666352) (xy 82.771579 -393.674114) (xy 82.717041 -393.674114)
			(xy 82.663057 -393.666352) (xy 82.610727 -393.650987) (xy 82.561117 -393.62833) (xy 82.515236 -393.598844)
			(xy 82.474019 -393.563129) (xy 82.438304 -393.521912) (xy 82.408818 -393.476031) (xy 82.386161 -393.426421)
			(xy 82.370796 -393.374091) (xy 82.363034 -393.320107) (xy 82.362548 -393.292838) (xy 81.925668 -393.292838)
			(xy 81.925182 -393.320089) (xy 81.917426 -393.374037) (xy 81.902071 -393.426332) (xy 81.879429 -393.475909)
			(xy 81.849963 -393.521759) (xy 81.814272 -393.56295) (xy 81.773081 -393.598641) (xy 81.727231 -393.628107)
			(xy 81.677654 -393.650749) (xy 81.625359 -393.666104) (xy 81.571411 -393.67386) (xy 81.516909 -393.67386)
			(xy 81.462961 -393.666104) (xy 81.410666 -393.650749) (xy 81.361089 -393.628107) (xy 81.315239 -393.598641)
			(xy 81.274048 -393.56295) (xy 81.238357 -393.521759) (xy 81.208891 -393.475909) (xy 81.186249 -393.426332)
			(xy 81.170894 -393.374037) (xy 81.163138 -393.320089) (xy 81.162652 -393.292838) (xy 80.725772 -393.292838)
			(xy 80.725286 -393.320089) (xy 80.71753 -393.374037) (xy 80.702175 -393.426332) (xy 80.679533 -393.475909)
			(xy 80.650067 -393.521759) (xy 80.614376 -393.56295) (xy 80.573185 -393.598641) (xy 80.527335 -393.628107)
			(xy 80.477758 -393.650749) (xy 80.425463 -393.666104) (xy 80.371515 -393.67386) (xy 80.317013 -393.67386)
			(xy 80.263065 -393.666104) (xy 80.21077 -393.650749) (xy 80.161193 -393.628107) (xy 80.115343 -393.598641)
			(xy 80.074152 -393.56295) (xy 80.038461 -393.521759) (xy 80.008995 -393.475909) (xy 79.986353 -393.426332)
			(xy 79.970998 -393.374037) (xy 79.963242 -393.320089) (xy 79.962756 -393.292838) (xy 66.197988 -393.292838)
			(xy 66.197502 -393.320089) (xy 66.189746 -393.374037) (xy 66.174391 -393.426332) (xy 66.151749 -393.475909)
			(xy 66.122283 -393.521759) (xy 66.086592 -393.56295) (xy 66.045401 -393.598641) (xy 65.999551 -393.628107)
			(xy 65.949974 -393.650749) (xy 65.897679 -393.666104) (xy 65.843731 -393.67386) (xy 65.789229 -393.67386)
			(xy 65.735281 -393.666104) (xy 65.682986 -393.650749) (xy 65.633409 -393.628107) (xy 65.587559 -393.598641)
			(xy 65.546368 -393.56295) (xy 65.510677 -393.521759) (xy 65.481211 -393.475909) (xy 65.458569 -393.426332)
			(xy 65.443214 -393.374037) (xy 65.435458 -393.320089) (xy 65.434972 -393.292838) (xy 64.998092 -393.292838)
			(xy 64.997606 -393.320089) (xy 64.98985 -393.374037) (xy 64.974495 -393.426332) (xy 64.951853 -393.475909)
			(xy 64.922387 -393.521759) (xy 64.886696 -393.56295) (xy 64.845505 -393.598641) (xy 64.799655 -393.628107)
			(xy 64.750078 -393.650749) (xy 64.697783 -393.666104) (xy 64.643835 -393.67386) (xy 64.589333 -393.67386)
			(xy 64.535385 -393.666104) (xy 64.48309 -393.650749) (xy 64.433513 -393.628107) (xy 64.387663 -393.598641)
			(xy 64.346472 -393.56295) (xy 64.310781 -393.521759) (xy 64.281315 -393.475909) (xy 64.258673 -393.426332)
			(xy 64.243318 -393.374037) (xy 64.235562 -393.320089) (xy 64.235076 -393.292838) (xy 63.798196 -393.292838)
			(xy 63.79771 -393.320107) (xy 63.789948 -393.374091) (xy 63.774583 -393.426421) (xy 63.751926 -393.476031)
			(xy 63.72244 -393.521912) (xy 63.686725 -393.563129) (xy 63.645508 -393.598844) (xy 63.599627 -393.62833)
			(xy 63.550017 -393.650987) (xy 63.497687 -393.666352) (xy 63.443703 -393.674114) (xy 63.389165 -393.674114)
			(xy 63.335181 -393.666352) (xy 63.282851 -393.650987) (xy 63.233241 -393.62833) (xy 63.18736 -393.598844)
			(xy 63.146143 -393.563129) (xy 63.110428 -393.521912) (xy 63.080942 -393.476031) (xy 63.058285 -393.426421)
			(xy 63.04292 -393.374091) (xy 63.035158 -393.320107) (xy 63.034672 -393.292838) (xy 62.5983 -393.292838)
			(xy 62.597814 -393.320107) (xy 62.590052 -393.374091) (xy 62.574687 -393.426421) (xy 62.55203 -393.476031)
			(xy 62.522544 -393.521912) (xy 62.486829 -393.563129) (xy 62.445612 -393.598844) (xy 62.399731 -393.62833)
			(xy 62.350121 -393.650987) (xy 62.297791 -393.666352) (xy 62.243807 -393.674114) (xy 62.189269 -393.674114)
			(xy 62.135285 -393.666352) (xy 62.082955 -393.650987) (xy 62.033345 -393.62833) (xy 61.987464 -393.598844)
			(xy 61.946247 -393.563129) (xy 61.910532 -393.521912) (xy 61.881046 -393.476031) (xy 61.858389 -393.426421)
			(xy 61.843024 -393.374091) (xy 61.835262 -393.320107) (xy 61.834776 -393.292838) (xy 61.398404 -393.292838)
			(xy 61.397918 -393.320107) (xy 61.390156 -393.374091) (xy 61.374791 -393.426421) (xy 61.352134 -393.476031)
			(xy 61.322648 -393.521912) (xy 61.286933 -393.563129) (xy 61.245716 -393.598844) (xy 61.199835 -393.62833)
			(xy 61.150225 -393.650987) (xy 61.097895 -393.666352) (xy 61.043911 -393.674114) (xy 60.989373 -393.674114)
			(xy 60.935389 -393.666352) (xy 60.883059 -393.650987) (xy 60.833449 -393.62833) (xy 60.787568 -393.598844)
			(xy 60.746351 -393.563129) (xy 60.710636 -393.521912) (xy 60.68115 -393.476031) (xy 60.658493 -393.426421)
			(xy 60.643128 -393.374091) (xy 60.635366 -393.320107) (xy 60.63488 -393.292838) (xy 60.198508 -393.292838)
			(xy 60.198022 -393.320107) (xy 60.19026 -393.374091) (xy 60.174895 -393.426421) (xy 60.152238 -393.476031)
			(xy 60.122752 -393.521912) (xy 60.087037 -393.563129) (xy 60.04582 -393.598844) (xy 59.999939 -393.62833)
			(xy 59.950329 -393.650987) (xy 59.897999 -393.666352) (xy 59.844015 -393.674114) (xy 59.789477 -393.674114)
			(xy 59.735493 -393.666352) (xy 59.683163 -393.650987) (xy 59.633553 -393.62833) (xy 59.587672 -393.598844)
			(xy 59.546455 -393.563129) (xy 59.51074 -393.521912) (xy 59.481254 -393.476031) (xy 59.458597 -393.426421)
			(xy 59.443232 -393.374091) (xy 59.43547 -393.320107) (xy 59.434984 -393.292838) (xy 58.998104 -393.292838)
			(xy 58.997618 -393.320089) (xy 58.989862 -393.374037) (xy 58.974507 -393.426332) (xy 58.951865 -393.475909)
			(xy 58.922399 -393.521759) (xy 58.886708 -393.56295) (xy 58.845517 -393.598641) (xy 58.799667 -393.628107)
			(xy 58.75009 -393.650749) (xy 58.697795 -393.666104) (xy 58.643847 -393.67386) (xy 58.589345 -393.67386)
			(xy 58.535397 -393.666104) (xy 58.483102 -393.650749) (xy 58.433525 -393.628107) (xy 58.387675 -393.598641)
			(xy 58.346484 -393.56295) (xy 58.310793 -393.521759) (xy 58.281327 -393.475909) (xy 58.258685 -393.426332)
			(xy 58.24333 -393.374037) (xy 58.235574 -393.320089) (xy 58.235088 -393.292838) (xy 57.798208 -393.292838)
			(xy 57.797722 -393.320089) (xy 57.789966 -393.374037) (xy 57.774611 -393.426332) (xy 57.751969 -393.475909)
			(xy 57.722503 -393.521759) (xy 57.686812 -393.56295) (xy 57.645621 -393.598641) (xy 57.599771 -393.628107)
			(xy 57.550194 -393.650749) (xy 57.497899 -393.666104) (xy 57.443951 -393.67386) (xy 57.389449 -393.67386)
			(xy 57.335501 -393.666104) (xy 57.283206 -393.650749) (xy 57.233629 -393.628107) (xy 57.187779 -393.598641)
			(xy 57.146588 -393.56295) (xy 57.110897 -393.521759) (xy 57.081431 -393.475909) (xy 57.058789 -393.426332)
			(xy 57.043434 -393.374037) (xy 57.035678 -393.320089) (xy 57.035192 -393.292838) (xy 56.598312 -393.292838)
			(xy 56.597826 -393.320107) (xy 56.590064 -393.374091) (xy 56.574699 -393.426421) (xy 56.552042 -393.476031)
			(xy 56.522556 -393.521912) (xy 56.486841 -393.563129) (xy 56.445624 -393.598844) (xy 56.399743 -393.62833)
			(xy 56.350133 -393.650987) (xy 56.297803 -393.666352) (xy 56.243819 -393.674114) (xy 56.189281 -393.674114)
			(xy 56.135297 -393.666352) (xy 56.082967 -393.650987) (xy 56.033357 -393.62833) (xy 55.987476 -393.598844)
			(xy 55.946259 -393.563129) (xy 55.910544 -393.521912) (xy 55.881058 -393.476031) (xy 55.858401 -393.426421)
			(xy 55.843036 -393.374091) (xy 55.835274 -393.320107) (xy 55.834788 -393.292838) (xy 55.398416 -393.292838)
			(xy 55.39793 -393.320107) (xy 55.390168 -393.374091) (xy 55.374803 -393.426421) (xy 55.352146 -393.476031)
			(xy 55.32266 -393.521912) (xy 55.286945 -393.563129) (xy 55.245728 -393.598844) (xy 55.199847 -393.62833)
			(xy 55.150237 -393.650987) (xy 55.097907 -393.666352) (xy 55.043923 -393.674114) (xy 54.989385 -393.674114)
			(xy 54.935401 -393.666352) (xy 54.883071 -393.650987) (xy 54.833461 -393.62833) (xy 54.78758 -393.598844)
			(xy 54.746363 -393.563129) (xy 54.710648 -393.521912) (xy 54.681162 -393.476031) (xy 54.658505 -393.426421)
			(xy 54.64314 -393.374091) (xy 54.635378 -393.320107) (xy 54.634892 -393.292838) (xy 54.198012 -393.292838)
			(xy 54.197526 -393.320089) (xy 54.18977 -393.374037) (xy 54.174415 -393.426332) (xy 54.151773 -393.475909)
			(xy 54.122307 -393.521759) (xy 54.086616 -393.56295) (xy 54.045425 -393.598641) (xy 53.999575 -393.628107)
			(xy 53.949998 -393.650749) (xy 53.897703 -393.666104) (xy 53.843755 -393.67386) (xy 53.789253 -393.67386)
			(xy 53.735305 -393.666104) (xy 53.68301 -393.650749) (xy 53.633433 -393.628107) (xy 53.587583 -393.598641)
			(xy 53.546392 -393.56295) (xy 53.510701 -393.521759) (xy 53.481235 -393.475909) (xy 53.458593 -393.426332)
			(xy 53.443238 -393.374037) (xy 53.435482 -393.320089) (xy 53.434996 -393.292838) (xy 52.998116 -393.292838)
			(xy 52.99763 -393.320089) (xy 52.989874 -393.374037) (xy 52.974519 -393.426332) (xy 52.951877 -393.475909)
			(xy 52.922411 -393.521759) (xy 52.88672 -393.56295) (xy 52.845529 -393.598641) (xy 52.799679 -393.628107)
			(xy 52.750102 -393.650749) (xy 52.697807 -393.666104) (xy 52.643859 -393.67386) (xy 52.589357 -393.67386)
			(xy 52.535409 -393.666104) (xy 52.483114 -393.650749) (xy 52.433537 -393.628107) (xy 52.387687 -393.598641)
			(xy 52.346496 -393.56295) (xy 52.310805 -393.521759) (xy 52.281339 -393.475909) (xy 52.258697 -393.426332)
			(xy 52.243342 -393.374037) (xy 52.235586 -393.320089) (xy 52.2351 -393.292838) (xy 51.79822 -393.292838)
			(xy 51.797734 -393.320107) (xy 51.789972 -393.374091) (xy 51.774607 -393.426421) (xy 51.75195 -393.476031)
			(xy 51.722464 -393.521912) (xy 51.686749 -393.563129) (xy 51.645532 -393.598844) (xy 51.599651 -393.62833)
			(xy 51.550041 -393.650987) (xy 51.497711 -393.666352) (xy 51.443727 -393.674114) (xy 51.389189 -393.674114)
			(xy 51.335205 -393.666352) (xy 51.282875 -393.650987) (xy 51.233265 -393.62833) (xy 51.187384 -393.598844)
			(xy 51.146167 -393.563129) (xy 51.110452 -393.521912) (xy 51.080966 -393.476031) (xy 51.058309 -393.426421)
			(xy 51.042944 -393.374091) (xy 51.035182 -393.320107) (xy 51.034696 -393.292838) (xy 50.598324 -393.292838)
			(xy 50.597838 -393.320107) (xy 50.590076 -393.374091) (xy 50.574711 -393.426421) (xy 50.552054 -393.476031)
			(xy 50.522568 -393.521912) (xy 50.486853 -393.563129) (xy 50.445636 -393.598844) (xy 50.399755 -393.62833)
			(xy 50.350145 -393.650987) (xy 50.297815 -393.666352) (xy 50.243831 -393.674114) (xy 50.189293 -393.674114)
			(xy 50.135309 -393.666352) (xy 50.082979 -393.650987) (xy 50.033369 -393.62833) (xy 49.987488 -393.598844)
			(xy 49.946271 -393.563129) (xy 49.910556 -393.521912) (xy 49.88107 -393.476031) (xy 49.858413 -393.426421)
			(xy 49.843048 -393.374091) (xy 49.835286 -393.320107) (xy 49.8348 -393.292838) (xy 49.39792 -393.292838)
			(xy 49.397434 -393.320089) (xy 49.389678 -393.374037) (xy 49.374323 -393.426332) (xy 49.351681 -393.475909)
			(xy 49.322215 -393.521759) (xy 49.286524 -393.56295) (xy 49.245333 -393.598641) (xy 49.199483 -393.628107)
			(xy 49.149906 -393.650749) (xy 49.097611 -393.666104) (xy 49.043663 -393.67386) (xy 48.989161 -393.67386)
			(xy 48.935213 -393.666104) (xy 48.882918 -393.650749) (xy 48.833341 -393.628107) (xy 48.787491 -393.598641)
			(xy 48.7463 -393.56295) (xy 48.710609 -393.521759) (xy 48.681143 -393.475909) (xy 48.658501 -393.426332)
			(xy 48.643146 -393.374037) (xy 48.63539 -393.320089) (xy 48.634904 -393.292838) (xy 48.198024 -393.292838)
			(xy 48.197538 -393.320089) (xy 48.189782 -393.374037) (xy 48.174427 -393.426332) (xy 48.151785 -393.475909)
			(xy 48.122319 -393.521759) (xy 48.086628 -393.56295) (xy 48.045437 -393.598641) (xy 47.999587 -393.628107)
			(xy 47.95001 -393.650749) (xy 47.897715 -393.666104) (xy 47.843767 -393.67386) (xy 47.789265 -393.67386)
			(xy 47.735317 -393.666104) (xy 47.683022 -393.650749) (xy 47.633445 -393.628107) (xy 47.587595 -393.598641)
			(xy 47.546404 -393.56295) (xy 47.510713 -393.521759) (xy 47.481247 -393.475909) (xy 47.458605 -393.426332)
			(xy 47.44325 -393.374037) (xy 47.435494 -393.320089) (xy 47.435008 -393.292838) (xy 2.509012 -393.292838)
			(xy 2.509012 -400.50847) (xy 103.485188 -400.50847) (xy 103.485723 -400.479553) (xy 103.494444 -400.422381)
			(xy 103.511697 -400.367182) (xy 103.537085 -400.315219) (xy 103.570027 -400.267685) (xy 103.609768 -400.225669)
			(xy 103.632254 -400.20748) (xy 103.64103 -400.199932) (xy 103.651203 -400.179162) (xy 103.651812 -400.167602)
			(xy 103.651812 -400.087338) (xy 103.651216 -400.075774) (xy 103.641039 -400.055003) (xy 103.632254 -400.04746)
			(xy 103.609742 -400.029303) (xy 103.57001 -399.987275) (xy 103.537076 -399.939733) (xy 103.511693 -399.887765)
			(xy 103.494443 -399.832562) (xy 103.48572 -399.775388) (xy 103.485188 -399.74647) (xy 103.485674 -399.719201)
			(xy 103.493436 -399.665217) (xy 103.508801 -399.612887) (xy 103.531458 -399.563277) (xy 103.560944 -399.517396)
			(xy 103.596659 -399.476179) (xy 103.637876 -399.440464) (xy 103.683757 -399.410978) (xy 103.733367 -399.388321)
			(xy 103.785697 -399.372956) (xy 103.839681 -399.365194) (xy 103.894219 -399.365194) (xy 103.948203 -399.372956)
			(xy 104.000533 -399.388321) (xy 104.050143 -399.410978) (xy 104.096024 -399.440464) (xy 104.137241 -399.476179)
			(xy 104.172956 -399.517396) (xy 104.202442 -399.563277) (xy 104.225099 -399.612887) (xy 104.240464 -399.665217)
			(xy 104.248226 -399.719201) (xy 104.248712 -399.74647) (xy 104.248206 -399.775388) (xy 104.239479 -399.832561)
			(xy 104.222221 -399.887762) (xy 104.196827 -399.939724) (xy 104.16388 -399.987257) (xy 104.124134 -400.029272)
			(xy 104.101646 -400.04746) (xy 104.092897 -400.055034) (xy 104.082709 -400.075784) (xy 104.082088 -400.087338)
			(xy 104.082088 -400.167602) (xy 104.082662 -400.179169) (xy 104.092854 -400.19994) (xy 104.101646 -400.20748)
			(xy 104.124129 -400.225671) (xy 104.163863 -400.267692) (xy 104.1968 -400.315227) (xy 104.222188 -400.367188)
			(xy 104.239445 -400.422385) (xy 104.248176 -400.479554) (xy 104.248712 -400.50847) (xy 104.248226 -400.535739)
			(xy 104.240464 -400.589723) (xy 104.225099 -400.642053) (xy 104.202442 -400.691663) (xy 104.172956 -400.737544)
			(xy 104.137241 -400.778761) (xy 104.096024 -400.814476) (xy 104.050143 -400.843962) (xy 104.000533 -400.866619)
			(xy 103.948203 -400.881984) (xy 103.894219 -400.889746) (xy 103.839681 -400.889746) (xy 103.785697 -400.881984)
			(xy 103.733367 -400.866619) (xy 103.683757 -400.843962) (xy 103.637876 -400.814476) (xy 103.596659 -400.778761)
			(xy 103.560944 -400.737544) (xy 103.531458 -400.691663) (xy 103.508801 -400.642053) (xy 103.493436 -400.589723)
			(xy 103.485674 -400.535739) (xy 103.485188 -400.50847) (xy 2.509012 -400.50847) (xy 2.509012 -403.371812)
			(xy 2.5095 -403.425034) (xy 2.517117 -403.531207) (xy 2.532283 -403.636566) (xy 2.554922 -403.740575)
			(xy 2.584919 -403.842706) (xy 2.622121 -403.942439) (xy 2.666338 -404.039266) (xy 2.717346 -404.132693)
			(xy 2.774884 -404.222247) (xy 2.838661 -404.307471) (xy 2.908351 -404.387931) (xy 2.945638 -404.425912)
			(xy 3.30962 -404.789894) (xy 37.568898 -404.789894) (xy 37.57287 -404.611651) (xy 37.584778 -404.433762)
			(xy 37.604599 -404.25658) (xy 37.632293 -404.080456) (xy 37.667805 -403.905741) (xy 37.711065 -403.732782)
			(xy 37.761987 -403.561921) (xy 37.82047 -403.393499) (xy 37.886397 -403.227849) (xy 37.959638 -403.0653)
			(xy 38.040048 -402.906175) (xy 38.127466 -402.75079) (xy 38.221719 -402.599454) (xy 38.32262 -402.452466)
			(xy 38.429969 -402.310119) (xy 38.543552 -402.172696) (xy 38.663145 -402.040469) (xy 38.788509 -401.9137)
			(xy 38.919396 -401.792642) (xy 39.055545 -401.677535) (xy 39.196687 -401.568607) (xy 39.342542 -401.466075)
			(xy 39.492819 -401.370141) (xy 39.64722 -401.280998) (xy 39.805439 -401.198821) (xy 39.967162 -401.123773)
			(xy 40.132067 -401.056005) (xy 40.299828 -400.995649) (xy 40.470111 -400.942827) (xy 40.642578 -400.897643)
			(xy 40.816886 -400.860186) (xy 40.99269 -400.830532) (xy 41.16964 -400.808739) (xy 41.347386 -400.794849)
			(xy 41.525573 -400.788892) (xy 41.70385 -400.790878) (xy 41.881861 -400.800804) (xy 42.059253 -400.81865)
			(xy 42.235673 -400.84438) (xy 42.410773 -400.877944) (xy 42.584204 -400.919274) (xy 42.755621 -400.96829)
			(xy 42.924684 -401.024892) (xy 43.091059 -401.08897) (xy 43.254413 -401.160396) (xy 43.414424 -401.239028)
			(xy 43.570773 -401.324709) (xy 43.72315 -401.417271) (xy 43.871253 -401.516528) (xy 44.014787 -401.622285)
			(xy 44.153467 -401.73433) (xy 44.287018 -401.852442) (xy 44.415175 -401.976386) (xy 44.537684 -402.105916)
			(xy 44.654301 -402.240775) (xy 44.764794 -402.380695) (xy 44.868945 -402.525398) (xy 44.966547 -402.674597)
			(xy 45.057405 -402.827996) (xy 45.141339 -402.98529) (xy 45.218184 -403.146166) (xy 45.287785 -403.310307)
			(xy 45.350006 -403.477384) (xy 45.404722 -403.647068) (xy 45.451824 -403.819021) (xy 45.49122 -403.992901)
			(xy 45.522831 -404.168364) (xy 45.546595 -404.34506) (xy 45.559703 -404.491748) (xy 47.413198 -404.491748)
			(xy 47.413198 -404.437252) (xy 47.420953 -404.38331) (xy 47.436306 -404.331021) (xy 47.458943 -404.281449)
			(xy 47.488404 -404.235603) (xy 47.52409 -404.194416) (xy 47.565274 -404.158726) (xy 47.611117 -404.12926)
			(xy 47.660687 -404.106618) (xy 47.712975 -404.091261) (xy 47.766916 -404.083501) (xy 47.794164 -404.083012)
			(xy 48.657764 -404.083012) (xy 48.68502 -404.083432) (xy 48.738978 -404.091186) (xy 48.791283 -404.106539)
			(xy 48.84087 -404.129181) (xy 48.88673 -404.15865) (xy 48.927929 -404.194345) (xy 48.963629 -404.235541)
			(xy 48.993102 -404.281398) (xy 49.015748 -404.330984) (xy 49.031107 -404.383287) (xy 49.038865 -404.437244)
			(xy 49.038865 -404.491752) (xy 50.476375 -404.491752) (xy 50.476375 -404.437248) (xy 50.484132 -404.3833)
			(xy 50.499487 -404.331005) (xy 50.522129 -404.281427) (xy 50.551596 -404.235576) (xy 50.587288 -404.194385)
			(xy 50.628479 -404.158693) (xy 50.67433 -404.129227) (xy 50.723908 -404.106586) (xy 50.776204 -404.091231)
			(xy 50.830152 -404.083475) (xy 50.857404 -404.083012) (xy 51.721004 -404.083012) (xy 51.748256 -404.083458)
			(xy 51.802207 -404.091215) (xy 51.854504 -404.106572) (xy 51.904083 -404.129214) (xy 51.949935 -404.158682)
			(xy 51.991127 -404.194376) (xy 52.02682 -404.235568) (xy 52.056288 -404.281421) (xy 52.07893 -404.331)
			(xy 52.094285 -404.383297) (xy 52.102042 -404.437248) (xy 52.102042 -404.491752) (xy 52.102042 -404.491753)
			(xy 53.539575 -404.491753) (xy 53.539575 -404.437247) (xy 53.547333 -404.383295) (xy 53.562691 -404.330996)
			(xy 53.585335 -404.281416) (xy 53.614806 -404.235563) (xy 53.650502 -404.194371) (xy 53.691698 -404.158679)
			(xy 53.737554 -404.129214) (xy 53.787137 -404.106575) (xy 53.839438 -404.091224) (xy 53.893391 -404.083472)
			(xy 53.920644 -404.083012) (xy 54.784244 -404.083012) (xy 54.811495 -404.083461) (xy 54.86544 -404.091223)
			(xy 54.917733 -404.106583) (xy 54.967307 -404.129227) (xy 55.013154 -404.158696) (xy 55.054341 -404.19439)
			(xy 55.09003 -404.235581) (xy 55.119494 -404.281432) (xy 55.142133 -404.331009) (xy 55.157487 -404.383303)
			(xy 55.165242 -404.437249) (xy 55.165242 -404.491749) (xy 56.602898 -404.491749) (xy 56.602898 -404.437251)
			(xy 56.610654 -404.383308) (xy 56.626007 -404.331017) (xy 56.648646 -404.281443) (xy 56.678109 -404.235596)
			(xy 56.713797 -404.194409) (xy 56.754983 -404.158719) (xy 56.800829 -404.129254) (xy 56.850402 -404.106613)
			(xy 56.902692 -404.091257) (xy 56.956635 -404.083499) (xy 56.983884 -404.083012) (xy 57.847484 -404.083012)
			(xy 57.874739 -404.083434) (xy 57.928695 -404.091189) (xy 57.980997 -404.106545) (xy 58.030582 -404.129188)
			(xy 58.07644 -404.158657) (xy 58.117636 -404.194352) (xy 58.153334 -404.235548) (xy 58.182805 -404.281404)
			(xy 58.20545 -404.330988) (xy 58.220807 -404.38329) (xy 58.228565 -404.437245) (xy 58.228565 -404.491753)
			(xy 59.666075 -404.491753) (xy 59.666075 -404.437247) (xy 59.673833 -404.383297) (xy 59.689189 -404.331)
			(xy 59.711832 -404.281421) (xy 59.741301 -404.235569) (xy 59.776995 -404.194378) (xy 59.818188 -404.158686)
			(xy 59.864042 -404.129221) (xy 59.913623 -404.106581) (xy 59.965921 -404.091227) (xy 60.019871 -404.083474)
			(xy 60.047124 -404.083012) (xy 60.910724 -404.083012) (xy 60.937976 -404.083459) (xy 60.991924 -404.091219)
			(xy 61.044218 -404.106577) (xy 61.093795 -404.129221) (xy 61.139645 -404.158689) (xy 61.180834 -404.194383)
			(xy 61.216525 -404.235575) (xy 61.245991 -404.281426) (xy 61.268631 -404.331004) (xy 61.283986 -404.3833)
			(xy 61.291742 -404.437248) (xy 61.291742 -404.491748) (xy 62.729398 -404.491748) (xy 62.729398 -404.437252)
			(xy 62.737153 -404.38331) (xy 62.752506 -404.331021) (xy 62.775143 -404.281449) (xy 62.804604 -404.235603)
			(xy 62.84029 -404.194416) (xy 62.881474 -404.158726) (xy 62.927317 -404.12926) (xy 62.976887 -404.106618)
			(xy 63.029175 -404.091261) (xy 63.083116 -404.083501) (xy 63.110364 -404.083012) (xy 63.973964 -404.083012)
			(xy 64.00122 -404.083432) (xy 64.055178 -404.091186) (xy 64.107483 -404.106539) (xy 64.15707 -404.129181)
			(xy 64.20293 -404.15865) (xy 64.244129 -404.194345) (xy 64.279829 -404.235541) (xy 64.309302 -404.281398)
			(xy 64.331948 -404.330984) (xy 64.347307 -404.383287) (xy 64.355065 -404.437244) (xy 64.355065 -404.491752)
			(xy 65.792575 -404.491752) (xy 65.792575 -404.437248) (xy 65.800332 -404.3833) (xy 65.815687 -404.331005)
			(xy 65.838329 -404.281427) (xy 65.867796 -404.235576) (xy 65.903488 -404.194385) (xy 65.944679 -404.158693)
			(xy 65.99053 -404.129227) (xy 66.040108 -404.106586) (xy 66.092404 -404.091231) (xy 66.146352 -404.083475)
			(xy 66.173604 -404.083012) (xy 67.037204 -404.083012) (xy 67.064456 -404.083458) (xy 67.118407 -404.091215)
			(xy 67.170704 -404.106572) (xy 67.220283 -404.129214) (xy 67.266135 -404.158682) (xy 67.307327 -404.194376)
			(xy 67.34302 -404.235568) (xy 67.372488 -404.281421) (xy 67.39513 -404.331) (xy 67.410485 -404.383297)
			(xy 67.418242 -404.437248) (xy 67.418242 -404.491752) (xy 67.418242 -404.491753) (xy 68.855775 -404.491753)
			(xy 68.855775 -404.437247) (xy 68.863533 -404.383295) (xy 68.878891 -404.330996) (xy 68.901535 -404.281416)
			(xy 68.931006 -404.235563) (xy 68.966702 -404.194371) (xy 69.007898 -404.158679) (xy 69.053754 -404.129214)
			(xy 69.103337 -404.106575) (xy 69.155638 -404.091224) (xy 69.209591 -404.083472) (xy 69.236844 -404.083012)
			(xy 70.100444 -404.083012) (xy 70.127695 -404.083461) (xy 70.18164 -404.091223) (xy 70.233933 -404.106583)
			(xy 70.283507 -404.129227) (xy 70.329354 -404.158696) (xy 70.370541 -404.19439) (xy 70.40623 -404.235581)
			(xy 70.435694 -404.281432) (xy 70.458333 -404.331009) (xy 70.473687 -404.383303) (xy 70.481442 -404.437249)
			(xy 70.481442 -404.491749) (xy 71.919098 -404.491749) (xy 71.919098 -404.437251) (xy 71.926854 -404.383308)
			(xy 71.942207 -404.331017) (xy 71.964846 -404.281443) (xy 71.994309 -404.235596) (xy 72.029997 -404.194409)
			(xy 72.071183 -404.158719) (xy 72.117029 -404.129254) (xy 72.166602 -404.106613) (xy 72.218892 -404.091257)
			(xy 72.272835 -404.083499) (xy 72.300084 -404.083012) (xy 73.163684 -404.083012) (xy 73.190939 -404.083434)
			(xy 73.244895 -404.091189) (xy 73.297197 -404.106545) (xy 73.346782 -404.129188) (xy 73.39264 -404.158657)
			(xy 73.433836 -404.194352) (xy 73.469534 -404.235548) (xy 73.499005 -404.281404) (xy 73.52165 -404.330988)
			(xy 73.537007 -404.38329) (xy 73.544765 -404.437245) (xy 73.544765 -404.491753) (xy 74.982275 -404.491753)
			(xy 74.982275 -404.437247) (xy 74.990033 -404.383297) (xy 75.005389 -404.331) (xy 75.028032 -404.281421)
			(xy 75.057501 -404.235569) (xy 75.093195 -404.194378) (xy 75.134388 -404.158686) (xy 75.180242 -404.129221)
			(xy 75.229823 -404.106581) (xy 75.282121 -404.091227) (xy 75.336071 -404.083474) (xy 75.363324 -404.083012)
			(xy 76.226924 -404.083012) (xy 76.254176 -404.083459) (xy 76.308124 -404.091219) (xy 76.360418 -404.106577)
			(xy 76.409995 -404.129221) (xy 76.455845 -404.158689) (xy 76.497034 -404.194383) (xy 76.532725 -404.235575)
			(xy 76.562191 -404.281426) (xy 76.584831 -404.331004) (xy 76.600186 -404.3833) (xy 76.607942 -404.437248)
			(xy 76.607942 -404.491748) (xy 78.045598 -404.491748) (xy 78.045598 -404.437252) (xy 78.053353 -404.38331)
			(xy 78.068706 -404.331021) (xy 78.091343 -404.281449) (xy 78.120804 -404.235603) (xy 78.15649 -404.194416)
			(xy 78.197674 -404.158726) (xy 78.243517 -404.12926) (xy 78.293087 -404.106618) (xy 78.345375 -404.091261)
			(xy 78.399316 -404.083501) (xy 78.426564 -404.083012) (xy 79.290164 -404.083012) (xy 79.31742 -404.083432)
			(xy 79.371378 -404.091186) (xy 79.423683 -404.106539) (xy 79.47327 -404.129181) (xy 79.51913 -404.15865)
			(xy 79.560329 -404.194345) (xy 79.596029 -404.235541) (xy 79.625502 -404.281398) (xy 79.648148 -404.330984)
			(xy 79.663507 -404.383287) (xy 79.671265 -404.437244) (xy 79.671265 -404.491752) (xy 81.108775 -404.491752)
			(xy 81.108775 -404.437248) (xy 81.116532 -404.3833) (xy 81.131887 -404.331005) (xy 81.154529 -404.281427)
			(xy 81.183996 -404.235576) (xy 81.219688 -404.194385) (xy 81.260879 -404.158693) (xy 81.30673 -404.129227)
			(xy 81.356308 -404.106586) (xy 81.408604 -404.091231) (xy 81.462552 -404.083475) (xy 81.489804 -404.083012)
			(xy 82.353404 -404.083012) (xy 82.380656 -404.083458) (xy 82.434607 -404.091215) (xy 82.486904 -404.106572)
			(xy 82.536483 -404.129214) (xy 82.582335 -404.158682) (xy 82.623527 -404.194376) (xy 82.65922 -404.235568)
			(xy 82.688688 -404.281421) (xy 82.71133 -404.331) (xy 82.726685 -404.383297) (xy 82.734442 -404.437248)
			(xy 82.734442 -404.491752) (xy 82.734442 -404.491753) (xy 84.171975 -404.491753) (xy 84.171975 -404.437247)
			(xy 84.179733 -404.383295) (xy 84.195091 -404.330996) (xy 84.217735 -404.281416) (xy 84.247206 -404.235563)
			(xy 84.282902 -404.194371) (xy 84.324098 -404.158679) (xy 84.369954 -404.129214) (xy 84.419537 -404.106575)
			(xy 84.471838 -404.091224) (xy 84.525791 -404.083472) (xy 84.553044 -404.083012) (xy 85.416644 -404.083012)
			(xy 85.443895 -404.083461) (xy 85.49784 -404.091223) (xy 85.550133 -404.106583) (xy 85.599707 -404.129227)
			(xy 85.645554 -404.158696) (xy 85.686741 -404.19439) (xy 85.72243 -404.235581) (xy 85.751894 -404.281432)
			(xy 85.774533 -404.331009) (xy 85.789887 -404.383303) (xy 85.797642 -404.437249) (xy 85.797642 -404.491749)
			(xy 87.235298 -404.491749) (xy 87.235298 -404.437251) (xy 87.243054 -404.383308) (xy 87.258407 -404.331017)
			(xy 87.281046 -404.281443) (xy 87.310509 -404.235596) (xy 87.346197 -404.194409) (xy 87.387383 -404.158719)
			(xy 87.433229 -404.129254) (xy 87.482802 -404.106613) (xy 87.535092 -404.091257) (xy 87.589035 -404.083499)
			(xy 87.616284 -404.083012) (xy 88.479884 -404.083012) (xy 88.507139 -404.083434) (xy 88.561095 -404.091189)
			(xy 88.613397 -404.106545) (xy 88.662982 -404.129188) (xy 88.70884 -404.158657) (xy 88.750036 -404.194352)
			(xy 88.785734 -404.235548) (xy 88.815205 -404.281404) (xy 88.83785 -404.330988) (xy 88.853207 -404.38329)
			(xy 88.860965 -404.437245) (xy 88.860965 -404.491753) (xy 90.298475 -404.491753) (xy 90.298475 -404.437247)
			(xy 90.306233 -404.383297) (xy 90.321589 -404.331) (xy 90.344232 -404.281421) (xy 90.373701 -404.235569)
			(xy 90.409395 -404.194378) (xy 90.450588 -404.158686) (xy 90.496442 -404.129221) (xy 90.546023 -404.106581)
			(xy 90.598321 -404.091227) (xy 90.652271 -404.083474) (xy 90.679524 -404.083012) (xy 91.543124 -404.083012)
			(xy 91.570376 -404.083459) (xy 91.624324 -404.091219) (xy 91.676618 -404.106577) (xy 91.726195 -404.129221)
			(xy 91.772045 -404.158689) (xy 91.813234 -404.194383) (xy 91.848925 -404.235575) (xy 91.878391 -404.281426)
			(xy 91.901031 -404.331004) (xy 91.916386 -404.3833) (xy 91.924142 -404.437248) (xy 91.924142 -404.491748)
			(xy 93.361798 -404.491748) (xy 93.361798 -404.437252) (xy 93.369553 -404.38331) (xy 93.384906 -404.331021)
			(xy 93.407543 -404.281449) (xy 93.437004 -404.235603) (xy 93.47269 -404.194416) (xy 93.513874 -404.158726)
			(xy 93.559717 -404.12926) (xy 93.609287 -404.106618) (xy 93.661575 -404.091261) (xy 93.715516 -404.083501)
			(xy 93.742764 -404.083012) (xy 94.606364 -404.083012) (xy 94.63362 -404.083432) (xy 94.687578 -404.091186)
			(xy 94.739883 -404.106539) (xy 94.78947 -404.129181) (xy 94.83533 -404.15865) (xy 94.876529 -404.194345)
			(xy 94.912229 -404.235541) (xy 94.941702 -404.281398) (xy 94.964348 -404.330984) (xy 94.979707 -404.383287)
			(xy 94.987465 -404.437244) (xy 94.987465 -404.491752) (xy 114.513075 -404.491752) (xy 114.513075 -404.437248)
			(xy 114.520832 -404.3833) (xy 114.536188 -404.331004) (xy 114.558829 -404.281426) (xy 114.588296 -404.235575)
			(xy 114.623989 -404.194384) (xy 114.66518 -404.158693) (xy 114.711031 -404.129226) (xy 114.76061 -404.106585)
			(xy 114.812906 -404.091231) (xy 114.866854 -404.083475) (xy 114.894106 -404.083012) (xy 115.757706 -404.083012)
			(xy 115.784958 -404.083458) (xy 115.838908 -404.091216) (xy 115.891205 -404.106572) (xy 115.940784 -404.129215)
			(xy 115.986636 -404.158683) (xy 116.027828 -404.194376) (xy 116.063521 -404.235569) (xy 116.092988 -404.281421)
			(xy 116.11563 -404.331001) (xy 116.130985 -404.383298) (xy 116.138742 -404.437248) (xy 116.138742 -404.491752)
			(xy 116.138742 -404.491754) (xy 117.576275 -404.491754) (xy 117.576275 -404.437246) (xy 117.584033 -404.383294)
			(xy 117.599391 -404.330996) (xy 117.622035 -404.281415) (xy 117.651506 -404.235562) (xy 117.687203 -404.19437)
			(xy 117.728399 -404.158679) (xy 117.774255 -404.129213) (xy 117.823839 -404.106575) (xy 117.876139 -404.091223)
			(xy 117.930092 -404.083472) (xy 117.957346 -404.083012) (xy 118.820946 -404.083012) (xy 118.848197 -404.083461)
			(xy 118.902142 -404.091223) (xy 118.954434 -404.106583) (xy 119.004008 -404.129228) (xy 119.049855 -404.158697)
			(xy 119.091042 -404.194391) (xy 119.12673 -404.235582) (xy 119.156194 -404.281432) (xy 119.178833 -404.331009)
			(xy 119.194187 -404.383303) (xy 119.201942 -404.437249) (xy 119.201942 -404.491749) (xy 120.639598 -404.491749)
			(xy 120.639598 -404.437251) (xy 120.647354 -404.383307) (xy 120.662708 -404.331016) (xy 120.685346 -404.281443)
			(xy 120.71481 -404.235596) (xy 120.750498 -404.194408) (xy 120.791684 -404.158718) (xy 120.83753 -404.129253)
			(xy 120.887103 -404.106612) (xy 120.939394 -404.091257) (xy 120.993337 -404.083499) (xy 121.020586 -404.083012)
			(xy 121.884186 -404.083012) (xy 121.911441 -404.083434) (xy 121.965396 -404.09119) (xy 122.017699 -404.106545)
			(xy 122.067283 -404.129188) (xy 122.113141 -404.158657) (xy 122.154337 -404.194353) (xy 122.190034 -404.235548)
			(xy 122.219505 -404.281405) (xy 122.24215 -404.330988) (xy 122.257507 -404.38329) (xy 122.265265 -404.437245)
			(xy 122.265265 -404.491753) (xy 123.702775 -404.491753) (xy 123.702775 -404.437247) (xy 123.710533 -404.383297)
			(xy 123.725889 -404.331) (xy 123.748532 -404.281421) (xy 123.778001 -404.235569) (xy 123.813696 -404.194377)
			(xy 123.854889 -404.158686) (xy 123.900743 -404.12922) (xy 123.950324 -404.10658) (xy 124.002622 -404.091227)
			(xy 124.056573 -404.083474) (xy 124.083826 -404.083012) (xy 124.947426 -404.083012) (xy 124.974677 -404.08346)
			(xy 125.028625 -404.09122) (xy 125.08092 -404.106578) (xy 125.130496 -404.129222) (xy 125.176346 -404.15869)
			(xy 125.217535 -404.194383) (xy 125.253226 -404.235575) (xy 125.282691 -404.281427) (xy 125.305331 -404.331005)
			(xy 125.320686 -404.3833) (xy 125.328442 -404.437249) (xy 125.328442 -404.491748) (xy 126.766098 -404.491748)
			(xy 126.766098 -404.437252) (xy 126.773853 -404.38331) (xy 126.789206 -404.331021) (xy 126.811843 -404.281448)
			(xy 126.841305 -404.235602) (xy 126.876991 -404.194415) (xy 126.918175 -404.158725) (xy 126.964018 -404.12926)
			(xy 127.013589 -404.106618) (xy 127.065877 -404.091261) (xy 127.119818 -404.083501) (xy 127.147066 -404.083012)
			(xy 128.010666 -404.083012) (xy 128.037922 -404.083433) (xy 128.091879 -404.091186) (xy 128.144184 -404.10654)
			(xy 128.193771 -404.129182) (xy 128.239631 -404.15865) (xy 128.28083 -404.194346) (xy 128.316529 -404.235542)
			(xy 128.346002 -404.281399) (xy 128.368648 -404.330984) (xy 128.384007 -404.383287) (xy 128.391765 -404.437244)
			(xy 128.391765 -404.491752) (xy 129.829275 -404.491752) (xy 129.829275 -404.437248) (xy 129.837032 -404.3833)
			(xy 129.852388 -404.331004) (xy 129.875029 -404.281426) (xy 129.904496 -404.235575) (xy 129.940189 -404.194384)
			(xy 129.98138 -404.158693) (xy 130.027231 -404.129226) (xy 130.07681 -404.106585) (xy 130.129106 -404.091231)
			(xy 130.183054 -404.083475) (xy 130.210306 -404.083012) (xy 131.073906 -404.083012) (xy 131.101158 -404.083458)
			(xy 131.155108 -404.091216) (xy 131.207405 -404.106572) (xy 131.256984 -404.129215) (xy 131.302836 -404.158683)
			(xy 131.344028 -404.194376) (xy 131.379721 -404.235569) (xy 131.409188 -404.281421) (xy 131.43183 -404.331001)
			(xy 131.447185 -404.383298) (xy 131.454942 -404.437248) (xy 131.454942 -404.491752) (xy 131.454942 -404.491754)
			(xy 132.892475 -404.491754) (xy 132.892475 -404.437246) (xy 132.900233 -404.383294) (xy 132.915591 -404.330996)
			(xy 132.938235 -404.281415) (xy 132.967706 -404.235562) (xy 133.003403 -404.19437) (xy 133.044599 -404.158679)
			(xy 133.090455 -404.129213) (xy 133.140039 -404.106575) (xy 133.192339 -404.091223) (xy 133.246292 -404.083472)
			(xy 133.273546 -404.083012) (xy 134.137146 -404.083012) (xy 134.164397 -404.083461) (xy 134.218342 -404.091223)
			(xy 134.270634 -404.106583) (xy 134.320208 -404.129228) (xy 134.366055 -404.158697) (xy 134.407242 -404.194391)
			(xy 134.44293 -404.235582) (xy 134.472394 -404.281432) (xy 134.495033 -404.331009) (xy 134.510387 -404.383303)
			(xy 134.518142 -404.437249) (xy 134.518142 -404.491749) (xy 135.955798 -404.491749) (xy 135.955798 -404.437251)
			(xy 135.963554 -404.383307) (xy 135.978908 -404.331016) (xy 136.001546 -404.281443) (xy 136.03101 -404.235596)
			(xy 136.066698 -404.194408) (xy 136.107884 -404.158718) (xy 136.15373 -404.129253) (xy 136.203303 -404.106612)
			(xy 136.255594 -404.091257) (xy 136.309537 -404.083499) (xy 136.336786 -404.083012) (xy 137.200386 -404.083012)
			(xy 137.227641 -404.083434) (xy 137.281596 -404.09119) (xy 137.333899 -404.106545) (xy 137.383483 -404.129188)
			(xy 137.429341 -404.158657) (xy 137.470537 -404.194353) (xy 137.506234 -404.235548) (xy 137.535705 -404.281405)
			(xy 137.55835 -404.330988) (xy 137.573707 -404.38329) (xy 137.581465 -404.437245) (xy 137.581465 -404.491753)
			(xy 139.018975 -404.491753) (xy 139.018975 -404.437247) (xy 139.026733 -404.383297) (xy 139.042089 -404.331)
			(xy 139.064732 -404.281421) (xy 139.094201 -404.235569) (xy 139.129896 -404.194377) (xy 139.171089 -404.158686)
			(xy 139.216943 -404.12922) (xy 139.266524 -404.10658) (xy 139.318822 -404.091227) (xy 139.372773 -404.083474)
			(xy 139.400026 -404.083012) (xy 140.263626 -404.083012) (xy 140.290877 -404.08346) (xy 140.344825 -404.09122)
			(xy 140.39712 -404.106578) (xy 140.446696 -404.129222) (xy 140.492546 -404.15869) (xy 140.533735 -404.194383)
			(xy 140.569426 -404.235575) (xy 140.598891 -404.281427) (xy 140.621531 -404.331005) (xy 140.636886 -404.3833)
			(xy 140.644642 -404.437249) (xy 140.644642 -404.491748) (xy 142.082298 -404.491748) (xy 142.082298 -404.437252)
			(xy 142.090053 -404.38331) (xy 142.105406 -404.331021) (xy 142.128043 -404.281448) (xy 142.157505 -404.235602)
			(xy 142.193191 -404.194415) (xy 142.234375 -404.158725) (xy 142.280218 -404.12926) (xy 142.329789 -404.106618)
			(xy 142.382077 -404.091261) (xy 142.436018 -404.083501) (xy 142.463266 -404.083012) (xy 143.326866 -404.083012)
			(xy 143.354122 -404.083433) (xy 143.408079 -404.091186) (xy 143.460384 -404.10654) (xy 143.509971 -404.129182)
			(xy 143.555831 -404.15865) (xy 143.59703 -404.194346) (xy 143.632729 -404.235542) (xy 143.662202 -404.281399)
			(xy 143.684848 -404.330984) (xy 143.700207 -404.383287) (xy 143.707965 -404.437244) (xy 143.707965 -404.491752)
			(xy 145.145475 -404.491752) (xy 145.145475 -404.437248) (xy 145.153232 -404.3833) (xy 145.168588 -404.331004)
			(xy 145.191229 -404.281426) (xy 145.220696 -404.235575) (xy 145.256389 -404.194384) (xy 145.29758 -404.158693)
			(xy 145.343431 -404.129226) (xy 145.39301 -404.106585) (xy 145.445306 -404.091231) (xy 145.499254 -404.083475)
			(xy 145.526506 -404.083012) (xy 146.390106 -404.083012) (xy 146.417358 -404.083458) (xy 146.471308 -404.091216)
			(xy 146.523605 -404.106572) (xy 146.573184 -404.129215) (xy 146.619036 -404.158683) (xy 146.660228 -404.194376)
			(xy 146.695921 -404.235569) (xy 146.725388 -404.281421) (xy 146.74803 -404.331001) (xy 146.763385 -404.383298)
			(xy 146.771142 -404.437248) (xy 146.771142 -404.491752) (xy 146.771142 -404.491754) (xy 148.208675 -404.491754)
			(xy 148.208675 -404.437246) (xy 148.216433 -404.383294) (xy 148.231791 -404.330996) (xy 148.254435 -404.281415)
			(xy 148.283906 -404.235562) (xy 148.319603 -404.19437) (xy 148.360799 -404.158679) (xy 148.406655 -404.129213)
			(xy 148.456239 -404.106575) (xy 148.508539 -404.091223) (xy 148.562492 -404.083472) (xy 148.589746 -404.083012)
			(xy 149.453346 -404.083012) (xy 149.480597 -404.083461) (xy 149.534542 -404.091223) (xy 149.586834 -404.106583)
			(xy 149.636408 -404.129228) (xy 149.682255 -404.158697) (xy 149.723442 -404.194391) (xy 149.75913 -404.235582)
			(xy 149.788594 -404.281432) (xy 149.811233 -404.331009) (xy 149.826587 -404.383303) (xy 149.834342 -404.437249)
			(xy 149.834342 -404.491749) (xy 151.271998 -404.491749) (xy 151.271998 -404.437251) (xy 151.279754 -404.383307)
			(xy 151.295108 -404.331016) (xy 151.317746 -404.281443) (xy 151.34721 -404.235596) (xy 151.382898 -404.194408)
			(xy 151.424084 -404.158718) (xy 151.46993 -404.129253) (xy 151.519503 -404.106612) (xy 151.571794 -404.091257)
			(xy 151.625737 -404.083499) (xy 151.652986 -404.083012) (xy 152.516586 -404.083012) (xy 152.543841 -404.083434)
			(xy 152.597796 -404.09119) (xy 152.650099 -404.106545) (xy 152.699683 -404.129188) (xy 152.745541 -404.158657)
			(xy 152.786737 -404.194353) (xy 152.822434 -404.235548) (xy 152.851905 -404.281405) (xy 152.87455 -404.330988)
			(xy 152.889907 -404.38329) (xy 152.897665 -404.437245) (xy 152.897665 -404.491753) (xy 154.335175 -404.491753)
			(xy 154.335175 -404.437247) (xy 154.342933 -404.383297) (xy 154.358289 -404.331) (xy 154.380932 -404.281421)
			(xy 154.410401 -404.235569) (xy 154.446096 -404.194377) (xy 154.487289 -404.158686) (xy 154.533143 -404.12922)
			(xy 154.582724 -404.10658) (xy 154.635022 -404.091227) (xy 154.688973 -404.083474) (xy 154.716226 -404.083012)
			(xy 155.579826 -404.083012) (xy 155.607077 -404.08346) (xy 155.661025 -404.09122) (xy 155.71332 -404.106578)
			(xy 155.762896 -404.129222) (xy 155.808746 -404.15869) (xy 155.849935 -404.194383) (xy 155.885626 -404.235575)
			(xy 155.915091 -404.281427) (xy 155.937731 -404.331005) (xy 155.953086 -404.3833) (xy 155.960842 -404.437249)
			(xy 155.960842 -404.491748) (xy 157.398498 -404.491748) (xy 157.398498 -404.437252) (xy 157.406253 -404.38331)
			(xy 157.421606 -404.331021) (xy 157.444243 -404.281448) (xy 157.473705 -404.235602) (xy 157.509391 -404.194415)
			(xy 157.550575 -404.158725) (xy 157.596418 -404.12926) (xy 157.645989 -404.106618) (xy 157.698277 -404.091261)
			(xy 157.752218 -404.083501) (xy 157.779466 -404.083012) (xy 158.643066 -404.083012) (xy 158.670322 -404.083433)
			(xy 158.724279 -404.091186) (xy 158.776584 -404.10654) (xy 158.826171 -404.129182) (xy 158.872031 -404.15865)
			(xy 158.91323 -404.194346) (xy 158.948929 -404.235542) (xy 158.978402 -404.281399) (xy 159.001048 -404.330984)
			(xy 159.016407 -404.383287) (xy 159.024165 -404.437244) (xy 159.024165 -404.491752) (xy 160.461675 -404.491752)
			(xy 160.461675 -404.437248) (xy 160.469432 -404.3833) (xy 160.484788 -404.331004) (xy 160.507429 -404.281426)
			(xy 160.536896 -404.235575) (xy 160.572589 -404.194384) (xy 160.61378 -404.158693) (xy 160.659631 -404.129226)
			(xy 160.70921 -404.106585) (xy 160.761506 -404.091231) (xy 160.815454 -404.083475) (xy 160.842706 -404.083012)
			(xy 161.706306 -404.083012) (xy 161.733558 -404.083458) (xy 161.787508 -404.091216) (xy 161.839805 -404.106572)
			(xy 161.889384 -404.129215) (xy 161.935236 -404.158683) (xy 161.976428 -404.194376) (xy 162.012121 -404.235569)
			(xy 162.041588 -404.281421) (xy 162.06423 -404.331001) (xy 162.079585 -404.383298) (xy 162.087342 -404.437248)
			(xy 162.087342 -404.491752) (xy 162.079585 -404.545702) (xy 162.06423 -404.597999) (xy 162.041588 -404.647579)
			(xy 162.012121 -404.693431) (xy 161.976428 -404.734624) (xy 161.935236 -404.770317) (xy 161.904774 -404.789894)
			(xy 166.998662 -404.789894) (xy 167.002634 -404.611651) (xy 167.014542 -404.433762) (xy 167.034363 -404.25658)
			(xy 167.062057 -404.080456) (xy 167.097569 -403.905741) (xy 167.140829 -403.732782) (xy 167.191751 -403.561921)
			(xy 167.250234 -403.393499) (xy 167.316161 -403.227849) (xy 167.389402 -403.0653) (xy 167.469812 -402.906175)
			(xy 167.55723 -402.75079) (xy 167.651483 -402.599454) (xy 167.752384 -402.452466) (xy 167.859733 -402.310119)
			(xy 167.973316 -402.172696) (xy 168.092909 -402.040469) (xy 168.218273 -401.9137) (xy 168.34916 -401.792642)
			(xy 168.485309 -401.677535) (xy 168.626451 -401.568607) (xy 168.772306 -401.466075) (xy 168.922583 -401.370141)
			(xy 169.076984 -401.280998) (xy 169.235203 -401.198821) (xy 169.396926 -401.123773) (xy 169.561831 -401.056005)
			(xy 169.729592 -400.995649) (xy 169.899875 -400.942827) (xy 170.072342 -400.897643) (xy 170.24665 -400.860186)
			(xy 170.422454 -400.830532) (xy 170.599404 -400.808739) (xy 170.77715 -400.794849) (xy 170.955337 -400.788892)
			(xy 171.133614 -400.790878) (xy 171.311625 -400.800804) (xy 171.489017 -400.81865) (xy 171.665437 -400.84438)
			(xy 171.840537 -400.877944) (xy 172.013968 -400.919274) (xy 172.185385 -400.96829) (xy 172.354448 -401.024892)
			(xy 172.520823 -401.08897) (xy 172.684177 -401.160396) (xy 172.844188 -401.239028) (xy 173.000537 -401.324709)
			(xy 173.152914 -401.417271) (xy 173.301017 -401.516528) (xy 173.444551 -401.622285) (xy 173.583231 -401.73433)
			(xy 173.716782 -401.852442) (xy 173.844939 -401.976386) (xy 173.967448 -402.105916) (xy 174.084065 -402.240775)
			(xy 174.194558 -402.380695) (xy 174.298709 -402.525398) (xy 174.396311 -402.674597) (xy 174.487169 -402.827996)
			(xy 174.571103 -402.98529) (xy 174.647948 -403.146166) (xy 174.717549 -403.310307) (xy 174.77977 -403.477384)
			(xy 174.834486 -403.647068) (xy 174.881588 -403.819021) (xy 174.920984 -403.992901) (xy 174.952595 -404.168364)
			(xy 174.976359 -404.34506) (xy 174.992227 -404.52264) (xy 175.000169 -404.70075) (xy 175.000666 -404.789894)
			(xy 175.000169 -404.879038) (xy 174.992227 -405.057148) (xy 174.976359 -405.234728) (xy 174.952595 -405.411424)
			(xy 174.920984 -405.586887) (xy 174.881588 -405.760767) (xy 174.834486 -405.93272) (xy 174.77977 -406.102404)
			(xy 174.717549 -406.269481) (xy 174.647948 -406.433622) (xy 174.571103 -406.594498) (xy 174.487169 -406.751792)
			(xy 174.396311 -406.905191) (xy 174.298709 -407.05439) (xy 174.194558 -407.199093) (xy 174.084065 -407.339013)
			(xy 173.967448 -407.473872) (xy 173.844939 -407.603402) (xy 173.716782 -407.727346) (xy 173.583231 -407.845458)
			(xy 173.444551 -407.957503) (xy 173.301017 -408.06326) (xy 173.152914 -408.162517) (xy 173.000537 -408.255079)
			(xy 172.844188 -408.34076) (xy 172.684177 -408.419392) (xy 172.520823 -408.490818) (xy 172.354448 -408.554896)
			(xy 172.185385 -408.611498) (xy 172.013968 -408.660514) (xy 171.840537 -408.701844) (xy 171.665437 -408.735408)
			(xy 171.489017 -408.761138) (xy 171.311625 -408.778984) (xy 171.133614 -408.78891) (xy 170.955337 -408.790896)
			(xy 170.77715 -408.784939) (xy 170.599404 -408.771049) (xy 170.422454 -408.749256) (xy 170.24665 -408.719602)
			(xy 170.072342 -408.682145) (xy 169.899875 -408.636961) (xy 169.729592 -408.584139) (xy 169.561831 -408.523783)
			(xy 169.396926 -408.456015) (xy 169.235203 -408.380967) (xy 169.076984 -408.29879) (xy 168.922583 -408.209647)
			(xy 168.772306 -408.113713) (xy 168.626451 -408.011181) (xy 168.485309 -407.902253) (xy 168.34916 -407.787146)
			(xy 168.218273 -407.666088) (xy 168.092909 -407.539319) (xy 167.973316 -407.407092) (xy 167.859733 -407.269669)
			(xy 167.752384 -407.127322) (xy 167.651483 -406.980334) (xy 167.55723 -406.828998) (xy 167.469812 -406.673613)
			(xy 167.389402 -406.514488) (xy 167.316161 -406.351939) (xy 167.250234 -406.186289) (xy 167.191751 -406.017867)
			(xy 167.140829 -405.847006) (xy 167.097569 -405.674047) (xy 167.062057 -405.499332) (xy 167.034363 -405.323208)
			(xy 167.014542 -405.146026) (xy 167.002634 -404.968137) (xy 166.998662 -404.789894) (xy 161.904774 -404.789894)
			(xy 161.889384 -404.799785) (xy 161.839805 -404.822428) (xy 161.787508 -404.837784) (xy 161.733558 -404.845542)
			(xy 161.706306 -404.846028) (xy 160.842706 -404.846028) (xy 160.815454 -404.845525) (xy 160.761506 -404.837769)
			(xy 160.70921 -404.822415) (xy 160.659631 -404.799774) (xy 160.61378 -404.770307) (xy 160.572589 -404.734616)
			(xy 160.536896 -404.693425) (xy 160.507429 -404.647574) (xy 160.484788 -404.597996) (xy 160.469432 -404.5457)
			(xy 160.461675 -404.491752) (xy 159.024165 -404.491752) (xy 159.024165 -404.491756) (xy 159.016407 -404.545713)
			(xy 159.001048 -404.598016) (xy 158.978402 -404.647601) (xy 158.948929 -404.693458) (xy 158.91323 -404.734654)
			(xy 158.872031 -404.77035) (xy 158.826171 -404.799818) (xy 158.776584 -404.82246) (xy 158.724279 -404.837814)
			(xy 158.670322 -404.845567) (xy 158.643066 -404.846028) (xy 157.779466 -404.846028) (xy 157.752218 -404.845499)
			(xy 157.698277 -404.837739) (xy 157.645989 -404.822382) (xy 157.596418 -404.79974) (xy 157.550575 -404.770275)
			(xy 157.509391 -404.734585) (xy 157.473705 -404.693398) (xy 157.444243 -404.647552) (xy 157.421606 -404.597979)
			(xy 157.406253 -404.54569) (xy 157.398498 -404.491748) (xy 155.960842 -404.491748) (xy 155.960842 -404.491751)
			(xy 155.953086 -404.5457) (xy 155.937731 -404.597995) (xy 155.915091 -404.647573) (xy 155.885626 -404.693425)
			(xy 155.849935 -404.734617) (xy 155.808746 -404.77031) (xy 155.762896 -404.799778) (xy 155.71332 -404.822422)
			(xy 155.661025 -404.83778) (xy 155.607077 -404.84554) (xy 155.579826 -404.846028) (xy 154.716226 -404.846028)
			(xy 154.688973 -404.845526) (xy 154.635022 -404.837773) (xy 154.582724 -404.82242) (xy 154.533143 -404.79978)
			(xy 154.487289 -404.770314) (xy 154.446096 -404.734623) (xy 154.410401 -404.693431) (xy 154.380932 -404.647579)
			(xy 154.358289 -404.598) (xy 154.342933 -404.545703) (xy 154.335175 -404.491753) (xy 152.897665 -404.491753)
			(xy 152.897665 -404.491755) (xy 152.889907 -404.54571) (xy 152.87455 -404.598012) (xy 152.851905 -404.647595)
			(xy 152.822434 -404.693452) (xy 152.786737 -404.734647) (xy 152.745541 -404.770343) (xy 152.699683 -404.799812)
			(xy 152.650099 -404.822455) (xy 152.597796 -404.83781) (xy 152.543841 -404.845566) (xy 152.516586 -404.846028)
			(xy 151.652986 -404.846028) (xy 151.625737 -404.845501) (xy 151.571794 -404.837743) (xy 151.519503 -404.822388)
			(xy 151.46993 -404.799747) (xy 151.424084 -404.770282) (xy 151.382898 -404.734592) (xy 151.34721 -404.693404)
			(xy 151.317746 -404.647557) (xy 151.295108 -404.597984) (xy 151.279754 -404.545693) (xy 151.271998 -404.491749)
			(xy 149.834342 -404.491749) (xy 149.834342 -404.491751) (xy 149.826587 -404.545697) (xy 149.811233 -404.597991)
			(xy 149.788594 -404.647568) (xy 149.75913 -404.693418) (xy 149.723442 -404.734609) (xy 149.682255 -404.770303)
			(xy 149.636408 -404.799772) (xy 149.586834 -404.822417) (xy 149.534542 -404.837777) (xy 149.480597 -404.845539)
			(xy 149.453346 -404.846028) (xy 148.589746 -404.846028) (xy 148.562492 -404.845528) (xy 148.508539 -404.837777)
			(xy 148.456239 -404.822425) (xy 148.406655 -404.799787) (xy 148.360799 -404.770321) (xy 148.319603 -404.73463)
			(xy 148.283906 -404.693438) (xy 148.254435 -404.647585) (xy 148.231791 -404.598004) (xy 148.216433 -404.545706)
			(xy 148.208675 -404.491754) (xy 146.771142 -404.491754) (xy 146.763385 -404.545702) (xy 146.74803 -404.597999)
			(xy 146.725388 -404.647579) (xy 146.695921 -404.693431) (xy 146.660228 -404.734624) (xy 146.619036 -404.770317)
			(xy 146.573184 -404.799785) (xy 146.523605 -404.822428) (xy 146.471308 -404.837784) (xy 146.417358 -404.845542)
			(xy 146.390106 -404.846028) (xy 145.526506 -404.846028) (xy 145.499254 -404.845525) (xy 145.445306 -404.837769)
			(xy 145.39301 -404.822415) (xy 145.343431 -404.799774) (xy 145.29758 -404.770307) (xy 145.256389 -404.734616)
			(xy 145.220696 -404.693425) (xy 145.191229 -404.647574) (xy 145.168588 -404.597996) (xy 145.153232 -404.5457)
			(xy 145.145475 -404.491752) (xy 143.707965 -404.491752) (xy 143.707965 -404.491756) (xy 143.700207 -404.545713)
			(xy 143.684848 -404.598016) (xy 143.662202 -404.647601) (xy 143.632729 -404.693458) (xy 143.59703 -404.734654)
			(xy 143.555831 -404.77035) (xy 143.509971 -404.799818) (xy 143.460384 -404.82246) (xy 143.408079 -404.837814)
			(xy 143.354122 -404.845567) (xy 143.326866 -404.846028) (xy 142.463266 -404.846028) (xy 142.436018 -404.845499)
			(xy 142.382077 -404.837739) (xy 142.329789 -404.822382) (xy 142.280218 -404.79974) (xy 142.234375 -404.770275)
			(xy 142.193191 -404.734585) (xy 142.157505 -404.693398) (xy 142.128043 -404.647552) (xy 142.105406 -404.597979)
			(xy 142.090053 -404.54569) (xy 142.082298 -404.491748) (xy 140.644642 -404.491748) (xy 140.644642 -404.491751)
			(xy 140.636886 -404.5457) (xy 140.621531 -404.597995) (xy 140.598891 -404.647573) (xy 140.569426 -404.693425)
			(xy 140.533735 -404.734617) (xy 140.492546 -404.77031) (xy 140.446696 -404.799778) (xy 140.39712 -404.822422)
			(xy 140.344825 -404.83778) (xy 140.290877 -404.84554) (xy 140.263626 -404.846028) (xy 139.400026 -404.846028)
			(xy 139.372773 -404.845526) (xy 139.318822 -404.837773) (xy 139.266524 -404.82242) (xy 139.216943 -404.79978)
			(xy 139.171089 -404.770314) (xy 139.129896 -404.734623) (xy 139.094201 -404.693431) (xy 139.064732 -404.647579)
			(xy 139.042089 -404.598) (xy 139.026733 -404.545703) (xy 139.018975 -404.491753) (xy 137.581465 -404.491753)
			(xy 137.581465 -404.491755) (xy 137.573707 -404.54571) (xy 137.55835 -404.598012) (xy 137.535705 -404.647595)
			(xy 137.506234 -404.693452) (xy 137.470537 -404.734647) (xy 137.429341 -404.770343) (xy 137.383483 -404.799812)
			(xy 137.333899 -404.822455) (xy 137.281596 -404.83781) (xy 137.227641 -404.845566) (xy 137.200386 -404.846028)
			(xy 136.336786 -404.846028) (xy 136.309537 -404.845501) (xy 136.255594 -404.837743) (xy 136.203303 -404.822388)
			(xy 136.15373 -404.799747) (xy 136.107884 -404.770282) (xy 136.066698 -404.734592) (xy 136.03101 -404.693404)
			(xy 136.001546 -404.647557) (xy 135.978908 -404.597984) (xy 135.963554 -404.545693) (xy 135.955798 -404.491749)
			(xy 134.518142 -404.491749) (xy 134.518142 -404.491751) (xy 134.510387 -404.545697) (xy 134.495033 -404.597991)
			(xy 134.472394 -404.647568) (xy 134.44293 -404.693418) (xy 134.407242 -404.734609) (xy 134.366055 -404.770303)
			(xy 134.320208 -404.799772) (xy 134.270634 -404.822417) (xy 134.218342 -404.837777) (xy 134.164397 -404.845539)
			(xy 134.137146 -404.846028) (xy 133.273546 -404.846028) (xy 133.246292 -404.845528) (xy 133.192339 -404.837777)
			(xy 133.140039 -404.822425) (xy 133.090455 -404.799787) (xy 133.044599 -404.770321) (xy 133.003403 -404.73463)
			(xy 132.967706 -404.693438) (xy 132.938235 -404.647585) (xy 132.915591 -404.598004) (xy 132.900233 -404.545706)
			(xy 132.892475 -404.491754) (xy 131.454942 -404.491754) (xy 131.447185 -404.545702) (xy 131.43183 -404.597999)
			(xy 131.409188 -404.647579) (xy 131.379721 -404.693431) (xy 131.344028 -404.734624) (xy 131.302836 -404.770317)
			(xy 131.256984 -404.799785) (xy 131.207405 -404.822428) (xy 131.155108 -404.837784) (xy 131.101158 -404.845542)
			(xy 131.073906 -404.846028) (xy 130.210306 -404.846028) (xy 130.183054 -404.845525) (xy 130.129106 -404.837769)
			(xy 130.07681 -404.822415) (xy 130.027231 -404.799774) (xy 129.98138 -404.770307) (xy 129.940189 -404.734616)
			(xy 129.904496 -404.693425) (xy 129.875029 -404.647574) (xy 129.852388 -404.597996) (xy 129.837032 -404.5457)
			(xy 129.829275 -404.491752) (xy 128.391765 -404.491752) (xy 128.391765 -404.491756) (xy 128.384007 -404.545713)
			(xy 128.368648 -404.598016) (xy 128.346002 -404.647601) (xy 128.316529 -404.693458) (xy 128.28083 -404.734654)
			(xy 128.239631 -404.77035) (xy 128.193771 -404.799818) (xy 128.144184 -404.82246) (xy 128.091879 -404.837814)
			(xy 128.037922 -404.845567) (xy 128.010666 -404.846028) (xy 127.147066 -404.846028) (xy 127.119818 -404.845499)
			(xy 127.065877 -404.837739) (xy 127.013589 -404.822382) (xy 126.964018 -404.79974) (xy 126.918175 -404.770275)
			(xy 126.876991 -404.734585) (xy 126.841305 -404.693398) (xy 126.811843 -404.647552) (xy 126.789206 -404.597979)
			(xy 126.773853 -404.54569) (xy 126.766098 -404.491748) (xy 125.328442 -404.491748) (xy 125.328442 -404.491751)
			(xy 125.320686 -404.5457) (xy 125.305331 -404.597995) (xy 125.282691 -404.647573) (xy 125.253226 -404.693425)
			(xy 125.217535 -404.734617) (xy 125.176346 -404.77031) (xy 125.130496 -404.799778) (xy 125.08092 -404.822422)
			(xy 125.028625 -404.83778) (xy 124.974677 -404.84554) (xy 124.947426 -404.846028) (xy 124.083826 -404.846028)
			(xy 124.056573 -404.845526) (xy 124.002622 -404.837773) (xy 123.950324 -404.82242) (xy 123.900743 -404.79978)
			(xy 123.854889 -404.770314) (xy 123.813696 -404.734623) (xy 123.778001 -404.693431) (xy 123.748532 -404.647579)
			(xy 123.725889 -404.598) (xy 123.710533 -404.545703) (xy 123.702775 -404.491753) (xy 122.265265 -404.491753)
			(xy 122.265265 -404.491755) (xy 122.257507 -404.54571) (xy 122.24215 -404.598012) (xy 122.219505 -404.647595)
			(xy 122.190034 -404.693452) (xy 122.154337 -404.734647) (xy 122.113141 -404.770343) (xy 122.067283 -404.799812)
			(xy 122.017699 -404.822455) (xy 121.965396 -404.83781) (xy 121.911441 -404.845566) (xy 121.884186 -404.846028)
			(xy 121.020586 -404.846028) (xy 120.993337 -404.845501) (xy 120.939394 -404.837743) (xy 120.887103 -404.822388)
			(xy 120.83753 -404.799747) (xy 120.791684 -404.770282) (xy 120.750498 -404.734592) (xy 120.71481 -404.693404)
			(xy 120.685346 -404.647557) (xy 120.662708 -404.597984) (xy 120.647354 -404.545693) (xy 120.639598 -404.491749)
			(xy 119.201942 -404.491749) (xy 119.201942 -404.491751) (xy 119.194187 -404.545697) (xy 119.178833 -404.597991)
			(xy 119.156194 -404.647568) (xy 119.12673 -404.693418) (xy 119.091042 -404.734609) (xy 119.049855 -404.770303)
			(xy 119.004008 -404.799772) (xy 118.954434 -404.822417) (xy 118.902142 -404.837777) (xy 118.848197 -404.845539)
			(xy 118.820946 -404.846028) (xy 117.957346 -404.846028) (xy 117.930092 -404.845528) (xy 117.876139 -404.837777)
			(xy 117.823839 -404.822425) (xy 117.774255 -404.799787) (xy 117.728399 -404.770321) (xy 117.687203 -404.73463)
			(xy 117.651506 -404.693438) (xy 117.622035 -404.647585) (xy 117.599391 -404.598004) (xy 117.584033 -404.545706)
			(xy 117.576275 -404.491754) (xy 116.138742 -404.491754) (xy 116.130985 -404.545702) (xy 116.11563 -404.597999)
			(xy 116.092988 -404.647579) (xy 116.063521 -404.693431) (xy 116.027828 -404.734624) (xy 115.986636 -404.770317)
			(xy 115.940784 -404.799785) (xy 115.891205 -404.822428) (xy 115.838908 -404.837784) (xy 115.784958 -404.845542)
			(xy 115.757706 -404.846028) (xy 114.894106 -404.846028) (xy 114.866854 -404.845525) (xy 114.812906 -404.837769)
			(xy 114.76061 -404.822415) (xy 114.711031 -404.799774) (xy 114.66518 -404.770307) (xy 114.623989 -404.734616)
			(xy 114.588296 -404.693425) (xy 114.558829 -404.647574) (xy 114.536188 -404.597996) (xy 114.520832 -404.5457)
			(xy 114.513075 -404.491752) (xy 94.987465 -404.491752) (xy 94.987465 -404.491756) (xy 94.979707 -404.545713)
			(xy 94.964348 -404.598016) (xy 94.941702 -404.647602) (xy 94.912229 -404.693459) (xy 94.876529 -404.734655)
			(xy 94.83533 -404.77035) (xy 94.78947 -404.799819) (xy 94.739883 -404.822461) (xy 94.687578 -404.837814)
			(xy 94.63362 -404.845568) (xy 94.606364 -404.846028) (xy 93.742764 -404.846028) (xy 93.715516 -404.845499)
			(xy 93.661575 -404.837739) (xy 93.609287 -404.822382) (xy 93.559717 -404.79974) (xy 93.513874 -404.770274)
			(xy 93.47269 -404.734584) (xy 93.437004 -404.693397) (xy 93.407543 -404.647551) (xy 93.384906 -404.597979)
			(xy 93.369553 -404.54569) (xy 93.361798 -404.491748) (xy 91.924142 -404.491748) (xy 91.924142 -404.491752)
			(xy 91.916386 -404.5457) (xy 91.901031 -404.597996) (xy 91.878391 -404.647574) (xy 91.848925 -404.693425)
			(xy 91.813234 -404.734617) (xy 91.772045 -404.770311) (xy 91.726195 -404.799779) (xy 91.676618 -404.822423)
			(xy 91.624324 -404.837781) (xy 91.570376 -404.845541) (xy 91.543124 -404.846028) (xy 90.679524 -404.846028)
			(xy 90.652271 -404.845526) (xy 90.598321 -404.837773) (xy 90.546023 -404.822419) (xy 90.496442 -404.799779)
			(xy 90.450588 -404.770314) (xy 90.409395 -404.734622) (xy 90.373701 -404.693431) (xy 90.344232 -404.647579)
			(xy 90.321589 -404.598) (xy 90.306233 -404.545703) (xy 90.298475 -404.491753) (xy 88.860965 -404.491753)
			(xy 88.860965 -404.491755) (xy 88.853207 -404.54571) (xy 88.83785 -404.598012) (xy 88.815205 -404.647596)
			(xy 88.785734 -404.693452) (xy 88.750036 -404.734648) (xy 88.70884 -404.770343) (xy 88.662982 -404.799812)
			(xy 88.613397 -404.822455) (xy 88.561095 -404.837811) (xy 88.507139 -404.845566) (xy 88.479884 -404.846028)
			(xy 87.616284 -404.846028) (xy 87.589035 -404.845501) (xy 87.535092 -404.837743) (xy 87.482802 -404.822387)
			(xy 87.433229 -404.799746) (xy 87.387383 -404.770281) (xy 87.346197 -404.734591) (xy 87.310509 -404.693404)
			(xy 87.281046 -404.647557) (xy 87.258407 -404.597983) (xy 87.243054 -404.545692) (xy 87.235298 -404.491749)
			(xy 85.797642 -404.491749) (xy 85.797642 -404.491751) (xy 85.789887 -404.545697) (xy 85.774533 -404.597991)
			(xy 85.751894 -404.647568) (xy 85.72243 -404.693419) (xy 85.686741 -404.73461) (xy 85.645554 -404.770304)
			(xy 85.599707 -404.799773) (xy 85.550133 -404.822417) (xy 85.49784 -404.837777) (xy 85.443895 -404.845539)
			(xy 85.416644 -404.846028) (xy 84.553044 -404.846028) (xy 84.525791 -404.845528) (xy 84.471838 -404.837776)
			(xy 84.419537 -404.822425) (xy 84.369954 -404.799786) (xy 84.324098 -404.770321) (xy 84.282902 -404.734629)
			(xy 84.247206 -404.693437) (xy 84.217735 -404.647584) (xy 84.195091 -404.598004) (xy 84.179733 -404.545705)
			(xy 84.171975 -404.491753) (xy 82.734442 -404.491753) (xy 82.726685 -404.545703) (xy 82.71133 -404.598)
			(xy 82.688688 -404.647579) (xy 82.65922 -404.693432) (xy 82.623527 -404.734624) (xy 82.582335 -404.770318)
			(xy 82.536483 -404.799786) (xy 82.486904 -404.822428) (xy 82.434607 -404.837785) (xy 82.380656 -404.845542)
			(xy 82.353404 -404.846028) (xy 81.489804 -404.846028) (xy 81.462552 -404.845525) (xy 81.408604 -404.837769)
			(xy 81.356308 -404.822414) (xy 81.30673 -404.799773) (xy 81.260879 -404.770307) (xy 81.219688 -404.734615)
			(xy 81.183996 -404.693424) (xy 81.154529 -404.647573) (xy 81.131887 -404.597995) (xy 81.116532 -404.5457)
			(xy 81.108775 -404.491752) (xy 79.671265 -404.491752) (xy 79.671265 -404.491756) (xy 79.663507 -404.545713)
			(xy 79.648148 -404.598016) (xy 79.625502 -404.647602) (xy 79.596029 -404.693459) (xy 79.560329 -404.734655)
			(xy 79.51913 -404.77035) (xy 79.47327 -404.799819) (xy 79.423683 -404.822461) (xy 79.371378 -404.837814)
			(xy 79.31742 -404.845568) (xy 79.290164 -404.846028) (xy 78.426564 -404.846028) (xy 78.399316 -404.845499)
			(xy 78.345375 -404.837739) (xy 78.293087 -404.822382) (xy 78.243517 -404.79974) (xy 78.197674 -404.770274)
			(xy 78.15649 -404.734584) (xy 78.120804 -404.693397) (xy 78.091343 -404.647551) (xy 78.068706 -404.597979)
			(xy 78.053353 -404.54569) (xy 78.045598 -404.491748) (xy 76.607942 -404.491748) (xy 76.607942 -404.491752)
			(xy 76.600186 -404.5457) (xy 76.584831 -404.597996) (xy 76.562191 -404.647574) (xy 76.532725 -404.693425)
			(xy 76.497034 -404.734617) (xy 76.455845 -404.770311) (xy 76.409995 -404.799779) (xy 76.360418 -404.822423)
			(xy 76.308124 -404.837781) (xy 76.254176 -404.845541) (xy 76.226924 -404.846028) (xy 75.363324 -404.846028)
			(xy 75.336071 -404.845526) (xy 75.282121 -404.837773) (xy 75.229823 -404.822419) (xy 75.180242 -404.799779)
			(xy 75.134388 -404.770314) (xy 75.093195 -404.734622) (xy 75.057501 -404.693431) (xy 75.028032 -404.647579)
			(xy 75.005389 -404.598) (xy 74.990033 -404.545703) (xy 74.982275 -404.491753) (xy 73.544765 -404.491753)
			(xy 73.544765 -404.491755) (xy 73.537007 -404.54571) (xy 73.52165 -404.598012) (xy 73.499005 -404.647596)
			(xy 73.469534 -404.693452) (xy 73.433836 -404.734648) (xy 73.39264 -404.770343) (xy 73.346782 -404.799812)
			(xy 73.297197 -404.822455) (xy 73.244895 -404.837811) (xy 73.190939 -404.845566) (xy 73.163684 -404.846028)
			(xy 72.300084 -404.846028) (xy 72.272835 -404.845501) (xy 72.218892 -404.837743) (xy 72.166602 -404.822387)
			(xy 72.117029 -404.799746) (xy 72.071183 -404.770281) (xy 72.029997 -404.734591) (xy 71.994309 -404.693404)
			(xy 71.964846 -404.647557) (xy 71.942207 -404.597983) (xy 71.926854 -404.545692) (xy 71.919098 -404.491749)
			(xy 70.481442 -404.491749) (xy 70.481442 -404.491751) (xy 70.473687 -404.545697) (xy 70.458333 -404.597991)
			(xy 70.435694 -404.647568) (xy 70.40623 -404.693419) (xy 70.370541 -404.73461) (xy 70.329354 -404.770304)
			(xy 70.283507 -404.799773) (xy 70.233933 -404.822417) (xy 70.18164 -404.837777) (xy 70.127695 -404.845539)
			(xy 70.100444 -404.846028) (xy 69.236844 -404.846028) (xy 69.209591 -404.845528) (xy 69.155638 -404.837776)
			(xy 69.103337 -404.822425) (xy 69.053754 -404.799786) (xy 69.007898 -404.770321) (xy 68.966702 -404.734629)
			(xy 68.931006 -404.693437) (xy 68.901535 -404.647584) (xy 68.878891 -404.598004) (xy 68.863533 -404.545705)
			(xy 68.855775 -404.491753) (xy 67.418242 -404.491753) (xy 67.410485 -404.545703) (xy 67.39513 -404.598)
			(xy 67.372488 -404.647579) (xy 67.34302 -404.693432) (xy 67.307327 -404.734624) (xy 67.266135 -404.770318)
			(xy 67.220283 -404.799786) (xy 67.170704 -404.822428) (xy 67.118407 -404.837785) (xy 67.064456 -404.845542)
			(xy 67.037204 -404.846028) (xy 66.173604 -404.846028) (xy 66.146352 -404.845525) (xy 66.092404 -404.837769)
			(xy 66.040108 -404.822414) (xy 65.99053 -404.799773) (xy 65.944679 -404.770307) (xy 65.903488 -404.734615)
			(xy 65.867796 -404.693424) (xy 65.838329 -404.647573) (xy 65.815687 -404.597995) (xy 65.800332 -404.5457)
			(xy 65.792575 -404.491752) (xy 64.355065 -404.491752) (xy 64.355065 -404.491756) (xy 64.347307 -404.545713)
			(xy 64.331948 -404.598016) (xy 64.309302 -404.647602) (xy 64.279829 -404.693459) (xy 64.244129 -404.734655)
			(xy 64.20293 -404.77035) (xy 64.15707 -404.799819) (xy 64.107483 -404.822461) (xy 64.055178 -404.837814)
			(xy 64.00122 -404.845568) (xy 63.973964 -404.846028) (xy 63.110364 -404.846028) (xy 63.083116 -404.845499)
			(xy 63.029175 -404.837739) (xy 62.976887 -404.822382) (xy 62.927317 -404.79974) (xy 62.881474 -404.770274)
			(xy 62.84029 -404.734584) (xy 62.804604 -404.693397) (xy 62.775143 -404.647551) (xy 62.752506 -404.597979)
			(xy 62.737153 -404.54569) (xy 62.729398 -404.491748) (xy 61.291742 -404.491748) (xy 61.291742 -404.491752)
			(xy 61.283986 -404.5457) (xy 61.268631 -404.597996) (xy 61.245991 -404.647574) (xy 61.216525 -404.693425)
			(xy 61.180834 -404.734617) (xy 61.139645 -404.770311) (xy 61.093795 -404.799779) (xy 61.044218 -404.822423)
			(xy 60.991924 -404.837781) (xy 60.937976 -404.845541) (xy 60.910724 -404.846028) (xy 60.047124 -404.846028)
			(xy 60.019871 -404.845526) (xy 59.965921 -404.837773) (xy 59.913623 -404.822419) (xy 59.864042 -404.799779)
			(xy 59.818188 -404.770314) (xy 59.776995 -404.734622) (xy 59.741301 -404.693431) (xy 59.711832 -404.647579)
			(xy 59.689189 -404.598) (xy 59.673833 -404.545703) (xy 59.666075 -404.491753) (xy 58.228565 -404.491753)
			(xy 58.228565 -404.491755) (xy 58.220807 -404.54571) (xy 58.20545 -404.598012) (xy 58.182805 -404.647596)
			(xy 58.153334 -404.693452) (xy 58.117636 -404.734648) (xy 58.07644 -404.770343) (xy 58.030582 -404.799812)
			(xy 57.980997 -404.822455) (xy 57.928695 -404.837811) (xy 57.874739 -404.845566) (xy 57.847484 -404.846028)
			(xy 56.983884 -404.846028) (xy 56.956635 -404.845501) (xy 56.902692 -404.837743) (xy 56.850402 -404.822387)
			(xy 56.800829 -404.799746) (xy 56.754983 -404.770281) (xy 56.713797 -404.734591) (xy 56.678109 -404.693404)
			(xy 56.648646 -404.647557) (xy 56.626007 -404.597983) (xy 56.610654 -404.545692) (xy 56.602898 -404.491749)
			(xy 55.165242 -404.491749) (xy 55.165242 -404.491751) (xy 55.157487 -404.545697) (xy 55.142133 -404.597991)
			(xy 55.119494 -404.647568) (xy 55.09003 -404.693419) (xy 55.054341 -404.73461) (xy 55.013154 -404.770304)
			(xy 54.967307 -404.799773) (xy 54.917733 -404.822417) (xy 54.86544 -404.837777) (xy 54.811495 -404.845539)
			(xy 54.784244 -404.846028) (xy 53.920644 -404.846028) (xy 53.893391 -404.845528) (xy 53.839438 -404.837776)
			(xy 53.787137 -404.822425) (xy 53.737554 -404.799786) (xy 53.691698 -404.770321) (xy 53.650502 -404.734629)
			(xy 53.614806 -404.693437) (xy 53.585335 -404.647584) (xy 53.562691 -404.598004) (xy 53.547333 -404.545705)
			(xy 53.539575 -404.491753) (xy 52.102042 -404.491753) (xy 52.094285 -404.545703) (xy 52.07893 -404.598)
			(xy 52.056288 -404.647579) (xy 52.02682 -404.693432) (xy 51.991127 -404.734624) (xy 51.949935 -404.770318)
			(xy 51.904083 -404.799786) (xy 51.854504 -404.822428) (xy 51.802207 -404.837785) (xy 51.748256 -404.845542)
			(xy 51.721004 -404.846028) (xy 50.857404 -404.846028) (xy 50.830152 -404.845525) (xy 50.776204 -404.837769)
			(xy 50.723908 -404.822414) (xy 50.67433 -404.799773) (xy 50.628479 -404.770307) (xy 50.587288 -404.734615)
			(xy 50.551596 -404.693424) (xy 50.522129 -404.647573) (xy 50.499487 -404.597995) (xy 50.484132 -404.5457)
			(xy 50.476375 -404.491752) (xy 49.038865 -404.491752) (xy 49.038865 -404.491756) (xy 49.031107 -404.545713)
			(xy 49.015748 -404.598016) (xy 48.993102 -404.647602) (xy 48.963629 -404.693459) (xy 48.927929 -404.734655)
			(xy 48.88673 -404.77035) (xy 48.84087 -404.799819) (xy 48.791283 -404.822461) (xy 48.738978 -404.837814)
			(xy 48.68502 -404.845568) (xy 48.657764 -404.846028) (xy 47.794164 -404.846028) (xy 47.766916 -404.845499)
			(xy 47.712975 -404.837739) (xy 47.660687 -404.822382) (xy 47.611117 -404.79974) (xy 47.565274 -404.770274)
			(xy 47.52409 -404.734584) (xy 47.488404 -404.693397) (xy 47.458943 -404.647551) (xy 47.436306 -404.597979)
			(xy 47.420953 -404.54569) (xy 47.413198 -404.491748) (xy 45.559703 -404.491748) (xy 45.562463 -404.52264)
			(xy 45.570405 -404.70075) (xy 45.570902 -404.789894) (xy 45.570405 -404.879038) (xy 45.562463 -405.057148)
			(xy 45.546595 -405.234728) (xy 45.522831 -405.411424) (xy 45.49122 -405.586887) (xy 45.479552 -405.638385)
			(xy 104.009796 -405.638385) (xy 104.013672 -405.584006) (xy 104.025246 -405.530732) (xy 104.044281 -405.479646)
			(xy 104.070391 -405.431789) (xy 104.103044 -405.388132) (xy 104.121966 -405.368506) (xy 104.732582 -404.757636)
			(xy 104.75423 -404.736857) (xy 104.802784 -404.701606) (xy 104.856253 -404.67438) (xy 104.91332 -404.655848)
			(xy 104.972583 -404.646465) (xy 105.002584 -404.645876) (xy 105.029856 -404.646316) (xy 105.083846 -404.654077)
			(xy 105.136181 -404.669444) (xy 105.185797 -404.692102) (xy 105.231683 -404.721592) (xy 105.272904 -404.757312)
			(xy 105.308622 -404.798535) (xy 105.338108 -404.844422) (xy 105.360764 -404.894039) (xy 105.376127 -404.946376)
			(xy 105.383885 -405.000366) (xy 105.384346 -405.027638) (xy 105.383744 -405.057639) (xy 105.374371 -405.116904)
			(xy 105.355845 -405.173974) (xy 105.328623 -405.227445) (xy 105.29971 -405.267273) (xy 106.824184 -405.267273)
			(xy 106.824184 -405.212727) (xy 106.831947 -405.158735) (xy 106.847315 -405.106398) (xy 106.869976 -405.05678)
			(xy 106.899467 -405.010893) (xy 106.935189 -404.969671) (xy 106.976414 -404.933951) (xy 107.022303 -404.904463)
			(xy 107.071922 -404.881806) (xy 107.12426 -404.866441) (xy 107.178252 -404.858682) (xy 107.205526 -404.85822)
			(xy 108.069126 -404.85822) (xy 108.096393 -404.858744) (xy 108.150371 -404.866508) (xy 108.202695 -404.881875)
			(xy 108.2523 -404.904532) (xy 108.298175 -404.934017) (xy 108.339388 -404.969731) (xy 108.375098 -405.010946)
			(xy 108.404581 -405.056823) (xy 108.427234 -405.106429) (xy 108.442597 -405.158754) (xy 108.450358 -405.212733)
			(xy 108.450358 -405.267267) (xy 108.442597 -405.321246) (xy 108.427234 -405.373571) (xy 108.404581 -405.423177)
			(xy 108.375098 -405.469054) (xy 108.339388 -405.510269) (xy 108.298175 -405.545983) (xy 108.2523 -405.575468)
			(xy 108.202695 -405.598125) (xy 108.150371 -405.613492) (xy 108.096393 -405.621256) (xy 108.069126 -405.621744)
			(xy 107.205526 -405.621744) (xy 107.178252 -405.621318) (xy 107.12426 -405.613559) (xy 107.071922 -405.598194)
			(xy 107.022303 -405.575537) (xy 106.976414 -405.546049) (xy 106.935189 -405.510329) (xy 106.899467 -405.469107)
			(xy 106.869976 -405.42322) (xy 106.847315 -405.373602) (xy 106.831947 -405.321265) (xy 106.824184 -405.267273)
			(xy 105.29971 -405.267273) (xy 105.293374 -405.276001) (xy 105.272586 -405.29764) (xy 104.661716 -405.908256)
			(xy 104.642167 -405.927256) (xy 104.598511 -405.959909) (xy 104.550654 -405.986019) (xy 104.499568 -406.005054)
			(xy 104.446294 -406.016628) (xy 104.391915 -406.020504) (xy 104.337538 -406.016603) (xy 104.284269 -406.005006)
			(xy 104.233192 -405.985949) (xy 104.185346 -405.959818) (xy 104.141704 -405.927145) (xy 104.103155 -405.888596)
			(xy 104.070482 -405.844954) (xy 104.044351 -405.797108) (xy 104.025294 -405.746031) (xy 104.013697 -405.692762)
			(xy 104.009796 -405.638385) (xy 45.479552 -405.638385) (xy 45.451824 -405.760767) (xy 45.404722 -405.93272)
			(xy 45.350006 -406.102404) (xy 45.287785 -406.269481) (xy 45.218184 -406.433622) (xy 45.141339 -406.594498)
			(xy 45.057405 -406.751792) (xy 44.966547 -406.905191) (xy 44.883756 -407.031749) (xy 48.944798 -407.031749)
			(xy 48.944798 -406.977251) (xy 48.952554 -406.923308) (xy 48.967907 -406.871017) (xy 48.990546 -406.821443)
			(xy 49.020009 -406.775596) (xy 49.055697 -406.734409) (xy 49.096883 -406.698719) (xy 49.142729 -406.669254)
			(xy 49.192302 -406.646613) (xy 49.244592 -406.631257) (xy 49.298535 -406.623499) (xy 49.325784 -406.623012)
			(xy 50.189384 -406.623012) (xy 50.216639 -406.623434) (xy 50.270595 -406.631189) (xy 50.322897 -406.646545)
			(xy 50.372482 -406.669188) (xy 50.41834 -406.698657) (xy 50.459536 -406.734352) (xy 50.495234 -406.775548)
			(xy 50.524705 -406.821404) (xy 50.54735 -406.870988) (xy 50.562707 -406.92329) (xy 50.570465 -406.977245)
			(xy 50.570465 -407.031753) (xy 52.007975 -407.031753) (xy 52.007975 -406.977247) (xy 52.015733 -406.923297)
			(xy 52.031089 -406.871) (xy 52.053732 -406.821421) (xy 52.083201 -406.775569) (xy 52.118895 -406.734378)
			(xy 52.160088 -406.698686) (xy 52.205942 -406.669221) (xy 52.255523 -406.646581) (xy 52.307821 -406.631227)
			(xy 52.361771 -406.623474) (xy 52.389024 -406.623012) (xy 53.252624 -406.623012) (xy 53.279876 -406.623459)
			(xy 53.333824 -406.631219) (xy 53.386118 -406.646577) (xy 53.435695 -406.669221) (xy 53.481545 -406.698689)
			(xy 53.522734 -406.734383) (xy 53.558425 -406.775575) (xy 53.587891 -406.821426) (xy 53.610531 -406.871004)
			(xy 53.625886 -406.9233) (xy 53.633642 -406.977248) (xy 53.633642 -407.031748) (xy 55.071298 -407.031748)
			(xy 55.071298 -406.977252) (xy 55.079053 -406.92331) (xy 55.094406 -406.871021) (xy 55.117043 -406.821449)
			(xy 55.146504 -406.775603) (xy 55.18219 -406.734416) (xy 55.223374 -406.698726) (xy 55.269217 -406.66926)
			(xy 55.318787 -406.646618) (xy 55.371075 -406.631261) (xy 55.425016 -406.623501) (xy 55.452264 -406.623012)
			(xy 56.315864 -406.623012) (xy 56.34312 -406.623432) (xy 56.397078 -406.631186) (xy 56.449383 -406.646539)
			(xy 56.49897 -406.669181) (xy 56.54483 -406.69865) (xy 56.586029 -406.734345) (xy 56.621729 -406.775541)
			(xy 56.651202 -406.821398) (xy 56.673848 -406.870984) (xy 56.689207 -406.923287) (xy 56.696965 -406.977244)
			(xy 56.696965 -407.031752) (xy 58.134475 -407.031752) (xy 58.134475 -406.977248) (xy 58.142232 -406.9233)
			(xy 58.157587 -406.871005) (xy 58.180229 -406.821427) (xy 58.209696 -406.775576) (xy 58.245388 -406.734385)
			(xy 58.286579 -406.698693) (xy 58.33243 -406.669227) (xy 58.382008 -406.646586) (xy 58.434304 -406.631231)
			(xy 58.488252 -406.623475) (xy 58.515504 -406.623012) (xy 59.379104 -406.623012) (xy 59.406356 -406.623458)
			(xy 59.460307 -406.631215) (xy 59.512604 -406.646572) (xy 59.562183 -406.669214) (xy 59.608035 -406.698682)
			(xy 59.649227 -406.734376) (xy 59.68492 -406.775568) (xy 59.714388 -406.821421) (xy 59.73703 -406.871)
			(xy 59.752385 -406.923297) (xy 59.760142 -406.977248) (xy 59.760142 -407.031752) (xy 59.760142 -407.031753)
			(xy 61.197675 -407.031753) (xy 61.197675 -406.977247) (xy 61.205433 -406.923295) (xy 61.220791 -406.870996)
			(xy 61.243435 -406.821416) (xy 61.272906 -406.775563) (xy 61.308602 -406.734371) (xy 61.349798 -406.698679)
			(xy 61.395654 -406.669214) (xy 61.445237 -406.646575) (xy 61.497538 -406.631224) (xy 61.551491 -406.623472)
			(xy 61.578744 -406.623012) (xy 62.442344 -406.623012) (xy 62.469595 -406.623461) (xy 62.52354 -406.631223)
			(xy 62.575833 -406.646583) (xy 62.625407 -406.669227) (xy 62.671254 -406.698696) (xy 62.712441 -406.73439)
			(xy 62.74813 -406.775581) (xy 62.777594 -406.821432) (xy 62.800233 -406.871009) (xy 62.815587 -406.923303)
			(xy 62.823342 -406.977249) (xy 62.823342 -407.031749) (xy 64.260998 -407.031749) (xy 64.260998 -406.977251)
			(xy 64.268754 -406.923308) (xy 64.284107 -406.871017) (xy 64.306746 -406.821443) (xy 64.336209 -406.775596)
			(xy 64.371897 -406.734409) (xy 64.413083 -406.698719) (xy 64.458929 -406.669254) (xy 64.508502 -406.646613)
			(xy 64.560792 -406.631257) (xy 64.614735 -406.623499) (xy 64.641984 -406.623012) (xy 65.505584 -406.623012)
			(xy 65.532839 -406.623434) (xy 65.586795 -406.631189) (xy 65.639097 -406.646545) (xy 65.688682 -406.669188)
			(xy 65.73454 -406.698657) (xy 65.775736 -406.734352) (xy 65.811434 -406.775548) (xy 65.840905 -406.821404)
			(xy 65.86355 -406.870988) (xy 65.878907 -406.92329) (xy 65.886665 -406.977245) (xy 65.886665 -407.031753)
			(xy 67.324175 -407.031753) (xy 67.324175 -406.977247) (xy 67.331933 -406.923297) (xy 67.347289 -406.871)
			(xy 67.369932 -406.821421) (xy 67.399401 -406.775569) (xy 67.435095 -406.734378) (xy 67.476288 -406.698686)
			(xy 67.522142 -406.669221) (xy 67.571723 -406.646581) (xy 67.624021 -406.631227) (xy 67.677971 -406.623474)
			(xy 67.705224 -406.623012) (xy 68.568824 -406.623012) (xy 68.596076 -406.623459) (xy 68.650024 -406.631219)
			(xy 68.702318 -406.646577) (xy 68.751895 -406.669221) (xy 68.797745 -406.698689) (xy 68.838934 -406.734383)
			(xy 68.874625 -406.775575) (xy 68.904091 -406.821426) (xy 68.926731 -406.871004) (xy 68.942086 -406.9233)
			(xy 68.949842 -406.977248) (xy 68.949842 -407.031748) (xy 70.387498 -407.031748) (xy 70.387498 -406.977252)
			(xy 70.395253 -406.92331) (xy 70.410606 -406.871021) (xy 70.433243 -406.821449) (xy 70.462704 -406.775603)
			(xy 70.49839 -406.734416) (xy 70.539574 -406.698726) (xy 70.585417 -406.66926) (xy 70.634987 -406.646618)
			(xy 70.687275 -406.631261) (xy 70.741216 -406.623501) (xy 70.768464 -406.623012) (xy 71.632064 -406.623012)
			(xy 71.65932 -406.623432) (xy 71.713278 -406.631186) (xy 71.765583 -406.646539) (xy 71.81517 -406.669181)
			(xy 71.86103 -406.69865) (xy 71.902229 -406.734345) (xy 71.937929 -406.775541) (xy 71.967402 -406.821398)
			(xy 71.990048 -406.870984) (xy 72.005407 -406.923287) (xy 72.013165 -406.977244) (xy 72.013165 -407.031752)
			(xy 73.450675 -407.031752) (xy 73.450675 -406.977248) (xy 73.458432 -406.9233) (xy 73.473787 -406.871005)
			(xy 73.496429 -406.821427) (xy 73.525896 -406.775576) (xy 73.561588 -406.734385) (xy 73.602779 -406.698693)
			(xy 73.64863 -406.669227) (xy 73.698208 -406.646586) (xy 73.750504 -406.631231) (xy 73.804452 -406.623475)
			(xy 73.831704 -406.623012) (xy 74.695304 -406.623012) (xy 74.722556 -406.623458) (xy 74.776507 -406.631215)
			(xy 74.828804 -406.646572) (xy 74.878383 -406.669214) (xy 74.924235 -406.698682) (xy 74.965427 -406.734376)
			(xy 75.00112 -406.775568) (xy 75.030588 -406.821421) (xy 75.05323 -406.871) (xy 75.068585 -406.923297)
			(xy 75.076342 -406.977248) (xy 75.076342 -407.031752) (xy 75.076342 -407.031753) (xy 76.513875 -407.031753)
			(xy 76.513875 -406.977247) (xy 76.521633 -406.923295) (xy 76.536991 -406.870996) (xy 76.559635 -406.821416)
			(xy 76.589106 -406.775563) (xy 76.624802 -406.734371) (xy 76.665998 -406.698679) (xy 76.711854 -406.669214)
			(xy 76.761437 -406.646575) (xy 76.813738 -406.631224) (xy 76.867691 -406.623472) (xy 76.894944 -406.623012)
			(xy 77.758544 -406.623012) (xy 77.785795 -406.623461) (xy 77.83974 -406.631223) (xy 77.892033 -406.646583)
			(xy 77.941607 -406.669227) (xy 77.987454 -406.698696) (xy 78.028641 -406.73439) (xy 78.06433 -406.775581)
			(xy 78.093794 -406.821432) (xy 78.116433 -406.871009) (xy 78.131787 -406.923303) (xy 78.139542 -406.977249)
			(xy 78.139542 -407.031749) (xy 79.577198 -407.031749) (xy 79.577198 -406.977251) (xy 79.584954 -406.923308)
			(xy 79.600307 -406.871017) (xy 79.622946 -406.821443) (xy 79.652409 -406.775596) (xy 79.688097 -406.734409)
			(xy 79.729283 -406.698719) (xy 79.775129 -406.669254) (xy 79.824702 -406.646613) (xy 79.876992 -406.631257)
			(xy 79.930935 -406.623499) (xy 79.958184 -406.623012) (xy 80.821784 -406.623012) (xy 80.849039 -406.623434)
			(xy 80.902995 -406.631189) (xy 80.955297 -406.646545) (xy 81.004882 -406.669188) (xy 81.05074 -406.698657)
			(xy 81.091936 -406.734352) (xy 81.127634 -406.775548) (xy 81.157105 -406.821404) (xy 81.17975 -406.870988)
			(xy 81.195107 -406.92329) (xy 81.202865 -406.977245) (xy 81.202865 -407.031753) (xy 82.640375 -407.031753)
			(xy 82.640375 -406.977247) (xy 82.648133 -406.923297) (xy 82.663489 -406.871) (xy 82.686132 -406.821421)
			(xy 82.715601 -406.775569) (xy 82.751295 -406.734378) (xy 82.792488 -406.698686) (xy 82.838342 -406.669221)
			(xy 82.887923 -406.646581) (xy 82.940221 -406.631227) (xy 82.994171 -406.623474) (xy 83.021424 -406.623012)
			(xy 83.885024 -406.623012) (xy 83.912276 -406.623459) (xy 83.966224 -406.631219) (xy 84.018518 -406.646577)
			(xy 84.068095 -406.669221) (xy 84.113945 -406.698689) (xy 84.155134 -406.734383) (xy 84.190825 -406.775575)
			(xy 84.220291 -406.821426) (xy 84.242931 -406.871004) (xy 84.258286 -406.9233) (xy 84.266042 -406.977248)
			(xy 84.266042 -407.031748) (xy 85.703698 -407.031748) (xy 85.703698 -406.977252) (xy 85.711453 -406.92331)
			(xy 85.726806 -406.871021) (xy 85.749443 -406.821449) (xy 85.778904 -406.775603) (xy 85.81459 -406.734416)
			(xy 85.855774 -406.698726) (xy 85.901617 -406.66926) (xy 85.951187 -406.646618) (xy 86.003475 -406.631261)
			(xy 86.057416 -406.623501) (xy 86.084664 -406.623012) (xy 86.948264 -406.623012) (xy 86.97552 -406.623432)
			(xy 87.029478 -406.631186) (xy 87.081783 -406.646539) (xy 87.13137 -406.669181) (xy 87.17723 -406.69865)
			(xy 87.218429 -406.734345) (xy 87.254129 -406.775541) (xy 87.283602 -406.821398) (xy 87.306248 -406.870984)
			(xy 87.321607 -406.923287) (xy 87.329365 -406.977244) (xy 87.329365 -407.031752) (xy 88.766875 -407.031752)
			(xy 88.766875 -406.977248) (xy 88.774632 -406.9233) (xy 88.789987 -406.871005) (xy 88.812629 -406.821427)
			(xy 88.842096 -406.775576) (xy 88.877788 -406.734385) (xy 88.918979 -406.698693) (xy 88.96483 -406.669227)
			(xy 89.014408 -406.646586) (xy 89.066704 -406.631231) (xy 89.120652 -406.623475) (xy 89.147904 -406.623012)
			(xy 90.011504 -406.623012) (xy 90.038756 -406.623458) (xy 90.092707 -406.631215) (xy 90.145004 -406.646572)
			(xy 90.194583 -406.669214) (xy 90.240435 -406.698682) (xy 90.281627 -406.734376) (xy 90.31732 -406.775568)
			(xy 90.346788 -406.821421) (xy 90.36943 -406.871) (xy 90.384785 -406.923297) (xy 90.392542 -406.977248)
			(xy 90.392542 -407.031752) (xy 90.392542 -407.031753) (xy 91.830075 -407.031753) (xy 91.830075 -406.977247)
			(xy 91.837833 -406.923295) (xy 91.853191 -406.870996) (xy 91.875835 -406.821416) (xy 91.905306 -406.775563)
			(xy 91.941002 -406.734371) (xy 91.982198 -406.698679) (xy 92.028054 -406.669214) (xy 92.077637 -406.646575)
			(xy 92.129938 -406.631224) (xy 92.183891 -406.623472) (xy 92.211144 -406.623012) (xy 93.074744 -406.623012)
			(xy 93.101995 -406.623461) (xy 93.15594 -406.631223) (xy 93.208233 -406.646583) (xy 93.257807 -406.669227)
			(xy 93.303654 -406.698696) (xy 93.344841 -406.73439) (xy 93.38053 -406.775581) (xy 93.409994 -406.821432)
			(xy 93.432633 -406.871009) (xy 93.447987 -406.923303) (xy 93.455742 -406.977249) (xy 93.455742 -407.031749)
			(xy 94.893398 -407.031749) (xy 94.893398 -406.977251) (xy 94.901154 -406.923308) (xy 94.916507 -406.871017)
			(xy 94.939146 -406.821443) (xy 94.968609 -406.775596) (xy 95.004297 -406.734409) (xy 95.045483 -406.698719)
			(xy 95.091329 -406.669254) (xy 95.140902 -406.646613) (xy 95.193192 -406.631257) (xy 95.247135 -406.623499)
			(xy 95.274384 -406.623012) (xy 96.137984 -406.623012) (xy 96.165239 -406.623434) (xy 96.219195 -406.631189)
			(xy 96.271497 -406.646545) (xy 96.321082 -406.669188) (xy 96.36694 -406.698657) (xy 96.408136 -406.734352)
			(xy 96.443834 -406.775548) (xy 96.473305 -406.821404) (xy 96.49595 -406.870988) (xy 96.511307 -406.92329)
			(xy 96.519065 -406.977245) (xy 96.519065 -407.031753) (xy 116.044675 -407.031753) (xy 116.044675 -406.977247)
			(xy 116.052433 -406.923297) (xy 116.067789 -406.871) (xy 116.090432 -406.821421) (xy 116.119901 -406.775569)
			(xy 116.155596 -406.734377) (xy 116.196789 -406.698686) (xy 116.242643 -406.66922) (xy 116.292224 -406.64658)
			(xy 116.344522 -406.631227) (xy 116.398473 -406.623474) (xy 116.425726 -406.623012) (xy 117.289326 -406.623012)
			(xy 117.316577 -406.62346) (xy 117.370525 -406.63122) (xy 117.42282 -406.646578) (xy 117.472396 -406.669222)
			(xy 117.518246 -406.69869) (xy 117.559435 -406.734383) (xy 117.595126 -406.775575) (xy 117.624591 -406.821427)
			(xy 117.647231 -406.871005) (xy 117.662586 -406.9233) (xy 117.670342 -406.977249) (xy 117.670342 -407.031748)
			(xy 119.107998 -407.031748) (xy 119.107998 -406.977252) (xy 119.115753 -406.92331) (xy 119.131106 -406.871021)
			(xy 119.153743 -406.821448) (xy 119.183205 -406.775602) (xy 119.218891 -406.734415) (xy 119.260075 -406.698725)
			(xy 119.305918 -406.66926) (xy 119.355489 -406.646618) (xy 119.407777 -406.631261) (xy 119.461718 -406.623501)
			(xy 119.488966 -406.623012) (xy 120.352566 -406.623012) (xy 120.379822 -406.623433) (xy 120.433779 -406.631186)
			(xy 120.486084 -406.64654) (xy 120.535671 -406.669182) (xy 120.581531 -406.69865) (xy 120.62273 -406.734346)
			(xy 120.658429 -406.775542) (xy 120.687902 -406.821399) (xy 120.710548 -406.870984) (xy 120.725907 -406.923287)
			(xy 120.733665 -406.977244) (xy 120.733665 -407.031752) (xy 122.171175 -407.031752) (xy 122.171175 -406.977248)
			(xy 122.178932 -406.9233) (xy 122.194288 -406.871004) (xy 122.216929 -406.821426) (xy 122.246396 -406.775575)
			(xy 122.282089 -406.734384) (xy 122.32328 -406.698693) (xy 122.369131 -406.669226) (xy 122.41871 -406.646585)
			(xy 122.471006 -406.631231) (xy 122.524954 -406.623475) (xy 122.552206 -406.623012) (xy 123.415806 -406.623012)
			(xy 123.443058 -406.623458) (xy 123.497008 -406.631216) (xy 123.549305 -406.646572) (xy 123.598884 -406.669215)
			(xy 123.644736 -406.698683) (xy 123.685928 -406.734376) (xy 123.721621 -406.775569) (xy 123.751088 -406.821421)
			(xy 123.77373 -406.871001) (xy 123.789085 -406.923298) (xy 123.796842 -406.977248) (xy 123.796842 -407.031752)
			(xy 123.796842 -407.031754) (xy 125.234375 -407.031754) (xy 125.234375 -406.977246) (xy 125.242133 -406.923294)
			(xy 125.257491 -406.870996) (xy 125.280135 -406.821415) (xy 125.309606 -406.775562) (xy 125.345303 -406.73437)
			(xy 125.386499 -406.698679) (xy 125.432355 -406.669213) (xy 125.481939 -406.646575) (xy 125.534239 -406.631223)
			(xy 125.588192 -406.623472) (xy 125.615446 -406.623012) (xy 126.479046 -406.623012) (xy 126.506297 -406.623461)
			(xy 126.560242 -406.631223) (xy 126.612534 -406.646583) (xy 126.662108 -406.669228) (xy 126.707955 -406.698697)
			(xy 126.749142 -406.734391) (xy 126.78483 -406.775582) (xy 126.814294 -406.821432) (xy 126.836933 -406.871009)
			(xy 126.852287 -406.923303) (xy 126.860042 -406.977249) (xy 126.860042 -407.031749) (xy 128.297698 -407.031749)
			(xy 128.297698 -406.977251) (xy 128.305454 -406.923307) (xy 128.320808 -406.871016) (xy 128.343446 -406.821443)
			(xy 128.37291 -406.775596) (xy 128.408598 -406.734408) (xy 128.449784 -406.698718) (xy 128.49563 -406.669253)
			(xy 128.545203 -406.646612) (xy 128.597494 -406.631257) (xy 128.651437 -406.623499) (xy 128.678686 -406.623012)
			(xy 129.542286 -406.623012) (xy 129.569541 -406.623434) (xy 129.623496 -406.63119) (xy 129.675799 -406.646545)
			(xy 129.725383 -406.669188) (xy 129.771241 -406.698657) (xy 129.812437 -406.734353) (xy 129.848134 -406.775548)
			(xy 129.877605 -406.821405) (xy 129.90025 -406.870988) (xy 129.915607 -406.92329) (xy 129.923365 -406.977245)
			(xy 129.923365 -407.031753) (xy 131.360875 -407.031753) (xy 131.360875 -406.977247) (xy 131.368633 -406.923297)
			(xy 131.383989 -406.871) (xy 131.406632 -406.821421) (xy 131.436101 -406.775569) (xy 131.471796 -406.734377)
			(xy 131.512989 -406.698686) (xy 131.558843 -406.66922) (xy 131.608424 -406.64658) (xy 131.660722 -406.631227)
			(xy 131.714673 -406.623474) (xy 131.741926 -406.623012) (xy 132.605526 -406.623012) (xy 132.632777 -406.62346)
			(xy 132.686725 -406.63122) (xy 132.73902 -406.646578) (xy 132.788596 -406.669222) (xy 132.834446 -406.69869)
			(xy 132.875635 -406.734383) (xy 132.911326 -406.775575) (xy 132.940791 -406.821427) (xy 132.963431 -406.871005)
			(xy 132.978786 -406.9233) (xy 132.986542 -406.977249) (xy 132.986542 -407.031748) (xy 134.424198 -407.031748)
			(xy 134.424198 -406.977252) (xy 134.431953 -406.92331) (xy 134.447306 -406.871021) (xy 134.469943 -406.821448)
			(xy 134.499405 -406.775602) (xy 134.535091 -406.734415) (xy 134.576275 -406.698725) (xy 134.622118 -406.66926)
			(xy 134.671689 -406.646618) (xy 134.723977 -406.631261) (xy 134.777918 -406.623501) (xy 134.805166 -406.623012)
			(xy 135.668766 -406.623012) (xy 135.696022 -406.623433) (xy 135.749979 -406.631186) (xy 135.802284 -406.64654)
			(xy 135.851871 -406.669182) (xy 135.897731 -406.69865) (xy 135.93893 -406.734346) (xy 135.974629 -406.775542)
			(xy 136.004102 -406.821399) (xy 136.026748 -406.870984) (xy 136.042107 -406.923287) (xy 136.049865 -406.977244)
			(xy 136.049865 -407.031752) (xy 137.487375 -407.031752) (xy 137.487375 -406.977248) (xy 137.495132 -406.9233)
			(xy 137.510488 -406.871004) (xy 137.533129 -406.821426) (xy 137.562596 -406.775575) (xy 137.598289 -406.734384)
			(xy 137.63948 -406.698693) (xy 137.685331 -406.669226) (xy 137.73491 -406.646585) (xy 137.787206 -406.631231)
			(xy 137.841154 -406.623475) (xy 137.868406 -406.623012) (xy 138.732006 -406.623012) (xy 138.759258 -406.623458)
			(xy 138.813208 -406.631216) (xy 138.865505 -406.646572) (xy 138.915084 -406.669215) (xy 138.960936 -406.698683)
			(xy 139.002128 -406.734376) (xy 139.037821 -406.775569) (xy 139.067288 -406.821421) (xy 139.08993 -406.871001)
			(xy 139.105285 -406.923298) (xy 139.113042 -406.977248) (xy 139.113042 -407.031752) (xy 139.113042 -407.031754)
			(xy 140.550575 -407.031754) (xy 140.550575 -406.977246) (xy 140.558333 -406.923294) (xy 140.573691 -406.870996)
			(xy 140.596335 -406.821415) (xy 140.625806 -406.775562) (xy 140.661503 -406.73437) (xy 140.702699 -406.698679)
			(xy 140.748555 -406.669213) (xy 140.798139 -406.646575) (xy 140.850439 -406.631223) (xy 140.904392 -406.623472)
			(xy 140.931646 -406.623012) (xy 141.795246 -406.623012) (xy 141.822497 -406.623461) (xy 141.876442 -406.631223)
			(xy 141.928734 -406.646583) (xy 141.978308 -406.669228) (xy 142.024155 -406.698697) (xy 142.065342 -406.734391)
			(xy 142.10103 -406.775582) (xy 142.130494 -406.821432) (xy 142.153133 -406.871009) (xy 142.168487 -406.923303)
			(xy 142.176242 -406.977249) (xy 142.176242 -407.031749) (xy 143.613898 -407.031749) (xy 143.613898 -406.977251)
			(xy 143.621654 -406.923307) (xy 143.637008 -406.871016) (xy 143.659646 -406.821443) (xy 143.68911 -406.775596)
			(xy 143.724798 -406.734408) (xy 143.765984 -406.698718) (xy 143.81183 -406.669253) (xy 143.861403 -406.646612)
			(xy 143.913694 -406.631257) (xy 143.967637 -406.623499) (xy 143.994886 -406.623012) (xy 144.858486 -406.623012)
			(xy 144.885741 -406.623434) (xy 144.939696 -406.63119) (xy 144.991999 -406.646545) (xy 145.041583 -406.669188)
			(xy 145.087441 -406.698657) (xy 145.128637 -406.734353) (xy 145.164334 -406.775548) (xy 145.193805 -406.821405)
			(xy 145.21645 -406.870988) (xy 145.231807 -406.92329) (xy 145.239565 -406.977245) (xy 145.239565 -407.031753)
			(xy 146.677075 -407.031753) (xy 146.677075 -406.977247) (xy 146.684833 -406.923297) (xy 146.700189 -406.871)
			(xy 146.722832 -406.821421) (xy 146.752301 -406.775569) (xy 146.787996 -406.734377) (xy 146.829189 -406.698686)
			(xy 146.875043 -406.66922) (xy 146.924624 -406.64658) (xy 146.976922 -406.631227) (xy 147.030873 -406.623474)
			(xy 147.058126 -406.623012) (xy 147.921726 -406.623012) (xy 147.948977 -406.62346) (xy 148.002925 -406.63122)
			(xy 148.05522 -406.646578) (xy 148.104796 -406.669222) (xy 148.150646 -406.69869) (xy 148.191835 -406.734383)
			(xy 148.227526 -406.775575) (xy 148.256991 -406.821427) (xy 148.279631 -406.871005) (xy 148.294986 -406.9233)
			(xy 148.302742 -406.977249) (xy 148.302742 -407.031748) (xy 149.740398 -407.031748) (xy 149.740398 -406.977252)
			(xy 149.748153 -406.92331) (xy 149.763506 -406.871021) (xy 149.786143 -406.821448) (xy 149.815605 -406.775602)
			(xy 149.851291 -406.734415) (xy 149.892475 -406.698725) (xy 149.938318 -406.66926) (xy 149.987889 -406.646618)
			(xy 150.040177 -406.631261) (xy 150.094118 -406.623501) (xy 150.121366 -406.623012) (xy 150.984966 -406.623012)
			(xy 151.012222 -406.623433) (xy 151.066179 -406.631186) (xy 151.118484 -406.64654) (xy 151.168071 -406.669182)
			(xy 151.213931 -406.69865) (xy 151.25513 -406.734346) (xy 151.290829 -406.775542) (xy 151.320302 -406.821399)
			(xy 151.342948 -406.870984) (xy 151.358307 -406.923287) (xy 151.366065 -406.977244) (xy 151.366065 -407.031752)
			(xy 152.803575 -407.031752) (xy 152.803575 -406.977248) (xy 152.811332 -406.9233) (xy 152.826688 -406.871004)
			(xy 152.849329 -406.821426) (xy 152.878796 -406.775575) (xy 152.914489 -406.734384) (xy 152.95568 -406.698693)
			(xy 153.001531 -406.669226) (xy 153.05111 -406.646585) (xy 153.103406 -406.631231) (xy 153.157354 -406.623475)
			(xy 153.184606 -406.623012) (xy 154.048206 -406.623012) (xy 154.075458 -406.623458) (xy 154.129408 -406.631216)
			(xy 154.181705 -406.646572) (xy 154.231284 -406.669215) (xy 154.277136 -406.698683) (xy 154.318328 -406.734376)
			(xy 154.354021 -406.775569) (xy 154.383488 -406.821421) (xy 154.40613 -406.871001) (xy 154.421485 -406.923298)
			(xy 154.429242 -406.977248) (xy 154.429242 -407.031752) (xy 154.429242 -407.031754) (xy 155.866775 -407.031754)
			(xy 155.866775 -406.977246) (xy 155.874533 -406.923294) (xy 155.889891 -406.870996) (xy 155.912535 -406.821415)
			(xy 155.942006 -406.775562) (xy 155.977703 -406.73437) (xy 156.018899 -406.698679) (xy 156.064755 -406.669213)
			(xy 156.114339 -406.646575) (xy 156.166639 -406.631223) (xy 156.220592 -406.623472) (xy 156.247846 -406.623012)
			(xy 157.111446 -406.623012) (xy 157.138697 -406.623461) (xy 157.192642 -406.631223) (xy 157.244934 -406.646583)
			(xy 157.294508 -406.669228) (xy 157.340355 -406.698697) (xy 157.381542 -406.734391) (xy 157.41723 -406.775582)
			(xy 157.446694 -406.821432) (xy 157.469333 -406.871009) (xy 157.484687 -406.923303) (xy 157.492442 -406.977249)
			(xy 157.492442 -407.031749) (xy 158.930098 -407.031749) (xy 158.930098 -406.977251) (xy 158.937854 -406.923307)
			(xy 158.953208 -406.871016) (xy 158.975846 -406.821443) (xy 159.00531 -406.775596) (xy 159.040998 -406.734408)
			(xy 159.082184 -406.698718) (xy 159.12803 -406.669253) (xy 159.177603 -406.646612) (xy 159.229894 -406.631257)
			(xy 159.283837 -406.623499) (xy 159.311086 -406.623012) (xy 160.174686 -406.623012) (xy 160.201941 -406.623434)
			(xy 160.255896 -406.63119) (xy 160.308199 -406.646545) (xy 160.357783 -406.669188) (xy 160.403641 -406.698657)
			(xy 160.444837 -406.734353) (xy 160.480534 -406.775548) (xy 160.510005 -406.821405) (xy 160.53265 -406.870988)
			(xy 160.548007 -406.92329) (xy 160.555765 -406.977245) (xy 160.555765 -407.031753) (xy 161.993275 -407.031753)
			(xy 161.993275 -406.977247) (xy 162.001033 -406.923297) (xy 162.016389 -406.871) (xy 162.039032 -406.821421)
			(xy 162.068501 -406.775569) (xy 162.104196 -406.734377) (xy 162.145389 -406.698686) (xy 162.191243 -406.66922)
			(xy 162.240824 -406.64658) (xy 162.293122 -406.631227) (xy 162.347073 -406.623474) (xy 162.374326 -406.623012)
			(xy 163.237926 -406.623012) (xy 163.265177 -406.62346) (xy 163.319125 -406.63122) (xy 163.37142 -406.646578)
			(xy 163.420996 -406.669222) (xy 163.466846 -406.69869) (xy 163.508035 -406.734383) (xy 163.543726 -406.775575)
			(xy 163.573191 -406.821427) (xy 163.595831 -406.871005) (xy 163.611186 -406.9233) (xy 163.618942 -406.977249)
			(xy 163.618942 -407.031751) (xy 163.611186 -407.0857) (xy 163.595831 -407.137995) (xy 163.573191 -407.187573)
			(xy 163.543726 -407.233425) (xy 163.508035 -407.274617) (xy 163.466846 -407.31031) (xy 163.420996 -407.339778)
			(xy 163.37142 -407.362422) (xy 163.319125 -407.37778) (xy 163.265177 -407.38554) (xy 163.237926 -407.386028)
			(xy 162.374326 -407.386028) (xy 162.347073 -407.385526) (xy 162.293122 -407.377773) (xy 162.240824 -407.36242)
			(xy 162.191243 -407.33978) (xy 162.145389 -407.310314) (xy 162.104196 -407.274623) (xy 162.068501 -407.233431)
			(xy 162.039032 -407.187579) (xy 162.016389 -407.138) (xy 162.001033 -407.085703) (xy 161.993275 -407.031753)
			(xy 160.555765 -407.031753) (xy 160.555765 -407.031755) (xy 160.548007 -407.08571) (xy 160.53265 -407.138012)
			(xy 160.510005 -407.187595) (xy 160.480534 -407.233452) (xy 160.444837 -407.274647) (xy 160.403641 -407.310343)
			(xy 160.357783 -407.339812) (xy 160.308199 -407.362455) (xy 160.255896 -407.37781) (xy 160.201941 -407.385566)
			(xy 160.174686 -407.386028) (xy 159.311086 -407.386028) (xy 159.283837 -407.385501) (xy 159.229894 -407.377743)
			(xy 159.177603 -407.362388) (xy 159.12803 -407.339747) (xy 159.082184 -407.310282) (xy 159.040998 -407.274592)
			(xy 159.00531 -407.233404) (xy 158.975846 -407.187557) (xy 158.953208 -407.137984) (xy 158.937854 -407.085693)
			(xy 158.930098 -407.031749) (xy 157.492442 -407.031749) (xy 157.492442 -407.031751) (xy 157.484687 -407.085697)
			(xy 157.469333 -407.137991) (xy 157.446694 -407.187568) (xy 157.41723 -407.233418) (xy 157.381542 -407.274609)
			(xy 157.340355 -407.310303) (xy 157.294508 -407.339772) (xy 157.244934 -407.362417) (xy 157.192642 -407.377777)
			(xy 157.138697 -407.385539) (xy 157.111446 -407.386028) (xy 156.247846 -407.386028) (xy 156.220592 -407.385528)
			(xy 156.166639 -407.377777) (xy 156.114339 -407.362425) (xy 156.064755 -407.339787) (xy 156.018899 -407.310321)
			(xy 155.977703 -407.27463) (xy 155.942006 -407.233438) (xy 155.912535 -407.187585) (xy 155.889891 -407.138004)
			(xy 155.874533 -407.085706) (xy 155.866775 -407.031754) (xy 154.429242 -407.031754) (xy 154.421485 -407.085702)
			(xy 154.40613 -407.137999) (xy 154.383488 -407.187579) (xy 154.354021 -407.233431) (xy 154.318328 -407.274624)
			(xy 154.277136 -407.310317) (xy 154.231284 -407.339785) (xy 154.181705 -407.362428) (xy 154.129408 -407.377784)
			(xy 154.075458 -407.385542) (xy 154.048206 -407.386028) (xy 153.184606 -407.386028) (xy 153.157354 -407.385525)
			(xy 153.103406 -407.377769) (xy 153.05111 -407.362415) (xy 153.001531 -407.339774) (xy 152.95568 -407.310307)
			(xy 152.914489 -407.274616) (xy 152.878796 -407.233425) (xy 152.849329 -407.187574) (xy 152.826688 -407.137996)
			(xy 152.811332 -407.0857) (xy 152.803575 -407.031752) (xy 151.366065 -407.031752) (xy 151.366065 -407.031756)
			(xy 151.358307 -407.085713) (xy 151.342948 -407.138016) (xy 151.320302 -407.187601) (xy 151.290829 -407.233458)
			(xy 151.25513 -407.274654) (xy 151.213931 -407.31035) (xy 151.168071 -407.339818) (xy 151.118484 -407.36246)
			(xy 151.066179 -407.377814) (xy 151.012222 -407.385567) (xy 150.984966 -407.386028) (xy 150.121366 -407.386028)
			(xy 150.094118 -407.385499) (xy 150.040177 -407.377739) (xy 149.987889 -407.362382) (xy 149.938318 -407.33974)
			(xy 149.892475 -407.310275) (xy 149.851291 -407.274585) (xy 149.815605 -407.233398) (xy 149.786143 -407.187552)
			(xy 149.763506 -407.137979) (xy 149.748153 -407.08569) (xy 149.740398 -407.031748) (xy 148.302742 -407.031748)
			(xy 148.302742 -407.031751) (xy 148.294986 -407.0857) (xy 148.279631 -407.137995) (xy 148.256991 -407.187573)
			(xy 148.227526 -407.233425) (xy 148.191835 -407.274617) (xy 148.150646 -407.31031) (xy 148.104796 -407.339778)
			(xy 148.05522 -407.362422) (xy 148.002925 -407.37778) (xy 147.948977 -407.38554) (xy 147.921726 -407.386028)
			(xy 147.058126 -407.386028) (xy 147.030873 -407.385526) (xy 146.976922 -407.377773) (xy 146.924624 -407.36242)
			(xy 146.875043 -407.33978) (xy 146.829189 -407.310314) (xy 146.787996 -407.274623) (xy 146.752301 -407.233431)
			(xy 146.722832 -407.187579) (xy 146.700189 -407.138) (xy 146.684833 -407.085703) (xy 146.677075 -407.031753)
			(xy 145.239565 -407.031753) (xy 145.239565 -407.031755) (xy 145.231807 -407.08571) (xy 145.21645 -407.138012)
			(xy 145.193805 -407.187595) (xy 145.164334 -407.233452) (xy 145.128637 -407.274647) (xy 145.087441 -407.310343)
			(xy 145.041583 -407.339812) (xy 144.991999 -407.362455) (xy 144.939696 -407.37781) (xy 144.885741 -407.385566)
			(xy 144.858486 -407.386028) (xy 143.994886 -407.386028) (xy 143.967637 -407.385501) (xy 143.913694 -407.377743)
			(xy 143.861403 -407.362388) (xy 143.81183 -407.339747) (xy 143.765984 -407.310282) (xy 143.724798 -407.274592)
			(xy 143.68911 -407.233404) (xy 143.659646 -407.187557) (xy 143.637008 -407.137984) (xy 143.621654 -407.085693)
			(xy 143.613898 -407.031749) (xy 142.176242 -407.031749) (xy 142.176242 -407.031751) (xy 142.168487 -407.085697)
			(xy 142.153133 -407.137991) (xy 142.130494 -407.187568) (xy 142.10103 -407.233418) (xy 142.065342 -407.274609)
			(xy 142.024155 -407.310303) (xy 141.978308 -407.339772) (xy 141.928734 -407.362417) (xy 141.876442 -407.377777)
			(xy 141.822497 -407.385539) (xy 141.795246 -407.386028) (xy 140.931646 -407.386028) (xy 140.904392 -407.385528)
			(xy 140.850439 -407.377777) (xy 140.798139 -407.362425) (xy 140.748555 -407.339787) (xy 140.702699 -407.310321)
			(xy 140.661503 -407.27463) (xy 140.625806 -407.233438) (xy 140.596335 -407.187585) (xy 140.573691 -407.138004)
			(xy 140.558333 -407.085706) (xy 140.550575 -407.031754) (xy 139.113042 -407.031754) (xy 139.105285 -407.085702)
			(xy 139.08993 -407.137999) (xy 139.067288 -407.187579) (xy 139.037821 -407.233431) (xy 139.002128 -407.274624)
			(xy 138.960936 -407.310317) (xy 138.915084 -407.339785) (xy 138.865505 -407.362428) (xy 138.813208 -407.377784)
			(xy 138.759258 -407.385542) (xy 138.732006 -407.386028) (xy 137.868406 -407.386028) (xy 137.841154 -407.385525)
			(xy 137.787206 -407.377769) (xy 137.73491 -407.362415) (xy 137.685331 -407.339774) (xy 137.63948 -407.310307)
			(xy 137.598289 -407.274616) (xy 137.562596 -407.233425) (xy 137.533129 -407.187574) (xy 137.510488 -407.137996)
			(xy 137.495132 -407.0857) (xy 137.487375 -407.031752) (xy 136.049865 -407.031752) (xy 136.049865 -407.031756)
			(xy 136.042107 -407.085713) (xy 136.026748 -407.138016) (xy 136.004102 -407.187601) (xy 135.974629 -407.233458)
			(xy 135.93893 -407.274654) (xy 135.897731 -407.31035) (xy 135.851871 -407.339818) (xy 135.802284 -407.36246)
			(xy 135.749979 -407.377814) (xy 135.696022 -407.385567) (xy 135.668766 -407.386028) (xy 134.805166 -407.386028)
			(xy 134.777918 -407.385499) (xy 134.723977 -407.377739) (xy 134.671689 -407.362382) (xy 134.622118 -407.33974)
			(xy 134.576275 -407.310275) (xy 134.535091 -407.274585) (xy 134.499405 -407.233398) (xy 134.469943 -407.187552)
			(xy 134.447306 -407.137979) (xy 134.431953 -407.08569) (xy 134.424198 -407.031748) (xy 132.986542 -407.031748)
			(xy 132.986542 -407.031751) (xy 132.978786 -407.0857) (xy 132.963431 -407.137995) (xy 132.940791 -407.187573)
			(xy 132.911326 -407.233425) (xy 132.875635 -407.274617) (xy 132.834446 -407.31031) (xy 132.788596 -407.339778)
			(xy 132.73902 -407.362422) (xy 132.686725 -407.37778) (xy 132.632777 -407.38554) (xy 132.605526 -407.386028)
			(xy 131.741926 -407.386028) (xy 131.714673 -407.385526) (xy 131.660722 -407.377773) (xy 131.608424 -407.36242)
			(xy 131.558843 -407.33978) (xy 131.512989 -407.310314) (xy 131.471796 -407.274623) (xy 131.436101 -407.233431)
			(xy 131.406632 -407.187579) (xy 131.383989 -407.138) (xy 131.368633 -407.085703) (xy 131.360875 -407.031753)
			(xy 129.923365 -407.031753) (xy 129.923365 -407.031755) (xy 129.915607 -407.08571) (xy 129.90025 -407.138012)
			(xy 129.877605 -407.187595) (xy 129.848134 -407.233452) (xy 129.812437 -407.274647) (xy 129.771241 -407.310343)
			(xy 129.725383 -407.339812) (xy 129.675799 -407.362455) (xy 129.623496 -407.37781) (xy 129.569541 -407.385566)
			(xy 129.542286 -407.386028) (xy 128.678686 -407.386028) (xy 128.651437 -407.385501) (xy 128.597494 -407.377743)
			(xy 128.545203 -407.362388) (xy 128.49563 -407.339747) (xy 128.449784 -407.310282) (xy 128.408598 -407.274592)
			(xy 128.37291 -407.233404) (xy 128.343446 -407.187557) (xy 128.320808 -407.137984) (xy 128.305454 -407.085693)
			(xy 128.297698 -407.031749) (xy 126.860042 -407.031749) (xy 126.860042 -407.031751) (xy 126.852287 -407.085697)
			(xy 126.836933 -407.137991) (xy 126.814294 -407.187568) (xy 126.78483 -407.233418) (xy 126.749142 -407.274609)
			(xy 126.707955 -407.310303) (xy 126.662108 -407.339772) (xy 126.612534 -407.362417) (xy 126.560242 -407.377777)
			(xy 126.506297 -407.385539) (xy 126.479046 -407.386028) (xy 125.615446 -407.386028) (xy 125.588192 -407.385528)
			(xy 125.534239 -407.377777) (xy 125.481939 -407.362425) (xy 125.432355 -407.339787) (xy 125.386499 -407.310321)
			(xy 125.345303 -407.27463) (xy 125.309606 -407.233438) (xy 125.280135 -407.187585) (xy 125.257491 -407.138004)
			(xy 125.242133 -407.085706) (xy 125.234375 -407.031754) (xy 123.796842 -407.031754) (xy 123.789085 -407.085702)
			(xy 123.77373 -407.137999) (xy 123.751088 -407.187579) (xy 123.721621 -407.233431) (xy 123.685928 -407.274624)
			(xy 123.644736 -407.310317) (xy 123.598884 -407.339785) (xy 123.549305 -407.362428) (xy 123.497008 -407.377784)
			(xy 123.443058 -407.385542) (xy 123.415806 -407.386028) (xy 122.552206 -407.386028) (xy 122.524954 -407.385525)
			(xy 122.471006 -407.377769) (xy 122.41871 -407.362415) (xy 122.369131 -407.339774) (xy 122.32328 -407.310307)
			(xy 122.282089 -407.274616) (xy 122.246396 -407.233425) (xy 122.216929 -407.187574) (xy 122.194288 -407.137996)
			(xy 122.178932 -407.0857) (xy 122.171175 -407.031752) (xy 120.733665 -407.031752) (xy 120.733665 -407.031756)
			(xy 120.725907 -407.085713) (xy 120.710548 -407.138016) (xy 120.687902 -407.187601) (xy 120.658429 -407.233458)
			(xy 120.62273 -407.274654) (xy 120.581531 -407.31035) (xy 120.535671 -407.339818) (xy 120.486084 -407.36246)
			(xy 120.433779 -407.377814) (xy 120.379822 -407.385567) (xy 120.352566 -407.386028) (xy 119.488966 -407.386028)
			(xy 119.461718 -407.385499) (xy 119.407777 -407.377739) (xy 119.355489 -407.362382) (xy 119.305918 -407.33974)
			(xy 119.260075 -407.310275) (xy 119.218891 -407.274585) (xy 119.183205 -407.233398) (xy 119.153743 -407.187552)
			(xy 119.131106 -407.137979) (xy 119.115753 -407.08569) (xy 119.107998 -407.031748) (xy 117.670342 -407.031748)
			(xy 117.670342 -407.031751) (xy 117.662586 -407.0857) (xy 117.647231 -407.137995) (xy 117.624591 -407.187573)
			(xy 117.595126 -407.233425) (xy 117.559435 -407.274617) (xy 117.518246 -407.31031) (xy 117.472396 -407.339778)
			(xy 117.42282 -407.362422) (xy 117.370525 -407.37778) (xy 117.316577 -407.38554) (xy 117.289326 -407.386028)
			(xy 116.425726 -407.386028) (xy 116.398473 -407.385526) (xy 116.344522 -407.377773) (xy 116.292224 -407.36242)
			(xy 116.242643 -407.33978) (xy 116.196789 -407.310314) (xy 116.155596 -407.274623) (xy 116.119901 -407.233431)
			(xy 116.090432 -407.187579) (xy 116.067789 -407.138) (xy 116.052433 -407.085703) (xy 116.044675 -407.031753)
			(xy 96.519065 -407.031753) (xy 96.519065 -407.031755) (xy 96.511307 -407.08571) (xy 96.49595 -407.138012)
			(xy 96.473305 -407.187596) (xy 96.443834 -407.233452) (xy 96.408136 -407.274648) (xy 96.36694 -407.310343)
			(xy 96.321082 -407.339812) (xy 96.271497 -407.362455) (xy 96.219195 -407.377811) (xy 96.165239 -407.385566)
			(xy 96.137984 -407.386028) (xy 95.274384 -407.386028) (xy 95.247135 -407.385501) (xy 95.193192 -407.377743)
			(xy 95.140902 -407.362387) (xy 95.091329 -407.339746) (xy 95.045483 -407.310281) (xy 95.004297 -407.274591)
			(xy 94.968609 -407.233404) (xy 94.939146 -407.187557) (xy 94.916507 -407.137983) (xy 94.901154 -407.085692)
			(xy 94.893398 -407.031749) (xy 93.455742 -407.031749) (xy 93.455742 -407.031751) (xy 93.447987 -407.085697)
			(xy 93.432633 -407.137991) (xy 93.409994 -407.187568) (xy 93.38053 -407.233419) (xy 93.344841 -407.27461)
			(xy 93.303654 -407.310304) (xy 93.257807 -407.339773) (xy 93.208233 -407.362417) (xy 93.15594 -407.377777)
			(xy 93.101995 -407.385539) (xy 93.074744 -407.386028) (xy 92.211144 -407.386028) (xy 92.183891 -407.385528)
			(xy 92.129938 -407.377776) (xy 92.077637 -407.362425) (xy 92.028054 -407.339786) (xy 91.982198 -407.310321)
			(xy 91.941002 -407.274629) (xy 91.905306 -407.233437) (xy 91.875835 -407.187584) (xy 91.853191 -407.138004)
			(xy 91.837833 -407.085705) (xy 91.830075 -407.031753) (xy 90.392542 -407.031753) (xy 90.384785 -407.085703)
			(xy 90.36943 -407.138) (xy 90.346788 -407.187579) (xy 90.31732 -407.233432) (xy 90.281627 -407.274624)
			(xy 90.240435 -407.310318) (xy 90.194583 -407.339786) (xy 90.145004 -407.362428) (xy 90.092707 -407.377785)
			(xy 90.038756 -407.385542) (xy 90.011504 -407.386028) (xy 89.147904 -407.386028) (xy 89.120652 -407.385525)
			(xy 89.066704 -407.377769) (xy 89.014408 -407.362414) (xy 88.96483 -407.339773) (xy 88.918979 -407.310307)
			(xy 88.877788 -407.274615) (xy 88.842096 -407.233424) (xy 88.812629 -407.187573) (xy 88.789987 -407.137995)
			(xy 88.774632 -407.0857) (xy 88.766875 -407.031752) (xy 87.329365 -407.031752) (xy 87.329365 -407.031756)
			(xy 87.321607 -407.085713) (xy 87.306248 -407.138016) (xy 87.283602 -407.187602) (xy 87.254129 -407.233459)
			(xy 87.218429 -407.274655) (xy 87.17723 -407.31035) (xy 87.13137 -407.339819) (xy 87.081783 -407.362461)
			(xy 87.029478 -407.377814) (xy 86.97552 -407.385568) (xy 86.948264 -407.386028) (xy 86.084664 -407.386028)
			(xy 86.057416 -407.385499) (xy 86.003475 -407.377739) (xy 85.951187 -407.362382) (xy 85.901617 -407.33974)
			(xy 85.855774 -407.310274) (xy 85.81459 -407.274584) (xy 85.778904 -407.233397) (xy 85.749443 -407.187551)
			(xy 85.726806 -407.137979) (xy 85.711453 -407.08569) (xy 85.703698 -407.031748) (xy 84.266042 -407.031748)
			(xy 84.266042 -407.031752) (xy 84.258286 -407.0857) (xy 84.242931 -407.137996) (xy 84.220291 -407.187574)
			(xy 84.190825 -407.233425) (xy 84.155134 -407.274617) (xy 84.113945 -407.310311) (xy 84.068095 -407.339779)
			(xy 84.018518 -407.362423) (xy 83.966224 -407.377781) (xy 83.912276 -407.385541) (xy 83.885024 -407.386028)
			(xy 83.021424 -407.386028) (xy 82.994171 -407.385526) (xy 82.940221 -407.377773) (xy 82.887923 -407.362419)
			(xy 82.838342 -407.339779) (xy 82.792488 -407.310314) (xy 82.751295 -407.274622) (xy 82.715601 -407.233431)
			(xy 82.686132 -407.187579) (xy 82.663489 -407.138) (xy 82.648133 -407.085703) (xy 82.640375 -407.031753)
			(xy 81.202865 -407.031753) (xy 81.202865 -407.031755) (xy 81.195107 -407.08571) (xy 81.17975 -407.138012)
			(xy 81.157105 -407.187596) (xy 81.127634 -407.233452) (xy 81.091936 -407.274648) (xy 81.05074 -407.310343)
			(xy 81.004882 -407.339812) (xy 80.955297 -407.362455) (xy 80.902995 -407.377811) (xy 80.849039 -407.385566)
			(xy 80.821784 -407.386028) (xy 79.958184 -407.386028) (xy 79.930935 -407.385501) (xy 79.876992 -407.377743)
			(xy 79.824702 -407.362387) (xy 79.775129 -407.339746) (xy 79.729283 -407.310281) (xy 79.688097 -407.274591)
			(xy 79.652409 -407.233404) (xy 79.622946 -407.187557) (xy 79.600307 -407.137983) (xy 79.584954 -407.085692)
			(xy 79.577198 -407.031749) (xy 78.139542 -407.031749) (xy 78.139542 -407.031751) (xy 78.131787 -407.085697)
			(xy 78.116433 -407.137991) (xy 78.093794 -407.187568) (xy 78.06433 -407.233419) (xy 78.028641 -407.27461)
			(xy 77.987454 -407.310304) (xy 77.941607 -407.339773) (xy 77.892033 -407.362417) (xy 77.83974 -407.377777)
			(xy 77.785795 -407.385539) (xy 77.758544 -407.386028) (xy 76.894944 -407.386028) (xy 76.867691 -407.385528)
			(xy 76.813738 -407.377776) (xy 76.761437 -407.362425) (xy 76.711854 -407.339786) (xy 76.665998 -407.310321)
			(xy 76.624802 -407.274629) (xy 76.589106 -407.233437) (xy 76.559635 -407.187584) (xy 76.536991 -407.138004)
			(xy 76.521633 -407.085705) (xy 76.513875 -407.031753) (xy 75.076342 -407.031753) (xy 75.068585 -407.085703)
			(xy 75.05323 -407.138) (xy 75.030588 -407.187579) (xy 75.00112 -407.233432) (xy 74.965427 -407.274624)
			(xy 74.924235 -407.310318) (xy 74.878383 -407.339786) (xy 74.828804 -407.362428) (xy 74.776507 -407.377785)
			(xy 74.722556 -407.385542) (xy 74.695304 -407.386028) (xy 73.831704 -407.386028) (xy 73.804452 -407.385525)
			(xy 73.750504 -407.377769) (xy 73.698208 -407.362414) (xy 73.64863 -407.339773) (xy 73.602779 -407.310307)
			(xy 73.561588 -407.274615) (xy 73.525896 -407.233424) (xy 73.496429 -407.187573) (xy 73.473787 -407.137995)
			(xy 73.458432 -407.0857) (xy 73.450675 -407.031752) (xy 72.013165 -407.031752) (xy 72.013165 -407.031756)
			(xy 72.005407 -407.085713) (xy 71.990048 -407.138016) (xy 71.967402 -407.187602) (xy 71.937929 -407.233459)
			(xy 71.902229 -407.274655) (xy 71.86103 -407.31035) (xy 71.81517 -407.339819) (xy 71.765583 -407.362461)
			(xy 71.713278 -407.377814) (xy 71.65932 -407.385568) (xy 71.632064 -407.386028) (xy 70.768464 -407.386028)
			(xy 70.741216 -407.385499) (xy 70.687275 -407.377739) (xy 70.634987 -407.362382) (xy 70.585417 -407.33974)
			(xy 70.539574 -407.310274) (xy 70.49839 -407.274584) (xy 70.462704 -407.233397) (xy 70.433243 -407.187551)
			(xy 70.410606 -407.137979) (xy 70.395253 -407.08569) (xy 70.387498 -407.031748) (xy 68.949842 -407.031748)
			(xy 68.949842 -407.031752) (xy 68.942086 -407.0857) (xy 68.926731 -407.137996) (xy 68.904091 -407.187574)
			(xy 68.874625 -407.233425) (xy 68.838934 -407.274617) (xy 68.797745 -407.310311) (xy 68.751895 -407.339779)
			(xy 68.702318 -407.362423) (xy 68.650024 -407.377781) (xy 68.596076 -407.385541) (xy 68.568824 -407.386028)
			(xy 67.705224 -407.386028) (xy 67.677971 -407.385526) (xy 67.624021 -407.377773) (xy 67.571723 -407.362419)
			(xy 67.522142 -407.339779) (xy 67.476288 -407.310314) (xy 67.435095 -407.274622) (xy 67.399401 -407.233431)
			(xy 67.369932 -407.187579) (xy 67.347289 -407.138) (xy 67.331933 -407.085703) (xy 67.324175 -407.031753)
			(xy 65.886665 -407.031753) (xy 65.886665 -407.031755) (xy 65.878907 -407.08571) (xy 65.86355 -407.138012)
			(xy 65.840905 -407.187596) (xy 65.811434 -407.233452) (xy 65.775736 -407.274648) (xy 65.73454 -407.310343)
			(xy 65.688682 -407.339812) (xy 65.639097 -407.362455) (xy 65.586795 -407.377811) (xy 65.532839 -407.385566)
			(xy 65.505584 -407.386028) (xy 64.641984 -407.386028) (xy 64.614735 -407.385501) (xy 64.560792 -407.377743)
			(xy 64.508502 -407.362387) (xy 64.458929 -407.339746) (xy 64.413083 -407.310281) (xy 64.371897 -407.274591)
			(xy 64.336209 -407.233404) (xy 64.306746 -407.187557) (xy 64.284107 -407.137983) (xy 64.268754 -407.085692)
			(xy 64.260998 -407.031749) (xy 62.823342 -407.031749) (xy 62.823342 -407.031751) (xy 62.815587 -407.085697)
			(xy 62.800233 -407.137991) (xy 62.777594 -407.187568) (xy 62.74813 -407.233419) (xy 62.712441 -407.27461)
			(xy 62.671254 -407.310304) (xy 62.625407 -407.339773) (xy 62.575833 -407.362417) (xy 62.52354 -407.377777)
			(xy 62.469595 -407.385539) (xy 62.442344 -407.386028) (xy 61.578744 -407.386028) (xy 61.551491 -407.385528)
			(xy 61.497538 -407.377776) (xy 61.445237 -407.362425) (xy 61.395654 -407.339786) (xy 61.349798 -407.310321)
			(xy 61.308602 -407.274629) (xy 61.272906 -407.233437) (xy 61.243435 -407.187584) (xy 61.220791 -407.138004)
			(xy 61.205433 -407.085705) (xy 61.197675 -407.031753) (xy 59.760142 -407.031753) (xy 59.752385 -407.085703)
			(xy 59.73703 -407.138) (xy 59.714388 -407.187579) (xy 59.68492 -407.233432) (xy 59.649227 -407.274624)
			(xy 59.608035 -407.310318) (xy 59.562183 -407.339786) (xy 59.512604 -407.362428) (xy 59.460307 -407.377785)
			(xy 59.406356 -407.385542) (xy 59.379104 -407.386028) (xy 58.515504 -407.386028) (xy 58.488252 -407.385525)
			(xy 58.434304 -407.377769) (xy 58.382008 -407.362414) (xy 58.33243 -407.339773) (xy 58.286579 -407.310307)
			(xy 58.245388 -407.274615) (xy 58.209696 -407.233424) (xy 58.180229 -407.187573) (xy 58.157587 -407.137995)
			(xy 58.142232 -407.0857) (xy 58.134475 -407.031752) (xy 56.696965 -407.031752) (xy 56.696965 -407.031756)
			(xy 56.689207 -407.085713) (xy 56.673848 -407.138016) (xy 56.651202 -407.187602) (xy 56.621729 -407.233459)
			(xy 56.586029 -407.274655) (xy 56.54483 -407.31035) (xy 56.49897 -407.339819) (xy 56.449383 -407.362461)
			(xy 56.397078 -407.377814) (xy 56.34312 -407.385568) (xy 56.315864 -407.386028) (xy 55.452264 -407.386028)
			(xy 55.425016 -407.385499) (xy 55.371075 -407.377739) (xy 55.318787 -407.362382) (xy 55.269217 -407.33974)
			(xy 55.223374 -407.310274) (xy 55.18219 -407.274584) (xy 55.146504 -407.233397) (xy 55.117043 -407.187551)
			(xy 55.094406 -407.137979) (xy 55.079053 -407.08569) (xy 55.071298 -407.031748) (xy 53.633642 -407.031748)
			(xy 53.633642 -407.031752) (xy 53.625886 -407.0857) (xy 53.610531 -407.137996) (xy 53.587891 -407.187574)
			(xy 53.558425 -407.233425) (xy 53.522734 -407.274617) (xy 53.481545 -407.310311) (xy 53.435695 -407.339779)
			(xy 53.386118 -407.362423) (xy 53.333824 -407.377781) (xy 53.279876 -407.385541) (xy 53.252624 -407.386028)
			(xy 52.389024 -407.386028) (xy 52.361771 -407.385526) (xy 52.307821 -407.377773) (xy 52.255523 -407.362419)
			(xy 52.205942 -407.339779) (xy 52.160088 -407.310314) (xy 52.118895 -407.274622) (xy 52.083201 -407.233431)
			(xy 52.053732 -407.187579) (xy 52.031089 -407.138) (xy 52.015733 -407.085703) (xy 52.007975 -407.031753)
			(xy 50.570465 -407.031753) (xy 50.570465 -407.031755) (xy 50.562707 -407.08571) (xy 50.54735 -407.138012)
			(xy 50.524705 -407.187596) (xy 50.495234 -407.233452) (xy 50.459536 -407.274648) (xy 50.41834 -407.310343)
			(xy 50.372482 -407.339812) (xy 50.322897 -407.362455) (xy 50.270595 -407.377811) (xy 50.216639 -407.385566)
			(xy 50.189384 -407.386028) (xy 49.325784 -407.386028) (xy 49.298535 -407.385501) (xy 49.244592 -407.377743)
			(xy 49.192302 -407.362387) (xy 49.142729 -407.339746) (xy 49.096883 -407.310281) (xy 49.055697 -407.274591)
			(xy 49.020009 -407.233404) (xy 48.990546 -407.187557) (xy 48.967907 -407.137983) (xy 48.952554 -407.085692)
			(xy 48.944798 -407.031749) (xy 44.883756 -407.031749) (xy 44.868945 -407.05439) (xy 44.764794 -407.199093)
			(xy 44.654301 -407.339013) (xy 44.537684 -407.473872) (xy 44.415175 -407.603402) (xy 44.287018 -407.727346)
			(xy 44.153467 -407.845458) (xy 44.014787 -407.957503) (xy 43.871253 -408.06326) (xy 43.72315 -408.162517)
			(xy 43.570773 -408.255079) (xy 43.414424 -408.34076) (xy 43.254413 -408.419392) (xy 43.091059 -408.490818)
			(xy 42.924684 -408.554896) (xy 42.755621 -408.611498) (xy 42.584204 -408.660514) (xy 42.410773 -408.701844)
			(xy 42.235673 -408.735408) (xy 42.059253 -408.761138) (xy 41.881861 -408.778984) (xy 41.70385 -408.78891)
			(xy 41.525573 -408.790896) (xy 41.347386 -408.784939) (xy 41.16964 -408.771049) (xy 40.99269 -408.749256)
			(xy 40.816886 -408.719602) (xy 40.642578 -408.682145) (xy 40.470111 -408.636961) (xy 40.299828 -408.584139)
			(xy 40.132067 -408.523783) (xy 39.967162 -408.456015) (xy 39.805439 -408.380967) (xy 39.64722 -408.29879)
			(xy 39.492819 -408.209647) (xy 39.342542 -408.113713) (xy 39.196687 -408.011181) (xy 39.055545 -407.902253)
			(xy 38.919396 -407.787146) (xy 38.788509 -407.666088) (xy 38.663145 -407.539319) (xy 38.543552 -407.407092)
			(xy 38.429969 -407.269669) (xy 38.32262 -407.127322) (xy 38.221719 -406.980334) (xy 38.127466 -406.828998)
			(xy 38.040048 -406.673613) (xy 37.959638 -406.514488) (xy 37.886397 -406.351939) (xy 37.82047 -406.186289)
			(xy 37.761987 -406.017867) (xy 37.711065 -405.847006) (xy 37.667805 -405.674047) (xy 37.632293 -405.499332)
			(xy 37.604599 -405.323208) (xy 37.584778 -405.146026) (xy 37.57287 -404.968137) (xy 37.568898 -404.789894)
			(xy 3.30962 -404.789894) (xy 6.274054 -407.754328) (xy 6.323479 -407.804444) (xy 6.417291 -407.909404)
			(xy 6.50507 -408.019459) (xy 6.58654 -408.134261) (xy 6.661445 -408.253452) (xy 6.72955 -408.376654)
			(xy 6.79064 -408.503481) (xy 6.844523 -408.633534) (xy 6.891029 -408.766403) (xy 6.930013 -408.901671)
			(xy 6.961351 -409.038912) (xy 6.984945 -409.177694) (xy 7.00072 -409.31758) (xy 7.008628 -409.458131)
			(xy 7.00913 -409.528518) (xy 7.00913 -409.563824) (xy 102.192836 -409.563824) (xy 102.192836 -408.700224)
			(xy 102.193322 -408.672955) (xy 102.201084 -408.618971) (xy 102.216449 -408.566641) (xy 102.239106 -408.517031)
			(xy 102.268592 -408.47115) (xy 102.304307 -408.429933) (xy 102.345524 -408.394218) (xy 102.391405 -408.364732)
			(xy 102.441015 -408.342075) (xy 102.493345 -408.32671) (xy 102.547329 -408.318948) (xy 102.601867 -408.318948)
			(xy 102.655851 -408.32671) (xy 102.708181 -408.342075) (xy 102.757791 -408.364732) (xy 102.803672 -408.394218)
			(xy 102.844889 -408.429933) (xy 102.880604 -408.47115) (xy 102.91009 -408.517031) (xy 102.932747 -408.566641)
			(xy 102.948112 -408.618971) (xy 102.955874 -408.672955) (xy 102.95636 -408.700224) (xy 102.95636 -409.563824)
			(xy 102.955874 -409.591093) (xy 102.948112 -409.645077) (xy 102.932747 -409.697407) (xy 102.91009 -409.747017)
			(xy 102.880604 -409.792898) (xy 102.844889 -409.834115) (xy 102.803672 -409.86983) (xy 102.757791 -409.899316)
			(xy 102.748244 -409.903676) (xy 110.559596 -409.903676) (xy 110.559596 -409.040076) (xy 110.560082 -409.012825)
			(xy 110.567838 -408.958877) (xy 110.583193 -408.906582) (xy 110.605835 -408.857005) (xy 110.635301 -408.811155)
			(xy 110.670992 -408.769964) (xy 110.712183 -408.734273) (xy 110.758033 -408.704807) (xy 110.80761 -408.682165)
			(xy 110.859905 -408.66681) (xy 110.913853 -408.659054) (xy 110.968355 -408.659054) (xy 111.022303 -408.66681)
			(xy 111.074598 -408.682165) (xy 111.124175 -408.704807) (xy 111.170025 -408.734273) (xy 111.211216 -408.769964)
			(xy 111.246907 -408.811155) (xy 111.276373 -408.857005) (xy 111.299015 -408.906582) (xy 111.31437 -408.958877)
			(xy 111.322126 -409.012825) (xy 111.322612 -409.040076) (xy 111.322612 -409.903676) (xy 111.322126 -409.930927)
			(xy 111.31437 -409.984875) (xy 111.299015 -410.03717) (xy 111.28975 -410.057456) (xy 116.044623 -410.057456)
			(xy 116.044623 -410.002944) (xy 116.052381 -409.948986) (xy 116.06774 -409.896681) (xy 116.090386 -409.847095)
			(xy 116.119859 -409.801237) (xy 116.155559 -409.76004) (xy 116.196758 -409.724344) (xy 116.242618 -409.694874)
			(xy 116.292206 -409.672231) (xy 116.344511 -409.656876) (xy 116.39847 -409.649121) (xy 116.425726 -409.64866)
			(xy 117.289326 -409.64866) (xy 117.316574 -409.649212) (xy 117.370514 -409.656971) (xy 117.422801 -409.672327)
			(xy 117.472371 -409.694968) (xy 117.518214 -409.724432) (xy 117.559398 -409.760121) (xy 117.595084 -409.801307)
			(xy 117.624545 -409.847152) (xy 117.647182 -409.896723) (xy 117.662535 -409.949011) (xy 117.67029 -410.002952)
			(xy 117.67029 -410.057448) (xy 117.670289 -410.057452) (xy 119.107946 -410.057452) (xy 119.107946 -410.002948)
			(xy 119.115702 -409.948999) (xy 119.131057 -409.896702) (xy 119.153697 -409.847123) (xy 119.183163 -409.801271)
			(xy 119.218854 -409.760078) (xy 119.260043 -409.724383) (xy 119.305893 -409.694914) (xy 119.35547 -409.672269)
			(xy 119.407765 -409.656909) (xy 119.461714 -409.649148) (xy 119.488966 -409.64866) (xy 120.352566 -409.64866)
			(xy 120.379818 -409.649185) (xy 120.433768 -409.656937) (xy 120.486066 -409.672289) (xy 120.535646 -409.694928)
			(xy 120.5815 -409.724392) (xy 120.622693 -409.760083) (xy 120.658387 -409.801273) (xy 120.687856 -409.847124)
			(xy 120.710499 -409.896702) (xy 120.725855 -409.948999) (xy 120.733613 -410.002948) (xy 120.733613 -410.057452)
			(xy 120.733613 -410.057455) (xy 122.171123 -410.057455) (xy 122.171123 -410.002945) (xy 122.178881 -409.948989)
			(xy 122.194238 -409.896686) (xy 122.216883 -409.847101) (xy 122.246354 -409.801244) (xy 122.282052 -409.760047)
			(xy 122.323249 -409.724351) (xy 122.369106 -409.69488) (xy 122.418691 -409.672236) (xy 122.470994 -409.656879)
			(xy 122.524951 -409.649123) (xy 122.552206 -409.64866) (xy 123.415806 -409.64866) (xy 123.443055 -409.649211)
			(xy 123.496997 -409.656967) (xy 123.549287 -409.672321) (xy 123.598859 -409.694961) (xy 123.644705 -409.724425)
			(xy 123.685891 -409.760113) (xy 123.721579 -409.8013) (xy 123.751042 -409.847146) (xy 123.773681 -409.896719)
			(xy 123.789034 -409.949009) (xy 123.79679 -410.002951) (xy 123.79679 -410.057449) (xy 123.796789 -410.057457)
			(xy 125.234323 -410.057457) (xy 125.234323 -410.002943) (xy 125.242082 -409.948983) (xy 125.257442 -409.896677)
			(xy 125.280089 -409.84709) (xy 125.309564 -409.801231) (xy 125.345266 -409.760033) (xy 125.386467 -409.724337)
			(xy 125.43233 -409.694867) (xy 125.48192 -409.672225) (xy 125.534228 -409.656872) (xy 125.588189 -409.64912)
			(xy 125.615446 -409.64866) (xy 126.479046 -409.64866) (xy 126.506293 -409.649213) (xy 126.560231 -409.656975)
			(xy 126.612516 -409.672332) (xy 126.662083 -409.694974) (xy 126.707924 -409.724439) (xy 126.749105 -409.760128)
			(xy 126.784788 -409.801313) (xy 126.814248 -409.847157) (xy 126.836884 -409.896727) (xy 126.852235 -409.949014)
			(xy 126.85999 -410.002953) (xy 126.85999 -410.057447) (xy 126.859989 -410.057453) (xy 128.297646 -410.057453)
			(xy 128.297646 -410.002947) (xy 128.305403 -409.948996) (xy 128.320758 -409.896698) (xy 128.3434 -409.847118)
			(xy 128.372868 -409.801264) (xy 128.408561 -409.760071) (xy 128.449753 -409.724376) (xy 128.495605 -409.694907)
			(xy 128.545185 -409.672263) (xy 128.597482 -409.656906) (xy 128.651433 -409.649147) (xy 128.678686 -409.64866)
			(xy 129.542286 -409.64866) (xy 129.569537 -409.649186) (xy 129.623485 -409.656941) (xy 129.67578 -409.672295)
			(xy 129.725358 -409.694934) (xy 129.771209 -409.724399) (xy 129.8124 -409.76009) (xy 129.848092 -409.80128)
			(xy 129.877559 -409.84713) (xy 129.900201 -409.896707) (xy 129.915556 -409.949001) (xy 129.923313 -410.002949)
			(xy 129.923313 -410.057451) (xy 129.923312 -410.057456) (xy 131.360823 -410.057456) (xy 131.360823 -410.002944)
			(xy 131.368581 -409.948986) (xy 131.38394 -409.896681) (xy 131.406586 -409.847095) (xy 131.436059 -409.801237)
			(xy 131.471759 -409.76004) (xy 131.512958 -409.724344) (xy 131.558818 -409.694874) (xy 131.608406 -409.672231)
			(xy 131.660711 -409.656876) (xy 131.71467 -409.649121) (xy 131.741926 -409.64866) (xy 132.605526 -409.64866)
			(xy 132.632774 -409.649212) (xy 132.686714 -409.656971) (xy 132.739001 -409.672327) (xy 132.788571 -409.694968)
			(xy 132.834414 -409.724432) (xy 132.875598 -409.760121) (xy 132.911284 -409.801307) (xy 132.940745 -409.847152)
			(xy 132.963382 -409.896723) (xy 132.978735 -409.949011) (xy 132.98649 -410.002952) (xy 132.98649 -410.057448)
			(xy 132.986489 -410.057452) (xy 134.424146 -410.057452) (xy 134.424146 -410.002948) (xy 134.431902 -409.948999)
			(xy 134.447257 -409.896702) (xy 134.469897 -409.847123) (xy 134.499363 -409.801271) (xy 134.535054 -409.760078)
			(xy 134.576243 -409.724383) (xy 134.622093 -409.694914) (xy 134.67167 -409.672269) (xy 134.723965 -409.656909)
			(xy 134.777914 -409.649148) (xy 134.805166 -409.64866) (xy 135.668766 -409.64866) (xy 135.696018 -409.649185)
			(xy 135.749968 -409.656937) (xy 135.802266 -409.672289) (xy 135.851846 -409.694928) (xy 135.8977 -409.724392)
			(xy 135.938893 -409.760083) (xy 135.974587 -409.801273) (xy 136.004056 -409.847124) (xy 136.026699 -409.896702)
			(xy 136.042055 -409.948999) (xy 136.049813 -410.002948) (xy 136.049813 -410.057452) (xy 136.049813 -410.057455)
			(xy 137.487323 -410.057455) (xy 137.487323 -410.002945) (xy 137.495081 -409.948989) (xy 137.510438 -409.896686)
			(xy 137.533083 -409.847101) (xy 137.562554 -409.801244) (xy 137.598252 -409.760047) (xy 137.639449 -409.724351)
			(xy 137.685306 -409.69488) (xy 137.734891 -409.672236) (xy 137.787194 -409.656879) (xy 137.841151 -409.649123)
			(xy 137.868406 -409.64866) (xy 138.732006 -409.64866) (xy 138.759255 -409.649211) (xy 138.813197 -409.656967)
			(xy 138.865487 -409.672321) (xy 138.915059 -409.694961) (xy 138.960905 -409.724425) (xy 139.002091 -409.760113)
			(xy 139.037779 -409.8013) (xy 139.067242 -409.847146) (xy 139.089881 -409.896719) (xy 139.105234 -409.949009)
			(xy 139.11299 -410.002951) (xy 139.11299 -410.057449) (xy 139.112989 -410.057457) (xy 140.550523 -410.057457)
			(xy 140.550523 -410.002943) (xy 140.558282 -409.948983) (xy 140.573642 -409.896677) (xy 140.596289 -409.84709)
			(xy 140.625764 -409.801231) (xy 140.661466 -409.760033) (xy 140.702667 -409.724337) (xy 140.74853 -409.694867)
			(xy 140.79812 -409.672225) (xy 140.850428 -409.656872) (xy 140.904389 -409.64912) (xy 140.931646 -409.64866)
			(xy 141.795246 -409.64866) (xy 141.822493 -409.649213) (xy 141.876431 -409.656975) (xy 141.928716 -409.672332)
			(xy 141.978283 -409.694974) (xy 142.024124 -409.724439) (xy 142.065305 -409.760128) (xy 142.100988 -409.801313)
			(xy 142.130448 -409.847157) (xy 142.153084 -409.896727) (xy 142.168435 -409.949014) (xy 142.17619 -410.002953)
			(xy 142.17619 -410.057447) (xy 142.176189 -410.057453) (xy 143.613846 -410.057453) (xy 143.613846 -410.002947)
			(xy 143.621603 -409.948996) (xy 143.636958 -409.896698) (xy 143.6596 -409.847118) (xy 143.689068 -409.801264)
			(xy 143.724761 -409.760071) (xy 143.765953 -409.724376) (xy 143.811805 -409.694907) (xy 143.861385 -409.672263)
			(xy 143.913682 -409.656906) (xy 143.967633 -409.649147) (xy 143.994886 -409.64866) (xy 144.858486 -409.64866)
			(xy 144.885737 -409.649186) (xy 144.939685 -409.656941) (xy 144.99198 -409.672295) (xy 145.041558 -409.694934)
			(xy 145.087409 -409.724399) (xy 145.1286 -409.76009) (xy 145.164292 -409.80128) (xy 145.193759 -409.84713)
			(xy 145.216401 -409.896707) (xy 145.231756 -409.949001) (xy 145.239513 -410.002949) (xy 145.239513 -410.057451)
			(xy 145.239512 -410.057456) (xy 146.677023 -410.057456) (xy 146.677023 -410.002944) (xy 146.684781 -409.948986)
			(xy 146.70014 -409.896681) (xy 146.722786 -409.847095) (xy 146.752259 -409.801237) (xy 146.787959 -409.76004)
			(xy 146.829158 -409.724344) (xy 146.875018 -409.694874) (xy 146.924606 -409.672231) (xy 146.976911 -409.656876)
			(xy 147.03087 -409.649121) (xy 147.058126 -409.64866) (xy 147.921726 -409.64866) (xy 147.948974 -409.649212)
			(xy 148.002914 -409.656971) (xy 148.055201 -409.672327) (xy 148.104771 -409.694968) (xy 148.150614 -409.724432)
			(xy 148.191798 -409.760121) (xy 148.227484 -409.801307) (xy 148.256945 -409.847152) (xy 148.279582 -409.896723)
			(xy 148.294935 -409.949011) (xy 148.30269 -410.002952) (xy 148.30269 -410.057448) (xy 148.302689 -410.057452)
			(xy 149.740346 -410.057452) (xy 149.740346 -410.002948) (xy 149.748102 -409.948999) (xy 149.763457 -409.896702)
			(xy 149.786097 -409.847123) (xy 149.815563 -409.801271) (xy 149.851254 -409.760078) (xy 149.892443 -409.724383)
			(xy 149.938293 -409.694914) (xy 149.98787 -409.672269) (xy 150.040165 -409.656909) (xy 150.094114 -409.649148)
			(xy 150.121366 -409.64866) (xy 150.984966 -409.64866) (xy 151.012218 -409.649185) (xy 151.066168 -409.656937)
			(xy 151.118466 -409.672289) (xy 151.168046 -409.694928) (xy 151.2139 -409.724392) (xy 151.255093 -409.760083)
			(xy 151.290787 -409.801273) (xy 151.320256 -409.847124) (xy 151.342899 -409.896702) (xy 151.358255 -409.948999)
			(xy 151.366013 -410.002948) (xy 151.366013 -410.057452) (xy 151.366013 -410.057455) (xy 152.803523 -410.057455)
			(xy 152.803523 -410.002945) (xy 152.811281 -409.948989) (xy 152.826638 -409.896686) (xy 152.849283 -409.847101)
			(xy 152.878754 -409.801244) (xy 152.914452 -409.760047) (xy 152.955649 -409.724351) (xy 153.001506 -409.69488)
			(xy 153.051091 -409.672236) (xy 153.103394 -409.656879) (xy 153.157351 -409.649123) (xy 153.184606 -409.64866)
			(xy 154.048206 -409.64866) (xy 154.075455 -409.649211) (xy 154.129397 -409.656967) (xy 154.181687 -409.672321)
			(xy 154.231259 -409.694961) (xy 154.277105 -409.724425) (xy 154.318291 -409.760113) (xy 154.353979 -409.8013)
			(xy 154.383442 -409.847146) (xy 154.406081 -409.896719) (xy 154.421434 -409.949009) (xy 154.42919 -410.002951)
			(xy 154.42919 -410.057449) (xy 154.429189 -410.057457) (xy 155.866723 -410.057457) (xy 155.866723 -410.002943)
			(xy 155.874482 -409.948983) (xy 155.889842 -409.896677) (xy 155.912489 -409.84709) (xy 155.941964 -409.801231)
			(xy 155.977666 -409.760033) (xy 156.018867 -409.724337) (xy 156.06473 -409.694867) (xy 156.11432 -409.672225)
			(xy 156.166628 -409.656872) (xy 156.220589 -409.64912) (xy 156.247846 -409.64866) (xy 157.111446 -409.64866)
			(xy 157.138693 -409.649213) (xy 157.192631 -409.656975) (xy 157.244916 -409.672332) (xy 157.294483 -409.694974)
			(xy 157.340324 -409.724439) (xy 157.381505 -409.760128) (xy 157.417188 -409.801313) (xy 157.446648 -409.847157)
			(xy 157.469284 -409.896727) (xy 157.484635 -409.949014) (xy 157.49239 -410.002953) (xy 157.49239 -410.057447)
			(xy 157.492389 -410.057453) (xy 158.930046 -410.057453) (xy 158.930046 -410.002947) (xy 158.937803 -409.948996)
			(xy 158.953158 -409.896698) (xy 158.9758 -409.847118) (xy 159.005268 -409.801264) (xy 159.040961 -409.760071)
			(xy 159.082153 -409.724376) (xy 159.128005 -409.694907) (xy 159.177585 -409.672263) (xy 159.229882 -409.656906)
			(xy 159.283833 -409.649147) (xy 159.311086 -409.64866) (xy 160.174686 -409.64866) (xy 160.201937 -409.649186)
			(xy 160.255885 -409.656941) (xy 160.30818 -409.672295) (xy 160.357758 -409.694934) (xy 160.403609 -409.724399)
			(xy 160.4448 -409.76009) (xy 160.480492 -409.80128) (xy 160.509959 -409.84713) (xy 160.532601 -409.896707)
			(xy 160.547956 -409.949001) (xy 160.555713 -410.002949) (xy 160.555713 -410.057451) (xy 160.555712 -410.057456)
			(xy 161.993223 -410.057456) (xy 161.993223 -410.002944) (xy 162.000981 -409.948986) (xy 162.01634 -409.896681)
			(xy 162.038986 -409.847095) (xy 162.068459 -409.801237) (xy 162.104159 -409.76004) (xy 162.145358 -409.724344)
			(xy 162.191218 -409.694874) (xy 162.240806 -409.672231) (xy 162.293111 -409.656876) (xy 162.34707 -409.649121)
			(xy 162.374326 -409.64866) (xy 163.237926 -409.64866) (xy 163.265174 -409.649212) (xy 163.319114 -409.656971)
			(xy 163.371401 -409.672327) (xy 163.420971 -409.694968) (xy 163.466814 -409.724432) (xy 163.507998 -409.760121)
			(xy 163.543684 -409.801307) (xy 163.573145 -409.847152) (xy 163.595782 -409.896723) (xy 163.611135 -409.949011)
			(xy 163.61889 -410.002952) (xy 163.61889 -410.057448) (xy 163.611135 -410.111389) (xy 163.595782 -410.163677)
			(xy 163.573145 -410.213248) (xy 163.543684 -410.259093) (xy 163.507998 -410.300279) (xy 163.466814 -410.335968)
			(xy 163.420971 -410.365432) (xy 163.371401 -410.388073) (xy 163.319114 -410.403429) (xy 163.265174 -410.411188)
			(xy 163.237926 -410.411676) (xy 162.374326 -410.411676) (xy 162.34707 -410.411279) (xy 162.293111 -410.403524)
			(xy 162.240806 -410.388169) (xy 162.191218 -410.365526) (xy 162.145358 -410.336056) (xy 162.104159 -410.30036)
			(xy 162.068459 -410.259163) (xy 162.038986 -410.213305) (xy 162.01634 -410.163719) (xy 162.000981 -410.111414)
			(xy 161.993223 -410.057456) (xy 160.555712 -410.057456) (xy 160.547956 -410.111399) (xy 160.532601 -410.163693)
			(xy 160.509959 -410.21327) (xy 160.480492 -410.25912) (xy 160.4448 -410.30031) (xy 160.403609 -410.336001)
			(xy 160.357758 -410.365466) (xy 160.30818 -410.388105) (xy 160.255885 -410.403459) (xy 160.201937 -410.411214)
			(xy 160.174686 -410.411676) (xy 159.311086 -410.411676) (xy 159.283833 -410.411253) (xy 159.229882 -410.403494)
			(xy 159.177585 -410.388137) (xy 159.128005 -410.365493) (xy 159.082153 -410.336024) (xy 159.040961 -410.300329)
			(xy 159.005268 -410.259136) (xy 158.9758 -410.213282) (xy 158.953158 -410.163702) (xy 158.937803 -410.111404)
			(xy 158.930046 -410.057453) (xy 157.492389 -410.057453) (xy 157.484635 -410.111386) (xy 157.469284 -410.163673)
			(xy 157.446648 -410.213243) (xy 157.417188 -410.259087) (xy 157.381505 -410.300272) (xy 157.340324 -410.335961)
			(xy 157.294483 -410.365426) (xy 157.244916 -410.388068) (xy 157.192631 -410.403425) (xy 157.138693 -410.411187)
			(xy 157.111446 -410.411676) (xy 156.247846 -410.411676) (xy 156.220589 -410.41128) (xy 156.166628 -410.403528)
			(xy 156.11432 -410.388175) (xy 156.06473 -410.365533) (xy 156.018867 -410.336063) (xy 155.977666 -410.300367)
			(xy 155.941964 -410.259169) (xy 155.912489 -410.21331) (xy 155.889842 -410.163723) (xy 155.874482 -410.111417)
			(xy 155.866723 -410.057457) (xy 154.429189 -410.057457) (xy 154.421434 -410.111391) (xy 154.406081 -410.163681)
			(xy 154.383442 -410.213254) (xy 154.353979 -410.2591) (xy 154.318291 -410.300287) (xy 154.277105 -410.335975)
			(xy 154.231259 -410.365439) (xy 154.181687 -410.388079) (xy 154.129397 -410.403433) (xy 154.075455 -410.411189)
			(xy 154.048206 -410.411676) (xy 153.184606 -410.411676) (xy 153.157351 -410.411277) (xy 153.103394 -410.403521)
			(xy 153.051091 -410.388164) (xy 153.001506 -410.36552) (xy 152.955649 -410.336049) (xy 152.914452 -410.300353)
			(xy 152.878754 -410.259156) (xy 152.849283 -410.213299) (xy 152.826638 -410.163714) (xy 152.811281 -410.111411)
			(xy 152.803523 -410.057455) (xy 151.366013 -410.057455) (xy 151.358255 -410.111402) (xy 151.342899 -410.163698)
			(xy 151.320256 -410.213276) (xy 151.290787 -410.259127) (xy 151.255093 -410.300317) (xy 151.2139 -410.336008)
			(xy 151.168046 -410.365472) (xy 151.118466 -410.388111) (xy 151.066168 -410.403463) (xy 151.012218 -410.411215)
			(xy 150.984966 -410.411676) (xy 150.121366 -410.411676) (xy 150.094114 -410.411252) (xy 150.040165 -410.403491)
			(xy 149.98787 -410.388131) (xy 149.938293 -410.365486) (xy 149.892443 -410.336017) (xy 149.851254 -410.300322)
			(xy 149.815563 -410.259129) (xy 149.786097 -410.213277) (xy 149.763457 -410.163698) (xy 149.748102 -410.111401)
			(xy 149.740346 -410.057452) (xy 148.302689 -410.057452) (xy 148.294935 -410.111389) (xy 148.279582 -410.163677)
			(xy 148.256945 -410.213248) (xy 148.227484 -410.259093) (xy 148.191798 -410.300279) (xy 148.150614 -410.335968)
			(xy 148.104771 -410.365432) (xy 148.055201 -410.388073) (xy 148.002914 -410.403429) (xy 147.948974 -410.411188)
			(xy 147.921726 -410.411676) (xy 147.058126 -410.411676) (xy 147.03087 -410.411279) (xy 146.976911 -410.403524)
			(xy 146.924606 -410.388169) (xy 146.875018 -410.365526) (xy 146.829158 -410.336056) (xy 146.787959 -410.30036)
			(xy 146.752259 -410.259163) (xy 146.722786 -410.213305) (xy 146.70014 -410.163719) (xy 146.684781 -410.111414)
			(xy 146.677023 -410.057456) (xy 145.239512 -410.057456) (xy 145.231756 -410.111399) (xy 145.216401 -410.163693)
			(xy 145.193759 -410.21327) (xy 145.164292 -410.25912) (xy 145.1286 -410.30031) (xy 145.087409 -410.336001)
			(xy 145.041558 -410.365466) (xy 144.99198 -410.388105) (xy 144.939685 -410.403459) (xy 144.885737 -410.411214)
			(xy 144.858486 -410.411676) (xy 143.994886 -410.411676) (xy 143.967633 -410.411253) (xy 143.913682 -410.403494)
			(xy 143.861385 -410.388137) (xy 143.811805 -410.365493) (xy 143.765953 -410.336024) (xy 143.724761 -410.300329)
			(xy 143.689068 -410.259136) (xy 143.6596 -410.213282) (xy 143.636958 -410.163702) (xy 143.621603 -410.111404)
			(xy 143.613846 -410.057453) (xy 142.176189 -410.057453) (xy 142.168435 -410.111386) (xy 142.153084 -410.163673)
			(xy 142.130448 -410.213243) (xy 142.100988 -410.259087) (xy 142.065305 -410.300272) (xy 142.024124 -410.335961)
			(xy 141.978283 -410.365426) (xy 141.928716 -410.388068) (xy 141.876431 -410.403425) (xy 141.822493 -410.411187)
			(xy 141.795246 -410.411676) (xy 140.931646 -410.411676) (xy 140.904389 -410.41128) (xy 140.850428 -410.403528)
			(xy 140.79812 -410.388175) (xy 140.74853 -410.365533) (xy 140.702667 -410.336063) (xy 140.661466 -410.300367)
			(xy 140.625764 -410.259169) (xy 140.596289 -410.21331) (xy 140.573642 -410.163723) (xy 140.558282 -410.111417)
			(xy 140.550523 -410.057457) (xy 139.112989 -410.057457) (xy 139.105234 -410.111391) (xy 139.089881 -410.163681)
			(xy 139.067242 -410.213254) (xy 139.037779 -410.2591) (xy 139.002091 -410.300287) (xy 138.960905 -410.335975)
			(xy 138.915059 -410.365439) (xy 138.865487 -410.388079) (xy 138.813197 -410.403433) (xy 138.759255 -410.411189)
			(xy 138.732006 -410.411676) (xy 137.868406 -410.411676) (xy 137.841151 -410.411277) (xy 137.787194 -410.403521)
			(xy 137.734891 -410.388164) (xy 137.685306 -410.36552) (xy 137.639449 -410.336049) (xy 137.598252 -410.300353)
			(xy 137.562554 -410.259156) (xy 137.533083 -410.213299) (xy 137.510438 -410.163714) (xy 137.495081 -410.111411)
			(xy 137.487323 -410.057455) (xy 136.049813 -410.057455) (xy 136.042055 -410.111402) (xy 136.026699 -410.163698)
			(xy 136.004056 -410.213276) (xy 135.974587 -410.259127) (xy 135.938893 -410.300317) (xy 135.8977 -410.336008)
			(xy 135.851846 -410.365472) (xy 135.802266 -410.388111) (xy 135.749968 -410.403463) (xy 135.696018 -410.411215)
			(xy 135.668766 -410.411676) (xy 134.805166 -410.411676) (xy 134.777914 -410.411252) (xy 134.723965 -410.403491)
			(xy 134.67167 -410.388131) (xy 134.622093 -410.365486) (xy 134.576243 -410.336017) (xy 134.535054 -410.300322)
			(xy 134.499363 -410.259129) (xy 134.469897 -410.213277) (xy 134.447257 -410.163698) (xy 134.431902 -410.111401)
			(xy 134.424146 -410.057452) (xy 132.986489 -410.057452) (xy 132.978735 -410.111389) (xy 132.963382 -410.163677)
			(xy 132.940745 -410.213248) (xy 132.911284 -410.259093) (xy 132.875598 -410.300279) (xy 132.834414 -410.335968)
			(xy 132.788571 -410.365432) (xy 132.739001 -410.388073) (xy 132.686714 -410.403429) (xy 132.632774 -410.411188)
			(xy 132.605526 -410.411676) (xy 131.741926 -410.411676) (xy 131.71467 -410.411279) (xy 131.660711 -410.403524)
			(xy 131.608406 -410.388169) (xy 131.558818 -410.365526) (xy 131.512958 -410.336056) (xy 131.471759 -410.30036)
			(xy 131.436059 -410.259163) (xy 131.406586 -410.213305) (xy 131.38394 -410.163719) (xy 131.368581 -410.111414)
			(xy 131.360823 -410.057456) (xy 129.923312 -410.057456) (xy 129.915556 -410.111399) (xy 129.900201 -410.163693)
			(xy 129.877559 -410.21327) (xy 129.848092 -410.25912) (xy 129.8124 -410.30031) (xy 129.771209 -410.336001)
			(xy 129.725358 -410.365466) (xy 129.67578 -410.388105) (xy 129.623485 -410.403459) (xy 129.569537 -410.411214)
			(xy 129.542286 -410.411676) (xy 128.678686 -410.411676) (xy 128.651433 -410.411253) (xy 128.597482 -410.403494)
			(xy 128.545185 -410.388137) (xy 128.495605 -410.365493) (xy 128.449753 -410.336024) (xy 128.408561 -410.300329)
			(xy 128.372868 -410.259136) (xy 128.3434 -410.213282) (xy 128.320758 -410.163702) (xy 128.305403 -410.111404)
			(xy 128.297646 -410.057453) (xy 126.859989 -410.057453) (xy 126.852235 -410.111386) (xy 126.836884 -410.163673)
			(xy 126.814248 -410.213243) (xy 126.784788 -410.259087) (xy 126.749105 -410.300272) (xy 126.707924 -410.335961)
			(xy 126.662083 -410.365426) (xy 126.612516 -410.388068) (xy 126.560231 -410.403425) (xy 126.506293 -410.411187)
			(xy 126.479046 -410.411676) (xy 125.615446 -410.411676) (xy 125.588189 -410.41128) (xy 125.534228 -410.403528)
			(xy 125.48192 -410.388175) (xy 125.43233 -410.365533) (xy 125.386467 -410.336063) (xy 125.345266 -410.300367)
			(xy 125.309564 -410.259169) (xy 125.280089 -410.21331) (xy 125.257442 -410.163723) (xy 125.242082 -410.111417)
			(xy 125.234323 -410.057457) (xy 123.796789 -410.057457) (xy 123.789034 -410.111391) (xy 123.773681 -410.163681)
			(xy 123.751042 -410.213254) (xy 123.721579 -410.2591) (xy 123.685891 -410.300287) (xy 123.644705 -410.335975)
			(xy 123.598859 -410.365439) (xy 123.549287 -410.388079) (xy 123.496997 -410.403433) (xy 123.443055 -410.411189)
			(xy 123.415806 -410.411676) (xy 122.552206 -410.411676) (xy 122.524951 -410.411277) (xy 122.470994 -410.403521)
			(xy 122.418691 -410.388164) (xy 122.369106 -410.36552) (xy 122.323249 -410.336049) (xy 122.282052 -410.300353)
			(xy 122.246354 -410.259156) (xy 122.216883 -410.213299) (xy 122.194238 -410.163714) (xy 122.178881 -410.111411)
			(xy 122.171123 -410.057455) (xy 120.733613 -410.057455) (xy 120.725855 -410.111402) (xy 120.710499 -410.163698)
			(xy 120.687856 -410.213276) (xy 120.658387 -410.259127) (xy 120.622693 -410.300317) (xy 120.5815 -410.336008)
			(xy 120.535646 -410.365472) (xy 120.486066 -410.388111) (xy 120.433768 -410.403463) (xy 120.379818 -410.411215)
			(xy 120.352566 -410.411676) (xy 119.488966 -410.411676) (xy 119.461714 -410.411252) (xy 119.407765 -410.403491)
			(xy 119.35547 -410.388131) (xy 119.305893 -410.365486) (xy 119.260043 -410.336017) (xy 119.218854 -410.300322)
			(xy 119.183163 -410.259129) (xy 119.153697 -410.213277) (xy 119.131057 -410.163698) (xy 119.115702 -410.111401)
			(xy 119.107946 -410.057452) (xy 117.670289 -410.057452) (xy 117.662535 -410.111389) (xy 117.647182 -410.163677)
			(xy 117.624545 -410.213248) (xy 117.595084 -410.259093) (xy 117.559398 -410.300279) (xy 117.518214 -410.335968)
			(xy 117.472371 -410.365432) (xy 117.422801 -410.388073) (xy 117.370514 -410.403429) (xy 117.316574 -410.411188)
			(xy 117.289326 -410.411676) (xy 116.425726 -410.411676) (xy 116.39847 -410.411279) (xy 116.344511 -410.403524)
			(xy 116.292206 -410.388169) (xy 116.242618 -410.365526) (xy 116.196758 -410.336056) (xy 116.155559 -410.30036)
			(xy 116.119859 -410.259163) (xy 116.090386 -410.213305) (xy 116.06774 -410.163719) (xy 116.052381 -410.111414)
			(xy 116.044623 -410.057456) (xy 111.28975 -410.057456) (xy 111.276373 -410.086747) (xy 111.246907 -410.132597)
			(xy 111.211216 -410.173788) (xy 111.170025 -410.209479) (xy 111.124175 -410.238945) (xy 111.074598 -410.261587)
			(xy 111.022303 -410.276942) (xy 110.968355 -410.284698) (xy 110.913853 -410.284698) (xy 110.859905 -410.276942)
			(xy 110.80761 -410.261587) (xy 110.758033 -410.238945) (xy 110.712183 -410.209479) (xy 110.670992 -410.173788)
			(xy 110.635301 -410.132597) (xy 110.605835 -410.086747) (xy 110.583193 -410.03717) (xy 110.567838 -409.984875)
			(xy 110.560082 -409.930927) (xy 110.559596 -409.903676) (xy 102.748244 -409.903676) (xy 102.708181 -409.921973)
			(xy 102.655851 -409.937338) (xy 102.601867 -409.9451) (xy 102.547329 -409.9451) (xy 102.493345 -409.937338)
			(xy 102.441015 -409.921973) (xy 102.391405 -409.899316) (xy 102.345524 -409.86983) (xy 102.304307 -409.834115)
			(xy 102.268592 -409.792898) (xy 102.239106 -409.747017) (xy 102.216449 -409.697407) (xy 102.201084 -409.645077)
			(xy 102.193322 -409.591093) (xy 102.192836 -409.563824) (xy 7.00913 -409.563824) (xy 7.00913 -410.057453)
			(xy 48.944746 -410.057453) (xy 48.944746 -410.002947) (xy 48.952503 -409.948996) (xy 48.967858 -409.896698)
			(xy 48.9905 -409.847118) (xy 49.019967 -409.801265) (xy 49.05566 -409.760071) (xy 49.096852 -409.724377)
			(xy 49.142704 -409.694908) (xy 49.192283 -409.672264) (xy 49.244581 -409.656906) (xy 49.298531 -409.649147)
			(xy 49.325784 -409.64866) (xy 50.189384 -409.64866) (xy 50.216635 -409.649186) (xy 50.270583 -409.656941)
			(xy 50.322879 -409.672294) (xy 50.372457 -409.694934) (xy 50.418308 -409.724399) (xy 50.459499 -409.760089)
			(xy 50.495192 -409.801279) (xy 50.524659 -409.847129) (xy 50.5473 -409.896706) (xy 50.562656 -409.949001)
			(xy 50.570413 -410.002949) (xy 50.570413 -410.057451) (xy 50.570412 -410.057456) (xy 52.007923 -410.057456)
			(xy 52.007923 -410.002944) (xy 52.015681 -409.948986) (xy 52.03104 -409.896682) (xy 52.053686 -409.847096)
			(xy 52.083159 -409.801238) (xy 52.118858 -409.760041) (xy 52.160057 -409.724344) (xy 52.205917 -409.694874)
			(xy 52.255504 -409.672231) (xy 52.30781 -409.656876) (xy 52.361768 -409.649121) (xy 52.389024 -409.64866)
			(xy 53.252624 -409.64866) (xy 53.279872 -409.649212) (xy 53.333812 -409.65697) (xy 53.3861 -409.672326)
			(xy 53.43567 -409.694967) (xy 53.481513 -409.724431) (xy 53.522697 -409.76012) (xy 53.558383 -409.801306)
			(xy 53.587845 -409.847151) (xy 53.610482 -409.896723) (xy 53.625835 -409.949011) (xy 53.63359 -410.002952)
			(xy 53.63359 -410.057448) (xy 53.633589 -410.057452) (xy 55.071246 -410.057452) (xy 55.071246 -410.002948)
			(xy 55.079002 -409.948999) (xy 55.094357 -409.896703) (xy 55.116997 -409.847124) (xy 55.146462 -409.801271)
			(xy 55.182153 -409.760079) (xy 55.223342 -409.724384) (xy 55.269192 -409.694914) (xy 55.318769 -409.672269)
			(xy 55.371064 -409.65691) (xy 55.425012 -409.649148) (xy 55.452264 -409.64866) (xy 56.315864 -409.64866)
			(xy 56.343116 -409.649185) (xy 56.397067 -409.656937) (xy 56.449364 -409.672289) (xy 56.498945 -409.694927)
			(xy 56.544799 -409.724392) (xy 56.585992 -409.760082) (xy 56.621687 -409.801273) (xy 56.651156 -409.847124)
			(xy 56.673799 -409.896702) (xy 56.689155 -409.948998) (xy 56.696913 -410.002948) (xy 56.696913 -410.057452)
			(xy 56.696913 -410.057455) (xy 58.134423 -410.057455) (xy 58.134423 -410.002945) (xy 58.142181 -409.948989)
			(xy 58.157538 -409.896686) (xy 58.180183 -409.847102) (xy 58.209654 -409.801244) (xy 58.245351 -409.760048)
			(xy 58.286548 -409.724351) (xy 58.332405 -409.694881) (xy 58.38199 -409.672237) (xy 58.434293 -409.65688)
			(xy 58.488249 -409.649123) (xy 58.515504 -409.64866) (xy 59.379104 -409.64866) (xy 59.406353 -409.64921)
			(xy 59.460295 -409.656967) (xy 59.512585 -409.672321) (xy 59.562158 -409.69496) (xy 59.608004 -409.724424)
			(xy 59.64919 -409.760113) (xy 59.684878 -409.801299) (xy 59.714342 -409.847146) (xy 59.73698 -409.896718)
			(xy 59.752334 -409.949008) (xy 59.76009 -410.002951) (xy 59.76009 -410.057449) (xy 59.760089 -410.057457)
			(xy 61.197623 -410.057457) (xy 61.197623 -410.002943) (xy 61.205382 -409.948983) (xy 61.220741 -409.896678)
			(xy 61.243389 -409.84709) (xy 61.272864 -409.801231) (xy 61.308565 -409.760034) (xy 61.349767 -409.724337)
			(xy 61.395629 -409.694868) (xy 61.445219 -409.672226) (xy 61.497527 -409.656872) (xy 61.551487 -409.64912)
			(xy 61.578744 -409.64866) (xy 62.442344 -409.64866) (xy 62.469591 -409.649213) (xy 62.523529 -409.656974)
			(xy 62.575814 -409.672332) (xy 62.625382 -409.694973) (xy 62.671223 -409.724438) (xy 62.712404 -409.760127)
			(xy 62.748088 -409.801313) (xy 62.777548 -409.847157) (xy 62.800184 -409.896727) (xy 62.815535 -409.949014)
			(xy 62.82329 -410.002953) (xy 62.82329 -410.057447) (xy 62.823289 -410.057453) (xy 64.260946 -410.057453)
			(xy 64.260946 -410.002947) (xy 64.268703 -409.948996) (xy 64.284058 -409.896698) (xy 64.3067 -409.847118)
			(xy 64.336167 -409.801265) (xy 64.37186 -409.760071) (xy 64.413052 -409.724377) (xy 64.458904 -409.694908)
			(xy 64.508483 -409.672264) (xy 64.560781 -409.656906) (xy 64.614731 -409.649147) (xy 64.641984 -409.64866)
			(xy 65.505584 -409.64866) (xy 65.532835 -409.649186) (xy 65.586783 -409.656941) (xy 65.639079 -409.672294)
			(xy 65.688657 -409.694934) (xy 65.734508 -409.724399) (xy 65.775699 -409.760089) (xy 65.811392 -409.801279)
			(xy 65.840859 -409.847129) (xy 65.8635 -409.896706) (xy 65.878856 -409.949001) (xy 65.886613 -410.002949)
			(xy 65.886613 -410.057451) (xy 65.886612 -410.057456) (xy 67.324123 -410.057456) (xy 67.324123 -410.002944)
			(xy 67.331881 -409.948986) (xy 67.34724 -409.896682) (xy 67.369886 -409.847096) (xy 67.399359 -409.801238)
			(xy 67.435058 -409.760041) (xy 67.476257 -409.724344) (xy 67.522117 -409.694874) (xy 67.571704 -409.672231)
			(xy 67.62401 -409.656876) (xy 67.677968 -409.649121) (xy 67.705224 -409.64866) (xy 68.568824 -409.64866)
			(xy 68.596072 -409.649212) (xy 68.650012 -409.65697) (xy 68.7023 -409.672326) (xy 68.75187 -409.694967)
			(xy 68.797713 -409.724431) (xy 68.838897 -409.76012) (xy 68.874583 -409.801306) (xy 68.904045 -409.847151)
			(xy 68.926682 -409.896723) (xy 68.942035 -409.949011) (xy 68.94979 -410.002952) (xy 68.94979 -410.057448)
			(xy 68.949789 -410.057452) (xy 70.387446 -410.057452) (xy 70.387446 -410.002948) (xy 70.395202 -409.948999)
			(xy 70.410557 -409.896703) (xy 70.433197 -409.847124) (xy 70.462662 -409.801271) (xy 70.498353 -409.760079)
			(xy 70.539542 -409.724384) (xy 70.585392 -409.694914) (xy 70.634969 -409.672269) (xy 70.687264 -409.65691)
			(xy 70.741212 -409.649148) (xy 70.768464 -409.64866) (xy 71.632064 -409.64866) (xy 71.659316 -409.649185)
			(xy 71.713267 -409.656937) (xy 71.765564 -409.672289) (xy 71.815145 -409.694927) (xy 71.860999 -409.724392)
			(xy 71.902192 -409.760082) (xy 71.937887 -409.801273) (xy 71.967356 -409.847124) (xy 71.989999 -409.896702)
			(xy 72.005355 -409.948998) (xy 72.013113 -410.002948) (xy 72.013113 -410.057452) (xy 72.013113 -410.057455)
			(xy 73.450623 -410.057455) (xy 73.450623 -410.002945) (xy 73.458381 -409.948989) (xy 73.473738 -409.896686)
			(xy 73.496383 -409.847102) (xy 73.525854 -409.801244) (xy 73.561551 -409.760048) (xy 73.602748 -409.724351)
			(xy 73.648605 -409.694881) (xy 73.69819 -409.672237) (xy 73.750493 -409.65688) (xy 73.804449 -409.649123)
			(xy 73.831704 -409.64866) (xy 74.695304 -409.64866) (xy 74.722553 -409.64921) (xy 74.776495 -409.656967)
			(xy 74.828785 -409.672321) (xy 74.878358 -409.69496) (xy 74.924204 -409.724424) (xy 74.96539 -409.760113)
			(xy 75.001078 -409.801299) (xy 75.030542 -409.847146) (xy 75.05318 -409.896718) (xy 75.068534 -409.949008)
			(xy 75.07629 -410.002951) (xy 75.07629 -410.057449) (xy 75.076289 -410.057457) (xy 76.513823 -410.057457)
			(xy 76.513823 -410.002943) (xy 76.521582 -409.948983) (xy 76.536941 -409.896678) (xy 76.559589 -409.84709)
			(xy 76.589064 -409.801231) (xy 76.624765 -409.760034) (xy 76.665967 -409.724337) (xy 76.711829 -409.694868)
			(xy 76.761419 -409.672226) (xy 76.813727 -409.656872) (xy 76.867687 -409.64912) (xy 76.894944 -409.64866)
			(xy 77.758544 -409.64866) (xy 77.785791 -409.649213) (xy 77.839729 -409.656974) (xy 77.892014 -409.672332)
			(xy 77.941582 -409.694973) (xy 77.987423 -409.724438) (xy 78.028604 -409.760127) (xy 78.064288 -409.801313)
			(xy 78.093748 -409.847157) (xy 78.116384 -409.896727) (xy 78.131735 -409.949014) (xy 78.13949 -410.002953)
			(xy 78.13949 -410.057447) (xy 78.139489 -410.057453) (xy 79.577146 -410.057453) (xy 79.577146 -410.002947)
			(xy 79.584903 -409.948996) (xy 79.600258 -409.896698) (xy 79.6229 -409.847118) (xy 79.652367 -409.801265)
			(xy 79.68806 -409.760071) (xy 79.729252 -409.724377) (xy 79.775104 -409.694908) (xy 79.824683 -409.672264)
			(xy 79.876981 -409.656906) (xy 79.930931 -409.649147) (xy 79.958184 -409.64866) (xy 80.821784 -409.64866)
			(xy 80.849035 -409.649186) (xy 80.902983 -409.656941) (xy 80.955279 -409.672294) (xy 81.004857 -409.694934)
			(xy 81.050708 -409.724399) (xy 81.091899 -409.760089) (xy 81.127592 -409.801279) (xy 81.157059 -409.847129)
			(xy 81.1797 -409.896706) (xy 81.195056 -409.949001) (xy 81.202813 -410.002949) (xy 81.202813 -410.057451)
			(xy 81.202812 -410.057456) (xy 82.640323 -410.057456) (xy 82.640323 -410.002944) (xy 82.648081 -409.948986)
			(xy 82.66344 -409.896682) (xy 82.686086 -409.847096) (xy 82.715559 -409.801238) (xy 82.751258 -409.760041)
			(xy 82.792457 -409.724344) (xy 82.838317 -409.694874) (xy 82.887904 -409.672231) (xy 82.94021 -409.656876)
			(xy 82.994168 -409.649121) (xy 83.021424 -409.64866) (xy 83.885024 -409.64866) (xy 83.912272 -409.649212)
			(xy 83.966212 -409.65697) (xy 84.0185 -409.672326) (xy 84.06807 -409.694967) (xy 84.113913 -409.724431)
			(xy 84.155097 -409.76012) (xy 84.190783 -409.801306) (xy 84.220245 -409.847151) (xy 84.242882 -409.896723)
			(xy 84.258235 -409.949011) (xy 84.26599 -410.002952) (xy 84.26599 -410.057448) (xy 84.265989 -410.057452)
			(xy 85.703646 -410.057452) (xy 85.703646 -410.002948) (xy 85.711402 -409.948999) (xy 85.726757 -409.896703)
			(xy 85.749397 -409.847124) (xy 85.778862 -409.801271) (xy 85.814553 -409.760079) (xy 85.855742 -409.724384)
			(xy 85.901592 -409.694914) (xy 85.951169 -409.672269) (xy 86.003464 -409.65691) (xy 86.057412 -409.649148)
			(xy 86.084664 -409.64866) (xy 86.948264 -409.64866) (xy 86.975516 -409.649185) (xy 87.029467 -409.656937)
			(xy 87.081764 -409.672289) (xy 87.131345 -409.694927) (xy 87.177199 -409.724392) (xy 87.218392 -409.760082)
			(xy 87.254087 -409.801273) (xy 87.283556 -409.847124) (xy 87.306199 -409.896702) (xy 87.321555 -409.948998)
			(xy 87.329313 -410.002948) (xy 87.329313 -410.057452) (xy 87.329313 -410.057455) (xy 88.766823 -410.057455)
			(xy 88.766823 -410.002945) (xy 88.774581 -409.948989) (xy 88.789938 -409.896686) (xy 88.812583 -409.847102)
			(xy 88.842054 -409.801244) (xy 88.877751 -409.760048) (xy 88.918948 -409.724351) (xy 88.964805 -409.694881)
			(xy 89.01439 -409.672237) (xy 89.066693 -409.65688) (xy 89.120649 -409.649123) (xy 89.147904 -409.64866)
			(xy 90.011504 -409.64866) (xy 90.038753 -409.64921) (xy 90.092695 -409.656967) (xy 90.144985 -409.672321)
			(xy 90.194558 -409.69496) (xy 90.240404 -409.724424) (xy 90.28159 -409.760113) (xy 90.317278 -409.801299)
			(xy 90.346742 -409.847146) (xy 90.36938 -409.896718) (xy 90.384734 -409.949008) (xy 90.39249 -410.002951)
			(xy 90.39249 -410.057449) (xy 90.392489 -410.057457) (xy 91.830023 -410.057457) (xy 91.830023 -410.002943)
			(xy 91.837782 -409.948983) (xy 91.853141 -409.896678) (xy 91.875789 -409.84709) (xy 91.905264 -409.801231)
			(xy 91.940965 -409.760034) (xy 91.982167 -409.724337) (xy 92.028029 -409.694868) (xy 92.077619 -409.672226)
			(xy 92.129927 -409.656872) (xy 92.183887 -409.64912) (xy 92.211144 -409.64866) (xy 93.074744 -409.64866)
			(xy 93.101991 -409.649213) (xy 93.155929 -409.656974) (xy 93.208214 -409.672332) (xy 93.257782 -409.694973)
			(xy 93.303623 -409.724438) (xy 93.344804 -409.760127) (xy 93.380488 -409.801313) (xy 93.409948 -409.847157)
			(xy 93.432584 -409.896727) (xy 93.447935 -409.949014) (xy 93.45569 -410.002953) (xy 93.45569 -410.057447)
			(xy 93.455689 -410.057453) (xy 94.893346 -410.057453) (xy 94.893346 -410.002947) (xy 94.901103 -409.948996)
			(xy 94.916458 -409.896698) (xy 94.9391 -409.847118) (xy 94.968567 -409.801265) (xy 95.00426 -409.760071)
			(xy 95.045452 -409.724377) (xy 95.091304 -409.694908) (xy 95.140883 -409.672264) (xy 95.193181 -409.656906)
			(xy 95.247131 -409.649147) (xy 95.274384 -409.64866) (xy 96.137984 -409.64866) (xy 96.165235 -409.649186)
			(xy 96.219183 -409.656941) (xy 96.271479 -409.672294) (xy 96.321057 -409.694934) (xy 96.366908 -409.724399)
			(xy 96.408099 -409.760089) (xy 96.443792 -409.801279) (xy 96.473259 -409.847129) (xy 96.4959 -409.896706)
			(xy 96.511256 -409.949001) (xy 96.519013 -410.002949) (xy 96.519013 -410.057451) (xy 96.511256 -410.111399)
			(xy 96.4959 -410.163694) (xy 96.473259 -410.213271) (xy 96.443792 -410.259121) (xy 96.408099 -410.300311)
			(xy 96.366908 -410.336001) (xy 96.321057 -410.365466) (xy 96.271479 -410.388106) (xy 96.219183 -410.403459)
			(xy 96.165235 -410.411214) (xy 96.137984 -410.411676) (xy 95.274384 -410.411676) (xy 95.247131 -410.411253)
			(xy 95.193181 -410.403494) (xy 95.140883 -410.388136) (xy 95.091304 -410.365492) (xy 95.045452 -410.336023)
			(xy 95.00426 -410.300329) (xy 94.968567 -410.259135) (xy 94.9391 -410.213282) (xy 94.916458 -410.163702)
			(xy 94.901103 -410.111404) (xy 94.893346 -410.057453) (xy 93.455689 -410.057453) (xy 93.447935 -410.111386)
			(xy 93.432584 -410.163673) (xy 93.409948 -410.213243) (xy 93.380488 -410.259087) (xy 93.344804 -410.300273)
			(xy 93.303623 -410.335962) (xy 93.257782 -410.365427) (xy 93.208214 -410.388068) (xy 93.155929 -410.403426)
			(xy 93.101991 -410.411187) (xy 93.074744 -410.411676) (xy 92.211144 -410.411676) (xy 92.183887 -410.41128)
			(xy 92.129927 -410.403528) (xy 92.077619 -410.388174) (xy 92.028029 -410.365532) (xy 91.982167 -410.336063)
			(xy 91.940965 -410.300366) (xy 91.905264 -410.259169) (xy 91.875789 -410.21331) (xy 91.853141 -410.163722)
			(xy 91.837782 -410.111417) (xy 91.830023 -410.057457) (xy 90.392489 -410.057457) (xy 90.384734 -410.111392)
			(xy 90.36938 -410.163682) (xy 90.346742 -410.213254) (xy 90.317278 -410.259101) (xy 90.28159 -410.300287)
			(xy 90.240404 -410.335976) (xy 90.194558 -410.36544) (xy 90.144985 -410.388079) (xy 90.092695 -410.403433)
			(xy 90.038753 -410.41119) (xy 90.011504 -410.411676) (xy 89.147904 -410.411676) (xy 89.120649 -410.411277)
			(xy 89.066693 -410.40352) (xy 89.01439 -410.388163) (xy 88.964805 -410.365519) (xy 88.918948 -410.336049)
			(xy 88.877751 -410.300352) (xy 88.842054 -410.259156) (xy 88.812583 -410.213298) (xy 88.789938 -410.163714)
			(xy 88.774581 -410.111411) (xy 88.766823 -410.057455) (xy 87.329313 -410.057455) (xy 87.321555 -410.111402)
			(xy 87.306199 -410.163698) (xy 87.283556 -410.213276) (xy 87.254087 -410.259127) (xy 87.218392 -410.300318)
			(xy 87.177199 -410.336008) (xy 87.131345 -410.365473) (xy 87.081764 -410.388111) (xy 87.029467 -410.403463)
			(xy 86.975516 -410.411215) (xy 86.948264 -410.411676) (xy 86.084664 -410.411676) (xy 86.057412 -410.411252)
			(xy 86.003464 -410.40349) (xy 85.951169 -410.388131) (xy 85.901592 -410.365486) (xy 85.855742 -410.336016)
			(xy 85.814553 -410.300321) (xy 85.778862 -410.259129) (xy 85.749397 -410.213276) (xy 85.726757 -410.163697)
			(xy 85.711402 -410.111401) (xy 85.703646 -410.057452) (xy 84.265989 -410.057452) (xy 84.258235 -410.111389)
			(xy 84.242882 -410.163677) (xy 84.220245 -410.213249) (xy 84.190783 -410.259094) (xy 84.155097 -410.30028)
			(xy 84.113913 -410.335969) (xy 84.06807 -410.365433) (xy 84.0185 -410.388074) (xy 83.966212 -410.40343)
			(xy 83.912272 -410.411188) (xy 83.885024 -410.411676) (xy 83.021424 -410.411676) (xy 82.994168 -410.411279)
			(xy 82.94021 -410.403524) (xy 82.887904 -410.388169) (xy 82.838317 -410.365526) (xy 82.792457 -410.336056)
			(xy 82.751258 -410.300359) (xy 82.715559 -410.259162) (xy 82.686086 -410.213304) (xy 82.66344 -410.163718)
			(xy 82.648081 -410.111414) (xy 82.640323 -410.057456) (xy 81.202812 -410.057456) (xy 81.195056 -410.111399)
			(xy 81.1797 -410.163694) (xy 81.157059 -410.213271) (xy 81.127592 -410.259121) (xy 81.091899 -410.300311)
			(xy 81.050708 -410.336001) (xy 81.004857 -410.365466) (xy 80.955279 -410.388106) (xy 80.902983 -410.403459)
			(xy 80.849035 -410.411214) (xy 80.821784 -410.411676) (xy 79.958184 -410.411676) (xy 79.930931 -410.411253)
			(xy 79.876981 -410.403494) (xy 79.824683 -410.388136) (xy 79.775104 -410.365492) (xy 79.729252 -410.336023)
			(xy 79.68806 -410.300329) (xy 79.652367 -410.259135) (xy 79.6229 -410.213282) (xy 79.600258 -410.163702)
			(xy 79.584903 -410.111404) (xy 79.577146 -410.057453) (xy 78.139489 -410.057453) (xy 78.131735 -410.111386)
			(xy 78.116384 -410.163673) (xy 78.093748 -410.213243) (xy 78.064288 -410.259087) (xy 78.028604 -410.300273)
			(xy 77.987423 -410.335962) (xy 77.941582 -410.365427) (xy 77.892014 -410.388068) (xy 77.839729 -410.403426)
			(xy 77.785791 -410.411187) (xy 77.758544 -410.411676) (xy 76.894944 -410.411676) (xy 76.867687 -410.41128)
			(xy 76.813727 -410.403528) (xy 76.761419 -410.388174) (xy 76.711829 -410.365532) (xy 76.665967 -410.336063)
			(xy 76.624765 -410.300366) (xy 76.589064 -410.259169) (xy 76.559589 -410.21331) (xy 76.536941 -410.163722)
			(xy 76.521582 -410.111417) (xy 76.513823 -410.057457) (xy 75.076289 -410.057457) (xy 75.068534 -410.111392)
			(xy 75.05318 -410.163682) (xy 75.030542 -410.213254) (xy 75.001078 -410.259101) (xy 74.96539 -410.300287)
			(xy 74.924204 -410.335976) (xy 74.878358 -410.36544) (xy 74.828785 -410.388079) (xy 74.776495 -410.403433)
			(xy 74.722553 -410.41119) (xy 74.695304 -410.411676) (xy 73.831704 -410.411676) (xy 73.804449 -410.411277)
			(xy 73.750493 -410.40352) (xy 73.69819 -410.388163) (xy 73.648605 -410.365519) (xy 73.602748 -410.336049)
			(xy 73.561551 -410.300352) (xy 73.525854 -410.259156) (xy 73.496383 -410.213298) (xy 73.473738 -410.163714)
			(xy 73.458381 -410.111411) (xy 73.450623 -410.057455) (xy 72.013113 -410.057455) (xy 72.005355 -410.111402)
			(xy 71.989999 -410.163698) (xy 71.967356 -410.213276) (xy 71.937887 -410.259127) (xy 71.902192 -410.300318)
			(xy 71.860999 -410.336008) (xy 71.815145 -410.365473) (xy 71.765564 -410.388111) (xy 71.713267 -410.403463)
			(xy 71.659316 -410.411215) (xy 71.632064 -410.411676) (xy 70.768464 -410.411676) (xy 70.741212 -410.411252)
			(xy 70.687264 -410.40349) (xy 70.634969 -410.388131) (xy 70.585392 -410.365486) (xy 70.539542 -410.336016)
			(xy 70.498353 -410.300321) (xy 70.462662 -410.259129) (xy 70.433197 -410.213276) (xy 70.410557 -410.163697)
			(xy 70.395202 -410.111401) (xy 70.387446 -410.057452) (xy 68.949789 -410.057452) (xy 68.942035 -410.111389)
			(xy 68.926682 -410.163677) (xy 68.904045 -410.213249) (xy 68.874583 -410.259094) (xy 68.838897 -410.30028)
			(xy 68.797713 -410.335969) (xy 68.75187 -410.365433) (xy 68.7023 -410.388074) (xy 68.650012 -410.40343)
			(xy 68.596072 -410.411188) (xy 68.568824 -410.411676) (xy 67.705224 -410.411676) (xy 67.677968 -410.411279)
			(xy 67.62401 -410.403524) (xy 67.571704 -410.388169) (xy 67.522117 -410.365526) (xy 67.476257 -410.336056)
			(xy 67.435058 -410.300359) (xy 67.399359 -410.259162) (xy 67.369886 -410.213304) (xy 67.34724 -410.163718)
			(xy 67.331881 -410.111414) (xy 67.324123 -410.057456) (xy 65.886612 -410.057456) (xy 65.878856 -410.111399)
			(xy 65.8635 -410.163694) (xy 65.840859 -410.213271) (xy 65.811392 -410.259121) (xy 65.775699 -410.300311)
			(xy 65.734508 -410.336001) (xy 65.688657 -410.365466) (xy 65.639079 -410.388106) (xy 65.586783 -410.403459)
			(xy 65.532835 -410.411214) (xy 65.505584 -410.411676) (xy 64.641984 -410.411676) (xy 64.614731 -410.411253)
			(xy 64.560781 -410.403494) (xy 64.508483 -410.388136) (xy 64.458904 -410.365492) (xy 64.413052 -410.336023)
			(xy 64.37186 -410.300329) (xy 64.336167 -410.259135) (xy 64.3067 -410.213282) (xy 64.284058 -410.163702)
			(xy 64.268703 -410.111404) (xy 64.260946 -410.057453) (xy 62.823289 -410.057453) (xy 62.815535 -410.111386)
			(xy 62.800184 -410.163673) (xy 62.777548 -410.213243) (xy 62.748088 -410.259087) (xy 62.712404 -410.300273)
			(xy 62.671223 -410.335962) (xy 62.625382 -410.365427) (xy 62.575814 -410.388068) (xy 62.523529 -410.403426)
			(xy 62.469591 -410.411187) (xy 62.442344 -410.411676) (xy 61.578744 -410.411676) (xy 61.551487 -410.41128)
			(xy 61.497527 -410.403528) (xy 61.445219 -410.388174) (xy 61.395629 -410.365532) (xy 61.349767 -410.336063)
			(xy 61.308565 -410.300366) (xy 61.272864 -410.259169) (xy 61.243389 -410.21331) (xy 61.220741 -410.163722)
			(xy 61.205382 -410.111417) (xy 61.197623 -410.057457) (xy 59.760089 -410.057457) (xy 59.752334 -410.111392)
			(xy 59.73698 -410.163682) (xy 59.714342 -410.213254) (xy 59.684878 -410.259101) (xy 59.64919 -410.300287)
			(xy 59.608004 -410.335976) (xy 59.562158 -410.36544) (xy 59.512585 -410.388079) (xy 59.460295 -410.403433)
			(xy 59.406353 -410.41119) (xy 59.379104 -410.411676) (xy 58.515504 -410.411676) (xy 58.488249 -410.411277)
			(xy 58.434293 -410.40352) (xy 58.38199 -410.388163) (xy 58.332405 -410.365519) (xy 58.286548 -410.336049)
			(xy 58.245351 -410.300352) (xy 58.209654 -410.259156) (xy 58.180183 -410.213298) (xy 58.157538 -410.163714)
			(xy 58.142181 -410.111411) (xy 58.134423 -410.057455) (xy 56.696913 -410.057455) (xy 56.689155 -410.111402)
			(xy 56.673799 -410.163698) (xy 56.651156 -410.213276) (xy 56.621687 -410.259127) (xy 56.585992 -410.300318)
			(xy 56.544799 -410.336008) (xy 56.498945 -410.365473) (xy 56.449364 -410.388111) (xy 56.397067 -410.403463)
			(xy 56.343116 -410.411215) (xy 56.315864 -410.411676) (xy 55.452264 -410.411676) (xy 55.425012 -410.411252)
			(xy 55.371064 -410.40349) (xy 55.318769 -410.388131) (xy 55.269192 -410.365486) (xy 55.223342 -410.336016)
			(xy 55.182153 -410.300321) (xy 55.146462 -410.259129) (xy 55.116997 -410.213276) (xy 55.094357 -410.163697)
			(xy 55.079002 -410.111401) (xy 55.071246 -410.057452) (xy 53.633589 -410.057452) (xy 53.625835 -410.111389)
			(xy 53.610482 -410.163677) (xy 53.587845 -410.213249) (xy 53.558383 -410.259094) (xy 53.522697 -410.30028)
			(xy 53.481513 -410.335969) (xy 53.43567 -410.365433) (xy 53.3861 -410.388074) (xy 53.333812 -410.40343)
			(xy 53.279872 -410.411188) (xy 53.252624 -410.411676) (xy 52.389024 -410.411676) (xy 52.361768 -410.411279)
			(xy 52.30781 -410.403524) (xy 52.255504 -410.388169) (xy 52.205917 -410.365526) (xy 52.160057 -410.336056)
			(xy 52.118858 -410.300359) (xy 52.083159 -410.259162) (xy 52.053686 -410.213304) (xy 52.03104 -410.163718)
			(xy 52.015681 -410.111414) (xy 52.007923 -410.057456) (xy 50.570412 -410.057456) (xy 50.562656 -410.111399)
			(xy 50.5473 -410.163694) (xy 50.524659 -410.213271) (xy 50.495192 -410.259121) (xy 50.459499 -410.300311)
			(xy 50.418308 -410.336001) (xy 50.372457 -410.365466) (xy 50.322879 -410.388106) (xy 50.270583 -410.403459)
			(xy 50.216635 -410.411214) (xy 50.189384 -410.411676) (xy 49.325784 -410.411676) (xy 49.298531 -410.411253)
			(xy 49.244581 -410.403494) (xy 49.192283 -410.388136) (xy 49.142704 -410.365492) (xy 49.096852 -410.336023)
			(xy 49.05566 -410.300329) (xy 49.019967 -410.259135) (xy 48.9905 -410.213282) (xy 48.967858 -410.163702)
			(xy 48.952503 -410.111404) (xy 48.944746 -410.057453) (xy 7.00913 -410.057453) (xy 7.00913 -410.708348)
			(xy 183.940958 -410.708348) (xy 183.940958 -400.09572) (xy 183.941483 -400.070772) (xy 183.94929 -400.021491)
			(xy 183.964701 -399.974034) (xy 183.987336 -399.929568) (xy 184.01664 -399.889183) (xy 184.033922 -399.871184)
			(xy 184.239408 -399.665698) (xy 184.257395 -399.648399) (xy 184.297773 -399.619076) (xy 184.342241 -399.59643)
			(xy 184.389704 -399.581018) (xy 184.438993 -399.57322) (xy 184.463944 -399.572734) (xy 188.119004 -399.572734)
			(xy 188.143952 -399.57325) (xy 188.193234 -399.581061) (xy 188.24069 -399.596474) (xy 188.285156 -399.619111)
			(xy 188.32554 -399.648416) (xy 188.34354 -399.665698) (xy 188.528452 -399.85061) (xy 188.545762 -399.868588)
			(xy 188.575091 -399.908966) (xy 188.597741 -399.953436) (xy 188.613156 -400.000901) (xy 188.620956 -400.050193)
			(xy 188.621416 -400.075146) (xy 188.621416 -402.753322) (xy 188.621826 -402.763393) (xy 188.629557 -402.781991)
			(xy 188.636402 -402.78939) (xy 191.190372 -405.34336) (xy 191.197792 -405.350175) (xy 191.216376 -405.35791)
			(xy 191.22644 -405.358346) (xy 195.26631 -405.358346) (xy 195.276382 -405.35794) (xy 195.29498 -405.350207)
			(xy 195.302378 -405.34336) (xy 197.179184 -403.466554) (xy 197.185991 -403.459128) (xy 197.193731 -403.440549)
			(xy 197.19417 -403.430486) (xy 197.19417 -400.104356) (xy 197.194651 -400.079406) (xy 197.202469 -400.030123)
			(xy 197.217889 -399.982665) (xy 197.240534 -399.9382) (xy 197.269848 -399.897818) (xy 197.287134 -399.87982)
			(xy 197.53961 -399.627344) (xy 197.557604 -399.610052) (xy 197.597979 -399.580727) (xy 197.642445 -399.558078)
			(xy 197.689907 -399.542665) (xy 197.739195 -399.534866) (xy 197.764146 -399.53438) (xy 201.33818 -399.53438)
			(xy 201.363128 -399.534898) (xy 201.41241 -399.542706) (xy 201.459867 -399.558118) (xy 201.504334 -399.580755)
			(xy 201.544717 -399.610061) (xy 201.562716 -399.627344) (xy 201.823066 -399.887694) (xy 201.840352 -399.905693)
			(xy 201.869678 -399.946068) (xy 201.892327 -399.990532) (xy 201.907742 -400.037992) (xy 201.915543 -400.08728)
			(xy 201.91603 -400.11223) (xy 201.91603 -403.422612) (xy 201.916441 -403.432683) (xy 201.924171 -403.451281)
			(xy 201.931016 -403.45868) (xy 202.036172 -403.563836) (xy 202.053479 -403.581816) (xy 202.082802 -403.622195)
			(xy 202.105447 -403.666665) (xy 202.120857 -403.714129) (xy 202.128652 -403.76342) (xy 202.129136 -403.788372)
			(xy 202.129136 -406.516078) (xy 202.129564 -406.526147) (xy 202.137282 -406.544745) (xy 202.144122 -406.552146)
			(xy 203.391008 -407.799032) (xy 203.39839 -407.805645) (xy 203.416673 -407.813238) (xy 203.426568 -407.813764)
			(xy 203.457048 -407.814018) (xy 203.466471 -407.813752) (xy 203.484091 -407.807093) (xy 203.491338 -407.801064)
			(xy 203.512428 -407.782761) (xy 203.558955 -407.751881) (xy 203.609485 -407.728114) (xy 203.662941 -407.711966)
			(xy 203.71818 -407.703783) (xy 203.7461 -407.703274) (xy 203.772675 -407.703742) (xy 203.825312 -407.711107)
			(xy 203.876417 -407.72571) (xy 203.924999 -407.747267) (xy 203.970118 -407.77536) (xy 204.010899 -407.809446)
			(xy 204.046552 -407.848864) (xy 204.076387 -407.89285) (xy 204.099826 -407.940552) (xy 204.108558 -407.965656)
			(xy 204.112315 -407.97567) (xy 204.126611 -407.991551) (xy 204.146134 -408.00024) (xy 204.156818 -408.000708)
			(xy 205.795372 -408.000708) (xy 205.805443 -408.000292) (xy 205.824042 -407.992567) (xy 205.83144 -407.985722)
			(xy 207.658716 -406.158446) (xy 207.66553 -406.151026) (xy 207.673264 -406.132442) (xy 207.673702 -406.122378)
			(xy 207.673702 -403.722586) (xy 207.674193 -403.697637) (xy 207.682006 -403.648353) (xy 207.697424 -403.600896)
			(xy 207.720068 -403.55643) (xy 207.74938 -403.516048) (xy 207.766666 -403.49805) (xy 207.847184 -403.417532)
			(xy 207.854 -403.410113) (xy 207.861735 -403.391528) (xy 207.86217 -403.381464) (xy 207.86217 -400.079464)
			(xy 207.862656 -400.054515) (xy 207.870472 -400.005231) (xy 207.885892 -399.957774) (xy 207.908536 -399.913308)
			(xy 207.937848 -399.872926) (xy 207.955134 -399.854928) (xy 208.201514 -399.608548) (xy 208.21949 -399.591236)
			(xy 208.259869 -399.561908) (xy 208.304339 -399.539258) (xy 208.351805 -399.523843) (xy 208.401097 -399.516044)
			(xy 208.42605 -399.515584) (xy 211.971128 -399.515584) (xy 211.996077 -399.516071) (xy 212.045361 -399.523886)
			(xy 212.092818 -399.539306) (xy 212.137284 -399.561949) (xy 212.177666 -399.591262) (xy 212.195664 -399.608548)
			(xy 212.507576 -399.92046) (xy 212.524847 -399.938473) (xy 212.554175 -399.978843) (xy 212.576826 -400.023305)
			(xy 212.592245 -400.070762) (xy 212.600051 -400.120047) (xy 212.60054 -400.144996) (xy 212.60054 -403.480016)
			(xy 212.600947 -403.490088) (xy 212.608679 -403.508686) (xy 212.615526 -403.516084) (xy 212.638894 -403.539452)
			(xy 212.656213 -403.557421) (xy 212.685533 -403.597804) (xy 212.708176 -403.642276) (xy 212.723583 -403.689743)
			(xy 212.731376 -403.739036) (xy 212.731858 -403.763988) (xy 212.731858 -406.258014) (xy 212.732261 -406.268086)
			(xy 212.739995 -406.286685) (xy 212.746844 -406.294082) (xy 214.186008 -407.733246) (xy 214.193923 -407.74035)
			(xy 214.21371 -407.748063) (xy 214.234927 -407.747127) (xy 214.244682 -407.742898) (xy 214.271123 -407.730432)
			(xy 214.326854 -407.712801) (xy 214.38462 -407.703855) (xy 214.413846 -407.703274) (xy 214.4141 -407.703274)
			(xy 214.441972 -407.70378) (xy 214.497125 -407.71188) (xy 214.550512 -407.727922) (xy 214.600994 -407.751564)
			(xy 214.647498 -407.782303) (xy 214.689031 -407.819484) (xy 214.72471 -407.862315) (xy 214.753774 -407.909883)
			(xy 214.775604 -407.961175) (xy 214.783162 -407.988008) (xy 214.78748 -408.004772) (xy 214.814912 -408.025854)
			(xy 216.38895 -408.025854) (xy 216.399018 -408.025415) (xy 216.417617 -408.017705) (xy 216.425018 -408.010868)
			(xy 218.335098 -406.100788) (xy 218.341936 -406.093386) (xy 218.349657 -406.074788) (xy 218.350084 -406.06472)
			(xy 218.350084 -403.755606) (xy 218.350592 -403.730657) (xy 218.358403 -403.681375) (xy 218.373817 -403.633918)
			(xy 218.396456 -403.589452) (xy 218.425764 -403.549069) (xy 218.443048 -403.53107) (xy 218.50731 -403.466808)
			(xy 218.51414 -403.4594) (xy 218.521865 -403.440807) (xy 218.522296 -403.43074) (xy 218.522296 -400.095974)
			(xy 218.522781 -400.071024) (xy 218.530596 -400.021741) (xy 218.546016 -399.974283) (xy 218.56866 -399.929817)
			(xy 218.597974 -399.889436) (xy 218.61526 -399.871438) (xy 218.820746 -399.665952) (xy 218.838709 -399.648625)
			(xy 218.879091 -399.619299) (xy 218.923564 -399.596652) (xy 218.971033 -399.581241) (xy 219.020328 -399.573446)
			(xy 219.045282 -399.572988) (xy 222.709232 -399.572988) (xy 222.734182 -399.573471) (xy 222.783465 -399.581288)
			(xy 222.830923 -399.596707) (xy 222.875388 -399.619352) (xy 222.91577 -399.648666) (xy 222.933768 -399.665952)
			(xy 223.130618 -399.862802) (xy 223.147917 -399.880789) (xy 223.177239 -399.921168) (xy 223.199885 -399.965636)
			(xy 223.215297 -400.013098) (xy 223.223096 -400.062387) (xy 223.223582 -400.087338) (xy 223.223582 -403.455124)
			(xy 223.223973 -403.465198) (xy 223.231716 -403.483796) (xy 223.238568 -403.491192) (xy 223.323658 -403.576282)
			(xy 223.340937 -403.594288) (xy 223.370264 -403.63466) (xy 223.392915 -403.679123) (xy 223.408331 -403.726582)
			(xy 223.416134 -403.775868) (xy 223.416622 -403.800818) (xy 223.416622 -406.262078) (xy 223.417053 -406.272147)
			(xy 223.424769 -406.290745) (xy 223.431608 -406.298146) (xy 224.874328 -407.740866) (xy 224.905824 -407.7462)
			(xy 224.920302 -407.739342) (xy 224.945735 -407.727945) (xy 224.999097 -407.71187) (xy 225.054234 -407.703754)
			(xy 225.0821 -407.703274) (xy 225.111289 -407.703848) (xy 225.168987 -407.712721) (xy 225.224657 -407.730289)
			(xy 225.276997 -407.756142) (xy 225.324782 -407.789675) (xy 225.366893 -407.830104) (xy 225.402346 -407.876481)
			(xy 225.430312 -407.927723) (xy 225.440748 -407.954988) (xy 225.444773 -407.964592) (xy 225.459011 -407.979756)
			(xy 225.4781 -407.988017) (xy 225.4885 -407.988516) (xy 227.066094 -407.988516) (xy 227.076166 -407.98811)
			(xy 227.094765 -407.980378) (xy 227.102162 -407.97353) (xy 228.999288 -406.076404) (xy 229.006117 -406.068995)
			(xy 229.013844 -406.050403) (xy 229.014274 -406.040336) (xy 229.014274 -403.768052) (xy 229.014751 -403.743102)
			(xy 229.02257 -403.693818) (xy 229.037991 -403.646361) (xy 229.060637 -403.601896) (xy 229.089951 -403.561514)
			(xy 229.107238 -403.543516) (xy 229.183692 -403.467062) (xy 229.19054 -403.459668) (xy 229.198255 -403.441064)
			(xy 229.198678 -403.430994) (xy 229.198678 -400.11223) (xy 229.199203 -400.087282) (xy 229.20701 -400.038)
			(xy 229.22242 -399.990544) (xy 229.245055 -399.946077) (xy 229.27436 -399.905693) (xy 229.291642 -399.887694)
			(xy 229.521766 -399.65757) (xy 229.539767 -399.640284) (xy 229.580139 -399.610952) (xy 229.624602 -399.588297)
			(xy 229.672062 -399.572876) (xy 229.721351 -399.56507) (xy 229.746302 -399.564606) (xy 233.352594 -399.564606)
			(xy 233.377543 -399.565108) (xy 233.426826 -399.572919) (xy 233.474284 -399.588334) (xy 233.51875 -399.610975)
			(xy 233.559132 -399.640285) (xy 233.57713 -399.65757) (xy 233.798872 -399.879312) (xy 233.816168 -399.897302)
			(xy 233.845492 -399.937679) (xy 233.868139 -399.982146) (xy 233.883552 -400.029608) (xy 233.89135 -400.078897)
			(xy 233.891836 -400.103848) (xy 233.891836 -403.52091) (xy 233.892247 -403.530981) (xy 233.899977 -403.549579)
			(xy 233.906822 -403.556978) (xy 234.044998 -403.695154) (xy 234.062318 -403.713122) (xy 234.091638 -403.753505)
			(xy 234.114281 -403.797978) (xy 234.129687 -403.845445) (xy 234.13748 -403.894737) (xy 234.137962 -403.91969)
			(xy 234.137962 -404.702518) (xy 234.138361 -404.712591) (xy 234.146098 -404.731189) (xy 234.152948 -404.738586)
			(xy 234.63885 -405.224488) (xy 234.646275 -405.231297) (xy 234.664855 -405.239035) (xy 234.674918 -405.239474)
			(xy 238.514382 -405.239474) (xy 238.524405 -405.239065) (xy 238.542927 -405.231396) (xy 238.557101 -405.21722)
			(xy 238.564767 -405.198697) (xy 238.565182 -405.188674) (xy 238.565182 -394.001498) (xy 238.565686 -393.976549)
			(xy 238.573497 -393.927266) (xy 238.588912 -393.879809) (xy 238.611553 -393.835343) (xy 238.640862 -393.79496)
			(xy 238.658146 -393.776962) (xy 238.727234 -393.707874) (xy 238.733961 -393.700496) (xy 238.741558 -393.682047)
			(xy 238.741546 -393.662096) (xy 238.733929 -393.643656) (xy 238.727234 -393.636246) (xy 238.579914 -393.488672)
			(xy 238.553014 -393.461125) (xy 238.504928 -393.400988) (xy 238.463885 -393.33584) (xy 238.430403 -393.266502)
			(xy 238.404904 -393.193848) (xy 238.387709 -393.118794) (xy 238.379036 -393.042285) (xy 238.378492 -393.003786)
			(xy 238.378492 -384.337306) (xy 238.379215 -384.306679) (xy 238.390978 -384.246564) (xy 238.40186 -384.217926)
			(xy 238.457994 -384.079496) (xy 238.466633 -384.059188) (xy 238.488684 -384.020961) (xy 238.515818 -383.986157)
			(xy 238.5314 -383.97053) (xy 238.583216 -383.920746) (xy 238.583724 -383.920238) (xy 239.05718 -383.446782)
			(xy 239.084743 -383.419899) (xy 239.144878 -383.371812) (xy 239.210023 -383.330768) (xy 239.279359 -383.297284)
			(xy 239.35201 -383.271782) (xy 239.427061 -383.254584) (xy 239.503568 -383.245906) (xy 239.542066 -383.24536)
			(xy 273.481546 -383.24536) (xy 273.512174 -383.24607) (xy 273.572289 -383.257841) (xy 273.600926 -383.268728)
			(xy 273.739356 -383.324862) (xy 273.759667 -383.333494) (xy 273.797892 -383.355549) (xy 273.832695 -383.382685)
			(xy 273.848322 -383.398268) (xy 273.898106 -383.450084) (xy 273.898614 -383.450592) (xy 274.11807 -383.670048)
			(xy 274.141946 -383.69494) (xy 274.148804 -383.70256) (xy 274.167854 -383.71145) (xy 274.251674 -383.713482)
			(xy 274.262067 -383.713236) (xy 274.281342 -383.705512) (xy 274.289012 -383.698496) (xy 274.649184 -383.338324)
			(xy 274.667186 -383.321041) (xy 274.70756 -383.291715) (xy 274.752024 -383.269066) (xy 274.799483 -383.25365)
			(xy 274.84877 -383.245848) (xy 274.87372 -383.24536) (xy 280.202132 -383.24536) (xy 280.227081 -383.245851)
			(xy 280.276364 -383.253667) (xy 280.323821 -383.269085) (xy 280.368287 -383.291728) (xy 280.40867 -383.321039)
			(xy 280.426668 -383.338324) (xy 281.135836 -384.047492) (xy 281.153135 -384.065481) (xy 281.182465 -384.105856)
			(xy 281.205118 -384.150322) (xy 281.220536 -384.197785) (xy 281.228338 -384.247076) (xy 281.2288 -384.272028)
			(xy 281.2288 -384.869944) (xy 287.06878 -384.869944) (xy 287.072752 -384.691701) (xy 287.08466 -384.513812)
			(xy 287.104481 -384.33663) (xy 287.132175 -384.160506) (xy 287.167687 -383.985791) (xy 287.210947 -383.812832)
			(xy 287.261869 -383.641971) (xy 287.320352 -383.473549) (xy 287.386279 -383.307899) (xy 287.45952 -383.14535)
			(xy 287.53993 -382.986225) (xy 287.627348 -382.83084) (xy 287.721601 -382.679504) (xy 287.822502 -382.532516)
			(xy 287.929851 -382.390169) (xy 288.043434 -382.252746) (xy 288.163027 -382.120519) (xy 288.288391 -381.99375)
			(xy 288.419278 -381.872692) (xy 288.555427 -381.757585) (xy 288.696569 -381.648657) (xy 288.842424 -381.546125)
			(xy 288.992701 -381.450191) (xy 289.147102 -381.361048) (xy 289.305321 -381.278871) (xy 289.467044 -381.203823)
			(xy 289.631949 -381.136055) (xy 289.79971 -381.075699) (xy 289.969993 -381.022877) (xy 290.14246 -380.977693)
			(xy 290.316768 -380.940236) (xy 290.492572 -380.910582) (xy 290.669522 -380.888789) (xy 290.847268 -380.874899)
			(xy 291.025455 -380.868942) (xy 291.203732 -380.870928) (xy 291.381743 -380.880854) (xy 291.559135 -380.8987)
			(xy 291.735555 -380.92443) (xy 291.910655 -380.957994) (xy 292.084086 -380.999324) (xy 292.255503 -381.04834)
			(xy 292.424566 -381.104942) (xy 292.590941 -381.16902) (xy 292.754295 -381.240446) (xy 292.914306 -381.319078)
			(xy 293.070655 -381.404759) (xy 293.223032 -381.497321) (xy 293.371135 -381.596578) (xy 293.514669 -381.702335)
			(xy 293.653349 -381.81438) (xy 293.7869 -381.932492) (xy 293.915057 -382.056436) (xy 294.037566 -382.185966)
			(xy 294.154183 -382.320825) (xy 294.194727 -382.372167) (xy 303.739054 -382.372167) (xy 303.739054 -382.317633)
			(xy 303.746815 -382.263654) (xy 303.762179 -382.211329) (xy 303.784833 -382.161723) (xy 303.814317 -382.115846)
			(xy 303.850029 -382.074631) (xy 303.891242 -382.038919) (xy 303.937119 -382.009435) (xy 303.986725 -381.986781)
			(xy 304.03905 -381.971416) (xy 304.093029 -381.963655) (xy 304.120296 -381.963168) (xy 304.983896 -381.963168)
			(xy 305.011169 -381.963571) (xy 305.065161 -381.971334) (xy 305.117498 -381.986701) (xy 305.167116 -382.00936)
			(xy 305.213003 -382.03885) (xy 305.254227 -382.07457) (xy 305.289948 -382.115793) (xy 305.319438 -382.161681)
			(xy 305.342098 -382.211298) (xy 305.357466 -382.263635) (xy 305.365228 -382.317627) (xy 305.365228 -382.372167)
			(xy 310.546254 -382.372167) (xy 310.546254 -382.317633) (xy 310.554015 -382.263654) (xy 310.569379 -382.211329)
			(xy 310.592033 -382.161723) (xy 310.621517 -382.115846) (xy 310.657229 -382.074631) (xy 310.698442 -382.038919)
			(xy 310.744319 -382.009435) (xy 310.793925 -381.986781) (xy 310.84625 -381.971416) (xy 310.900229 -381.963655)
			(xy 310.927496 -381.963168) (xy 311.791096 -381.963168) (xy 311.818369 -381.963571) (xy 311.872361 -381.971334)
			(xy 311.924698 -381.986701) (xy 311.974316 -382.00936) (xy 312.020203 -382.03885) (xy 312.061427 -382.07457)
			(xy 312.097148 -382.115793) (xy 312.126638 -382.161681) (xy 312.149298 -382.211298) (xy 312.164666 -382.263635)
			(xy 312.172428 -382.317627) (xy 312.172428 -382.372167) (xy 317.353454 -382.372167) (xy 317.353454 -382.317633)
			(xy 317.361215 -382.263654) (xy 317.376579 -382.211329) (xy 317.399233 -382.161723) (xy 317.428717 -382.115846)
			(xy 317.464429 -382.074631) (xy 317.505642 -382.038919) (xy 317.551519 -382.009435) (xy 317.601125 -381.986781)
			(xy 317.65345 -381.971416) (xy 317.707429 -381.963655) (xy 317.734696 -381.963168) (xy 318.598296 -381.963168)
			(xy 318.625569 -381.963571) (xy 318.679561 -381.971334) (xy 318.731898 -381.986701) (xy 318.781516 -382.00936)
			(xy 318.827403 -382.03885) (xy 318.868627 -382.07457) (xy 318.904348 -382.115793) (xy 318.933838 -382.161681)
			(xy 318.956498 -382.211298) (xy 318.971866 -382.263635) (xy 318.979628 -382.317627) (xy 318.979628 -382.372171)
			(xy 336.266732 -382.372171) (xy 336.266732 -382.317629) (xy 336.274494 -382.263643) (xy 336.289861 -382.211311)
			(xy 336.312521 -382.161698) (xy 336.34201 -382.115816) (xy 336.377729 -382.074598) (xy 336.418951 -382.038884)
			(xy 336.464837 -382.009399) (xy 336.514452 -381.986746) (xy 336.566786 -381.971385) (xy 336.620773 -381.963628)
			(xy 336.648044 -381.963168) (xy 337.511644 -381.963168) (xy 337.538913 -381.963598) (xy 337.592897 -381.971365)
			(xy 337.645225 -381.986735) (xy 337.694833 -382.009396) (xy 337.740712 -382.038885) (xy 337.781928 -382.074603)
			(xy 337.817641 -382.115823) (xy 337.847125 -382.161705) (xy 337.86978 -382.211316) (xy 337.885144 -382.263647)
			(xy 337.892906 -382.31763) (xy 337.892906 -382.37217) (xy 337.892906 -382.372171) (xy 343.073932 -382.372171)
			(xy 343.073932 -382.317629) (xy 343.081694 -382.263643) (xy 343.097061 -382.211311) (xy 343.119721 -382.161698)
			(xy 343.14921 -382.115816) (xy 343.184929 -382.074598) (xy 343.226151 -382.038884) (xy 343.272037 -382.009399)
			(xy 343.321652 -381.986746) (xy 343.373986 -381.971385) (xy 343.427973 -381.963628) (xy 343.455244 -381.963168)
			(xy 344.318844 -381.963168) (xy 344.346113 -381.963598) (xy 344.400097 -381.971365) (xy 344.452425 -381.986735)
			(xy 344.502033 -382.009396) (xy 344.547912 -382.038885) (xy 344.589128 -382.074603) (xy 344.624841 -382.115823)
			(xy 344.654325 -382.161705) (xy 344.67698 -382.211316) (xy 344.692344 -382.263647) (xy 344.700106 -382.31763)
			(xy 344.700106 -382.37217) (xy 344.700106 -382.372171) (xy 349.881132 -382.372171) (xy 349.881132 -382.317629)
			(xy 349.888894 -382.263643) (xy 349.904261 -382.211311) (xy 349.926921 -382.161698) (xy 349.95641 -382.115816)
			(xy 349.992129 -382.074598) (xy 350.033351 -382.038884) (xy 350.079237 -382.009399) (xy 350.128852 -381.986746)
			(xy 350.181186 -381.971385) (xy 350.235173 -381.963628) (xy 350.262444 -381.963168) (xy 351.126044 -381.963168)
			(xy 351.153313 -381.963598) (xy 351.207297 -381.971365) (xy 351.259625 -381.986735) (xy 351.309233 -382.009396)
			(xy 351.355112 -382.038885) (xy 351.396328 -382.074603) (xy 351.432041 -382.115823) (xy 351.461525 -382.161705)
			(xy 351.48418 -382.211316) (xy 351.499544 -382.263647) (xy 351.507306 -382.31763) (xy 351.507306 -382.372167)
			(xy 370.839254 -382.372167) (xy 370.839254 -382.317633) (xy 370.847015 -382.263654) (xy 370.862379 -382.21133)
			(xy 370.885033 -382.161724) (xy 370.914516 -382.115847) (xy 370.950227 -382.074633) (xy 370.991441 -382.03892)
			(xy 371.037317 -382.009437) (xy 371.086922 -381.986782) (xy 371.139247 -381.971417) (xy 371.193225 -381.963655)
			(xy 371.220492 -381.963168) (xy 372.084092 -381.963168) (xy 372.111366 -381.963571) (xy 372.165357 -381.971333)
			(xy 372.217695 -381.9867) (xy 372.267313 -382.009359) (xy 372.313202 -382.038848) (xy 372.354426 -382.074568)
			(xy 372.390147 -382.115792) (xy 372.419638 -382.16168) (xy 372.442298 -382.211297) (xy 372.457665 -382.263635)
			(xy 372.465428 -382.317626) (xy 372.465428 -382.372167) (xy 377.646454 -382.372167) (xy 377.646454 -382.317633)
			(xy 377.654215 -382.263654) (xy 377.669579 -382.21133) (xy 377.692233 -382.161724) (xy 377.721716 -382.115847)
			(xy 377.757427 -382.074633) (xy 377.798641 -382.03892) (xy 377.844517 -382.009437) (xy 377.894122 -381.986782)
			(xy 377.946447 -381.971417) (xy 378.000425 -381.963655) (xy 378.027692 -381.963168) (xy 378.891292 -381.963168)
			(xy 378.918566 -381.963571) (xy 378.972557 -381.971333) (xy 379.024895 -381.9867) (xy 379.074513 -382.009359)
			(xy 379.120402 -382.038848) (xy 379.161626 -382.074568) (xy 379.197347 -382.115792) (xy 379.226838 -382.16168)
			(xy 379.249498 -382.211297) (xy 379.264865 -382.263635) (xy 379.272628 -382.317626) (xy 379.272628 -382.372167)
			(xy 384.453654 -382.372167) (xy 384.453654 -382.317633) (xy 384.461415 -382.263654) (xy 384.476779 -382.21133)
			(xy 384.499433 -382.161724) (xy 384.528916 -382.115847) (xy 384.564627 -382.074633) (xy 384.605841 -382.03892)
			(xy 384.651717 -382.009437) (xy 384.701322 -381.986782) (xy 384.753647 -381.971417) (xy 384.807625 -381.963655)
			(xy 384.834892 -381.963168) (xy 385.698492 -381.963168) (xy 385.725766 -381.963571) (xy 385.779757 -381.971333)
			(xy 385.832095 -381.9867) (xy 385.881713 -382.009359) (xy 385.927602 -382.038848) (xy 385.968826 -382.074568)
			(xy 386.004547 -382.115792) (xy 386.034038 -382.16168) (xy 386.056698 -382.211297) (xy 386.072065 -382.263635)
			(xy 386.079828 -382.317626) (xy 386.079828 -382.372171) (xy 403.366932 -382.372171) (xy 403.366932 -382.317629)
			(xy 403.374694 -382.263643) (xy 403.390061 -382.211311) (xy 403.41272 -382.161699) (xy 403.442209 -382.115817)
			(xy 403.477928 -382.0746) (xy 403.51915 -382.038885) (xy 403.565035 -382.009401) (xy 403.614649 -381.986747)
			(xy 403.666982 -381.971386) (xy 403.720969 -381.963629) (xy 403.74824 -381.963168) (xy 404.61184 -381.963168)
			(xy 404.63911 -381.963597) (xy 404.693093 -381.971364) (xy 404.745422 -381.986734) (xy 404.795031 -382.009394)
			(xy 404.840911 -382.038884) (xy 404.882127 -382.074602) (xy 404.91784 -382.115822) (xy 404.947325 -382.161704)
			(xy 404.96998 -382.211316) (xy 404.985344 -382.263646) (xy 404.993106 -382.31763) (xy 404.993106 -382.37217)
			(xy 404.993106 -382.372171) (xy 410.174132 -382.372171) (xy 410.174132 -382.317629) (xy 410.181894 -382.263643)
			(xy 410.197261 -382.211311) (xy 410.21992 -382.161699) (xy 410.249409 -382.115817) (xy 410.285128 -382.0746)
			(xy 410.32635 -382.038885) (xy 410.372235 -382.009401) (xy 410.421849 -381.986747) (xy 410.474182 -381.971386)
			(xy 410.528169 -381.963629) (xy 410.55544 -381.963168) (xy 411.41904 -381.963168) (xy 411.44631 -381.963597)
			(xy 411.500293 -381.971364) (xy 411.552622 -381.986734) (xy 411.602231 -382.009394) (xy 411.648111 -382.038884)
			(xy 411.689327 -382.074602) (xy 411.72504 -382.115822) (xy 411.754525 -382.161704) (xy 411.77718 -382.211316)
			(xy 411.792544 -382.263646) (xy 411.800306 -382.31763) (xy 411.800306 -382.37217) (xy 411.800306 -382.372171)
			(xy 416.981332 -382.372171) (xy 416.981332 -382.317629) (xy 416.989094 -382.263643) (xy 417.004461 -382.211311)
			(xy 417.02712 -382.161699) (xy 417.056609 -382.115817) (xy 417.092328 -382.0746) (xy 417.13355 -382.038885)
			(xy 417.179435 -382.009401) (xy 417.229049 -381.986747) (xy 417.281382 -381.971386) (xy 417.335369 -381.963629)
			(xy 417.36264 -381.963168) (xy 418.22624 -381.963168) (xy 418.25351 -381.963597) (xy 418.307493 -381.971364)
			(xy 418.359822 -381.986734) (xy 418.409431 -382.009394) (xy 418.455311 -382.038884) (xy 418.496527 -382.074602)
			(xy 418.53224 -382.115822) (xy 418.561725 -382.161704) (xy 418.58438 -382.211316) (xy 418.599744 -382.263646)
			(xy 418.607506 -382.31763) (xy 418.607506 -382.37217) (xy 418.599744 -382.426154) (xy 418.58438 -382.478484)
			(xy 418.561725 -382.528096) (xy 418.53224 -382.573978) (xy 418.496527 -382.615198) (xy 418.455311 -382.650916)
			(xy 418.409431 -382.680406) (xy 418.359822 -382.703066) (xy 418.307493 -382.718436) (xy 418.25351 -382.726203)
			(xy 418.22624 -382.726692) (xy 417.36264 -382.726692) (xy 417.335369 -382.726171) (xy 417.281382 -382.718414)
			(xy 417.229049 -382.703053) (xy 417.179435 -382.680399) (xy 417.13355 -382.650915) (xy 417.092328 -382.6152)
			(xy 417.056609 -382.573983) (xy 417.02712 -382.528101) (xy 417.004461 -382.478489) (xy 416.989094 -382.426157)
			(xy 416.981332 -382.372171) (xy 411.800306 -382.372171) (xy 411.792544 -382.426154) (xy 411.77718 -382.478484)
			(xy 411.754525 -382.528096) (xy 411.72504 -382.573978) (xy 411.689327 -382.615198) (xy 411.648111 -382.650916)
			(xy 411.602231 -382.680406) (xy 411.552622 -382.703066) (xy 411.500293 -382.718436) (xy 411.44631 -382.726203)
			(xy 411.41904 -382.726692) (xy 410.55544 -382.726692) (xy 410.528169 -382.726171) (xy 410.474182 -382.718414)
			(xy 410.421849 -382.703053) (xy 410.372235 -382.680399) (xy 410.32635 -382.650915) (xy 410.285128 -382.6152)
			(xy 410.249409 -382.573983) (xy 410.21992 -382.528101) (xy 410.197261 -382.478489) (xy 410.181894 -382.426157)
			(xy 410.174132 -382.372171) (xy 404.993106 -382.372171) (xy 404.985344 -382.426154) (xy 404.96998 -382.478484)
			(xy 404.947325 -382.528096) (xy 404.91784 -382.573978) (xy 404.882127 -382.615198) (xy 404.840911 -382.650916)
			(xy 404.795031 -382.680406) (xy 404.745422 -382.703066) (xy 404.693093 -382.718436) (xy 404.63911 -382.726203)
			(xy 404.61184 -382.726692) (xy 403.74824 -382.726692) (xy 403.720969 -382.726171) (xy 403.666982 -382.718414)
			(xy 403.614649 -382.703053) (xy 403.565035 -382.680399) (xy 403.51915 -382.650915) (xy 403.477928 -382.6152)
			(xy 403.442209 -382.573983) (xy 403.41272 -382.528101) (xy 403.390061 -382.478489) (xy 403.374694 -382.426157)
			(xy 403.366932 -382.372171) (xy 386.079828 -382.372171) (xy 386.079828 -382.372174) (xy 386.072065 -382.426165)
			(xy 386.056698 -382.478503) (xy 386.034038 -382.52812) (xy 386.004547 -382.574008) (xy 385.968826 -382.615232)
			(xy 385.927602 -382.650952) (xy 385.881713 -382.680441) (xy 385.832095 -382.7031) (xy 385.779757 -382.718467)
			(xy 385.725766 -382.726229) (xy 385.698492 -382.726692) (xy 384.834892 -382.726692) (xy 384.807625 -382.726145)
			(xy 384.753647 -382.718383) (xy 384.701322 -382.703018) (xy 384.651717 -382.680363) (xy 384.605841 -382.65088)
			(xy 384.564627 -382.615167) (xy 384.528916 -382.573953) (xy 384.499433 -382.528076) (xy 384.476779 -382.47847)
			(xy 384.461415 -382.426146) (xy 384.453654 -382.372167) (xy 379.272628 -382.372167) (xy 379.272628 -382.372174)
			(xy 379.264865 -382.426165) (xy 379.249498 -382.478503) (xy 379.226838 -382.52812) (xy 379.197347 -382.574008)
			(xy 379.161626 -382.615232) (xy 379.120402 -382.650952) (xy 379.074513 -382.680441) (xy 379.024895 -382.7031)
			(xy 378.972557 -382.718467) (xy 378.918566 -382.726229) (xy 378.891292 -382.726692) (xy 378.027692 -382.726692)
			(xy 378.000425 -382.726145) (xy 377.946447 -382.718383) (xy 377.894122 -382.703018) (xy 377.844517 -382.680363)
			(xy 377.798641 -382.65088) (xy 377.757427 -382.615167) (xy 377.721716 -382.573953) (xy 377.692233 -382.528076)
			(xy 377.669579 -382.47847) (xy 377.654215 -382.426146) (xy 377.646454 -382.372167) (xy 372.465428 -382.372167)
			(xy 372.465428 -382.372174) (xy 372.457665 -382.426165) (xy 372.442298 -382.478503) (xy 372.419638 -382.52812)
			(xy 372.390147 -382.574008) (xy 372.354426 -382.615232) (xy 372.313202 -382.650952) (xy 372.267313 -382.680441)
			(xy 372.217695 -382.7031) (xy 372.165357 -382.718467) (xy 372.111366 -382.726229) (xy 372.084092 -382.726692)
			(xy 371.220492 -382.726692) (xy 371.193225 -382.726145) (xy 371.139247 -382.718383) (xy 371.086922 -382.703018)
			(xy 371.037317 -382.680363) (xy 370.991441 -382.65088) (xy 370.950227 -382.615167) (xy 370.914516 -382.573953)
			(xy 370.885033 -382.528076) (xy 370.862379 -382.47847) (xy 370.847015 -382.426146) (xy 370.839254 -382.372167)
			(xy 351.507306 -382.372167) (xy 351.507306 -382.37217) (xy 351.499544 -382.426153) (xy 351.48418 -382.478484)
			(xy 351.461525 -382.528095) (xy 351.432041 -382.573977) (xy 351.396328 -382.615197) (xy 351.355112 -382.650915)
			(xy 351.309233 -382.680404) (xy 351.259625 -382.703065) (xy 351.207297 -382.718435) (xy 351.153313 -382.726202)
			(xy 351.126044 -382.726692) (xy 350.262444 -382.726692) (xy 350.235173 -382.726172) (xy 350.181186 -382.718415)
			(xy 350.128852 -382.703054) (xy 350.079237 -382.680401) (xy 350.033351 -382.650916) (xy 349.992129 -382.615202)
			(xy 349.95641 -382.573984) (xy 349.926921 -382.528102) (xy 349.904261 -382.478489) (xy 349.888894 -382.426157)
			(xy 349.881132 -382.372171) (xy 344.700106 -382.372171) (xy 344.692344 -382.426153) (xy 344.67698 -382.478484)
			(xy 344.654325 -382.528095) (xy 344.624841 -382.573977) (xy 344.589128 -382.615197) (xy 344.547912 -382.650915)
			(xy 344.502033 -382.680404) (xy 344.452425 -382.703065) (xy 344.400097 -382.718435) (xy 344.346113 -382.726202)
			(xy 344.318844 -382.726692) (xy 343.455244 -382.726692) (xy 343.427973 -382.726172) (xy 343.373986 -382.718415)
			(xy 343.321652 -382.703054) (xy 343.272037 -382.680401) (xy 343.226151 -382.650916) (xy 343.184929 -382.615202)
			(xy 343.14921 -382.573984) (xy 343.119721 -382.528102) (xy 343.097061 -382.478489) (xy 343.081694 -382.426157)
			(xy 343.073932 -382.372171) (xy 337.892906 -382.372171) (xy 337.885144 -382.426153) (xy 337.86978 -382.478484)
			(xy 337.847125 -382.528095) (xy 337.817641 -382.573977) (xy 337.781928 -382.615197) (xy 337.740712 -382.650915)
			(xy 337.694833 -382.680404) (xy 337.645225 -382.703065) (xy 337.592897 -382.718435) (xy 337.538913 -382.726202)
			(xy 337.511644 -382.726692) (xy 336.648044 -382.726692) (xy 336.620773 -382.726172) (xy 336.566786 -382.718415)
			(xy 336.514452 -382.703054) (xy 336.464837 -382.680401) (xy 336.418951 -382.650916) (xy 336.377729 -382.615202)
			(xy 336.34201 -382.573984) (xy 336.312521 -382.528102) (xy 336.289861 -382.478489) (xy 336.274494 -382.426157)
			(xy 336.266732 -382.372171) (xy 318.979628 -382.372171) (xy 318.979628 -382.372173) (xy 318.971866 -382.426165)
			(xy 318.956498 -382.478502) (xy 318.933838 -382.528119) (xy 318.904348 -382.574007) (xy 318.868627 -382.61523)
			(xy 318.827403 -382.65095) (xy 318.781516 -382.68044) (xy 318.731898 -382.703099) (xy 318.679561 -382.718466)
			(xy 318.625569 -382.726229) (xy 318.598296 -382.726692) (xy 317.734696 -382.726692) (xy 317.707429 -382.726145)
			(xy 317.65345 -382.718384) (xy 317.601125 -382.703019) (xy 317.551519 -382.680365) (xy 317.505642 -382.650881)
			(xy 317.464429 -382.615169) (xy 317.428717 -382.573954) (xy 317.399233 -382.528077) (xy 317.376579 -382.478471)
			(xy 317.361215 -382.426146) (xy 317.353454 -382.372167) (xy 312.172428 -382.372167) (xy 312.172428 -382.372173)
			(xy 312.164666 -382.426165) (xy 312.149298 -382.478502) (xy 312.126638 -382.528119) (xy 312.097148 -382.574007)
			(xy 312.061427 -382.61523) (xy 312.020203 -382.65095) (xy 311.974316 -382.68044) (xy 311.924698 -382.703099)
			(xy 311.872361 -382.718466) (xy 311.818369 -382.726229) (xy 311.791096 -382.726692) (xy 310.927496 -382.726692)
			(xy 310.900229 -382.726145) (xy 310.84625 -382.718384) (xy 310.793925 -382.703019) (xy 310.744319 -382.680365)
			(xy 310.698442 -382.650881) (xy 310.657229 -382.615169) (xy 310.621517 -382.573954) (xy 310.592033 -382.528077)
			(xy 310.569379 -382.478471) (xy 310.554015 -382.426146) (xy 310.546254 -382.372167) (xy 305.365228 -382.372167)
			(xy 305.365228 -382.372173) (xy 305.357466 -382.426165) (xy 305.342098 -382.478502) (xy 305.319438 -382.528119)
			(xy 305.289948 -382.574007) (xy 305.254227 -382.61523) (xy 305.213003 -382.65095) (xy 305.167116 -382.68044)
			(xy 305.117498 -382.703099) (xy 305.065161 -382.718466) (xy 305.011169 -382.726229) (xy 304.983896 -382.726692)
			(xy 304.120296 -382.726692) (xy 304.093029 -382.726145) (xy 304.03905 -382.718384) (xy 303.986725 -382.703019)
			(xy 303.937119 -382.680365) (xy 303.891242 -382.650881) (xy 303.850029 -382.615169) (xy 303.814317 -382.573954)
			(xy 303.784833 -382.528077) (xy 303.762179 -382.478471) (xy 303.746815 -382.426146) (xy 303.739054 -382.372167)
			(xy 294.194727 -382.372167) (xy 294.264676 -382.460745) (xy 294.368827 -382.605448) (xy 294.466429 -382.754647)
			(xy 294.557287 -382.908046) (xy 294.641221 -383.06534) (xy 294.718066 -383.226216) (xy 294.787667 -383.390357)
			(xy 294.849888 -383.557434) (xy 294.904604 -383.727118) (xy 294.951706 -383.899071) (xy 294.991102 -384.072951)
			(xy 295.022713 -384.248414) (xy 295.046477 -384.42511) (xy 295.062345 -384.60269) (xy 295.070287 -384.7808)
			(xy 295.070784 -384.869944) (xy 295.070287 -384.959088) (xy 295.062345 -385.137198) (xy 295.055495 -385.21386)
			(xy 297.048936 -385.21386) (xy 297.048936 -384.35026) (xy 297.049422 -384.323009) (xy 297.057178 -384.269061)
			(xy 297.072533 -384.216766) (xy 297.095175 -384.167189) (xy 297.124641 -384.121339) (xy 297.160332 -384.080148)
			(xy 297.201523 -384.044457) (xy 297.247373 -384.014991) (xy 297.29695 -383.992349) (xy 297.349245 -383.976994)
			(xy 297.403193 -383.969238) (xy 297.457695 -383.969238) (xy 297.511643 -383.976994) (xy 297.563938 -383.992349)
			(xy 297.613515 -384.014991) (xy 297.659365 -384.044457) (xy 297.700556 -384.080148) (xy 297.736247 -384.121339)
			(xy 297.765713 -384.167189) (xy 297.788355 -384.216766) (xy 297.80371 -384.269061) (xy 297.811466 -384.323009)
			(xy 297.811952 -384.35026) (xy 297.811952 -385.21386) (xy 297.811466 -385.241111) (xy 297.80371 -385.295059)
			(xy 297.790858 -385.338828) (xy 326.895968 -385.338828) (xy 326.895968 -384.475228) (xy 326.896454 -384.447977)
			(xy 326.90421 -384.394029) (xy 326.919565 -384.341734) (xy 326.942207 -384.292157) (xy 326.971673 -384.246307)
			(xy 327.007364 -384.205116) (xy 327.048555 -384.169425) (xy 327.094405 -384.139959) (xy 327.143982 -384.117317)
			(xy 327.196277 -384.101962) (xy 327.250225 -384.094206) (xy 327.304727 -384.094206) (xy 327.358675 -384.101962)
			(xy 327.41097 -384.117317) (xy 327.460547 -384.139959) (xy 327.506397 -384.169425) (xy 327.547588 -384.205116)
			(xy 327.583279 -384.246307) (xy 327.612745 -384.292157) (xy 327.635387 -384.341734) (xy 327.650742 -384.394029)
			(xy 327.658498 -384.447977) (xy 327.658984 -384.475228) (xy 327.658984 -385.21386) (xy 329.576684 -385.21386)
			(xy 329.576684 -384.35026) (xy 329.57717 -384.323009) (xy 329.584926 -384.269061) (xy 329.600281 -384.216766)
			(xy 329.622923 -384.167189) (xy 329.652389 -384.121339) (xy 329.68808 -384.080148) (xy 329.729271 -384.044457)
			(xy 329.775121 -384.014991) (xy 329.824698 -383.992349) (xy 329.876993 -383.976994) (xy 329.930941 -383.969238)
			(xy 329.985443 -383.969238) (xy 330.039391 -383.976994) (xy 330.091686 -383.992349) (xy 330.141263 -384.014991)
			(xy 330.187113 -384.044457) (xy 330.228304 -384.080148) (xy 330.263995 -384.121339) (xy 330.293461 -384.167189)
			(xy 330.316103 -384.216766) (xy 330.331458 -384.269061) (xy 330.339214 -384.323009) (xy 330.3397 -384.35026)
			(xy 330.3397 -385.21386) (xy 330.339214 -385.241111) (xy 330.331458 -385.295059) (xy 330.318606 -385.338828)
			(xy 359.423716 -385.338828) (xy 359.423716 -384.475228) (xy 359.424202 -384.447977) (xy 359.431958 -384.394029)
			(xy 359.447313 -384.341734) (xy 359.469955 -384.292157) (xy 359.499421 -384.246307) (xy 359.535112 -384.205116)
			(xy 359.576303 -384.169425) (xy 359.622153 -384.139959) (xy 359.67173 -384.117317) (xy 359.724025 -384.101962)
			(xy 359.777973 -384.094206) (xy 359.832475 -384.094206) (xy 359.886423 -384.101962) (xy 359.938718 -384.117317)
			(xy 359.988295 -384.139959) (xy 360.034145 -384.169425) (xy 360.075336 -384.205116) (xy 360.111027 -384.246307)
			(xy 360.140493 -384.292157) (xy 360.163135 -384.341734) (xy 360.17849 -384.394029) (xy 360.186246 -384.447977)
			(xy 360.186732 -384.475228) (xy 360.186732 -385.21386) (xy 364.149132 -385.21386) (xy 364.149132 -384.35026)
			(xy 364.149618 -384.323009) (xy 364.157374 -384.269061) (xy 364.172729 -384.216766) (xy 364.195371 -384.167189)
			(xy 364.224837 -384.121339) (xy 364.260528 -384.080148) (xy 364.301719 -384.044457) (xy 364.347569 -384.014991)
			(xy 364.397146 -383.992349) (xy 364.449441 -383.976994) (xy 364.503389 -383.969238) (xy 364.557891 -383.969238)
			(xy 364.611839 -383.976994) (xy 364.664134 -383.992349) (xy 364.713711 -384.014991) (xy 364.759561 -384.044457)
			(xy 364.800752 -384.080148) (xy 364.836443 -384.121339) (xy 364.865909 -384.167189) (xy 364.888551 -384.216766)
			(xy 364.903906 -384.269061) (xy 364.911662 -384.323009) (xy 364.912148 -384.35026) (xy 364.912148 -385.21386)
			(xy 364.911662 -385.241111) (xy 364.903906 -385.295059) (xy 364.891054 -385.338828) (xy 393.996164 -385.338828)
			(xy 393.996164 -384.475228) (xy 393.99665 -384.447977) (xy 394.004406 -384.394029) (xy 394.019761 -384.341734)
			(xy 394.042403 -384.292157) (xy 394.071869 -384.246307) (xy 394.10756 -384.205116) (xy 394.148751 -384.169425)
			(xy 394.194601 -384.139959) (xy 394.244178 -384.117317) (xy 394.296473 -384.101962) (xy 394.350421 -384.094206)
			(xy 394.404923 -384.094206) (xy 394.458871 -384.101962) (xy 394.511166 -384.117317) (xy 394.560743 -384.139959)
			(xy 394.606593 -384.169425) (xy 394.647784 -384.205116) (xy 394.683475 -384.246307) (xy 394.712941 -384.292157)
			(xy 394.735583 -384.341734) (xy 394.750938 -384.394029) (xy 394.758694 -384.447977) (xy 394.75918 -384.475228)
			(xy 394.75918 -385.21386) (xy 396.67688 -385.21386) (xy 396.67688 -384.35026) (xy 396.677366 -384.323009)
			(xy 396.685122 -384.269061) (xy 396.700477 -384.216766) (xy 396.723119 -384.167189) (xy 396.752585 -384.121339)
			(xy 396.788276 -384.080148) (xy 396.829467 -384.044457) (xy 396.875317 -384.014991) (xy 396.924894 -383.992349)
			(xy 396.977189 -383.976994) (xy 397.031137 -383.969238) (xy 397.085639 -383.969238) (xy 397.139587 -383.976994)
			(xy 397.191882 -383.992349) (xy 397.241459 -384.014991) (xy 397.287309 -384.044457) (xy 397.3285 -384.080148)
			(xy 397.364191 -384.121339) (xy 397.393657 -384.167189) (xy 397.416299 -384.216766) (xy 397.431654 -384.269061)
			(xy 397.43941 -384.323009) (xy 397.439896 -384.35026) (xy 397.439896 -385.21386) (xy 397.43941 -385.241111)
			(xy 397.431654 -385.295059) (xy 397.418802 -385.338828) (xy 426.523912 -385.338828) (xy 426.523912 -384.475228)
			(xy 426.524398 -384.447977) (xy 426.532154 -384.394029) (xy 426.547509 -384.341734) (xy 426.570151 -384.292157)
			(xy 426.599617 -384.246307) (xy 426.635308 -384.205116) (xy 426.676499 -384.169425) (xy 426.722349 -384.139959)
			(xy 426.771926 -384.117317) (xy 426.824221 -384.101962) (xy 426.878169 -384.094206) (xy 426.932671 -384.094206)
			(xy 426.986619 -384.101962) (xy 427.038914 -384.117317) (xy 427.088491 -384.139959) (xy 427.134341 -384.169425)
			(xy 427.175532 -384.205116) (xy 427.211223 -384.246307) (xy 427.240689 -384.292157) (xy 427.263331 -384.341734)
			(xy 427.278686 -384.394029) (xy 427.286442 -384.447977) (xy 427.286928 -384.475228) (xy 427.286928 -384.869944)
			(xy 429.498772 -384.869944) (xy 429.502744 -384.691701) (xy 429.514652 -384.513812) (xy 429.534473 -384.33663)
			(xy 429.562167 -384.160506) (xy 429.597679 -383.985791) (xy 429.640939 -383.812832) (xy 429.691861 -383.641971)
			(xy 429.750344 -383.473549) (xy 429.816271 -383.307899) (xy 429.889512 -383.14535) (xy 429.969922 -382.986225)
			(xy 430.05734 -382.83084) (xy 430.151593 -382.679504) (xy 430.252494 -382.532516) (xy 430.359843 -382.390169)
			(xy 430.473426 -382.252746) (xy 430.593019 -382.120519) (xy 430.718383 -381.99375) (xy 430.84927 -381.872692)
			(xy 430.985419 -381.757585) (xy 431.126561 -381.648657) (xy 431.272416 -381.546125) (xy 431.422693 -381.450191)
			(xy 431.577094 -381.361048) (xy 431.735313 -381.278871) (xy 431.897036 -381.203823) (xy 432.061941 -381.136055)
			(xy 432.229702 -381.075699) (xy 432.399985 -381.022877) (xy 432.572452 -380.977693) (xy 432.74676 -380.940236)
			(xy 432.922564 -380.910582) (xy 433.099514 -380.888789) (xy 433.27726 -380.874899) (xy 433.455447 -380.868942)
			(xy 433.633724 -380.870928) (xy 433.811735 -380.880854) (xy 433.989127 -380.8987) (xy 434.165547 -380.92443)
			(xy 434.340647 -380.957994) (xy 434.514078 -380.999324) (xy 434.685495 -381.04834) (xy 434.854558 -381.104942)
			(xy 435.020933 -381.16902) (xy 435.184287 -381.240446) (xy 435.344298 -381.319078) (xy 435.500647 -381.404759)
			(xy 435.653024 -381.497321) (xy 435.801127 -381.596578) (xy 435.944661 -381.702335) (xy 436.083341 -381.81438)
			(xy 436.216892 -381.932492) (xy 436.345049 -382.056436) (xy 436.467558 -382.185966) (xy 436.584175 -382.320825)
			(xy 436.694668 -382.460745) (xy 436.798819 -382.605448) (xy 436.896421 -382.754647) (xy 436.987279 -382.908046)
			(xy 437.071213 -383.06534) (xy 437.148058 -383.226216) (xy 437.217659 -383.390357) (xy 437.27988 -383.557434)
			(xy 437.334596 -383.727118) (xy 437.381698 -383.899071) (xy 437.421094 -384.072951) (xy 437.452705 -384.248414)
			(xy 437.476469 -384.42511) (xy 437.492337 -384.60269) (xy 437.500279 -384.7808) (xy 437.500776 -384.869944)
			(xy 437.500279 -384.959088) (xy 437.492337 -385.137198) (xy 437.476469 -385.314778) (xy 437.452705 -385.491474)
			(xy 437.421094 -385.666937) (xy 437.381698 -385.840817) (xy 437.334596 -386.01277) (xy 437.27988 -386.182454)
			(xy 437.217659 -386.349531) (xy 437.148058 -386.513672) (xy 437.071213 -386.674548) (xy 436.987279 -386.831842)
			(xy 436.896421 -386.985241) (xy 436.798819 -387.13444) (xy 436.694668 -387.279143) (xy 436.584175 -387.419063)
			(xy 436.467558 -387.553922) (xy 436.345049 -387.683452) (xy 436.216892 -387.807396) (xy 436.083341 -387.925508)
			(xy 435.944661 -388.037553) (xy 435.801127 -388.14331) (xy 435.653024 -388.242567) (xy 435.500647 -388.335129)
			(xy 435.344298 -388.42081) (xy 435.184287 -388.499442) (xy 435.020933 -388.570868) (xy 434.854558 -388.634946)
			(xy 434.685495 -388.691548) (xy 434.514078 -388.740564) (xy 434.340647 -388.781894) (xy 434.165547 -388.815458)
			(xy 433.989127 -388.841188) (xy 433.811735 -388.859034) (xy 433.633724 -388.86896) (xy 433.455447 -388.870946)
			(xy 433.27726 -388.864989) (xy 433.099514 -388.851099) (xy 432.922564 -388.829306) (xy 432.74676 -388.799652)
			(xy 432.572452 -388.762195) (xy 432.399985 -388.717011) (xy 432.229702 -388.664189) (xy 432.061941 -388.603833)
			(xy 431.897036 -388.536065) (xy 431.735313 -388.461017) (xy 431.577094 -388.37884) (xy 431.422693 -388.289697)
			(xy 431.272416 -388.193763) (xy 431.126561 -388.091231) (xy 430.985419 -387.982303) (xy 430.84927 -387.867196)
			(xy 430.718383 -387.746138) (xy 430.593019 -387.619369) (xy 430.473426 -387.487142) (xy 430.359843 -387.349719)
			(xy 430.252494 -387.207372) (xy 430.151593 -387.060384) (xy 430.05734 -386.909048) (xy 429.969922 -386.753663)
			(xy 429.889512 -386.594538) (xy 429.816271 -386.431989) (xy 429.750344 -386.266339) (xy 429.691861 -386.097917)
			(xy 429.640939 -385.927056) (xy 429.597679 -385.754097) (xy 429.562167 -385.579382) (xy 429.534473 -385.403258)
			(xy 429.514652 -385.226076) (xy 429.502744 -385.048187) (xy 429.498772 -384.869944) (xy 427.286928 -384.869944)
			(xy 427.286928 -385.338828) (xy 427.286442 -385.366079) (xy 427.278686 -385.420027) (xy 427.263331 -385.472322)
			(xy 427.240689 -385.521899) (xy 427.211223 -385.567749) (xy 427.175532 -385.60894) (xy 427.134341 -385.644631)
			(xy 427.088491 -385.674097) (xy 427.038914 -385.696739) (xy 426.986619 -385.712094) (xy 426.932671 -385.71985)
			(xy 426.878169 -385.71985) (xy 426.824221 -385.712094) (xy 426.771926 -385.696739) (xy 426.722349 -385.674097)
			(xy 426.676499 -385.644631) (xy 426.635308 -385.60894) (xy 426.599617 -385.567749) (xy 426.570151 -385.521899)
			(xy 426.547509 -385.472322) (xy 426.532154 -385.420027) (xy 426.524398 -385.366079) (xy 426.523912 -385.338828)
			(xy 397.418802 -385.338828) (xy 397.416299 -385.347354) (xy 397.393657 -385.396931) (xy 397.364191 -385.442781)
			(xy 397.3285 -385.483972) (xy 397.287309 -385.519663) (xy 397.241459 -385.549129) (xy 397.191882 -385.571771)
			(xy 397.139587 -385.587126) (xy 397.085639 -385.594882) (xy 397.031137 -385.594882) (xy 396.977189 -385.587126)
			(xy 396.924894 -385.571771) (xy 396.875317 -385.549129) (xy 396.829467 -385.519663) (xy 396.788276 -385.483972)
			(xy 396.752585 -385.442781) (xy 396.723119 -385.396931) (xy 396.700477 -385.347354) (xy 396.685122 -385.295059)
			(xy 396.677366 -385.241111) (xy 396.67688 -385.21386) (xy 394.75918 -385.21386) (xy 394.75918 -385.338828)
			(xy 394.758694 -385.366079) (xy 394.750938 -385.420027) (xy 394.735583 -385.472322) (xy 394.712941 -385.521899)
			(xy 394.683475 -385.567749) (xy 394.647784 -385.60894) (xy 394.606593 -385.644631) (xy 394.560743 -385.674097)
			(xy 394.511166 -385.696739) (xy 394.458871 -385.712094) (xy 394.404923 -385.71985) (xy 394.350421 -385.71985)
			(xy 394.296473 -385.712094) (xy 394.244178 -385.696739) (xy 394.194601 -385.674097) (xy 394.148751 -385.644631)
			(xy 394.10756 -385.60894) (xy 394.071869 -385.567749) (xy 394.042403 -385.521899) (xy 394.019761 -385.472322)
			(xy 394.004406 -385.420027) (xy 393.99665 -385.366079) (xy 393.996164 -385.338828) (xy 364.891054 -385.338828)
			(xy 364.888551 -385.347354) (xy 364.865909 -385.396931) (xy 364.836443 -385.442781) (xy 364.800752 -385.483972)
			(xy 364.759561 -385.519663) (xy 364.713711 -385.549129) (xy 364.664134 -385.571771) (xy 364.611839 -385.587126)
			(xy 364.557891 -385.594882) (xy 364.503389 -385.594882) (xy 364.449441 -385.587126) (xy 364.397146 -385.571771)
			(xy 364.347569 -385.549129) (xy 364.301719 -385.519663) (xy 364.260528 -385.483972) (xy 364.224837 -385.442781)
			(xy 364.195371 -385.396931) (xy 364.172729 -385.347354) (xy 364.157374 -385.295059) (xy 364.149618 -385.241111)
			(xy 364.149132 -385.21386) (xy 360.186732 -385.21386) (xy 360.186732 -385.338828) (xy 360.186246 -385.366079)
			(xy 360.17849 -385.420027) (xy 360.163135 -385.472322) (xy 360.140493 -385.521899) (xy 360.111027 -385.567749)
			(xy 360.075336 -385.60894) (xy 360.034145 -385.644631) (xy 359.988295 -385.674097) (xy 359.938718 -385.696739)
			(xy 359.886423 -385.712094) (xy 359.832475 -385.71985) (xy 359.777973 -385.71985) (xy 359.724025 -385.712094)
			(xy 359.67173 -385.696739) (xy 359.622153 -385.674097) (xy 359.576303 -385.644631) (xy 359.535112 -385.60894)
			(xy 359.499421 -385.567749) (xy 359.469955 -385.521899) (xy 359.447313 -385.472322) (xy 359.431958 -385.420027)
			(xy 359.424202 -385.366079) (xy 359.423716 -385.338828) (xy 330.318606 -385.338828) (xy 330.316103 -385.347354)
			(xy 330.293461 -385.396931) (xy 330.263995 -385.442781) (xy 330.228304 -385.483972) (xy 330.187113 -385.519663)
			(xy 330.141263 -385.549129) (xy 330.091686 -385.571771) (xy 330.039391 -385.587126) (xy 329.985443 -385.594882)
			(xy 329.930941 -385.594882) (xy 329.876993 -385.587126) (xy 329.824698 -385.571771) (xy 329.775121 -385.549129)
			(xy 329.729271 -385.519663) (xy 329.68808 -385.483972) (xy 329.652389 -385.442781) (xy 329.622923 -385.396931)
			(xy 329.600281 -385.347354) (xy 329.584926 -385.295059) (xy 329.57717 -385.241111) (xy 329.576684 -385.21386)
			(xy 327.658984 -385.21386) (xy 327.658984 -385.338828) (xy 327.658498 -385.366079) (xy 327.650742 -385.420027)
			(xy 327.635387 -385.472322) (xy 327.612745 -385.521899) (xy 327.583279 -385.567749) (xy 327.547588 -385.60894)
			(xy 327.506397 -385.644631) (xy 327.460547 -385.674097) (xy 327.41097 -385.696739) (xy 327.358675 -385.712094)
			(xy 327.304727 -385.71985) (xy 327.250225 -385.71985) (xy 327.196277 -385.712094) (xy 327.143982 -385.696739)
			(xy 327.094405 -385.674097) (xy 327.048555 -385.644631) (xy 327.007364 -385.60894) (xy 326.971673 -385.567749)
			(xy 326.942207 -385.521899) (xy 326.919565 -385.472322) (xy 326.90421 -385.420027) (xy 326.896454 -385.366079)
			(xy 326.895968 -385.338828) (xy 297.790858 -385.338828) (xy 297.788355 -385.347354) (xy 297.765713 -385.396931)
			(xy 297.736247 -385.442781) (xy 297.700556 -385.483972) (xy 297.659365 -385.519663) (xy 297.613515 -385.549129)
			(xy 297.563938 -385.571771) (xy 297.511643 -385.587126) (xy 297.457695 -385.594882) (xy 297.403193 -385.594882)
			(xy 297.349245 -385.587126) (xy 297.29695 -385.571771) (xy 297.247373 -385.549129) (xy 297.201523 -385.519663)
			(xy 297.160332 -385.483972) (xy 297.124641 -385.442781) (xy 297.095175 -385.396931) (xy 297.072533 -385.347354)
			(xy 297.057178 -385.295059) (xy 297.049422 -385.241111) (xy 297.048936 -385.21386) (xy 295.055495 -385.21386)
			(xy 295.046477 -385.314778) (xy 295.022713 -385.491474) (xy 294.991102 -385.666937) (xy 294.951706 -385.840817)
			(xy 294.904604 -386.01277) (xy 294.849888 -386.182454) (xy 294.787667 -386.349531) (xy 294.718066 -386.513672)
			(xy 294.641221 -386.674548) (xy 294.557287 -386.831842) (xy 294.466429 -386.985241) (xy 294.368827 -387.13444)
			(xy 294.264676 -387.279143) (xy 294.154183 -387.419063) (xy 294.037566 -387.553922) (xy 293.915057 -387.683452)
			(xy 293.7869 -387.807396) (xy 293.653349 -387.925508) (xy 293.514669 -388.037553) (xy 293.371135 -388.14331)
			(xy 293.223032 -388.242567) (xy 293.070655 -388.335129) (xy 292.914306 -388.42081) (xy 292.754295 -388.499442)
			(xy 292.590941 -388.570868) (xy 292.424566 -388.634946) (xy 292.255503 -388.691548) (xy 292.084086 -388.740564)
			(xy 292.076264 -388.742428) (xy 326.895968 -388.742428) (xy 326.895968 -387.878828) (xy 326.896454 -387.851577)
			(xy 326.90421 -387.797629) (xy 326.919565 -387.745334) (xy 326.942207 -387.695757) (xy 326.971673 -387.649907)
			(xy 327.007364 -387.608716) (xy 327.048555 -387.573025) (xy 327.094405 -387.543559) (xy 327.143982 -387.520917)
			(xy 327.196277 -387.505562) (xy 327.250225 -387.497806) (xy 327.304727 -387.497806) (xy 327.358675 -387.505562)
			(xy 327.41097 -387.520917) (xy 327.460547 -387.543559) (xy 327.506397 -387.573025) (xy 327.547588 -387.608716)
			(xy 327.583279 -387.649907) (xy 327.612745 -387.695757) (xy 327.635387 -387.745334) (xy 327.650742 -387.797629)
			(xy 327.658498 -387.851577) (xy 327.658984 -387.878828) (xy 327.658984 -388.742428) (xy 359.423716 -388.742428)
			(xy 359.423716 -387.878828) (xy 359.424202 -387.851577) (xy 359.431958 -387.797629) (xy 359.447313 -387.745334)
			(xy 359.469955 -387.695757) (xy 359.499421 -387.649907) (xy 359.535112 -387.608716) (xy 359.576303 -387.573025)
			(xy 359.622153 -387.543559) (xy 359.67173 -387.520917) (xy 359.724025 -387.505562) (xy 359.777973 -387.497806)
			(xy 359.832475 -387.497806) (xy 359.886423 -387.505562) (xy 359.938718 -387.520917) (xy 359.988295 -387.543559)
			(xy 360.034145 -387.573025) (xy 360.075336 -387.608716) (xy 360.111027 -387.649907) (xy 360.140493 -387.695757)
			(xy 360.163135 -387.745334) (xy 360.17849 -387.797629) (xy 360.186246 -387.851577) (xy 360.186732 -387.878828)
			(xy 360.186732 -388.742428) (xy 393.996164 -388.742428) (xy 393.996164 -387.878828) (xy 393.99665 -387.851577)
			(xy 394.004406 -387.797629) (xy 394.019761 -387.745334) (xy 394.042403 -387.695757) (xy 394.071869 -387.649907)
			(xy 394.10756 -387.608716) (xy 394.148751 -387.573025) (xy 394.194601 -387.543559) (xy 394.244178 -387.520917)
			(xy 394.296473 -387.505562) (xy 394.350421 -387.497806) (xy 394.404923 -387.497806) (xy 394.458871 -387.505562)
			(xy 394.511166 -387.520917) (xy 394.560743 -387.543559) (xy 394.606593 -387.573025) (xy 394.647784 -387.608716)
			(xy 394.683475 -387.649907) (xy 394.712941 -387.695757) (xy 394.735583 -387.745334) (xy 394.750938 -387.797629)
			(xy 394.758694 -387.851577) (xy 394.75918 -387.878828) (xy 394.75918 -388.742428) (xy 426.523912 -388.742428)
			(xy 426.523912 -387.878828) (xy 426.524398 -387.851577) (xy 426.532154 -387.797629) (xy 426.547509 -387.745334)
			(xy 426.570151 -387.695757) (xy 426.599617 -387.649907) (xy 426.635308 -387.608716) (xy 426.676499 -387.573025)
			(xy 426.722349 -387.543559) (xy 426.771926 -387.520917) (xy 426.824221 -387.505562) (xy 426.878169 -387.497806)
			(xy 426.932671 -387.497806) (xy 426.986619 -387.505562) (xy 427.038914 -387.520917) (xy 427.088491 -387.543559)
			(xy 427.134341 -387.573025) (xy 427.175532 -387.608716) (xy 427.211223 -387.649907) (xy 427.240689 -387.695757)
			(xy 427.263331 -387.745334) (xy 427.278686 -387.797629) (xy 427.286442 -387.851577) (xy 427.286928 -387.878828)
			(xy 427.286928 -388.742428) (xy 427.286442 -388.769679) (xy 427.278686 -388.823627) (xy 427.263331 -388.875922)
			(xy 427.240689 -388.925499) (xy 427.211223 -388.971349) (xy 427.175532 -389.01254) (xy 427.134341 -389.048231)
			(xy 427.088491 -389.077697) (xy 427.038914 -389.100339) (xy 426.986619 -389.115694) (xy 426.932671 -389.12345)
			(xy 426.878169 -389.12345) (xy 426.824221 -389.115694) (xy 426.771926 -389.100339) (xy 426.722349 -389.077697)
			(xy 426.676499 -389.048231) (xy 426.635308 -389.01254) (xy 426.599617 -388.971349) (xy 426.570151 -388.925499)
			(xy 426.547509 -388.875922) (xy 426.532154 -388.823627) (xy 426.524398 -388.769679) (xy 426.523912 -388.742428)
			(xy 394.75918 -388.742428) (xy 394.758694 -388.769679) (xy 394.750938 -388.823627) (xy 394.735583 -388.875922)
			(xy 394.712941 -388.925499) (xy 394.683475 -388.971349) (xy 394.647784 -389.01254) (xy 394.606593 -389.048231)
			(xy 394.560743 -389.077697) (xy 394.511166 -389.100339) (xy 394.458871 -389.115694) (xy 394.404923 -389.12345)
			(xy 394.350421 -389.12345) (xy 394.296473 -389.115694) (xy 394.244178 -389.100339) (xy 394.194601 -389.077697)
			(xy 394.148751 -389.048231) (xy 394.10756 -389.01254) (xy 394.071869 -388.971349) (xy 394.042403 -388.925499)
			(xy 394.019761 -388.875922) (xy 394.004406 -388.823627) (xy 393.99665 -388.769679) (xy 393.996164 -388.742428)
			(xy 360.186732 -388.742428) (xy 360.186246 -388.769679) (xy 360.17849 -388.823627) (xy 360.163135 -388.875922)
			(xy 360.140493 -388.925499) (xy 360.111027 -388.971349) (xy 360.075336 -389.01254) (xy 360.034145 -389.048231)
			(xy 359.988295 -389.077697) (xy 359.938718 -389.100339) (xy 359.886423 -389.115694) (xy 359.832475 -389.12345)
			(xy 359.777973 -389.12345) (xy 359.724025 -389.115694) (xy 359.67173 -389.100339) (xy 359.622153 -389.077697)
			(xy 359.576303 -389.048231) (xy 359.535112 -389.01254) (xy 359.499421 -388.971349) (xy 359.469955 -388.925499)
			(xy 359.447313 -388.875922) (xy 359.431958 -388.823627) (xy 359.424202 -388.769679) (xy 359.423716 -388.742428)
			(xy 327.658984 -388.742428) (xy 327.658498 -388.769679) (xy 327.650742 -388.823627) (xy 327.635387 -388.875922)
			(xy 327.612745 -388.925499) (xy 327.583279 -388.971349) (xy 327.547588 -389.01254) (xy 327.506397 -389.048231)
			(xy 327.460547 -389.077697) (xy 327.41097 -389.100339) (xy 327.358675 -389.115694) (xy 327.304727 -389.12345)
			(xy 327.250225 -389.12345) (xy 327.196277 -389.115694) (xy 327.143982 -389.100339) (xy 327.094405 -389.077697)
			(xy 327.048555 -389.048231) (xy 327.007364 -389.01254) (xy 326.971673 -388.971349) (xy 326.942207 -388.925499)
			(xy 326.919565 -388.875922) (xy 326.90421 -388.823627) (xy 326.896454 -388.769679) (xy 326.895968 -388.742428)
			(xy 292.076264 -388.742428) (xy 291.910655 -388.781894) (xy 291.735555 -388.815458) (xy 291.559135 -388.841188)
			(xy 291.381743 -388.859034) (xy 291.203732 -388.86896) (xy 291.025455 -388.870946) (xy 290.847268 -388.864989)
			(xy 290.669522 -388.851099) (xy 290.492572 -388.829306) (xy 290.316768 -388.799652) (xy 290.14246 -388.762195)
			(xy 289.969993 -388.717011) (xy 289.79971 -388.664189) (xy 289.631949 -388.603833) (xy 289.467044 -388.536065)
			(xy 289.305321 -388.461017) (xy 289.147102 -388.37884) (xy 288.992701 -388.289697) (xy 288.842424 -388.193763)
			(xy 288.696569 -388.091231) (xy 288.555427 -387.982303) (xy 288.419278 -387.867196) (xy 288.288391 -387.746138)
			(xy 288.163027 -387.619369) (xy 288.043434 -387.487142) (xy 287.929851 -387.349719) (xy 287.822502 -387.207372)
			(xy 287.721601 -387.060384) (xy 287.627348 -386.909048) (xy 287.53993 -386.753663) (xy 287.45952 -386.594538)
			(xy 287.386279 -386.431989) (xy 287.320352 -386.266339) (xy 287.261869 -386.097917) (xy 287.210947 -385.927056)
			(xy 287.167687 -385.754097) (xy 287.132175 -385.579382) (xy 287.104481 -385.403258) (xy 287.08466 -385.226076)
			(xy 287.072752 -385.048187) (xy 287.06878 -384.869944) (xy 281.2288 -384.869944) (xy 281.2288 -387.375146)
			(xy 281.245056 -387.400292) (xy 281.258772 -387.406388) (xy 281.283524 -387.41805) (xy 281.329666 -387.447457)
			(xy 281.371135 -387.483154) (xy 281.407078 -387.524408) (xy 281.43676 -387.570374) (xy 281.45957 -387.620109)
			(xy 281.475042 -387.672592) (xy 281.482858 -387.726748) (xy 281.482857 -387.781464) (xy 281.47504 -387.835619)
			(xy 281.459566 -387.888102) (xy 281.436754 -387.937836) (xy 281.407071 -387.983801) (xy 281.371126 -388.025055)
			(xy 281.329657 -388.06075) (xy 281.283514 -388.090155) (xy 281.258772 -388.10184) (xy 281.245056 -388.107936)
			(xy 281.2288 -388.133082) (xy 281.2288 -390.75106) (xy 297.048936 -390.75106) (xy 297.048936 -389.88746)
			(xy 297.049422 -389.860209) (xy 297.057178 -389.806261) (xy 297.072533 -389.753966) (xy 297.095175 -389.704389)
			(xy 297.124641 -389.658539) (xy 297.160332 -389.617348) (xy 297.201523 -389.581657) (xy 297.247373 -389.552191)
			(xy 297.29695 -389.529549) (xy 297.349245 -389.514194) (xy 297.403193 -389.506438) (xy 297.457695 -389.506438)
			(xy 297.511643 -389.514194) (xy 297.563938 -389.529549) (xy 297.613515 -389.552191) (xy 297.659365 -389.581657)
			(xy 297.700556 -389.617348) (xy 297.736247 -389.658539) (xy 297.765713 -389.704389) (xy 297.788355 -389.753966)
			(xy 297.80371 -389.806261) (xy 297.811466 -389.860209) (xy 297.811952 -389.88746) (xy 297.811952 -390.75106)
			(xy 329.576684 -390.75106) (xy 329.576684 -389.88746) (xy 329.57717 -389.860209) (xy 329.584926 -389.806261)
			(xy 329.600281 -389.753966) (xy 329.622923 -389.704389) (xy 329.652389 -389.658539) (xy 329.68808 -389.617348)
			(xy 329.729271 -389.581657) (xy 329.775121 -389.552191) (xy 329.824698 -389.529549) (xy 329.876993 -389.514194)
			(xy 329.930941 -389.506438) (xy 329.985443 -389.506438) (xy 330.039391 -389.514194) (xy 330.091686 -389.529549)
			(xy 330.141263 -389.552191) (xy 330.187113 -389.581657) (xy 330.228304 -389.617348) (xy 330.263995 -389.658539)
			(xy 330.293461 -389.704389) (xy 330.316103 -389.753966) (xy 330.331458 -389.806261) (xy 330.339214 -389.860209)
			(xy 330.3397 -389.88746) (xy 330.3397 -390.75106) (xy 364.149132 -390.75106) (xy 364.149132 -389.88746)
			(xy 364.149618 -389.860209) (xy 364.157374 -389.806261) (xy 364.172729 -389.753966) (xy 364.195371 -389.704389)
			(xy 364.224837 -389.658539) (xy 364.260528 -389.617348) (xy 364.301719 -389.581657) (xy 364.347569 -389.552191)
			(xy 364.397146 -389.529549) (xy 364.449441 -389.514194) (xy 364.503389 -389.506438) (xy 364.557891 -389.506438)
			(xy 364.611839 -389.514194) (xy 364.664134 -389.529549) (xy 364.713711 -389.552191) (xy 364.759561 -389.581657)
			(xy 364.800752 -389.617348) (xy 364.836443 -389.658539) (xy 364.865909 -389.704389) (xy 364.888551 -389.753966)
			(xy 364.903906 -389.806261) (xy 364.911662 -389.860209) (xy 364.912148 -389.88746) (xy 364.912148 -390.75106)
			(xy 396.67688 -390.75106) (xy 396.67688 -389.88746) (xy 396.677366 -389.860209) (xy 396.685122 -389.806261)
			(xy 396.700477 -389.753966) (xy 396.723119 -389.704389) (xy 396.752585 -389.658539) (xy 396.788276 -389.617348)
			(xy 396.829467 -389.581657) (xy 396.875317 -389.552191) (xy 396.924894 -389.529549) (xy 396.977189 -389.514194)
			(xy 397.031137 -389.506438) (xy 397.085639 -389.506438) (xy 397.139587 -389.514194) (xy 397.191882 -389.529549)
			(xy 397.241459 -389.552191) (xy 397.287309 -389.581657) (xy 397.3285 -389.617348) (xy 397.364191 -389.658539)
			(xy 397.393657 -389.704389) (xy 397.416299 -389.753966) (xy 397.431654 -389.806261) (xy 397.43941 -389.860209)
			(xy 397.439896 -389.88746) (xy 397.439896 -390.75106) (xy 397.43941 -390.778311) (xy 397.431654 -390.832259)
			(xy 397.416299 -390.884554) (xy 397.393657 -390.934131) (xy 397.364191 -390.979981) (xy 397.3285 -391.021172)
			(xy 397.287309 -391.056863) (xy 397.241459 -391.086329) (xy 397.191882 -391.108971) (xy 397.139587 -391.124326)
			(xy 397.085639 -391.132082) (xy 397.031137 -391.132082) (xy 396.977189 -391.124326) (xy 396.924894 -391.108971)
			(xy 396.875317 -391.086329) (xy 396.829467 -391.056863) (xy 396.788276 -391.021172) (xy 396.752585 -390.979981)
			(xy 396.723119 -390.934131) (xy 396.700477 -390.884554) (xy 396.685122 -390.832259) (xy 396.677366 -390.778311)
			(xy 396.67688 -390.75106) (xy 364.912148 -390.75106) (xy 364.911662 -390.778311) (xy 364.903906 -390.832259)
			(xy 364.888551 -390.884554) (xy 364.865909 -390.934131) (xy 364.836443 -390.979981) (xy 364.800752 -391.021172)
			(xy 364.759561 -391.056863) (xy 364.713711 -391.086329) (xy 364.664134 -391.108971) (xy 364.611839 -391.124326)
			(xy 364.557891 -391.132082) (xy 364.503389 -391.132082) (xy 364.449441 -391.124326) (xy 364.397146 -391.108971)
			(xy 364.347569 -391.086329) (xy 364.301719 -391.056863) (xy 364.260528 -391.021172) (xy 364.224837 -390.979981)
			(xy 364.195371 -390.934131) (xy 364.172729 -390.884554) (xy 364.157374 -390.832259) (xy 364.149618 -390.778311)
			(xy 364.149132 -390.75106) (xy 330.3397 -390.75106) (xy 330.339214 -390.778311) (xy 330.331458 -390.832259)
			(xy 330.316103 -390.884554) (xy 330.293461 -390.934131) (xy 330.263995 -390.979981) (xy 330.228304 -391.021172)
			(xy 330.187113 -391.056863) (xy 330.141263 -391.086329) (xy 330.091686 -391.108971) (xy 330.039391 -391.124326)
			(xy 329.985443 -391.132082) (xy 329.930941 -391.132082) (xy 329.876993 -391.124326) (xy 329.824698 -391.108971)
			(xy 329.775121 -391.086329) (xy 329.729271 -391.056863) (xy 329.68808 -391.021172) (xy 329.652389 -390.979981)
			(xy 329.622923 -390.934131) (xy 329.600281 -390.884554) (xy 329.584926 -390.832259) (xy 329.57717 -390.778311)
			(xy 329.576684 -390.75106) (xy 297.811952 -390.75106) (xy 297.811466 -390.778311) (xy 297.80371 -390.832259)
			(xy 297.788355 -390.884554) (xy 297.765713 -390.934131) (xy 297.736247 -390.979981) (xy 297.700556 -391.021172)
			(xy 297.659365 -391.056863) (xy 297.613515 -391.086329) (xy 297.563938 -391.108971) (xy 297.511643 -391.124326)
			(xy 297.457695 -391.132082) (xy 297.403193 -391.132082) (xy 297.349245 -391.124326) (xy 297.29695 -391.108971)
			(xy 297.247373 -391.086329) (xy 297.201523 -391.056863) (xy 297.160332 -391.021172) (xy 297.124641 -390.979981)
			(xy 297.095175 -390.934131) (xy 297.072533 -390.884554) (xy 297.057178 -390.832259) (xy 297.049422 -390.778311)
			(xy 297.048936 -390.75106) (xy 281.2288 -390.75106) (xy 281.2288 -392.180572) (xy 281.228283 -392.20552)
			(xy 281.220475 -392.254803) (xy 281.205064 -392.30226) (xy 281.182426 -392.346726) (xy 281.153119 -392.387109)
			(xy 281.135836 -392.405108) (xy 280.810462 -392.730482) (xy 280.803632 -392.73789) (xy 280.795908 -392.756483)
			(xy 280.795476 -392.76655) (xy 280.795476 -393.110974) (xy 280.794938 -393.135921) (xy 280.787132 -393.185202)
			(xy 280.771724 -393.232658) (xy 280.749092 -393.277124) (xy 280.719792 -393.31751) (xy 280.702512 -393.33551)
			(xy 280.345134 -393.692888) (xy 303.485804 -393.692888) (xy 303.485804 -393.69238) (xy 303.486244 -393.668388)
			(xy 303.493754 -393.620994) (xy 303.508585 -393.575359) (xy 303.530372 -393.532605) (xy 303.558579 -393.493786)
			(xy 303.592511 -393.459858) (xy 303.631333 -393.431655) (xy 303.674088 -393.409872) (xy 303.719725 -393.395046)
			(xy 303.76712 -393.387542) (xy 303.791112 -393.387072) (xy 303.815046 -393.38757) (xy 303.862329 -393.395022)
			(xy 303.907871 -393.409757) (xy 303.950558 -393.431416) (xy 303.989344 -393.459467) (xy 304.02328 -393.493224)
			(xy 304.051536 -393.531861) (xy 304.062892 -393.552934) (xy 304.0634 -393.55395) (xy 304.143706 -393.692888)
			(xy 304.6857 -393.692888) (xy 304.6857 -393.69238) (xy 304.686144 -393.668388) (xy 304.693654 -393.620995)
			(xy 304.708484 -393.57536) (xy 304.730271 -393.532606) (xy 304.758477 -393.493788) (xy 304.792409 -393.459859)
			(xy 304.83123 -393.431656) (xy 304.873986 -393.409873) (xy 304.919622 -393.395047) (xy 304.967016 -393.387542)
			(xy 304.991008 -393.387072) (xy 305.014941 -393.387573) (xy 305.062224 -393.395024) (xy 305.107767 -393.409759)
			(xy 305.150453 -393.431417) (xy 305.189239 -393.459468) (xy 305.223176 -393.493224) (xy 305.251432 -393.531861)
			(xy 305.262788 -393.552934) (xy 305.263296 -393.55395) (xy 305.343602 -393.692888) (xy 305.885596 -393.692888)
			(xy 305.885596 -393.69238) (xy 305.886044 -393.668388) (xy 305.893553 -393.620995) (xy 305.908384 -393.575361)
			(xy 305.93017 -393.532608) (xy 305.958376 -393.493789) (xy 305.992307 -393.459861) (xy 306.031128 -393.431658)
			(xy 306.073883 -393.409875) (xy 306.119519 -393.395048) (xy 306.166912 -393.387542) (xy 306.190904 -393.387072)
			(xy 306.191158 -393.387072) (xy 306.215093 -393.387532) (xy 306.262378 -393.394992) (xy 306.307921 -393.409734)
			(xy 306.350607 -393.431398) (xy 306.389393 -393.459455) (xy 306.423328 -393.493217) (xy 306.451583 -393.531859)
			(xy 306.462938 -393.552934) (xy 306.463446 -393.55395) (xy 306.543752 -393.692888) (xy 307.085492 -393.692888)
			(xy 307.085492 -393.69238) (xy 307.085943 -393.668401) (xy 307.093444 -393.621033) (xy 307.108259 -393.57542)
			(xy 307.130023 -393.532685) (xy 307.158201 -393.493877) (xy 307.192099 -393.459953) (xy 307.230885 -393.431745)
			(xy 307.273604 -393.409949) (xy 307.319205 -393.395099) (xy 307.366567 -393.387562) (xy 307.390546 -393.387072)
			(xy 307.391054 -393.387072) (xy 307.414989 -393.387536) (xy 307.462274 -393.394994) (xy 307.507817 -393.409736)
			(xy 307.550503 -393.4314) (xy 307.589289 -393.459456) (xy 307.623224 -393.493218) (xy 307.651479 -393.531859)
			(xy 307.662834 -393.552934) (xy 307.663342 -393.55395) (xy 307.743648 -393.692888) (xy 308.285388 -393.692888)
			(xy 308.285388 -393.69238) (xy 308.285843 -393.668401) (xy 308.293344 -393.621034) (xy 308.308159 -393.575421)
			(xy 308.329922 -393.532686) (xy 308.358099 -393.493879) (xy 308.391998 -393.459954) (xy 308.430783 -393.431747)
			(xy 308.473501 -393.40995) (xy 308.519102 -393.3951) (xy 308.566463 -393.387562) (xy 308.590442 -393.387072)
			(xy 308.59095 -393.387072) (xy 308.614885 -393.387539) (xy 308.662169 -393.394997) (xy 308.707712 -393.409738)
			(xy 308.750399 -393.431401) (xy 308.789184 -393.459457) (xy 308.82312 -393.493218) (xy 308.851375 -393.531859)
			(xy 308.86273 -393.552934) (xy 308.863238 -393.55395) (xy 308.943544 -393.692888) (xy 309.485792 -393.692888)
			(xy 309.485792 -393.69238) (xy 309.486244 -393.668388) (xy 309.493753 -393.620996) (xy 309.508583 -393.575362)
			(xy 309.530369 -393.532609) (xy 309.558575 -393.49379) (xy 309.592506 -393.459862) (xy 309.631326 -393.431659)
			(xy 309.67408 -393.409876) (xy 309.719715 -393.395049) (xy 309.767108 -393.387543) (xy 309.7911 -393.387072)
			(xy 309.815033 -393.38758) (xy 309.862316 -393.39503) (xy 309.907858 -393.409764) (xy 309.950544 -393.43142)
			(xy 309.989331 -393.45947) (xy 310.023268 -393.493226) (xy 310.051524 -393.531862) (xy 310.06288 -393.552934)
			(xy 310.063388 -393.55395) (xy 310.143694 -393.692888) (xy 310.685688 -393.692888) (xy 310.685688 -393.69238)
			(xy 310.686144 -393.668388) (xy 310.693653 -393.620996) (xy 310.708483 -393.575362) (xy 310.730269 -393.53261)
			(xy 310.758474 -393.493792) (xy 310.792404 -393.459863) (xy 310.831224 -393.43166) (xy 310.873977 -393.409877)
			(xy 310.919612 -393.395049) (xy 310.967004 -393.387543) (xy 310.990996 -393.387072) (xy 311.014932 -393.387502)
			(xy 311.062218 -393.394966) (xy 311.107762 -393.409714) (xy 311.150449 -393.431384) (xy 311.189234 -393.459445)
			(xy 311.223168 -393.493212) (xy 311.251422 -393.531857) (xy 311.262776 -393.552934) (xy 311.263284 -393.55395)
			(xy 311.34359 -393.692888) (xy 311.885584 -393.692888) (xy 311.885584 -393.69238) (xy 311.886044 -393.668389)
			(xy 311.893553 -393.620997) (xy 311.908383 -393.575363) (xy 311.930168 -393.532611) (xy 311.958373 -393.493793)
			(xy 311.992302 -393.459865) (xy 312.031121 -393.431662) (xy 312.073874 -393.409878) (xy 312.119509 -393.39505)
			(xy 312.166901 -393.387543) (xy 312.190892 -393.387072) (xy 312.191146 -393.387072) (xy 312.215081 -393.387542)
			(xy 312.262365 -393.394999) (xy 312.307908 -393.40974) (xy 312.350594 -393.431403) (xy 312.38938 -393.459458)
			(xy 312.423316 -393.493219) (xy 312.451571 -393.531859) (xy 312.462926 -393.552934) (xy 312.463434 -393.55395)
			(xy 312.54374 -393.692888) (xy 313.08548 -393.692888) (xy 313.08548 -393.69238) (xy 313.085921 -393.668374)
			(xy 313.093438 -393.620955) (xy 313.108284 -393.575296) (xy 313.130093 -393.532524) (xy 313.158327 -393.493692)
			(xy 313.192291 -393.459757) (xy 313.231147 -393.431556) (xy 313.273939 -393.409783) (xy 313.31961 -393.394977)
			(xy 313.367036 -393.3875) (xy 313.391042 -393.387072) (xy 313.391296 -393.387072) (xy 313.415232 -393.387502)
			(xy 313.462518 -393.394966) (xy 313.508062 -393.409714) (xy 313.550749 -393.431384) (xy 313.589534 -393.459445)
			(xy 313.623468 -393.493212) (xy 313.651722 -393.531857) (xy 313.663076 -393.552934) (xy 313.663584 -393.55395)
			(xy 313.74389 -393.692888) (xy 314.285376 -393.692888) (xy 314.285376 -393.69238) (xy 314.285821 -393.668374)
			(xy 314.293338 -393.620955) (xy 314.308183 -393.575297) (xy 314.329992 -393.532525) (xy 314.358226 -393.493693)
			(xy 314.392189 -393.459758) (xy 314.431045 -393.431557) (xy 314.473836 -393.409785) (xy 314.519507 -393.394977)
			(xy 314.566932 -393.3875) (xy 314.590938 -393.387072) (xy 314.591192 -393.387072) (xy 314.615128 -393.387505)
			(xy 314.662414 -393.394969) (xy 314.707958 -393.409716) (xy 314.750644 -393.431385) (xy 314.78943 -393.459446)
			(xy 314.823364 -393.493212) (xy 314.851618 -393.531857) (xy 314.862972 -393.552934) (xy 314.86348 -393.55395)
			(xy 314.943786 -393.692888) (xy 315.48578 -393.692888) (xy 315.48578 -393.69238) (xy 315.486244 -393.668389)
			(xy 315.493753 -393.620998) (xy 315.508582 -393.575364) (xy 315.530367 -393.532612) (xy 315.558571 -393.493795)
			(xy 315.592501 -393.459866) (xy 315.631319 -393.431663) (xy 315.674072 -393.409879) (xy 315.719705 -393.395051)
			(xy 315.767097 -393.387543) (xy 315.791088 -393.387072) (xy 315.815024 -393.387508) (xy 315.86231 -393.394972)
			(xy 315.907853 -393.409718) (xy 315.95054 -393.431387) (xy 315.989325 -393.459447) (xy 316.02326 -393.493213)
			(xy 316.051514 -393.531858) (xy 316.062868 -393.552934) (xy 316.063376 -393.55395) (xy 316.143682 -393.692888)
			(xy 316.685676 -393.692888) (xy 316.685676 -393.69238) (xy 316.686144 -393.668389) (xy 316.693653 -393.620998)
			(xy 316.708482 -393.575365) (xy 316.730267 -393.532614) (xy 316.75847 -393.493796) (xy 316.792399 -393.459868)
			(xy 316.831217 -393.431664) (xy 316.873969 -393.40988) (xy 316.919602 -393.395052) (xy 316.966993 -393.387544)
			(xy 316.990984 -393.387072) (xy 316.991238 -393.387072) (xy 317.015172 -393.387549) (xy 317.062456 -393.395005)
			(xy 317.107999 -393.409744) (xy 317.150686 -393.431406) (xy 317.189472 -393.45946) (xy 317.223407 -393.49322)
			(xy 317.251663 -393.53186) (xy 317.263018 -393.552934) (xy 317.263526 -393.55395) (xy 317.343832 -393.692888)
			(xy 317.885572 -393.692888) (xy 317.885572 -393.69238) (xy 317.886043 -393.668402) (xy 317.893544 -393.621036)
			(xy 317.908357 -393.575425) (xy 317.930119 -393.532691) (xy 317.958295 -393.493884) (xy 317.992191 -393.45996)
			(xy 318.030974 -393.431752) (xy 318.07369 -393.409954) (xy 318.119289 -393.395103) (xy 318.166648 -393.387563)
			(xy 318.190626 -393.387072) (xy 318.191134 -393.387072) (xy 318.215068 -393.387552) (xy 318.262352 -393.395007)
			(xy 318.307895 -393.409746) (xy 318.350581 -393.431407) (xy 318.389367 -393.459461) (xy 318.423303 -393.493221)
			(xy 318.451559 -393.53186) (xy 318.462914 -393.552934) (xy 318.463422 -393.55395) (xy 318.543728 -393.692888)
			(xy 319.085468 -393.692888) (xy 319.085468 -393.69238) (xy 319.085921 -393.668375) (xy 319.093437 -393.620957)
			(xy 319.108283 -393.575299) (xy 319.130091 -393.532527) (xy 319.158324 -393.493696) (xy 319.192286 -393.459761)
			(xy 319.231141 -393.43156) (xy 319.27393 -393.409787) (xy 319.3196 -393.394979) (xy 319.367024 -393.387501)
			(xy 319.39103 -393.387072) (xy 319.391284 -393.387072) (xy 319.41522 -393.387511) (xy 319.462506 -393.394974)
			(xy 319.508049 -393.40972) (xy 319.550736 -393.431388) (xy 319.589521 -393.459448) (xy 319.623456 -393.493214)
			(xy 319.65171 -393.531858) (xy 319.663064 -393.552934) (xy 319.663572 -393.55395) (xy 319.743878 -393.692888)
			(xy 320.285872 -393.692888) (xy 320.285872 -393.69238) (xy 320.286344 -393.668389) (xy 320.293853 -393.620999)
			(xy 320.308681 -393.575366) (xy 320.330466 -393.532615) (xy 320.358669 -393.493797) (xy 320.392597 -393.459869)
			(xy 320.431415 -393.431666) (xy 320.474166 -393.409881) (xy 320.519799 -393.395053) (xy 320.567189 -393.387544)
			(xy 320.59118 -393.387072) (xy 320.615116 -393.387515) (xy 320.662401 -393.394977) (xy 320.707945 -393.409722)
			(xy 320.750631 -393.43139) (xy 320.789417 -393.459449) (xy 320.823352 -393.493214) (xy 320.851606 -393.531858)
			(xy 320.86296 -393.552934) (xy 320.863468 -393.55395) (xy 320.943774 -393.692888) (xy 321.485768 -393.692888)
			(xy 321.485768 -393.69238) (xy 321.486244 -393.668389) (xy 321.493752 -393.620999) (xy 321.508581 -393.575367)
			(xy 321.530365 -393.532616) (xy 321.558568 -393.493799) (xy 321.592496 -393.459871) (xy 321.631313 -393.431667)
			(xy 321.674063 -393.409883) (xy 321.719695 -393.395053) (xy 321.767085 -393.387544) (xy 321.791076 -393.387072)
			(xy 321.815011 -393.387518) (xy 321.862297 -393.39498) (xy 321.90784 -393.409724) (xy 321.950527 -393.431391)
			(xy 321.989312 -393.45945) (xy 322.023247 -393.493215) (xy 322.051501 -393.531858) (xy 322.062856 -393.552934)
			(xy 322.063364 -393.55395) (xy 322.14367 -393.692888) (xy 336.013552 -393.692888) (xy 336.013552 -393.69238)
			(xy 336.014044 -393.66839) (xy 336.021552 -393.621002) (xy 336.03638 -393.575371) (xy 336.058162 -393.532621)
			(xy 336.086363 -393.493804) (xy 336.120289 -393.459876) (xy 336.159104 -393.431673) (xy 336.201852 -393.409887)
			(xy 336.247482 -393.395057) (xy 336.29487 -393.387546) (xy 336.31886 -393.387072) (xy 336.342795 -393.387531)
			(xy 336.39008 -393.39499) (xy 336.435623 -393.409733) (xy 336.47831 -393.431398) (xy 336.517095 -393.459455)
			(xy 336.551031 -393.493217) (xy 336.579285 -393.531859) (xy 336.59064 -393.552934) (xy 336.591148 -393.55395)
			(xy 336.671454 -393.692888) (xy 337.213448 -393.692888) (xy 337.213448 -393.69238) (xy 337.213944 -393.66839)
			(xy 337.221452 -393.621002) (xy 337.236279 -393.575372) (xy 337.258061 -393.532622) (xy 337.286262 -393.493805)
			(xy 337.320187 -393.459878) (xy 337.359001 -393.431674) (xy 337.401749 -393.409888) (xy 337.447379 -393.395057)
			(xy 337.494766 -393.387546) (xy 337.518756 -393.387072) (xy 337.542691 -393.387534) (xy 337.589976 -393.394993)
			(xy 337.635519 -393.409735) (xy 337.678205 -393.431399) (xy 337.716991 -393.459456) (xy 337.750926 -393.493218)
			(xy 337.779181 -393.531859) (xy 337.790536 -393.552934) (xy 337.791044 -393.55395) (xy 337.87135 -393.692888)
			(xy 338.413344 -393.692888) (xy 338.413344 -393.69238) (xy 338.413844 -393.668391) (xy 338.421352 -393.621003)
			(xy 338.436179 -393.575373) (xy 338.457961 -393.532623) (xy 338.486161 -393.493807) (xy 338.520086 -393.459879)
			(xy 338.558899 -393.431675) (xy 338.601647 -393.40989) (xy 338.647276 -393.395058) (xy 338.694663 -393.387546)
			(xy 338.718652 -393.387072) (xy 338.718906 -393.387072) (xy 338.742839 -393.387575) (xy 338.790122 -393.395026)
			(xy 338.835664 -393.40976) (xy 338.878351 -393.431418) (xy 338.917137 -393.459468) (xy 338.951074 -393.493225)
			(xy 338.97933 -393.531861) (xy 338.990686 -393.552934) (xy 338.991194 -393.55395) (xy 339.0715 -393.692888)
			(xy 339.61324 -393.692888) (xy 339.61324 -393.69238) (xy 339.613643 -393.668399) (xy 339.621146 -393.621026)
			(xy 339.635964 -393.575409) (xy 339.657732 -393.53267) (xy 339.685915 -393.493861) (xy 339.719819 -393.459936)
			(xy 339.758612 -393.431729) (xy 339.801337 -393.409935) (xy 339.846945 -393.395089) (xy 339.894313 -393.387558)
			(xy 339.918294 -393.387072) (xy 339.918802 -393.387072) (xy 339.942735 -393.387578) (xy 339.990018 -393.395028)
			(xy 340.03556 -393.409763) (xy 340.078247 -393.43142) (xy 340.117033 -393.459469) (xy 340.15097 -393.493225)
			(xy 340.179226 -393.531861) (xy 340.190582 -393.552934) (xy 340.19109 -393.55395) (xy 340.271396 -393.692888)
			(xy 340.813136 -393.692888) (xy 340.813136 -393.69238) (xy 340.813543 -393.668399) (xy 340.821046 -393.621027)
			(xy 340.835863 -393.57541) (xy 340.857631 -393.532672) (xy 340.885813 -393.493862) (xy 340.919718 -393.459937)
			(xy 340.958509 -393.43173) (xy 341.001234 -393.409936) (xy 341.046841 -393.39509) (xy 341.094209 -393.387558)
			(xy 341.11819 -393.387072) (xy 341.118698 -393.387072) (xy 341.142634 -393.3875) (xy 341.189921 -393.394965)
			(xy 341.235464 -393.409713) (xy 341.278151 -393.431383) (xy 341.316936 -393.459445) (xy 341.35087 -393.493212)
			(xy 341.379124 -393.531857) (xy 341.390478 -393.552934) (xy 341.390986 -393.55395) (xy 341.471292 -393.692888)
			(xy 342.01354 -393.692888) (xy 342.01354 -393.69238) (xy 342.01392 -393.668384) (xy 342.021431 -393.620983)
			(xy 342.036265 -393.575341) (xy 342.058057 -393.532582) (xy 342.08627 -393.493758) (xy 342.12021 -393.459826)
			(xy 342.15904 -393.431622) (xy 342.201804 -393.409839) (xy 342.247449 -393.395015) (xy 342.294852 -393.387515)
			(xy 342.318848 -393.387072) (xy 342.342783 -393.387541) (xy 342.390067 -393.394998) (xy 342.43561 -393.409739)
			(xy 342.478297 -393.431402) (xy 342.517082 -393.459458) (xy 342.551018 -393.493219) (xy 342.579273 -393.531859)
			(xy 342.590628 -393.552934) (xy 342.591136 -393.55395) (xy 342.671442 -393.692888) (xy 343.213436 -393.692888)
			(xy 343.213436 -393.69238) (xy 343.21382 -393.668384) (xy 343.221331 -393.620984) (xy 343.236165 -393.575342)
			(xy 343.257957 -393.532583) (xy 343.286169 -393.493759) (xy 343.320108 -393.459828) (xy 343.358938 -393.431623)
			(xy 343.401701 -393.40984) (xy 343.447346 -393.395016) (xy 343.494748 -393.387515) (xy 343.518744 -393.387072)
			(xy 343.542678 -393.387544) (xy 343.589963 -393.395001) (xy 343.635506 -393.409741) (xy 343.678192 -393.431404)
			(xy 343.716978 -393.459459) (xy 343.750914 -393.493219) (xy 343.779169 -393.53186) (xy 343.790524 -393.552934)
			(xy 343.791032 -393.55395) (xy 343.871338 -393.692888) (xy 344.413332 -393.692888) (xy 344.413332 -393.69238)
			(xy 344.41372 -393.668384) (xy 344.421231 -393.620984) (xy 344.436065 -393.575343) (xy 344.457856 -393.532584)
			(xy 344.486068 -393.493761) (xy 344.520006 -393.459829) (xy 344.558835 -393.431624) (xy 344.601598 -393.409842)
			(xy 344.647243 -393.395017) (xy 344.694644 -393.387515) (xy 344.71864 -393.387072) (xy 344.718894 -393.387072)
			(xy 344.74283 -393.387503) (xy 344.790116 -393.394968) (xy 344.83566 -393.409715) (xy 344.878347 -393.431385)
			(xy 344.917132 -393.459446) (xy 344.951066 -393.493212) (xy 344.97932 -393.531857) (xy 344.990674 -393.552934)
			(xy 344.991182 -393.55395) (xy 345.071488 -393.692888) (xy 345.613228 -393.692888) (xy 345.613228 -393.69238)
			(xy 345.613643 -393.668399) (xy 345.621146 -393.621028) (xy 345.635962 -393.575412) (xy 345.657729 -393.532674)
			(xy 345.685911 -393.493865) (xy 345.719814 -393.45994) (xy 345.758605 -393.431733) (xy 345.801329 -393.409938)
			(xy 345.846935 -393.395092) (xy 345.894301 -393.387559) (xy 345.918282 -393.387072) (xy 345.91879 -393.387072)
			(xy 345.942726 -393.387506) (xy 345.990012 -393.39497) (xy 346.035556 -393.409717) (xy 346.078242 -393.431386)
			(xy 346.117027 -393.459447) (xy 346.150962 -393.493213) (xy 346.179216 -393.531857) (xy 346.19057 -393.552934)
			(xy 346.191078 -393.55395) (xy 346.271384 -393.692888) (xy 346.813124 -393.692888) (xy 346.813124 -393.69238)
			(xy 346.813543 -393.668399) (xy 346.821045 -393.621028) (xy 346.835862 -393.575413) (xy 346.857629 -393.532675)
			(xy 346.88581 -393.493866) (xy 346.919713 -393.459941) (xy 346.958503 -393.431734) (xy 347.001226 -393.40994)
			(xy 347.046832 -393.395093) (xy 347.094198 -393.387559) (xy 347.118178 -393.387072) (xy 347.118686 -393.387072)
			(xy 347.142622 -393.38751) (xy 347.189908 -393.394973) (xy 347.235451 -393.409719) (xy 347.278138 -393.431388)
			(xy 347.316923 -393.459448) (xy 347.350858 -393.493213) (xy 347.379112 -393.531858) (xy 347.390466 -393.552934)
			(xy 347.390974 -393.55395) (xy 347.47128 -393.692888) (xy 348.013528 -393.692888) (xy 348.013528 -393.69238)
			(xy 348.01392 -393.668385) (xy 348.021431 -393.620985) (xy 348.036264 -393.575344) (xy 348.058055 -393.532585)
			(xy 348.086267 -393.493762) (xy 348.120205 -393.45983) (xy 348.159033 -393.431626) (xy 348.201796 -393.409843)
			(xy 348.247439 -393.395018) (xy 348.29484 -393.387515) (xy 348.318836 -393.387072) (xy 348.34277 -393.38755)
			(xy 348.390054 -393.395006) (xy 348.435597 -393.409745) (xy 348.478284 -393.431407) (xy 348.517069 -393.459461)
			(xy 348.551005 -393.49322) (xy 348.579261 -393.53186) (xy 348.590616 -393.552934) (xy 348.591124 -393.55395)
			(xy 348.67143 -393.692888) (xy 349.213424 -393.692888) (xy 349.213424 -393.69238) (xy 349.21382 -393.668385)
			(xy 349.221331 -393.620985) (xy 349.236164 -393.575345) (xy 349.257954 -393.532586) (xy 349.286166 -393.493764)
			(xy 349.320103 -393.459832) (xy 349.358931 -393.431627) (xy 349.401693 -393.409844) (xy 349.447336 -393.395018)
			(xy 349.494737 -393.387516) (xy 349.518732 -393.387072) (xy 349.542666 -393.387554) (xy 349.58995 -393.395009)
			(xy 349.635493 -393.409747) (xy 349.678179 -393.431408) (xy 349.716965 -393.459462) (xy 349.750901 -393.493221)
			(xy 349.779157 -393.53186) (xy 349.790512 -393.552934) (xy 349.79102 -393.55395) (xy 349.871326 -393.692888)
			(xy 350.41332 -393.692888) (xy 350.41332 -393.69238) (xy 350.41372 -393.668385) (xy 350.42123 -393.620986)
			(xy 350.436063 -393.575346) (xy 350.457854 -393.532588) (xy 350.486065 -393.493765) (xy 350.520001 -393.459833)
			(xy 350.558829 -393.431629) (xy 350.60159 -393.409845) (xy 350.647233 -393.395019) (xy 350.694633 -393.387516)
			(xy 350.718628 -393.387072) (xy 350.718882 -393.387072) (xy 350.742818 -393.387513) (xy 350.790103 -393.394976)
			(xy 350.835647 -393.409721) (xy 350.878334 -393.431389) (xy 350.917119 -393.459449) (xy 350.951054 -393.493214)
			(xy 350.979308 -393.531858) (xy 350.990662 -393.552934) (xy 350.99117 -393.55395) (xy 351.071476 -393.692888)
			(xy 351.613216 -393.692888) (xy 351.613216 -393.69238) (xy 351.613643 -393.6684) (xy 351.621145 -393.621029)
			(xy 351.635961 -393.575415) (xy 351.657727 -393.532678) (xy 351.685908 -393.493869) (xy 351.719809 -393.459944)
			(xy 351.758598 -393.431737) (xy 351.80132 -393.409942) (xy 351.846925 -393.395094) (xy 351.89429 -393.38756)
			(xy 351.91827 -393.387072) (xy 351.918778 -393.387072) (xy 351.942713 -393.387516) (xy 351.989999 -393.394978)
			(xy 352.035543 -393.409723) (xy 352.078229 -393.431391) (xy 352.117015 -393.45945) (xy 352.150949 -393.493214)
			(xy 352.179204 -393.531858) (xy 352.190558 -393.552934) (xy 352.191066 -393.55395) (xy 352.271372 -393.692888)
			(xy 352.813112 -393.692888) (xy 352.813112 -393.69238) (xy 352.813521 -393.668373) (xy 352.821039 -393.62095)
			(xy 352.835887 -393.575289) (xy 352.857699 -393.532514) (xy 352.885937 -393.493681) (xy 352.919904 -393.459745)
			(xy 352.958765 -393.431545) (xy 353.001561 -393.409774) (xy 353.047236 -393.39497) (xy 353.094666 -393.387498)
			(xy 353.118674 -393.387072) (xy 353.118928 -393.387072) (xy 353.142862 -393.387557) (xy 353.190146 -393.395011)
			(xy 353.235688 -393.409749) (xy 353.278375 -393.43141) (xy 353.317161 -393.459463) (xy 353.351097 -393.493222)
			(xy 353.379353 -393.53186) (xy 353.390708 -393.552934) (xy 353.391216 -393.55395) (xy 353.471522 -393.692888)
			(xy 354.013516 -393.692888) (xy 354.013516 -393.69238) (xy 354.01392 -393.668385) (xy 354.02143 -393.620987)
			(xy 354.036263 -393.575347) (xy 354.058053 -393.532589) (xy 354.086263 -393.493766) (xy 354.1202 -393.459835)
			(xy 354.159026 -393.43163) (xy 354.201787 -393.409846) (xy 354.247429 -393.39502) (xy 354.294829 -393.387516)
			(xy 354.318824 -393.387072) (xy 354.342758 -393.38756) (xy 354.390042 -393.395014) (xy 354.435584 -393.409751)
			(xy 354.478271 -393.431411) (xy 354.517057 -393.459464) (xy 354.550993 -393.493222) (xy 354.579249 -393.53186)
			(xy 354.590604 -393.552934) (xy 354.591112 -393.55395) (xy 354.671418 -393.692888) (xy 370.586 -393.692888)
			(xy 370.586 -393.69238) (xy 370.586444 -393.668388) (xy 370.593954 -393.620995) (xy 370.608784 -393.57536)
			(xy 370.630571 -393.532606) (xy 370.658777 -393.493788) (xy 370.692709 -393.459859) (xy 370.73153 -393.431656)
			(xy 370.774286 -393.409873) (xy 370.819922 -393.395047) (xy 370.867316 -393.387542) (xy 370.891308 -393.387072)
			(xy 370.915241 -393.387573) (xy 370.962524 -393.395024) (xy 371.008067 -393.409759) (xy 371.050753 -393.431417)
			(xy 371.089539 -393.459468) (xy 371.123476 -393.493224) (xy 371.151732 -393.531861) (xy 371.163088 -393.552934)
			(xy 371.163596 -393.55395) (xy 371.243902 -393.692888) (xy 371.785896 -393.692888) (xy 371.785896 -393.69238)
			(xy 371.786344 -393.668388) (xy 371.793853 -393.620995) (xy 371.808684 -393.575361) (xy 371.83047 -393.532608)
			(xy 371.858676 -393.493789) (xy 371.892607 -393.459861) (xy 371.931428 -393.431658) (xy 371.974183 -393.409875)
			(xy 372.019819 -393.395048) (xy 372.067212 -393.387542) (xy 372.091204 -393.387072) (xy 372.115137 -393.387576)
			(xy 372.16242 -393.395027) (xy 372.207962 -393.409762) (xy 372.250649 -393.431419) (xy 372.289435 -393.459469)
			(xy 372.323372 -393.493225) (xy 372.351628 -393.531861) (xy 372.362984 -393.552934) (xy 372.363492 -393.55395)
			(xy 372.443798 -393.692888) (xy 372.985792 -393.692888) (xy 372.985792 -393.69238) (xy 372.986244 -393.668388)
			(xy 372.993753 -393.620996) (xy 373.008583 -393.575362) (xy 373.030369 -393.532609) (xy 373.058575 -393.49379)
			(xy 373.092506 -393.459862) (xy 373.131326 -393.431659) (xy 373.17408 -393.409876) (xy 373.219715 -393.395049)
			(xy 373.267108 -393.387543) (xy 373.2911 -393.387072) (xy 373.315033 -393.38758) (xy 373.362316 -393.39503)
			(xy 373.407858 -393.409764) (xy 373.450544 -393.43142) (xy 373.489331 -393.45947) (xy 373.523268 -393.493226)
			(xy 373.551524 -393.531862) (xy 373.56288 -393.552934) (xy 373.563388 -393.55395) (xy 373.643694 -393.692888)
			(xy 374.185688 -393.692888) (xy 374.185688 -393.69238) (xy 374.186143 -393.668401) (xy 374.193644 -393.621034)
			(xy 374.208459 -393.575421) (xy 374.230222 -393.532686) (xy 374.258399 -393.493879) (xy 374.292298 -393.459954)
			(xy 374.331083 -393.431747) (xy 374.373801 -393.40995) (xy 374.419402 -393.3951) (xy 374.466763 -393.387562)
			(xy 374.490742 -393.387072) (xy 374.49125 -393.387072) (xy 374.515185 -393.387539) (xy 374.562469 -393.394997)
			(xy 374.608012 -393.409738) (xy 374.650699 -393.431401) (xy 374.689484 -393.459457) (xy 374.72342 -393.493218)
			(xy 374.751675 -393.531859) (xy 374.76303 -393.552934) (xy 374.763538 -393.55395) (xy 374.843844 -393.692888)
			(xy 375.385584 -393.692888) (xy 375.385584 -393.69238) (xy 375.386043 -393.668401) (xy 375.393544 -393.621034)
			(xy 375.408358 -393.575422) (xy 375.430121 -393.532687) (xy 375.458298 -393.49388) (xy 375.492196 -393.459956)
			(xy 375.53098 -393.431748) (xy 375.573698 -393.409951) (xy 375.619298 -393.395101) (xy 375.66666 -393.387562)
			(xy 375.690638 -393.387072) (xy 375.691146 -393.387072) (xy 375.715081 -393.387542) (xy 375.762365 -393.394999)
			(xy 375.807908 -393.40974) (xy 375.850594 -393.431403) (xy 375.88938 -393.459458) (xy 375.923316 -393.493219)
			(xy 375.951571 -393.531859) (xy 375.962926 -393.552934) (xy 375.963434 -393.55395) (xy 376.04374 -393.692888)
			(xy 376.585988 -393.692888) (xy 376.585988 -393.69238) (xy 376.586444 -393.668388) (xy 376.593953 -393.620996)
			(xy 376.608783 -393.575362) (xy 376.630569 -393.53261) (xy 376.658774 -393.493792) (xy 376.692704 -393.459863)
			(xy 376.731524 -393.43166) (xy 376.774277 -393.409877) (xy 376.819912 -393.395049) (xy 376.867304 -393.387543)
			(xy 376.891296 -393.387072) (xy 376.915232 -393.387502) (xy 376.962518 -393.394966) (xy 377.008062 -393.409714)
			(xy 377.050749 -393.431384) (xy 377.089534 -393.459445) (xy 377.123468 -393.493212) (xy 377.151722 -393.531857)
			(xy 377.163076 -393.552934) (xy 377.163584 -393.55395) (xy 377.24389 -393.692888) (xy 377.785884 -393.692888)
			(xy 377.785884 -393.69238) (xy 377.786344 -393.668389) (xy 377.793853 -393.620997) (xy 377.808683 -393.575363)
			(xy 377.830468 -393.532611) (xy 377.858673 -393.493793) (xy 377.892602 -393.459865) (xy 377.931421 -393.431662)
			(xy 377.974174 -393.409878) (xy 378.019809 -393.39505) (xy 378.067201 -393.387543) (xy 378.091192 -393.387072)
			(xy 378.115128 -393.387505) (xy 378.162414 -393.394969) (xy 378.207958 -393.409716) (xy 378.250644 -393.431385)
			(xy 378.28943 -393.459446) (xy 378.323364 -393.493212) (xy 378.351618 -393.531857) (xy 378.362972 -393.552934)
			(xy 378.36348 -393.55395) (xy 378.443786 -393.692888) (xy 378.98578 -393.692888) (xy 378.98578 -393.69238)
			(xy 378.986244 -393.668389) (xy 378.993753 -393.620998) (xy 379.008582 -393.575364) (xy 379.030367 -393.532612)
			(xy 379.058571 -393.493795) (xy 379.092501 -393.459866) (xy 379.131319 -393.431663) (xy 379.174072 -393.409879)
			(xy 379.219705 -393.395051) (xy 379.267097 -393.387543) (xy 379.291088 -393.387072) (xy 379.315024 -393.387508)
			(xy 379.36231 -393.394972) (xy 379.407853 -393.409718) (xy 379.45054 -393.431387) (xy 379.489325 -393.459447)
			(xy 379.52326 -393.493213) (xy 379.551514 -393.531858) (xy 379.562868 -393.552934) (xy 379.563376 -393.55395)
			(xy 379.643682 -393.692888) (xy 380.185676 -393.692888) (xy 380.185676 -393.69238) (xy 380.186143 -393.668402)
			(xy 380.193644 -393.621035) (xy 380.208457 -393.575424) (xy 380.23022 -393.532689) (xy 380.258396 -393.493883)
			(xy 380.292292 -393.459959) (xy 380.331076 -393.431751) (xy 380.373793 -393.409953) (xy 380.419392 -393.395102)
			(xy 380.466752 -393.387563) (xy 380.49073 -393.387072) (xy 380.491238 -393.387072) (xy 380.515172 -393.387549)
			(xy 380.562456 -393.395005) (xy 380.607999 -393.409744) (xy 380.650686 -393.431406) (xy 380.689472 -393.45946)
			(xy 380.723407 -393.49322) (xy 380.751663 -393.53186) (xy 380.763018 -393.552934) (xy 380.763526 -393.55395)
			(xy 380.843832 -393.692888) (xy 381.385572 -393.692888) (xy 381.385572 -393.69238) (xy 381.386043 -393.668402)
			(xy 381.393544 -393.621036) (xy 381.408357 -393.575425) (xy 381.430119 -393.532691) (xy 381.458295 -393.493884)
			(xy 381.492191 -393.45996) (xy 381.530974 -393.431752) (xy 381.57369 -393.409954) (xy 381.619289 -393.395103)
			(xy 381.666648 -393.387563) (xy 381.690626 -393.387072) (xy 381.691134 -393.387072) (xy 381.715068 -393.387552)
			(xy 381.762352 -393.395007) (xy 381.807895 -393.409746) (xy 381.850581 -393.431407) (xy 381.889367 -393.459461)
			(xy 381.923303 -393.493221) (xy 381.951559 -393.53186) (xy 381.962914 -393.552934) (xy 381.963422 -393.55395)
			(xy 382.043728 -393.692888) (xy 382.585976 -393.692888) (xy 382.585976 -393.69238) (xy 382.586444 -393.668389)
			(xy 382.593953 -393.620998) (xy 382.608782 -393.575365) (xy 382.630567 -393.532614) (xy 382.65877 -393.493796)
			(xy 382.692699 -393.459868) (xy 382.731517 -393.431664) (xy 382.774269 -393.40988) (xy 382.819902 -393.395052)
			(xy 382.867293 -393.387544) (xy 382.891284 -393.387072) (xy 382.91522 -393.387511) (xy 382.962506 -393.394974)
			(xy 383.008049 -393.40972) (xy 383.050736 -393.431388) (xy 383.089521 -393.459448) (xy 383.123456 -393.493214)
			(xy 383.15171 -393.531858) (xy 383.163064 -393.552934) (xy 383.163572 -393.55395) (xy 383.243878 -393.692888)
			(xy 383.785872 -393.692888) (xy 383.785872 -393.69238) (xy 383.786344 -393.668389) (xy 383.793853 -393.620999)
			(xy 383.808681 -393.575366) (xy 383.830466 -393.532615) (xy 383.858669 -393.493797) (xy 383.892597 -393.459869)
			(xy 383.931415 -393.431666) (xy 383.974166 -393.409881) (xy 384.019799 -393.395053) (xy 384.067189 -393.387544)
			(xy 384.09118 -393.387072) (xy 384.115116 -393.387515) (xy 384.162401 -393.394977) (xy 384.207945 -393.409722)
			(xy 384.250631 -393.43139) (xy 384.289417 -393.459449) (xy 384.323352 -393.493214) (xy 384.351606 -393.531858)
			(xy 384.36296 -393.552934) (xy 384.363468 -393.55395) (xy 384.443774 -393.692888) (xy 384.985768 -393.692888)
			(xy 384.985768 -393.69238) (xy 384.986244 -393.668389) (xy 384.993752 -393.620999) (xy 385.008581 -393.575367)
			(xy 385.030365 -393.532616) (xy 385.058568 -393.493799) (xy 385.092496 -393.459871) (xy 385.131313 -393.431667)
			(xy 385.174063 -393.409883) (xy 385.219695 -393.395053) (xy 385.267085 -393.387544) (xy 385.291076 -393.387072)
			(xy 385.315011 -393.387518) (xy 385.362297 -393.39498) (xy 385.40784 -393.409724) (xy 385.450527 -393.431391)
			(xy 385.489312 -393.45945) (xy 385.523247 -393.493215) (xy 385.551501 -393.531858) (xy 385.562856 -393.552934)
			(xy 385.563364 -393.55395) (xy 385.64367 -393.692888) (xy 386.185664 -393.692888) (xy 386.185664 -393.69238)
			(xy 386.186143 -393.668402) (xy 386.193643 -393.621037) (xy 386.208456 -393.575427) (xy 386.230218 -393.532693)
			(xy 386.258392 -393.493887) (xy 386.292287 -393.459963) (xy 386.331069 -393.431755) (xy 386.373784 -393.409957)
			(xy 386.419382 -393.395105) (xy 386.466741 -393.387564) (xy 386.490718 -393.387072) (xy 386.491226 -393.387072)
			(xy 386.51516 -393.387558) (xy 386.562444 -393.395013) (xy 386.607986 -393.40975) (xy 386.650673 -393.43141)
			(xy 386.689459 -393.459463) (xy 386.723395 -393.493222) (xy 386.751651 -393.53186) (xy 386.763006 -393.552934)
			(xy 386.763514 -393.55395) (xy 386.84382 -393.692888) (xy 387.38556 -393.692888) (xy 387.38556 -393.69238)
			(xy 387.386043 -393.668403) (xy 387.393543 -393.621038) (xy 387.408356 -393.575428) (xy 387.430117 -393.532694)
			(xy 387.458291 -393.493888) (xy 387.492186 -393.459964) (xy 387.530967 -393.431756) (xy 387.573682 -393.409958)
			(xy 387.619279 -393.395105) (xy 387.666637 -393.387564) (xy 387.690614 -393.387072) (xy 387.691122 -393.387072)
			(xy 387.715056 -393.387562) (xy 387.762339 -393.395015) (xy 387.807882 -393.409752) (xy 387.850568 -393.431412)
			(xy 387.889354 -393.459464) (xy 387.923291 -393.493222) (xy 387.951547 -393.531861) (xy 387.962902 -393.552934)
			(xy 387.96341 -393.55395) (xy 388.043716 -393.692888) (xy 388.585964 -393.692888) (xy 388.585964 -393.69238)
			(xy 388.586444 -393.66839) (xy 388.593952 -393.621) (xy 388.608781 -393.575368) (xy 388.630564 -393.532617)
			(xy 388.658767 -393.4938) (xy 388.692694 -393.459872) (xy 388.73151 -393.431668) (xy 388.774261 -393.409884)
			(xy 388.819892 -393.395054) (xy 388.867282 -393.387545) (xy 388.891272 -393.387072) (xy 388.915207 -393.387521)
			(xy 388.962493 -393.394982) (xy 389.008036 -393.409727) (xy 389.050723 -393.431393) (xy 389.089508 -393.459451)
			(xy 389.123443 -393.493215) (xy 389.151697 -393.531858) (xy 389.163052 -393.552934) (xy 389.16356 -393.55395)
			(xy 389.243866 -393.692888) (xy 403.113748 -393.692888) (xy 403.113748 -393.69238) (xy 403.114244 -393.66839)
			(xy 403.121752 -393.621002) (xy 403.136579 -393.575372) (xy 403.158361 -393.532622) (xy 403.186562 -393.493805)
			(xy 403.220487 -393.459878) (xy 403.259301 -393.431674) (xy 403.302049 -393.409888) (xy 403.347679 -393.395057)
			(xy 403.395066 -393.387546) (xy 403.419056 -393.387072) (xy 403.442991 -393.387534) (xy 403.490276 -393.394993)
			(xy 403.535819 -393.409735) (xy 403.578505 -393.431399) (xy 403.617291 -393.459456) (xy 403.651226 -393.493218)
			(xy 403.679481 -393.531859) (xy 403.690836 -393.552934) (xy 403.691344 -393.55395) (xy 403.77165 -393.692888)
			(xy 404.313644 -393.692888) (xy 404.313644 -393.69238) (xy 404.314144 -393.668391) (xy 404.321652 -393.621003)
			(xy 404.336479 -393.575373) (xy 404.358261 -393.532623) (xy 404.386461 -393.493807) (xy 404.420386 -393.459879)
			(xy 404.459199 -393.431675) (xy 404.501947 -393.40989) (xy 404.547576 -393.395058) (xy 404.594963 -393.387546)
			(xy 404.618952 -393.387072) (xy 404.642887 -393.387537) (xy 404.690171 -393.394995) (xy 404.735714 -393.409737)
			(xy 404.778401 -393.431401) (xy 404.817187 -393.459457) (xy 404.851122 -393.493218) (xy 404.879377 -393.531859)
			(xy 404.890732 -393.552934) (xy 404.89124 -393.55395) (xy 404.971546 -393.692888) (xy 405.51354 -393.692888)
			(xy 405.51354 -393.69238) (xy 405.51392 -393.668384) (xy 405.521431 -393.620983) (xy 405.536265 -393.575341)
			(xy 405.558057 -393.532582) (xy 405.58627 -393.493758) (xy 405.62021 -393.459826) (xy 405.65904 -393.431622)
			(xy 405.701804 -393.409839) (xy 405.747449 -393.395015) (xy 405.794852 -393.387515) (xy 405.818848 -393.387072)
			(xy 405.842783 -393.387541) (xy 405.890067 -393.394998) (xy 405.93561 -393.409739) (xy 405.978297 -393.431402)
			(xy 406.017082 -393.459458) (xy 406.051018 -393.493219) (xy 406.079273 -393.531859) (xy 406.090628 -393.552934)
			(xy 406.091136 -393.55395) (xy 406.171442 -393.692888) (xy 406.713436 -393.692888) (xy 406.713436 -393.69238)
			(xy 406.713843 -393.668399) (xy 406.721346 -393.621027) (xy 406.736163 -393.57541) (xy 406.757931 -393.532672)
			(xy 406.786113 -393.493862) (xy 406.820018 -393.459937) (xy 406.858809 -393.43173) (xy 406.901534 -393.409936)
			(xy 406.947141 -393.39509) (xy 406.994509 -393.387558) (xy 407.01849 -393.387072) (xy 407.018998 -393.387072)
			(xy 407.042934 -393.3875) (xy 407.090221 -393.394965) (xy 407.135764 -393.409713) (xy 407.178451 -393.431383)
			(xy 407.217236 -393.459445) (xy 407.25117 -393.493212) (xy 407.279424 -393.531857) (xy 407.290778 -393.552934)
			(xy 407.291286 -393.55395) (xy 407.371592 -393.692888) (xy 407.913332 -393.692888) (xy 407.913332 -393.69238)
			(xy 407.913743 -393.668399) (xy 407.921246 -393.621027) (xy 407.936063 -393.575411) (xy 407.95783 -393.532673)
			(xy 407.986012 -393.493864) (xy 408.019916 -393.459939) (xy 408.058707 -393.431732) (xy 408.101432 -393.409937)
			(xy 408.147038 -393.395091) (xy 408.194405 -393.387559) (xy 408.218386 -393.387072) (xy 408.218894 -393.387072)
			(xy 408.24283 -393.387503) (xy 408.290116 -393.394968) (xy 408.33566 -393.409715) (xy 408.378347 -393.431385)
			(xy 408.417132 -393.459446) (xy 408.451066 -393.493212) (xy 408.47932 -393.531857) (xy 408.490674 -393.552934)
			(xy 408.491182 -393.55395) (xy 408.571488 -393.692888) (xy 409.113736 -393.692888) (xy 409.113736 -393.69238)
			(xy 409.11412 -393.668384) (xy 409.121631 -393.620984) (xy 409.136465 -393.575342) (xy 409.158257 -393.532583)
			(xy 409.186469 -393.493759) (xy 409.220408 -393.459828) (xy 409.259238 -393.431623) (xy 409.302001 -393.40984)
			(xy 409.347646 -393.395016) (xy 409.395048 -393.387515) (xy 409.419044 -393.387072) (xy 409.442978 -393.387544)
			(xy 409.490263 -393.395001) (xy 409.535806 -393.409741) (xy 409.578492 -393.431404) (xy 409.617278 -393.459459)
			(xy 409.651214 -393.493219) (xy 409.679469 -393.53186) (xy 409.690824 -393.552934) (xy 409.691332 -393.55395)
			(xy 409.771638 -393.692888) (xy 410.313632 -393.692888) (xy 410.313632 -393.69238) (xy 410.31402 -393.668384)
			(xy 410.321531 -393.620984) (xy 410.336365 -393.575343) (xy 410.358156 -393.532584) (xy 410.386368 -393.493761)
			(xy 410.420306 -393.459829) (xy 410.459135 -393.431624) (xy 410.501898 -393.409842) (xy 410.547543 -393.395017)
			(xy 410.594944 -393.387515) (xy 410.61894 -393.387072) (xy 410.642874 -393.387547) (xy 410.690159 -393.395003)
			(xy 410.735701 -393.409743) (xy 410.778388 -393.431405) (xy 410.817174 -393.45946) (xy 410.85111 -393.49322)
			(xy 410.879365 -393.53186) (xy 410.89072 -393.552934) (xy 410.891228 -393.55395) (xy 410.971534 -393.692888)
			(xy 411.513528 -393.692888) (xy 411.513528 -393.69238) (xy 411.51392 -393.668385) (xy 411.521431 -393.620985)
			(xy 411.536264 -393.575344) (xy 411.558055 -393.532585) (xy 411.586267 -393.493762) (xy 411.620205 -393.45983)
			(xy 411.659033 -393.431626) (xy 411.701796 -393.409843) (xy 411.747439 -393.395018) (xy 411.79484 -393.387515)
			(xy 411.818836 -393.387072) (xy 411.84277 -393.38755) (xy 411.890054 -393.395006) (xy 411.935597 -393.409745)
			(xy 411.978284 -393.431407) (xy 412.017069 -393.459461) (xy 412.051005 -393.49322) (xy 412.079261 -393.53186)
			(xy 412.090616 -393.552934) (xy 412.091124 -393.55395) (xy 412.17143 -393.692888) (xy 412.713424 -393.692888)
			(xy 412.713424 -393.69238) (xy 412.713843 -393.668399) (xy 412.721345 -393.621028) (xy 412.736162 -393.575413)
			(xy 412.757929 -393.532675) (xy 412.78611 -393.493866) (xy 412.820013 -393.459941) (xy 412.858803 -393.431734)
			(xy 412.901526 -393.40994) (xy 412.947132 -393.395093) (xy 412.994498 -393.387559) (xy 413.018478 -393.387072)
			(xy 413.018986 -393.387072) (xy 413.042922 -393.38751) (xy 413.090208 -393.394973) (xy 413.135751 -393.409719)
			(xy 413.178438 -393.431388) (xy 413.217223 -393.459448) (xy 413.251158 -393.493213) (xy 413.279412 -393.531858)
			(xy 413.290766 -393.552934) (xy 413.291274 -393.55395) (xy 413.37158 -393.692888) (xy 413.91332 -393.692888)
			(xy 413.91332 -393.69238) (xy 413.913743 -393.6684) (xy 413.921245 -393.621029) (xy 413.936062 -393.575414)
			(xy 413.957828 -393.532676) (xy 413.986009 -393.493868) (xy 414.019911 -393.459943) (xy 414.0587 -393.431736)
			(xy 414.101423 -393.409941) (xy 414.147028 -393.395093) (xy 414.194394 -393.387559) (xy 414.218374 -393.387072)
			(xy 414.218882 -393.387072) (xy 414.242818 -393.387513) (xy 414.290103 -393.394976) (xy 414.335647 -393.409721)
			(xy 414.378334 -393.431389) (xy 414.417119 -393.459449) (xy 414.451054 -393.493214) (xy 414.479308 -393.531858)
			(xy 414.490662 -393.552934) (xy 414.49117 -393.55395) (xy 414.571476 -393.692888) (xy 415.113724 -393.692888)
			(xy 415.113724 -393.69238) (xy 415.11412 -393.668385) (xy 415.121631 -393.620985) (xy 415.136464 -393.575345)
			(xy 415.158254 -393.532586) (xy 415.186466 -393.493764) (xy 415.220403 -393.459832) (xy 415.259231 -393.431627)
			(xy 415.301993 -393.409844) (xy 415.347636 -393.395018) (xy 415.395037 -393.387516) (xy 415.419032 -393.387072)
			(xy 415.442966 -393.387554) (xy 415.49025 -393.395009) (xy 415.535793 -393.409747) (xy 415.578479 -393.431408)
			(xy 415.617265 -393.459462) (xy 415.651201 -393.493221) (xy 415.679457 -393.53186) (xy 415.690812 -393.552934)
			(xy 415.69132 -393.55395) (xy 415.771626 -393.692888) (xy 416.31362 -393.692888) (xy 416.31362 -393.69238)
			(xy 416.31402 -393.668385) (xy 416.32153 -393.620986) (xy 416.336363 -393.575346) (xy 416.358154 -393.532588)
			(xy 416.386365 -393.493765) (xy 416.420301 -393.459833) (xy 416.459129 -393.431629) (xy 416.50189 -393.409845)
			(xy 416.547533 -393.395019) (xy 416.594933 -393.387516) (xy 416.618928 -393.387072) (xy 416.642862 -393.387557)
			(xy 416.690146 -393.395011) (xy 416.735688 -393.409749) (xy 416.778375 -393.43141) (xy 416.817161 -393.459463)
			(xy 416.851097 -393.493222) (xy 416.879353 -393.53186) (xy 416.890708 -393.552934) (xy 416.891216 -393.55395)
			(xy 416.971522 -393.692888) (xy 417.513516 -393.692888) (xy 417.513516 -393.69238) (xy 417.51392 -393.668385)
			(xy 417.52143 -393.620987) (xy 417.536263 -393.575347) (xy 417.558053 -393.532589) (xy 417.586263 -393.493766)
			(xy 417.6202 -393.459835) (xy 417.659026 -393.43163) (xy 417.701787 -393.409846) (xy 417.747429 -393.39502)
			(xy 417.794829 -393.387516) (xy 417.818824 -393.387072) (xy 417.842758 -393.38756) (xy 417.890042 -393.395014)
			(xy 417.935584 -393.409751) (xy 417.978271 -393.431411) (xy 418.017057 -393.459464) (xy 418.050993 -393.493222)
			(xy 418.079249 -393.53186) (xy 418.090604 -393.552934) (xy 418.091112 -393.55395) (xy 418.171418 -393.692888)
			(xy 418.713412 -393.692888) (xy 418.713412 -393.69238) (xy 418.713843 -393.6684) (xy 418.721345 -393.62103)
			(xy 418.736161 -393.575416) (xy 418.757927 -393.532679) (xy 418.786106 -393.493871) (xy 418.820008 -393.459946)
			(xy 418.858796 -393.431739) (xy 418.901518 -393.409943) (xy 418.947122 -393.395095) (xy 418.994486 -393.38756)
			(xy 419.018466 -393.387072) (xy 419.018974 -393.387072) (xy 419.042909 -393.387519) (xy 419.090195 -393.394981)
			(xy 419.135738 -393.409726) (xy 419.178425 -393.431392) (xy 419.21721 -393.459451) (xy 419.251145 -393.493215)
			(xy 419.279399 -393.531858) (xy 419.290754 -393.552934) (xy 419.291262 -393.55395) (xy 419.371568 -393.692888)
			(xy 419.913308 -393.692888) (xy 419.913308 -393.69238) (xy 419.913743 -393.6684) (xy 419.921245 -393.621031)
			(xy 419.936061 -393.575417) (xy 419.957826 -393.53268) (xy 419.986005 -393.493872) (xy 420.019906 -393.459947)
			(xy 420.058694 -393.43174) (xy 420.101415 -393.409944) (xy 420.147018 -393.395096) (xy 420.194382 -393.38756)
			(xy 420.218362 -393.387072) (xy 420.21887 -393.387072) (xy 420.242805 -393.387523) (xy 420.290091 -393.394984)
			(xy 420.335634 -393.409728) (xy 420.378321 -393.431394) (xy 420.417106 -393.459452) (xy 420.451041 -393.493216)
			(xy 420.479295 -393.531858) (xy 420.49065 -393.552934) (xy 420.491158 -393.55395) (xy 420.571464 -393.692888)
			(xy 421.113712 -393.692888) (xy 421.113712 -393.69238) (xy 421.114144 -393.668387) (xy 421.121654 -393.620993)
			(xy 421.136485 -393.575357) (xy 421.158273 -393.532603) (xy 421.186481 -393.493784) (xy 421.220414 -393.459855)
			(xy 421.259237 -393.431652) (xy 421.301994 -393.40987) (xy 421.347632 -393.395045) (xy 421.395027 -393.387541)
			(xy 421.41902 -393.387072) (xy 421.442954 -393.387563) (xy 421.490237 -393.395017) (xy 421.53578 -393.409753)
			(xy 421.578466 -393.431413) (xy 421.617252 -393.459465) (xy 421.651189 -393.493223) (xy 421.679444 -393.531861)
			(xy 421.6908 -393.552934) (xy 421.691308 -393.55395) (xy 422.083738 -394.232892) (xy 422.096563 -394.256225)
			(xy 422.114783 -394.306247) (xy 422.124043 -394.358673) (xy 422.124632 -394.385292) (xy 422.124131 -394.409269)
			(xy 422.116635 -394.456634) (xy 422.101826 -394.502244) (xy 422.080067 -394.544978) (xy 422.051895 -394.583784)
			(xy 422.018002 -394.617709) (xy 421.979222 -394.645918) (xy 421.936509 -394.667716) (xy 421.890912 -394.682568)
			(xy 421.843555 -394.690109) (xy 421.819578 -394.6906) (xy 421.81907 -394.6906) (xy 421.795495 -394.69023)
			(xy 421.748906 -394.682984) (xy 421.703987 -394.668654) (xy 421.661808 -394.647582) (xy 421.623376 -394.620268)
			(xy 421.589605 -394.587365) (xy 421.5613 -394.549657) (xy 421.54983 -394.529056) (xy 421.549322 -394.528294)
			(xy 421.151558 -393.839954) (xy 421.139699 -393.817269) (xy 421.122842 -393.76894) (xy 421.114262 -393.71848)
			(xy 421.113712 -393.692888) (xy 420.571464 -393.692888) (xy 420.883588 -394.232892) (xy 420.89632 -394.256211)
			(xy 420.914415 -394.306158) (xy 420.923631 -394.358477) (xy 420.924228 -394.385038) (xy 420.924228 -394.385292)
			(xy 420.92373 -394.409282) (xy 420.916226 -394.456672) (xy 420.901401 -394.502304) (xy 420.87962 -394.545055)
			(xy 420.85142 -394.583873) (xy 420.817494 -394.617801) (xy 420.778679 -394.646005) (xy 420.73593 -394.66779)
			(xy 420.690299 -394.682619) (xy 420.64291 -394.690128) (xy 420.61892 -394.6906) (xy 420.595347 -394.69019)
			(xy 420.548759 -394.682952) (xy 420.503841 -394.668629) (xy 420.461662 -394.647563) (xy 420.423229 -394.620256)
			(xy 420.389457 -394.587358) (xy 420.361151 -394.549655) (xy 420.34968 -394.529056) (xy 420.349172 -394.528294)
			(xy 419.951408 -393.839954) (xy 419.939474 -393.817295) (xy 419.922543 -393.768965) (xy 419.913891 -393.718491)
			(xy 419.913308 -393.692888) (xy 419.371568 -393.692888) (xy 419.683692 -394.232892) (xy 419.696424 -394.25621)
			(xy 419.714519 -394.306158) (xy 419.723735 -394.358477) (xy 419.724332 -394.385038) (xy 419.724332 -394.385292)
			(xy 419.72383 -394.409282) (xy 419.716326 -394.456671) (xy 419.701501 -394.502303) (xy 419.679721 -394.545054)
			(xy 419.651521 -394.583871) (xy 419.617596 -394.6178) (xy 419.578781 -394.646004) (xy 419.536032 -394.667789)
			(xy 419.490402 -394.682618) (xy 419.443014 -394.690128) (xy 419.419024 -394.6906) (xy 419.395451 -394.690187)
			(xy 419.348863 -394.682949) (xy 419.303945 -394.668627) (xy 419.261767 -394.647561) (xy 419.223333 -394.620255)
			(xy 419.189561 -394.587358) (xy 419.161255 -394.549655) (xy 419.149784 -394.529056) (xy 419.149276 -394.528294)
			(xy 418.751512 -393.839954) (xy 418.739579 -393.817295) (xy 418.722647 -393.768965) (xy 418.713995 -393.718491)
			(xy 418.713412 -393.692888) (xy 418.171418 -393.692888) (xy 418.483542 -394.232892) (xy 418.496367 -394.256224)
			(xy 418.514587 -394.306247) (xy 418.523847 -394.358673) (xy 418.524436 -394.385292) (xy 418.523931 -394.409269)
			(xy 418.516435 -394.456633) (xy 418.501626 -394.502243) (xy 418.479868 -394.544977) (xy 418.451696 -394.583783)
			(xy 418.417804 -394.617708) (xy 418.379024 -394.645916) (xy 418.336311 -394.667715) (xy 418.290716 -394.682567)
			(xy 418.243358 -394.690108) (xy 418.219382 -394.6906) (xy 418.218874 -394.6906) (xy 418.195299 -394.690227)
			(xy 418.14871 -394.682982) (xy 418.103791 -394.668652) (xy 418.061613 -394.64758) (xy 418.02318 -394.620267)
			(xy 417.989409 -394.587365) (xy 417.961104 -394.549657) (xy 417.949634 -394.529056) (xy 417.949126 -394.528294)
			(xy 417.551362 -393.839954) (xy 417.539504 -393.817268) (xy 417.522646 -393.76894) (xy 417.514066 -393.71848)
			(xy 417.513516 -393.692888) (xy 416.971522 -393.692888) (xy 417.283646 -394.232892) (xy 417.296471 -394.256224)
			(xy 417.314691 -394.306247) (xy 417.323951 -394.358673) (xy 417.32454 -394.385292) (xy 417.324031 -394.409269)
			(xy 417.316535 -394.456633) (xy 417.301726 -394.502242) (xy 417.279969 -394.544976) (xy 417.251798 -394.583782)
			(xy 417.217906 -394.617706) (xy 417.179127 -394.645915) (xy 417.136414 -394.667714) (xy 417.090819 -394.682566)
			(xy 417.043462 -394.690108) (xy 417.019486 -394.6906) (xy 417.018978 -394.6906) (xy 416.995403 -394.690224)
			(xy 416.948814 -394.682979) (xy 416.903895 -394.66865) (xy 416.861717 -394.647579) (xy 416.823284 -394.620266)
			(xy 416.789513 -394.587364) (xy 416.761208 -394.549657) (xy 416.749738 -394.529056) (xy 416.74923 -394.528294)
			(xy 416.351466 -393.839954) (xy 416.339608 -393.817268) (xy 416.32275 -393.76894) (xy 416.31417 -393.71848)
			(xy 416.31362 -393.692888) (xy 415.771626 -393.692888) (xy 416.08375 -394.232892) (xy 416.096576 -394.256224)
			(xy 416.114795 -394.306247) (xy 416.124055 -394.358673) (xy 416.124644 -394.385292) (xy 416.124131 -394.409269)
			(xy 416.116635 -394.456632) (xy 416.101827 -394.502241) (xy 416.080069 -394.544974) (xy 416.051899 -394.58378)
			(xy 416.018007 -394.617705) (xy 415.979229 -394.645913) (xy 415.936517 -394.667712) (xy 415.890922 -394.682566)
			(xy 415.843566 -394.690108) (xy 415.81959 -394.6906) (xy 415.819082 -394.6906) (xy 415.795507 -394.690221)
			(xy 415.748919 -394.682977) (xy 415.704 -394.668648) (xy 415.661821 -394.647577) (xy 415.623388 -394.620265)
			(xy 415.589617 -394.587364) (xy 415.561312 -394.549657) (xy 415.549842 -394.529056) (xy 415.549334 -394.528294)
			(xy 415.15157 -393.839954) (xy 415.139712 -393.817268) (xy 415.122855 -393.768939) (xy 415.114274 -393.71848)
			(xy 415.113724 -393.692888) (xy 414.571476 -393.692888) (xy 414.8836 -394.232892) (xy 414.896333 -394.25621)
			(xy 414.914427 -394.306158) (xy 414.923643 -394.358477) (xy 414.92424 -394.385038) (xy 414.92424 -394.385292)
			(xy 414.92373 -394.409281) (xy 414.916226 -394.45667) (xy 414.901402 -394.502301) (xy 414.879622 -394.545051)
			(xy 414.851423 -394.583869) (xy 414.817499 -394.617797) (xy 414.778686 -394.646001) (xy 414.735938 -394.667787)
			(xy 414.690309 -394.682617) (xy 414.642921 -394.690127) (xy 414.618932 -394.6906) (xy 414.595359 -394.69018)
			(xy 414.548772 -394.682944) (xy 414.503854 -394.668623) (xy 414.461675 -394.647558) (xy 414.423242 -394.620253)
			(xy 414.38947 -394.587357) (xy 414.361163 -394.549654) (xy 414.349692 -394.529056) (xy 414.349184 -394.528294)
			(xy 413.95142 -393.839954) (xy 413.939487 -393.817294) (xy 413.922556 -393.768965) (xy 413.913903 -393.718491)
			(xy 413.91332 -393.692888) (xy 413.37158 -393.692888) (xy 413.683704 -394.232892) (xy 413.696437 -394.25621)
			(xy 413.714531 -394.306158) (xy 413.723747 -394.358477) (xy 413.724344 -394.385038) (xy 413.724344 -394.385292)
			(xy 413.72383 -394.409281) (xy 413.716326 -394.456669) (xy 413.701502 -394.5023) (xy 413.679723 -394.54505)
			(xy 413.651524 -394.583867) (xy 413.617601 -394.617796) (xy 413.578788 -394.646) (xy 413.536041 -394.667785)
			(xy 413.490412 -394.682616) (xy 413.443025 -394.690127) (xy 413.419036 -394.6906) (xy 413.395463 -394.690177)
			(xy 413.348876 -394.682941) (xy 413.303958 -394.668621) (xy 413.26178 -394.647557) (xy 413.223346 -394.620252)
			(xy 413.189574 -394.587356) (xy 413.161267 -394.549654) (xy 413.149796 -394.529056) (xy 413.149288 -394.528294)
			(xy 412.751524 -393.839954) (xy 412.739592 -393.817294) (xy 412.72266 -393.768965) (xy 412.714007 -393.718491)
			(xy 412.713424 -393.692888) (xy 412.17143 -393.692888) (xy 412.483554 -394.232892) (xy 412.49638 -394.256224)
			(xy 412.514599 -394.306247) (xy 412.523859 -394.358673) (xy 412.524448 -394.385292) (xy 412.523931 -394.409268)
			(xy 412.516436 -394.456632) (xy 412.501627 -394.50224) (xy 412.47987 -394.544973) (xy 412.4517 -394.583779)
			(xy 412.417809 -394.617703) (xy 412.379031 -394.645912) (xy 412.33632 -394.667711) (xy 412.290726 -394.682565)
			(xy 412.24337 -394.690107) (xy 412.219394 -394.6906) (xy 412.218886 -394.6906) (xy 412.195312 -394.690217)
			(xy 412.148723 -394.682974) (xy 412.103804 -394.668646) (xy 412.061626 -394.647576) (xy 412.023193 -394.620264)
			(xy 411.989421 -394.587363) (xy 411.961116 -394.549656) (xy 411.949646 -394.529056) (xy 411.949138 -394.528294)
			(xy 411.551374 -393.839954) (xy 411.539517 -393.817268) (xy 411.522659 -393.768939) (xy 411.514078 -393.718479)
			(xy 411.513528 -393.692888) (xy 410.971534 -393.692888) (xy 411.283658 -394.232892) (xy 411.296484 -394.256224)
			(xy 411.314704 -394.306247) (xy 411.323963 -394.358673) (xy 411.324552 -394.385292) (xy 411.324031 -394.409268)
			(xy 411.316536 -394.456631) (xy 411.301727 -394.502239) (xy 411.279971 -394.544972) (xy 411.251801 -394.583778)
			(xy 411.217911 -394.617702) (xy 411.179133 -394.645911) (xy 411.136423 -394.66771) (xy 411.090829 -394.682564)
			(xy 411.043474 -394.690107) (xy 411.019498 -394.6906) (xy 411.01899 -394.6906) (xy 410.995416 -394.690214)
			(xy 410.948827 -394.682971) (xy 410.903908 -394.668644) (xy 410.86173 -394.647574) (xy 410.823297 -394.620263)
			(xy 410.789526 -394.587363) (xy 410.76122 -394.549656) (xy 410.74975 -394.529056) (xy 410.749242 -394.528294)
			(xy 410.351478 -393.839954) (xy 410.339621 -393.817268) (xy 410.322763 -393.768939) (xy 410.314182 -393.718479)
			(xy 410.313632 -393.692888) (xy 409.771638 -393.692888) (xy 410.083762 -394.232892) (xy 410.096589 -394.256224)
			(xy 410.114808 -394.306247) (xy 410.124067 -394.358673) (xy 410.124656 -394.385292) (xy 410.124131 -394.409268)
			(xy 410.116636 -394.45663) (xy 410.101828 -394.502239) (xy 410.080072 -394.544971) (xy 410.051902 -394.583776)
			(xy 410.018012 -394.617701) (xy 409.979235 -394.645909) (xy 409.936525 -394.667709) (xy 409.890932 -394.682563)
			(xy 409.843577 -394.690107) (xy 409.819602 -394.6906) (xy 409.819094 -394.6906) (xy 409.79552 -394.690211)
			(xy 409.748931 -394.682969) (xy 409.704013 -394.668642) (xy 409.661834 -394.647573) (xy 409.623401 -394.620262)
			(xy 409.58963 -394.587362) (xy 409.561324 -394.549656) (xy 409.549854 -394.529056) (xy 409.549346 -394.528294)
			(xy 409.151582 -393.839954) (xy 409.139725 -393.817268) (xy 409.122867 -393.768939) (xy 409.114286 -393.718479)
			(xy 409.113736 -393.692888) (xy 408.571488 -393.692888) (xy 408.883612 -394.232892) (xy 408.896346 -394.25621)
			(xy 408.914439 -394.306158) (xy 408.923655 -394.358477) (xy 408.924252 -394.385038) (xy 408.924252 -394.385292)
			(xy 408.92373 -394.409281) (xy 408.916227 -394.456668) (xy 408.901403 -394.502298) (xy 408.879624 -394.545048)
			(xy 408.851427 -394.583865) (xy 408.817504 -394.617793) (xy 408.778692 -394.645997) (xy 408.735946 -394.667783)
			(xy 408.690319 -394.682614) (xy 408.642933 -394.690126) (xy 408.618944 -394.6906) (xy 408.595371 -394.690171)
			(xy 408.548785 -394.682936) (xy 408.503867 -394.668616) (xy 408.461689 -394.647554) (xy 408.423255 -394.620249)
			(xy 408.389482 -394.587355) (xy 408.361175 -394.549654) (xy 408.349704 -394.529056) (xy 408.349196 -394.528294)
			(xy 407.951432 -393.839954) (xy 407.9395 -393.817294) (xy 407.922568 -393.768965) (xy 407.913915 -393.718491)
			(xy 407.913332 -393.692888) (xy 407.371592 -393.692888) (xy 407.683716 -394.232892) (xy 407.69645 -394.256209)
			(xy 407.714543 -394.306158) (xy 407.723759 -394.358477) (xy 407.724356 -394.385038) (xy 407.724356 -394.385292)
			(xy 407.72383 -394.409281) (xy 407.716327 -394.456667) (xy 407.701503 -394.502297) (xy 407.679725 -394.545047)
			(xy 407.651528 -394.583863) (xy 407.617606 -394.617791) (xy 407.578794 -394.645996) (xy 407.536049 -394.667782)
			(xy 407.490422 -394.682614) (xy 407.443037 -394.690126) (xy 407.419048 -394.6906) (xy 407.395475 -394.690168)
			(xy 407.348889 -394.682933) (xy 407.303971 -394.668614) (xy 407.261793 -394.647552) (xy 407.223359 -394.620248)
			(xy 407.189586 -394.587354) (xy 407.161279 -394.549654) (xy 407.149808 -394.529056) (xy 407.1493 -394.528294)
			(xy 406.751536 -393.839954) (xy 406.739605 -393.817294) (xy 406.722672 -393.768964) (xy 406.714019 -393.718491)
			(xy 406.713436 -393.692888) (xy 406.171442 -393.692888) (xy 406.483566 -394.232892) (xy 406.496393 -394.256223)
			(xy 406.514612 -394.306247) (xy 406.523871 -394.358673) (xy 406.52446 -394.385292) (xy 406.524031 -394.409273)
			(xy 406.516532 -394.456644) (xy 406.501719 -394.502261) (xy 406.479954 -394.544999) (xy 406.451774 -394.583809)
			(xy 406.417872 -394.617735) (xy 406.379082 -394.645942) (xy 406.336359 -394.667737) (xy 406.290753 -394.682582)
			(xy 406.243386 -394.690114) (xy 406.219406 -394.6906) (xy 406.218898 -394.6906) (xy 406.195324 -394.690208)
			(xy 406.148736 -394.682966) (xy 406.103817 -394.66864) (xy 406.061639 -394.647571) (xy 406.023206 -394.620261)
			(xy 405.989434 -394.587361) (xy 405.961128 -394.549656) (xy 405.949658 -394.529056) (xy 405.94915 -394.528294)
			(xy 405.551386 -393.839954) (xy 405.53953 -393.817267) (xy 405.522671 -393.768939) (xy 405.51409 -393.718479)
			(xy 405.51354 -393.692888) (xy 404.971546 -393.692888) (xy 405.28367 -394.232892) (xy 405.296497 -394.256223)
			(xy 405.314716 -394.306247) (xy 405.323975 -394.358673) (xy 405.324564 -394.385292) (xy 405.324131 -394.409273)
			(xy 405.316633 -394.456644) (xy 405.301819 -394.50226) (xy 405.280055 -394.544998) (xy 405.251875 -394.583808)
			(xy 405.217974 -394.617733) (xy 405.179184 -394.645941) (xy 405.136461 -394.667735) (xy 405.090856 -394.682581)
			(xy 405.04349 -394.690114) (xy 405.01951 -394.6906) (xy 405.019002 -394.6906) (xy 404.995428 -394.690205)
			(xy 404.94884 -394.682963) (xy 404.903921 -394.668638) (xy 404.861743 -394.64757) (xy 404.82331 -394.62026)
			(xy 404.789538 -394.587361) (xy 404.761233 -394.549656) (xy 404.749762 -394.529056) (xy 404.749254 -394.528294)
			(xy 404.35149 -393.839954) (xy 404.339634 -393.817267) (xy 404.322775 -393.768939) (xy 404.314194 -393.718479)
			(xy 404.313644 -393.692888) (xy 403.77165 -393.692888) (xy 404.083774 -394.232892) (xy 404.096601 -394.256223)
			(xy 404.11482 -394.306247) (xy 404.124079 -394.358673) (xy 404.124668 -394.385292) (xy 404.124231 -394.409272)
			(xy 404.116733 -394.456643) (xy 404.101919 -394.502259) (xy 404.080155 -394.544997) (xy 404.051976 -394.583806)
			(xy 404.018075 -394.617732) (xy 403.979287 -394.645939) (xy 403.936564 -394.667734) (xy 403.890959 -394.682581)
			(xy 403.843594 -394.690113) (xy 403.819614 -394.6906) (xy 403.819106 -394.6906) (xy 403.795532 -394.690201)
			(xy 403.748944 -394.682961) (xy 403.704026 -394.668636) (xy 403.661847 -394.647568) (xy 403.623414 -394.620259)
			(xy 403.589642 -394.58736) (xy 403.561337 -394.549655) (xy 403.549866 -394.529056) (xy 403.549358 -394.528294)
			(xy 403.151594 -393.839954) (xy 403.139738 -393.817267) (xy 403.122879 -393.768939) (xy 403.114298 -393.718479)
			(xy 403.113748 -393.692888) (xy 389.243866 -393.692888) (xy 389.55599 -394.232892) (xy 389.568819 -394.256222)
			(xy 389.587037 -394.306246) (xy 389.596295 -394.358673) (xy 389.596884 -394.385292) (xy 389.596431 -394.409272)
			(xy 389.588933 -394.456641) (xy 389.574121 -394.502255) (xy 389.552358 -394.544992) (xy 389.524181 -394.583801)
			(xy 389.490282 -394.617726) (xy 389.451496 -394.645934) (xy 389.408775 -394.66773) (xy 389.363173 -394.682578)
			(xy 389.315809 -394.690112) (xy 389.29183 -394.6906) (xy 389.291322 -394.6906) (xy 389.267749 -394.690188)
			(xy 389.221161 -394.68295) (xy 389.176243 -394.668628) (xy 389.134065 -394.647562) (xy 389.095631 -394.620255)
			(xy 389.061859 -394.587358) (xy 389.033553 -394.549655) (xy 389.022082 -394.529056) (xy 389.021574 -394.528294)
			(xy 388.62381 -393.839954) (xy 388.611948 -393.81727) (xy 388.595093 -393.76894) (xy 388.586513 -393.71848)
			(xy 388.585964 -393.692888) (xy 388.043716 -393.692888) (xy 388.35584 -394.232892) (xy 388.368576 -394.256208)
			(xy 388.386668 -394.306157) (xy 388.395883 -394.358476) (xy 388.39648 -394.385038) (xy 388.39648 -394.385292)
			(xy 388.396054 -394.409286) (xy 388.388548 -394.456684) (xy 388.373719 -394.502324) (xy 388.351932 -394.545082)
			(xy 388.323724 -394.583905) (xy 388.28979 -394.617837) (xy 388.250965 -394.646042) (xy 388.208206 -394.667826)
			(xy 388.162565 -394.682653) (xy 388.115166 -394.690156) (xy 388.091172 -394.6906) (xy 388.067597 -394.690229)
			(xy 388.021008 -394.682983) (xy 387.976089 -394.668653) (xy 387.93391 -394.647581) (xy 387.895478 -394.620268)
			(xy 387.861707 -394.587365) (xy 387.833402 -394.549657) (xy 387.821932 -394.529056) (xy 387.821424 -394.528294)
			(xy 387.42366 -393.839954) (xy 387.41173 -393.817293) (xy 387.394797 -393.768964) (xy 387.386143 -393.718491)
			(xy 387.38556 -393.692888) (xy 386.84382 -393.692888) (xy 387.155944 -394.232892) (xy 387.16868 -394.256208)
			(xy 387.186772 -394.306157) (xy 387.195988 -394.358476) (xy 387.196584 -394.385038) (xy 387.196584 -394.385292)
			(xy 387.196154 -394.409286) (xy 387.188648 -394.456684) (xy 387.173819 -394.502323) (xy 387.152033 -394.545081)
			(xy 387.123825 -394.583904) (xy 387.089892 -394.617836) (xy 387.051067 -394.646041) (xy 387.008308 -394.667825)
			(xy 386.962668 -394.682652) (xy 386.91527 -394.690156) (xy 386.891276 -394.6906) (xy 386.867701 -394.690226)
			(xy 386.821112 -394.68298) (xy 386.776193 -394.668651) (xy 386.734015 -394.647579) (xy 386.695582 -394.620267)
			(xy 386.661811 -394.587365) (xy 386.633506 -394.549657) (xy 386.622036 -394.529056) (xy 386.621528 -394.528294)
			(xy 386.223764 -393.839954) (xy 386.211835 -393.817292) (xy 386.194901 -393.768964) (xy 386.186248 -393.718491)
			(xy 386.185664 -393.692888) (xy 385.64367 -393.692888) (xy 385.955794 -394.232892) (xy 385.968623 -394.256222)
			(xy 385.986841 -394.306246) (xy 385.996099 -394.358673) (xy 385.996688 -394.385292) (xy 385.996231 -394.409271)
			(xy 385.988733 -394.45664) (xy 385.973921 -394.502254) (xy 385.952159 -394.544991) (xy 385.923982 -394.5838)
			(xy 385.890084 -394.617725) (xy 385.851298 -394.645932) (xy 385.808578 -394.667728) (xy 385.762976 -394.682577)
			(xy 385.715613 -394.690112) (xy 385.691634 -394.6906) (xy 385.691126 -394.6906) (xy 385.667553 -394.690185)
			(xy 385.620965 -394.682948) (xy 385.576047 -394.668626) (xy 385.533869 -394.64756) (xy 385.495436 -394.620254)
			(xy 385.461663 -394.587357) (xy 385.433357 -394.549655) (xy 385.421886 -394.529056) (xy 385.421378 -394.528294)
			(xy 385.023614 -393.839954) (xy 385.011752 -393.81727) (xy 384.994897 -393.76894) (xy 384.986317 -393.71848)
			(xy 384.985768 -393.692888) (xy 384.443774 -393.692888) (xy 384.755898 -394.232892) (xy 384.768719 -394.256226)
			(xy 384.786942 -394.306248) (xy 384.796203 -394.358674) (xy 384.796792 -394.385292) (xy 384.796331 -394.409271)
			(xy 384.788834 -394.45664) (xy 384.774022 -394.502253) (xy 384.75226 -394.54499) (xy 384.724083 -394.583798)
			(xy 384.690186 -394.617723) (xy 384.6514 -394.645931) (xy 384.608681 -394.667727) (xy 384.563079 -394.682576)
			(xy 384.515717 -394.690112) (xy 384.491738 -394.6906) (xy 384.49123 -394.6906) (xy 384.467657 -394.690182)
			(xy 384.42107 -394.682945) (xy 384.376152 -394.668624) (xy 384.333973 -394.647559) (xy 384.29554 -394.620253)
			(xy 384.261768 -394.587357) (xy 384.233461 -394.549654) (xy 384.22199 -394.529056) (xy 384.221482 -394.528294)
			(xy 383.823718 -393.839954) (xy 383.811856 -393.81727) (xy 383.795001 -393.76894) (xy 383.786421 -393.71848)
			(xy 383.785872 -393.692888) (xy 383.243878 -393.692888) (xy 383.556002 -394.232892) (xy 383.568824 -394.256226)
			(xy 383.587046 -394.306248) (xy 383.596307 -394.358674) (xy 383.596896 -394.385292) (xy 383.596431 -394.409271)
			(xy 383.588934 -394.456639) (xy 383.574122 -394.502252) (xy 383.552361 -394.544989) (xy 383.524185 -394.583797)
			(xy 383.490287 -394.617722) (xy 383.451502 -394.64593) (xy 383.408784 -394.667726) (xy 383.363183 -394.682575)
			(xy 383.315821 -394.690111) (xy 383.291842 -394.6906) (xy 383.291334 -394.6906) (xy 383.267761 -394.690179)
			(xy 383.221174 -394.682942) (xy 383.176256 -394.668622) (xy 383.134078 -394.647557) (xy 383.095644 -394.620252)
			(xy 383.061872 -394.587356) (xy 383.033565 -394.549654) (xy 383.022094 -394.529056) (xy 383.021586 -394.528294)
			(xy 382.623822 -393.839954) (xy 382.611961 -393.81727) (xy 382.595105 -393.76894) (xy 382.586526 -393.71848)
			(xy 382.585976 -393.692888) (xy 382.043728 -393.692888) (xy 382.355852 -394.232892) (xy 382.368589 -394.256208)
			(xy 382.386681 -394.306157) (xy 382.395896 -394.358476) (xy 382.396492 -394.385038) (xy 382.396492 -394.385292)
			(xy 382.396054 -394.409286) (xy 382.388548 -394.456682) (xy 382.37372 -394.502321) (xy 382.351934 -394.545079)
			(xy 382.323728 -394.583901) (xy 382.289795 -394.617833) (xy 382.250972 -394.646038) (xy 382.208214 -394.667823)
			(xy 382.162575 -394.68265) (xy 382.115178 -394.690155) (xy 382.091184 -394.6906) (xy 382.06761 -394.690219)
			(xy 382.021021 -394.682975) (xy 381.976102 -394.668647) (xy 381.933923 -394.647576) (xy 381.895491 -394.620265)
			(xy 381.861719 -394.587363) (xy 381.833414 -394.549656) (xy 381.821944 -394.529056) (xy 381.821436 -394.528294)
			(xy 381.423672 -393.839954) (xy 381.411736 -393.817296) (xy 381.394806 -393.768965) (xy 381.386155 -393.718492)
			(xy 381.385572 -393.692888) (xy 380.843832 -393.692888) (xy 381.155956 -394.232892) (xy 381.168693 -394.256208)
			(xy 381.186785 -394.306157) (xy 381.196 -394.358476) (xy 381.196596 -394.385038) (xy 381.196596 -394.385292)
			(xy 381.196154 -394.409286) (xy 381.188648 -394.456682) (xy 381.17382 -394.50232) (xy 381.152035 -394.545077)
			(xy 381.123829 -394.5839) (xy 381.089897 -394.617831) (xy 381.051074 -394.646037) (xy 381.008317 -394.667822)
			(xy 380.962678 -394.682649) (xy 380.915282 -394.690155) (xy 380.891288 -394.6906) (xy 380.867714 -394.690216)
			(xy 380.821125 -394.682973) (xy 380.776206 -394.668645) (xy 380.734028 -394.647575) (xy 380.695595 -394.620264)
			(xy 380.661823 -394.587363) (xy 380.633518 -394.549656) (xy 380.622048 -394.529056) (xy 380.62154 -394.528294)
			(xy 380.223776 -393.839954) (xy 380.21184 -393.817296) (xy 380.19491 -393.768965) (xy 380.186259 -393.718492)
			(xy 380.185676 -393.692888) (xy 379.643682 -393.692888) (xy 379.955806 -394.232892) (xy 379.968628 -394.256226)
			(xy 379.98685 -394.306248) (xy 379.996111 -394.358674) (xy 379.9967 -394.385292) (xy 379.996231 -394.409271)
			(xy 379.988734 -394.456639) (xy 379.973922 -394.502251) (xy 379.952161 -394.544988) (xy 379.923986 -394.583795)
			(xy 379.890089 -394.617721) (xy 379.851304 -394.645928) (xy 379.808586 -394.667725) (xy 379.762986 -394.682574)
			(xy 379.715624 -394.690111) (xy 379.691646 -394.6906) (xy 379.691138 -394.6906) (xy 379.667565 -394.690176)
			(xy 379.620978 -394.68294) (xy 379.57606 -394.66862) (xy 379.533882 -394.647556) (xy 379.495448 -394.620251)
			(xy 379.461676 -394.587356) (xy 379.433369 -394.549654) (xy 379.421898 -394.529056) (xy 379.42139 -394.528294)
			(xy 379.023626 -393.839954) (xy 379.011765 -393.81727) (xy 378.994909 -393.76894) (xy 378.98633 -393.71848)
			(xy 378.98578 -393.692888) (xy 378.443786 -393.692888) (xy 378.75591 -394.232892) (xy 378.768732 -394.256226)
			(xy 378.786954 -394.306248) (xy 378.796215 -394.358673) (xy 378.796804 -394.385292) (xy 378.796331 -394.409271)
			(xy 378.788834 -394.456638) (xy 378.774023 -394.502251) (xy 378.752262 -394.544986) (xy 378.724087 -394.583794)
			(xy 378.690191 -394.617719) (xy 378.651407 -394.645927) (xy 378.608689 -394.667724) (xy 378.563089 -394.682574)
			(xy 378.515728 -394.690111) (xy 378.49175 -394.6906) (xy 378.491242 -394.6906) (xy 378.467669 -394.690172)
			(xy 378.421083 -394.682937) (xy 378.376165 -394.668617) (xy 378.333986 -394.647554) (xy 378.295553 -394.62025)
			(xy 378.26178 -394.587355) (xy 378.233473 -394.549654) (xy 378.222002 -394.529056) (xy 378.221494 -394.528294)
			(xy 377.82373 -393.839954) (xy 377.811869 -393.81727) (xy 377.795013 -393.76894) (xy 377.786434 -393.71848)
			(xy 377.785884 -393.692888) (xy 377.24389 -393.692888) (xy 377.556014 -394.232892) (xy 377.568837 -394.256226)
			(xy 377.587058 -394.306248) (xy 377.596319 -394.358673) (xy 377.596908 -394.385292) (xy 377.596431 -394.40927)
			(xy 377.588934 -394.456637) (xy 377.574123 -394.50225) (xy 377.552363 -394.544985) (xy 377.524188 -394.583793)
			(xy 377.490292 -394.617718) (xy 377.451509 -394.645926) (xy 377.408792 -394.667723) (xy 377.363192 -394.682573)
			(xy 377.315832 -394.69011) (xy 377.291854 -394.6906) (xy 377.291346 -394.6906) (xy 377.267773 -394.690169)
			(xy 377.221187 -394.682935) (xy 377.176269 -394.668615) (xy 377.134091 -394.647553) (xy 377.095657 -394.620249)
			(xy 377.061884 -394.587355) (xy 377.033577 -394.549654) (xy 377.022106 -394.529056) (xy 377.021598 -394.528294)
			(xy 376.623834 -393.839954) (xy 376.611974 -393.81727) (xy 376.595118 -393.76894) (xy 376.586538 -393.71848)
			(xy 376.585988 -393.692888) (xy 376.04374 -393.692888) (xy 376.355864 -394.232892) (xy 376.368602 -394.256207)
			(xy 376.386693 -394.306157) (xy 376.395908 -394.358476) (xy 376.396504 -394.385038) (xy 376.396504 -394.385292)
			(xy 376.396054 -394.409285) (xy 376.388549 -394.456681) (xy 376.373721 -394.502319) (xy 376.351936 -394.545075)
			(xy 376.323731 -394.583897) (xy 376.2898 -394.617829) (xy 376.250978 -394.646034) (xy 376.208222 -394.66782)
			(xy 376.162585 -394.682648) (xy 376.115189 -394.690154) (xy 376.091196 -394.6906) (xy 376.067622 -394.690209)
			(xy 376.021033 -394.682967) (xy 375.976115 -394.668641) (xy 375.933936 -394.647572) (xy 375.895503 -394.620262)
			(xy 375.861732 -394.587362) (xy 375.833426 -394.549656) (xy 375.821956 -394.529056) (xy 375.821448 -394.528294)
			(xy 375.423684 -393.839954) (xy 375.411748 -393.817296) (xy 375.394819 -393.768965) (xy 375.386167 -393.718492)
			(xy 375.385584 -393.692888) (xy 374.843844 -393.692888) (xy 375.155968 -394.232892) (xy 375.168706 -394.256207)
			(xy 375.186797 -394.306157) (xy 375.196012 -394.358476) (xy 375.196608 -394.385038) (xy 375.196608 -394.385292)
			(xy 375.196154 -394.409285) (xy 375.188649 -394.45668) (xy 375.173821 -394.502318) (xy 375.152037 -394.545074)
			(xy 375.123832 -394.583896) (xy 375.089902 -394.617827) (xy 375.051081 -394.646033) (xy 375.008325 -394.667818)
			(xy 374.962688 -394.682647) (xy 374.915293 -394.690154) (xy 374.8913 -394.6906) (xy 374.867726 -394.690206)
			(xy 374.821138 -394.682965) (xy 374.776219 -394.668639) (xy 374.734041 -394.64757) (xy 374.695608 -394.620261)
			(xy 374.661836 -394.587361) (xy 374.63353 -394.549656) (xy 374.62206 -394.529056) (xy 374.621552 -394.528294)
			(xy 374.223788 -393.839954) (xy 374.211853 -393.817296) (xy 374.194923 -393.768965) (xy 374.186271 -393.718491)
			(xy 374.185688 -393.692888) (xy 373.643694 -393.692888) (xy 373.955818 -394.232892) (xy 373.968641 -394.256226)
			(xy 373.986862 -394.306248) (xy 373.996123 -394.358673) (xy 373.996712 -394.385292) (xy 373.996231 -394.40927)
			(xy 373.988734 -394.456637) (xy 373.973924 -394.502249) (xy 373.952164 -394.544984) (xy 373.923989 -394.583791)
			(xy 373.890094 -394.617716) (xy 373.851311 -394.645924) (xy 373.808595 -394.667722) (xy 373.762996 -394.682572)
			(xy 373.715636 -394.69011) (xy 373.691658 -394.6906) (xy 373.69115 -394.6906) (xy 373.667577 -394.690166)
			(xy 373.620991 -394.682932) (xy 373.576073 -394.668613) (xy 373.533895 -394.647551) (xy 373.495461 -394.620248)
			(xy 373.461688 -394.587354) (xy 373.433381 -394.549653) (xy 373.42191 -394.529056) (xy 373.421402 -394.528294)
			(xy 373.023638 -393.839954) (xy 373.011778 -393.817269) (xy 372.994922 -393.76894) (xy 372.986342 -393.71848)
			(xy 372.985792 -393.692888) (xy 372.443798 -393.692888) (xy 372.755922 -394.232892) (xy 372.768745 -394.256225)
			(xy 372.786966 -394.306248) (xy 372.796227 -394.358673) (xy 372.796816 -394.385292) (xy 372.796331 -394.40927)
			(xy 372.788834 -394.456636) (xy 372.774024 -394.502248) (xy 372.752264 -394.544983) (xy 372.72409 -394.58379)
			(xy 372.690196 -394.617715) (xy 372.651413 -394.645923) (xy 372.608698 -394.66772) (xy 372.563099 -394.682571)
			(xy 372.51574 -394.69011) (xy 372.491762 -394.6906) (xy 372.491254 -394.6906) (xy 372.467682 -394.690163)
			(xy 372.421095 -394.682929) (xy 372.376178 -394.668611) (xy 372.333999 -394.64755) (xy 372.295566 -394.620247)
			(xy 372.261793 -394.587353) (xy 372.233485 -394.549653) (xy 372.222014 -394.529056) (xy 372.221506 -394.528294)
			(xy 371.823742 -393.839954) (xy 371.811882 -393.817269) (xy 371.795026 -393.76894) (xy 371.786446 -393.71848)
			(xy 371.785896 -393.692888) (xy 371.243902 -393.692888) (xy 371.556026 -394.232892) (xy 371.56885 -394.256225)
			(xy 371.587071 -394.306247) (xy 371.596331 -394.358673) (xy 371.59692 -394.385292) (xy 371.596431 -394.40927)
			(xy 371.588935 -394.456636) (xy 371.574124 -394.502247) (xy 371.552365 -394.544982) (xy 371.524192 -394.583789)
			(xy 371.490297 -394.617713) (xy 371.451516 -394.645922) (xy 371.4088 -394.667719) (xy 371.363202 -394.68257)
			(xy 371.315843 -394.69011) (xy 371.291866 -394.6906) (xy 371.291358 -394.6906) (xy 371.267786 -394.690159)
			(xy 371.2212 -394.682927) (xy 371.176282 -394.668609) (xy 371.134104 -394.647548) (xy 371.09567 -394.620246)
			(xy 371.061897 -394.587353) (xy 371.03359 -394.549653) (xy 371.022118 -394.529056) (xy 371.02161 -394.528294)
			(xy 370.623846 -393.839954) (xy 370.611986 -393.817269) (xy 370.59513 -393.76894) (xy 370.58655 -393.71848)
			(xy 370.586 -393.692888) (xy 354.671418 -393.692888) (xy 354.983542 -394.232892) (xy 354.996367 -394.256224)
			(xy 355.014587 -394.306247) (xy 355.023847 -394.358673) (xy 355.024436 -394.385292) (xy 355.023931 -394.409269)
			(xy 355.016435 -394.456633) (xy 355.001626 -394.502243) (xy 354.979868 -394.544977) (xy 354.951696 -394.583783)
			(xy 354.917804 -394.617708) (xy 354.879024 -394.645916) (xy 354.836311 -394.667715) (xy 354.790716 -394.682567)
			(xy 354.743358 -394.690108) (xy 354.719382 -394.6906) (xy 354.718874 -394.6906) (xy 354.695299 -394.690227)
			(xy 354.64871 -394.682982) (xy 354.603791 -394.668652) (xy 354.561613 -394.64758) (xy 354.52318 -394.620267)
			(xy 354.489409 -394.587365) (xy 354.461104 -394.549657) (xy 354.449634 -394.529056) (xy 354.449126 -394.528294)
			(xy 354.051362 -393.839954) (xy 354.039504 -393.817268) (xy 354.022646 -393.76894) (xy 354.014066 -393.71848)
			(xy 354.013516 -393.692888) (xy 353.471522 -393.692888) (xy 353.783646 -394.232892) (xy 353.796471 -394.256224)
			(xy 353.814691 -394.306247) (xy 353.823951 -394.358673) (xy 353.82454 -394.385292) (xy 353.824054 -394.409296)
			(xy 353.816541 -394.456713) (xy 353.8017 -394.502369) (xy 353.779896 -394.54514) (xy 353.751667 -394.583972)
			(xy 353.717709 -394.617907) (xy 353.678857 -394.646108) (xy 353.636071 -394.667882) (xy 353.590404 -394.682691)
			(xy 353.542982 -394.69017) (xy 353.518978 -394.6906) (xy 353.518724 -394.6906) (xy 353.495151 -394.690187)
			(xy 353.448563 -394.682949) (xy 353.403645 -394.668627) (xy 353.361467 -394.647561) (xy 353.323033 -394.620255)
			(xy 353.289261 -394.587358) (xy 353.260955 -394.549655) (xy 353.249484 -394.529056) (xy 353.248976 -394.528294)
			(xy 352.851212 -393.839954) (xy 352.839279 -393.817295) (xy 352.822347 -393.768965) (xy 352.813695 -393.718491)
			(xy 352.813112 -393.692888) (xy 352.271372 -393.692888) (xy 352.583496 -394.232892) (xy 352.596228 -394.25621)
			(xy 352.614323 -394.306158) (xy 352.623539 -394.358477) (xy 352.624136 -394.385038) (xy 352.624136 -394.385292)
			(xy 352.62363 -394.409282) (xy 352.616126 -394.45667) (xy 352.601301 -394.502302) (xy 352.579521 -394.545053)
			(xy 352.551322 -394.58387) (xy 352.517397 -394.617798) (xy 352.478583 -394.646002) (xy 352.435835 -394.667788)
			(xy 352.390205 -394.682618) (xy 352.342818 -394.690127) (xy 352.318828 -394.6906) (xy 352.295255 -394.690184)
			(xy 352.248668 -394.682946) (xy 352.20375 -394.668625) (xy 352.161571 -394.64756) (xy 352.123138 -394.620254)
			(xy 352.089365 -394.587357) (xy 352.061059 -394.549654) (xy 352.049588 -394.529056) (xy 352.04908 -394.528294)
			(xy 351.651316 -393.839954) (xy 351.639383 -393.817294) (xy 351.622452 -393.768965) (xy 351.613799 -393.718491)
			(xy 351.613216 -393.692888) (xy 351.071476 -393.692888) (xy 351.3836 -394.232892) (xy 351.396333 -394.25621)
			(xy 351.414427 -394.306158) (xy 351.423643 -394.358477) (xy 351.42424 -394.385038) (xy 351.42424 -394.385292)
			(xy 351.42373 -394.409281) (xy 351.416226 -394.45667) (xy 351.401402 -394.502301) (xy 351.379622 -394.545051)
			(xy 351.351423 -394.583869) (xy 351.317499 -394.617797) (xy 351.278686 -394.646001) (xy 351.235938 -394.667787)
			(xy 351.190309 -394.682617) (xy 351.142921 -394.690127) (xy 351.118932 -394.6906) (xy 351.118678 -394.6906)
			(xy 351.095103 -394.690224) (xy 351.048514 -394.682979) (xy 351.003595 -394.66865) (xy 350.961417 -394.647579)
			(xy 350.922984 -394.620266) (xy 350.889213 -394.587364) (xy 350.860908 -394.549657) (xy 350.849438 -394.529056)
			(xy 350.84893 -394.528294) (xy 350.451166 -393.839954) (xy 350.439308 -393.817268) (xy 350.42245 -393.76894)
			(xy 350.41387 -393.71848) (xy 350.41332 -393.692888) (xy 349.871326 -393.692888) (xy 350.18345 -394.232892)
			(xy 350.196276 -394.256224) (xy 350.214495 -394.306247) (xy 350.223755 -394.358673) (xy 350.224344 -394.385292)
			(xy 350.223831 -394.409269) (xy 350.216335 -394.456632) (xy 350.201527 -394.502241) (xy 350.179769 -394.544974)
			(xy 350.151599 -394.58378) (xy 350.117707 -394.617705) (xy 350.078929 -394.645913) (xy 350.036217 -394.667712)
			(xy 349.990622 -394.682566) (xy 349.943266 -394.690108) (xy 349.91929 -394.6906) (xy 349.918782 -394.6906)
			(xy 349.895207 -394.690221) (xy 349.848619 -394.682977) (xy 349.8037 -394.668648) (xy 349.761521 -394.647577)
			(xy 349.723088 -394.620265) (xy 349.689317 -394.587364) (xy 349.661012 -394.549657) (xy 349.649542 -394.529056)
			(xy 349.649034 -394.528294) (xy 349.25127 -393.839954) (xy 349.239412 -393.817268) (xy 349.222555 -393.768939)
			(xy 349.213974 -393.71848) (xy 349.213424 -393.692888) (xy 348.67143 -393.692888) (xy 348.983554 -394.232892)
			(xy 348.99638 -394.256224) (xy 349.014599 -394.306247) (xy 349.023859 -394.358673) (xy 349.024448 -394.385292)
			(xy 349.023931 -394.409268) (xy 349.016436 -394.456632) (xy 349.001627 -394.50224) (xy 348.97987 -394.544973)
			(xy 348.9517 -394.583779) (xy 348.917809 -394.617703) (xy 348.879031 -394.645912) (xy 348.83632 -394.667711)
			(xy 348.790726 -394.682565) (xy 348.74337 -394.690107) (xy 348.719394 -394.6906) (xy 348.718886 -394.6906)
			(xy 348.695312 -394.690217) (xy 348.648723 -394.682974) (xy 348.603804 -394.668646) (xy 348.561626 -394.647576)
			(xy 348.523193 -394.620264) (xy 348.489421 -394.587363) (xy 348.461116 -394.549656) (xy 348.449646 -394.529056)
			(xy 348.449138 -394.528294) (xy 348.051374 -393.839954) (xy 348.039517 -393.817268) (xy 348.022659 -393.768939)
			(xy 348.014078 -393.718479) (xy 348.013528 -393.692888) (xy 347.47128 -393.692888) (xy 347.783404 -394.232892)
			(xy 347.796137 -394.25621) (xy 347.814231 -394.306158) (xy 347.823447 -394.358477) (xy 347.824044 -394.385038)
			(xy 347.824044 -394.385292) (xy 347.82353 -394.409281) (xy 347.816026 -394.456669) (xy 347.801202 -394.5023)
			(xy 347.779423 -394.54505) (xy 347.751224 -394.583867) (xy 347.717301 -394.617796) (xy 347.678488 -394.646)
			(xy 347.635741 -394.667785) (xy 347.590112 -394.682616) (xy 347.542725 -394.690127) (xy 347.518736 -394.6906)
			(xy 347.495163 -394.690177) (xy 347.448576 -394.682941) (xy 347.403658 -394.668621) (xy 347.36148 -394.647557)
			(xy 347.323046 -394.620252) (xy 347.289274 -394.587356) (xy 347.260967 -394.549654) (xy 347.249496 -394.529056)
			(xy 347.248988 -394.528294) (xy 346.851224 -393.839954) (xy 346.839292 -393.817294) (xy 346.82236 -393.768965)
			(xy 346.813707 -393.718491) (xy 346.813124 -393.692888) (xy 346.271384 -393.692888) (xy 346.583508 -394.232892)
			(xy 346.596241 -394.25621) (xy 346.614335 -394.306158) (xy 346.623551 -394.358477) (xy 346.624148 -394.385038)
			(xy 346.624148 -394.385292) (xy 346.62363 -394.409281) (xy 346.616126 -394.456669) (xy 346.601303 -394.502299)
			(xy 346.579524 -394.545049) (xy 346.551325 -394.583866) (xy 346.517403 -394.617794) (xy 346.47859 -394.645998)
			(xy 346.435843 -394.667784) (xy 346.390215 -394.682615) (xy 346.342829 -394.690126) (xy 346.31884 -394.6906)
			(xy 346.295267 -394.690174) (xy 346.24868 -394.682939) (xy 346.203763 -394.668618) (xy 346.161584 -394.647555)
			(xy 346.123151 -394.620251) (xy 346.089378 -394.587355) (xy 346.061071 -394.549654) (xy 346.0496 -394.529056)
			(xy 346.049092 -394.528294) (xy 345.651328 -393.839954) (xy 345.639396 -393.817294) (xy 345.622464 -393.768965)
			(xy 345.613811 -393.718491) (xy 345.613228 -393.692888) (xy 345.071488 -393.692888) (xy 345.383612 -394.232892)
			(xy 345.396346 -394.25621) (xy 345.414439 -394.306158) (xy 345.423655 -394.358477) (xy 345.424252 -394.385038)
			(xy 345.424252 -394.385292) (xy 345.42373 -394.409281) (xy 345.416227 -394.456668) (xy 345.401403 -394.502298)
			(xy 345.379624 -394.545048) (xy 345.351427 -394.583865) (xy 345.317504 -394.617793) (xy 345.278692 -394.645997)
			(xy 345.235946 -394.667783) (xy 345.190319 -394.682614) (xy 345.142933 -394.690126) (xy 345.118944 -394.6906)
			(xy 345.11869 -394.6906) (xy 345.095116 -394.690214) (xy 345.048527 -394.682971) (xy 345.003608 -394.668644)
			(xy 344.96143 -394.647574) (xy 344.922997 -394.620263) (xy 344.889226 -394.587363) (xy 344.86092 -394.549656)
			(xy 344.84945 -394.529056) (xy 344.848942 -394.528294) (xy 344.451178 -393.839954) (xy 344.439321 -393.817268)
			(xy 344.422463 -393.768939) (xy 344.413882 -393.718479) (xy 344.413332 -393.692888) (xy 343.871338 -393.692888)
			(xy 344.183462 -394.232892) (xy 344.196289 -394.256224) (xy 344.214508 -394.306247) (xy 344.223767 -394.358673)
			(xy 344.224356 -394.385292) (xy 344.223831 -394.409268) (xy 344.216336 -394.45663) (xy 344.201528 -394.502239)
			(xy 344.179772 -394.544971) (xy 344.151602 -394.583776) (xy 344.117712 -394.617701) (xy 344.078935 -394.645909)
			(xy 344.036225 -394.667709) (xy 343.990632 -394.682563) (xy 343.943277 -394.690107) (xy 343.919302 -394.6906)
			(xy 343.918794 -394.6906) (xy 343.89522 -394.690211) (xy 343.848631 -394.682969) (xy 343.803713 -394.668642)
			(xy 343.761534 -394.647573) (xy 343.723101 -394.620262) (xy 343.68933 -394.587362) (xy 343.661024 -394.549656)
			(xy 343.649554 -394.529056) (xy 343.649046 -394.528294) (xy 343.251282 -393.839954) (xy 343.239425 -393.817268)
			(xy 343.222567 -393.768939) (xy 343.213986 -393.718479) (xy 343.213436 -393.692888) (xy 342.671442 -393.692888)
			(xy 342.983566 -394.232892) (xy 342.996393 -394.256223) (xy 343.014612 -394.306247) (xy 343.023871 -394.358673)
			(xy 343.02446 -394.385292) (xy 343.024031 -394.409273) (xy 343.016532 -394.456644) (xy 343.001719 -394.502261)
			(xy 342.979954 -394.544999) (xy 342.951774 -394.583809) (xy 342.917872 -394.617735) (xy 342.879082 -394.645942)
			(xy 342.836359 -394.667737) (xy 342.790753 -394.682582) (xy 342.743386 -394.690114) (xy 342.719406 -394.6906)
			(xy 342.718898 -394.6906) (xy 342.695324 -394.690208) (xy 342.648736 -394.682966) (xy 342.603817 -394.66864)
			(xy 342.561639 -394.647571) (xy 342.523206 -394.620261) (xy 342.489434 -394.587361) (xy 342.461128 -394.549656)
			(xy 342.449658 -394.529056) (xy 342.44915 -394.528294) (xy 342.051386 -393.839954) (xy 342.03953 -393.817267)
			(xy 342.022671 -393.768939) (xy 342.01409 -393.718479) (xy 342.01354 -393.692888) (xy 341.471292 -393.692888)
			(xy 341.783416 -394.232892) (xy 341.79615 -394.256209) (xy 341.814243 -394.306158) (xy 341.823459 -394.358477)
			(xy 341.824056 -394.385038) (xy 341.824056 -394.385292) (xy 341.82353 -394.409281) (xy 341.816027 -394.456667)
			(xy 341.801203 -394.502297) (xy 341.779425 -394.545047) (xy 341.751228 -394.583863) (xy 341.717306 -394.617791)
			(xy 341.678494 -394.645996) (xy 341.635749 -394.667782) (xy 341.590122 -394.682614) (xy 341.542737 -394.690126)
			(xy 341.518748 -394.6906) (xy 341.495175 -394.690168) (xy 341.448589 -394.682933) (xy 341.403671 -394.668614)
			(xy 341.361493 -394.647552) (xy 341.323059 -394.620248) (xy 341.289286 -394.587354) (xy 341.260979 -394.549654)
			(xy 341.249508 -394.529056) (xy 341.249 -394.528294) (xy 340.851236 -393.839954) (xy 340.839305 -393.817294)
			(xy 340.822372 -393.768964) (xy 340.813719 -393.718491) (xy 340.813136 -393.692888) (xy 340.271396 -393.692888)
			(xy 340.58352 -394.232892) (xy 340.596254 -394.256209) (xy 340.614348 -394.306158) (xy 340.623563 -394.358476)
			(xy 340.62416 -394.385038) (xy 340.62416 -394.385292) (xy 340.623754 -394.409287) (xy 340.616247 -394.456687)
			(xy 340.601417 -394.502329) (xy 340.579628 -394.545088) (xy 340.551418 -394.583912) (xy 340.517482 -394.617844)
			(xy 340.478654 -394.646049) (xy 340.435892 -394.667832) (xy 340.390248 -394.682657) (xy 340.342847 -394.690157)
			(xy 340.318852 -394.6906) (xy 340.295279 -394.690164) (xy 340.248693 -394.682931) (xy 340.203776 -394.668612)
			(xy 340.161597 -394.647551) (xy 340.123164 -394.620247) (xy 340.089391 -394.587354) (xy 340.061083 -394.549653)
			(xy 340.049612 -394.529056) (xy 340.049104 -394.528294) (xy 339.65134 -393.839954) (xy 339.639409 -393.817293)
			(xy 339.622476 -393.768964) (xy 339.613823 -393.718491) (xy 339.61324 -393.692888) (xy 339.0715 -393.692888)
			(xy 339.383624 -394.232892) (xy 339.396359 -394.256209) (xy 339.414452 -394.306158) (xy 339.423667 -394.358476)
			(xy 339.424264 -394.385038) (xy 339.424264 -394.385292) (xy 339.423854 -394.409287) (xy 339.416347 -394.456687)
			(xy 339.401517 -394.502328) (xy 339.379729 -394.545087) (xy 339.351519 -394.583911) (xy 339.317583 -394.617843)
			(xy 339.278756 -394.646048) (xy 339.235995 -394.667831) (xy 339.190352 -394.682656) (xy 339.142951 -394.690157)
			(xy 339.118956 -394.6906) (xy 339.118702 -394.6906) (xy 339.095128 -394.690205) (xy 339.04854 -394.682963)
			(xy 339.003621 -394.668638) (xy 338.961443 -394.64757) (xy 338.92301 -394.62026) (xy 338.889238 -394.587361)
			(xy 338.860933 -394.549656) (xy 338.849462 -394.529056) (xy 338.848954 -394.528294) (xy 338.45119 -393.839954)
			(xy 338.439334 -393.817267) (xy 338.422475 -393.768939) (xy 338.413894 -393.718479) (xy 338.413344 -393.692888)
			(xy 337.87135 -393.692888) (xy 338.183474 -394.232892) (xy 338.196301 -394.256223) (xy 338.21452 -394.306247)
			(xy 338.223779 -394.358673) (xy 338.224368 -394.385292) (xy 338.223931 -394.409272) (xy 338.216433 -394.456643)
			(xy 338.201619 -394.502259) (xy 338.179855 -394.544997) (xy 338.151676 -394.583806) (xy 338.117775 -394.617732)
			(xy 338.078987 -394.645939) (xy 338.036264 -394.667734) (xy 337.990659 -394.682581) (xy 337.943294 -394.690113)
			(xy 337.919314 -394.6906) (xy 337.918806 -394.6906) (xy 337.895232 -394.690201) (xy 337.848644 -394.682961)
			(xy 337.803726 -394.668636) (xy 337.761547 -394.647568) (xy 337.723114 -394.620259) (xy 337.689342 -394.58736)
			(xy 337.661037 -394.549655) (xy 337.649566 -394.529056) (xy 337.649058 -394.528294) (xy 337.251294 -393.839954)
			(xy 337.239438 -393.817267) (xy 337.222579 -393.768939) (xy 337.213998 -393.718479) (xy 337.213448 -393.692888)
			(xy 336.671454 -393.692888) (xy 336.983578 -394.232892) (xy 336.996406 -394.256223) (xy 337.014624 -394.306247)
			(xy 337.023883 -394.358673) (xy 337.024472 -394.385292) (xy 337.024031 -394.409272) (xy 337.016533 -394.456643)
			(xy 337.00172 -394.502258) (xy 336.979956 -394.544996) (xy 336.951778 -394.583805) (xy 336.917877 -394.617731)
			(xy 336.879089 -394.645938) (xy 336.836367 -394.667733) (xy 336.790763 -394.68258) (xy 336.743398 -394.690113)
			(xy 336.719418 -394.6906) (xy 336.71891 -394.6906) (xy 336.695336 -394.690198) (xy 336.648748 -394.682958)
			(xy 336.60383 -394.668634) (xy 336.561652 -394.647566) (xy 336.523218 -394.620258) (xy 336.489447 -394.58736)
			(xy 336.461141 -394.549655) (xy 336.44967 -394.529056) (xy 336.449162 -394.528294) (xy 336.051398 -393.839954)
			(xy 336.039542 -393.817267) (xy 336.022683 -393.768939) (xy 336.014102 -393.718479) (xy 336.013552 -393.692888)
			(xy 322.14367 -393.692888) (xy 322.455794 -394.232892) (xy 322.468623 -394.256222) (xy 322.486841 -394.306246)
			(xy 322.496099 -394.358673) (xy 322.496688 -394.385292) (xy 322.496231 -394.409271) (xy 322.488733 -394.45664)
			(xy 322.473921 -394.502254) (xy 322.452159 -394.544991) (xy 322.423982 -394.5838) (xy 322.390084 -394.617725)
			(xy 322.351298 -394.645932) (xy 322.308578 -394.667728) (xy 322.262976 -394.682577) (xy 322.215613 -394.690112)
			(xy 322.191634 -394.6906) (xy 322.191126 -394.6906) (xy 322.167553 -394.690185) (xy 322.120965 -394.682948)
			(xy 322.076047 -394.668626) (xy 322.033869 -394.64756) (xy 321.995436 -394.620254) (xy 321.961663 -394.587357)
			(xy 321.933357 -394.549655) (xy 321.921886 -394.529056) (xy 321.921378 -394.528294) (xy 321.523614 -393.839954)
			(xy 321.511752 -393.81727) (xy 321.494897 -393.76894) (xy 321.486317 -393.71848) (xy 321.485768 -393.692888)
			(xy 320.943774 -393.692888) (xy 321.255898 -394.232892) (xy 321.268719 -394.256226) (xy 321.286942 -394.306248)
			(xy 321.296203 -394.358674) (xy 321.296792 -394.385292) (xy 321.296331 -394.409271) (xy 321.288834 -394.45664)
			(xy 321.274022 -394.502253) (xy 321.25226 -394.54499) (xy 321.224083 -394.583798) (xy 321.190186 -394.617723)
			(xy 321.1514 -394.645931) (xy 321.108681 -394.667727) (xy 321.063079 -394.682576) (xy 321.015717 -394.690112)
			(xy 320.991738 -394.6906) (xy 320.99123 -394.6906) (xy 320.967657 -394.690182) (xy 320.92107 -394.682945)
			(xy 320.876152 -394.668624) (xy 320.833973 -394.647559) (xy 320.79554 -394.620253) (xy 320.761768 -394.587357)
			(xy 320.733461 -394.549654) (xy 320.72199 -394.529056) (xy 320.721482 -394.528294) (xy 320.323718 -393.839954)
			(xy 320.311856 -393.81727) (xy 320.295001 -393.76894) (xy 320.286421 -393.71848) (xy 320.285872 -393.692888)
			(xy 319.743878 -393.692888) (xy 320.056002 -394.232892) (xy 320.068824 -394.256226) (xy 320.087046 -394.306248)
			(xy 320.096307 -394.358674) (xy 320.096896 -394.385292) (xy 320.096453 -394.409298) (xy 320.08894 -394.456719)
			(xy 320.074096 -394.502379) (xy 320.052288 -394.545153) (xy 320.024055 -394.583987) (xy 319.99009 -394.617922)
			(xy 319.951233 -394.646123) (xy 319.908441 -394.667895) (xy 319.862768 -394.6827) (xy 319.815341 -394.690174)
			(xy 319.791334 -394.6906) (xy 319.79108 -394.6906) (xy 319.767505 -394.690222) (xy 319.720916 -394.682978)
			(xy 319.675997 -394.668649) (xy 319.633819 -394.647578) (xy 319.595386 -394.620266) (xy 319.561615 -394.587364)
			(xy 319.53331 -394.549657) (xy 319.52184 -394.529056) (xy 319.521332 -394.528294) (xy 319.123568 -393.839954)
			(xy 319.111639 -393.817292) (xy 319.094706 -393.768964) (xy 319.086052 -393.718491) (xy 319.085468 -393.692888)
			(xy 318.543728 -393.692888) (xy 318.855852 -394.232892) (xy 318.868589 -394.256208) (xy 318.886681 -394.306157)
			(xy 318.895896 -394.358476) (xy 318.896492 -394.385038) (xy 318.896492 -394.385292) (xy 318.896054 -394.409286)
			(xy 318.888548 -394.456682) (xy 318.87372 -394.502321) (xy 318.851934 -394.545079) (xy 318.823728 -394.583901)
			(xy 318.789795 -394.617833) (xy 318.750972 -394.646038) (xy 318.708214 -394.667823) (xy 318.662575 -394.68265)
			(xy 318.615178 -394.690155) (xy 318.591184 -394.6906) (xy 318.56761 -394.690219) (xy 318.521021 -394.682975)
			(xy 318.476102 -394.668647) (xy 318.433923 -394.647576) (xy 318.395491 -394.620265) (xy 318.361719 -394.587363)
			(xy 318.333414 -394.549656) (xy 318.321944 -394.529056) (xy 318.321436 -394.528294) (xy 317.923672 -393.839954)
			(xy 317.911736 -393.817296) (xy 317.894806 -393.768965) (xy 317.886155 -393.718492) (xy 317.885572 -393.692888)
			(xy 317.343832 -393.692888) (xy 317.655956 -394.232892) (xy 317.668693 -394.256208) (xy 317.686785 -394.306157)
			(xy 317.696 -394.358476) (xy 317.696596 -394.385038) (xy 317.696596 -394.385292) (xy 317.696154 -394.409286)
			(xy 317.688648 -394.456682) (xy 317.67382 -394.50232) (xy 317.652035 -394.545077) (xy 317.623829 -394.5839)
			(xy 317.589897 -394.617831) (xy 317.551074 -394.646037) (xy 317.508317 -394.667822) (xy 317.462678 -394.682649)
			(xy 317.415282 -394.690155) (xy 317.391288 -394.6906) (xy 317.391034 -394.6906) (xy 317.367461 -394.690179)
			(xy 317.320874 -394.682942) (xy 317.275956 -394.668622) (xy 317.233778 -394.647557) (xy 317.195344 -394.620252)
			(xy 317.161572 -394.587356) (xy 317.133265 -394.549654) (xy 317.121794 -394.529056) (xy 317.121286 -394.528294)
			(xy 316.723522 -393.839954) (xy 316.711661 -393.81727) (xy 316.694805 -393.76894) (xy 316.686226 -393.71848)
			(xy 316.685676 -393.692888) (xy 316.143682 -393.692888) (xy 316.455806 -394.232892) (xy 316.468628 -394.256226)
			(xy 316.48685 -394.306248) (xy 316.496111 -394.358674) (xy 316.4967 -394.385292) (xy 316.496231 -394.409271)
			(xy 316.488734 -394.456639) (xy 316.473922 -394.502251) (xy 316.452161 -394.544988) (xy 316.423986 -394.583795)
			(xy 316.390089 -394.617721) (xy 316.351304 -394.645928) (xy 316.308586 -394.667725) (xy 316.262986 -394.682574)
			(xy 316.215624 -394.690111) (xy 316.191646 -394.6906) (xy 316.191138 -394.6906) (xy 316.167565 -394.690176)
			(xy 316.120978 -394.68294) (xy 316.07606 -394.66862) (xy 316.033882 -394.647556) (xy 315.995448 -394.620251)
			(xy 315.961676 -394.587356) (xy 315.933369 -394.549654) (xy 315.921898 -394.529056) (xy 315.92139 -394.528294)
			(xy 315.523626 -393.839954) (xy 315.511765 -393.81727) (xy 315.494909 -393.76894) (xy 315.48633 -393.71848)
			(xy 315.48578 -393.692888) (xy 314.943786 -393.692888) (xy 315.25591 -394.232892) (xy 315.268732 -394.256226)
			(xy 315.286954 -394.306248) (xy 315.296215 -394.358673) (xy 315.296804 -394.385292) (xy 315.296354 -394.409298)
			(xy 315.28884 -394.456718) (xy 315.273997 -394.502377) (xy 315.25219 -394.545151) (xy 315.223957 -394.583984)
			(xy 315.189994 -394.61792) (xy 315.151137 -394.646121) (xy 315.108346 -394.667893) (xy 315.062674 -394.682698)
			(xy 315.015248 -394.690173) (xy 314.991242 -394.6906) (xy 314.990988 -394.6906) (xy 314.967414 -394.690216)
			(xy 314.920825 -394.682973) (xy 314.875906 -394.668645) (xy 314.833728 -394.647575) (xy 314.795295 -394.620264)
			(xy 314.761523 -394.587363) (xy 314.733218 -394.549656) (xy 314.721748 -394.529056) (xy 314.72124 -394.528294)
			(xy 314.323476 -393.839954) (xy 314.31154 -393.817296) (xy 314.29461 -393.768965) (xy 314.285959 -393.718492)
			(xy 314.285376 -393.692888) (xy 313.74389 -393.692888) (xy 314.056014 -394.232892) (xy 314.068837 -394.256226)
			(xy 314.087058 -394.306248) (xy 314.096319 -394.358673) (xy 314.096908 -394.385292) (xy 314.096454 -394.409298)
			(xy 314.08894 -394.456717) (xy 314.074097 -394.502377) (xy 314.052291 -394.54515) (xy 314.024058 -394.583983)
			(xy 313.990095 -394.617918) (xy 313.95124 -394.646119) (xy 313.908449 -394.667891) (xy 313.862778 -394.682698)
			(xy 313.815352 -394.690173) (xy 313.791346 -394.6906) (xy 313.791092 -394.6906) (xy 313.767518 -394.690213)
			(xy 313.720929 -394.68297) (xy 313.67601 -394.668643) (xy 313.633832 -394.647573) (xy 313.595399 -394.620263)
			(xy 313.561628 -394.587362) (xy 313.533322 -394.549656) (xy 313.521852 -394.529056) (xy 313.521344 -394.528294)
			(xy 313.12358 -393.839954) (xy 313.111644 -393.817296) (xy 313.094715 -393.768965) (xy 313.086063 -393.718492)
			(xy 313.08548 -393.692888) (xy 312.54374 -393.692888) (xy 312.855864 -394.232892) (xy 312.868602 -394.256207)
			(xy 312.886693 -394.306157) (xy 312.895908 -394.358476) (xy 312.896504 -394.385038) (xy 312.896504 -394.385292)
			(xy 312.896054 -394.409285) (xy 312.888549 -394.456681) (xy 312.873721 -394.502319) (xy 312.851936 -394.545075)
			(xy 312.823731 -394.583897) (xy 312.7898 -394.617829) (xy 312.750978 -394.646034) (xy 312.708222 -394.66782)
			(xy 312.662585 -394.682648) (xy 312.615189 -394.690154) (xy 312.591196 -394.6906) (xy 312.590942 -394.6906)
			(xy 312.567369 -394.690172) (xy 312.520783 -394.682937) (xy 312.475865 -394.668617) (xy 312.433686 -394.647554)
			(xy 312.395253 -394.62025) (xy 312.36148 -394.587355) (xy 312.333173 -394.549654) (xy 312.321702 -394.529056)
			(xy 312.321194 -394.528294) (xy 311.92343 -393.839954) (xy 311.911569 -393.81727) (xy 311.894713 -393.76894)
			(xy 311.886134 -393.71848) (xy 311.885584 -393.692888) (xy 311.34359 -393.692888) (xy 311.655714 -394.232892)
			(xy 311.668537 -394.256226) (xy 311.686758 -394.306248) (xy 311.696019 -394.358673) (xy 311.696608 -394.385292)
			(xy 311.696131 -394.40927) (xy 311.688634 -394.456637) (xy 311.673823 -394.50225) (xy 311.652063 -394.544985)
			(xy 311.623888 -394.583793) (xy 311.589992 -394.617718) (xy 311.551209 -394.645926) (xy 311.508492 -394.667723)
			(xy 311.462892 -394.682573) (xy 311.415532 -394.69011) (xy 311.391554 -394.6906) (xy 311.391046 -394.6906)
			(xy 311.367473 -394.690169) (xy 311.320887 -394.682935) (xy 311.275969 -394.668615) (xy 311.233791 -394.647553)
			(xy 311.195357 -394.620249) (xy 311.161584 -394.587355) (xy 311.133277 -394.549654) (xy 311.121806 -394.529056)
			(xy 311.121298 -394.528294) (xy 310.723534 -393.839954) (xy 310.711674 -393.81727) (xy 310.694818 -393.76894)
			(xy 310.686238 -393.71848) (xy 310.685688 -393.692888) (xy 310.143694 -393.692888) (xy 310.455818 -394.232892)
			(xy 310.468641 -394.256226) (xy 310.486862 -394.306248) (xy 310.496123 -394.358673) (xy 310.496712 -394.385292)
			(xy 310.496231 -394.40927) (xy 310.488734 -394.456637) (xy 310.473924 -394.502249) (xy 310.452164 -394.544984)
			(xy 310.423989 -394.583791) (xy 310.390094 -394.617716) (xy 310.351311 -394.645924) (xy 310.308595 -394.667722)
			(xy 310.262996 -394.682572) (xy 310.215636 -394.69011) (xy 310.191658 -394.6906) (xy 310.19115 -394.6906)
			(xy 310.167577 -394.690166) (xy 310.120991 -394.682932) (xy 310.076073 -394.668613) (xy 310.033895 -394.647551)
			(xy 309.995461 -394.620248) (xy 309.961688 -394.587354) (xy 309.933381 -394.549653) (xy 309.92191 -394.529056)
			(xy 309.921402 -394.528294) (xy 309.523638 -393.839954) (xy 309.511778 -393.817269) (xy 309.494922 -393.76894)
			(xy 309.486342 -393.71848) (xy 309.485792 -393.692888) (xy 308.943544 -393.692888) (xy 309.255668 -394.232892)
			(xy 309.268406 -394.256207) (xy 309.286497 -394.306157) (xy 309.295712 -394.358476) (xy 309.296308 -394.385038)
			(xy 309.296308 -394.385292) (xy 309.295854 -394.409285) (xy 309.288349 -394.45668) (xy 309.273521 -394.502318)
			(xy 309.251737 -394.545074) (xy 309.223532 -394.583896) (xy 309.189602 -394.617827) (xy 309.150781 -394.646033)
			(xy 309.108025 -394.667818) (xy 309.062388 -394.682647) (xy 309.014993 -394.690154) (xy 308.991 -394.6906)
			(xy 308.967426 -394.690206) (xy 308.920838 -394.682965) (xy 308.875919 -394.668639) (xy 308.833741 -394.64757)
			(xy 308.795308 -394.620261) (xy 308.761536 -394.587361) (xy 308.73323 -394.549656) (xy 308.72176 -394.529056)
			(xy 308.721252 -394.528294) (xy 308.323488 -393.839954) (xy 308.311553 -393.817296) (xy 308.294623 -393.768965)
			(xy 308.285971 -393.718491) (xy 308.285388 -393.692888) (xy 307.743648 -393.692888) (xy 308.055772 -394.232892)
			(xy 308.068511 -394.256207) (xy 308.086601 -394.306157) (xy 308.095816 -394.358476) (xy 308.096412 -394.385038)
			(xy 308.096412 -394.385292) (xy 308.095954 -394.409285) (xy 308.088449 -394.45668) (xy 308.073622 -394.502317)
			(xy 308.051838 -394.545073) (xy 308.023634 -394.583894) (xy 307.989703 -394.617826) (xy 307.950883 -394.646032)
			(xy 307.908128 -394.667817) (xy 307.862491 -394.682646) (xy 307.815097 -394.690154) (xy 307.791104 -394.6906)
			(xy 307.76753 -394.690203) (xy 307.720942 -394.682962) (xy 307.676023 -394.668637) (xy 307.633845 -394.647569)
			(xy 307.595412 -394.62026) (xy 307.56164 -394.587361) (xy 307.533335 -394.549656) (xy 307.521864 -394.529056)
			(xy 307.521356 -394.528294) (xy 307.123592 -393.839954) (xy 307.111657 -393.817295) (xy 307.094727 -393.768965)
			(xy 307.086075 -393.718491) (xy 307.085492 -393.692888) (xy 306.543752 -393.692888) (xy 306.855876 -394.232892)
			(xy 306.868615 -394.256207) (xy 306.886705 -394.306157) (xy 306.89592 -394.358476) (xy 306.896516 -394.385038)
			(xy 306.896516 -394.385292) (xy 306.89603 -394.409283) (xy 306.888525 -394.456673) (xy 306.8737 -394.502306)
			(xy 306.851918 -394.545059) (xy 306.823716 -394.583877) (xy 306.789789 -394.617806) (xy 306.750972 -394.646009)
			(xy 306.708221 -394.667793) (xy 306.662589 -394.682622) (xy 306.615199 -394.690129) (xy 306.591208 -394.6906)
			(xy 306.590954 -394.6906) (xy 306.567382 -394.690163) (xy 306.520795 -394.682929) (xy 306.475878 -394.668611)
			(xy 306.433699 -394.64755) (xy 306.395266 -394.620247) (xy 306.361493 -394.587353) (xy 306.333185 -394.549653)
			(xy 306.321714 -394.529056) (xy 306.321206 -394.528294) (xy 305.923442 -393.839954) (xy 305.911582 -393.817269)
			(xy 305.894726 -393.76894) (xy 305.886146 -393.71848) (xy 305.885596 -393.692888) (xy 305.343602 -393.692888)
			(xy 305.655726 -394.232892) (xy 305.66855 -394.256225) (xy 305.686771 -394.306247) (xy 305.696031 -394.358673)
			(xy 305.69662 -394.385292) (xy 305.696131 -394.40927) (xy 305.688635 -394.456636) (xy 305.673824 -394.502247)
			(xy 305.652065 -394.544982) (xy 305.623892 -394.583789) (xy 305.589997 -394.617713) (xy 305.551216 -394.645922)
			(xy 305.5085 -394.667719) (xy 305.462902 -394.68257) (xy 305.415543 -394.69011) (xy 305.391566 -394.6906)
			(xy 305.391058 -394.6906) (xy 305.367486 -394.690159) (xy 305.3209 -394.682927) (xy 305.275982 -394.668609)
			(xy 305.233804 -394.647548) (xy 305.19537 -394.620246) (xy 305.161597 -394.587353) (xy 305.13329 -394.549653)
			(xy 305.121818 -394.529056) (xy 305.12131 -394.528294) (xy 304.723546 -393.839954) (xy 304.711686 -393.817269)
			(xy 304.69483 -393.76894) (xy 304.68625 -393.71848) (xy 304.6857 -393.692888) (xy 304.143706 -393.692888)
			(xy 304.45583 -394.232892) (xy 304.468654 -394.256225) (xy 304.486875 -394.306247) (xy 304.496135 -394.358673)
			(xy 304.496724 -394.385292) (xy 304.496231 -394.40927) (xy 304.488735 -394.456635) (xy 304.473925 -394.502246)
			(xy 304.452166 -394.54498) (xy 304.423993 -394.583787) (xy 304.390099 -394.617712) (xy 304.351318 -394.64592)
			(xy 304.308603 -394.667718) (xy 304.263006 -394.68257) (xy 304.215647 -394.690109) (xy 304.19167 -394.6906)
			(xy 304.191162 -394.6906) (xy 304.16759 -394.690156) (xy 304.121004 -394.682924) (xy 304.076086 -394.668607)
			(xy 304.033908 -394.647547) (xy 303.995474 -394.620245) (xy 303.961701 -394.587352) (xy 303.933394 -394.549653)
			(xy 303.921922 -394.529056) (xy 303.921414 -394.528294) (xy 303.52365 -393.839954) (xy 303.511791 -393.817269)
			(xy 303.494934 -393.76894) (xy 303.486354 -393.71848) (xy 303.485804 -393.692888) (xy 280.345134 -393.692888)
			(xy 280.093674 -393.944348) (xy 280.08686 -393.951769) (xy 280.079126 -393.970352) (xy 280.078688 -393.980416)
			(xy 280.079196 -394.062966) (xy 280.08707 -394.081508) (xy 280.094436 -394.08862) (xy 280.100532 -394.094716)
			(xy 280.483818 -394.478002) (xy 280.510712 -394.505555) (xy 280.558798 -394.565692) (xy 280.599841 -394.630839)
			(xy 280.633323 -394.700176) (xy 280.658823 -394.772829) (xy 280.67602 -394.847882) (xy 280.684696 -394.924389)
			(xy 280.68524 -394.962888) (xy 280.68524 -396.171674) (xy 296.901108 -396.171674) (xy 296.901108 -395.308074)
			(xy 296.901594 -395.280823) (xy 296.90935 -395.226875) (xy 296.924705 -395.17458) (xy 296.947347 -395.125003)
			(xy 296.976813 -395.079153) (xy 297.012504 -395.037962) (xy 297.053695 -395.002271) (xy 297.099545 -394.972805)
			(xy 297.149122 -394.950163) (xy 297.201417 -394.934808) (xy 297.255365 -394.927052) (xy 297.309867 -394.927052)
			(xy 297.363815 -394.934808) (xy 297.41611 -394.950163) (xy 297.465687 -394.972805) (xy 297.511537 -395.002271)
			(xy 297.552728 -395.037962) (xy 297.588419 -395.079153) (xy 297.617885 -395.125003) (xy 297.640527 -395.17458)
			(xy 297.655882 -395.226875) (xy 297.663638 -395.280823) (xy 297.664124 -395.308074) (xy 297.664124 -396.171674)
			(xy 329.428856 -396.171674) (xy 329.428856 -395.308074) (xy 329.429342 -395.280823) (xy 329.437098 -395.226875)
			(xy 329.452453 -395.17458) (xy 329.475095 -395.125003) (xy 329.504561 -395.079153) (xy 329.540252 -395.037962)
			(xy 329.581443 -395.002271) (xy 329.627293 -394.972805) (xy 329.67687 -394.950163) (xy 329.729165 -394.934808)
			(xy 329.783113 -394.927052) (xy 329.837615 -394.927052) (xy 329.891563 -394.934808) (xy 329.943858 -394.950163)
			(xy 329.993435 -394.972805) (xy 330.039285 -395.002271) (xy 330.080476 -395.037962) (xy 330.116167 -395.079153)
			(xy 330.145633 -395.125003) (xy 330.168275 -395.17458) (xy 330.18363 -395.226875) (xy 330.191386 -395.280823)
			(xy 330.191872 -395.308074) (xy 330.191872 -396.171674) (xy 364.001304 -396.171674) (xy 364.001304 -395.308074)
			(xy 364.00179 -395.280823) (xy 364.009546 -395.226875) (xy 364.024901 -395.17458) (xy 364.047543 -395.125003)
			(xy 364.077009 -395.079153) (xy 364.1127 -395.037962) (xy 364.153891 -395.002271) (xy 364.199741 -394.972805)
			(xy 364.249318 -394.950163) (xy 364.301613 -394.934808) (xy 364.355561 -394.927052) (xy 364.410063 -394.927052)
			(xy 364.464011 -394.934808) (xy 364.516306 -394.950163) (xy 364.565883 -394.972805) (xy 364.611733 -395.002271)
			(xy 364.652924 -395.037962) (xy 364.688615 -395.079153) (xy 364.718081 -395.125003) (xy 364.740723 -395.17458)
			(xy 364.756078 -395.226875) (xy 364.763834 -395.280823) (xy 364.76432 -395.308074) (xy 364.76432 -396.171674)
			(xy 396.529052 -396.171674) (xy 396.529052 -395.308074) (xy 396.529538 -395.280823) (xy 396.537294 -395.226875)
			(xy 396.552649 -395.17458) (xy 396.575291 -395.125003) (xy 396.604757 -395.079153) (xy 396.640448 -395.037962)
			(xy 396.681639 -395.002271) (xy 396.727489 -394.972805) (xy 396.777066 -394.950163) (xy 396.829361 -394.934808)
			(xy 396.883309 -394.927052) (xy 396.937811 -394.927052) (xy 396.991759 -394.934808) (xy 397.044054 -394.950163)
			(xy 397.093631 -394.972805) (xy 397.139481 -395.002271) (xy 397.180672 -395.037962) (xy 397.216363 -395.079153)
			(xy 397.245829 -395.125003) (xy 397.268471 -395.17458) (xy 397.283826 -395.226875) (xy 397.291582 -395.280823)
			(xy 397.292068 -395.308074) (xy 397.292068 -396.171674) (xy 397.291582 -396.198925) (xy 397.283826 -396.252873)
			(xy 397.268471 -396.305168) (xy 397.245829 -396.354745) (xy 397.216363 -396.400595) (xy 397.180672 -396.441786)
			(xy 397.139481 -396.477477) (xy 397.093631 -396.506943) (xy 397.044054 -396.529585) (xy 396.991759 -396.54494)
			(xy 396.937811 -396.552696) (xy 396.883309 -396.552696) (xy 396.829361 -396.54494) (xy 396.777066 -396.529585)
			(xy 396.727489 -396.506943) (xy 396.681639 -396.477477) (xy 396.640448 -396.441786) (xy 396.604757 -396.400595)
			(xy 396.575291 -396.354745) (xy 396.552649 -396.305168) (xy 396.537294 -396.252873) (xy 396.529538 -396.198925)
			(xy 396.529052 -396.171674) (xy 364.76432 -396.171674) (xy 364.763834 -396.198925) (xy 364.756078 -396.252873)
			(xy 364.740723 -396.305168) (xy 364.718081 -396.354745) (xy 364.688615 -396.400595) (xy 364.652924 -396.441786)
			(xy 364.611733 -396.477477) (xy 364.565883 -396.506943) (xy 364.516306 -396.529585) (xy 364.464011 -396.54494)
			(xy 364.410063 -396.552696) (xy 364.355561 -396.552696) (xy 364.301613 -396.54494) (xy 364.249318 -396.529585)
			(xy 364.199741 -396.506943) (xy 364.153891 -396.477477) (xy 364.1127 -396.441786) (xy 364.077009 -396.400595)
			(xy 364.047543 -396.354745) (xy 364.024901 -396.305168) (xy 364.009546 -396.252873) (xy 364.00179 -396.198925)
			(xy 364.001304 -396.171674) (xy 330.191872 -396.171674) (xy 330.191386 -396.198925) (xy 330.18363 -396.252873)
			(xy 330.168275 -396.305168) (xy 330.145633 -396.354745) (xy 330.116167 -396.400595) (xy 330.080476 -396.441786)
			(xy 330.039285 -396.477477) (xy 329.993435 -396.506943) (xy 329.943858 -396.529585) (xy 329.891563 -396.54494)
			(xy 329.837615 -396.552696) (xy 329.783113 -396.552696) (xy 329.729165 -396.54494) (xy 329.67687 -396.529585)
			(xy 329.627293 -396.506943) (xy 329.581443 -396.477477) (xy 329.540252 -396.441786) (xy 329.504561 -396.400595)
			(xy 329.475095 -396.354745) (xy 329.452453 -396.305168) (xy 329.437098 -396.252873) (xy 329.429342 -396.198925)
			(xy 329.428856 -396.171674) (xy 297.664124 -396.171674) (xy 297.663638 -396.198925) (xy 297.655882 -396.252873)
			(xy 297.640527 -396.305168) (xy 297.617885 -396.354745) (xy 297.588419 -396.400595) (xy 297.552728 -396.441786)
			(xy 297.511537 -396.477477) (xy 297.465687 -396.506943) (xy 297.41611 -396.529585) (xy 297.363815 -396.54494)
			(xy 297.309867 -396.552696) (xy 297.255365 -396.552696) (xy 297.201417 -396.54494) (xy 297.149122 -396.529585)
			(xy 297.099545 -396.506943) (xy 297.053695 -396.477477) (xy 297.012504 -396.441786) (xy 296.976813 -396.400595)
			(xy 296.947347 -396.354745) (xy 296.924705 -396.305168) (xy 296.90935 -396.252873) (xy 296.901594 -396.198925)
			(xy 296.901108 -396.171674) (xy 280.68524 -396.171674) (xy 280.68524 -397.15694) (xy 303.485804 -397.15694)
			(xy 303.485804 -397.156432) (xy 303.486268 -397.132439) (xy 303.49377 -397.085044) (xy 303.508595 -397.039405)
			(xy 303.530377 -396.996648) (xy 303.558581 -396.957826) (xy 303.592511 -396.923894) (xy 303.631331 -396.895688)
			(xy 303.674087 -396.873903) (xy 303.719724 -396.859075) (xy 303.767119 -396.851569) (xy 303.791112 -396.851124)
			(xy 303.815047 -396.851594) (xy 303.862333 -396.859047) (xy 303.907877 -396.873786) (xy 303.950565 -396.895448)
			(xy 303.989351 -396.923504) (xy 304.023286 -396.957267) (xy 304.051539 -396.99591) (xy 304.062892 -397.016986)
			(xy 304.0634 -397.018002) (xy 304.143706 -397.15694) (xy 304.6857 -397.15694) (xy 304.6857 -397.156432)
			(xy 304.686168 -397.132439) (xy 304.69367 -397.085044) (xy 304.708495 -397.039406) (xy 304.730277 -396.99665)
			(xy 304.75848 -396.957827) (xy 304.792409 -396.923895) (xy 304.831229 -396.895689) (xy 304.873984 -396.873904)
			(xy 304.919621 -396.859076) (xy 304.967015 -396.85157) (xy 304.991008 -396.851124) (xy 305.014943 -396.851597)
			(xy 305.062229 -396.85905) (xy 305.107773 -396.873788) (xy 305.150461 -396.89545) (xy 305.189247 -396.923505)
			(xy 305.223182 -396.957268) (xy 305.251435 -396.99591) (xy 305.262788 -397.016986) (xy 305.263296 -397.018002)
			(xy 305.343602 -397.15694) (xy 305.885596 -397.15694) (xy 305.885596 -397.156432) (xy 305.886068 -397.13244)
			(xy 305.89357 -397.085045) (xy 305.908394 -397.039407) (xy 305.930176 -396.996651) (xy 305.958378 -396.957829)
			(xy 305.992307 -396.923897) (xy 306.031127 -396.895691) (xy 306.073881 -396.873905) (xy 306.119517 -396.859076)
			(xy 306.166912 -396.85157) (xy 306.190904 -396.851124) (xy 306.214839 -396.8516) (xy 306.262124 -396.859053)
			(xy 306.307668 -396.87379) (xy 306.350356 -396.895451) (xy 306.389142 -396.923506) (xy 306.423077 -396.957268)
			(xy 306.451331 -396.99591) (xy 306.462684 -397.016986) (xy 306.463192 -397.018002) (xy 306.543498 -397.15694)
			(xy 307.085492 -397.15694) (xy 307.085492 -397.156432) (xy 307.085991 -397.132454) (xy 307.093484 -397.085088)
			(xy 307.108292 -397.039476) (xy 307.130049 -396.996741) (xy 307.158222 -396.957933) (xy 307.192115 -396.924008)
			(xy 307.230897 -396.895799) (xy 307.273612 -396.874002) (xy 307.31921 -396.859151) (xy 307.366569 -396.851614)
			(xy 307.390546 -396.851124) (xy 307.391054 -396.851124) (xy 307.41499 -396.85156) (xy 307.462278 -396.85902)
			(xy 307.507823 -396.873764) (xy 307.550511 -396.895432) (xy 307.589296 -396.923493) (xy 307.62323 -396.957261)
			(xy 307.651481 -396.995908) (xy 307.662834 -397.016986) (xy 307.663342 -397.018002) (xy 307.743648 -397.15694)
			(xy 308.285388 -397.15694) (xy 308.285388 -397.156432) (xy 308.285891 -397.132455) (xy 308.293384 -397.085089)
			(xy 308.308192 -397.039477) (xy 308.329949 -396.996742) (xy 308.35812 -396.957934) (xy 308.392013 -396.924009)
			(xy 308.430794 -396.895801) (xy 308.473509 -396.874003) (xy 308.519106 -396.859152) (xy 308.566465 -396.851614)
			(xy 308.590442 -396.851124) (xy 308.59095 -396.851124) (xy 308.614886 -396.851563) (xy 308.662173 -396.859022)
			(xy 308.707718 -396.873766) (xy 308.750406 -396.895434) (xy 308.789192 -396.923494) (xy 308.823126 -396.957262)
			(xy 308.851377 -396.995908) (xy 308.86273 -397.016986) (xy 308.863238 -397.018002) (xy 308.943544 -397.15694)
			(xy 309.485792 -397.15694) (xy 309.485792 -397.156432) (xy 309.486268 -397.13244) (xy 309.49377 -397.085045)
			(xy 309.508594 -397.039408) (xy 309.530375 -396.996652) (xy 309.558577 -396.95783) (xy 309.592506 -396.923898)
			(xy 309.631325 -396.895692) (xy 309.674079 -396.873906) (xy 309.719714 -396.859077) (xy 309.767108 -396.85157)
			(xy 309.7911 -396.851124) (xy 309.815035 -396.851603) (xy 309.86232 -396.859055) (xy 309.907864 -396.873792)
			(xy 309.950552 -396.895453) (xy 309.989338 -396.923507) (xy 310.023273 -396.957269) (xy 310.051526 -396.995911)
			(xy 310.06288 -397.016986) (xy 310.063388 -397.018002) (xy 310.143694 -397.15694) (xy 310.685688 -397.15694)
			(xy 310.685688 -397.156432) (xy 310.686168 -397.13244) (xy 310.69367 -397.085046) (xy 310.708493 -397.039409)
			(xy 310.730274 -396.996653) (xy 310.758476 -396.957831) (xy 310.792404 -396.9239) (xy 310.831223 -396.895693)
			(xy 310.873976 -396.873907) (xy 310.919611 -396.859078) (xy 310.967004 -396.851571) (xy 310.990996 -396.851124)
			(xy 311.014933 -396.851526) (xy 311.062223 -396.858992) (xy 311.107768 -396.873742) (xy 311.150456 -396.895416)
			(xy 311.189241 -396.923483) (xy 311.223174 -396.957255) (xy 311.251424 -396.995906) (xy 311.262776 -397.016986)
			(xy 311.263284 -397.018002) (xy 311.34359 -397.15694) (xy 311.885584 -397.15694) (xy 311.885584 -397.156432)
			(xy 311.886068 -397.13244) (xy 311.893569 -397.085046) (xy 311.908393 -397.03941) (xy 311.930174 -396.996654)
			(xy 311.958375 -396.957833) (xy 311.992302 -396.923901) (xy 312.03112 -396.895695) (xy 312.073873 -396.873908)
			(xy 312.119508 -396.859079) (xy 312.1669 -396.851571) (xy 312.190892 -396.851124) (xy 312.214829 -396.851529)
			(xy 312.262118 -396.858995) (xy 312.307664 -396.873745) (xy 312.350352 -396.895418) (xy 312.389137 -396.923484)
			(xy 312.42307 -396.957256) (xy 312.45132 -396.995906) (xy 312.462672 -397.016986) (xy 312.46318 -397.018002)
			(xy 312.543486 -397.15694) (xy 313.08548 -397.15694) (xy 313.08548 -397.156432) (xy 313.085991 -397.132455)
			(xy 313.093484 -397.08509) (xy 313.108291 -397.039479) (xy 313.130047 -396.996744) (xy 313.158218 -396.957937)
			(xy 313.19211 -396.924012) (xy 313.23089 -396.895803) (xy 313.273603 -396.874005) (xy 313.3192 -396.859154)
			(xy 313.366557 -396.851614) (xy 313.390534 -396.851124) (xy 313.391042 -396.851124) (xy 313.414978 -396.851569)
			(xy 313.462265 -396.859028) (xy 313.50781 -396.87377) (xy 313.550497 -396.895437) (xy 313.589283 -396.923496)
			(xy 313.623217 -396.957263) (xy 313.651469 -396.995909) (xy 313.662822 -397.016986) (xy 313.66333 -397.018002)
			(xy 313.743636 -397.15694) (xy 314.285376 -397.15694) (xy 314.285376 -397.156432) (xy 314.285891 -397.132455)
			(xy 314.293384 -397.08509) (xy 314.308191 -397.03948) (xy 314.329947 -396.996746) (xy 314.358117 -396.957938)
			(xy 314.392008 -396.924013) (xy 314.430788 -396.895805) (xy 314.473501 -396.874006) (xy 314.519096 -396.859155)
			(xy 314.566454 -396.851615) (xy 314.59043 -396.851124) (xy 314.590938 -396.851124) (xy 314.614874 -396.851573)
			(xy 314.662161 -396.85903) (xy 314.707705 -396.873772) (xy 314.750393 -396.895438) (xy 314.789179 -396.923498)
			(xy 314.823113 -396.957263) (xy 314.851365 -396.995909) (xy 314.862718 -397.016986) (xy 314.863226 -397.018002)
			(xy 314.943532 -397.15694) (xy 315.48578 -397.15694) (xy 315.48578 -397.156432) (xy 315.486268 -397.13244)
			(xy 315.493769 -397.085047) (xy 315.508593 -397.039411) (xy 315.530373 -396.996656) (xy 315.558574 -396.957834)
			(xy 315.592501 -396.923902) (xy 315.631318 -396.895696) (xy 315.67407 -396.87391) (xy 315.719704 -396.85908)
			(xy 315.767096 -396.851571) (xy 315.791088 -396.851124) (xy 315.815025 -396.851532) (xy 315.862314 -396.858997)
			(xy 315.90786 -396.873747) (xy 315.950547 -396.895419) (xy 315.989333 -396.923485) (xy 316.023266 -396.957256)
			(xy 316.051516 -396.995907) (xy 316.062868 -397.016986) (xy 316.063376 -397.018002) (xy 316.143682 -397.15694)
			(xy 316.685676 -397.15694) (xy 316.685676 -397.156432) (xy 316.686168 -397.132441) (xy 316.693669 -397.085048)
			(xy 316.708492 -397.039412) (xy 316.730272 -396.996657) (xy 316.758473 -396.957836) (xy 316.792399 -396.923904)
			(xy 316.831216 -396.895697) (xy 316.873967 -396.873911) (xy 316.919601 -396.85908) (xy 316.966993 -396.851571)
			(xy 316.990984 -396.851124) (xy 317.014921 -396.851535) (xy 317.06221 -396.859) (xy 317.107755 -396.873749)
			(xy 317.150443 -396.895421) (xy 317.189228 -396.923486) (xy 317.223161 -396.957257) (xy 317.251412 -396.995907)
			(xy 317.262764 -397.016986) (xy 317.263272 -397.018002) (xy 317.343578 -397.15694) (xy 317.885572 -397.15694)
			(xy 317.885572 -397.156432) (xy 317.886068 -397.132441) (xy 317.893569 -397.085048) (xy 317.908392 -397.039413)
			(xy 317.930172 -396.996658) (xy 317.958371 -396.957837) (xy 317.992297 -396.923905) (xy 318.031114 -396.895699)
			(xy 318.073865 -396.873912) (xy 318.119498 -396.859081) (xy 318.166889 -396.851572) (xy 318.19088 -396.851124)
			(xy 318.214817 -396.851539) (xy 318.262105 -396.859002) (xy 318.307651 -396.873751) (xy 318.350339 -396.895422)
			(xy 318.389124 -396.923487) (xy 318.423057 -396.957257) (xy 318.451308 -396.995907) (xy 318.46266 -397.016986)
			(xy 318.463168 -397.018002) (xy 318.543474 -397.15694) (xy 319.085468 -397.15694) (xy 319.085468 -397.156432)
			(xy 319.085991 -397.132456) (xy 319.093484 -397.085092) (xy 319.10829 -397.039482) (xy 319.130045 -396.996748)
			(xy 319.158215 -396.957941) (xy 319.192105 -396.924016) (xy 319.230883 -396.895807) (xy 319.273595 -396.874009)
			(xy 319.31919 -396.859156) (xy 319.366546 -396.851615) (xy 319.390522 -396.851124) (xy 319.39103 -396.851124)
			(xy 319.414965 -396.851579) (xy 319.462252 -396.859035) (xy 319.507797 -396.873776) (xy 319.550484 -396.895441)
			(xy 319.58927 -396.9235) (xy 319.623205 -396.957264) (xy 319.651457 -396.995909) (xy 319.66281 -397.016986)
			(xy 319.663318 -397.018002) (xy 319.743624 -397.15694) (xy 320.285364 -397.15694) (xy 320.285364 -397.156432)
			(xy 320.285891 -397.132456) (xy 320.293383 -397.085092) (xy 320.308189 -397.039483) (xy 320.329944 -396.996749)
			(xy 320.358113 -396.957943) (xy 320.392003 -396.924018) (xy 320.430781 -396.895809) (xy 320.473492 -396.87401)
			(xy 320.519086 -396.859157) (xy 320.566442 -396.851616) (xy 320.590418 -396.851124) (xy 320.590926 -396.851124)
			(xy 320.614861 -396.851582) (xy 320.662148 -396.859038) (xy 320.707692 -396.873778) (xy 320.75038 -396.895443)
			(xy 320.789166 -396.923501) (xy 320.823101 -396.957265) (xy 320.851353 -396.995909) (xy 320.862706 -397.016986)
			(xy 320.863214 -397.018002) (xy 320.94352 -397.15694) (xy 321.485768 -397.15694) (xy 321.485768 -397.156432)
			(xy 321.486268 -397.132441) (xy 321.493769 -397.085049) (xy 321.508592 -397.039414) (xy 321.530371 -396.996659)
			(xy 321.55857 -396.957838) (xy 321.592496 -396.923907) (xy 321.631311 -396.8957) (xy 321.674062 -396.873913)
			(xy 321.719694 -396.859082) (xy 321.767085 -396.851572) (xy 321.791076 -396.851124) (xy 321.815013 -396.851542)
			(xy 321.862301 -396.859005) (xy 321.907847 -396.873753) (xy 321.950534 -396.895424) (xy 321.98932 -396.923488)
			(xy 322.023253 -396.957258) (xy 322.051504 -396.995907) (xy 322.062856 -397.016986) (xy 322.063364 -397.018002)
			(xy 322.129999 -397.133287) (xy 336.013603 -397.133287) (xy 336.020935 -397.085732) (xy 336.035629 -397.039915)
			(xy 336.057324 -396.996967) (xy 336.085482 -396.95795) (xy 336.119407 -396.923829) (xy 336.15826 -396.895446)
			(xy 336.201082 -396.873504) (xy 336.246814 -396.858545) (xy 336.294325 -396.850939) (xy 336.342442 -396.850873)
			(xy 336.389974 -396.85835) (xy 336.435746 -396.873184) (xy 336.478628 -396.895009) (xy 336.517559 -396.923285)
			(xy 336.551577 -396.957314) (xy 336.579841 -396.996254) (xy 336.591148 -397.017494) (xy 336.591656 -397.018764)
			(xy 336.657839 -397.133287) (xy 337.213506 -397.133287) (xy 337.220838 -397.085733) (xy 337.235533 -397.039916)
			(xy 337.257227 -396.996969) (xy 337.285384 -396.957952) (xy 337.319309 -396.923831) (xy 337.358162 -396.895449)
			(xy 337.400983 -396.873508) (xy 337.446714 -396.858549) (xy 337.494225 -396.850942) (xy 337.54234 -396.850877)
			(xy 337.589872 -396.858353) (xy 337.635644 -396.873187) (xy 337.678525 -396.895011) (xy 337.717455 -396.923287)
			(xy 337.751473 -396.957315) (xy 337.779737 -396.996254) (xy 337.791044 -397.017494) (xy 337.791552 -397.018764)
			(xy 337.857735 -397.133286) (xy 338.41341 -397.133286) (xy 338.420742 -397.085733) (xy 338.435436 -397.039917)
			(xy 338.45713 -396.996971) (xy 338.485287 -396.957955) (xy 338.519211 -396.923834) (xy 338.558063 -396.895453)
			(xy 338.600884 -396.873511) (xy 338.646615 -396.858552) (xy 338.694124 -396.850946) (xy 338.742239 -396.85088)
			(xy 338.78977 -396.858356) (xy 338.835541 -396.87319) (xy 338.878422 -396.895014) (xy 338.917352 -396.923289)
			(xy 338.951369 -396.957316) (xy 338.979633 -396.996254) (xy 338.99094 -397.017494) (xy 338.991448 -397.018764)
			(xy 339.057629 -397.133284) (xy 339.613655 -397.133284) (xy 339.620986 -397.08574) (xy 339.635678 -397.039932)
			(xy 339.657368 -396.996993) (xy 339.68552 -396.957985) (xy 339.719438 -396.92387) (xy 339.758283 -396.895493)
			(xy 339.801095 -396.873555) (xy 339.846817 -396.858598) (xy 339.894318 -396.850991) (xy 339.942424 -396.850924)
			(xy 339.989947 -396.858397) (xy 340.03571 -396.873225) (xy 340.078584 -396.895043) (xy 340.117509 -396.923311)
			(xy 340.151522 -396.95733) (xy 340.179784 -396.996259) (xy 340.19109 -397.017494) (xy 340.191598 -397.018764)
			(xy 340.257779 -397.133284) (xy 340.813558 -397.133284) (xy 340.82089 -397.08574) (xy 340.835582 -397.039933)
			(xy 340.857271 -396.996995) (xy 340.885423 -396.957987) (xy 340.91934 -396.923873) (xy 340.958184 -396.895496)
			(xy 341.000996 -396.873558) (xy 341.046717 -396.858601) (xy 341.094218 -396.850995) (xy 341.142323 -396.850927)
			(xy 341.189845 -396.8584) (xy 341.235608 -396.873228) (xy 341.278481 -396.895045) (xy 341.317406 -396.923312)
			(xy 341.351419 -396.957331) (xy 341.37968 -396.996259) (xy 341.390986 -397.017494) (xy 341.391494 -397.018764)
			(xy 341.457677 -397.133286) (xy 342.013613 -397.133286) (xy 342.020945 -397.085734) (xy 342.03564 -397.039918)
			(xy 342.057333 -396.996972) (xy 342.08549 -396.957957) (xy 342.119413 -396.923837) (xy 342.158265 -396.895456)
			(xy 342.201085 -396.873515) (xy 342.246815 -396.858556) (xy 342.294324 -396.85095) (xy 342.342438 -396.850884)
			(xy 342.389968 -396.858359) (xy 342.435739 -396.873192) (xy 342.478619 -396.895016) (xy 342.517549 -396.92329)
			(xy 342.551566 -396.957317) (xy 342.579829 -396.996255) (xy 342.591136 -397.017494) (xy 342.591644 -397.018764)
			(xy 342.657827 -397.133286) (xy 343.213517 -397.133286) (xy 343.220849 -397.085734) (xy 343.235543 -397.03992)
			(xy 343.257236 -396.996974) (xy 343.285392 -396.95796) (xy 343.319315 -396.92384) (xy 343.358166 -396.895459)
			(xy 343.400986 -396.873518) (xy 343.446715 -396.85856) (xy 343.494223 -396.850953) (xy 343.542337 -396.850887)
			(xy 343.589866 -396.858363) (xy 343.635636 -396.873195) (xy 343.678516 -396.895018) (xy 343.717445 -396.923292)
			(xy 343.751462 -396.957318) (xy 343.779725 -396.996255) (xy 343.791032 -397.017494) (xy 343.79154 -397.018764)
			(xy 343.857723 -397.133286) (xy 344.413421 -397.133286) (xy 344.420752 -397.085735) (xy 344.435446 -397.039921)
			(xy 344.457139 -396.996976) (xy 344.485295 -396.957962) (xy 344.519217 -396.923843) (xy 344.558068 -396.895462)
			(xy 344.600887 -396.873522) (xy 344.646615 -396.858563) (xy 344.694123 -396.850957) (xy 344.742236 -396.850891)
			(xy 344.789764 -396.858366) (xy 344.835534 -396.873198) (xy 344.878413 -396.895021) (xy 344.917342 -396.923294)
			(xy 344.951358 -396.957319) (xy 344.979621 -396.996256) (xy 344.990928 -397.017494) (xy 344.991436 -397.018764)
			(xy 345.057617 -397.133284) (xy 345.613665 -397.133284) (xy 345.620997 -397.085741) (xy 345.635688 -397.039936)
			(xy 345.657377 -396.996999) (xy 345.685528 -396.957992) (xy 345.719444 -396.923879) (xy 345.758287 -396.895503)
			(xy 345.801098 -396.873565) (xy 345.846818 -396.858609) (xy 345.894317 -396.851002) (xy 345.942421 -396.850934)
			(xy 345.989941 -396.858406) (xy 346.035703 -396.873234) (xy 346.078575 -396.89505) (xy 346.117499 -396.923316)
			(xy 346.151511 -396.957333) (xy 346.179772 -396.99626) (xy 346.191078 -397.017494) (xy 346.191586 -397.018764)
			(xy 346.284753 -397.179979) (xy 346.813611 -397.179979) (xy 346.813859 -397.129044) (xy 346.822553 -397.078855)
			(xy 346.83945 -397.030804) (xy 346.864083 -396.986221) (xy 346.89577 -396.946341) (xy 346.933633 -396.912269)
			(xy 346.976622 -396.884949) (xy 347.023547 -396.865138) (xy 347.073108 -396.853385) (xy 347.123932 -396.850014)
			(xy 347.174611 -396.85512) (xy 347.223742 -396.868562) (xy 347.269962 -396.889966) (xy 347.311992 -396.918739)
			(xy 347.348668 -396.954086) (xy 347.378973 -396.995025) (xy 347.390974 -397.017494) (xy 347.391482 -397.018764)
			(xy 347.457665 -397.133286) (xy 348.013624 -397.133286) (xy 348.020956 -397.085735) (xy 348.03565 -397.039922)
			(xy 348.057342 -396.996978) (xy 348.085497 -396.957964) (xy 348.119419 -396.923846) (xy 348.15827 -396.895466)
			(xy 348.201088 -396.873525) (xy 348.246815 -396.858567) (xy 348.294322 -396.850961) (xy 348.342434 -396.850894)
			(xy 348.389962 -396.858369) (xy 348.435731 -396.873201) (xy 348.47861 -396.895023) (xy 348.517538 -396.923296)
			(xy 348.551554 -396.95732) (xy 348.579817 -396.996256) (xy 348.591124 -397.017494) (xy 348.591632 -397.018764)
			(xy 348.657814 -397.133285) (xy 349.213528 -397.133285) (xy 349.220859 -397.085736) (xy 349.235553 -397.039923)
			(xy 349.257245 -396.99698) (xy 349.2854 -396.957967) (xy 349.319322 -396.923849) (xy 349.358171 -396.895469)
			(xy 349.400989 -396.873529) (xy 349.446716 -396.858571) (xy 349.494222 -396.850964) (xy 349.542333 -396.850898)
			(xy 349.58986 -396.858372) (xy 349.635629 -396.873204) (xy 349.678507 -396.895025) (xy 349.717435 -396.923297)
			(xy 349.751451 -396.957321) (xy 349.779713 -396.996256) (xy 349.79102 -397.017494) (xy 349.791528 -397.018764)
			(xy 349.85771 -397.133285) (xy 350.413431 -397.133285) (xy 350.420763 -397.085737) (xy 350.435456 -397.039924)
			(xy 350.457148 -396.996982) (xy 350.485303 -396.957969) (xy 350.519224 -396.923851) (xy 350.558073 -396.895472)
			(xy 350.60089 -396.873532) (xy 350.646616 -396.858574) (xy 350.694121 -396.850968) (xy 350.742232 -396.850901)
			(xy 350.789759 -396.858376) (xy 350.835526 -396.873207) (xy 350.878404 -396.895028) (xy 350.917331 -396.923299)
			(xy 350.951347 -396.957323) (xy 350.979609 -396.996257) (xy 350.990916 -397.017494) (xy 350.991424 -397.018764)
			(xy 351.084589 -397.179977) (xy 351.613718 -397.179977) (xy 351.613966 -397.129044) (xy 351.62266 -397.078857)
			(xy 351.639557 -397.030807) (xy 351.664189 -396.986225) (xy 351.695875 -396.946346) (xy 351.733736 -396.912275)
			(xy 351.776724 -396.884956) (xy 351.823648 -396.865145) (xy 351.873208 -396.853392) (xy 351.92403 -396.850021)
			(xy 351.974708 -396.855127) (xy 352.023837 -396.868568) (xy 352.070056 -396.88997) (xy 352.112086 -396.918743)
			(xy 352.14876 -396.954088) (xy 352.179065 -396.995026) (xy 352.191066 -397.017494) (xy 352.191574 -397.018764)
			(xy 352.284739 -397.179976) (xy 352.813621 -397.179976) (xy 352.81387 -397.129044) (xy 352.822563 -397.078857)
			(xy 352.83946 -397.030808) (xy 352.864092 -396.986227) (xy 352.895778 -396.946349) (xy 352.933638 -396.912278)
			(xy 352.976626 -396.88496) (xy 353.023549 -396.865149) (xy 353.073108 -396.853396) (xy 353.123929 -396.850025)
			(xy 353.174606 -396.85513) (xy 353.223735 -396.86857) (xy 353.269953 -396.889973) (xy 353.311982 -396.918745)
			(xy 353.348657 -396.954089) (xy 353.378961 -396.995027) (xy 353.390962 -397.017494) (xy 353.39147 -397.018764)
			(xy 353.457652 -397.133285) (xy 354.013635 -397.133285) (xy 354.020967 -397.085737) (xy 354.03566 -397.039926)
			(xy 354.057351 -396.996983) (xy 354.085505 -396.957971) (xy 354.119426 -396.923854) (xy 354.158274 -396.895475)
			(xy 354.20109 -396.873536) (xy 354.246816 -396.858578) (xy 354.294321 -396.850971) (xy 354.342431 -396.850905)
			(xy 354.389957 -396.858379) (xy 354.435724 -396.873209) (xy 354.478601 -396.89503) (xy 354.517528 -396.923301)
			(xy 354.551543 -396.957324) (xy 354.579805 -396.996257) (xy 354.591112 -397.017494) (xy 354.59162 -397.018764)
			(xy 354.657801 -397.133284) (xy 370.586149 -397.133284) (xy 370.593481 -397.085739) (xy 370.608173 -397.03993)
			(xy 370.629864 -396.996991) (xy 370.658016 -396.957981) (xy 370.691934 -396.923866) (xy 370.73078 -396.895488)
			(xy 370.773594 -396.87355) (xy 370.819317 -396.858592) (xy 370.866819 -396.850986) (xy 370.914926 -396.850918)
			(xy 370.962449 -396.858392) (xy 371.008214 -396.873221) (xy 371.051089 -396.895039) (xy 371.090014 -396.923308)
			(xy 371.124028 -396.957328) (xy 371.15229 -396.996259) (xy 371.163596 -397.017494) (xy 371.164104 -397.018764)
			(xy 371.230285 -397.133284) (xy 371.786053 -397.133284) (xy 371.793384 -397.08574) (xy 371.808077 -397.039932)
			(xy 371.829767 -396.996992) (xy 371.857919 -396.957983) (xy 371.891837 -396.923869) (xy 371.930682 -396.895491)
			(xy 371.973495 -396.873553) (xy 372.019217 -396.858596) (xy 372.066718 -396.850989) (xy 372.114825 -396.850922)
			(xy 372.162347 -396.858395) (xy 372.208111 -396.873224) (xy 372.250986 -396.895042) (xy 372.289911 -396.92331)
			(xy 372.323924 -396.957329) (xy 372.352186 -396.996259) (xy 372.363492 -397.017494) (xy 372.364 -397.018764)
			(xy 372.430181 -397.133284) (xy 372.985956 -397.133284) (xy 372.993288 -397.08574) (xy 373.00798 -397.039933)
			(xy 373.02967 -396.996994) (xy 373.057821 -396.957986) (xy 373.091739 -396.923872) (xy 373.130584 -396.895495)
			(xy 373.173396 -396.873557) (xy 373.219117 -396.858599) (xy 373.266618 -396.850993) (xy 373.314724 -396.850925)
			(xy 373.362246 -396.858398) (xy 373.408009 -396.873226) (xy 373.450883 -396.895044) (xy 373.489807 -396.923311)
			(xy 373.523821 -396.95733) (xy 373.552082 -396.996259) (xy 373.563388 -397.017494) (xy 373.563896 -397.018764)
			(xy 373.630079 -397.133286) (xy 374.186012 -397.133286) (xy 374.193344 -397.085734) (xy 374.208038 -397.039918)
			(xy 374.229732 -396.996971) (xy 374.257888 -396.957956) (xy 374.291812 -396.923836) (xy 374.330664 -396.895454)
			(xy 374.373485 -396.873513) (xy 374.419215 -396.858554) (xy 374.466724 -396.850948) (xy 374.514839 -396.850882)
			(xy 374.562369 -396.858358) (xy 374.60814 -396.873191) (xy 374.65102 -396.895015) (xy 374.68995 -396.92329)
			(xy 374.723968 -396.957317) (xy 374.752231 -396.996255) (xy 374.763538 -397.017494) (xy 374.764046 -397.018764)
			(xy 374.830229 -397.133286) (xy 375.385915 -397.133286) (xy 375.393247 -397.085734) (xy 375.407941 -397.039919)
			(xy 375.429635 -396.996973) (xy 375.457791 -396.957958) (xy 375.491714 -396.923839) (xy 375.530566 -396.895457)
			(xy 375.573385 -396.873516) (xy 375.619115 -396.858558) (xy 375.666624 -396.850952) (xy 375.714737 -396.850885)
			(xy 375.762267 -396.858361) (xy 375.808037 -396.873194) (xy 375.850917 -396.895017) (xy 375.889847 -396.923291)
			(xy 375.923864 -396.957318) (xy 375.952127 -396.996255) (xy 375.963434 -397.017494) (xy 375.963942 -397.018764)
			(xy 376.030123 -397.133284) (xy 376.58616 -397.133284) (xy 376.593491 -397.085741) (xy 376.608183 -397.039934)
			(xy 376.629873 -396.996996) (xy 376.658024 -396.957988) (xy 376.691941 -396.923874) (xy 376.730785 -396.895498)
			(xy 376.773597 -396.87356) (xy 376.819317 -396.858603) (xy 376.866817 -396.850997) (xy 376.914922 -396.850929)
			(xy 376.962444 -396.858401) (xy 377.008207 -396.873229) (xy 377.05108 -396.895046) (xy 377.090004 -396.923313)
			(xy 377.124017 -396.957331) (xy 377.152278 -396.99626) (xy 377.163584 -397.017494) (xy 377.164092 -397.018764)
			(xy 377.230273 -397.133284) (xy 377.786064 -397.133284) (xy 377.793395 -397.085741) (xy 377.808087 -397.039935)
			(xy 377.829776 -396.996998) (xy 377.857927 -396.957991) (xy 377.891843 -396.923877) (xy 377.930687 -396.895501)
			(xy 377.973498 -396.873564) (xy 378.019218 -396.858607) (xy 378.066717 -396.851) (xy 378.114821 -396.850932)
			(xy 378.162342 -396.858405) (xy 378.208104 -396.873232) (xy 378.250977 -396.895049) (xy 378.2899 -396.923315)
			(xy 378.323913 -396.957332) (xy 378.352174 -396.99626) (xy 378.36348 -397.017494) (xy 378.363988 -397.018764)
			(xy 378.430169 -397.133284) (xy 378.985967 -397.133284) (xy 378.993298 -397.085742) (xy 379.00799 -397.039936)
			(xy 379.029679 -396.997) (xy 379.057829 -396.957993) (xy 379.091745 -396.92388) (xy 379.130588 -396.895504)
			(xy 379.173398 -396.873567) (xy 379.219118 -396.85861) (xy 379.266616 -396.851004) (xy 379.31472 -396.850936)
			(xy 379.36224 -396.858408) (xy 379.408002 -396.873235) (xy 379.450874 -396.895051) (xy 379.489797 -396.923317)
			(xy 379.523809 -396.957333) (xy 379.55207 -396.99626) (xy 379.563376 -397.017494) (xy 379.563884 -397.018764)
			(xy 379.630067 -397.133286) (xy 380.186022 -397.133286) (xy 380.193354 -397.085735) (xy 380.208048 -397.039921)
			(xy 380.229741 -396.996977) (xy 380.257896 -396.957963) (xy 380.291818 -396.923844) (xy 380.330669 -396.895464)
			(xy 380.373487 -396.873523) (xy 380.419215 -396.858565) (xy 380.466723 -396.850959) (xy 380.514835 -396.850892)
			(xy 380.562363 -396.858368) (xy 380.608132 -396.8732) (xy 380.651011 -396.895022) (xy 380.68994 -396.923295)
			(xy 380.723956 -396.95732) (xy 380.752219 -396.996256) (xy 380.763526 -397.017494) (xy 380.764034 -397.018764)
			(xy 380.830217 -397.133286) (xy 381.385926 -397.133286) (xy 381.393258 -397.085736) (xy 381.407951 -397.039923)
			(xy 381.429644 -396.996979) (xy 381.457799 -396.957966) (xy 381.49172 -396.923847) (xy 381.53057 -396.895467)
			(xy 381.573388 -396.873527) (xy 381.619116 -396.858569) (xy 381.666622 -396.850962) (xy 381.714734 -396.850896)
			(xy 381.762261 -396.858371) (xy 381.80803 -396.873202) (xy 381.850908 -396.895024) (xy 381.889837 -396.923297)
			(xy 381.923853 -396.957321) (xy 381.952115 -396.996256) (xy 381.963422 -397.017494) (xy 381.96393 -397.018764)
			(xy 382.057097 -397.179979) (xy 382.586212 -397.179979) (xy 382.586461 -397.129044) (xy 382.595154 -397.078856)
			(xy 382.612052 -397.030805) (xy 382.636685 -396.986222) (xy 382.668371 -396.946342) (xy 382.706233 -396.912271)
			(xy 382.749222 -396.884951) (xy 382.796147 -396.86514) (xy 382.845708 -396.853387) (xy 382.896532 -396.850016)
			(xy 382.947211 -396.855122) (xy 382.996341 -396.868563) (xy 383.042561 -396.889967) (xy 383.084591 -396.91874)
			(xy 383.121266 -396.954086) (xy 383.151571 -396.995026) (xy 383.163572 -397.017494) (xy 383.16408 -397.018764)
			(xy 383.257246 -397.179978) (xy 383.786116 -397.179978) (xy 383.786365 -397.129044) (xy 383.795058 -397.078856)
			(xy 383.811955 -397.030806) (xy 383.836588 -396.986224) (xy 383.868274 -396.946345) (xy 383.906135 -396.912274)
			(xy 383.949124 -396.884955) (xy 383.996048 -396.865144) (xy 384.045608 -396.85339) (xy 384.096431 -396.85002)
			(xy 384.147109 -396.855125) (xy 384.196238 -396.868566) (xy 384.242458 -396.889969) (xy 384.284487 -396.918742)
			(xy 384.321162 -396.954087) (xy 384.351467 -396.995026) (xy 384.363468 -397.017494) (xy 384.363976 -397.018764)
			(xy 384.457141 -397.179977) (xy 384.986019 -397.179977) (xy 384.986268 -397.129044) (xy 384.994961 -397.078857)
			(xy 385.011858 -397.030807) (xy 385.036491 -396.986226) (xy 385.068176 -396.946348) (xy 385.106037 -396.912277)
			(xy 385.149025 -396.884958) (xy 385.195948 -396.865147) (xy 385.245508 -396.853394) (xy 385.29633 -396.850023)
			(xy 385.347007 -396.855129) (xy 385.396136 -396.868569) (xy 385.442355 -396.889972) (xy 385.484384 -396.918744)
			(xy 385.521058 -396.954088) (xy 385.551363 -396.995026) (xy 385.563364 -397.017494) (xy 385.563872 -397.018764)
			(xy 385.630054 -397.133285) (xy 386.186033 -397.133285) (xy 386.193365 -397.085737) (xy 386.208058 -397.039925)
			(xy 386.22975 -396.996982) (xy 386.257904 -396.95797) (xy 386.291825 -396.923853) (xy 386.330673 -396.895474)
			(xy 386.37349 -396.873534) (xy 386.419216 -396.858576) (xy 386.466721 -396.85097) (xy 386.514831 -396.850903)
			(xy 386.562358 -396.858377) (xy 386.608125 -396.873208) (xy 386.651002 -396.895029) (xy 386.68993 -396.9233)
			(xy 386.723945 -396.957323) (xy 386.752207 -396.996257) (xy 386.763514 -397.017494) (xy 386.764022 -397.018764)
			(xy 386.830204 -397.133285) (xy 387.385937 -397.133285) (xy 387.393268 -397.085737) (xy 387.407961 -397.039926)
			(xy 387.429653 -396.996984) (xy 387.457807 -396.957973) (xy 387.491727 -396.923856) (xy 387.530575 -396.895477)
			(xy 387.573391 -396.873537) (xy 387.619116 -396.85858) (xy 387.666621 -396.850973) (xy 387.71473 -396.850906)
			(xy 387.762256 -396.85838) (xy 387.808023 -396.873211) (xy 387.850899 -396.895031) (xy 387.889826 -396.923302)
			(xy 387.923841 -396.957324) (xy 387.952103 -396.996257) (xy 387.96341 -397.017494) (xy 387.963918 -397.018764)
			(xy 388.057083 -397.179976) (xy 388.586223 -397.179976) (xy 388.586472 -397.129043) (xy 388.595165 -397.078858)
			(xy 388.612062 -397.030809) (xy 388.636694 -396.986228) (xy 388.668379 -396.94635) (xy 388.706239 -396.91228)
			(xy 388.749226 -396.884961) (xy 388.796149 -396.865151) (xy 388.845707 -396.853397) (xy 388.896529 -396.850027)
			(xy 388.947206 -396.855132) (xy 388.996334 -396.868572) (xy 389.042552 -396.889974) (xy 389.08458 -396.918746)
			(xy 389.121255 -396.95409) (xy 389.151559 -396.995027) (xy 389.16356 -397.017494) (xy 389.164068 -397.018764)
			(xy 389.24392 -397.15694) (xy 403.113748 -397.15694) (xy 403.113748 -397.156432) (xy 403.114292 -397.132444)
			(xy 403.121792 -397.085057) (xy 403.136612 -397.039428) (xy 403.158388 -396.996678) (xy 403.186583 -396.957861)
			(xy 403.220503 -396.923933) (xy 403.259313 -396.895728) (xy 403.302057 -396.873941) (xy 403.347683 -396.85911)
			(xy 403.395068 -396.851598) (xy 403.419056 -396.851124) (xy 403.442992 -396.851558) (xy 403.49028 -396.859018)
			(xy 403.535825 -396.873763) (xy 403.578513 -396.895431) (xy 403.617298 -396.923493) (xy 403.651232 -396.957261)
			(xy 403.679483 -396.995908) (xy 403.690836 -397.016986) (xy 403.691344 -397.018002) (xy 403.77165 -397.15694)
			(xy 404.313644 -397.15694) (xy 404.313644 -397.156432) (xy 404.314192 -397.132444) (xy 404.321692 -397.085058)
			(xy 404.336512 -397.039429) (xy 404.358287 -396.996679) (xy 404.386482 -396.957862) (xy 404.420401 -396.923934)
			(xy 404.459211 -396.895729) (xy 404.501955 -396.873943) (xy 404.54758 -396.859111) (xy 404.594964 -396.851598)
			(xy 404.618952 -396.851124) (xy 404.642888 -396.851561) (xy 404.690176 -396.859021) (xy 404.735721 -396.873765)
			(xy 404.778408 -396.895433) (xy 404.817194 -396.923494) (xy 404.851128 -396.957261) (xy 404.879379 -396.995908)
			(xy 404.890732 -397.016986) (xy 404.89124 -397.018002) (xy 404.971546 -397.15694) (xy 405.51354 -397.15694)
			(xy 405.51354 -397.156432) (xy 405.513968 -397.132437) (xy 405.521471 -397.085038) (xy 405.536298 -397.039397)
			(xy 405.558084 -396.996638) (xy 405.586291 -396.957814) (xy 405.620226 -396.923881) (xy 405.659051 -396.895676)
			(xy 405.701812 -396.873892) (xy 405.747454 -396.859068) (xy 405.794853 -396.851567) (xy 405.818848 -396.851124)
			(xy 405.842784 -396.851565) (xy 405.890071 -396.859024) (xy 405.935616 -396.873767) (xy 405.978304 -396.895434)
			(xy 406.01709 -396.923495) (xy 406.051024 -396.957262) (xy 406.079275 -396.995908) (xy 406.090628 -397.016986)
			(xy 406.091136 -397.018002) (xy 406.171442 -397.15694) (xy 406.713436 -397.15694) (xy 406.713436 -397.156432)
			(xy 406.713891 -397.132452) (xy 406.721386 -397.085082) (xy 406.736196 -397.039466) (xy 406.757958 -396.996728)
			(xy 406.786134 -396.957918) (xy 406.820034 -396.923992) (xy 406.858821 -396.895784) (xy 406.901542 -396.873989)
			(xy 406.947146 -396.859143) (xy 406.99451 -396.85161) (xy 407.01849 -396.851124) (xy 407.018998 -396.851124)
			(xy 407.042935 -396.851524) (xy 407.090225 -396.858991) (xy 407.135771 -396.873741) (xy 407.178458 -396.895415)
			(xy 407.217243 -396.923482) (xy 407.251176 -396.957255) (xy 407.279426 -396.995906) (xy 407.290778 -397.016986)
			(xy 407.291286 -397.018002) (xy 407.371592 -397.15694) (xy 407.913332 -397.15694) (xy 407.913332 -397.156432)
			(xy 407.913791 -397.132452) (xy 407.921286 -397.085082) (xy 407.936096 -397.039467) (xy 407.957857 -396.996729)
			(xy 407.986033 -396.957919) (xy 408.019932 -396.923993) (xy 408.058719 -396.895786) (xy 408.101439 -396.87399)
			(xy 408.147043 -396.859143) (xy 408.194407 -396.851611) (xy 408.218386 -396.851124) (xy 408.218894 -396.851124)
			(xy 408.242831 -396.851527) (xy 408.29012 -396.858993) (xy 408.335666 -396.873744) (xy 408.378354 -396.895417)
			(xy 408.417139 -396.923483) (xy 408.451072 -396.957255) (xy 408.479322 -396.995906) (xy 408.490674 -397.016986)
			(xy 408.491182 -397.018002) (xy 408.571488 -397.15694) (xy 409.113736 -397.15694) (xy 409.113736 -397.156432)
			(xy 409.114168 -397.132438) (xy 409.121671 -397.085039) (xy 409.136498 -397.039398) (xy 409.158283 -396.996639)
			(xy 409.18649 -396.957815) (xy 409.220424 -396.923882) (xy 409.259249 -396.895677) (xy 409.302009 -396.873893)
			(xy 409.347651 -396.859068) (xy 409.39505 -396.851567) (xy 409.419044 -396.851124) (xy 409.44298 -396.851568)
			(xy 409.490267 -396.859026) (xy 409.535812 -396.873769) (xy 409.5785 -396.895436) (xy 409.617285 -396.923496)
			(xy 409.651219 -396.957262) (xy 409.679471 -396.995909) (xy 409.690824 -397.016986) (xy 409.691332 -397.018002)
			(xy 409.771638 -397.15694) (xy 410.313632 -397.15694) (xy 410.313632 -397.156432) (xy 410.314068 -397.132438)
			(xy 410.321571 -397.085039) (xy 410.336398 -397.039399) (xy 410.358183 -396.99664) (xy 410.386389 -396.957816)
			(xy 410.420322 -396.923884) (xy 410.459147 -396.895678) (xy 410.501906 -396.873895) (xy 410.547547 -396.859069)
			(xy 410.594946 -396.851567) (xy 410.61894 -396.851124) (xy 410.642876 -396.851571) (xy 410.690163 -396.859029)
			(xy 410.735708 -396.873771) (xy 410.778395 -396.895437) (xy 410.817181 -396.923497) (xy 410.851115 -396.957263)
			(xy 410.879367 -396.995909) (xy 410.89072 -397.016986) (xy 410.891228 -397.018002) (xy 410.971534 -397.15694)
			(xy 411.513528 -397.15694) (xy 411.513528 -397.156432) (xy 411.513968 -397.132438) (xy 411.521471 -397.08504)
			(xy 411.536297 -397.0394) (xy 411.558082 -396.996641) (xy 411.586288 -396.957818) (xy 411.620221 -396.923885)
			(xy 411.659045 -396.89568) (xy 411.701804 -396.873896) (xy 411.747444 -396.85907) (xy 411.794842 -396.851568)
			(xy 411.818836 -396.851124) (xy 411.842772 -396.851574) (xy 411.890058 -396.859031) (xy 411.935603 -396.873773)
			(xy 411.978291 -396.895439) (xy 412.017077 -396.923498) (xy 412.051011 -396.957264) (xy 412.079263 -396.995909)
			(xy 412.090616 -397.016986) (xy 412.091124 -397.018002) (xy 412.17143 -397.15694) (xy 412.713424 -397.15694)
			(xy 412.713424 -397.156432) (xy 412.713891 -397.132453) (xy 412.721386 -397.085083) (xy 412.736195 -397.039469)
			(xy 412.757955 -396.996731) (xy 412.786131 -396.957922) (xy 412.820029 -396.923996) (xy 412.858814 -396.895788)
			(xy 412.901534 -396.873993) (xy 412.947136 -396.859145) (xy 412.994499 -396.851611) (xy 413.018478 -396.851124)
			(xy 413.018986 -396.851124) (xy 413.042923 -396.851534) (xy 413.090212 -396.858998) (xy 413.135757 -396.873748)
			(xy 413.178445 -396.89542) (xy 413.21723 -396.923485) (xy 413.251164 -396.957256) (xy 413.279414 -396.995907)
			(xy 413.290766 -397.016986) (xy 413.291274 -397.018002) (xy 413.37158 -397.15694) (xy 413.91332 -397.15694)
			(xy 413.91332 -397.156432) (xy 413.913791 -397.132453) (xy 413.921285 -397.085084) (xy 413.936095 -397.03947)
			(xy 413.957855 -396.996732) (xy 413.98603 -396.957923) (xy 414.019927 -396.923998) (xy 414.058712 -396.89579)
			(xy 414.101431 -396.873994) (xy 414.147033 -396.859146) (xy 414.194395 -396.851612) (xy 414.218374 -396.851124)
			(xy 414.218882 -396.851124) (xy 414.242819 -396.851537) (xy 414.290108 -396.859001) (xy 414.335653 -396.87375)
			(xy 414.378341 -396.895422) (xy 414.417126 -396.923486) (xy 414.451059 -396.957257) (xy 414.47931 -396.995907)
			(xy 414.490662 -397.016986) (xy 414.49117 -397.018002) (xy 414.571476 -397.15694) (xy 415.113724 -397.15694)
			(xy 415.113724 -397.156432) (xy 415.114168 -397.132438) (xy 415.121671 -397.085041) (xy 415.136497 -397.039401)
			(xy 415.158281 -396.996643) (xy 415.186487 -396.957819) (xy 415.220419 -396.923887) (xy 415.259243 -396.895681)
			(xy 415.302001 -396.873897) (xy 415.347641 -396.859071) (xy 415.395038 -396.851568) (xy 415.419032 -396.851124)
			(xy 415.442968 -396.851578) (xy 415.490254 -396.859034) (xy 415.535799 -396.873775) (xy 415.578487 -396.89544)
			(xy 415.617272 -396.923499) (xy 415.651207 -396.957264) (xy 415.679459 -396.995909) (xy 415.690812 -397.016986)
			(xy 415.69132 -397.018002) (xy 415.771626 -397.15694) (xy 416.31362 -397.15694) (xy 416.31362 -397.156432)
			(xy 416.314068 -397.132438) (xy 416.321571 -397.085041) (xy 416.336397 -397.039402) (xy 416.35818 -396.996644)
			(xy 416.386386 -396.95782) (xy 416.420317 -396.923888) (xy 416.45914 -396.895682) (xy 416.501898 -396.873898)
			(xy 416.547537 -396.859072) (xy 416.594934 -396.851568) (xy 416.618928 -396.851124) (xy 416.642863 -396.851581)
			(xy 416.69015 -396.859037) (xy 416.735695 -396.873777) (xy 416.778382 -396.895442) (xy 416.817168 -396.9235)
			(xy 416.851103 -396.957265) (xy 416.879355 -396.995909) (xy 416.890708 -397.016986) (xy 416.891216 -397.018002)
			(xy 416.971522 -397.15694) (xy 417.513516 -397.15694) (xy 417.513516 -397.156432) (xy 417.513968 -397.132439)
			(xy 417.521471 -397.085042) (xy 417.536296 -397.039403) (xy 417.55808 -396.996645) (xy 417.586284 -396.957822)
			(xy 417.620216 -396.92389) (xy 417.659038 -396.895684) (xy 417.701795 -396.873899) (xy 417.747434 -396.859072)
			(xy 417.794831 -396.851568) (xy 417.818824 -396.851124) (xy 417.842759 -396.851584) (xy 417.890046 -396.859039)
			(xy 417.93559 -396.873779) (xy 417.978278 -396.895444) (xy 418.017064 -396.923501) (xy 418.050998 -396.957265)
			(xy 418.079251 -396.99591) (xy 418.090604 -397.016986) (xy 418.091112 -397.018002) (xy 418.171418 -397.15694)
			(xy 418.713412 -397.15694) (xy 418.713412 -397.156432) (xy 418.713891 -397.132453) (xy 418.721385 -397.085085)
			(xy 418.736194 -397.039472) (xy 418.757953 -396.996735) (xy 418.786127 -396.957926) (xy 418.820024 -396.924)
			(xy 418.858808 -396.895792) (xy 418.901525 -396.873996) (xy 418.947126 -396.859147) (xy 418.994488 -396.851612)
			(xy 419.018466 -396.851124) (xy 419.018974 -396.851124) (xy 419.042911 -396.851543) (xy 419.090199 -396.859006)
			(xy 419.135744 -396.873754) (xy 419.178432 -396.895425) (xy 419.217218 -396.923488) (xy 419.251151 -396.957258)
			(xy 419.279402 -396.995907) (xy 419.290754 -397.016986) (xy 419.291262 -397.018002) (xy 419.371568 -397.15694)
			(xy 419.913308 -397.15694) (xy 419.913308 -397.156432) (xy 419.913791 -397.132454) (xy 419.921285 -397.085086)
			(xy 419.936094 -397.039473) (xy 419.957852 -396.996736) (xy 419.986026 -396.957927) (xy 420.019922 -396.924002)
			(xy 420.058705 -396.895794) (xy 420.101423 -396.873997) (xy 420.147023 -396.859148) (xy 420.194384 -396.851612)
			(xy 420.218362 -396.851124) (xy 420.21887 -396.851124) (xy 420.242807 -396.851547) (xy 420.290095 -396.859009)
			(xy 420.33564 -396.873756) (xy 420.378328 -396.895426) (xy 420.417113 -396.923489) (xy 420.451047 -396.957259)
			(xy 420.479298 -396.995907) (xy 420.49065 -397.016986) (xy 420.491158 -397.018002) (xy 420.571464 -397.15694)
			(xy 421.113712 -397.15694) (xy 421.113712 -397.156432) (xy 421.114168 -397.132439) (xy 421.12167 -397.085042)
			(xy 421.136496 -397.039404) (xy 421.158279 -396.996646) (xy 421.186483 -396.957823) (xy 421.220414 -396.923891)
			(xy 421.259236 -396.895685) (xy 421.301992 -396.8739) (xy 421.347631 -396.859073) (xy 421.395027 -396.851569)
			(xy 421.41902 -396.851124) (xy 421.442955 -396.851587) (xy 421.490241 -396.859042) (xy 421.535786 -396.873782)
			(xy 421.578474 -396.895445) (xy 421.61726 -396.923502) (xy 421.651194 -396.957266) (xy 421.679447 -396.99591)
			(xy 421.6908 -397.016986) (xy 421.691308 -397.018002) (xy 422.083738 -397.696944) (xy 422.096544 -397.720286)
			(xy 422.114771 -397.770304) (xy 422.124039 -397.822727) (xy 422.124632 -397.849344) (xy 422.124179 -397.873323)
			(xy 422.116675 -397.920689) (xy 422.101859 -397.9663) (xy 422.080094 -398.009034) (xy 422.051916 -398.04784)
			(xy 422.018018 -398.081764) (xy 421.979234 -398.109971) (xy 421.936517 -398.131769) (xy 421.890917 -398.14662)
			(xy 421.843556 -398.154161) (xy 421.819578 -398.154652) (xy 421.81907 -398.154652) (xy 421.795497 -398.154255)
			(xy 421.74891 -398.14701) (xy 421.703993 -398.132683) (xy 421.661815 -398.111614) (xy 421.623383 -398.084306)
			(xy 421.58961 -398.051409) (xy 421.561302 -398.013706) (xy 421.54983 -397.993108) (xy 421.549322 -397.992346)
			(xy 421.151558 -397.304006) (xy 421.139682 -397.281329) (xy 421.122831 -397.232996) (xy 421.114258 -397.182533)
			(xy 421.113712 -397.15694) (xy 420.571464 -397.15694) (xy 420.883588 -397.696944) (xy 420.896302 -397.720272)
			(xy 420.914403 -397.770215) (xy 420.923627 -397.82253) (xy 420.924228 -397.84909) (xy 420.924228 -397.849344)
			(xy 420.923778 -397.873335) (xy 420.916266 -397.920727) (xy 420.901434 -397.96636) (xy 420.879647 -398.009111)
			(xy 420.851441 -398.047928) (xy 420.81751 -398.081856) (xy 420.778691 -398.110059) (xy 420.735937 -398.131843)
			(xy 420.690303 -398.146672) (xy 420.642911 -398.15418) (xy 420.61892 -398.154652) (xy 420.595348 -398.154215)
			(xy 420.548763 -398.146978) (xy 420.503847 -398.132658) (xy 420.46167 -398.111595) (xy 420.423236 -398.084293)
			(xy 420.389462 -398.051402) (xy 420.361153 -398.013704) (xy 420.34968 -397.993108) (xy 420.349172 -397.992346)
			(xy 419.951408 -397.304006) (xy 419.939493 -397.281337) (xy 419.922555 -397.233012) (xy 419.913896 -397.182542)
			(xy 419.913308 -397.15694) (xy 419.371568 -397.15694) (xy 419.683692 -397.696944) (xy 419.696406 -397.720272)
			(xy 419.714507 -397.770215) (xy 419.723731 -397.82253) (xy 419.724332 -397.84909) (xy 419.724332 -397.849344)
			(xy 419.723878 -397.873335) (xy 419.716366 -397.920726) (xy 419.701534 -397.966359) (xy 419.679747 -398.00911)
			(xy 419.651542 -398.047927) (xy 419.617612 -398.081855) (xy 419.578793 -398.110058) (xy 419.53604 -398.131842)
			(xy 419.490407 -398.146671) (xy 419.443015 -398.15418) (xy 419.419024 -398.154652) (xy 419.395452 -398.154211)
			(xy 419.348867 -398.146975) (xy 419.303951 -398.132656) (xy 419.261774 -398.111594) (xy 419.223341 -398.084292)
			(xy 419.189567 -398.051401) (xy 419.161257 -398.013704) (xy 419.149784 -397.993108) (xy 419.149276 -397.992346)
			(xy 418.751512 -397.304006) (xy 418.739598 -397.281337) (xy 418.72266 -397.233012) (xy 418.714 -397.182542)
			(xy 418.713412 -397.15694) (xy 418.171418 -397.15694) (xy 418.483542 -397.696944) (xy 418.496349 -397.720286)
			(xy 418.514576 -397.770304) (xy 418.523843 -397.822727) (xy 418.524436 -397.849344) (xy 418.523979 -397.873322)
			(xy 418.516475 -397.920688) (xy 418.501659 -397.966299) (xy 418.479895 -398.009033) (xy 418.451717 -398.047839)
			(xy 418.41782 -398.081762) (xy 418.379036 -398.10997) (xy 418.336319 -398.131768) (xy 418.29072 -398.14662)
			(xy 418.24336 -398.15416) (xy 418.219382 -398.154652) (xy 418.218874 -398.154652) (xy 418.195301 -398.154252)
			(xy 418.148714 -398.147008) (xy 418.103797 -398.132681) (xy 418.06162 -398.111613) (xy 418.023187 -398.084305)
			(xy 417.989414 -398.051408) (xy 417.961106 -398.013706) (xy 417.949634 -397.993108) (xy 417.949126 -397.992346)
			(xy 417.551362 -397.304006) (xy 417.539486 -397.281329) (xy 417.522635 -397.232996) (xy 417.514062 -397.182533)
			(xy 417.513516 -397.15694) (xy 416.971522 -397.15694) (xy 417.283646 -397.696944) (xy 417.296453 -397.720286)
			(xy 417.31468 -397.770304) (xy 417.323947 -397.822727) (xy 417.32454 -397.849344) (xy 417.324079 -397.873322)
			(xy 417.316575 -397.920688) (xy 417.301759 -397.966298) (xy 417.279995 -398.009032) (xy 417.251818 -398.047837)
			(xy 417.217922 -398.081761) (xy 417.179138 -398.109969) (xy 417.136422 -398.131767) (xy 417.090824 -398.146619)
			(xy 417.043464 -398.15416) (xy 417.019486 -398.154652) (xy 417.018978 -398.154652) (xy 416.995405 -398.154249)
			(xy 416.948818 -398.147005) (xy 416.903901 -398.132679) (xy 416.861724 -398.111611) (xy 416.823291 -398.084304)
			(xy 416.789518 -398.051408) (xy 416.76121 -398.013706) (xy 416.749738 -397.993108) (xy 416.74923 -397.992346)
			(xy 416.351466 -397.304006) (xy 416.339591 -397.281329) (xy 416.322739 -397.232996) (xy 416.314166 -397.182533)
			(xy 416.31362 -397.15694) (xy 415.771626 -397.15694) (xy 416.08375 -397.696944) (xy 416.096557 -397.720285)
			(xy 416.114784 -397.770304) (xy 416.124051 -397.822726) (xy 416.124644 -397.849344) (xy 416.124179 -397.873322)
			(xy 416.116676 -397.920687) (xy 416.10186 -397.966297) (xy 416.080096 -398.00903) (xy 416.05192 -398.047836)
			(xy 416.018023 -398.08176) (xy 415.97924 -398.109967) (xy 415.936525 -398.131765) (xy 415.890927 -398.146618)
			(xy 415.843568 -398.15416) (xy 415.81959 -398.154652) (xy 415.819082 -398.154652) (xy 415.795509 -398.154245)
			(xy 415.748922 -398.147003) (xy 415.704006 -398.132677) (xy 415.661828 -398.11161) (xy 415.623395 -398.084303)
			(xy 415.589623 -398.051407) (xy 415.561314 -398.013706) (xy 415.549842 -397.993108) (xy 415.549334 -397.992346)
			(xy 415.15157 -397.304006) (xy 415.139695 -397.281329) (xy 415.122843 -397.232996) (xy 415.11427 -397.182533)
			(xy 415.113724 -397.15694) (xy 414.571476 -397.15694) (xy 414.8836 -397.696944) (xy 414.896315 -397.720271)
			(xy 414.914415 -397.770215) (xy 414.923639 -397.82253) (xy 414.92424 -397.84909) (xy 414.92424 -397.849344)
			(xy 414.923778 -397.873335) (xy 414.916266 -397.920725) (xy 414.901435 -397.966357) (xy 414.879649 -398.009107)
			(xy 414.851444 -398.047924) (xy 414.817515 -398.081852) (xy 414.778697 -398.110055) (xy 414.735946 -398.13184)
			(xy 414.690313 -398.146669) (xy 414.642923 -398.154179) (xy 414.618932 -398.154652) (xy 414.59536 -398.154205)
			(xy 414.548776 -398.14697) (xy 414.50386 -398.132651) (xy 414.461683 -398.111591) (xy 414.423249 -398.08429)
			(xy 414.389475 -398.0514) (xy 414.361165 -398.013703) (xy 414.349692 -397.993108) (xy 414.349184 -397.992346)
			(xy 413.95142 -397.304006) (xy 413.939506 -397.281337) (xy 413.922568 -397.233012) (xy 413.913908 -397.182542)
			(xy 413.91332 -397.15694) (xy 413.37158 -397.15694) (xy 413.683704 -397.696944) (xy 413.696419 -397.720271)
			(xy 413.71452 -397.770214) (xy 413.723743 -397.82253) (xy 413.724344 -397.84909) (xy 413.724344 -397.849344)
			(xy 413.723878 -397.873335) (xy 413.716367 -397.920724) (xy 413.701535 -397.966356) (xy 413.679749 -398.009106)
			(xy 413.651545 -398.047923) (xy 413.617617 -398.08185) (xy 413.578799 -398.110054) (xy 413.536049 -398.131838)
			(xy 413.490417 -398.146668) (xy 413.443027 -398.154179) (xy 413.419036 -398.154652) (xy 413.395464 -398.154202)
			(xy 413.34888 -398.146967) (xy 413.303964 -398.132649) (xy 413.261787 -398.111589) (xy 413.223353 -398.084289)
			(xy 413.189579 -398.051399) (xy 413.161269 -398.013703) (xy 413.149796 -397.993108) (xy 413.149288 -397.992346)
			(xy 412.751524 -397.304006) (xy 412.739611 -397.281337) (xy 412.722672 -397.233012) (xy 412.714012 -397.182542)
			(xy 412.713424 -397.15694) (xy 412.17143 -397.15694) (xy 412.483554 -397.696944) (xy 412.496362 -397.720285)
			(xy 412.514588 -397.770304) (xy 412.523855 -397.822726) (xy 412.524448 -397.849344) (xy 412.523979 -397.873322)
			(xy 412.516476 -397.920687) (xy 412.50166 -397.966296) (xy 412.479897 -398.009029) (xy 412.451721 -398.047835)
			(xy 412.417825 -398.081758) (xy 412.379043 -398.109966) (xy 412.336328 -398.131764) (xy 412.29073 -398.146617)
			(xy 412.243371 -398.154159) (xy 412.219394 -398.154652) (xy 412.218886 -398.154652) (xy 412.195313 -398.154242)
			(xy 412.148727 -398.147) (xy 412.10381 -398.132675) (xy 412.061633 -398.111608) (xy 412.0232 -398.084302)
			(xy 411.989427 -398.051406) (xy 411.961119 -398.013705) (xy 411.949646 -397.993108) (xy 411.949138 -397.992346)
			(xy 411.551374 -397.304006) (xy 411.539499 -397.281329) (xy 411.522648 -397.232996) (xy 411.514074 -397.182533)
			(xy 411.513528 -397.15694) (xy 410.971534 -397.15694) (xy 411.283658 -397.696944) (xy 411.296466 -397.720285)
			(xy 411.314692 -397.770304) (xy 411.323959 -397.822726) (xy 411.324552 -397.849344) (xy 411.324079 -397.873322)
			(xy 411.316576 -397.920686) (xy 411.301761 -397.966295) (xy 411.279998 -398.009028) (xy 411.251822 -398.047833)
			(xy 411.217927 -398.081757) (xy 411.179145 -398.109965) (xy 411.13643 -398.131763) (xy 411.090833 -398.146616)
			(xy 411.043475 -398.154159) (xy 411.019498 -398.154652) (xy 411.01899 -398.154652) (xy 410.995417 -398.154239)
			(xy 410.948831 -398.146997) (xy 410.903914 -398.132673) (xy 410.861737 -398.111607) (xy 410.823304 -398.084301)
			(xy 410.789531 -398.051406) (xy 410.761223 -398.013705) (xy 410.74975 -397.993108) (xy 410.749242 -397.992346)
			(xy 410.351478 -397.304006) (xy 410.339603 -397.281328) (xy 410.322752 -397.232996) (xy 410.314178 -397.182533)
			(xy 410.313632 -397.15694) (xy 409.771638 -397.15694) (xy 410.083762 -397.696944) (xy 410.09657 -397.720285)
			(xy 410.114796 -397.770304) (xy 410.124063 -397.822726) (xy 410.124656 -397.849344) (xy 410.124179 -397.873321)
			(xy 410.116676 -397.920686) (xy 410.101861 -397.966295) (xy 410.080098 -398.009027) (xy 410.051923 -398.047832)
			(xy 410.018028 -398.081755) (xy 409.979247 -398.109963) (xy 409.936533 -398.131762) (xy 409.890937 -398.146616)
			(xy 409.843579 -398.154159) (xy 409.819602 -398.154652) (xy 409.819094 -398.154652) (xy 409.795521 -398.154236)
			(xy 409.748935 -398.146995) (xy 409.704019 -398.132671) (xy 409.661841 -398.111605) (xy 409.623408 -398.0843)
			(xy 409.589635 -398.051405) (xy 409.561327 -398.013705) (xy 409.549854 -397.993108) (xy 409.549346 -397.992346)
			(xy 409.151582 -397.304006) (xy 409.139708 -397.281328) (xy 409.122856 -397.232996) (xy 409.114282 -397.182533)
			(xy 409.113736 -397.15694) (xy 408.571488 -397.15694) (xy 408.883612 -397.696944) (xy 408.896328 -397.720271)
			(xy 408.914428 -397.770214) (xy 408.923651 -397.82253) (xy 408.924252 -397.84909) (xy 408.924252 -397.849344)
			(xy 408.923778 -397.873334) (xy 408.916267 -397.920723) (xy 408.901436 -397.966354) (xy 408.879651 -398.009104)
			(xy 408.851448 -398.04792) (xy 408.81752 -398.081848) (xy 408.778704 -398.110051) (xy 408.735954 -398.131836)
			(xy 408.690323 -398.146667) (xy 408.642934 -398.154178) (xy 408.618944 -398.154652) (xy 408.595373 -398.154195)
			(xy 408.548789 -398.146962) (xy 408.503873 -398.132645) (xy 408.461696 -398.111586) (xy 408.423262 -398.084287)
			(xy 408.389488 -398.051398) (xy 408.361178 -398.013703) (xy 408.349704 -397.993108) (xy 408.349196 -397.992346)
			(xy 407.951432 -397.304006) (xy 407.939519 -397.281336) (xy 407.92258 -397.233012) (xy 407.91392 -397.182542)
			(xy 407.913332 -397.15694) (xy 407.371592 -397.15694) (xy 407.683716 -397.696944) (xy 407.696432 -397.720271)
			(xy 407.714532 -397.770214) (xy 407.723755 -397.82253) (xy 407.724356 -397.84909) (xy 407.724356 -397.849344)
			(xy 407.723878 -397.873334) (xy 407.716367 -397.920723) (xy 407.701536 -397.966353) (xy 407.679752 -398.009103)
			(xy 407.651549 -398.047919) (xy 407.617622 -398.081846) (xy 407.578806 -398.11005) (xy 407.536057 -398.131835)
			(xy 407.490427 -398.146666) (xy 407.443038 -398.154178) (xy 407.419048 -398.154652) (xy 407.395477 -398.154192)
			(xy 407.348893 -398.146959) (xy 407.303977 -398.132643) (xy 407.2618 -398.111585) (xy 407.223366 -398.084286)
			(xy 407.189592 -398.051398) (xy 407.161282 -398.013703) (xy 407.149808 -397.993108) (xy 407.1493 -397.992346)
			(xy 406.751536 -397.304006) (xy 406.739623 -397.281336) (xy 406.722684 -397.233012) (xy 406.714024 -397.182542)
			(xy 406.713436 -397.15694) (xy 406.171442 -397.15694) (xy 406.483566 -397.696944) (xy 406.496375 -397.720285)
			(xy 406.5146 -397.770303) (xy 406.523867 -397.822726) (xy 406.52446 -397.849344) (xy 406.524079 -397.873326)
			(xy 406.516573 -397.9207) (xy 406.501752 -397.966317) (xy 406.479981 -398.009055) (xy 406.451795 -398.047865)
			(xy 406.417888 -398.08179) (xy 406.379094 -398.109996) (xy 406.336367 -398.13179) (xy 406.290757 -398.146635)
			(xy 406.243388 -398.154166) (xy 406.219406 -398.154652) (xy 406.218898 -398.154652) (xy 406.195325 -398.154232)
			(xy 406.14874 -398.146992) (xy 406.103823 -398.132669) (xy 406.061646 -398.111604) (xy 406.023213 -398.084299)
			(xy 405.989439 -398.051405) (xy 405.961131 -398.013705) (xy 405.949658 -397.993108) (xy 405.94915 -397.992346)
			(xy 405.551386 -397.304006) (xy 405.539512 -397.281328) (xy 405.52266 -397.232996) (xy 405.514086 -397.182533)
			(xy 405.51354 -397.15694) (xy 404.971546 -397.15694) (xy 405.28367 -397.696944) (xy 405.296479 -397.720285)
			(xy 405.314704 -397.770303) (xy 405.323971 -397.822726) (xy 405.324564 -397.849344) (xy 405.324179 -397.873326)
			(xy 405.316673 -397.920699) (xy 405.301852 -397.966316) (xy 405.280081 -398.009054) (xy 405.251896 -398.047863)
			(xy 405.21799 -398.081788) (xy 405.179196 -398.109994) (xy 405.136469 -398.131788) (xy 405.090861 -398.146634)
			(xy 405.043492 -398.154166) (xy 405.01951 -398.154652) (xy 405.019002 -398.154652) (xy 404.995429 -398.154229)
			(xy 404.948844 -398.14699) (xy 404.903927 -398.132667) (xy 404.86175 -398.111602) (xy 404.823317 -398.084298)
			(xy 404.789544 -398.051404) (xy 404.761235 -398.013705) (xy 404.749762 -397.993108) (xy 404.749254 -397.992346)
			(xy 404.35149 -397.304006) (xy 404.339616 -397.281328) (xy 404.322764 -397.232995) (xy 404.31419 -397.182533)
			(xy 404.313644 -397.15694) (xy 403.77165 -397.15694) (xy 404.083774 -397.696944) (xy 404.096583 -397.720284)
			(xy 404.114808 -397.770303) (xy 404.124075 -397.822726) (xy 404.124668 -397.849344) (xy 404.124279 -397.873326)
			(xy 404.116773 -397.920698) (xy 404.101952 -397.966315) (xy 404.080182 -398.009053) (xy 404.051997 -398.047862)
			(xy 404.018091 -398.081787) (xy 403.979298 -398.109993) (xy 403.936572 -398.131787) (xy 403.890964 -398.146633)
			(xy 403.843595 -398.154165) (xy 403.819614 -398.154652) (xy 403.819106 -398.154652) (xy 403.795534 -398.154226)
			(xy 403.748948 -398.146987) (xy 403.704032 -398.132665) (xy 403.661854 -398.111601) (xy 403.623421 -398.084297)
			(xy 403.589648 -398.051404) (xy 403.561339 -398.013705) (xy 403.549866 -397.993108) (xy 403.549358 -397.992346)
			(xy 403.151594 -397.304006) (xy 403.139721 -397.281328) (xy 403.122868 -397.232995) (xy 403.114294 -397.182532)
			(xy 403.113748 -397.15694) (xy 389.24392 -397.15694) (xy 389.55599 -397.696944) (xy 389.556244 -397.697452)
			(xy 389.556498 -397.697452) (xy 389.557768 -397.699992) (xy 389.570036 -397.722909) (xy 389.587445 -397.771886)
			(xy 389.59632 -397.823102) (xy 389.596884 -397.84909) (xy 389.596884 -397.849344) (xy 389.596479 -397.873325)
			(xy 389.588973 -397.920696) (xy 389.574154 -397.966311) (xy 389.552385 -398.009048) (xy 389.524202 -398.047856)
			(xy 389.490298 -398.081781) (xy 389.451507 -398.109988) (xy 389.408783 -398.131783) (xy 389.363177 -398.14663)
			(xy 389.315811 -398.154164) (xy 389.29183 -398.154652) (xy 389.291322 -398.154652) (xy 389.267658 -398.154195)
			(xy 389.220898 -398.146888) (xy 389.175823 -398.13246) (xy 389.133511 -398.111257) (xy 389.094972 -398.083784)
			(xy 389.061129 -398.0507) (xy 389.032791 -398.012795) (xy 389.02132 -397.992092) (xy 389.021066 -397.99133)
			(xy 388.62381 -397.304006) (xy 388.611629 -397.280791) (xy 388.594516 -397.231239) (xy 388.589774 -397.205454)
			(xy 388.589774 -397.2052) (xy 388.586223 -397.179976) (xy 388.057083 -397.179976) (xy 388.35584 -397.696944)
			(xy 388.356094 -397.697452) (xy 388.356348 -397.697452) (xy 388.357618 -397.699992) (xy 388.369851 -397.722916)
			(xy 388.387171 -397.771902) (xy 388.395958 -397.823111) (xy 388.39648 -397.84909) (xy 388.39648 -397.849344)
			(xy 388.396078 -397.873338) (xy 388.388564 -397.920734) (xy 388.373729 -397.966371) (xy 388.351938 -398.009125)
			(xy 388.323726 -398.047945) (xy 388.28979 -398.081873) (xy 388.250964 -398.110075) (xy 388.208204 -398.131857)
			(xy 388.162564 -398.146681) (xy 388.115166 -398.154184) (xy 388.091172 -398.154652) (xy 388.06751 -398.154155)
			(xy 388.020751 -398.146855) (xy 387.975677 -398.132434) (xy 387.933365 -398.111238) (xy 387.894826 -398.083772)
			(xy 387.860982 -398.050693) (xy 387.832641 -398.012793) (xy 387.82117 -397.992092) (xy 387.820916 -397.99133)
			(xy 387.42366 -397.304006) (xy 387.411482 -397.280789) (xy 387.394366 -397.231239) (xy 387.389624 -397.205454)
			(xy 387.389624 -397.2052) (xy 387.386148 -397.181394) (xy 387.385937 -397.133285) (xy 386.830204 -397.133285)
			(xy 387.155944 -397.696944) (xy 387.156198 -397.697452) (xy 387.156452 -397.697452) (xy 387.157722 -397.699992)
			(xy 387.169955 -397.722916) (xy 387.187275 -397.771902) (xy 387.196062 -397.823111) (xy 387.196584 -397.84909)
			(xy 387.196584 -397.849344) (xy 387.196178 -397.873338) (xy 387.188664 -397.920733) (xy 387.17383 -397.96637)
			(xy 387.152038 -398.009124) (xy 387.123828 -398.047943) (xy 387.089892 -398.081872) (xy 387.051066 -398.110074)
			(xy 387.008307 -398.131856) (xy 386.962667 -398.14668) (xy 386.91527 -398.154183) (xy 386.891276 -398.154652)
			(xy 386.867611 -398.154232) (xy 386.820849 -398.146918) (xy 386.775773 -398.132483) (xy 386.733461 -398.111274)
			(xy 386.694923 -398.083796) (xy 386.661081 -398.050707) (xy 386.632744 -398.012797) (xy 386.621274 -397.992092)
			(xy 386.62102 -397.99133) (xy 386.223764 -397.304006) (xy 386.211586 -397.280789) (xy 386.19447 -397.231239)
			(xy 386.189728 -397.205454) (xy 386.189728 -397.2052) (xy 386.186245 -397.181395) (xy 386.186033 -397.133285)
			(xy 385.630054 -397.133285) (xy 385.955794 -397.696944) (xy 385.956048 -397.697452) (xy 385.956302 -397.697452)
			(xy 385.957572 -397.699992) (xy 385.969841 -397.722909) (xy 385.987249 -397.771886) (xy 385.996124 -397.823102)
			(xy 385.996688 -397.84909) (xy 385.996688 -397.849344) (xy 385.996279 -397.873325) (xy 385.988774 -397.920695)
			(xy 385.973954 -397.96631) (xy 385.952186 -398.009047) (xy 385.924003 -398.047855) (xy 385.8901 -398.08178)
			(xy 385.851309 -398.109986) (xy 385.808586 -398.131782) (xy 385.76298 -398.146629) (xy 385.715614 -398.154164)
			(xy 385.691634 -398.154652) (xy 385.691126 -398.154652) (xy 385.667462 -398.154192) (xy 385.620702 -398.146885)
			(xy 385.575627 -398.132458) (xy 385.533315 -398.111255) (xy 385.494777 -398.083783) (xy 385.460934 -398.0507)
			(xy 385.432595 -398.012795) (xy 385.421124 -397.992092) (xy 385.42087 -397.99133) (xy 385.023614 -397.304006)
			(xy 385.011433 -397.28079) (xy 384.99432 -397.231239) (xy 384.989578 -397.205454) (xy 384.989578 -397.2052)
			(xy 384.986019 -397.179977) (xy 384.457141 -397.179977) (xy 384.755898 -397.696944) (xy 384.756152 -397.697452)
			(xy 384.756406 -397.697452) (xy 384.757676 -397.699992) (xy 384.769945 -397.722909) (xy 384.787353 -397.771886)
			(xy 384.796228 -397.823102) (xy 384.796792 -397.84909) (xy 384.796792 -397.849344) (xy 384.796379 -397.873325)
			(xy 384.788874 -397.920695) (xy 384.774055 -397.966309) (xy 384.752287 -398.009046) (xy 384.724104 -398.047854)
			(xy 384.690201 -398.081778) (xy 384.651412 -398.109985) (xy 384.608689 -398.13178) (xy 384.563084 -398.146628)
			(xy 384.515718 -398.154164) (xy 384.491738 -398.154652) (xy 384.49123 -398.154652) (xy 384.467566 -398.154188)
			(xy 384.420807 -398.146882) (xy 384.375732 -398.132456) (xy 384.333419 -398.111254) (xy 384.294881 -398.083782)
			(xy 384.261038 -398.050699) (xy 384.232699 -398.012794) (xy 384.221228 -397.992092) (xy 384.220974 -397.99133)
			(xy 383.823718 -397.304006) (xy 383.811537 -397.28079) (xy 383.794424 -397.231239) (xy 383.789682 -397.205454)
			(xy 383.789682 -397.2052) (xy 383.786116 -397.179978) (xy 383.257246 -397.179978) (xy 383.556002 -397.696944)
			(xy 383.556256 -397.697452) (xy 383.55651 -397.697452) (xy 383.55778 -397.699992) (xy 383.570049 -397.722909)
			(xy 383.587457 -397.771886) (xy 383.596332 -397.823102) (xy 383.596896 -397.84909) (xy 383.596896 -397.849344)
			(xy 383.596479 -397.873324) (xy 383.588974 -397.920694) (xy 383.574155 -397.966308) (xy 383.552387 -398.009045)
			(xy 383.524206 -398.047852) (xy 383.490303 -398.081777) (xy 383.451514 -398.109984) (xy 383.408792 -398.131779)
			(xy 383.363187 -398.146628) (xy 383.315822 -398.154163) (xy 383.291842 -398.154652) (xy 383.291334 -398.154652)
			(xy 383.267671 -398.154185) (xy 383.220911 -398.14688) (xy 383.175836 -398.132454) (xy 383.133524 -398.111252)
			(xy 383.094985 -398.083781) (xy 383.061142 -398.050699) (xy 383.032803 -398.012794) (xy 383.021332 -397.992092)
			(xy 383.021078 -397.99133) (xy 382.623822 -397.304006) (xy 382.611641 -397.28079) (xy 382.594528 -397.231239)
			(xy 382.589786 -397.205454) (xy 382.589786 -397.2052) (xy 382.586212 -397.179979) (xy 382.057097 -397.179979)
			(xy 382.355852 -397.696944) (xy 382.356106 -397.697452) (xy 382.35636 -397.697452) (xy 382.35763 -397.699992)
			(xy 382.369864 -397.722916) (xy 382.387183 -397.771902) (xy 382.395971 -397.823111) (xy 382.396492 -397.84909)
			(xy 382.396492 -397.849344) (xy 382.396078 -397.873337) (xy 382.388565 -397.920732) (xy 382.37373 -397.966368)
			(xy 382.35194 -398.009122) (xy 382.32373 -398.047941) (xy 382.289795 -398.081869) (xy 382.250971 -398.110071)
			(xy 382.208212 -398.131853) (xy 382.162574 -398.146679) (xy 382.115177 -398.154183) (xy 382.091184 -398.154652)
			(xy 382.067519 -398.154226) (xy 382.020757 -398.146913) (xy 381.975682 -398.132479) (xy 381.933369 -398.111271)
			(xy 381.894832 -398.083794) (xy 381.860989 -398.050706) (xy 381.832652 -398.012796) (xy 381.821182 -397.992092)
			(xy 381.820928 -397.99133) (xy 381.423672 -397.304006) (xy 381.411495 -397.280788) (xy 381.394379 -397.231238)
			(xy 381.389636 -397.205454) (xy 381.389636 -397.2052) (xy 381.386138 -397.181397) (xy 381.385926 -397.133286)
			(xy 380.830217 -397.133286) (xy 381.155956 -397.696944) (xy 381.15621 -397.697452) (xy 381.156464 -397.697452)
			(xy 381.157734 -397.699992) (xy 381.169968 -397.722915) (xy 381.187288 -397.771902) (xy 381.196075 -397.823111)
			(xy 381.196596 -397.84909) (xy 381.196596 -397.849344) (xy 381.196178 -397.873337) (xy 381.188665 -397.920731)
			(xy 381.173831 -397.966367) (xy 381.152041 -398.009121) (xy 381.123831 -398.047939) (xy 381.089897 -398.081868)
			(xy 381.051073 -398.11007) (xy 381.008315 -398.131852) (xy 380.962677 -398.146678) (xy 380.915281 -398.154182)
			(xy 380.891288 -398.154652) (xy 380.867623 -398.154222) (xy 380.820862 -398.14691) (xy 380.775786 -398.132477)
			(xy 380.733474 -398.111269) (xy 380.694936 -398.083793) (xy 380.661094 -398.050705) (xy 380.632756 -398.012796)
			(xy 380.621286 -397.992092) (xy 380.621032 -397.99133) (xy 380.223776 -397.304006) (xy 380.211599 -397.280788)
			(xy 380.194483 -397.231238) (xy 380.18974 -397.205454) (xy 380.18974 -397.2052) (xy 380.186234 -397.181398)
			(xy 380.186022 -397.133286) (xy 379.630067 -397.133286) (xy 379.955806 -397.696944) (xy 379.95606 -397.697452)
			(xy 379.956314 -397.697452) (xy 379.957584 -397.699992) (xy 379.969854 -397.722909) (xy 379.987261 -397.771886)
			(xy 379.996136 -397.823101) (xy 379.9967 -397.84909) (xy 379.9967 -397.849344) (xy 379.996279 -397.873324)
			(xy 379.988774 -397.920694) (xy 379.973956 -397.966307) (xy 379.952188 -398.009044) (xy 379.924007 -398.047851)
			(xy 379.890105 -398.081775) (xy 379.851316 -398.109982) (xy 379.808594 -398.131778) (xy 379.76299 -398.146627)
			(xy 379.715626 -398.154163) (xy 379.691646 -398.154652) (xy 379.691138 -398.154652) (xy 379.667475 -398.154182)
			(xy 379.620715 -398.146877) (xy 379.57564 -398.132452) (xy 379.533328 -398.111251) (xy 379.494789 -398.08378)
			(xy 379.460946 -398.050698) (xy 379.432607 -398.012794) (xy 379.421136 -397.992092) (xy 379.420882 -397.99133)
			(xy 379.023626 -397.304006) (xy 379.011446 -397.28079) (xy 378.994332 -397.231239) (xy 378.98959 -397.205454)
			(xy 378.98959 -397.2052) (xy 378.986178 -397.181387) (xy 378.985967 -397.133284) (xy 378.430169 -397.133284)
			(xy 378.75591 -397.696944) (xy 378.756164 -397.697452) (xy 378.756418 -397.697452) (xy 378.757688 -397.699992)
			(xy 378.769958 -397.722908) (xy 378.787365 -397.771886) (xy 378.79624 -397.823101) (xy 378.796804 -397.84909)
			(xy 378.796804 -397.849344) (xy 378.796379 -397.873324) (xy 378.788874 -397.920693) (xy 378.774056 -397.966307)
			(xy 378.752289 -398.009042) (xy 378.724108 -398.04785) (xy 378.690206 -398.081774) (xy 378.651418 -398.109981)
			(xy 378.608697 -398.131777) (xy 378.563094 -398.146626) (xy 378.51573 -398.154163) (xy 378.49175 -398.154652)
			(xy 378.491242 -398.154652) (xy 378.467579 -398.154179) (xy 378.420819 -398.146875) (xy 378.375745 -398.13245)
			(xy 378.333432 -398.111249) (xy 378.294894 -398.083779) (xy 378.26105 -398.050697) (xy 378.232711 -398.012794)
			(xy 378.22124 -397.992092) (xy 378.220986 -397.99133) (xy 377.82373 -397.304006) (xy 377.81155 -397.28079)
			(xy 377.794436 -397.231239) (xy 377.789694 -397.205454) (xy 377.789694 -397.2052) (xy 377.786274 -397.181388)
			(xy 377.786064 -397.133284) (xy 377.230273 -397.133284) (xy 377.556014 -397.696944) (xy 377.556268 -397.697452)
			(xy 377.556522 -397.697452) (xy 377.557792 -397.699992) (xy 377.570062 -397.722908) (xy 377.587469 -397.771886)
			(xy 377.596344 -397.823101) (xy 377.596908 -397.84909) (xy 377.596908 -397.849344) (xy 377.596479 -397.873324)
			(xy 377.588974 -397.920693) (xy 377.574156 -397.966306) (xy 377.552389 -398.009041) (xy 377.524209 -398.047848)
			(xy 377.490308 -398.081772) (xy 377.45152 -398.10998) (xy 377.4088 -398.131776) (xy 377.363197 -398.146625)
			(xy 377.315833 -398.154162) (xy 377.291854 -398.154652) (xy 377.291346 -398.154652) (xy 377.267683 -398.154176)
			(xy 377.220924 -398.146872) (xy 377.175849 -398.132448) (xy 377.133537 -398.111248) (xy 377.094998 -398.083778)
			(xy 377.061154 -398.050697) (xy 377.032815 -398.012794) (xy 377.021344 -397.992092) (xy 377.02109 -397.99133)
			(xy 376.623834 -397.304006) (xy 376.611654 -397.28079) (xy 376.59454 -397.231239) (xy 376.589798 -397.205454)
			(xy 376.589798 -397.2052) (xy 376.586371 -397.181389) (xy 376.58616 -397.133284) (xy 376.030123 -397.133284)
			(xy 376.355864 -397.696944) (xy 376.356118 -397.697452) (xy 376.356372 -397.697452) (xy 376.357642 -397.699992)
			(xy 376.369877 -397.722915) (xy 376.387196 -397.771902) (xy 376.395983 -397.823111) (xy 376.396504 -397.84909)
			(xy 376.396504 -397.849344) (xy 376.396078 -397.873337) (xy 376.388565 -397.92073) (xy 376.373731 -397.966365)
			(xy 376.351942 -398.009118) (xy 376.323733 -398.047937) (xy 376.2898 -398.081865) (xy 376.250977 -398.110067)
			(xy 376.208221 -398.13185) (xy 376.162583 -398.146676) (xy 376.115189 -398.154182) (xy 376.091196 -398.154652)
			(xy 376.067531 -398.154216) (xy 376.02077 -398.146905) (xy 375.975695 -398.132473) (xy 375.933382 -398.111266)
			(xy 375.894844 -398.083791) (xy 375.861002 -398.050704) (xy 375.832664 -398.012796) (xy 375.821194 -397.992092)
			(xy 375.82094 -397.99133) (xy 375.423684 -397.304006) (xy 375.411508 -397.280788) (xy 375.394391 -397.231238)
			(xy 375.389648 -397.205454) (xy 375.389648 -397.2052) (xy 375.386127 -397.181399) (xy 375.385915 -397.133286)
			(xy 374.830229 -397.133286) (xy 375.155968 -397.696944) (xy 375.156222 -397.697452) (xy 375.156476 -397.697452)
			(xy 375.157746 -397.699992) (xy 375.169981 -397.722915) (xy 375.1873 -397.771902) (xy 375.196087 -397.823111)
			(xy 375.196608 -397.84909) (xy 375.196608 -397.849344) (xy 375.196178 -397.873336) (xy 375.188665 -397.92073)
			(xy 375.173832 -397.966364) (xy 375.152043 -398.009117) (xy 375.123835 -398.047935) (xy 375.089902 -398.081863)
			(xy 375.051079 -398.110066) (xy 375.008324 -398.131849) (xy 374.962687 -398.146676) (xy 374.915292 -398.154181)
			(xy 374.8913 -398.154652) (xy 374.867636 -398.154213) (xy 374.820875 -398.146902) (xy 374.775799 -398.132471)
			(xy 374.733487 -398.111265) (xy 374.694949 -398.08379) (xy 374.661106 -398.050703) (xy 374.632768 -398.012796)
			(xy 374.621298 -397.992092) (xy 374.621044 -397.99133) (xy 374.223788 -397.304006) (xy 374.211612 -397.280788)
			(xy 374.194495 -397.231238) (xy 374.189752 -397.205454) (xy 374.189752 -397.2052) (xy 374.186223 -397.1814)
			(xy 374.186012 -397.133286) (xy 373.630079 -397.133286) (xy 373.955818 -397.696944) (xy 373.956072 -397.697452)
			(xy 373.956326 -397.697452) (xy 373.957596 -397.699992) (xy 373.969867 -397.722908) (xy 373.987274 -397.771886)
			(xy 373.996148 -397.823101) (xy 373.996712 -397.84909) (xy 373.996712 -397.849344) (xy 373.996279 -397.873324)
			(xy 373.988774 -397.920692) (xy 373.973957 -397.966305) (xy 373.95219 -398.00904) (xy 373.92401 -398.047847)
			(xy 373.89011 -398.081771) (xy 373.851323 -398.109978) (xy 373.808603 -398.131775) (xy 373.763 -398.146624)
			(xy 373.715637 -398.154162) (xy 373.691658 -398.154652) (xy 373.69115 -398.154652) (xy 373.667487 -398.154172)
			(xy 373.620728 -398.146869) (xy 373.575653 -398.132446) (xy 373.533341 -398.111246) (xy 373.494802 -398.083777)
			(xy 373.460959 -398.050696) (xy 373.432619 -398.012793) (xy 373.421148 -397.992092) (xy 373.420894 -397.99133)
			(xy 373.023638 -397.304006) (xy 373.011458 -397.28079) (xy 372.994344 -397.231239) (xy 372.989602 -397.205454)
			(xy 372.989602 -397.2052) (xy 372.986167 -397.181389) (xy 372.985956 -397.133284) (xy 372.430181 -397.133284)
			(xy 372.755922 -397.696944) (xy 372.756176 -397.697452) (xy 372.75643 -397.697452) (xy 372.7577 -397.699992)
			(xy 372.769971 -397.722908) (xy 372.787378 -397.771886) (xy 372.796252 -397.823101) (xy 372.796816 -397.84909)
			(xy 372.796816 -397.849344) (xy 372.796379 -397.873323) (xy 372.788875 -397.920691) (xy 372.774057 -397.966304)
			(xy 372.752291 -398.009039) (xy 372.724111 -398.047846) (xy 372.690212 -398.08177) (xy 372.651425 -398.109977)
			(xy 372.608705 -398.131773) (xy 372.563104 -398.146624) (xy 372.515741 -398.154162) (xy 372.491762 -398.154652)
			(xy 372.491254 -398.154652) (xy 372.467591 -398.154169) (xy 372.420832 -398.146867) (xy 372.375758 -398.132444)
			(xy 372.333445 -398.111245) (xy 372.294907 -398.083776) (xy 372.261063 -398.050696) (xy 372.232723 -398.012793)
			(xy 372.221252 -397.992092) (xy 372.220998 -397.99133) (xy 371.823742 -397.304006) (xy 371.811563 -397.280789)
			(xy 371.794448 -397.231239) (xy 371.789706 -397.205454) (xy 371.789706 -397.2052) (xy 371.786264 -397.18139)
			(xy 371.786053 -397.133284) (xy 371.230285 -397.133284) (xy 371.556026 -397.696944) (xy 371.55628 -397.697452)
			(xy 371.556534 -397.697452) (xy 371.557804 -397.699992) (xy 371.570075 -397.722908) (xy 371.587482 -397.771886)
			(xy 371.596356 -397.823101) (xy 371.59692 -397.84909) (xy 371.59692 -397.849344) (xy 371.596479 -397.873323)
			(xy 371.588975 -397.920691) (xy 371.574157 -397.966303) (xy 371.552392 -398.009038) (xy 371.524213 -398.047844)
			(xy 371.490313 -398.081768) (xy 371.451527 -398.109975) (xy 371.408808 -398.131772) (xy 371.363207 -398.146623)
			(xy 371.315845 -398.154162) (xy 371.291866 -398.154652) (xy 371.291358 -398.154652) (xy 371.267695 -398.154166)
			(xy 371.220936 -398.146864) (xy 371.175862 -398.132442) (xy 371.13355 -398.111243) (xy 371.095011 -398.083775)
			(xy 371.061167 -398.050695) (xy 371.032827 -398.012793) (xy 371.021356 -397.992092) (xy 371.021102 -397.99133)
			(xy 370.623846 -397.304006) (xy 370.611667 -397.280789) (xy 370.594552 -397.231239) (xy 370.58981 -397.205454)
			(xy 370.58981 -397.2052) (xy 370.58636 -397.181391) (xy 370.586149 -397.133284) (xy 354.657801 -397.133284)
			(xy 354.983542 -397.696944) (xy 354.983796 -397.697452) (xy 354.98405 -397.697452) (xy 354.98532 -397.699992)
			(xy 354.997593 -397.722907) (xy 355.014998 -397.771885) (xy 355.023872 -397.823101) (xy 355.024436 -397.84909)
			(xy 355.024436 -397.849344) (xy 355.023979 -397.873322) (xy 355.016475 -397.920688) (xy 355.001659 -397.966299)
			(xy 354.979895 -398.009033) (xy 354.951717 -398.047839) (xy 354.91782 -398.081762) (xy 354.879036 -398.10997)
			(xy 354.836319 -398.131768) (xy 354.79072 -398.14662) (xy 354.74336 -398.15416) (xy 354.719382 -398.154652)
			(xy 354.718874 -398.154652) (xy 354.695212 -398.154153) (xy 354.648453 -398.146854) (xy 354.603379 -398.132433)
			(xy 354.561067 -398.111237) (xy 354.522528 -398.083771) (xy 354.488684 -398.050693) (xy 354.460343 -398.012792)
			(xy 354.448872 -397.992092) (xy 354.448618 -397.99133) (xy 354.051362 -397.304006) (xy 354.039184 -397.280789)
			(xy 354.022068 -397.231239) (xy 354.017326 -397.205454) (xy 354.017326 -397.2052) (xy 354.013846 -397.181395)
			(xy 354.013635 -397.133285) (xy 353.457652 -397.133285) (xy 353.783392 -397.696944) (xy 353.783646 -397.697452)
			(xy 353.7839 -397.697452) (xy 353.78517 -397.699992) (xy 353.797399 -397.722918) (xy 353.814722 -397.771903)
			(xy 353.82351 -397.823111) (xy 353.824032 -397.84909) (xy 353.824032 -397.849344) (xy 353.823578 -397.873335)
			(xy 353.816066 -397.920726) (xy 353.801234 -397.966359) (xy 353.779447 -398.00911) (xy 353.751242 -398.047927)
			(xy 353.717312 -398.081855) (xy 353.678493 -398.110058) (xy 353.63574 -398.131842) (xy 353.590107 -398.146671)
			(xy 353.542715 -398.15418) (xy 353.518724 -398.154652) (xy 353.49506 -398.154193) (xy 353.4483 -398.146886)
			(xy 353.403225 -398.132459) (xy 353.360913 -398.111256) (xy 353.322374 -398.083784) (xy 353.288531 -398.0507)
			(xy 353.260193 -398.012795) (xy 353.248722 -397.992092) (xy 353.248468 -397.99133) (xy 352.851212 -397.304006)
			(xy 352.839031 -397.28079) (xy 352.821918 -397.231239) (xy 352.817176 -397.205454) (xy 352.817176 -397.2052)
			(xy 352.813621 -397.179976) (xy 352.284739 -397.179976) (xy 352.583496 -397.696944) (xy 352.58375 -397.697452)
			(xy 352.584004 -397.697452) (xy 352.585274 -397.699992) (xy 352.597504 -397.722918) (xy 352.614826 -397.771903)
			(xy 352.623614 -397.823111) (xy 352.624136 -397.84909) (xy 352.624136 -397.849344) (xy 352.623678 -397.873335)
			(xy 352.616166 -397.920726) (xy 352.601335 -397.966358) (xy 352.579548 -398.009109) (xy 352.551343 -398.047926)
			(xy 352.517413 -398.081853) (xy 352.478595 -398.110056) (xy 352.435843 -398.131841) (xy 352.39021 -398.14667)
			(xy 352.342819 -398.154179) (xy 352.318828 -398.154652) (xy 352.295164 -398.15419) (xy 352.248404 -398.146884)
			(xy 352.203329 -398.132457) (xy 352.161017 -398.111254) (xy 352.122479 -398.083783) (xy 352.088636 -398.050699)
			(xy 352.060297 -398.012794) (xy 352.048826 -397.992092) (xy 352.048572 -397.99133) (xy 351.651316 -397.304006)
			(xy 351.639135 -397.28079) (xy 351.622022 -397.231239) (xy 351.61728 -397.205454) (xy 351.61728 -397.2052)
			(xy 351.613718 -397.179977) (xy 351.084589 -397.179977) (xy 351.383346 -397.696944) (xy 351.3836 -397.697452)
			(xy 351.383854 -397.697452) (xy 351.385124 -397.699992) (xy 351.397397 -397.722907) (xy 351.414802 -397.771885)
			(xy 351.423676 -397.823101) (xy 351.42424 -397.84909) (xy 351.42424 -397.849344) (xy 351.423779 -397.873322)
			(xy 351.416275 -397.920688) (xy 351.401459 -397.966298) (xy 351.379695 -398.009032) (xy 351.351518 -398.047837)
			(xy 351.317622 -398.081761) (xy 351.278838 -398.109969) (xy 351.236122 -398.131767) (xy 351.190524 -398.146619)
			(xy 351.143164 -398.15416) (xy 351.119186 -398.154652) (xy 351.118678 -398.154652) (xy 351.095013 -398.15423)
			(xy 351.048251 -398.146916) (xy 351.003175 -398.132482) (xy 350.960863 -398.111273) (xy 350.922325 -398.083796)
			(xy 350.888483 -398.050707) (xy 350.860146 -398.012797) (xy 350.848676 -397.992092) (xy 350.848422 -397.99133)
			(xy 350.451166 -397.304006) (xy 350.438988 -397.280789) (xy 350.421872 -397.231239) (xy 350.41713 -397.205454)
			(xy 350.41713 -397.2052) (xy 350.413643 -397.181396) (xy 350.413431 -397.133285) (xy 349.85771 -397.133285)
			(xy 350.18345 -397.696944) (xy 350.183704 -397.697452) (xy 350.183958 -397.697452) (xy 350.185228 -397.699992)
			(xy 350.197501 -397.722907) (xy 350.214906 -397.771885) (xy 350.22378 -397.823101) (xy 350.224344 -397.84909)
			(xy 350.224344 -397.849344) (xy 350.223879 -397.873322) (xy 350.216376 -397.920687) (xy 350.20156 -397.966297)
			(xy 350.179796 -398.00903) (xy 350.15162 -398.047836) (xy 350.117723 -398.08176) (xy 350.07894 -398.109967)
			(xy 350.036225 -398.131765) (xy 349.990627 -398.146618) (xy 349.943268 -398.15416) (xy 349.91929 -398.154652)
			(xy 349.918782 -398.154652) (xy 349.895117 -398.154227) (xy 349.848355 -398.146914) (xy 349.80328 -398.13248)
			(xy 349.760967 -398.111272) (xy 349.722429 -398.083795) (xy 349.688587 -398.050706) (xy 349.66025 -398.012797)
			(xy 349.64878 -397.992092) (xy 349.648526 -397.99133) (xy 349.25127 -397.304006) (xy 349.239093 -397.280789)
			(xy 349.221977 -397.231238) (xy 349.217234 -397.205454) (xy 349.217234 -397.2052) (xy 349.213739 -397.181396)
			(xy 349.213528 -397.133285) (xy 348.657814 -397.133285) (xy 348.983554 -397.696944) (xy 348.983808 -397.697452)
			(xy 348.984062 -397.697452) (xy 348.985332 -397.699992) (xy 348.997606 -397.722907) (xy 349.015011 -397.771885)
			(xy 349.023884 -397.823101) (xy 349.024448 -397.84909) (xy 349.024448 -397.849344) (xy 349.023979 -397.873322)
			(xy 349.016476 -397.920687) (xy 349.00166 -397.966296) (xy 348.979897 -398.009029) (xy 348.951721 -398.047835)
			(xy 348.917825 -398.081758) (xy 348.879043 -398.109966) (xy 348.836328 -398.131764) (xy 348.79073 -398.146617)
			(xy 348.743371 -398.154159) (xy 348.719394 -398.154652) (xy 348.718886 -398.154652) (xy 348.695221 -398.154224)
			(xy 348.64846 -398.146911) (xy 348.603384 -398.132478) (xy 348.561072 -398.11127) (xy 348.522534 -398.083794)
			(xy 348.488692 -398.050705) (xy 348.460354 -398.012796) (xy 348.448884 -397.992092) (xy 348.44863 -397.99133)
			(xy 348.051374 -397.304006) (xy 348.039197 -397.280788) (xy 348.022081 -397.231238) (xy 348.017338 -397.205454)
			(xy 348.017338 -397.2052) (xy 348.013836 -397.181397) (xy 348.013624 -397.133286) (xy 347.457665 -397.133286)
			(xy 347.783404 -397.696944) (xy 347.783658 -397.697452) (xy 347.783912 -397.697452) (xy 347.785182 -397.699992)
			(xy 347.797412 -397.722918) (xy 347.814734 -397.771903) (xy 347.823522 -397.823111) (xy 347.824044 -397.84909)
			(xy 347.824044 -397.849344) (xy 347.823578 -397.873335) (xy 347.816067 -397.920724) (xy 347.801235 -397.966356)
			(xy 347.779449 -398.009106) (xy 347.751245 -398.047923) (xy 347.717317 -398.08185) (xy 347.678499 -398.110054)
			(xy 347.635749 -398.131838) (xy 347.590117 -398.146668) (xy 347.542727 -398.154179) (xy 347.518736 -398.154652)
			(xy 347.495073 -398.154184) (xy 347.448313 -398.146878) (xy 347.403238 -398.132453) (xy 347.360926 -398.111251)
			(xy 347.322387 -398.083781) (xy 347.288544 -398.050698) (xy 347.260205 -398.012794) (xy 347.248734 -397.992092)
			(xy 347.24848 -397.99133) (xy 346.851224 -397.304006) (xy 346.839044 -397.28079) (xy 346.82193 -397.231239)
			(xy 346.817188 -397.205454) (xy 346.817188 -397.2052) (xy 346.813611 -397.179979) (xy 346.284753 -397.179979)
			(xy 346.583508 -397.696944) (xy 346.583762 -397.697452) (xy 346.584016 -397.697452) (xy 346.585286 -397.699992)
			(xy 346.597517 -397.722917) (xy 346.614838 -397.771902) (xy 346.623626 -397.823111) (xy 346.624148 -397.84909)
			(xy 346.624148 -397.849344) (xy 346.623678 -397.873334) (xy 346.616167 -397.920724) (xy 346.601336 -397.966355)
			(xy 346.57955 -398.009105) (xy 346.551346 -398.047922) (xy 346.517418 -398.081849) (xy 346.478602 -398.110052)
			(xy 346.435851 -398.131837) (xy 346.39022 -398.146668) (xy 346.34283 -398.154178) (xy 346.31884 -398.154652)
			(xy 346.295177 -398.15418) (xy 346.248417 -398.146876) (xy 346.203342 -398.132451) (xy 346.16103 -398.11125)
			(xy 346.122492 -398.08378) (xy 346.088648 -398.050698) (xy 346.060309 -398.012794) (xy 346.048838 -397.992092)
			(xy 346.048584 -397.99133) (xy 345.651328 -397.304006) (xy 345.639148 -397.28079) (xy 345.622034 -397.231239)
			(xy 345.617292 -397.205454) (xy 345.617292 -397.2052) (xy 345.613876 -397.181387) (xy 345.613665 -397.133284)
			(xy 345.057617 -397.133284) (xy 345.383358 -397.696944) (xy 345.383612 -397.697452) (xy 345.383866 -397.697452)
			(xy 345.385136 -397.699992) (xy 345.39741 -397.722906) (xy 345.414815 -397.771885) (xy 345.423688 -397.823101)
			(xy 345.424252 -397.84909) (xy 345.424252 -397.849344) (xy 345.423779 -397.873322) (xy 345.416276 -397.920686)
			(xy 345.401461 -397.966295) (xy 345.379698 -398.009028) (xy 345.351522 -398.047833) (xy 345.317627 -398.081757)
			(xy 345.278845 -398.109965) (xy 345.23613 -398.131763) (xy 345.190533 -398.146616) (xy 345.143175 -398.154159)
			(xy 345.119198 -398.154652) (xy 345.11869 -398.154652) (xy 345.095025 -398.154221) (xy 345.048264 -398.146909)
			(xy 345.003188 -398.132476) (xy 344.960876 -398.111269) (xy 344.922338 -398.083793) (xy 344.888496 -398.050705)
			(xy 344.860158 -398.012796) (xy 344.848688 -397.992092) (xy 344.848434 -397.99133) (xy 344.451178 -397.304006)
			(xy 344.439001 -397.280788) (xy 344.421885 -397.231238) (xy 344.417142 -397.205454) (xy 344.417142 -397.2052)
			(xy 344.413632 -397.181398) (xy 344.413421 -397.133286) (xy 343.857723 -397.133286) (xy 344.183462 -397.696944)
			(xy 344.183716 -397.697452) (xy 344.18397 -397.697452) (xy 344.18524 -397.699992) (xy 344.197514 -397.722906)
			(xy 344.214919 -397.771885) (xy 344.223792 -397.823101) (xy 344.224356 -397.84909) (xy 344.224356 -397.849344)
			(xy 344.223879 -397.873321) (xy 344.216376 -397.920686) (xy 344.201561 -397.966295) (xy 344.179798 -398.009027)
			(xy 344.151623 -398.047832) (xy 344.117728 -398.081755) (xy 344.078947 -398.109963) (xy 344.036233 -398.131762)
			(xy 343.990637 -398.146616) (xy 343.943279 -398.154159) (xy 343.919302 -398.154652) (xy 343.918794 -398.154652)
			(xy 343.895129 -398.154217) (xy 343.848368 -398.146906) (xy 343.803293 -398.132474) (xy 343.76098 -398.111267)
			(xy 343.722442 -398.083792) (xy 343.6886 -398.050704) (xy 343.660262 -398.012796) (xy 343.648792 -397.992092)
			(xy 343.648538 -397.99133) (xy 343.251282 -397.304006) (xy 343.239105 -397.280788) (xy 343.221989 -397.231238)
			(xy 343.217246 -397.205454) (xy 343.217246 -397.2052) (xy 343.213729 -397.181399) (xy 343.213517 -397.133286)
			(xy 342.657827 -397.133286) (xy 342.983566 -397.696944) (xy 342.98382 -397.697452) (xy 342.984074 -397.697452)
			(xy 342.985344 -397.699992) (xy 342.997619 -397.722906) (xy 343.015023 -397.771885) (xy 343.023896 -397.823101)
			(xy 343.02446 -397.84909) (xy 343.02446 -397.849344) (xy 343.024079 -397.873326) (xy 343.016573 -397.9207)
			(xy 343.001752 -397.966317) (xy 342.979981 -398.009055) (xy 342.951795 -398.047865) (xy 342.917888 -398.08179)
			(xy 342.879094 -398.109996) (xy 342.836367 -398.13179) (xy 342.790757 -398.146635) (xy 342.743388 -398.154166)
			(xy 342.719406 -398.154652) (xy 342.718898 -398.154652) (xy 342.695234 -398.154214) (xy 342.648472 -398.146903)
			(xy 342.603397 -398.132472) (xy 342.561085 -398.111266) (xy 342.522547 -398.083791) (xy 342.488704 -398.050704)
			(xy 342.460366 -398.012796) (xy 342.448896 -397.992092) (xy 342.448642 -397.99133) (xy 342.051386 -397.304006)
			(xy 342.03921 -397.280788) (xy 342.022093 -397.231238) (xy 342.01735 -397.205454) (xy 342.01735 -397.2052)
			(xy 342.013825 -397.1814) (xy 342.013613 -397.133286) (xy 341.457677 -397.133286) (xy 341.783416 -397.696944)
			(xy 341.78367 -397.697452) (xy 341.783924 -397.697452) (xy 341.785194 -397.699992) (xy 341.797425 -397.722917)
			(xy 341.814746 -397.771902) (xy 341.823534 -397.823111) (xy 341.824056 -397.84909) (xy 341.824056 -397.849344)
			(xy 341.823578 -397.873334) (xy 341.816067 -397.920723) (xy 341.801236 -397.966353) (xy 341.779452 -398.009103)
			(xy 341.751249 -398.047919) (xy 341.717322 -398.081846) (xy 341.678506 -398.11005) (xy 341.635757 -398.131835)
			(xy 341.590127 -398.146666) (xy 341.542738 -398.154178) (xy 341.518748 -398.154652) (xy 341.495085 -398.154174)
			(xy 341.448326 -398.146871) (xy 341.403251 -398.132447) (xy 341.360939 -398.111247) (xy 341.3224 -398.083778)
			(xy 341.288557 -398.050697) (xy 341.260217 -398.012794) (xy 341.248746 -397.992092) (xy 341.248492 -397.99133)
			(xy 340.851236 -397.304006) (xy 340.839056 -397.28079) (xy 340.821942 -397.231239) (xy 340.8172 -397.205454)
			(xy 340.8172 -397.2052) (xy 340.813769 -397.181389) (xy 340.813558 -397.133284) (xy 340.257779 -397.133284)
			(xy 340.58352 -397.696944) (xy 340.583774 -397.697452) (xy 340.584028 -397.697452) (xy 340.585298 -397.699992)
			(xy 340.597529 -397.722917) (xy 340.61485 -397.771902) (xy 340.623638 -397.823111) (xy 340.62416 -397.84909)
			(xy 340.62416 -397.849344) (xy 340.623802 -397.873341) (xy 340.616287 -397.920742) (xy 340.60145 -397.966385)
			(xy 340.579655 -398.009144) (xy 340.551439 -398.047968) (xy 340.517498 -398.081899) (xy 340.478666 -398.110103)
			(xy 340.4359 -398.131885) (xy 340.390253 -398.146709) (xy 340.342849 -398.154209) (xy 340.318852 -398.154652)
			(xy 340.295189 -398.154171) (xy 340.24843 -398.146868) (xy 340.203356 -398.132445) (xy 340.161043 -398.111245)
			(xy 340.122505 -398.083777) (xy 340.088661 -398.050696) (xy 340.060321 -398.012793) (xy 340.04885 -397.992092)
			(xy 340.048596 -397.99133) (xy 339.65134 -397.304006) (xy 339.639161 -397.28079) (xy 339.622046 -397.231239)
			(xy 339.617304 -397.205454) (xy 339.617304 -397.2052) (xy 339.613866 -397.18139) (xy 339.613655 -397.133284)
			(xy 339.057629 -397.133284) (xy 339.38337 -397.696944) (xy 339.383624 -397.697452) (xy 339.383878 -397.697452)
			(xy 339.385148 -397.699992) (xy 339.397423 -397.722906) (xy 339.414827 -397.771885) (xy 339.4237 -397.823101)
			(xy 339.424264 -397.84909) (xy 339.424264 -397.849344) (xy 339.423879 -397.873326) (xy 339.416373 -397.920699)
			(xy 339.401552 -397.966316) (xy 339.379781 -398.009054) (xy 339.351596 -398.047863) (xy 339.31769 -398.081788)
			(xy 339.278896 -398.109994) (xy 339.236169 -398.131788) (xy 339.190561 -398.146634) (xy 339.143192 -398.154166)
			(xy 339.11921 -398.154652) (xy 339.118702 -398.154652) (xy 339.095038 -398.154211) (xy 339.048277 -398.146901)
			(xy 339.003201 -398.13247) (xy 338.960889 -398.111264) (xy 338.922351 -398.08379) (xy 338.888508 -398.050703)
			(xy 338.86017 -398.012796) (xy 338.8487 -397.992092) (xy 338.848446 -397.99133) (xy 338.45119 -397.304006)
			(xy 338.439014 -397.280788) (xy 338.421897 -397.231238) (xy 338.417154 -397.205454) (xy 338.417154 -397.2052)
			(xy 338.413622 -397.181401) (xy 338.41341 -397.133286) (xy 337.857735 -397.133286) (xy 338.183474 -397.696944)
			(xy 338.183728 -397.697452) (xy 338.183982 -397.697452) (xy 338.185252 -397.699992) (xy 338.197527 -397.722906)
			(xy 338.214931 -397.771885) (xy 338.223804 -397.823101) (xy 338.224368 -397.84909) (xy 338.224368 -397.849344)
			(xy 338.223979 -397.873326) (xy 338.216473 -397.920698) (xy 338.201652 -397.966315) (xy 338.179882 -398.009053)
			(xy 338.151697 -398.047862) (xy 338.117791 -398.081787) (xy 338.078998 -398.109993) (xy 338.036272 -398.131787)
			(xy 337.990664 -398.146633) (xy 337.943295 -398.154165) (xy 337.919314 -398.154652) (xy 337.918806 -398.154652)
			(xy 337.895142 -398.154208) (xy 337.848381 -398.146898) (xy 337.803306 -398.132468) (xy 337.760993 -398.111263)
			(xy 337.722455 -398.083789) (xy 337.688613 -398.050703) (xy 337.660274 -398.012795) (xy 337.648804 -397.992092)
			(xy 337.64855 -397.99133) (xy 337.251294 -397.304006) (xy 337.239112 -397.280791) (xy 337.221999 -397.231239)
			(xy 337.217258 -397.205454) (xy 337.217258 -397.2052) (xy 337.213718 -397.181402) (xy 337.213506 -397.133287)
			(xy 336.657839 -397.133287) (xy 336.983578 -397.696944) (xy 336.983832 -397.697452) (xy 336.984086 -397.697452)
			(xy 336.985356 -397.699992) (xy 336.997631 -397.722906) (xy 337.015035 -397.771885) (xy 337.023908 -397.823101)
			(xy 337.024472 -397.84909) (xy 337.024472 -397.849344) (xy 337.024079 -397.873326) (xy 337.016573 -397.920698)
			(xy 337.001753 -397.966314) (xy 336.979983 -398.009052) (xy 336.951799 -398.047861) (xy 336.917893 -398.081785)
			(xy 336.8791 -398.109992) (xy 336.836375 -398.131786) (xy 336.790767 -398.146632) (xy 336.743399 -398.154165)
			(xy 336.719418 -398.154652) (xy 336.71891 -398.154652) (xy 336.695246 -398.154205) (xy 336.648485 -398.146896)
			(xy 336.60341 -398.132466) (xy 336.561098 -398.111261) (xy 336.522559 -398.083788) (xy 336.488717 -398.050702)
			(xy 336.460378 -398.012795) (xy 336.448908 -397.992092) (xy 336.448654 -397.99133) (xy 336.051398 -397.304006)
			(xy 336.039216 -397.280791) (xy 336.022103 -397.231239) (xy 336.017362 -397.205454) (xy 336.017362 -397.2052)
			(xy 336.013815 -397.181402) (xy 336.013603 -397.133287) (xy 322.129999 -397.133287) (xy 322.455794 -397.696944)
			(xy 322.468605 -397.720283) (xy 322.486829 -397.770303) (xy 322.496095 -397.822726) (xy 322.496688 -397.849344)
			(xy 322.496279 -397.873325) (xy 322.488774 -397.920695) (xy 322.473954 -397.96631) (xy 322.452186 -398.009047)
			(xy 322.424003 -398.047855) (xy 322.3901 -398.08178) (xy 322.351309 -398.109986) (xy 322.308586 -398.131782)
			(xy 322.26298 -398.146629) (xy 322.215614 -398.154164) (xy 322.191634 -398.154652) (xy 322.191126 -398.154652)
			(xy 322.167554 -398.15421) (xy 322.120969 -398.146974) (xy 322.076053 -398.132654) (xy 322.033876 -398.111593)
			(xy 321.995443 -398.084292) (xy 321.961669 -398.051401) (xy 321.933359 -398.013704) (xy 321.921886 -397.993108)
			(xy 321.921378 -397.992346) (xy 321.523614 -397.304006) (xy 321.511735 -397.281331) (xy 321.494886 -397.232997)
			(xy 321.486314 -397.182533) (xy 321.485768 -397.15694) (xy 320.94352 -397.15694) (xy 321.255644 -397.696944)
			(xy 321.268362 -397.720269) (xy 321.286461 -397.770214) (xy 321.295683 -397.82253) (xy 321.296284 -397.84909)
			(xy 321.296284 -397.849344) (xy 321.295878 -397.873338) (xy 321.288364 -397.920733) (xy 321.27353 -397.96637)
			(xy 321.251738 -398.009124) (xy 321.223528 -398.047943) (xy 321.189592 -398.081872) (xy 321.150766 -398.110074)
			(xy 321.108007 -398.131856) (xy 321.062367 -398.14668) (xy 321.01497 -398.154183) (xy 320.990976 -398.154652)
			(xy 320.967403 -398.15425) (xy 320.920816 -398.147007) (xy 320.875899 -398.13268) (xy 320.833722 -398.111612)
			(xy 320.795289 -398.084305) (xy 320.761516 -398.051408) (xy 320.733208 -398.013706) (xy 320.721736 -397.993108)
			(xy 320.721228 -397.992346) (xy 320.323464 -397.304006) (xy 320.311554 -397.281335) (xy 320.294614 -397.233011)
			(xy 320.285952 -397.182542) (xy 320.285364 -397.15694) (xy 319.743624 -397.15694) (xy 320.055748 -397.696944)
			(xy 320.068467 -397.720269) (xy 320.086565 -397.770214) (xy 320.095787 -397.82253) (xy 320.096388 -397.84909)
			(xy 320.096388 -397.849344) (xy 320.095978 -397.873337) (xy 320.088465 -397.920733) (xy 320.07363 -397.966369)
			(xy 320.051839 -398.009123) (xy 320.023629 -398.047942) (xy 319.989693 -398.08187) (xy 319.950868 -398.110073)
			(xy 319.90811 -398.131854) (xy 319.86247 -398.14668) (xy 319.815074 -398.154183) (xy 319.79108 -398.154652)
			(xy 319.767507 -398.154247) (xy 319.72092 -398.147004) (xy 319.676003 -398.132678) (xy 319.633826 -398.111611)
			(xy 319.595393 -398.084304) (xy 319.561621 -398.051407) (xy 319.533312 -398.013706) (xy 319.52184 -397.993108)
			(xy 319.521332 -397.992346) (xy 319.123568 -397.304006) (xy 319.111658 -397.281335) (xy 319.094718 -397.233011)
			(xy 319.086056 -397.182542) (xy 319.085468 -397.15694) (xy 318.543474 -397.15694) (xy 318.855598 -397.696944)
			(xy 318.868401 -397.720288) (xy 318.88663 -397.770305) (xy 318.895899 -397.822727) (xy 318.896492 -397.849344)
			(xy 318.896079 -397.873325) (xy 318.888574 -397.920695) (xy 318.873755 -397.966309) (xy 318.851987 -398.009046)
			(xy 318.823804 -398.047854) (xy 318.789901 -398.081778) (xy 318.751112 -398.109985) (xy 318.708389 -398.13178)
			(xy 318.662784 -398.146628) (xy 318.615418 -398.154164) (xy 318.591438 -398.154652) (xy 318.59093 -398.154652)
			(xy 318.567358 -398.154207) (xy 318.520774 -398.146971) (xy 318.475858 -398.132652) (xy 318.43368 -398.111592)
			(xy 318.395247 -398.084291) (xy 318.361473 -398.0514) (xy 318.333163 -398.013704) (xy 318.32169 -397.993108)
			(xy 318.321182 -397.992346) (xy 317.923418 -397.304006) (xy 317.911539 -397.281331) (xy 317.89469 -397.232997)
			(xy 317.886118 -397.182533) (xy 317.885572 -397.15694) (xy 317.343578 -397.15694) (xy 317.655702 -397.696944)
			(xy 317.668505 -397.720288) (xy 317.686734 -397.770305) (xy 317.696003 -397.822727) (xy 317.696596 -397.849344)
			(xy 317.696179 -397.873324) (xy 317.688674 -397.920694) (xy 317.673855 -397.966308) (xy 317.652087 -398.009045)
			(xy 317.623906 -398.047852) (xy 317.590003 -398.081777) (xy 317.551214 -398.109984) (xy 317.508492 -398.131779)
			(xy 317.462887 -398.146628) (xy 317.415522 -398.154163) (xy 317.391542 -398.154652) (xy 317.391034 -398.154652)
			(xy 317.367462 -398.154203) (xy 317.320878 -398.146969) (xy 317.275962 -398.13265) (xy 317.233785 -398.11159)
			(xy 317.195351 -398.08429) (xy 317.161577 -398.0514) (xy 317.133267 -398.013703) (xy 317.121794 -397.993108)
			(xy 317.121286 -397.992346) (xy 316.723522 -397.304006) (xy 316.711643 -397.281331) (xy 316.694794 -397.232996)
			(xy 316.686222 -397.182533) (xy 316.685676 -397.15694) (xy 316.143682 -397.15694) (xy 316.455806 -397.696944)
			(xy 316.46861 -397.720287) (xy 316.486838 -397.770304) (xy 316.496107 -397.822727) (xy 316.4967 -397.849344)
			(xy 316.496279 -397.873324) (xy 316.488774 -397.920694) (xy 316.473956 -397.966307) (xy 316.452188 -398.009044)
			(xy 316.424007 -398.047851) (xy 316.390105 -398.081775) (xy 316.351316 -398.109982) (xy 316.308594 -398.131778)
			(xy 316.26299 -398.146627) (xy 316.215626 -398.154163) (xy 316.191646 -398.154652) (xy 316.191138 -398.154652)
			(xy 316.167566 -398.1542) (xy 316.120982 -398.146966) (xy 316.076066 -398.132648) (xy 316.033889 -398.111589)
			(xy 315.995456 -398.084289) (xy 315.961681 -398.051399) (xy 315.933371 -398.013703) (xy 315.921898 -397.993108)
			(xy 315.92139 -397.992346) (xy 315.523626 -397.304006) (xy 315.511747 -397.28133) (xy 315.494898 -397.232996)
			(xy 315.486326 -397.182533) (xy 315.48578 -397.15694) (xy 314.943532 -397.15694) (xy 315.255656 -397.696944)
			(xy 315.268375 -397.720269) (xy 315.286473 -397.770214) (xy 315.295695 -397.822529) (xy 315.296296 -397.84909)
			(xy 315.296296 -397.849344) (xy 315.295878 -397.873337) (xy 315.288365 -397.920731) (xy 315.273531 -397.966367)
			(xy 315.251741 -398.009121) (xy 315.223531 -398.047939) (xy 315.189597 -398.081868) (xy 315.150773 -398.11007)
			(xy 315.108015 -398.131852) (xy 315.062377 -398.146678) (xy 315.014981 -398.154182) (xy 314.990988 -398.154652)
			(xy 314.967415 -398.154241) (xy 314.920829 -398.146999) (xy 314.875912 -398.132674) (xy 314.833735 -398.111608)
			(xy 314.795302 -398.084301) (xy 314.761529 -398.051406) (xy 314.733221 -398.013705) (xy 314.721748 -397.993108)
			(xy 314.72124 -397.992346) (xy 314.323476 -397.304006) (xy 314.311559 -397.281339) (xy 314.294623 -397.233013)
			(xy 314.285963 -397.182542) (xy 314.285376 -397.15694) (xy 313.743636 -397.15694) (xy 314.05576 -397.696944)
			(xy 314.06848 -397.720269) (xy 314.086577 -397.770214) (xy 314.095799 -397.822529) (xy 314.0964 -397.84909)
			(xy 314.0964 -397.849344) (xy 314.095978 -397.873337) (xy 314.088465 -397.920731) (xy 314.073631 -397.966366)
			(xy 314.051841 -398.009119) (xy 314.023632 -398.047938) (xy 313.989698 -398.081866) (xy 313.950875 -398.110069)
			(xy 313.908118 -398.131851) (xy 313.86248 -398.146677) (xy 313.815085 -398.154182) (xy 313.791092 -398.154652)
			(xy 313.767519 -398.154237) (xy 313.720933 -398.146996) (xy 313.676016 -398.132672) (xy 313.633839 -398.111606)
			(xy 313.595406 -398.0843) (xy 313.561633 -398.051406) (xy 313.533325 -398.013705) (xy 313.521852 -397.993108)
			(xy 313.521344 -397.992346) (xy 313.12358 -397.304006) (xy 313.111663 -397.281339) (xy 313.094727 -397.233013)
			(xy 313.086067 -397.182542) (xy 313.08548 -397.15694) (xy 312.543486 -397.15694) (xy 312.85561 -397.696944)
			(xy 312.868414 -397.720287) (xy 312.886643 -397.770304) (xy 312.895911 -397.822727) (xy 312.896504 -397.849344)
			(xy 312.896079 -397.873324) (xy 312.888574 -397.920693) (xy 312.873756 -397.966307) (xy 312.851989 -398.009042)
			(xy 312.823808 -398.04785) (xy 312.789906 -398.081774) (xy 312.751118 -398.109981) (xy 312.708397 -398.131777)
			(xy 312.662794 -398.146626) (xy 312.61543 -398.154163) (xy 312.59145 -398.154652) (xy 312.590942 -398.154652)
			(xy 312.567371 -398.154197) (xy 312.520786 -398.146963) (xy 312.475871 -398.132646) (xy 312.433693 -398.111587)
			(xy 312.39526 -398.084288) (xy 312.361486 -398.051398) (xy 312.333176 -398.013703) (xy 312.321702 -397.993108)
			(xy 312.321194 -397.992346) (xy 311.92343 -397.304006) (xy 311.911552 -397.28133) (xy 311.894702 -397.232996)
			(xy 311.88613 -397.182533) (xy 311.885584 -397.15694) (xy 311.34359 -397.15694) (xy 311.655714 -397.696944)
			(xy 311.668518 -397.720287) (xy 311.686747 -397.770304) (xy 311.696015 -397.822727) (xy 311.696608 -397.849344)
			(xy 311.696179 -397.873324) (xy 311.688674 -397.920693) (xy 311.673856 -397.966306) (xy 311.652089 -398.009041)
			(xy 311.623909 -398.047848) (xy 311.590008 -398.081772) (xy 311.55122 -398.10998) (xy 311.5085 -398.131776)
			(xy 311.462897 -398.146625) (xy 311.415533 -398.154162) (xy 311.391554 -398.154652) (xy 311.391046 -398.154652)
			(xy 311.367475 -398.154194) (xy 311.320891 -398.146961) (xy 311.275975 -398.132644) (xy 311.233798 -398.111586)
			(xy 311.195364 -398.084287) (xy 311.16159 -398.051398) (xy 311.13328 -398.013703) (xy 311.121806 -397.993108)
			(xy 311.121298 -397.992346) (xy 310.723534 -397.304006) (xy 310.711656 -397.28133) (xy 310.694806 -397.232996)
			(xy 310.686234 -397.182533) (xy 310.685688 -397.15694) (xy 310.143694 -397.15694) (xy 310.455818 -397.696944)
			(xy 310.468623 -397.720287) (xy 310.486851 -397.770304) (xy 310.496119 -397.822727) (xy 310.496712 -397.849344)
			(xy 310.496279 -397.873324) (xy 310.488774 -397.920692) (xy 310.473957 -397.966305) (xy 310.45219 -398.00904)
			(xy 310.42401 -398.047847) (xy 310.39011 -398.081771) (xy 310.351323 -398.109978) (xy 310.308603 -398.131775)
			(xy 310.263 -398.146624) (xy 310.215637 -398.154162) (xy 310.191658 -398.154652) (xy 310.19115 -398.154652)
			(xy 310.167579 -398.154191) (xy 310.120995 -398.146958) (xy 310.076079 -398.132642) (xy 310.033902 -398.111584)
			(xy 309.995468 -398.084286) (xy 309.961694 -398.051397) (xy 309.933384 -398.013703) (xy 309.92191 -397.993108)
			(xy 309.921402 -397.992346) (xy 309.523638 -397.304006) (xy 309.51176 -397.28133) (xy 309.494911 -397.232996)
			(xy 309.486338 -397.182533) (xy 309.485792 -397.15694) (xy 308.943544 -397.15694) (xy 309.255668 -397.696944)
			(xy 309.268388 -397.720268) (xy 309.286486 -397.770213) (xy 309.295708 -397.822529) (xy 309.296308 -397.84909)
			(xy 309.296308 -397.849344) (xy 309.295878 -397.873336) (xy 309.288365 -397.92073) (xy 309.273532 -397.966364)
			(xy 309.251743 -398.009117) (xy 309.223535 -398.047935) (xy 309.189602 -398.081863) (xy 309.150779 -398.110066)
			(xy 309.108024 -398.131849) (xy 309.062387 -398.146676) (xy 309.014992 -398.154181) (xy 308.991 -398.154652)
			(xy 308.967427 -398.154231) (xy 308.920842 -398.146991) (xy 308.875925 -398.132668) (xy 308.833748 -398.111603)
			(xy 308.795315 -398.084298) (xy 308.761542 -398.051404) (xy 308.733233 -398.013705) (xy 308.72176 -397.993108)
			(xy 308.721252 -397.992346) (xy 308.323488 -397.304006) (xy 308.311572 -397.281338) (xy 308.294635 -397.233013)
			(xy 308.285975 -397.182542) (xy 308.285388 -397.15694) (xy 307.743648 -397.15694) (xy 308.055772 -397.696944)
			(xy 308.068493 -397.720268) (xy 308.08659 -397.770213) (xy 308.095812 -397.822529) (xy 308.096412 -397.84909)
			(xy 308.096412 -397.849344) (xy 308.095978 -397.873336) (xy 308.088465 -397.920729) (xy 308.073632 -397.966363)
			(xy 308.051844 -398.009116) (xy 308.023636 -398.047934) (xy 307.989703 -398.081862) (xy 307.950882 -398.110065)
			(xy 307.908126 -398.131848) (xy 307.86249 -398.146675) (xy 307.815096 -398.154181) (xy 307.791104 -398.154652)
			(xy 307.767532 -398.154228) (xy 307.720946 -398.146988) (xy 307.676029 -398.132666) (xy 307.633852 -398.111602)
			(xy 307.595419 -398.084297) (xy 307.561646 -398.051404) (xy 307.533337 -398.013705) (xy 307.521864 -397.993108)
			(xy 307.521356 -397.992346) (xy 307.123592 -397.304006) (xy 307.111676 -397.281338) (xy 307.094739 -397.233012)
			(xy 307.086079 -397.182542) (xy 307.085492 -397.15694) (xy 306.543498 -397.15694) (xy 306.855622 -397.696944)
			(xy 306.868427 -397.720287) (xy 306.886655 -397.770304) (xy 306.895923 -397.822727) (xy 306.896516 -397.849344)
			(xy 306.896079 -397.873323) (xy 306.888575 -397.920691) (xy 306.873757 -397.966304) (xy 306.851991 -398.009039)
			(xy 306.823811 -398.047846) (xy 306.789912 -398.08177) (xy 306.751125 -398.109977) (xy 306.708405 -398.131773)
			(xy 306.662804 -398.146624) (xy 306.615441 -398.154162) (xy 306.591462 -398.154652) (xy 306.590954 -398.154652)
			(xy 306.567383 -398.154187) (xy 306.520799 -398.146955) (xy 306.475884 -398.13264) (xy 306.433706 -398.111583)
			(xy 306.395273 -398.084285) (xy 306.361498 -398.051397) (xy 306.333188 -398.013702) (xy 306.321714 -397.993108)
			(xy 306.321206 -397.992346) (xy 305.923442 -397.304006) (xy 305.911565 -397.28133) (xy 305.894715 -397.232996)
			(xy 305.886142 -397.182533) (xy 305.885596 -397.15694) (xy 305.343602 -397.15694) (xy 305.655726 -397.696944)
			(xy 305.668531 -397.720286) (xy 305.686759 -397.770304) (xy 305.696027 -397.822727) (xy 305.69662 -397.849344)
			(xy 305.696179 -397.873323) (xy 305.688675 -397.920691) (xy 305.673857 -397.966303) (xy 305.652092 -398.009038)
			(xy 305.623913 -398.047844) (xy 305.590013 -398.081768) (xy 305.551227 -398.109975) (xy 305.508508 -398.131772)
			(xy 305.462907 -398.146623) (xy 305.415545 -398.154162) (xy 305.391566 -398.154652) (xy 305.391058 -398.154652)
			(xy 305.367487 -398.154184) (xy 305.320904 -398.146953) (xy 305.275988 -398.132638) (xy 305.233811 -398.111581)
			(xy 305.195377 -398.084284) (xy 305.161602 -398.051396) (xy 305.133292 -398.013702) (xy 305.121818 -397.993108)
			(xy 305.12131 -397.992346) (xy 304.723546 -397.304006) (xy 304.711669 -397.28133) (xy 304.694819 -397.232996)
			(xy 304.686246 -397.182533) (xy 304.6857 -397.15694) (xy 304.143706 -397.15694) (xy 304.45583 -397.696944)
			(xy 304.468636 -397.720286) (xy 304.486863 -397.770304) (xy 304.496131 -397.822727) (xy 304.496724 -397.849344)
			(xy 304.496279 -397.873323) (xy 304.488775 -397.92069) (xy 304.473958 -397.966302) (xy 304.452192 -398.009036)
			(xy 304.424014 -398.047843) (xy 304.390115 -398.081767) (xy 304.351329 -398.109974) (xy 304.308611 -398.131771)
			(xy 304.26301 -398.146622) (xy 304.215649 -398.154161) (xy 304.19167 -398.154652) (xy 304.191162 -398.154652)
			(xy 304.167591 -398.154181) (xy 304.121008 -398.14695) (xy 304.076092 -398.132636) (xy 304.033915 -398.11158)
			(xy 303.995481 -398.084283) (xy 303.961707 -398.051396) (xy 303.933396 -398.013702) (xy 303.921922 -397.993108)
			(xy 303.921414 -397.992346) (xy 303.52365 -397.304006) (xy 303.511773 -397.281329) (xy 303.494923 -397.232996)
			(xy 303.48635 -397.182533) (xy 303.485804 -397.15694) (xy 280.68524 -397.15694) (xy 280.68524 -401.674838)
			(xy 303.434496 -401.674838) (xy 303.434496 -400.811238) (xy 303.434982 -400.783969) (xy 303.442744 -400.729985)
			(xy 303.458109 -400.677655) (xy 303.480766 -400.628045) (xy 303.510252 -400.582164) (xy 303.545967 -400.540947)
			(xy 303.587184 -400.505232) (xy 303.633065 -400.475746) (xy 303.682675 -400.453089) (xy 303.735005 -400.437724)
			(xy 303.788989 -400.429962) (xy 303.843527 -400.429962) (xy 303.897511 -400.437724) (xy 303.949841 -400.453089)
			(xy 303.999451 -400.475746) (xy 304.045332 -400.505232) (xy 304.086549 -400.540947) (xy 304.122264 -400.582164)
			(xy 304.15175 -400.628045) (xy 304.174407 -400.677655) (xy 304.189772 -400.729985) (xy 304.197534 -400.783969)
			(xy 304.19802 -400.811238) (xy 304.19802 -401.674838) (xy 304.634392 -401.674838) (xy 304.634392 -400.811238)
			(xy 304.634878 -400.783969) (xy 304.64264 -400.729985) (xy 304.658005 -400.677655) (xy 304.680662 -400.628045)
			(xy 304.710148 -400.582164) (xy 304.745863 -400.540947) (xy 304.78708 -400.505232) (xy 304.832961 -400.475746)
			(xy 304.882571 -400.453089) (xy 304.934901 -400.437724) (xy 304.988885 -400.429962) (xy 305.043423 -400.429962)
			(xy 305.097407 -400.437724) (xy 305.149737 -400.453089) (xy 305.199347 -400.475746) (xy 305.245228 -400.505232)
			(xy 305.286445 -400.540947) (xy 305.32216 -400.582164) (xy 305.351646 -400.628045) (xy 305.374303 -400.677655)
			(xy 305.389668 -400.729985) (xy 305.39743 -400.783969) (xy 305.397916 -400.811238) (xy 305.397916 -401.674838)
			(xy 305.834796 -401.674838) (xy 305.834796 -400.811238) (xy 305.835282 -400.783987) (xy 305.843038 -400.730039)
			(xy 305.858393 -400.677744) (xy 305.881035 -400.628167) (xy 305.910501 -400.582317) (xy 305.946192 -400.541126)
			(xy 305.987383 -400.505435) (xy 306.033233 -400.475969) (xy 306.08281 -400.453327) (xy 306.135105 -400.437972)
			(xy 306.189053 -400.430216) (xy 306.243555 -400.430216) (xy 306.297503 -400.437972) (xy 306.349798 -400.453327)
			(xy 306.399375 -400.475969) (xy 306.445225 -400.505435) (xy 306.486416 -400.541126) (xy 306.522107 -400.582317)
			(xy 306.551573 -400.628167) (xy 306.574215 -400.677744) (xy 306.58957 -400.730039) (xy 306.597326 -400.783987)
			(xy 306.597812 -400.811238) (xy 306.597812 -401.674838) (xy 307.034692 -401.674838) (xy 307.034692 -400.811238)
			(xy 307.035178 -400.783987) (xy 307.042934 -400.730039) (xy 307.058289 -400.677744) (xy 307.080931 -400.628167)
			(xy 307.110397 -400.582317) (xy 307.146088 -400.541126) (xy 307.187279 -400.505435) (xy 307.233129 -400.475969)
			(xy 307.282706 -400.453327) (xy 307.335001 -400.437972) (xy 307.388949 -400.430216) (xy 307.443451 -400.430216)
			(xy 307.497399 -400.437972) (xy 307.549694 -400.453327) (xy 307.599271 -400.475969) (xy 307.645121 -400.505435)
			(xy 307.686312 -400.541126) (xy 307.722003 -400.582317) (xy 307.751469 -400.628167) (xy 307.774111 -400.677744)
			(xy 307.789466 -400.730039) (xy 307.797222 -400.783987) (xy 307.797708 -400.811238) (xy 307.797708 -401.674838)
			(xy 308.234588 -401.674838) (xy 308.234588 -400.811238) (xy 308.235074 -400.783969) (xy 308.242836 -400.729985)
			(xy 308.258201 -400.677655) (xy 308.280858 -400.628045) (xy 308.310344 -400.582164) (xy 308.346059 -400.540947)
			(xy 308.387276 -400.505232) (xy 308.433157 -400.475746) (xy 308.482767 -400.453089) (xy 308.535097 -400.437724)
			(xy 308.589081 -400.429962) (xy 308.643619 -400.429962) (xy 308.697603 -400.437724) (xy 308.749933 -400.453089)
			(xy 308.799543 -400.475746) (xy 308.845424 -400.505232) (xy 308.886641 -400.540947) (xy 308.922356 -400.582164)
			(xy 308.951842 -400.628045) (xy 308.974499 -400.677655) (xy 308.989864 -400.729985) (xy 308.997626 -400.783969)
			(xy 308.998112 -400.811238) (xy 308.998112 -401.674838) (xy 309.434484 -401.674838) (xy 309.434484 -400.811238)
			(xy 309.43497 -400.783969) (xy 309.442732 -400.729985) (xy 309.458097 -400.677655) (xy 309.480754 -400.628045)
			(xy 309.51024 -400.582164) (xy 309.545955 -400.540947) (xy 309.587172 -400.505232) (xy 309.633053 -400.475746)
			(xy 309.682663 -400.453089) (xy 309.734993 -400.437724) (xy 309.788977 -400.429962) (xy 309.843515 -400.429962)
			(xy 309.897499 -400.437724) (xy 309.949829 -400.453089) (xy 309.999439 -400.475746) (xy 310.04532 -400.505232)
			(xy 310.086537 -400.540947) (xy 310.122252 -400.582164) (xy 310.151738 -400.628045) (xy 310.174395 -400.677655)
			(xy 310.18976 -400.729985) (xy 310.197522 -400.783969) (xy 310.198008 -400.811238) (xy 310.198008 -401.674838)
			(xy 310.634888 -401.674838) (xy 310.634888 -400.811238) (xy 310.635374 -400.783987) (xy 310.64313 -400.730039)
			(xy 310.658485 -400.677744) (xy 310.681127 -400.628167) (xy 310.710593 -400.582317) (xy 310.746284 -400.541126)
			(xy 310.787475 -400.505435) (xy 310.833325 -400.475969) (xy 310.882902 -400.453327) (xy 310.935197 -400.437972)
			(xy 310.989145 -400.430216) (xy 311.043647 -400.430216) (xy 311.097595 -400.437972) (xy 311.14989 -400.453327)
			(xy 311.199467 -400.475969) (xy 311.245317 -400.505435) (xy 311.286508 -400.541126) (xy 311.322199 -400.582317)
			(xy 311.351665 -400.628167) (xy 311.374307 -400.677744) (xy 311.389662 -400.730039) (xy 311.397418 -400.783987)
			(xy 311.397904 -400.811238) (xy 311.397904 -401.674838) (xy 311.834784 -401.674838) (xy 311.834784 -400.811238)
			(xy 311.83527 -400.783987) (xy 311.843026 -400.730039) (xy 311.858381 -400.677744) (xy 311.881023 -400.628167)
			(xy 311.910489 -400.582317) (xy 311.94618 -400.541126) (xy 311.987371 -400.505435) (xy 312.033221 -400.475969)
			(xy 312.082798 -400.453327) (xy 312.135093 -400.437972) (xy 312.189041 -400.430216) (xy 312.243543 -400.430216)
			(xy 312.297491 -400.437972) (xy 312.349786 -400.453327) (xy 312.399363 -400.475969) (xy 312.445213 -400.505435)
			(xy 312.486404 -400.541126) (xy 312.522095 -400.582317) (xy 312.551561 -400.628167) (xy 312.574203 -400.677744)
			(xy 312.589558 -400.730039) (xy 312.597314 -400.783987) (xy 312.5978 -400.811238) (xy 312.5978 -401.674838)
			(xy 313.03468 -401.674838) (xy 313.03468 -400.811238) (xy 313.035166 -400.783969) (xy 313.042928 -400.729985)
			(xy 313.058293 -400.677655) (xy 313.08095 -400.628045) (xy 313.110436 -400.582164) (xy 313.146151 -400.540947)
			(xy 313.187368 -400.505232) (xy 313.233249 -400.475746) (xy 313.282859 -400.453089) (xy 313.335189 -400.437724)
			(xy 313.389173 -400.429962) (xy 313.443711 -400.429962) (xy 313.497695 -400.437724) (xy 313.550025 -400.453089)
			(xy 313.599635 -400.475746) (xy 313.645516 -400.505232) (xy 313.686733 -400.540947) (xy 313.722448 -400.582164)
			(xy 313.751934 -400.628045) (xy 313.774591 -400.677655) (xy 313.789956 -400.729985) (xy 313.797718 -400.783969)
			(xy 313.798204 -400.811238) (xy 313.798204 -401.674838) (xy 314.234576 -401.674838) (xy 314.234576 -400.811238)
			(xy 314.235062 -400.783969) (xy 314.242824 -400.729985) (xy 314.258189 -400.677655) (xy 314.280846 -400.628045)
			(xy 314.310332 -400.582164) (xy 314.346047 -400.540947) (xy 314.387264 -400.505232) (xy 314.433145 -400.475746)
			(xy 314.482755 -400.453089) (xy 314.535085 -400.437724) (xy 314.589069 -400.429962) (xy 314.643607 -400.429962)
			(xy 314.697591 -400.437724) (xy 314.749921 -400.453089) (xy 314.799531 -400.475746) (xy 314.845412 -400.505232)
			(xy 314.886629 -400.540947) (xy 314.922344 -400.582164) (xy 314.95183 -400.628045) (xy 314.974487 -400.677655)
			(xy 314.989852 -400.729985) (xy 314.997614 -400.783969) (xy 314.9981 -400.811238) (xy 314.9981 -401.674838)
			(xy 315.43498 -401.674838) (xy 315.43498 -400.811238) (xy 315.435466 -400.783987) (xy 315.443222 -400.730039)
			(xy 315.458577 -400.677744) (xy 315.481219 -400.628167) (xy 315.510685 -400.582317) (xy 315.546376 -400.541126)
			(xy 315.587567 -400.505435) (xy 315.633417 -400.475969) (xy 315.682994 -400.453327) (xy 315.735289 -400.437972)
			(xy 315.789237 -400.430216) (xy 315.843739 -400.430216) (xy 315.897687 -400.437972) (xy 315.949982 -400.453327)
			(xy 315.999559 -400.475969) (xy 316.045409 -400.505435) (xy 316.0866 -400.541126) (xy 316.122291 -400.582317)
			(xy 316.151757 -400.628167) (xy 316.174399 -400.677744) (xy 316.189754 -400.730039) (xy 316.19751 -400.783987)
			(xy 316.197996 -400.811238) (xy 316.197996 -401.674838) (xy 316.634876 -401.674838) (xy 316.634876 -400.811238)
			(xy 316.635362 -400.783987) (xy 316.643118 -400.730039) (xy 316.658473 -400.677744) (xy 316.681115 -400.628167)
			(xy 316.710581 -400.582317) (xy 316.746272 -400.541126) (xy 316.787463 -400.505435) (xy 316.833313 -400.475969)
			(xy 316.88289 -400.453327) (xy 316.935185 -400.437972) (xy 316.989133 -400.430216) (xy 317.043635 -400.430216)
			(xy 317.097583 -400.437972) (xy 317.149878 -400.453327) (xy 317.199455 -400.475969) (xy 317.245305 -400.505435)
			(xy 317.286496 -400.541126) (xy 317.322187 -400.582317) (xy 317.351653 -400.628167) (xy 317.374295 -400.677744)
			(xy 317.38965 -400.730039) (xy 317.397406 -400.783987) (xy 317.397892 -400.811238) (xy 317.397892 -401.674838)
			(xy 317.834772 -401.674838) (xy 317.834772 -400.811238) (xy 317.835258 -400.783987) (xy 317.843014 -400.730039)
			(xy 317.858369 -400.677744) (xy 317.881011 -400.628167) (xy 317.910477 -400.582317) (xy 317.946168 -400.541126)
			(xy 317.987359 -400.505435) (xy 318.033209 -400.475969) (xy 318.082786 -400.453327) (xy 318.135081 -400.437972)
			(xy 318.189029 -400.430216) (xy 318.243531 -400.430216) (xy 318.297479 -400.437972) (xy 318.349774 -400.453327)
			(xy 318.399351 -400.475969) (xy 318.445201 -400.505435) (xy 318.486392 -400.541126) (xy 318.522083 -400.582317)
			(xy 318.551549 -400.628167) (xy 318.574191 -400.677744) (xy 318.589546 -400.730039) (xy 318.597302 -400.783987)
			(xy 318.597788 -400.811238) (xy 318.597788 -401.674838) (xy 319.034668 -401.674838) (xy 319.034668 -400.811238)
			(xy 319.035154 -400.783987) (xy 319.04291 -400.730039) (xy 319.058265 -400.677744) (xy 319.080907 -400.628167)
			(xy 319.110373 -400.582317) (xy 319.146064 -400.541126) (xy 319.187255 -400.505435) (xy 319.233105 -400.475969)
			(xy 319.282682 -400.453327) (xy 319.334977 -400.437972) (xy 319.388925 -400.430216) (xy 319.443427 -400.430216)
			(xy 319.497375 -400.437972) (xy 319.54967 -400.453327) (xy 319.599247 -400.475969) (xy 319.645097 -400.505435)
			(xy 319.686288 -400.541126) (xy 319.721979 -400.582317) (xy 319.751445 -400.628167) (xy 319.774087 -400.677744)
			(xy 319.789442 -400.730039) (xy 319.797198 -400.783987) (xy 319.797684 -400.811238) (xy 319.797684 -401.674838)
			(xy 320.234564 -401.674838) (xy 320.234564 -400.811238) (xy 320.23505 -400.783969) (xy 320.242812 -400.729985)
			(xy 320.258177 -400.677655) (xy 320.280834 -400.628045) (xy 320.31032 -400.582164) (xy 320.346035 -400.540947)
			(xy 320.387252 -400.505232) (xy 320.433133 -400.475746) (xy 320.482743 -400.453089) (xy 320.535073 -400.437724)
			(xy 320.589057 -400.429962) (xy 320.643595 -400.429962) (xy 320.697579 -400.437724) (xy 320.749909 -400.453089)
			(xy 320.799519 -400.475746) (xy 320.8454 -400.505232) (xy 320.886617 -400.540947) (xy 320.922332 -400.582164)
			(xy 320.951818 -400.628045) (xy 320.974475 -400.677655) (xy 320.98984 -400.729985) (xy 320.997602 -400.783969)
			(xy 320.998088 -400.811238) (xy 320.998088 -401.674838) (xy 321.43446 -401.674838) (xy 321.43446 -400.811238)
			(xy 321.434946 -400.783969) (xy 321.442708 -400.729985) (xy 321.458073 -400.677655) (xy 321.48073 -400.628045)
			(xy 321.510216 -400.582164) (xy 321.545931 -400.540947) (xy 321.587148 -400.505232) (xy 321.633029 -400.475746)
			(xy 321.682639 -400.453089) (xy 321.734969 -400.437724) (xy 321.788953 -400.429962) (xy 321.843491 -400.429962)
			(xy 321.897475 -400.437724) (xy 321.949805 -400.453089) (xy 321.999415 -400.475746) (xy 322.045296 -400.505232)
			(xy 322.086513 -400.540947) (xy 322.122228 -400.582164) (xy 322.151714 -400.628045) (xy 322.174371 -400.677655)
			(xy 322.189736 -400.729985) (xy 322.197498 -400.783969) (xy 322.197984 -400.811238) (xy 322.197984 -401.674838)
			(xy 335.962244 -401.674838) (xy 335.962244 -400.811238) (xy 335.96273 -400.783969) (xy 335.970492 -400.729985)
			(xy 335.985857 -400.677655) (xy 336.008514 -400.628045) (xy 336.038 -400.582164) (xy 336.073715 -400.540947)
			(xy 336.114932 -400.505232) (xy 336.160813 -400.475746) (xy 336.210423 -400.453089) (xy 336.262753 -400.437724)
			(xy 336.316737 -400.429962) (xy 336.371275 -400.429962) (xy 336.425259 -400.437724) (xy 336.477589 -400.453089)
			(xy 336.527199 -400.475746) (xy 336.57308 -400.505232) (xy 336.614297 -400.540947) (xy 336.650012 -400.582164)
			(xy 336.679498 -400.628045) (xy 336.702155 -400.677655) (xy 336.71752 -400.729985) (xy 336.725282 -400.783969)
			(xy 336.725768 -400.811238) (xy 336.725768 -401.674838) (xy 337.16214 -401.674838) (xy 337.16214 -400.811238)
			(xy 337.162626 -400.783969) (xy 337.170388 -400.729985) (xy 337.185753 -400.677655) (xy 337.20841 -400.628045)
			(xy 337.237896 -400.582164) (xy 337.273611 -400.540947) (xy 337.314828 -400.505232) (xy 337.360709 -400.475746)
			(xy 337.410319 -400.453089) (xy 337.462649 -400.437724) (xy 337.516633 -400.429962) (xy 337.571171 -400.429962)
			(xy 337.625155 -400.437724) (xy 337.677485 -400.453089) (xy 337.727095 -400.475746) (xy 337.772976 -400.505232)
			(xy 337.814193 -400.540947) (xy 337.849908 -400.582164) (xy 337.879394 -400.628045) (xy 337.902051 -400.677655)
			(xy 337.917416 -400.729985) (xy 337.925178 -400.783969) (xy 337.925664 -400.811238) (xy 337.925664 -401.674838)
			(xy 338.362544 -401.674838) (xy 338.362544 -400.811238) (xy 338.36303 -400.783987) (xy 338.370786 -400.730039)
			(xy 338.386141 -400.677744) (xy 338.408783 -400.628167) (xy 338.438249 -400.582317) (xy 338.47394 -400.541126)
			(xy 338.515131 -400.505435) (xy 338.560981 -400.475969) (xy 338.610558 -400.453327) (xy 338.662853 -400.437972)
			(xy 338.716801 -400.430216) (xy 338.771303 -400.430216) (xy 338.825251 -400.437972) (xy 338.877546 -400.453327)
			(xy 338.927123 -400.475969) (xy 338.972973 -400.505435) (xy 339.014164 -400.541126) (xy 339.049855 -400.582317)
			(xy 339.079321 -400.628167) (xy 339.101963 -400.677744) (xy 339.117318 -400.730039) (xy 339.125074 -400.783987)
			(xy 339.12556 -400.811238) (xy 339.12556 -401.674838) (xy 339.56244 -401.674838) (xy 339.56244 -400.811238)
			(xy 339.562926 -400.783987) (xy 339.570682 -400.730039) (xy 339.586037 -400.677744) (xy 339.608679 -400.628167)
			(xy 339.638145 -400.582317) (xy 339.673836 -400.541126) (xy 339.715027 -400.505435) (xy 339.760877 -400.475969)
			(xy 339.810454 -400.453327) (xy 339.862749 -400.437972) (xy 339.916697 -400.430216) (xy 339.971199 -400.430216)
			(xy 340.025147 -400.437972) (xy 340.077442 -400.453327) (xy 340.127019 -400.475969) (xy 340.172869 -400.505435)
			(xy 340.21406 -400.541126) (xy 340.249751 -400.582317) (xy 340.279217 -400.628167) (xy 340.301859 -400.677744)
			(xy 340.317214 -400.730039) (xy 340.32497 -400.783987) (xy 340.325456 -400.811238) (xy 340.325456 -401.674838)
			(xy 340.762336 -401.674838) (xy 340.762336 -400.811238) (xy 340.762822 -400.783969) (xy 340.770584 -400.729985)
			(xy 340.785949 -400.677655) (xy 340.808606 -400.628045) (xy 340.838092 -400.582164) (xy 340.873807 -400.540947)
			(xy 340.915024 -400.505232) (xy 340.960905 -400.475746) (xy 341.010515 -400.453089) (xy 341.062845 -400.437724)
			(xy 341.116829 -400.429962) (xy 341.171367 -400.429962) (xy 341.225351 -400.437724) (xy 341.277681 -400.453089)
			(xy 341.327291 -400.475746) (xy 341.373172 -400.505232) (xy 341.414389 -400.540947) (xy 341.450104 -400.582164)
			(xy 341.47959 -400.628045) (xy 341.502247 -400.677655) (xy 341.517612 -400.729985) (xy 341.525374 -400.783969)
			(xy 341.52586 -400.811238) (xy 341.52586 -401.674838) (xy 341.962232 -401.674838) (xy 341.962232 -400.811238)
			(xy 341.962718 -400.783969) (xy 341.97048 -400.729985) (xy 341.985845 -400.677655) (xy 342.008502 -400.628045)
			(xy 342.037988 -400.582164) (xy 342.073703 -400.540947) (xy 342.11492 -400.505232) (xy 342.160801 -400.475746)
			(xy 342.210411 -400.453089) (xy 342.262741 -400.437724) (xy 342.316725 -400.429962) (xy 342.371263 -400.429962)
			(xy 342.425247 -400.437724) (xy 342.477577 -400.453089) (xy 342.527187 -400.475746) (xy 342.573068 -400.505232)
			(xy 342.614285 -400.540947) (xy 342.65 -400.582164) (xy 342.679486 -400.628045) (xy 342.702143 -400.677655)
			(xy 342.717508 -400.729985) (xy 342.72527 -400.783969) (xy 342.725756 -400.811238) (xy 342.725756 -401.674838)
			(xy 343.162636 -401.674838) (xy 343.162636 -400.811238) (xy 343.163122 -400.783987) (xy 343.170878 -400.730039)
			(xy 343.186233 -400.677744) (xy 343.208875 -400.628167) (xy 343.238341 -400.582317) (xy 343.274032 -400.541126)
			(xy 343.315223 -400.505435) (xy 343.361073 -400.475969) (xy 343.41065 -400.453327) (xy 343.462945 -400.437972)
			(xy 343.516893 -400.430216) (xy 343.571395 -400.430216) (xy 343.625343 -400.437972) (xy 343.677638 -400.453327)
			(xy 343.727215 -400.475969) (xy 343.773065 -400.505435) (xy 343.814256 -400.541126) (xy 343.849947 -400.582317)
			(xy 343.879413 -400.628167) (xy 343.902055 -400.677744) (xy 343.91741 -400.730039) (xy 343.925166 -400.783987)
			(xy 343.925652 -400.811238) (xy 343.925652 -401.674838) (xy 344.362532 -401.674838) (xy 344.362532 -400.811238)
			(xy 344.363018 -400.783987) (xy 344.370774 -400.730039) (xy 344.386129 -400.677744) (xy 344.408771 -400.628167)
			(xy 344.438237 -400.582317) (xy 344.473928 -400.541126) (xy 344.515119 -400.505435) (xy 344.560969 -400.475969)
			(xy 344.610546 -400.453327) (xy 344.662841 -400.437972) (xy 344.716789 -400.430216) (xy 344.771291 -400.430216)
			(xy 344.825239 -400.437972) (xy 344.877534 -400.453327) (xy 344.927111 -400.475969) (xy 344.972961 -400.505435)
			(xy 345.014152 -400.541126) (xy 345.049843 -400.582317) (xy 345.079309 -400.628167) (xy 345.101951 -400.677744)
			(xy 345.117306 -400.730039) (xy 345.125062 -400.783987) (xy 345.125548 -400.811238) (xy 345.125548 -401.674838)
			(xy 345.562428 -401.674838) (xy 345.562428 -400.811238) (xy 345.562914 -400.783969) (xy 345.570676 -400.729985)
			(xy 345.586041 -400.677655) (xy 345.608698 -400.628045) (xy 345.638184 -400.582164) (xy 345.673899 -400.540947)
			(xy 345.715116 -400.505232) (xy 345.760997 -400.475746) (xy 345.810607 -400.453089) (xy 345.862937 -400.437724)
			(xy 345.916921 -400.429962) (xy 345.971459 -400.429962) (xy 346.025443 -400.437724) (xy 346.077773 -400.453089)
			(xy 346.127383 -400.475746) (xy 346.173264 -400.505232) (xy 346.214481 -400.540947) (xy 346.250196 -400.582164)
			(xy 346.279682 -400.628045) (xy 346.302339 -400.677655) (xy 346.317704 -400.729985) (xy 346.325466 -400.783969)
			(xy 346.325952 -400.811238) (xy 346.325952 -401.674838) (xy 346.762324 -401.674838) (xy 346.762324 -400.811238)
			(xy 346.76281 -400.783969) (xy 346.770572 -400.729985) (xy 346.785937 -400.677655) (xy 346.808594 -400.628045)
			(xy 346.83808 -400.582164) (xy 346.873795 -400.540947) (xy 346.915012 -400.505232) (xy 346.960893 -400.475746)
			(xy 347.010503 -400.453089) (xy 347.062833 -400.437724) (xy 347.116817 -400.429962) (xy 347.171355 -400.429962)
			(xy 347.225339 -400.437724) (xy 347.277669 -400.453089) (xy 347.327279 -400.475746) (xy 347.37316 -400.505232)
			(xy 347.414377 -400.540947) (xy 347.450092 -400.582164) (xy 347.479578 -400.628045) (xy 347.502235 -400.677655)
			(xy 347.5176 -400.729985) (xy 347.525362 -400.783969) (xy 347.525848 -400.811238) (xy 347.525848 -401.674838)
			(xy 347.962728 -401.674838) (xy 347.962728 -400.811238) (xy 347.963214 -400.783987) (xy 347.97097 -400.730039)
			(xy 347.986325 -400.677744) (xy 348.008967 -400.628167) (xy 348.038433 -400.582317) (xy 348.074124 -400.541126)
			(xy 348.115315 -400.505435) (xy 348.161165 -400.475969) (xy 348.210742 -400.453327) (xy 348.263037 -400.437972)
			(xy 348.316985 -400.430216) (xy 348.371487 -400.430216) (xy 348.425435 -400.437972) (xy 348.47773 -400.453327)
			(xy 348.527307 -400.475969) (xy 348.573157 -400.505435) (xy 348.614348 -400.541126) (xy 348.650039 -400.582317)
			(xy 348.679505 -400.628167) (xy 348.702147 -400.677744) (xy 348.717502 -400.730039) (xy 348.725258 -400.783987)
			(xy 348.725744 -400.811238) (xy 348.725744 -401.674838) (xy 349.162624 -401.674838) (xy 349.162624 -400.811238)
			(xy 349.16311 -400.783987) (xy 349.170866 -400.730039) (xy 349.186221 -400.677744) (xy 349.208863 -400.628167)
			(xy 349.238329 -400.582317) (xy 349.27402 -400.541126) (xy 349.315211 -400.505435) (xy 349.361061 -400.475969)
			(xy 349.410638 -400.453327) (xy 349.462933 -400.437972) (xy 349.516881 -400.430216) (xy 349.571383 -400.430216)
			(xy 349.625331 -400.437972) (xy 349.677626 -400.453327) (xy 349.727203 -400.475969) (xy 349.773053 -400.505435)
			(xy 349.814244 -400.541126) (xy 349.849935 -400.582317) (xy 349.879401 -400.628167) (xy 349.902043 -400.677744)
			(xy 349.917398 -400.730039) (xy 349.925154 -400.783987) (xy 349.92564 -400.811238) (xy 349.92564 -401.674838)
			(xy 350.36252 -401.674838) (xy 350.36252 -400.811238) (xy 350.363006 -400.783987) (xy 350.370762 -400.730039)
			(xy 350.386117 -400.677744) (xy 350.408759 -400.628167) (xy 350.438225 -400.582317) (xy 350.473916 -400.541126)
			(xy 350.515107 -400.505435) (xy 350.560957 -400.475969) (xy 350.610534 -400.453327) (xy 350.662829 -400.437972)
			(xy 350.716777 -400.430216) (xy 350.771279 -400.430216) (xy 350.825227 -400.437972) (xy 350.877522 -400.453327)
			(xy 350.927099 -400.475969) (xy 350.972949 -400.505435) (xy 351.01414 -400.541126) (xy 351.049831 -400.582317)
			(xy 351.079297 -400.628167) (xy 351.101939 -400.677744) (xy 351.117294 -400.730039) (xy 351.12505 -400.783987)
			(xy 351.125536 -400.811238) (xy 351.125536 -401.674838) (xy 351.562416 -401.674838) (xy 351.562416 -400.811238)
			(xy 351.562902 -400.783987) (xy 351.570658 -400.730039) (xy 351.586013 -400.677744) (xy 351.608655 -400.628167)
			(xy 351.638121 -400.582317) (xy 351.673812 -400.541126) (xy 351.715003 -400.505435) (xy 351.760853 -400.475969)
			(xy 351.81043 -400.453327) (xy 351.862725 -400.437972) (xy 351.916673 -400.430216) (xy 351.971175 -400.430216)
			(xy 352.025123 -400.437972) (xy 352.077418 -400.453327) (xy 352.126995 -400.475969) (xy 352.172845 -400.505435)
			(xy 352.214036 -400.541126) (xy 352.249727 -400.582317) (xy 352.279193 -400.628167) (xy 352.301835 -400.677744)
			(xy 352.31719 -400.730039) (xy 352.324946 -400.783987) (xy 352.325432 -400.811238) (xy 352.325432 -401.674838)
			(xy 352.762312 -401.674838) (xy 352.762312 -400.811238) (xy 352.762798 -400.783969) (xy 352.77056 -400.729985)
			(xy 352.785925 -400.677655) (xy 352.808582 -400.628045) (xy 352.838068 -400.582164) (xy 352.873783 -400.540947)
			(xy 352.915 -400.505232) (xy 352.960881 -400.475746) (xy 353.010491 -400.453089) (xy 353.062821 -400.437724)
			(xy 353.116805 -400.429962) (xy 353.171343 -400.429962) (xy 353.225327 -400.437724) (xy 353.277657 -400.453089)
			(xy 353.327267 -400.475746) (xy 353.373148 -400.505232) (xy 353.414365 -400.540947) (xy 353.45008 -400.582164)
			(xy 353.479566 -400.628045) (xy 353.502223 -400.677655) (xy 353.517588 -400.729985) (xy 353.52535 -400.783969)
			(xy 353.525836 -400.811238) (xy 353.525836 -401.674838) (xy 353.962208 -401.674838) (xy 353.962208 -400.811238)
			(xy 353.962694 -400.783969) (xy 353.970456 -400.729985) (xy 353.985821 -400.677655) (xy 354.008478 -400.628045)
			(xy 354.037964 -400.582164) (xy 354.073679 -400.540947) (xy 354.114896 -400.505232) (xy 354.160777 -400.475746)
			(xy 354.210387 -400.453089) (xy 354.262717 -400.437724) (xy 354.316701 -400.429962) (xy 354.371239 -400.429962)
			(xy 354.425223 -400.437724) (xy 354.477553 -400.453089) (xy 354.527163 -400.475746) (xy 354.573044 -400.505232)
			(xy 354.614261 -400.540947) (xy 354.649976 -400.582164) (xy 354.679462 -400.628045) (xy 354.702119 -400.677655)
			(xy 354.717484 -400.729985) (xy 354.725246 -400.783969) (xy 354.725732 -400.811238) (xy 354.725732 -401.674838)
			(xy 370.534692 -401.674838) (xy 370.534692 -400.811238) (xy 370.535178 -400.783969) (xy 370.54294 -400.729985)
			(xy 370.558305 -400.677655) (xy 370.580962 -400.628045) (xy 370.610448 -400.582164) (xy 370.646163 -400.540947)
			(xy 370.68738 -400.505232) (xy 370.733261 -400.475746) (xy 370.782871 -400.453089) (xy 370.835201 -400.437724)
			(xy 370.889185 -400.429962) (xy 370.943723 -400.429962) (xy 370.997707 -400.437724) (xy 371.050037 -400.453089)
			(xy 371.099647 -400.475746) (xy 371.145528 -400.505232) (xy 371.186745 -400.540947) (xy 371.22246 -400.582164)
			(xy 371.251946 -400.628045) (xy 371.274603 -400.677655) (xy 371.289968 -400.729985) (xy 371.29773 -400.783969)
			(xy 371.298216 -400.811238) (xy 371.298216 -401.674838) (xy 371.734588 -401.674838) (xy 371.734588 -400.811238)
			(xy 371.735074 -400.783969) (xy 371.742836 -400.729985) (xy 371.758201 -400.677655) (xy 371.780858 -400.628045)
			(xy 371.810344 -400.582164) (xy 371.846059 -400.540947) (xy 371.887276 -400.505232) (xy 371.933157 -400.475746)
			(xy 371.982767 -400.453089) (xy 372.035097 -400.437724) (xy 372.089081 -400.429962) (xy 372.143619 -400.429962)
			(xy 372.197603 -400.437724) (xy 372.249933 -400.453089) (xy 372.299543 -400.475746) (xy 372.345424 -400.505232)
			(xy 372.386641 -400.540947) (xy 372.422356 -400.582164) (xy 372.451842 -400.628045) (xy 372.474499 -400.677655)
			(xy 372.489864 -400.729985) (xy 372.497626 -400.783969) (xy 372.498112 -400.811238) (xy 372.498112 -401.674838)
			(xy 372.934992 -401.674838) (xy 372.934992 -400.811238) (xy 372.935478 -400.783987) (xy 372.943234 -400.730039)
			(xy 372.958589 -400.677744) (xy 372.981231 -400.628167) (xy 373.010697 -400.582317) (xy 373.046388 -400.541126)
			(xy 373.087579 -400.505435) (xy 373.133429 -400.475969) (xy 373.183006 -400.453327) (xy 373.235301 -400.437972)
			(xy 373.289249 -400.430216) (xy 373.343751 -400.430216) (xy 373.397699 -400.437972) (xy 373.449994 -400.453327)
			(xy 373.499571 -400.475969) (xy 373.545421 -400.505435) (xy 373.586612 -400.541126) (xy 373.622303 -400.582317)
			(xy 373.651769 -400.628167) (xy 373.674411 -400.677744) (xy 373.689766 -400.730039) (xy 373.697522 -400.783987)
			(xy 373.698008 -400.811238) (xy 373.698008 -401.674838) (xy 374.134888 -401.674838) (xy 374.134888 -400.811238)
			(xy 374.135374 -400.783987) (xy 374.14313 -400.730039) (xy 374.158485 -400.677744) (xy 374.181127 -400.628167)
			(xy 374.210593 -400.582317) (xy 374.246284 -400.541126) (xy 374.287475 -400.505435) (xy 374.333325 -400.475969)
			(xy 374.382902 -400.453327) (xy 374.435197 -400.437972) (xy 374.489145 -400.430216) (xy 374.543647 -400.430216)
			(xy 374.597595 -400.437972) (xy 374.64989 -400.453327) (xy 374.699467 -400.475969) (xy 374.745317 -400.505435)
			(xy 374.786508 -400.541126) (xy 374.822199 -400.582317) (xy 374.851665 -400.628167) (xy 374.874307 -400.677744)
			(xy 374.889662 -400.730039) (xy 374.897418 -400.783987) (xy 374.897904 -400.811238) (xy 374.897904 -401.674838)
			(xy 375.334784 -401.674838) (xy 375.334784 -400.811238) (xy 375.33527 -400.783969) (xy 375.343032 -400.729985)
			(xy 375.358397 -400.677655) (xy 375.381054 -400.628045) (xy 375.41054 -400.582164) (xy 375.446255 -400.540947)
			(xy 375.487472 -400.505232) (xy 375.533353 -400.475746) (xy 375.582963 -400.453089) (xy 375.635293 -400.437724)
			(xy 375.689277 -400.429962) (xy 375.743815 -400.429962) (xy 375.797799 -400.437724) (xy 375.850129 -400.453089)
			(xy 375.899739 -400.475746) (xy 375.94562 -400.505232) (xy 375.986837 -400.540947) (xy 376.022552 -400.582164)
			(xy 376.052038 -400.628045) (xy 376.074695 -400.677655) (xy 376.09006 -400.729985) (xy 376.097822 -400.783969)
			(xy 376.098308 -400.811238) (xy 376.098308 -401.674838) (xy 376.53468 -401.674838) (xy 376.53468 -400.811238)
			(xy 376.535166 -400.783969) (xy 376.542928 -400.729985) (xy 376.558293 -400.677655) (xy 376.58095 -400.628045)
			(xy 376.610436 -400.582164) (xy 376.646151 -400.540947) (xy 376.687368 -400.505232) (xy 376.733249 -400.475746)
			(xy 376.782859 -400.453089) (xy 376.835189 -400.437724) (xy 376.889173 -400.429962) (xy 376.943711 -400.429962)
			(xy 376.997695 -400.437724) (xy 377.050025 -400.453089) (xy 377.099635 -400.475746) (xy 377.145516 -400.505232)
			(xy 377.186733 -400.540947) (xy 377.222448 -400.582164) (xy 377.251934 -400.628045) (xy 377.274591 -400.677655)
			(xy 377.289956 -400.729985) (xy 377.297718 -400.783969) (xy 377.298204 -400.811238) (xy 377.298204 -401.674838)
			(xy 377.735084 -401.674838) (xy 377.735084 -400.811238) (xy 377.73557 -400.783987) (xy 377.743326 -400.730039)
			(xy 377.758681 -400.677744) (xy 377.781323 -400.628167) (xy 377.810789 -400.582317) (xy 377.84648 -400.541126)
			(xy 377.887671 -400.505435) (xy 377.933521 -400.475969) (xy 377.983098 -400.453327) (xy 378.035393 -400.437972)
			(xy 378.089341 -400.430216) (xy 378.143843 -400.430216) (xy 378.197791 -400.437972) (xy 378.250086 -400.453327)
			(xy 378.299663 -400.475969) (xy 378.345513 -400.505435) (xy 378.386704 -400.541126) (xy 378.422395 -400.582317)
			(xy 378.451861 -400.628167) (xy 378.474503 -400.677744) (xy 378.489858 -400.730039) (xy 378.497614 -400.783987)
			(xy 378.4981 -400.811238) (xy 378.4981 -401.674838) (xy 378.93498 -401.674838) (xy 378.93498 -400.811238)
			(xy 378.935466 -400.783987) (xy 378.943222 -400.730039) (xy 378.958577 -400.677744) (xy 378.981219 -400.628167)
			(xy 379.010685 -400.582317) (xy 379.046376 -400.541126) (xy 379.087567 -400.505435) (xy 379.133417 -400.475969)
			(xy 379.182994 -400.453327) (xy 379.235289 -400.437972) (xy 379.289237 -400.430216) (xy 379.343739 -400.430216)
			(xy 379.397687 -400.437972) (xy 379.449982 -400.453327) (xy 379.499559 -400.475969) (xy 379.545409 -400.505435)
			(xy 379.5866 -400.541126) (xy 379.622291 -400.582317) (xy 379.651757 -400.628167) (xy 379.674399 -400.677744)
			(xy 379.689754 -400.730039) (xy 379.69751 -400.783987) (xy 379.697996 -400.811238) (xy 379.697996 -401.674838)
			(xy 380.134876 -401.674838) (xy 380.134876 -400.811238) (xy 380.135362 -400.783969) (xy 380.143124 -400.729985)
			(xy 380.158489 -400.677655) (xy 380.181146 -400.628045) (xy 380.210632 -400.582164) (xy 380.246347 -400.540947)
			(xy 380.287564 -400.505232) (xy 380.333445 -400.475746) (xy 380.383055 -400.453089) (xy 380.435385 -400.437724)
			(xy 380.489369 -400.429962) (xy 380.543907 -400.429962) (xy 380.597891 -400.437724) (xy 380.650221 -400.453089)
			(xy 380.699831 -400.475746) (xy 380.745712 -400.505232) (xy 380.786929 -400.540947) (xy 380.822644 -400.582164)
			(xy 380.85213 -400.628045) (xy 380.874787 -400.677655) (xy 380.890152 -400.729985) (xy 380.897914 -400.783969)
			(xy 380.8984 -400.811238) (xy 380.8984 -401.674838) (xy 381.334772 -401.674838) (xy 381.334772 -400.811238)
			(xy 381.335258 -400.783969) (xy 381.34302 -400.729985) (xy 381.358385 -400.677655) (xy 381.381042 -400.628045)
			(xy 381.410528 -400.582164) (xy 381.446243 -400.540947) (xy 381.48746 -400.505232) (xy 381.533341 -400.475746)
			(xy 381.582951 -400.453089) (xy 381.635281 -400.437724) (xy 381.689265 -400.429962) (xy 381.743803 -400.429962)
			(xy 381.797787 -400.437724) (xy 381.850117 -400.453089) (xy 381.899727 -400.475746) (xy 381.945608 -400.505232)
			(xy 381.986825 -400.540947) (xy 382.02254 -400.582164) (xy 382.052026 -400.628045) (xy 382.074683 -400.677655)
			(xy 382.090048 -400.729985) (xy 382.09781 -400.783969) (xy 382.098296 -400.811238) (xy 382.098296 -401.674838)
			(xy 382.535176 -401.674838) (xy 382.535176 -400.811238) (xy 382.535662 -400.783987) (xy 382.543418 -400.730039)
			(xy 382.558773 -400.677744) (xy 382.581415 -400.628167) (xy 382.610881 -400.582317) (xy 382.646572 -400.541126)
			(xy 382.687763 -400.505435) (xy 382.733613 -400.475969) (xy 382.78319 -400.453327) (xy 382.835485 -400.437972)
			(xy 382.889433 -400.430216) (xy 382.943935 -400.430216) (xy 382.997883 -400.437972) (xy 383.050178 -400.453327)
			(xy 383.099755 -400.475969) (xy 383.145605 -400.505435) (xy 383.186796 -400.541126) (xy 383.222487 -400.582317)
			(xy 383.251953 -400.628167) (xy 383.274595 -400.677744) (xy 383.28995 -400.730039) (xy 383.297706 -400.783987)
			(xy 383.298192 -400.811238) (xy 383.298192 -401.674838) (xy 383.735072 -401.674838) (xy 383.735072 -400.811238)
			(xy 383.735558 -400.783987) (xy 383.743314 -400.730039) (xy 383.758669 -400.677744) (xy 383.781311 -400.628167)
			(xy 383.810777 -400.582317) (xy 383.846468 -400.541126) (xy 383.887659 -400.505435) (xy 383.933509 -400.475969)
			(xy 383.983086 -400.453327) (xy 384.035381 -400.437972) (xy 384.089329 -400.430216) (xy 384.143831 -400.430216)
			(xy 384.197779 -400.437972) (xy 384.250074 -400.453327) (xy 384.299651 -400.475969) (xy 384.345501 -400.505435)
			(xy 384.386692 -400.541126) (xy 384.422383 -400.582317) (xy 384.451849 -400.628167) (xy 384.474491 -400.677744)
			(xy 384.489846 -400.730039) (xy 384.497602 -400.783987) (xy 384.498088 -400.811238) (xy 384.498088 -401.674838)
			(xy 384.934968 -401.674838) (xy 384.934968 -400.811238) (xy 384.935454 -400.783987) (xy 384.94321 -400.730039)
			(xy 384.958565 -400.677744) (xy 384.981207 -400.628167) (xy 385.010673 -400.582317) (xy 385.046364 -400.541126)
			(xy 385.087555 -400.505435) (xy 385.133405 -400.475969) (xy 385.182982 -400.453327) (xy 385.235277 -400.437972)
			(xy 385.289225 -400.430216) (xy 385.343727 -400.430216) (xy 385.397675 -400.437972) (xy 385.44997 -400.453327)
			(xy 385.499547 -400.475969) (xy 385.545397 -400.505435) (xy 385.586588 -400.541126) (xy 385.622279 -400.582317)
			(xy 385.651745 -400.628167) (xy 385.674387 -400.677744) (xy 385.689742 -400.730039) (xy 385.697498 -400.783987)
			(xy 385.697984 -400.811238) (xy 385.697984 -401.674838) (xy 386.134864 -401.674838) (xy 386.134864 -400.811238)
			(xy 386.13535 -400.783987) (xy 386.143106 -400.730039) (xy 386.158461 -400.677744) (xy 386.181103 -400.628167)
			(xy 386.210569 -400.582317) (xy 386.24626 -400.541126) (xy 386.287451 -400.505435) (xy 386.333301 -400.475969)
			(xy 386.382878 -400.453327) (xy 386.435173 -400.437972) (xy 386.489121 -400.430216) (xy 386.543623 -400.430216)
			(xy 386.597571 -400.437972) (xy 386.649866 -400.453327) (xy 386.699443 -400.475969) (xy 386.745293 -400.505435)
			(xy 386.786484 -400.541126) (xy 386.822175 -400.582317) (xy 386.851641 -400.628167) (xy 386.874283 -400.677744)
			(xy 386.889638 -400.730039) (xy 386.897394 -400.783987) (xy 386.89788 -400.811238) (xy 386.89788 -401.674838)
			(xy 387.33476 -401.674838) (xy 387.33476 -400.811238) (xy 387.335246 -400.783969) (xy 387.343008 -400.729985)
			(xy 387.358373 -400.677655) (xy 387.38103 -400.628045) (xy 387.410516 -400.582164) (xy 387.446231 -400.540947)
			(xy 387.487448 -400.505232) (xy 387.533329 -400.475746) (xy 387.582939 -400.453089) (xy 387.635269 -400.437724)
			(xy 387.689253 -400.429962) (xy 387.743791 -400.429962) (xy 387.797775 -400.437724) (xy 387.850105 -400.453089)
			(xy 387.899715 -400.475746) (xy 387.945596 -400.505232) (xy 387.986813 -400.540947) (xy 388.022528 -400.582164)
			(xy 388.052014 -400.628045) (xy 388.074671 -400.677655) (xy 388.090036 -400.729985) (xy 388.097798 -400.783969)
			(xy 388.098284 -400.811238) (xy 388.098284 -401.674838) (xy 388.534656 -401.674838) (xy 388.534656 -400.811238)
			(xy 388.535142 -400.783969) (xy 388.542904 -400.729985) (xy 388.558269 -400.677655) (xy 388.580926 -400.628045)
			(xy 388.610412 -400.582164) (xy 388.646127 -400.540947) (xy 388.687344 -400.505232) (xy 388.733225 -400.475746)
			(xy 388.782835 -400.453089) (xy 388.835165 -400.437724) (xy 388.889149 -400.429962) (xy 388.943687 -400.429962)
			(xy 388.997671 -400.437724) (xy 389.050001 -400.453089) (xy 389.099611 -400.475746) (xy 389.145492 -400.505232)
			(xy 389.186709 -400.540947) (xy 389.222424 -400.582164) (xy 389.25191 -400.628045) (xy 389.274567 -400.677655)
			(xy 389.289932 -400.729985) (xy 389.297694 -400.783969) (xy 389.29818 -400.811238) (xy 389.29818 -401.674838)
			(xy 403.06244 -401.674838) (xy 403.06244 -400.811238) (xy 403.062926 -400.783969) (xy 403.070688 -400.729985)
			(xy 403.086053 -400.677655) (xy 403.10871 -400.628045) (xy 403.138196 -400.582164) (xy 403.173911 -400.540947)
			(xy 403.215128 -400.505232) (xy 403.261009 -400.475746) (xy 403.310619 -400.453089) (xy 403.362949 -400.437724)
			(xy 403.416933 -400.429962) (xy 403.471471 -400.429962) (xy 403.525455 -400.437724) (xy 403.577785 -400.453089)
			(xy 403.627395 -400.475746) (xy 403.673276 -400.505232) (xy 403.714493 -400.540947) (xy 403.750208 -400.582164)
			(xy 403.779694 -400.628045) (xy 403.802351 -400.677655) (xy 403.817716 -400.729985) (xy 403.825478 -400.783969)
			(xy 403.825964 -400.811238) (xy 403.825964 -401.674838) (xy 404.262336 -401.674838) (xy 404.262336 -400.811238)
			(xy 404.262822 -400.783969) (xy 404.270584 -400.729985) (xy 404.285949 -400.677655) (xy 404.308606 -400.628045)
			(xy 404.338092 -400.582164) (xy 404.373807 -400.540947) (xy 404.415024 -400.505232) (xy 404.460905 -400.475746)
			(xy 404.510515 -400.453089) (xy 404.562845 -400.437724) (xy 404.616829 -400.429962) (xy 404.671367 -400.429962)
			(xy 404.725351 -400.437724) (xy 404.777681 -400.453089) (xy 404.827291 -400.475746) (xy 404.873172 -400.505232)
			(xy 404.914389 -400.540947) (xy 404.950104 -400.582164) (xy 404.97959 -400.628045) (xy 405.002247 -400.677655)
			(xy 405.017612 -400.729985) (xy 405.025374 -400.783969) (xy 405.02586 -400.811238) (xy 405.02586 -401.674838)
			(xy 405.46274 -401.674838) (xy 405.46274 -400.811238) (xy 405.463226 -400.783987) (xy 405.470982 -400.730039)
			(xy 405.486337 -400.677744) (xy 405.508979 -400.628167) (xy 405.538445 -400.582317) (xy 405.574136 -400.541126)
			(xy 405.615327 -400.505435) (xy 405.661177 -400.475969) (xy 405.710754 -400.453327) (xy 405.763049 -400.437972)
			(xy 405.816997 -400.430216) (xy 405.871499 -400.430216) (xy 405.925447 -400.437972) (xy 405.977742 -400.453327)
			(xy 406.027319 -400.475969) (xy 406.073169 -400.505435) (xy 406.11436 -400.541126) (xy 406.150051 -400.582317)
			(xy 406.179517 -400.628167) (xy 406.202159 -400.677744) (xy 406.217514 -400.730039) (xy 406.22527 -400.783987)
			(xy 406.225756 -400.811238) (xy 406.225756 -401.674838) (xy 406.662636 -401.674838) (xy 406.662636 -400.811238)
			(xy 406.663122 -400.783987) (xy 406.670878 -400.730039) (xy 406.686233 -400.677744) (xy 406.708875 -400.628167)
			(xy 406.738341 -400.582317) (xy 406.774032 -400.541126) (xy 406.815223 -400.505435) (xy 406.861073 -400.475969)
			(xy 406.91065 -400.453327) (xy 406.962945 -400.437972) (xy 407.016893 -400.430216) (xy 407.071395 -400.430216)
			(xy 407.125343 -400.437972) (xy 407.177638 -400.453327) (xy 407.227215 -400.475969) (xy 407.273065 -400.505435)
			(xy 407.314256 -400.541126) (xy 407.349947 -400.582317) (xy 407.379413 -400.628167) (xy 407.402055 -400.677744)
			(xy 407.41741 -400.730039) (xy 407.425166 -400.783987) (xy 407.425652 -400.811238) (xy 407.425652 -401.674838)
			(xy 407.862532 -401.674838) (xy 407.862532 -400.811238) (xy 407.863018 -400.783969) (xy 407.87078 -400.729985)
			(xy 407.886145 -400.677655) (xy 407.908802 -400.628045) (xy 407.938288 -400.582164) (xy 407.974003 -400.540947)
			(xy 408.01522 -400.505232) (xy 408.061101 -400.475746) (xy 408.110711 -400.453089) (xy 408.163041 -400.437724)
			(xy 408.217025 -400.429962) (xy 408.271563 -400.429962) (xy 408.325547 -400.437724) (xy 408.377877 -400.453089)
			(xy 408.427487 -400.475746) (xy 408.473368 -400.505232) (xy 408.514585 -400.540947) (xy 408.5503 -400.582164)
			(xy 408.579786 -400.628045) (xy 408.602443 -400.677655) (xy 408.617808 -400.729985) (xy 408.62557 -400.783969)
			(xy 408.626056 -400.811238) (xy 408.626056 -401.674838) (xy 409.062428 -401.674838) (xy 409.062428 -400.811238)
			(xy 409.062914 -400.783969) (xy 409.070676 -400.729985) (xy 409.086041 -400.677655) (xy 409.108698 -400.628045)
			(xy 409.138184 -400.582164) (xy 409.173899 -400.540947) (xy 409.215116 -400.505232) (xy 409.260997 -400.475746)
			(xy 409.310607 -400.453089) (xy 409.362937 -400.437724) (xy 409.416921 -400.429962) (xy 409.471459 -400.429962)
			(xy 409.525443 -400.437724) (xy 409.577773 -400.453089) (xy 409.627383 -400.475746) (xy 409.673264 -400.505232)
			(xy 409.714481 -400.540947) (xy 409.750196 -400.582164) (xy 409.779682 -400.628045) (xy 409.802339 -400.677655)
			(xy 409.817704 -400.729985) (xy 409.825466 -400.783969) (xy 409.825952 -400.811238) (xy 409.825952 -401.674838)
			(xy 410.262832 -401.674838) (xy 410.262832 -400.811238) (xy 410.263318 -400.783987) (xy 410.271074 -400.730039)
			(xy 410.286429 -400.677744) (xy 410.309071 -400.628167) (xy 410.338537 -400.582317) (xy 410.374228 -400.541126)
			(xy 410.415419 -400.505435) (xy 410.461269 -400.475969) (xy 410.510846 -400.453327) (xy 410.563141 -400.437972)
			(xy 410.617089 -400.430216) (xy 410.671591 -400.430216) (xy 410.725539 -400.437972) (xy 410.777834 -400.453327)
			(xy 410.827411 -400.475969) (xy 410.873261 -400.505435) (xy 410.914452 -400.541126) (xy 410.950143 -400.582317)
			(xy 410.979609 -400.628167) (xy 411.002251 -400.677744) (xy 411.017606 -400.730039) (xy 411.025362 -400.783987)
			(xy 411.025848 -400.811238) (xy 411.025848 -401.674838) (xy 411.462728 -401.674838) (xy 411.462728 -400.811238)
			(xy 411.463214 -400.783987) (xy 411.47097 -400.730039) (xy 411.486325 -400.677744) (xy 411.508967 -400.628167)
			(xy 411.538433 -400.582317) (xy 411.574124 -400.541126) (xy 411.615315 -400.505435) (xy 411.661165 -400.475969)
			(xy 411.710742 -400.453327) (xy 411.763037 -400.437972) (xy 411.816985 -400.430216) (xy 411.871487 -400.430216)
			(xy 411.925435 -400.437972) (xy 411.97773 -400.453327) (xy 412.027307 -400.475969) (xy 412.073157 -400.505435)
			(xy 412.114348 -400.541126) (xy 412.150039 -400.582317) (xy 412.179505 -400.628167) (xy 412.202147 -400.677744)
			(xy 412.217502 -400.730039) (xy 412.225258 -400.783987) (xy 412.225744 -400.811238) (xy 412.225744 -401.674838)
			(xy 412.662624 -401.674838) (xy 412.662624 -400.811238) (xy 412.66311 -400.783969) (xy 412.670872 -400.729985)
			(xy 412.686237 -400.677655) (xy 412.708894 -400.628045) (xy 412.73838 -400.582164) (xy 412.774095 -400.540947)
			(xy 412.815312 -400.505232) (xy 412.861193 -400.475746) (xy 412.910803 -400.453089) (xy 412.963133 -400.437724)
			(xy 413.017117 -400.429962) (xy 413.071655 -400.429962) (xy 413.125639 -400.437724) (xy 413.177969 -400.453089)
			(xy 413.227579 -400.475746) (xy 413.27346 -400.505232) (xy 413.314677 -400.540947) (xy 413.350392 -400.582164)
			(xy 413.379878 -400.628045) (xy 413.402535 -400.677655) (xy 413.4179 -400.729985) (xy 413.425662 -400.783969)
			(xy 413.426148 -400.811238) (xy 413.426148 -401.674838) (xy 413.86252 -401.674838) (xy 413.86252 -400.811238)
			(xy 413.863006 -400.783969) (xy 413.870768 -400.729985) (xy 413.886133 -400.677655) (xy 413.90879 -400.628045)
			(xy 413.938276 -400.582164) (xy 413.973991 -400.540947) (xy 414.015208 -400.505232) (xy 414.061089 -400.475746)
			(xy 414.110699 -400.453089) (xy 414.163029 -400.437724) (xy 414.217013 -400.429962) (xy 414.271551 -400.429962)
			(xy 414.325535 -400.437724) (xy 414.377865 -400.453089) (xy 414.427475 -400.475746) (xy 414.473356 -400.505232)
			(xy 414.514573 -400.540947) (xy 414.550288 -400.582164) (xy 414.579774 -400.628045) (xy 414.602431 -400.677655)
			(xy 414.617796 -400.729985) (xy 414.625558 -400.783969) (xy 414.626044 -400.811238) (xy 414.626044 -401.674838)
			(xy 415.062924 -401.674838) (xy 415.062924 -400.811238) (xy 415.06341 -400.783987) (xy 415.071166 -400.730039)
			(xy 415.086521 -400.677744) (xy 415.109163 -400.628167) (xy 415.138629 -400.582317) (xy 415.17432 -400.541126)
			(xy 415.215511 -400.505435) (xy 415.261361 -400.475969) (xy 415.310938 -400.453327) (xy 415.363233 -400.437972)
			(xy 415.417181 -400.430216) (xy 415.471683 -400.430216) (xy 415.525631 -400.437972) (xy 415.577926 -400.453327)
			(xy 415.627503 -400.475969) (xy 415.673353 -400.505435) (xy 415.714544 -400.541126) (xy 415.750235 -400.582317)
			(xy 415.779701 -400.628167) (xy 415.802343 -400.677744) (xy 415.817698 -400.730039) (xy 415.825454 -400.783987)
			(xy 415.82594 -400.811238) (xy 415.82594 -401.674838) (xy 416.26282 -401.674838) (xy 416.26282 -400.811238)
			(xy 416.263306 -400.783987) (xy 416.271062 -400.730039) (xy 416.286417 -400.677744) (xy 416.309059 -400.628167)
			(xy 416.338525 -400.582317) (xy 416.374216 -400.541126) (xy 416.415407 -400.505435) (xy 416.461257 -400.475969)
			(xy 416.510834 -400.453327) (xy 416.563129 -400.437972) (xy 416.617077 -400.430216) (xy 416.671579 -400.430216)
			(xy 416.725527 -400.437972) (xy 416.777822 -400.453327) (xy 416.827399 -400.475969) (xy 416.873249 -400.505435)
			(xy 416.91444 -400.541126) (xy 416.950131 -400.582317) (xy 416.979597 -400.628167) (xy 417.002239 -400.677744)
			(xy 417.017594 -400.730039) (xy 417.02535 -400.783987) (xy 417.025836 -400.811238) (xy 417.025836 -401.674838)
			(xy 417.462716 -401.674838) (xy 417.462716 -400.811238) (xy 417.463202 -400.783987) (xy 417.470958 -400.730039)
			(xy 417.486313 -400.677744) (xy 417.508955 -400.628167) (xy 417.538421 -400.582317) (xy 417.574112 -400.541126)
			(xy 417.615303 -400.505435) (xy 417.661153 -400.475969) (xy 417.71073 -400.453327) (xy 417.763025 -400.437972)
			(xy 417.816973 -400.430216) (xy 417.871475 -400.430216) (xy 417.925423 -400.437972) (xy 417.977718 -400.453327)
			(xy 418.027295 -400.475969) (xy 418.073145 -400.505435) (xy 418.114336 -400.541126) (xy 418.150027 -400.582317)
			(xy 418.179493 -400.628167) (xy 418.202135 -400.677744) (xy 418.21749 -400.730039) (xy 418.225246 -400.783987)
			(xy 418.225732 -400.811238) (xy 418.225732 -401.674838) (xy 418.662612 -401.674838) (xy 418.662612 -400.811238)
			(xy 418.663098 -400.783987) (xy 418.670854 -400.730039) (xy 418.686209 -400.677744) (xy 418.708851 -400.628167)
			(xy 418.738317 -400.582317) (xy 418.774008 -400.541126) (xy 418.815199 -400.505435) (xy 418.861049 -400.475969)
			(xy 418.910626 -400.453327) (xy 418.962921 -400.437972) (xy 419.016869 -400.430216) (xy 419.071371 -400.430216)
			(xy 419.125319 -400.437972) (xy 419.177614 -400.453327) (xy 419.227191 -400.475969) (xy 419.273041 -400.505435)
			(xy 419.314232 -400.541126) (xy 419.349923 -400.582317) (xy 419.379389 -400.628167) (xy 419.402031 -400.677744)
			(xy 419.417386 -400.730039) (xy 419.425142 -400.783987) (xy 419.425628 -400.811238) (xy 419.425628 -401.674838)
			(xy 419.862508 -401.674838) (xy 419.862508 -400.811238) (xy 419.862994 -400.783969) (xy 419.870756 -400.729985)
			(xy 419.886121 -400.677655) (xy 419.908778 -400.628045) (xy 419.938264 -400.582164) (xy 419.973979 -400.540947)
			(xy 420.015196 -400.505232) (xy 420.061077 -400.475746) (xy 420.110687 -400.453089) (xy 420.163017 -400.437724)
			(xy 420.217001 -400.429962) (xy 420.271539 -400.429962) (xy 420.325523 -400.437724) (xy 420.377853 -400.453089)
			(xy 420.427463 -400.475746) (xy 420.473344 -400.505232) (xy 420.514561 -400.540947) (xy 420.550276 -400.582164)
			(xy 420.579762 -400.628045) (xy 420.602419 -400.677655) (xy 420.617784 -400.729985) (xy 420.625546 -400.783969)
			(xy 420.626032 -400.811238) (xy 420.626032 -401.674838) (xy 421.062404 -401.674838) (xy 421.062404 -400.811238)
			(xy 421.06289 -400.783969) (xy 421.070652 -400.729985) (xy 421.086017 -400.677655) (xy 421.108674 -400.628045)
			(xy 421.13816 -400.582164) (xy 421.173875 -400.540947) (xy 421.215092 -400.505232) (xy 421.260973 -400.475746)
			(xy 421.310583 -400.453089) (xy 421.362913 -400.437724) (xy 421.416897 -400.429962) (xy 421.471435 -400.429962)
			(xy 421.525419 -400.437724) (xy 421.577749 -400.453089) (xy 421.627359 -400.475746) (xy 421.67324 -400.505232)
			(xy 421.714457 -400.540947) (xy 421.750172 -400.582164) (xy 421.779658 -400.628045) (xy 421.802315 -400.677655)
			(xy 421.81768 -400.729985) (xy 421.825442 -400.783969) (xy 421.825928 -400.811238) (xy 421.825928 -401.674838)
			(xy 421.825442 -401.702107) (xy 421.81768 -401.756091) (xy 421.802315 -401.808421) (xy 421.779658 -401.858031)
			(xy 421.750172 -401.903912) (xy 421.714457 -401.945129) (xy 421.67324 -401.980844) (xy 421.627359 -402.01033)
			(xy 421.577749 -402.032987) (xy 421.525419 -402.048352) (xy 421.471435 -402.056114) (xy 421.416897 -402.056114)
			(xy 421.362913 -402.048352) (xy 421.310583 -402.032987) (xy 421.260973 -402.01033) (xy 421.215092 -401.980844)
			(xy 421.173875 -401.945129) (xy 421.13816 -401.903912) (xy 421.108674 -401.858031) (xy 421.086017 -401.808421)
			(xy 421.070652 -401.756091) (xy 421.06289 -401.702107) (xy 421.062404 -401.674838) (xy 420.626032 -401.674838)
			(xy 420.625546 -401.702107) (xy 420.617784 -401.756091) (xy 420.602419 -401.808421) (xy 420.579762 -401.858031)
			(xy 420.550276 -401.903912) (xy 420.514561 -401.945129) (xy 420.473344 -401.980844) (xy 420.427463 -402.01033)
			(xy 420.377853 -402.032987) (xy 420.325523 -402.048352) (xy 420.271539 -402.056114) (xy 420.217001 -402.056114)
			(xy 420.163017 -402.048352) (xy 420.110687 -402.032987) (xy 420.061077 -402.01033) (xy 420.015196 -401.980844)
			(xy 419.973979 -401.945129) (xy 419.938264 -401.903912) (xy 419.908778 -401.858031) (xy 419.886121 -401.808421)
			(xy 419.870756 -401.756091) (xy 419.862994 -401.702107) (xy 419.862508 -401.674838) (xy 419.425628 -401.674838)
			(xy 419.425142 -401.702089) (xy 419.417386 -401.756037) (xy 419.402031 -401.808332) (xy 419.379389 -401.857909)
			(xy 419.349923 -401.903759) (xy 419.314232 -401.94495) (xy 419.273041 -401.980641) (xy 419.227191 -402.010107)
			(xy 419.177614 -402.032749) (xy 419.125319 -402.048104) (xy 419.071371 -402.05586) (xy 419.016869 -402.05586)
			(xy 418.962921 -402.048104) (xy 418.910626 -402.032749) (xy 418.861049 -402.010107) (xy 418.815199 -401.980641)
			(xy 418.774008 -401.94495) (xy 418.738317 -401.903759) (xy 418.708851 -401.857909) (xy 418.686209 -401.808332)
			(xy 418.670854 -401.756037) (xy 418.663098 -401.702089) (xy 418.662612 -401.674838) (xy 418.225732 -401.674838)
			(xy 418.225246 -401.702089) (xy 418.21749 -401.756037) (xy 418.202135 -401.808332) (xy 418.179493 -401.857909)
			(xy 418.150027 -401.903759) (xy 418.114336 -401.94495) (xy 418.073145 -401.980641) (xy 418.027295 -402.010107)
			(xy 417.977718 -402.032749) (xy 417.925423 -402.048104) (xy 417.871475 -402.05586) (xy 417.816973 -402.05586)
			(xy 417.763025 -402.048104) (xy 417.71073 -402.032749) (xy 417.661153 -402.010107) (xy 417.615303 -401.980641)
			(xy 417.574112 -401.94495) (xy 417.538421 -401.903759) (xy 417.508955 -401.857909) (xy 417.486313 -401.808332)
			(xy 417.470958 -401.756037) (xy 417.463202 -401.702089) (xy 417.462716 -401.674838) (xy 417.025836 -401.674838)
			(xy 417.02535 -401.702089) (xy 417.017594 -401.756037) (xy 417.002239 -401.808332) (xy 416.979597 -401.857909)
			(xy 416.950131 -401.903759) (xy 416.91444 -401.94495) (xy 416.873249 -401.980641) (xy 416.827399 -402.010107)
			(xy 416.777822 -402.032749) (xy 416.725527 -402.048104) (xy 416.671579 -402.05586) (xy 416.617077 -402.05586)
			(xy 416.563129 -402.048104) (xy 416.510834 -402.032749) (xy 416.461257 -402.010107) (xy 416.415407 -401.980641)
			(xy 416.374216 -401.94495) (xy 416.338525 -401.903759) (xy 416.309059 -401.857909) (xy 416.286417 -401.808332)
			(xy 416.271062 -401.756037) (xy 416.263306 -401.702089) (xy 416.26282 -401.674838) (xy 415.82594 -401.674838)
			(xy 415.825454 -401.702089) (xy 415.817698 -401.756037) (xy 415.802343 -401.808332) (xy 415.779701 -401.857909)
			(xy 415.750235 -401.903759) (xy 415.714544 -401.94495) (xy 415.673353 -401.980641) (xy 415.627503 -402.010107)
			(xy 415.577926 -402.032749) (xy 415.525631 -402.048104) (xy 415.471683 -402.05586) (xy 415.417181 -402.05586)
			(xy 415.363233 -402.048104) (xy 415.310938 -402.032749) (xy 415.261361 -402.010107) (xy 415.215511 -401.980641)
			(xy 415.17432 -401.94495) (xy 415.138629 -401.903759) (xy 415.109163 -401.857909) (xy 415.086521 -401.808332)
			(xy 415.071166 -401.756037) (xy 415.06341 -401.702089) (xy 415.062924 -401.674838) (xy 414.626044 -401.674838)
			(xy 414.625558 -401.702107) (xy 414.617796 -401.756091) (xy 414.602431 -401.808421) (xy 414.579774 -401.858031)
			(xy 414.550288 -401.903912) (xy 414.514573 -401.945129) (xy 414.473356 -401.980844) (xy 414.427475 -402.01033)
			(xy 414.377865 -402.032987) (xy 414.325535 -402.048352) (xy 414.271551 -402.056114) (xy 414.217013 -402.056114)
			(xy 414.163029 -402.048352) (xy 414.110699 -402.032987) (xy 414.061089 -402.01033) (xy 414.015208 -401.980844)
			(xy 413.973991 -401.945129) (xy 413.938276 -401.903912) (xy 413.90879 -401.858031) (xy 413.886133 -401.808421)
			(xy 413.870768 -401.756091) (xy 413.863006 -401.702107) (xy 413.86252 -401.674838) (xy 413.426148 -401.674838)
			(xy 413.425662 -401.702107) (xy 413.4179 -401.756091) (xy 413.402535 -401.808421) (xy 413.379878 -401.858031)
			(xy 413.350392 -401.903912) (xy 413.314677 -401.945129) (xy 413.27346 -401.980844) (xy 413.227579 -402.01033)
			(xy 413.177969 -402.032987) (xy 413.125639 -402.048352) (xy 413.071655 -402.056114) (xy 413.017117 -402.056114)
			(xy 412.963133 -402.048352) (xy 412.910803 -402.032987) (xy 412.861193 -402.01033) (xy 412.815312 -401.980844)
			(xy 412.774095 -401.945129) (xy 412.73838 -401.903912) (xy 412.708894 -401.858031) (xy 412.686237 -401.808421)
			(xy 412.670872 -401.756091) (xy 412.66311 -401.702107) (xy 412.662624 -401.674838) (xy 412.225744 -401.674838)
			(xy 412.225258 -401.702089) (xy 412.217502 -401.756037) (xy 412.202147 -401.808332) (xy 412.179505 -401.857909)
			(xy 412.150039 -401.903759) (xy 412.114348 -401.94495) (xy 412.073157 -401.980641) (xy 412.027307 -402.010107)
			(xy 411.97773 -402.032749) (xy 411.925435 -402.048104) (xy 411.871487 -402.05586) (xy 411.816985 -402.05586)
			(xy 411.763037 -402.048104) (xy 411.710742 -402.032749) (xy 411.661165 -402.010107) (xy 411.615315 -401.980641)
			(xy 411.574124 -401.94495) (xy 411.538433 -401.903759) (xy 411.508967 -401.857909) (xy 411.486325 -401.808332)
			(xy 411.47097 -401.756037) (xy 411.463214 -401.702089) (xy 411.462728 -401.674838) (xy 411.025848 -401.674838)
			(xy 411.025362 -401.702089) (xy 411.017606 -401.756037) (xy 411.002251 -401.808332) (xy 410.979609 -401.857909)
			(xy 410.950143 -401.903759) (xy 410.914452 -401.94495) (xy 410.873261 -401.980641) (xy 410.827411 -402.010107)
			(xy 410.777834 -402.032749) (xy 410.725539 -402.048104) (xy 410.671591 -402.05586) (xy 410.617089 -402.05586)
			(xy 410.563141 -402.048104) (xy 410.510846 -402.032749) (xy 410.461269 -402.010107) (xy 410.415419 -401.980641)
			(xy 410.374228 -401.94495) (xy 410.338537 -401.903759) (xy 410.309071 -401.857909) (xy 410.286429 -401.808332)
			(xy 410.271074 -401.756037) (xy 410.263318 -401.702089) (xy 410.262832 -401.674838) (xy 409.825952 -401.674838)
			(xy 409.825466 -401.702107) (xy 409.817704 -401.756091) (xy 409.802339 -401.808421) (xy 409.779682 -401.858031)
			(xy 409.750196 -401.903912) (xy 409.714481 -401.945129) (xy 409.673264 -401.980844) (xy 409.627383 -402.01033)
			(xy 409.577773 -402.032987) (xy 409.525443 -402.048352) (xy 409.471459 -402.056114) (xy 409.416921 -402.056114)
			(xy 409.362937 -402.048352) (xy 409.310607 -402.032987) (xy 409.260997 -402.01033) (xy 409.215116 -401.980844)
			(xy 409.173899 -401.945129) (xy 409.138184 -401.903912) (xy 409.108698 -401.858031) (xy 409.086041 -401.808421)
			(xy 409.070676 -401.756091) (xy 409.062914 -401.702107) (xy 409.062428 -401.674838) (xy 408.626056 -401.674838)
			(xy 408.62557 -401.702107) (xy 408.617808 -401.756091) (xy 408.602443 -401.808421) (xy 408.579786 -401.858031)
			(xy 408.5503 -401.903912) (xy 408.514585 -401.945129) (xy 408.473368 -401.980844) (xy 408.427487 -402.01033)
			(xy 408.377877 -402.032987) (xy 408.325547 -402.048352) (xy 408.271563 -402.056114) (xy 408.217025 -402.056114)
			(xy 408.163041 -402.048352) (xy 408.110711 -402.032987) (xy 408.061101 -402.01033) (xy 408.01522 -401.980844)
			(xy 407.974003 -401.945129) (xy 407.938288 -401.903912) (xy 407.908802 -401.858031) (xy 407.886145 -401.808421)
			(xy 407.87078 -401.756091) (xy 407.863018 -401.702107) (xy 407.862532 -401.674838) (xy 407.425652 -401.674838)
			(xy 407.425166 -401.702089) (xy 407.41741 -401.756037) (xy 407.402055 -401.808332) (xy 407.379413 -401.857909)
			(xy 407.349947 -401.903759) (xy 407.314256 -401.94495) (xy 407.273065 -401.980641) (xy 407.227215 -402.010107)
			(xy 407.177638 -402.032749) (xy 407.125343 -402.048104) (xy 407.071395 -402.05586) (xy 407.016893 -402.05586)
			(xy 406.962945 -402.048104) (xy 406.91065 -402.032749) (xy 406.861073 -402.010107) (xy 406.815223 -401.980641)
			(xy 406.774032 -401.94495) (xy 406.738341 -401.903759) (xy 406.708875 -401.857909) (xy 406.686233 -401.808332)
			(xy 406.670878 -401.756037) (xy 406.663122 -401.702089) (xy 406.662636 -401.674838) (xy 406.225756 -401.674838)
			(xy 406.22527 -401.702089) (xy 406.217514 -401.756037) (xy 406.202159 -401.808332) (xy 406.179517 -401.857909)
			(xy 406.150051 -401.903759) (xy 406.11436 -401.94495) (xy 406.073169 -401.980641) (xy 406.027319 -402.010107)
			(xy 405.977742 -402.032749) (xy 405.925447 -402.048104) (xy 405.871499 -402.05586) (xy 405.816997 -402.05586)
			(xy 405.763049 -402.048104) (xy 405.710754 -402.032749) (xy 405.661177 -402.010107) (xy 405.615327 -401.980641)
			(xy 405.574136 -401.94495) (xy 405.538445 -401.903759) (xy 405.508979 -401.857909) (xy 405.486337 -401.808332)
			(xy 405.470982 -401.756037) (xy 405.463226 -401.702089) (xy 405.46274 -401.674838) (xy 405.02586 -401.674838)
			(xy 405.025374 -401.702107) (xy 405.017612 -401.756091) (xy 405.002247 -401.808421) (xy 404.97959 -401.858031)
			(xy 404.950104 -401.903912) (xy 404.914389 -401.945129) (xy 404.873172 -401.980844) (xy 404.827291 -402.01033)
			(xy 404.777681 -402.032987) (xy 404.725351 -402.048352) (xy 404.671367 -402.056114) (xy 404.616829 -402.056114)
			(xy 404.562845 -402.048352) (xy 404.510515 -402.032987) (xy 404.460905 -402.01033) (xy 404.415024 -401.980844)
			(xy 404.373807 -401.945129) (xy 404.338092 -401.903912) (xy 404.308606 -401.858031) (xy 404.285949 -401.808421)
			(xy 404.270584 -401.756091) (xy 404.262822 -401.702107) (xy 404.262336 -401.674838) (xy 403.825964 -401.674838)
			(xy 403.825478 -401.702107) (xy 403.817716 -401.756091) (xy 403.802351 -401.808421) (xy 403.779694 -401.858031)
			(xy 403.750208 -401.903912) (xy 403.714493 -401.945129) (xy 403.673276 -401.980844) (xy 403.627395 -402.01033)
			(xy 403.577785 -402.032987) (xy 403.525455 -402.048352) (xy 403.471471 -402.056114) (xy 403.416933 -402.056114)
			(xy 403.362949 -402.048352) (xy 403.310619 -402.032987) (xy 403.261009 -402.01033) (xy 403.215128 -401.980844)
			(xy 403.173911 -401.945129) (xy 403.138196 -401.903912) (xy 403.10871 -401.858031) (xy 403.086053 -401.808421)
			(xy 403.070688 -401.756091) (xy 403.062926 -401.702107) (xy 403.06244 -401.674838) (xy 389.29818 -401.674838)
			(xy 389.297694 -401.702107) (xy 389.289932 -401.756091) (xy 389.274567 -401.808421) (xy 389.25191 -401.858031)
			(xy 389.222424 -401.903912) (xy 389.186709 -401.945129) (xy 389.145492 -401.980844) (xy 389.099611 -402.01033)
			(xy 389.050001 -402.032987) (xy 388.997671 -402.048352) (xy 388.943687 -402.056114) (xy 388.889149 -402.056114)
			(xy 388.835165 -402.048352) (xy 388.782835 -402.032987) (xy 388.733225 -402.01033) (xy 388.687344 -401.980844)
			(xy 388.646127 -401.945129) (xy 388.610412 -401.903912) (xy 388.580926 -401.858031) (xy 388.558269 -401.808421)
			(xy 388.542904 -401.756091) (xy 388.535142 -401.702107) (xy 388.534656 -401.674838) (xy 388.098284 -401.674838)
			(xy 388.097798 -401.702107) (xy 388.090036 -401.756091) (xy 388.074671 -401.808421) (xy 388.052014 -401.858031)
			(xy 388.022528 -401.903912) (xy 387.986813 -401.945129) (xy 387.945596 -401.980844) (xy 387.899715 -402.01033)
			(xy 387.850105 -402.032987) (xy 387.797775 -402.048352) (xy 387.743791 -402.056114) (xy 387.689253 -402.056114)
			(xy 387.635269 -402.048352) (xy 387.582939 -402.032987) (xy 387.533329 -402.01033) (xy 387.487448 -401.980844)
			(xy 387.446231 -401.945129) (xy 387.410516 -401.903912) (xy 387.38103 -401.858031) (xy 387.358373 -401.808421)
			(xy 387.343008 -401.756091) (xy 387.335246 -401.702107) (xy 387.33476 -401.674838) (xy 386.89788 -401.674838)
			(xy 386.897394 -401.702089) (xy 386.889638 -401.756037) (xy 386.874283 -401.808332) (xy 386.851641 -401.857909)
			(xy 386.822175 -401.903759) (xy 386.786484 -401.94495) (xy 386.745293 -401.980641) (xy 386.699443 -402.010107)
			(xy 386.649866 -402.032749) (xy 386.597571 -402.048104) (xy 386.543623 -402.05586) (xy 386.489121 -402.05586)
			(xy 386.435173 -402.048104) (xy 386.382878 -402.032749) (xy 386.333301 -402.010107) (xy 386.287451 -401.980641)
			(xy 386.24626 -401.94495) (xy 386.210569 -401.903759) (xy 386.181103 -401.857909) (xy 386.158461 -401.808332)
			(xy 386.143106 -401.756037) (xy 386.13535 -401.702089) (xy 386.134864 -401.674838) (xy 385.697984 -401.674838)
			(xy 385.697498 -401.702089) (xy 385.689742 -401.756037) (xy 385.674387 -401.808332) (xy 385.651745 -401.857909)
			(xy 385.622279 -401.903759) (xy 385.586588 -401.94495) (xy 385.545397 -401.980641) (xy 385.499547 -402.010107)
			(xy 385.44997 -402.032749) (xy 385.397675 -402.048104) (xy 385.343727 -402.05586) (xy 385.289225 -402.05586)
			(xy 385.235277 -402.048104) (xy 385.182982 -402.032749) (xy 385.133405 -402.010107) (xy 385.087555 -401.980641)
			(xy 385.046364 -401.94495) (xy 385.010673 -401.903759) (xy 384.981207 -401.857909) (xy 384.958565 -401.808332)
			(xy 384.94321 -401.756037) (xy 384.935454 -401.702089) (xy 384.934968 -401.674838) (xy 384.498088 -401.674838)
			(xy 384.497602 -401.702089) (xy 384.489846 -401.756037) (xy 384.474491 -401.808332) (xy 384.451849 -401.857909)
			(xy 384.422383 -401.903759) (xy 384.386692 -401.94495) (xy 384.345501 -401.980641) (xy 384.299651 -402.010107)
			(xy 384.250074 -402.032749) (xy 384.197779 -402.048104) (xy 384.143831 -402.05586) (xy 384.089329 -402.05586)
			(xy 384.035381 -402.048104) (xy 383.983086 -402.032749) (xy 383.933509 -402.010107) (xy 383.887659 -401.980641)
			(xy 383.846468 -401.94495) (xy 383.810777 -401.903759) (xy 383.781311 -401.857909) (xy 383.758669 -401.808332)
			(xy 383.743314 -401.756037) (xy 383.735558 -401.702089) (xy 383.735072 -401.674838) (xy 383.298192 -401.674838)
			(xy 383.297706 -401.702089) (xy 383.28995 -401.756037) (xy 383.274595 -401.808332) (xy 383.251953 -401.857909)
			(xy 383.222487 -401.903759) (xy 383.186796 -401.94495) (xy 383.145605 -401.980641) (xy 383.099755 -402.010107)
			(xy 383.050178 -402.032749) (xy 382.997883 -402.048104) (xy 382.943935 -402.05586) (xy 382.889433 -402.05586)
			(xy 382.835485 -402.048104) (xy 382.78319 -402.032749) (xy 382.733613 -402.010107) (xy 382.687763 -401.980641)
			(xy 382.646572 -401.94495) (xy 382.610881 -401.903759) (xy 382.581415 -401.857909) (xy 382.558773 -401.808332)
			(xy 382.543418 -401.756037) (xy 382.535662 -401.702089) (xy 382.535176 -401.674838) (xy 382.098296 -401.674838)
			(xy 382.09781 -401.702107) (xy 382.090048 -401.756091) (xy 382.074683 -401.808421) (xy 382.052026 -401.858031)
			(xy 382.02254 -401.903912) (xy 381.986825 -401.945129) (xy 381.945608 -401.980844) (xy 381.899727 -402.01033)
			(xy 381.850117 -402.032987) (xy 381.797787 -402.048352) (xy 381.743803 -402.056114) (xy 381.689265 -402.056114)
			(xy 381.635281 -402.048352) (xy 381.582951 -402.032987) (xy 381.533341 -402.01033) (xy 381.48746 -401.980844)
			(xy 381.446243 -401.945129) (xy 381.410528 -401.903912) (xy 381.381042 -401.858031) (xy 381.358385 -401.808421)
			(xy 381.34302 -401.756091) (xy 381.335258 -401.702107) (xy 381.334772 -401.674838) (xy 380.8984 -401.674838)
			(xy 380.897914 -401.702107) (xy 380.890152 -401.756091) (xy 380.874787 -401.808421) (xy 380.85213 -401.858031)
			(xy 380.822644 -401.903912) (xy 380.786929 -401.945129) (xy 380.745712 -401.980844) (xy 380.699831 -402.01033)
			(xy 380.650221 -402.032987) (xy 380.597891 -402.048352) (xy 380.543907 -402.056114) (xy 380.489369 -402.056114)
			(xy 380.435385 -402.048352) (xy 380.383055 -402.032987) (xy 380.333445 -402.01033) (xy 380.287564 -401.980844)
			(xy 380.246347 -401.945129) (xy 380.210632 -401.903912) (xy 380.181146 -401.858031) (xy 380.158489 -401.808421)
			(xy 380.143124 -401.756091) (xy 380.135362 -401.702107) (xy 380.134876 -401.674838) (xy 379.697996 -401.674838)
			(xy 379.69751 -401.702089) (xy 379.689754 -401.756037) (xy 379.674399 -401.808332) (xy 379.651757 -401.857909)
			(xy 379.622291 -401.903759) (xy 379.5866 -401.94495) (xy 379.545409 -401.980641) (xy 379.499559 -402.010107)
			(xy 379.449982 -402.032749) (xy 379.397687 -402.048104) (xy 379.343739 -402.05586) (xy 379.289237 -402.05586)
			(xy 379.235289 -402.048104) (xy 379.182994 -402.032749) (xy 379.133417 -402.010107) (xy 379.087567 -401.980641)
			(xy 379.046376 -401.94495) (xy 379.010685 -401.903759) (xy 378.981219 -401.857909) (xy 378.958577 -401.808332)
			(xy 378.943222 -401.756037) (xy 378.935466 -401.702089) (xy 378.93498 -401.674838) (xy 378.4981 -401.674838)
			(xy 378.497614 -401.702089) (xy 378.489858 -401.756037) (xy 378.474503 -401.808332) (xy 378.451861 -401.857909)
			(xy 378.422395 -401.903759) (xy 378.386704 -401.94495) (xy 378.345513 -401.980641) (xy 378.299663 -402.010107)
			(xy 378.250086 -402.032749) (xy 378.197791 -402.048104) (xy 378.143843 -402.05586) (xy 378.089341 -402.05586)
			(xy 378.035393 -402.048104) (xy 377.983098 -402.032749) (xy 377.933521 -402.010107) (xy 377.887671 -401.980641)
			(xy 377.84648 -401.94495) (xy 377.810789 -401.903759) (xy 377.781323 -401.857909) (xy 377.758681 -401.808332)
			(xy 377.743326 -401.756037) (xy 377.73557 -401.702089) (xy 377.735084 -401.674838) (xy 377.298204 -401.674838)
			(xy 377.297718 -401.702107) (xy 377.289956 -401.756091) (xy 377.274591 -401.808421) (xy 377.251934 -401.858031)
			(xy 377.222448 -401.903912) (xy 377.186733 -401.945129) (xy 377.145516 -401.980844) (xy 377.099635 -402.01033)
			(xy 377.050025 -402.032987) (xy 376.997695 -402.048352) (xy 376.943711 -402.056114) (xy 376.889173 -402.056114)
			(xy 376.835189 -402.048352) (xy 376.782859 -402.032987) (xy 376.733249 -402.01033) (xy 376.687368 -401.980844)
			(xy 376.646151 -401.945129) (xy 376.610436 -401.903912) (xy 376.58095 -401.858031) (xy 376.558293 -401.808421)
			(xy 376.542928 -401.756091) (xy 376.535166 -401.702107) (xy 376.53468 -401.674838) (xy 376.098308 -401.674838)
			(xy 376.097822 -401.702107) (xy 376.09006 -401.756091) (xy 376.074695 -401.808421) (xy 376.052038 -401.858031)
			(xy 376.022552 -401.903912) (xy 375.986837 -401.945129) (xy 375.94562 -401.980844) (xy 375.899739 -402.01033)
			(xy 375.850129 -402.032987) (xy 375.797799 -402.048352) (xy 375.743815 -402.056114) (xy 375.689277 -402.056114)
			(xy 375.635293 -402.048352) (xy 375.582963 -402.032987) (xy 375.533353 -402.01033) (xy 375.487472 -401.980844)
			(xy 375.446255 -401.945129) (xy 375.41054 -401.903912) (xy 375.381054 -401.858031) (xy 375.358397 -401.808421)
			(xy 375.343032 -401.756091) (xy 375.33527 -401.702107) (xy 375.334784 -401.674838) (xy 374.897904 -401.674838)
			(xy 374.897418 -401.702089) (xy 374.889662 -401.756037) (xy 374.874307 -401.808332) (xy 374.851665 -401.857909)
			(xy 374.822199 -401.903759) (xy 374.786508 -401.94495) (xy 374.745317 -401.980641) (xy 374.699467 -402.010107)
			(xy 374.64989 -402.032749) (xy 374.597595 -402.048104) (xy 374.543647 -402.05586) (xy 374.489145 -402.05586)
			(xy 374.435197 -402.048104) (xy 374.382902 -402.032749) (xy 374.333325 -402.010107) (xy 374.287475 -401.980641)
			(xy 374.246284 -401.94495) (xy 374.210593 -401.903759) (xy 374.181127 -401.857909) (xy 374.158485 -401.808332)
			(xy 374.14313 -401.756037) (xy 374.135374 -401.702089) (xy 374.134888 -401.674838) (xy 373.698008 -401.674838)
			(xy 373.697522 -401.702089) (xy 373.689766 -401.756037) (xy 373.674411 -401.808332) (xy 373.651769 -401.857909)
			(xy 373.622303 -401.903759) (xy 373.586612 -401.94495) (xy 373.545421 -401.980641) (xy 373.499571 -402.010107)
			(xy 373.449994 -402.032749) (xy 373.397699 -402.048104) (xy 373.343751 -402.05586) (xy 373.289249 -402.05586)
			(xy 373.235301 -402.048104) (xy 373.183006 -402.032749) (xy 373.133429 -402.010107) (xy 373.087579 -401.980641)
			(xy 373.046388 -401.94495) (xy 373.010697 -401.903759) (xy 372.981231 -401.857909) (xy 372.958589 -401.808332)
			(xy 372.943234 -401.756037) (xy 372.935478 -401.702089) (xy 372.934992 -401.674838) (xy 372.498112 -401.674838)
			(xy 372.497626 -401.702107) (xy 372.489864 -401.756091) (xy 372.474499 -401.808421) (xy 372.451842 -401.858031)
			(xy 372.422356 -401.903912) (xy 372.386641 -401.945129) (xy 372.345424 -401.980844) (xy 372.299543 -402.01033)
			(xy 372.249933 -402.032987) (xy 372.197603 -402.048352) (xy 372.143619 -402.056114) (xy 372.089081 -402.056114)
			(xy 372.035097 -402.048352) (xy 371.982767 -402.032987) (xy 371.933157 -402.01033) (xy 371.887276 -401.980844)
			(xy 371.846059 -401.945129) (xy 371.810344 -401.903912) (xy 371.780858 -401.858031) (xy 371.758201 -401.808421)
			(xy 371.742836 -401.756091) (xy 371.735074 -401.702107) (xy 371.734588 -401.674838) (xy 371.298216 -401.674838)
			(xy 371.29773 -401.702107) (xy 371.289968 -401.756091) (xy 371.274603 -401.808421) (xy 371.251946 -401.858031)
			(xy 371.22246 -401.903912) (xy 371.186745 -401.945129) (xy 371.145528 -401.980844) (xy 371.099647 -402.01033)
			(xy 371.050037 -402.032987) (xy 370.997707 -402.048352) (xy 370.943723 -402.056114) (xy 370.889185 -402.056114)
			(xy 370.835201 -402.048352) (xy 370.782871 -402.032987) (xy 370.733261 -402.01033) (xy 370.68738 -401.980844)
			(xy 370.646163 -401.945129) (xy 370.610448 -401.903912) (xy 370.580962 -401.858031) (xy 370.558305 -401.808421)
			(xy 370.54294 -401.756091) (xy 370.535178 -401.702107) (xy 370.534692 -401.674838) (xy 354.725732 -401.674838)
			(xy 354.725246 -401.702107) (xy 354.717484 -401.756091) (xy 354.702119 -401.808421) (xy 354.679462 -401.858031)
			(xy 354.649976 -401.903912) (xy 354.614261 -401.945129) (xy 354.573044 -401.980844) (xy 354.527163 -402.01033)
			(xy 354.477553 -402.032987) (xy 354.425223 -402.048352) (xy 354.371239 -402.056114) (xy 354.316701 -402.056114)
			(xy 354.262717 -402.048352) (xy 354.210387 -402.032987) (xy 354.160777 -402.01033) (xy 354.114896 -401.980844)
			(xy 354.073679 -401.945129) (xy 354.037964 -401.903912) (xy 354.008478 -401.858031) (xy 353.985821 -401.808421)
			(xy 353.970456 -401.756091) (xy 353.962694 -401.702107) (xy 353.962208 -401.674838) (xy 353.525836 -401.674838)
			(xy 353.52535 -401.702107) (xy 353.517588 -401.756091) (xy 353.502223 -401.808421) (xy 353.479566 -401.858031)
			(xy 353.45008 -401.903912) (xy 353.414365 -401.945129) (xy 353.373148 -401.980844) (xy 353.327267 -402.01033)
			(xy 353.277657 -402.032987) (xy 353.225327 -402.048352) (xy 353.171343 -402.056114) (xy 353.116805 -402.056114)
			(xy 353.062821 -402.048352) (xy 353.010491 -402.032987) (xy 352.960881 -402.01033) (xy 352.915 -401.980844)
			(xy 352.873783 -401.945129) (xy 352.838068 -401.903912) (xy 352.808582 -401.858031) (xy 352.785925 -401.808421)
			(xy 352.77056 -401.756091) (xy 352.762798 -401.702107) (xy 352.762312 -401.674838) (xy 352.325432 -401.674838)
			(xy 352.324946 -401.702089) (xy 352.31719 -401.756037) (xy 352.301835 -401.808332) (xy 352.279193 -401.857909)
			(xy 352.249727 -401.903759) (xy 352.214036 -401.94495) (xy 352.172845 -401.980641) (xy 352.126995 -402.010107)
			(xy 352.077418 -402.032749) (xy 352.025123 -402.048104) (xy 351.971175 -402.05586) (xy 351.916673 -402.05586)
			(xy 351.862725 -402.048104) (xy 351.81043 -402.032749) (xy 351.760853 -402.010107) (xy 351.715003 -401.980641)
			(xy 351.673812 -401.94495) (xy 351.638121 -401.903759) (xy 351.608655 -401.857909) (xy 351.586013 -401.808332)
			(xy 351.570658 -401.756037) (xy 351.562902 -401.702089) (xy 351.562416 -401.674838) (xy 351.125536 -401.674838)
			(xy 351.12505 -401.702089) (xy 351.117294 -401.756037) (xy 351.101939 -401.808332) (xy 351.079297 -401.857909)
			(xy 351.049831 -401.903759) (xy 351.01414 -401.94495) (xy 350.972949 -401.980641) (xy 350.927099 -402.010107)
			(xy 350.877522 -402.032749) (xy 350.825227 -402.048104) (xy 350.771279 -402.05586) (xy 350.716777 -402.05586)
			(xy 350.662829 -402.048104) (xy 350.610534 -402.032749) (xy 350.560957 -402.010107) (xy 350.515107 -401.980641)
			(xy 350.473916 -401.94495) (xy 350.438225 -401.903759) (xy 350.408759 -401.857909) (xy 350.386117 -401.808332)
			(xy 350.370762 -401.756037) (xy 350.363006 -401.702089) (xy 350.36252 -401.674838) (xy 349.92564 -401.674838)
			(xy 349.925154 -401.702089) (xy 349.917398 -401.756037) (xy 349.902043 -401.808332) (xy 349.879401 -401.857909)
			(xy 349.849935 -401.903759) (xy 349.814244 -401.94495) (xy 349.773053 -401.980641) (xy 349.727203 -402.010107)
			(xy 349.677626 -402.032749) (xy 349.625331 -402.048104) (xy 349.571383 -402.05586) (xy 349.516881 -402.05586)
			(xy 349.462933 -402.048104) (xy 349.410638 -402.032749) (xy 349.361061 -402.010107) (xy 349.315211 -401.980641)
			(xy 349.27402 -401.94495) (xy 349.238329 -401.903759) (xy 349.208863 -401.857909) (xy 349.186221 -401.808332)
			(xy 349.170866 -401.756037) (xy 349.16311 -401.702089) (xy 349.162624 -401.674838) (xy 348.725744 -401.674838)
			(xy 348.725258 -401.702089) (xy 348.717502 -401.756037) (xy 348.702147 -401.808332) (xy 348.679505 -401.857909)
			(xy 348.650039 -401.903759) (xy 348.614348 -401.94495) (xy 348.573157 -401.980641) (xy 348.527307 -402.010107)
			(xy 348.47773 -402.032749) (xy 348.425435 -402.048104) (xy 348.371487 -402.05586) (xy 348.316985 -402.05586)
			(xy 348.263037 -402.048104) (xy 348.210742 -402.032749) (xy 348.161165 -402.010107) (xy 348.115315 -401.980641)
			(xy 348.074124 -401.94495) (xy 348.038433 -401.903759) (xy 348.008967 -401.857909) (xy 347.986325 -401.808332)
			(xy 347.97097 -401.756037) (xy 347.963214 -401.702089) (xy 347.962728 -401.674838) (xy 347.525848 -401.674838)
			(xy 347.525362 -401.702107) (xy 347.5176 -401.756091) (xy 347.502235 -401.808421) (xy 347.479578 -401.858031)
			(xy 347.450092 -401.903912) (xy 347.414377 -401.945129) (xy 347.37316 -401.980844) (xy 347.327279 -402.01033)
			(xy 347.277669 -402.032987) (xy 347.225339 -402.048352) (xy 347.171355 -402.056114) (xy 347.116817 -402.056114)
			(xy 347.062833 -402.048352) (xy 347.010503 -402.032987) (xy 346.960893 -402.01033) (xy 346.915012 -401.980844)
			(xy 346.873795 -401.945129) (xy 346.83808 -401.903912) (xy 346.808594 -401.858031) (xy 346.785937 -401.808421)
			(xy 346.770572 -401.756091) (xy 346.76281 -401.702107) (xy 346.762324 -401.674838) (xy 346.325952 -401.674838)
			(xy 346.325466 -401.702107) (xy 346.317704 -401.756091) (xy 346.302339 -401.808421) (xy 346.279682 -401.858031)
			(xy 346.250196 -401.903912) (xy 346.214481 -401.945129) (xy 346.173264 -401.980844) (xy 346.127383 -402.01033)
			(xy 346.077773 -402.032987) (xy 346.025443 -402.048352) (xy 345.971459 -402.056114) (xy 345.916921 -402.056114)
			(xy 345.862937 -402.048352) (xy 345.810607 -402.032987) (xy 345.760997 -402.01033) (xy 345.715116 -401.980844)
			(xy 345.673899 -401.945129) (xy 345.638184 -401.903912) (xy 345.608698 -401.858031) (xy 345.586041 -401.808421)
			(xy 345.570676 -401.756091) (xy 345.562914 -401.702107) (xy 345.562428 -401.674838) (xy 345.125548 -401.674838)
			(xy 345.125062 -401.702089) (xy 345.117306 -401.756037) (xy 345.101951 -401.808332) (xy 345.079309 -401.857909)
			(xy 345.049843 -401.903759) (xy 345.014152 -401.94495) (xy 344.972961 -401.980641) (xy 344.927111 -402.010107)
			(xy 344.877534 -402.032749) (xy 344.825239 -402.048104) (xy 344.771291 -402.05586) (xy 344.716789 -402.05586)
			(xy 344.662841 -402.048104) (xy 344.610546 -402.032749) (xy 344.560969 -402.010107) (xy 344.515119 -401.980641)
			(xy 344.473928 -401.94495) (xy 344.438237 -401.903759) (xy 344.408771 -401.857909) (xy 344.386129 -401.808332)
			(xy 344.370774 -401.756037) (xy 344.363018 -401.702089) (xy 344.362532 -401.674838) (xy 343.925652 -401.674838)
			(xy 343.925166 -401.702089) (xy 343.91741 -401.756037) (xy 343.902055 -401.808332) (xy 343.879413 -401.857909)
			(xy 343.849947 -401.903759) (xy 343.814256 -401.94495) (xy 343.773065 -401.980641) (xy 343.727215 -402.010107)
			(xy 343.677638 -402.032749) (xy 343.625343 -402.048104) (xy 343.571395 -402.05586) (xy 343.516893 -402.05586)
			(xy 343.462945 -402.048104) (xy 343.41065 -402.032749) (xy 343.361073 -402.010107) (xy 343.315223 -401.980641)
			(xy 343.274032 -401.94495) (xy 343.238341 -401.903759) (xy 343.208875 -401.857909) (xy 343.186233 -401.808332)
			(xy 343.170878 -401.756037) (xy 343.163122 -401.702089) (xy 343.162636 -401.674838) (xy 342.725756 -401.674838)
			(xy 342.72527 -401.702107) (xy 342.717508 -401.756091) (xy 342.702143 -401.808421) (xy 342.679486 -401.858031)
			(xy 342.65 -401.903912) (xy 342.614285 -401.945129) (xy 342.573068 -401.980844) (xy 342.527187 -402.01033)
			(xy 342.477577 -402.032987) (xy 342.425247 -402.048352) (xy 342.371263 -402.056114) (xy 342.316725 -402.056114)
			(xy 342.262741 -402.048352) (xy 342.210411 -402.032987) (xy 342.160801 -402.01033) (xy 342.11492 -401.980844)
			(xy 342.073703 -401.945129) (xy 342.037988 -401.903912) (xy 342.008502 -401.858031) (xy 341.985845 -401.808421)
			(xy 341.97048 -401.756091) (xy 341.962718 -401.702107) (xy 341.962232 -401.674838) (xy 341.52586 -401.674838)
			(xy 341.525374 -401.702107) (xy 341.517612 -401.756091) (xy 341.502247 -401.808421) (xy 341.47959 -401.858031)
			(xy 341.450104 -401.903912) (xy 341.414389 -401.945129) (xy 341.373172 -401.980844) (xy 341.327291 -402.01033)
			(xy 341.277681 -402.032987) (xy 341.225351 -402.048352) (xy 341.171367 -402.056114) (xy 341.116829 -402.056114)
			(xy 341.062845 -402.048352) (xy 341.010515 -402.032987) (xy 340.960905 -402.01033) (xy 340.915024 -401.980844)
			(xy 340.873807 -401.945129) (xy 340.838092 -401.903912) (xy 340.808606 -401.858031) (xy 340.785949 -401.808421)
			(xy 340.770584 -401.756091) (xy 340.762822 -401.702107) (xy 340.762336 -401.674838) (xy 340.325456 -401.674838)
			(xy 340.32497 -401.702089) (xy 340.317214 -401.756037) (xy 340.301859 -401.808332) (xy 340.279217 -401.857909)
			(xy 340.249751 -401.903759) (xy 340.21406 -401.94495) (xy 340.172869 -401.980641) (xy 340.127019 -402.010107)
			(xy 340.077442 -402.032749) (xy 340.025147 -402.048104) (xy 339.971199 -402.05586) (xy 339.916697 -402.05586)
			(xy 339.862749 -402.048104) (xy 339.810454 -402.032749) (xy 339.760877 -402.010107) (xy 339.715027 -401.980641)
			(xy 339.673836 -401.94495) (xy 339.638145 -401.903759) (xy 339.608679 -401.857909) (xy 339.586037 -401.808332)
			(xy 339.570682 -401.756037) (xy 339.562926 -401.702089) (xy 339.56244 -401.674838) (xy 339.12556 -401.674838)
			(xy 339.125074 -401.702089) (xy 339.117318 -401.756037) (xy 339.101963 -401.808332) (xy 339.079321 -401.857909)
			(xy 339.049855 -401.903759) (xy 339.014164 -401.94495) (xy 338.972973 -401.980641) (xy 338.927123 -402.010107)
			(xy 338.877546 -402.032749) (xy 338.825251 -402.048104) (xy 338.771303 -402.05586) (xy 338.716801 -402.05586)
			(xy 338.662853 -402.048104) (xy 338.610558 -402.032749) (xy 338.560981 -402.010107) (xy 338.515131 -401.980641)
			(xy 338.47394 -401.94495) (xy 338.438249 -401.903759) (xy 338.408783 -401.857909) (xy 338.386141 -401.808332)
			(xy 338.370786 -401.756037) (xy 338.36303 -401.702089) (xy 338.362544 -401.674838) (xy 337.925664 -401.674838)
			(xy 337.925178 -401.702107) (xy 337.917416 -401.756091) (xy 337.902051 -401.808421) (xy 337.879394 -401.858031)
			(xy 337.849908 -401.903912) (xy 337.814193 -401.945129) (xy 337.772976 -401.980844) (xy 337.727095 -402.01033)
			(xy 337.677485 -402.032987) (xy 337.625155 -402.048352) (xy 337.571171 -402.056114) (xy 337.516633 -402.056114)
			(xy 337.462649 -402.048352) (xy 337.410319 -402.032987) (xy 337.360709 -402.01033) (xy 337.314828 -401.980844)
			(xy 337.273611 -401.945129) (xy 337.237896 -401.903912) (xy 337.20841 -401.858031) (xy 337.185753 -401.808421)
			(xy 337.170388 -401.756091) (xy 337.162626 -401.702107) (xy 337.16214 -401.674838) (xy 336.725768 -401.674838)
			(xy 336.725282 -401.702107) (xy 336.71752 -401.756091) (xy 336.702155 -401.808421) (xy 336.679498 -401.858031)
			(xy 336.650012 -401.903912) (xy 336.614297 -401.945129) (xy 336.57308 -401.980844) (xy 336.527199 -402.01033)
			(xy 336.477589 -402.032987) (xy 336.425259 -402.048352) (xy 336.371275 -402.056114) (xy 336.316737 -402.056114)
			(xy 336.262753 -402.048352) (xy 336.210423 -402.032987) (xy 336.160813 -402.01033) (xy 336.114932 -401.980844)
			(xy 336.073715 -401.945129) (xy 336.038 -401.903912) (xy 336.008514 -401.858031) (xy 335.985857 -401.808421)
			(xy 335.970492 -401.756091) (xy 335.96273 -401.702107) (xy 335.962244 -401.674838) (xy 322.197984 -401.674838)
			(xy 322.197498 -401.702107) (xy 322.189736 -401.756091) (xy 322.174371 -401.808421) (xy 322.151714 -401.858031)
			(xy 322.122228 -401.903912) (xy 322.086513 -401.945129) (xy 322.045296 -401.980844) (xy 321.999415 -402.01033)
			(xy 321.949805 -402.032987) (xy 321.897475 -402.048352) (xy 321.843491 -402.056114) (xy 321.788953 -402.056114)
			(xy 321.734969 -402.048352) (xy 321.682639 -402.032987) (xy 321.633029 -402.01033) (xy 321.587148 -401.980844)
			(xy 321.545931 -401.945129) (xy 321.510216 -401.903912) (xy 321.48073 -401.858031) (xy 321.458073 -401.808421)
			(xy 321.442708 -401.756091) (xy 321.434946 -401.702107) (xy 321.43446 -401.674838) (xy 320.998088 -401.674838)
			(xy 320.997602 -401.702107) (xy 320.98984 -401.756091) (xy 320.974475 -401.808421) (xy 320.951818 -401.858031)
			(xy 320.922332 -401.903912) (xy 320.886617 -401.945129) (xy 320.8454 -401.980844) (xy 320.799519 -402.01033)
			(xy 320.749909 -402.032987) (xy 320.697579 -402.048352) (xy 320.643595 -402.056114) (xy 320.589057 -402.056114)
			(xy 320.535073 -402.048352) (xy 320.482743 -402.032987) (xy 320.433133 -402.01033) (xy 320.387252 -401.980844)
			(xy 320.346035 -401.945129) (xy 320.31032 -401.903912) (xy 320.280834 -401.858031) (xy 320.258177 -401.808421)
			(xy 320.242812 -401.756091) (xy 320.23505 -401.702107) (xy 320.234564 -401.674838) (xy 319.797684 -401.674838)
			(xy 319.797198 -401.702089) (xy 319.789442 -401.756037) (xy 319.774087 -401.808332) (xy 319.751445 -401.857909)
			(xy 319.721979 -401.903759) (xy 319.686288 -401.94495) (xy 319.645097 -401.980641) (xy 319.599247 -402.010107)
			(xy 319.54967 -402.032749) (xy 319.497375 -402.048104) (xy 319.443427 -402.05586) (xy 319.388925 -402.05586)
			(xy 319.334977 -402.048104) (xy 319.282682 -402.032749) (xy 319.233105 -402.010107) (xy 319.187255 -401.980641)
			(xy 319.146064 -401.94495) (xy 319.110373 -401.903759) (xy 319.080907 -401.857909) (xy 319.058265 -401.808332)
			(xy 319.04291 -401.756037) (xy 319.035154 -401.702089) (xy 319.034668 -401.674838) (xy 318.597788 -401.674838)
			(xy 318.597302 -401.702089) (xy 318.589546 -401.756037) (xy 318.574191 -401.808332) (xy 318.551549 -401.857909)
			(xy 318.522083 -401.903759) (xy 318.486392 -401.94495) (xy 318.445201 -401.980641) (xy 318.399351 -402.010107)
			(xy 318.349774 -402.032749) (xy 318.297479 -402.048104) (xy 318.243531 -402.05586) (xy 318.189029 -402.05586)
			(xy 318.135081 -402.048104) (xy 318.082786 -402.032749) (xy 318.033209 -402.010107) (xy 317.987359 -401.980641)
			(xy 317.946168 -401.94495) (xy 317.910477 -401.903759) (xy 317.881011 -401.857909) (xy 317.858369 -401.808332)
			(xy 317.843014 -401.756037) (xy 317.835258 -401.702089) (xy 317.834772 -401.674838) (xy 317.397892 -401.674838)
			(xy 317.397406 -401.702089) (xy 317.38965 -401.756037) (xy 317.374295 -401.808332) (xy 317.351653 -401.857909)
			(xy 317.322187 -401.903759) (xy 317.286496 -401.94495) (xy 317.245305 -401.980641) (xy 317.199455 -402.010107)
			(xy 317.149878 -402.032749) (xy 317.097583 -402.048104) (xy 317.043635 -402.05586) (xy 316.989133 -402.05586)
			(xy 316.935185 -402.048104) (xy 316.88289 -402.032749) (xy 316.833313 -402.010107) (xy 316.787463 -401.980641)
			(xy 316.746272 -401.94495) (xy 316.710581 -401.903759) (xy 316.681115 -401.857909) (xy 316.658473 -401.808332)
			(xy 316.643118 -401.756037) (xy 316.635362 -401.702089) (xy 316.634876 -401.674838) (xy 316.197996 -401.674838)
			(xy 316.19751 -401.702089) (xy 316.189754 -401.756037) (xy 316.174399 -401.808332) (xy 316.151757 -401.857909)
			(xy 316.122291 -401.903759) (xy 316.0866 -401.94495) (xy 316.045409 -401.980641) (xy 315.999559 -402.010107)
			(xy 315.949982 -402.032749) (xy 315.897687 -402.048104) (xy 315.843739 -402.05586) (xy 315.789237 -402.05586)
			(xy 315.735289 -402.048104) (xy 315.682994 -402.032749) (xy 315.633417 -402.010107) (xy 315.587567 -401.980641)
			(xy 315.546376 -401.94495) (xy 315.510685 -401.903759) (xy 315.481219 -401.857909) (xy 315.458577 -401.808332)
			(xy 315.443222 -401.756037) (xy 315.435466 -401.702089) (xy 315.43498 -401.674838) (xy 314.9981 -401.674838)
			(xy 314.997614 -401.702107) (xy 314.989852 -401.756091) (xy 314.974487 -401.808421) (xy 314.95183 -401.858031)
			(xy 314.922344 -401.903912) (xy 314.886629 -401.945129) (xy 314.845412 -401.980844) (xy 314.799531 -402.01033)
			(xy 314.749921 -402.032987) (xy 314.697591 -402.048352) (xy 314.643607 -402.056114) (xy 314.589069 -402.056114)
			(xy 314.535085 -402.048352) (xy 314.482755 -402.032987) (xy 314.433145 -402.01033) (xy 314.387264 -401.980844)
			(xy 314.346047 -401.945129) (xy 314.310332 -401.903912) (xy 314.280846 -401.858031) (xy 314.258189 -401.808421)
			(xy 314.242824 -401.756091) (xy 314.235062 -401.702107) (xy 314.234576 -401.674838) (xy 313.798204 -401.674838)
			(xy 313.797718 -401.702107) (xy 313.789956 -401.756091) (xy 313.774591 -401.808421) (xy 313.751934 -401.858031)
			(xy 313.722448 -401.903912) (xy 313.686733 -401.945129) (xy 313.645516 -401.980844) (xy 313.599635 -402.01033)
			(xy 313.550025 -402.032987) (xy 313.497695 -402.048352) (xy 313.443711 -402.056114) (xy 313.389173 -402.056114)
			(xy 313.335189 -402.048352) (xy 313.282859 -402.032987) (xy 313.233249 -402.01033) (xy 313.187368 -401.980844)
			(xy 313.146151 -401.945129) (xy 313.110436 -401.903912) (xy 313.08095 -401.858031) (xy 313.058293 -401.808421)
			(xy 313.042928 -401.756091) (xy 313.035166 -401.702107) (xy 313.03468 -401.674838) (xy 312.5978 -401.674838)
			(xy 312.597314 -401.702089) (xy 312.589558 -401.756037) (xy 312.574203 -401.808332) (xy 312.551561 -401.857909)
			(xy 312.522095 -401.903759) (xy 312.486404 -401.94495) (xy 312.445213 -401.980641) (xy 312.399363 -402.010107)
			(xy 312.349786 -402.032749) (xy 312.297491 -402.048104) (xy 312.243543 -402.05586) (xy 312.189041 -402.05586)
			(xy 312.135093 -402.048104) (xy 312.082798 -402.032749) (xy 312.033221 -402.010107) (xy 311.987371 -401.980641)
			(xy 311.94618 -401.94495) (xy 311.910489 -401.903759) (xy 311.881023 -401.857909) (xy 311.858381 -401.808332)
			(xy 311.843026 -401.756037) (xy 311.83527 -401.702089) (xy 311.834784 -401.674838) (xy 311.397904 -401.674838)
			(xy 311.397418 -401.702089) (xy 311.389662 -401.756037) (xy 311.374307 -401.808332) (xy 311.351665 -401.857909)
			(xy 311.322199 -401.903759) (xy 311.286508 -401.94495) (xy 311.245317 -401.980641) (xy 311.199467 -402.010107)
			(xy 311.14989 -402.032749) (xy 311.097595 -402.048104) (xy 311.043647 -402.05586) (xy 310.989145 -402.05586)
			(xy 310.935197 -402.048104) (xy 310.882902 -402.032749) (xy 310.833325 -402.010107) (xy 310.787475 -401.980641)
			(xy 310.746284 -401.94495) (xy 310.710593 -401.903759) (xy 310.681127 -401.857909) (xy 310.658485 -401.808332)
			(xy 310.64313 -401.756037) (xy 310.635374 -401.702089) (xy 310.634888 -401.674838) (xy 310.198008 -401.674838)
			(xy 310.197522 -401.702107) (xy 310.18976 -401.756091) (xy 310.174395 -401.808421) (xy 310.151738 -401.858031)
			(xy 310.122252 -401.903912) (xy 310.086537 -401.945129) (xy 310.04532 -401.980844) (xy 309.999439 -402.01033)
			(xy 309.949829 -402.032987) (xy 309.897499 -402.048352) (xy 309.843515 -402.056114) (xy 309.788977 -402.056114)
			(xy 309.734993 -402.048352) (xy 309.682663 -402.032987) (xy 309.633053 -402.01033) (xy 309.587172 -401.980844)
			(xy 309.545955 -401.945129) (xy 309.51024 -401.903912) (xy 309.480754 -401.858031) (xy 309.458097 -401.808421)
			(xy 309.442732 -401.756091) (xy 309.43497 -401.702107) (xy 309.434484 -401.674838) (xy 308.998112 -401.674838)
			(xy 308.997626 -401.702107) (xy 308.989864 -401.756091) (xy 308.974499 -401.808421) (xy 308.951842 -401.858031)
			(xy 308.922356 -401.903912) (xy 308.886641 -401.945129) (xy 308.845424 -401.980844) (xy 308.799543 -402.01033)
			(xy 308.749933 -402.032987) (xy 308.697603 -402.048352) (xy 308.643619 -402.056114) (xy 308.589081 -402.056114)
			(xy 308.535097 -402.048352) (xy 308.482767 -402.032987) (xy 308.433157 -402.01033) (xy 308.387276 -401.980844)
			(xy 308.346059 -401.945129) (xy 308.310344 -401.903912) (xy 308.280858 -401.858031) (xy 308.258201 -401.808421)
			(xy 308.242836 -401.756091) (xy 308.235074 -401.702107) (xy 308.234588 -401.674838) (xy 307.797708 -401.674838)
			(xy 307.797222 -401.702089) (xy 307.789466 -401.756037) (xy 307.774111 -401.808332) (xy 307.751469 -401.857909)
			(xy 307.722003 -401.903759) (xy 307.686312 -401.94495) (xy 307.645121 -401.980641) (xy 307.599271 -402.010107)
			(xy 307.549694 -402.032749) (xy 307.497399 -402.048104) (xy 307.443451 -402.05586) (xy 307.388949 -402.05586)
			(xy 307.335001 -402.048104) (xy 307.282706 -402.032749) (xy 307.233129 -402.010107) (xy 307.187279 -401.980641)
			(xy 307.146088 -401.94495) (xy 307.110397 -401.903759) (xy 307.080931 -401.857909) (xy 307.058289 -401.808332)
			(xy 307.042934 -401.756037) (xy 307.035178 -401.702089) (xy 307.034692 -401.674838) (xy 306.597812 -401.674838)
			(xy 306.597326 -401.702089) (xy 306.58957 -401.756037) (xy 306.574215 -401.808332) (xy 306.551573 -401.857909)
			(xy 306.522107 -401.903759) (xy 306.486416 -401.94495) (xy 306.445225 -401.980641) (xy 306.399375 -402.010107)
			(xy 306.349798 -402.032749) (xy 306.297503 -402.048104) (xy 306.243555 -402.05586) (xy 306.189053 -402.05586)
			(xy 306.135105 -402.048104) (xy 306.08281 -402.032749) (xy 306.033233 -402.010107) (xy 305.987383 -401.980641)
			(xy 305.946192 -401.94495) (xy 305.910501 -401.903759) (xy 305.881035 -401.857909) (xy 305.858393 -401.808332)
			(xy 305.843038 -401.756037) (xy 305.835282 -401.702089) (xy 305.834796 -401.674838) (xy 305.397916 -401.674838)
			(xy 305.39743 -401.702107) (xy 305.389668 -401.756091) (xy 305.374303 -401.808421) (xy 305.351646 -401.858031)
			(xy 305.32216 -401.903912) (xy 305.286445 -401.945129) (xy 305.245228 -401.980844) (xy 305.199347 -402.01033)
			(xy 305.149737 -402.032987) (xy 305.097407 -402.048352) (xy 305.043423 -402.056114) (xy 304.988885 -402.056114)
			(xy 304.934901 -402.048352) (xy 304.882571 -402.032987) (xy 304.832961 -402.01033) (xy 304.78708 -401.980844)
			(xy 304.745863 -401.945129) (xy 304.710148 -401.903912) (xy 304.680662 -401.858031) (xy 304.658005 -401.808421)
			(xy 304.64264 -401.756091) (xy 304.634878 -401.702107) (xy 304.634392 -401.674838) (xy 304.19802 -401.674838)
			(xy 304.197534 -401.702107) (xy 304.189772 -401.756091) (xy 304.174407 -401.808421) (xy 304.15175 -401.858031)
			(xy 304.122264 -401.903912) (xy 304.086549 -401.945129) (xy 304.045332 -401.980844) (xy 303.999451 -402.01033)
			(xy 303.949841 -402.032987) (xy 303.897511 -402.048352) (xy 303.843527 -402.056114) (xy 303.788989 -402.056114)
			(xy 303.735005 -402.048352) (xy 303.682675 -402.032987) (xy 303.633065 -402.01033) (xy 303.587184 -401.980844)
			(xy 303.545967 -401.945129) (xy 303.510252 -401.903912) (xy 303.480766 -401.858031) (xy 303.458109 -401.808421)
			(xy 303.442744 -401.756091) (xy 303.434982 -401.702107) (xy 303.434496 -401.674838) (xy 280.68524 -401.674838)
			(xy 280.68524 -404.215092) (xy 283.62402 -404.215092) (xy 283.62402 -403.351492) (xy 283.624506 -403.324223)
			(xy 283.632268 -403.270239) (xy 283.647633 -403.217909) (xy 283.67029 -403.168299) (xy 283.699776 -403.122418)
			(xy 283.735491 -403.081201) (xy 283.776708 -403.045486) (xy 283.822589 -403.016) (xy 283.872199 -402.993343)
			(xy 283.924529 -402.977978) (xy 283.978513 -402.970216) (xy 284.033051 -402.970216) (xy 284.087035 -402.977978)
			(xy 284.139365 -402.993343) (xy 284.188975 -403.016) (xy 284.203533 -403.025356) (xy 289.919156 -403.025356)
			(xy 289.919156 -402.161756) (xy 289.919642 -402.134487) (xy 289.927404 -402.080503) (xy 289.942769 -402.028173)
			(xy 289.965426 -401.978563) (xy 289.994912 -401.932682) (xy 290.030627 -401.891465) (xy 290.071844 -401.85575)
			(xy 290.117725 -401.826264) (xy 290.167335 -401.803607) (xy 290.219665 -401.788242) (xy 290.273649 -401.78048)
			(xy 290.328187 -401.78048) (xy 290.382171 -401.788242) (xy 290.434501 -401.803607) (xy 290.484111 -401.826264)
			(xy 290.529992 -401.85575) (xy 290.571209 -401.891465) (xy 290.606924 -401.932682) (xy 290.63641 -401.978563)
			(xy 290.659067 -402.028173) (xy 290.674432 -402.080503) (xy 290.682194 -402.134487) (xy 290.68268 -402.161756)
			(xy 290.68268 -403.025356) (xy 290.682194 -403.052625) (xy 290.674432 -403.106609) (xy 290.659067 -403.158939)
			(xy 290.63641 -403.208549) (xy 290.606924 -403.25443) (xy 290.571209 -403.295647) (xy 290.529992 -403.331362)
			(xy 290.484111 -403.360848) (xy 290.434501 -403.383505) (xy 290.382171 -403.39887) (xy 290.328187 -403.406632)
			(xy 290.273649 -403.406632) (xy 290.219665 -403.39887) (xy 290.167335 -403.383505) (xy 290.117725 -403.360848)
			(xy 290.071844 -403.331362) (xy 290.030627 -403.295647) (xy 289.994912 -403.25443) (xy 289.965426 -403.208549)
			(xy 289.942769 -403.158939) (xy 289.927404 -403.106609) (xy 289.919642 -403.052625) (xy 289.919156 -403.025356)
			(xy 284.203533 -403.025356) (xy 284.234856 -403.045486) (xy 284.276073 -403.081201) (xy 284.311788 -403.122418)
			(xy 284.341274 -403.168299) (xy 284.363931 -403.217909) (xy 284.379296 -403.270239) (xy 284.387058 -403.324223)
			(xy 284.387544 -403.351492) (xy 284.387544 -404.215092) (xy 284.387058 -404.242361) (xy 284.379296 -404.296345)
			(xy 284.363931 -404.348675) (xy 284.341274 -404.398285) (xy 284.311788 -404.444166) (xy 284.276073 -404.485383)
			(xy 284.234856 -404.521098) (xy 284.188975 -404.550584) (xy 284.139365 -404.573241) (xy 284.087035 -404.588606)
			(xy 284.033051 -404.596368) (xy 283.978513 -404.596368) (xy 283.924529 -404.588606) (xy 283.872199 -404.573241)
			(xy 283.822589 -404.550584) (xy 283.776708 -404.521098) (xy 283.735491 -404.485383) (xy 283.699776 -404.444166)
			(xy 283.67029 -404.398285) (xy 283.647633 -404.348675) (xy 283.632268 -404.296345) (xy 283.624506 -404.242361)
			(xy 283.62402 -404.215092) (xy 280.68524 -404.215092) (xy 280.68524 -407.583953) (xy 282.536071 -407.583953)
			(xy 282.536071 -407.529447) (xy 282.543829 -407.475495) (xy 282.559186 -407.423196) (xy 282.581831 -407.373615)
			(xy 282.611301 -407.327762) (xy 282.646997 -407.28657) (xy 282.688193 -407.250878) (xy 282.734049 -407.221412)
			(xy 282.783632 -407.198773) (xy 282.835932 -407.183421) (xy 282.889885 -407.175669) (xy 282.917138 -407.175208)
			(xy 283.780738 -407.175208) (xy 283.807989 -407.175664) (xy 283.861934 -407.183426) (xy 283.914227 -407.198785)
			(xy 283.963801 -407.221429) (xy 284.009649 -407.250898) (xy 284.050836 -407.286591) (xy 284.086525 -407.327782)
			(xy 284.115989 -407.373632) (xy 284.134525 -407.414222) (xy 287.101788 -407.414222) (xy 287.101788 -406.550622)
			(xy 287.102274 -406.523371) (xy 287.11003 -406.469423) (xy 287.125385 -406.417128) (xy 287.148027 -406.367551)
			(xy 287.177493 -406.321701) (xy 287.213184 -406.28051) (xy 287.254375 -406.244819) (xy 287.300225 -406.215353)
			(xy 287.349802 -406.192711) (xy 287.402097 -406.177356) (xy 287.456045 -406.1696) (xy 287.510547 -406.1696)
			(xy 287.564495 -406.177356) (xy 287.61679 -406.192711) (xy 287.666367 -406.215353) (xy 287.712217 -406.244819)
			(xy 287.753408 -406.28051) (xy 287.789099 -406.321701) (xy 287.818565 -406.367551) (xy 287.841207 -406.417128)
			(xy 287.856562 -406.469423) (xy 287.864318 -406.523371) (xy 287.864804 -406.550622) (xy 287.864804 -407.414222)
			(xy 287.864318 -407.441473) (xy 287.856562 -407.495421) (xy 287.841207 -407.547716) (xy 287.818565 -407.597293)
			(xy 287.789099 -407.643143) (xy 287.753408 -407.684334) (xy 287.712217 -407.720025) (xy 287.666367 -407.749491)
			(xy 287.61679 -407.772133) (xy 287.564495 -407.787488) (xy 287.510547 -407.795244) (xy 287.456045 -407.795244)
			(xy 287.402097 -407.787488) (xy 287.349802 -407.772133) (xy 287.300225 -407.749491) (xy 287.254375 -407.720025)
			(xy 287.213184 -407.684334) (xy 287.177493 -407.643143) (xy 287.148027 -407.597293) (xy 287.125385 -407.547716)
			(xy 287.11003 -407.495421) (xy 287.102274 -407.441473) (xy 287.101788 -407.414222) (xy 284.134525 -407.414222)
			(xy 284.138629 -407.423209) (xy 284.153982 -407.475503) (xy 284.161738 -407.529449) (xy 284.161738 -407.583951)
			(xy 284.153982 -407.637897) (xy 284.138629 -407.690191) (xy 284.115989 -407.739768) (xy 284.086525 -407.785619)
			(xy 284.050836 -407.826809) (xy 284.009649 -407.862502) (xy 283.963801 -407.891971) (xy 283.914227 -407.914615)
			(xy 283.861934 -407.929974) (xy 283.807989 -407.937736) (xy 283.780738 -407.938224) (xy 282.917138 -407.938224)
			(xy 282.889885 -407.937731) (xy 282.835932 -407.929979) (xy 282.783632 -407.914627) (xy 282.734049 -407.891988)
			(xy 282.688193 -407.862522) (xy 282.646997 -407.82683) (xy 282.611301 -407.785638) (xy 282.581831 -407.739785)
			(xy 282.559186 -407.690204) (xy 282.543829 -407.637905) (xy 282.536071 -407.583953) (xy 280.68524 -407.583953)
			(xy 280.68524 -409.10256) (xy 280.684766 -409.12751) (xy 280.676946 -409.176794) (xy 280.661524 -409.224251)
			(xy 280.638877 -409.268716) (xy 280.609563 -409.309098) (xy 280.592276 -409.327096) (xy 276.749256 -413.170116)
			(xy 293.568894 -413.170116) (xy 293.572866 -412.991873) (xy 293.584774 -412.813984) (xy 293.604595 -412.636802)
			(xy 293.632289 -412.460678) (xy 293.667801 -412.285963) (xy 293.711061 -412.113004) (xy 293.761983 -411.942143)
			(xy 293.820466 -411.773721) (xy 293.886393 -411.608071) (xy 293.959634 -411.445522) (xy 294.040044 -411.286397)
			(xy 294.127462 -411.131012) (xy 294.221715 -410.979676) (xy 294.322616 -410.832688) (xy 294.429965 -410.690341)
			(xy 294.543548 -410.552918) (xy 294.663141 -410.420691) (xy 294.788505 -410.293922) (xy 294.919392 -410.172864)
			(xy 295.055541 -410.057757) (xy 295.196683 -409.948829) (xy 295.342538 -409.846297) (xy 295.492815 -409.750363)
			(xy 295.647216 -409.66122) (xy 295.805435 -409.579043) (xy 295.967158 -409.503995) (xy 296.132063 -409.436227)
			(xy 296.299824 -409.375871) (xy 296.470107 -409.323049) (xy 296.642574 -409.277865) (xy 296.816882 -409.240408)
			(xy 296.992686 -409.210754) (xy 297.169636 -409.188961) (xy 297.347382 -409.175071) (xy 297.525569 -409.169114)
			(xy 297.703846 -409.1711) (xy 297.881857 -409.181026) (xy 298.059249 -409.198872) (xy 298.235669 -409.224602)
			(xy 298.410769 -409.258166) (xy 298.5842 -409.299496) (xy 298.755617 -409.348512) (xy 298.92468 -409.405114)
			(xy 299.091055 -409.469192) (xy 299.254409 -409.540618) (xy 299.41442 -409.61925) (xy 299.570769 -409.704931)
			(xy 299.723146 -409.797493) (xy 299.871249 -409.89675) (xy 300.014783 -410.002507) (xy 300.153463 -410.114552)
			(xy 300.287014 -410.232664) (xy 300.415171 -410.356608) (xy 300.53768 -410.486138) (xy 300.654297 -410.620997)
			(xy 300.76479 -410.760917) (xy 300.868941 -410.90562) (xy 300.966543 -411.054819) (xy 301.057401 -411.208218)
			(xy 301.141335 -411.365512) (xy 301.21818 -411.526388) (xy 301.287781 -411.690529) (xy 301.350002 -411.857606)
			(xy 301.404718 -412.02729) (xy 301.45182 -412.199243) (xy 301.491216 -412.373123) (xy 301.522827 -412.548586)
			(xy 301.546591 -412.725282) (xy 301.559858 -412.873752) (xy 303.412875 -412.873752) (xy 303.412875 -412.819248)
			(xy 303.420632 -412.7653) (xy 303.435988 -412.713004) (xy 303.458629 -412.663426) (xy 303.488096 -412.617575)
			(xy 303.523789 -412.576384) (xy 303.56498 -412.540693) (xy 303.610831 -412.511226) (xy 303.66041 -412.488585)
			(xy 303.712706 -412.473231) (xy 303.766654 -412.465475) (xy 303.793906 -412.465012) (xy 304.657506 -412.465012)
			(xy 304.684758 -412.465458) (xy 304.738708 -412.473216) (xy 304.791005 -412.488572) (xy 304.840584 -412.511215)
			(xy 304.886436 -412.540683) (xy 304.927628 -412.576376) (xy 304.963321 -412.617569) (xy 304.992788 -412.663421)
			(xy 305.01543 -412.713001) (xy 305.030785 -412.765298) (xy 305.038542 -412.819248) (xy 305.038542 -412.873752)
			(xy 305.038542 -412.873754) (xy 306.476075 -412.873754) (xy 306.476075 -412.819246) (xy 306.483833 -412.765294)
			(xy 306.499191 -412.712996) (xy 306.521835 -412.663415) (xy 306.551306 -412.617562) (xy 306.587003 -412.57637)
			(xy 306.628199 -412.540679) (xy 306.674055 -412.511213) (xy 306.723639 -412.488575) (xy 306.775939 -412.473223)
			(xy 306.829892 -412.465472) (xy 306.857146 -412.465012) (xy 307.720746 -412.465012) (xy 307.747997 -412.465461)
			(xy 307.801942 -412.473223) (xy 307.854234 -412.488583) (xy 307.903808 -412.511228) (xy 307.949655 -412.540697)
			(xy 307.990842 -412.576391) (xy 308.02653 -412.617582) (xy 308.055994 -412.663432) (xy 308.078633 -412.713009)
			(xy 308.093987 -412.765303) (xy 308.101742 -412.819249) (xy 308.101742 -412.873749) (xy 309.539398 -412.873749)
			(xy 309.539398 -412.819251) (xy 309.547154 -412.765307) (xy 309.562508 -412.713016) (xy 309.585146 -412.663443)
			(xy 309.61461 -412.617596) (xy 309.650298 -412.576408) (xy 309.691484 -412.540718) (xy 309.73733 -412.511253)
			(xy 309.786903 -412.488612) (xy 309.839194 -412.473257) (xy 309.893137 -412.465499) (xy 309.920386 -412.465012)
			(xy 310.783986 -412.465012) (xy 310.811241 -412.465434) (xy 310.865196 -412.47319) (xy 310.917499 -412.488545)
			(xy 310.967083 -412.511188) (xy 311.012941 -412.540657) (xy 311.054137 -412.576353) (xy 311.089834 -412.617548)
			(xy 311.119305 -412.663405) (xy 311.14195 -412.712988) (xy 311.157307 -412.76529) (xy 311.165065 -412.819245)
			(xy 311.165065 -412.873753) (xy 312.602575 -412.873753) (xy 312.602575 -412.819247) (xy 312.610333 -412.765297)
			(xy 312.625689 -412.713) (xy 312.648332 -412.663421) (xy 312.677801 -412.617569) (xy 312.713496 -412.576377)
			(xy 312.754689 -412.540686) (xy 312.800543 -412.51122) (xy 312.850124 -412.48858) (xy 312.902422 -412.473227)
			(xy 312.956373 -412.465474) (xy 312.983626 -412.465012) (xy 313.847226 -412.465012) (xy 313.874477 -412.46546)
			(xy 313.928425 -412.47322) (xy 313.98072 -412.488578) (xy 314.030296 -412.511222) (xy 314.076146 -412.54069)
			(xy 314.117335 -412.576383) (xy 314.153026 -412.617575) (xy 314.182491 -412.663427) (xy 314.205131 -412.713005)
			(xy 314.220486 -412.7653) (xy 314.228242 -412.819249) (xy 314.228242 -412.873748) (xy 315.665898 -412.873748)
			(xy 315.665898 -412.819252) (xy 315.673653 -412.76531) (xy 315.689006 -412.713021) (xy 315.711643 -412.663448)
			(xy 315.741105 -412.617602) (xy 315.776791 -412.576415) (xy 315.817975 -412.540725) (xy 315.863818 -412.51126)
			(xy 315.913389 -412.488618) (xy 315.965677 -412.473261) (xy 316.019618 -412.465501) (xy 316.046866 -412.465012)
			(xy 316.910466 -412.465012) (xy 316.937722 -412.465433) (xy 316.991679 -412.473186) (xy 317.043984 -412.48854)
			(xy 317.093571 -412.511182) (xy 317.139431 -412.54065) (xy 317.18063 -412.576346) (xy 317.216329 -412.617542)
			(xy 317.245802 -412.663399) (xy 317.268448 -412.712984) (xy 317.283807 -412.765287) (xy 317.291565 -412.819244)
			(xy 317.291565 -412.873752) (xy 318.729075 -412.873752) (xy 318.729075 -412.819248) (xy 318.736832 -412.7653)
			(xy 318.752188 -412.713004) (xy 318.774829 -412.663426) (xy 318.804296 -412.617575) (xy 318.839989 -412.576384)
			(xy 318.88118 -412.540693) (xy 318.927031 -412.511226) (xy 318.97661 -412.488585) (xy 319.028906 -412.473231)
			(xy 319.082854 -412.465475) (xy 319.110106 -412.465012) (xy 319.973706 -412.465012) (xy 320.000958 -412.465458)
			(xy 320.054908 -412.473216) (xy 320.107205 -412.488572) (xy 320.156784 -412.511215) (xy 320.202636 -412.540683)
			(xy 320.243828 -412.576376) (xy 320.279521 -412.617569) (xy 320.308988 -412.663421) (xy 320.33163 -412.713001)
			(xy 320.346985 -412.765298) (xy 320.354742 -412.819248) (xy 320.354742 -412.873752) (xy 320.354742 -412.873754)
			(xy 321.792275 -412.873754) (xy 321.792275 -412.819246) (xy 321.800033 -412.765294) (xy 321.815391 -412.712996)
			(xy 321.838035 -412.663415) (xy 321.867506 -412.617562) (xy 321.903203 -412.57637) (xy 321.944399 -412.540679)
			(xy 321.990255 -412.511213) (xy 322.039839 -412.488575) (xy 322.092139 -412.473223) (xy 322.146092 -412.465472)
			(xy 322.173346 -412.465012) (xy 323.036946 -412.465012) (xy 323.064197 -412.465461) (xy 323.118142 -412.473223)
			(xy 323.170434 -412.488583) (xy 323.220008 -412.511228) (xy 323.265855 -412.540697) (xy 323.307042 -412.576391)
			(xy 323.34273 -412.617582) (xy 323.372194 -412.663432) (xy 323.394833 -412.713009) (xy 323.410187 -412.765303)
			(xy 323.417942 -412.819249) (xy 323.417942 -412.873749) (xy 324.855598 -412.873749) (xy 324.855598 -412.819251)
			(xy 324.863354 -412.765307) (xy 324.878708 -412.713016) (xy 324.901346 -412.663443) (xy 324.93081 -412.617596)
			(xy 324.966498 -412.576408) (xy 325.007684 -412.540718) (xy 325.05353 -412.511253) (xy 325.103103 -412.488612)
			(xy 325.155394 -412.473257) (xy 325.209337 -412.465499) (xy 325.236586 -412.465012) (xy 326.100186 -412.465012)
			(xy 326.127441 -412.465434) (xy 326.181396 -412.47319) (xy 326.233699 -412.488545) (xy 326.283283 -412.511188)
			(xy 326.329141 -412.540657) (xy 326.370337 -412.576353) (xy 326.406034 -412.617548) (xy 326.435505 -412.663405)
			(xy 326.45815 -412.712988) (xy 326.473507 -412.76529) (xy 326.481265 -412.819245) (xy 326.481265 -412.873753)
			(xy 327.918775 -412.873753) (xy 327.918775 -412.819247) (xy 327.926533 -412.765297) (xy 327.941889 -412.713)
			(xy 327.964532 -412.663421) (xy 327.994001 -412.617569) (xy 328.029696 -412.576377) (xy 328.070889 -412.540686)
			(xy 328.116743 -412.51122) (xy 328.166324 -412.48858) (xy 328.218622 -412.473227) (xy 328.272573 -412.465474)
			(xy 328.299826 -412.465012) (xy 329.163426 -412.465012) (xy 329.190677 -412.46546) (xy 329.244625 -412.47322)
			(xy 329.29692 -412.488578) (xy 329.346496 -412.511222) (xy 329.392346 -412.54069) (xy 329.433535 -412.576383)
			(xy 329.469226 -412.617575) (xy 329.498691 -412.663427) (xy 329.521331 -412.713005) (xy 329.536686 -412.7653)
			(xy 329.544442 -412.819249) (xy 329.544442 -412.873748) (xy 330.982098 -412.873748) (xy 330.982098 -412.819252)
			(xy 330.989853 -412.76531) (xy 331.005206 -412.713021) (xy 331.027843 -412.663448) (xy 331.057305 -412.617602)
			(xy 331.092991 -412.576415) (xy 331.134175 -412.540725) (xy 331.180018 -412.51126) (xy 331.229589 -412.488618)
			(xy 331.281877 -412.473261) (xy 331.335818 -412.465501) (xy 331.363066 -412.465012) (xy 332.226666 -412.465012)
			(xy 332.253922 -412.465433) (xy 332.307879 -412.473186) (xy 332.360184 -412.48854) (xy 332.409771 -412.511182)
			(xy 332.455631 -412.54065) (xy 332.49683 -412.576346) (xy 332.532529 -412.617542) (xy 332.562002 -412.663399)
			(xy 332.584648 -412.712984) (xy 332.600007 -412.765287) (xy 332.607765 -412.819244) (xy 332.607765 -412.873752)
			(xy 334.045275 -412.873752) (xy 334.045275 -412.819248) (xy 334.053032 -412.7653) (xy 334.068388 -412.713004)
			(xy 334.091029 -412.663426) (xy 334.120496 -412.617575) (xy 334.156189 -412.576384) (xy 334.19738 -412.540693)
			(xy 334.243231 -412.511226) (xy 334.29281 -412.488585) (xy 334.345106 -412.473231) (xy 334.399054 -412.465475)
			(xy 334.426306 -412.465012) (xy 335.289906 -412.465012) (xy 335.317158 -412.465458) (xy 335.371108 -412.473216)
			(xy 335.423405 -412.488572) (xy 335.472984 -412.511215) (xy 335.518836 -412.540683) (xy 335.560028 -412.576376)
			(xy 335.595721 -412.617569) (xy 335.625188 -412.663421) (xy 335.64783 -412.713001) (xy 335.663185 -412.765298)
			(xy 335.670942 -412.819248) (xy 335.670942 -412.873752) (xy 335.670942 -412.873754) (xy 337.108475 -412.873754)
			(xy 337.108475 -412.819246) (xy 337.116233 -412.765294) (xy 337.131591 -412.712996) (xy 337.154235 -412.663415)
			(xy 337.183706 -412.617562) (xy 337.219403 -412.57637) (xy 337.260599 -412.540679) (xy 337.306455 -412.511213)
			(xy 337.356039 -412.488575) (xy 337.408339 -412.473223) (xy 337.462292 -412.465472) (xy 337.489546 -412.465012)
			(xy 338.353146 -412.465012) (xy 338.380397 -412.465461) (xy 338.434342 -412.473223) (xy 338.486634 -412.488583)
			(xy 338.536208 -412.511228) (xy 338.582055 -412.540697) (xy 338.623242 -412.576391) (xy 338.65893 -412.617582)
			(xy 338.688394 -412.663432) (xy 338.711033 -412.713009) (xy 338.726387 -412.765303) (xy 338.734142 -412.819249)
			(xy 338.734142 -412.873749) (xy 340.171798 -412.873749) (xy 340.171798 -412.819251) (xy 340.179554 -412.765307)
			(xy 340.194908 -412.713016) (xy 340.217546 -412.663443) (xy 340.24701 -412.617596) (xy 340.282698 -412.576408)
			(xy 340.323884 -412.540718) (xy 340.36973 -412.511253) (xy 340.419303 -412.488612) (xy 340.471594 -412.473257)
			(xy 340.525537 -412.465499) (xy 340.552786 -412.465012) (xy 341.416386 -412.465012) (xy 341.443641 -412.465434)
			(xy 341.497596 -412.47319) (xy 341.549899 -412.488545) (xy 341.599483 -412.511188) (xy 341.645341 -412.540657)
			(xy 341.686537 -412.576353) (xy 341.722234 -412.617548) (xy 341.751705 -412.663405) (xy 341.77435 -412.712988)
			(xy 341.789707 -412.76529) (xy 341.797465 -412.819245) (xy 341.797465 -412.873753) (xy 343.234975 -412.873753)
			(xy 343.234975 -412.819247) (xy 343.242733 -412.765297) (xy 343.258089 -412.713) (xy 343.280732 -412.663421)
			(xy 343.310201 -412.617569) (xy 343.345896 -412.576377) (xy 343.387089 -412.540686) (xy 343.432943 -412.51122)
			(xy 343.482524 -412.48858) (xy 343.534822 -412.473227) (xy 343.588773 -412.465474) (xy 343.616026 -412.465012)
			(xy 344.479626 -412.465012) (xy 344.506877 -412.46546) (xy 344.560825 -412.47322) (xy 344.61312 -412.488578)
			(xy 344.662696 -412.511222) (xy 344.708546 -412.54069) (xy 344.749735 -412.576383) (xy 344.785426 -412.617575)
			(xy 344.814891 -412.663427) (xy 344.837531 -412.713005) (xy 344.852886 -412.7653) (xy 344.860642 -412.819249)
			(xy 344.860642 -412.873748) (xy 346.298298 -412.873748) (xy 346.298298 -412.819252) (xy 346.306053 -412.76531)
			(xy 346.321406 -412.713021) (xy 346.344043 -412.663448) (xy 346.373505 -412.617602) (xy 346.409191 -412.576415)
			(xy 346.450375 -412.540725) (xy 346.496218 -412.51126) (xy 346.545789 -412.488618) (xy 346.598077 -412.473261)
			(xy 346.652018 -412.465501) (xy 346.679266 -412.465012) (xy 347.542866 -412.465012) (xy 347.570122 -412.465433)
			(xy 347.624079 -412.473186) (xy 347.676384 -412.48854) (xy 347.725971 -412.511182) (xy 347.771831 -412.54065)
			(xy 347.81303 -412.576346) (xy 347.848729 -412.617542) (xy 347.878202 -412.663399) (xy 347.900848 -412.712984)
			(xy 347.916207 -412.765287) (xy 347.923965 -412.819244) (xy 347.923965 -412.873752) (xy 349.361475 -412.873752)
			(xy 349.361475 -412.819248) (xy 349.369232 -412.7653) (xy 349.384588 -412.713004) (xy 349.407229 -412.663426)
			(xy 349.436696 -412.617575) (xy 349.472389 -412.576384) (xy 349.51358 -412.540693) (xy 349.559431 -412.511226)
			(xy 349.60901 -412.488585) (xy 349.661306 -412.473231) (xy 349.715254 -412.465475) (xy 349.742506 -412.465012)
			(xy 350.606106 -412.465012) (xy 350.633358 -412.465458) (xy 350.687308 -412.473216) (xy 350.739605 -412.488572)
			(xy 350.789184 -412.511215) (xy 350.835036 -412.540683) (xy 350.876228 -412.576376) (xy 350.911921 -412.617569)
			(xy 350.941388 -412.663421) (xy 350.96403 -412.713001) (xy 350.979385 -412.765298) (xy 350.987142 -412.819248)
			(xy 350.987142 -412.873752) (xy 370.513075 -412.873752) (xy 370.513075 -412.819248) (xy 370.520832 -412.7653)
			(xy 370.536187 -412.713005) (xy 370.558829 -412.663427) (xy 370.588295 -412.617576) (xy 370.623987 -412.576386)
			(xy 370.665178 -412.540694) (xy 370.711029 -412.511228) (xy 370.760607 -412.488587) (xy 370.812902 -412.473231)
			(xy 370.86685 -412.465475) (xy 370.894102 -412.465012) (xy 371.757702 -412.465012) (xy 371.784955 -412.465458)
			(xy 371.838905 -412.473215) (xy 371.891202 -412.488571) (xy 371.940782 -412.511214) (xy 371.986634 -412.540682)
			(xy 372.027826 -412.576375) (xy 372.06352 -412.617567) (xy 372.092987 -412.66342) (xy 372.115629 -412.713)
			(xy 372.130985 -412.765297) (xy 372.138742 -412.819247) (xy 372.138742 -412.873753) (xy 373.576275 -412.873753)
			(xy 373.576275 -412.819247) (xy 373.584033 -412.765295) (xy 373.59939 -412.712996) (xy 373.622035 -412.663416)
			(xy 373.651505 -412.617563) (xy 373.687201 -412.576372) (xy 373.728397 -412.54068) (xy 373.774253 -412.511215)
			(xy 373.823836 -412.488576) (xy 373.876136 -412.473224) (xy 373.930089 -412.465472) (xy 373.957342 -412.465012)
			(xy 374.820942 -412.465012) (xy 374.848193 -412.465461) (xy 374.902139 -412.473222) (xy 374.954431 -412.488582)
			(xy 375.004006 -412.511227) (xy 375.049853 -412.540696) (xy 375.091041 -412.576389) (xy 375.126729 -412.61758)
			(xy 375.156193 -412.663431) (xy 375.178833 -412.713008) (xy 375.194186 -412.765302) (xy 375.201942 -412.819249)
			(xy 375.201942 -412.873749) (xy 376.639598 -412.873749) (xy 376.639598 -412.819251) (xy 376.647354 -412.765308)
			(xy 376.662707 -412.713017) (xy 376.685346 -412.663444) (xy 376.714809 -412.617597) (xy 376.750497 -412.576409)
			(xy 376.791682 -412.54072) (xy 376.837528 -412.511254) (xy 376.8871 -412.488613) (xy 376.93939 -412.473258)
			(xy 376.993333 -412.465499) (xy 377.020582 -412.465012) (xy 377.884182 -412.465012) (xy 377.911437 -412.465434)
			(xy 377.965393 -412.473189) (xy 378.017696 -412.488544) (xy 378.067281 -412.511187) (xy 378.113139 -412.540656)
			(xy 378.154336 -412.576352) (xy 378.190033 -412.617547) (xy 378.219504 -412.663403) (xy 378.242149 -412.712987)
			(xy 378.257507 -412.765289) (xy 378.265265 -412.819245) (xy 378.265265 -412.873752) (xy 379.702775 -412.873752)
			(xy 379.702775 -412.819248) (xy 379.710532 -412.765298) (xy 379.725889 -412.713001) (xy 379.748532 -412.663422)
			(xy 379.778 -412.61757) (xy 379.813694 -412.576379) (xy 379.854888 -412.540687) (xy 379.900741 -412.511221)
			(xy 379.950321 -412.488581) (xy 380.002619 -412.473228) (xy 380.05657 -412.465474) (xy 380.083822 -412.465012)
			(xy 380.947422 -412.465012) (xy 380.974674 -412.465459) (xy 381.028622 -412.473219) (xy 381.080917 -412.488577)
			(xy 381.130494 -412.51122) (xy 381.176344 -412.540689) (xy 381.217534 -412.576382) (xy 381.253225 -412.617574)
			(xy 381.28269 -412.663426) (xy 381.305331 -412.713004) (xy 381.320686 -412.7653) (xy 381.328442 -412.819248)
			(xy 381.328442 -412.873748) (xy 382.766098 -412.873748) (xy 382.766098 -412.819252) (xy 382.773853 -412.76531)
			(xy 382.789206 -412.713022) (xy 382.811843 -412.663449) (xy 382.841304 -412.617603) (xy 382.876989 -412.576416)
			(xy 382.918173 -412.540727) (xy 382.964016 -412.511261) (xy 383.013586 -412.488619) (xy 383.065873 -412.473261)
			(xy 383.119814 -412.465501) (xy 383.147062 -412.465012) (xy 384.010662 -412.465012) (xy 384.037918 -412.465432)
			(xy 384.091876 -412.473185) (xy 384.144181 -412.488539) (xy 384.193769 -412.51118) (xy 384.239629 -412.540649)
			(xy 384.280829 -412.576345) (xy 384.316528 -412.61754) (xy 384.346001 -412.663398) (xy 384.368648 -412.712983)
			(xy 384.384007 -412.765287) (xy 384.391765 -412.819244) (xy 384.391765 -412.873752) (xy 385.829275 -412.873752)
			(xy 385.829275 -412.819248) (xy 385.837032 -412.7653) (xy 385.852387 -412.713005) (xy 385.875029 -412.663427)
			(xy 385.904495 -412.617576) (xy 385.940187 -412.576386) (xy 385.981378 -412.540694) (xy 386.027229 -412.511228)
			(xy 386.076807 -412.488587) (xy 386.129102 -412.473231) (xy 386.18305 -412.465475) (xy 386.210302 -412.465012)
			(xy 387.073902 -412.465012) (xy 387.101155 -412.465458) (xy 387.155105 -412.473215) (xy 387.207402 -412.488571)
			(xy 387.256982 -412.511214) (xy 387.302834 -412.540682) (xy 387.344026 -412.576375) (xy 387.37972 -412.617567)
			(xy 387.409187 -412.66342) (xy 387.431829 -412.713) (xy 387.447185 -412.765297) (xy 387.454942 -412.819247)
			(xy 387.454942 -412.873753) (xy 388.892475 -412.873753) (xy 388.892475 -412.819247) (xy 388.900233 -412.765295)
			(xy 388.91559 -412.712996) (xy 388.938235 -412.663416) (xy 388.967705 -412.617563) (xy 389.003401 -412.576372)
			(xy 389.044597 -412.54068) (xy 389.090453 -412.511215) (xy 389.140036 -412.488576) (xy 389.192336 -412.473224)
			(xy 389.246289 -412.465472) (xy 389.273542 -412.465012) (xy 390.137142 -412.465012) (xy 390.164393 -412.465461)
			(xy 390.218339 -412.473222) (xy 390.270631 -412.488582) (xy 390.320206 -412.511227) (xy 390.366053 -412.540696)
			(xy 390.407241 -412.576389) (xy 390.442929 -412.61758) (xy 390.472393 -412.663431) (xy 390.495033 -412.713008)
			(xy 390.510386 -412.765302) (xy 390.518142 -412.819249) (xy 390.518142 -412.873749) (xy 391.955798 -412.873749)
			(xy 391.955798 -412.819251) (xy 391.963554 -412.765308) (xy 391.978907 -412.713017) (xy 392.001546 -412.663444)
			(xy 392.031009 -412.617597) (xy 392.066697 -412.576409) (xy 392.107882 -412.54072) (xy 392.153728 -412.511254)
			(xy 392.2033 -412.488613) (xy 392.25559 -412.473258) (xy 392.309533 -412.465499) (xy 392.336782 -412.465012)
			(xy 393.200382 -412.465012) (xy 393.227637 -412.465434) (xy 393.281593 -412.473189) (xy 393.333896 -412.488544)
			(xy 393.383481 -412.511187) (xy 393.429339 -412.540656) (xy 393.470536 -412.576352) (xy 393.506233 -412.617547)
			(xy 393.535704 -412.663403) (xy 393.558349 -412.712987) (xy 393.573707 -412.765289) (xy 393.581465 -412.819245)
			(xy 393.581465 -412.873752) (xy 395.018975 -412.873752) (xy 395.018975 -412.819248) (xy 395.026732 -412.765298)
			(xy 395.042089 -412.713001) (xy 395.064732 -412.663422) (xy 395.0942 -412.61757) (xy 395.129894 -412.576379)
			(xy 395.171088 -412.540687) (xy 395.216941 -412.511221) (xy 395.266521 -412.488581) (xy 395.318819 -412.473228)
			(xy 395.37277 -412.465474) (xy 395.400022 -412.465012) (xy 396.263622 -412.465012) (xy 396.290874 -412.465459)
			(xy 396.344822 -412.473219) (xy 396.397117 -412.488577) (xy 396.446694 -412.51122) (xy 396.492544 -412.540689)
			(xy 396.533734 -412.576382) (xy 396.569425 -412.617574) (xy 396.59889 -412.663426) (xy 396.621531 -412.713004)
			(xy 396.636886 -412.7653) (xy 396.644642 -412.819248) (xy 396.644642 -412.873748) (xy 398.082298 -412.873748)
			(xy 398.082298 -412.819252) (xy 398.090053 -412.76531) (xy 398.105406 -412.713022) (xy 398.128043 -412.663449)
			(xy 398.157504 -412.617603) (xy 398.193189 -412.576416) (xy 398.234373 -412.540727) (xy 398.280216 -412.511261)
			(xy 398.329786 -412.488619) (xy 398.382073 -412.473261) (xy 398.436014 -412.465501) (xy 398.463262 -412.465012)
			(xy 399.326862 -412.465012) (xy 399.354118 -412.465432) (xy 399.408076 -412.473185) (xy 399.460381 -412.488539)
			(xy 399.509969 -412.51118) (xy 399.555829 -412.540649) (xy 399.597029 -412.576345) (xy 399.632728 -412.61754)
			(xy 399.662201 -412.663398) (xy 399.684848 -412.712983) (xy 399.700207 -412.765287) (xy 399.707965 -412.819244)
			(xy 399.707965 -412.873752) (xy 401.145475 -412.873752) (xy 401.145475 -412.819248) (xy 401.153232 -412.7653)
			(xy 401.168587 -412.713005) (xy 401.191229 -412.663427) (xy 401.220695 -412.617576) (xy 401.256387 -412.576386)
			(xy 401.297578 -412.540694) (xy 401.343429 -412.511228) (xy 401.393007 -412.488587) (xy 401.445302 -412.473231)
			(xy 401.49925 -412.465475) (xy 401.526502 -412.465012) (xy 402.390102 -412.465012) (xy 402.417355 -412.465458)
			(xy 402.471305 -412.473215) (xy 402.523602 -412.488571) (xy 402.573182 -412.511214) (xy 402.619034 -412.540682)
			(xy 402.660226 -412.576375) (xy 402.69592 -412.617567) (xy 402.725387 -412.66342) (xy 402.748029 -412.713)
			(xy 402.763385 -412.765297) (xy 402.771142 -412.819247) (xy 402.771142 -412.873753) (xy 404.208675 -412.873753)
			(xy 404.208675 -412.819247) (xy 404.216433 -412.765295) (xy 404.23179 -412.712996) (xy 404.254435 -412.663416)
			(xy 404.283905 -412.617563) (xy 404.319601 -412.576372) (xy 404.360797 -412.54068) (xy 404.406653 -412.511215)
			(xy 404.456236 -412.488576) (xy 404.508536 -412.473224) (xy 404.562489 -412.465472) (xy 404.589742 -412.465012)
			(xy 405.453342 -412.465012) (xy 405.480593 -412.465461) (xy 405.534539 -412.473222) (xy 405.586831 -412.488582)
			(xy 405.636406 -412.511227) (xy 405.682253 -412.540696) (xy 405.723441 -412.576389) (xy 405.759129 -412.61758)
			(xy 405.788593 -412.663431) (xy 405.811233 -412.713008) (xy 405.826586 -412.765302) (xy 405.834342 -412.819249)
			(xy 405.834342 -412.873749) (xy 407.271998 -412.873749) (xy 407.271998 -412.819251) (xy 407.279754 -412.765308)
			(xy 407.295107 -412.713017) (xy 407.317746 -412.663444) (xy 407.347209 -412.617597) (xy 407.382897 -412.576409)
			(xy 407.424082 -412.54072) (xy 407.469928 -412.511254) (xy 407.5195 -412.488613) (xy 407.57179 -412.473258)
			(xy 407.625733 -412.465499) (xy 407.652982 -412.465012) (xy 408.516582 -412.465012) (xy 408.543837 -412.465434)
			(xy 408.597793 -412.473189) (xy 408.650096 -412.488544) (xy 408.699681 -412.511187) (xy 408.745539 -412.540656)
			(xy 408.786736 -412.576352) (xy 408.822433 -412.617547) (xy 408.851904 -412.663403) (xy 408.874549 -412.712987)
			(xy 408.889907 -412.765289) (xy 408.897665 -412.819245) (xy 408.897665 -412.873752) (xy 410.335175 -412.873752)
			(xy 410.335175 -412.819248) (xy 410.342932 -412.765298) (xy 410.358289 -412.713001) (xy 410.380932 -412.663422)
			(xy 410.4104 -412.61757) (xy 410.446094 -412.576379) (xy 410.487288 -412.540687) (xy 410.533141 -412.511221)
			(xy 410.582721 -412.488581) (xy 410.635019 -412.473228) (xy 410.68897 -412.465474) (xy 410.716222 -412.465012)
			(xy 411.579822 -412.465012) (xy 411.607074 -412.465459) (xy 411.661022 -412.473219) (xy 411.713317 -412.488577)
			(xy 411.762894 -412.51122) (xy 411.808744 -412.540689) (xy 411.849934 -412.576382) (xy 411.885625 -412.617574)
			(xy 411.91509 -412.663426) (xy 411.937731 -412.713004) (xy 411.953086 -412.7653) (xy 411.960842 -412.819248)
			(xy 411.960842 -412.873748) (xy 413.398498 -412.873748) (xy 413.398498 -412.819252) (xy 413.406253 -412.76531)
			(xy 413.421606 -412.713022) (xy 413.444243 -412.663449) (xy 413.473704 -412.617603) (xy 413.509389 -412.576416)
			(xy 413.550573 -412.540727) (xy 413.596416 -412.511261) (xy 413.645986 -412.488619) (xy 413.698273 -412.473261)
			(xy 413.752214 -412.465501) (xy 413.779462 -412.465012) (xy 414.643062 -412.465012) (xy 414.670318 -412.465432)
			(xy 414.724276 -412.473185) (xy 414.776581 -412.488539) (xy 414.826169 -412.51118) (xy 414.872029 -412.540649)
			(xy 414.913229 -412.576345) (xy 414.948928 -412.61754) (xy 414.978401 -412.663398) (xy 415.001048 -412.712983)
			(xy 415.016407 -412.765287) (xy 415.024165 -412.819244) (xy 415.024165 -412.873752) (xy 416.461675 -412.873752)
			(xy 416.461675 -412.819248) (xy 416.469432 -412.7653) (xy 416.484787 -412.713005) (xy 416.507429 -412.663427)
			(xy 416.536895 -412.617576) (xy 416.572587 -412.576386) (xy 416.613778 -412.540694) (xy 416.659629 -412.511228)
			(xy 416.709207 -412.488587) (xy 416.761502 -412.473231) (xy 416.81545 -412.465475) (xy 416.842702 -412.465012)
			(xy 417.706302 -412.465012) (xy 417.733555 -412.465458) (xy 417.787505 -412.473215) (xy 417.839802 -412.488571)
			(xy 417.889382 -412.511214) (xy 417.935234 -412.540682) (xy 417.976426 -412.576375) (xy 418.01212 -412.617567)
			(xy 418.041587 -412.66342) (xy 418.064229 -412.713) (xy 418.079585 -412.765297) (xy 418.087342 -412.819247)
			(xy 418.087342 -412.873753) (xy 418.079585 -412.927703) (xy 418.064229 -412.98) (xy 418.041587 -413.02958)
			(xy 418.01212 -413.075433) (xy 417.976426 -413.116625) (xy 417.935234 -413.152318) (xy 417.90754 -413.170116)
			(xy 422.998658 -413.170116) (xy 423.00263 -412.991873) (xy 423.014538 -412.813984) (xy 423.034359 -412.636802)
			(xy 423.062053 -412.460678) (xy 423.097565 -412.285963) (xy 423.140825 -412.113004) (xy 423.191747 -411.942143)
			(xy 423.25023 -411.773721) (xy 423.316157 -411.608071) (xy 423.389398 -411.445522) (xy 423.469808 -411.286397)
			(xy 423.557226 -411.131012) (xy 423.651479 -410.979676) (xy 423.75238 -410.832688) (xy 423.859729 -410.690341)
			(xy 423.973312 -410.552918) (xy 424.092905 -410.420691) (xy 424.218269 -410.293922) (xy 424.349156 -410.172864)
			(xy 424.485305 -410.057757) (xy 424.626447 -409.948829) (xy 424.772302 -409.846297) (xy 424.922579 -409.750363)
			(xy 425.07698 -409.66122) (xy 425.235199 -409.579043) (xy 425.396922 -409.503995) (xy 425.561827 -409.436227)
			(xy 425.729588 -409.375871) (xy 425.899871 -409.323049) (xy 426.072338 -409.277865) (xy 426.246646 -409.240408)
			(xy 426.42245 -409.210754) (xy 426.5994 -409.188961) (xy 426.777146 -409.175071) (xy 426.955333 -409.169114)
			(xy 427.13361 -409.1711) (xy 427.311621 -409.181026) (xy 427.489013 -409.198872) (xy 427.665433 -409.224602)
			(xy 427.840533 -409.258166) (xy 428.013964 -409.299496) (xy 428.185381 -409.348512) (xy 428.354444 -409.405114)
			(xy 428.520819 -409.469192) (xy 428.684173 -409.540618) (xy 428.844184 -409.61925) (xy 429.000533 -409.704931)
			(xy 429.15291 -409.797493) (xy 429.301013 -409.89675) (xy 429.444547 -410.002507) (xy 429.583227 -410.114552)
			(xy 429.716778 -410.232664) (xy 429.844935 -410.356608) (xy 429.967444 -410.486138) (xy 430.084061 -410.620997)
			(xy 430.194554 -410.760917) (xy 430.298705 -410.90562) (xy 430.396307 -411.054819) (xy 430.487165 -411.208218)
			(xy 430.571099 -411.365512) (xy 430.647944 -411.526388) (xy 430.717545 -411.690529) (xy 430.779766 -411.857606)
			(xy 430.834482 -412.02729) (xy 430.881584 -412.199243) (xy 430.92098 -412.373123) (xy 430.952591 -412.548586)
			(xy 430.976355 -412.725282) (xy 430.992223 -412.902862) (xy 431.000165 -413.080972) (xy 431.000662 -413.170116)
			(xy 431.000165 -413.25926) (xy 430.992223 -413.43737) (xy 430.976355 -413.61495) (xy 430.952591 -413.791646)
			(xy 430.92098 -413.967109) (xy 430.881584 -414.140989) (xy 430.834482 -414.312942) (xy 430.779766 -414.482626)
			(xy 430.717545 -414.649703) (xy 430.647944 -414.813844) (xy 430.571099 -414.97472) (xy 430.487165 -415.132014)
			(xy 430.396307 -415.285413) (xy 430.298705 -415.434612) (xy 430.194554 -415.579315) (xy 430.084061 -415.719235)
			(xy 429.967444 -415.854094) (xy 429.844935 -415.983624) (xy 429.716778 -416.107568) (xy 429.583227 -416.22568)
			(xy 429.444547 -416.337725) (xy 429.301013 -416.443482) (xy 429.15291 -416.542739) (xy 429.000533 -416.635301)
			(xy 428.844184 -416.720982) (xy 428.684173 -416.799614) (xy 428.520819 -416.87104) (xy 428.354444 -416.935118)
			(xy 428.185381 -416.99172) (xy 428.013964 -417.040736) (xy 427.840533 -417.082066) (xy 427.665433 -417.11563)
			(xy 427.489013 -417.14136) (xy 427.311621 -417.159206) (xy 427.13361 -417.169132) (xy 426.955333 -417.171118)
			(xy 426.777146 -417.165161) (xy 426.5994 -417.151271) (xy 426.42245 -417.129478) (xy 426.246646 -417.099824)
			(xy 426.072338 -417.062367) (xy 425.899871 -417.017183) (xy 425.729588 -416.964361) (xy 425.561827 -416.904005)
			(xy 425.396922 -416.836237) (xy 425.235199 -416.761189) (xy 425.07698 -416.679012) (xy 424.922579 -416.589869)
			(xy 424.772302 -416.493935) (xy 424.626447 -416.391403) (xy 424.485305 -416.282475) (xy 424.349156 -416.167368)
			(xy 424.218269 -416.04631) (xy 424.092905 -415.919541) (xy 423.973312 -415.787314) (xy 423.859729 -415.649891)
			(xy 423.75238 -415.507544) (xy 423.651479 -415.360556) (xy 423.557226 -415.20922) (xy 423.469808 -415.053835)
			(xy 423.389398 -414.89471) (xy 423.316157 -414.732161) (xy 423.25023 -414.566511) (xy 423.191747 -414.398089)
			(xy 423.140825 -414.227228) (xy 423.097565 -414.054269) (xy 423.062053 -413.879554) (xy 423.034359 -413.70343)
			(xy 423.014538 -413.526248) (xy 423.00263 -413.348359) (xy 422.998658 -413.170116) (xy 417.90754 -413.170116)
			(xy 417.889382 -413.181786) (xy 417.839802 -413.204429) (xy 417.787505 -413.219785) (xy 417.733555 -413.227542)
			(xy 417.706302 -413.228028) (xy 416.842702 -413.228028) (xy 416.81545 -413.227525) (xy 416.761502 -413.219769)
			(xy 416.709207 -413.204413) (xy 416.659629 -413.181772) (xy 416.613778 -413.152306) (xy 416.572587 -413.116614)
			(xy 416.536895 -413.075424) (xy 416.507429 -413.029573) (xy 416.484787 -412.979995) (xy 416.469432 -412.9277)
			(xy 416.461675 -412.873752) (xy 415.024165 -412.873752) (xy 415.024165 -412.873756) (xy 415.016407 -412.927713)
			(xy 415.001048 -412.980017) (xy 414.978401 -413.029602) (xy 414.948928 -413.07546) (xy 414.913229 -413.116655)
			(xy 414.872029 -413.152351) (xy 414.826169 -413.18182) (xy 414.776581 -413.204461) (xy 414.724276 -413.219815)
			(xy 414.670318 -413.227568) (xy 414.643062 -413.228028) (xy 413.779462 -413.228028) (xy 413.752214 -413.227499)
			(xy 413.698273 -413.219739) (xy 413.645986 -413.204381) (xy 413.596416 -413.181739) (xy 413.550573 -413.152273)
			(xy 413.509389 -413.116584) (xy 413.473704 -413.075397) (xy 413.444243 -413.029551) (xy 413.421606 -412.979978)
			(xy 413.406253 -412.92769) (xy 413.398498 -412.873748) (xy 411.960842 -412.873748) (xy 411.960842 -412.873752)
			(xy 411.953086 -412.9277) (xy 411.937731 -412.979996) (xy 411.91509 -413.029574) (xy 411.885625 -413.075426)
			(xy 411.849934 -413.116618) (xy 411.808744 -413.152311) (xy 411.762894 -413.18178) (xy 411.713317 -413.204423)
			(xy 411.661022 -413.219781) (xy 411.607074 -413.227541) (xy 411.579822 -413.228028) (xy 410.716222 -413.228028)
			(xy 410.68897 -413.227526) (xy 410.635019 -413.219772) (xy 410.582721 -413.204419) (xy 410.533141 -413.181779)
			(xy 410.487288 -413.152313) (xy 410.446094 -413.116621) (xy 410.4104 -413.07543) (xy 410.380932 -413.029578)
			(xy 410.358289 -412.979999) (xy 410.342932 -412.927702) (xy 410.335175 -412.873752) (xy 408.897665 -412.873752)
			(xy 408.897665 -412.873755) (xy 408.889907 -412.927711) (xy 408.874549 -412.980013) (xy 408.851904 -413.029597)
			(xy 408.822433 -413.075453) (xy 408.786736 -413.116648) (xy 408.745539 -413.152344) (xy 408.699681 -413.181813)
			(xy 408.650096 -413.204456) (xy 408.597793 -413.219811) (xy 408.543837 -413.227566) (xy 408.516582 -413.228028)
			(xy 407.652982 -413.228028) (xy 407.625733 -413.227501) (xy 407.57179 -413.219742) (xy 407.5195 -413.204387)
			(xy 407.469928 -413.181746) (xy 407.424082 -413.15228) (xy 407.382897 -413.116591) (xy 407.347209 -413.075403)
			(xy 407.317746 -413.029556) (xy 407.295107 -412.979983) (xy 407.279754 -412.927692) (xy 407.271998 -412.873749)
			(xy 405.834342 -412.873749) (xy 405.834342 -412.873751) (xy 405.826586 -412.927698) (xy 405.811233 -412.979992)
			(xy 405.788593 -413.029569) (xy 405.759129 -413.07542) (xy 405.723441 -413.116611) (xy 405.682253 -413.152304)
			(xy 405.636406 -413.181773) (xy 405.586831 -413.204418) (xy 405.534539 -413.219778) (xy 405.480593 -413.227539)
			(xy 405.453342 -413.228028) (xy 404.589742 -413.228028) (xy 404.562489 -413.227528) (xy 404.508536 -413.219776)
			(xy 404.456236 -413.204424) (xy 404.406653 -413.181785) (xy 404.360797 -413.15232) (xy 404.319601 -413.116628)
			(xy 404.283905 -413.075437) (xy 404.254435 -413.029584) (xy 404.23179 -412.980004) (xy 404.216433 -412.927705)
			(xy 404.208675 -412.873753) (xy 402.771142 -412.873753) (xy 402.763385 -412.927703) (xy 402.748029 -412.98)
			(xy 402.725387 -413.02958) (xy 402.69592 -413.075433) (xy 402.660226 -413.116625) (xy 402.619034 -413.152318)
			(xy 402.573182 -413.181786) (xy 402.523602 -413.204429) (xy 402.471305 -413.219785) (xy 402.417355 -413.227542)
			(xy 402.390102 -413.228028) (xy 401.526502 -413.228028) (xy 401.49925 -413.227525) (xy 401.445302 -413.219769)
			(xy 401.393007 -413.204413) (xy 401.343429 -413.181772) (xy 401.297578 -413.152306) (xy 401.256387 -413.116614)
			(xy 401.220695 -413.075424) (xy 401.191229 -413.029573) (xy 401.168587 -412.979995) (xy 401.153232 -412.9277)
			(xy 401.145475 -412.873752) (xy 399.707965 -412.873752) (xy 399.707965 -412.873756) (xy 399.700207 -412.927713)
			(xy 399.684848 -412.980017) (xy 399.662201 -413.029602) (xy 399.632728 -413.07546) (xy 399.597029 -413.116655)
			(xy 399.555829 -413.152351) (xy 399.509969 -413.18182) (xy 399.460381 -413.204461) (xy 399.408076 -413.219815)
			(xy 399.354118 -413.227568) (xy 399.326862 -413.228028) (xy 398.463262 -413.228028) (xy 398.436014 -413.227499)
			(xy 398.382073 -413.219739) (xy 398.329786 -413.204381) (xy 398.280216 -413.181739) (xy 398.234373 -413.152273)
			(xy 398.193189 -413.116584) (xy 398.157504 -413.075397) (xy 398.128043 -413.029551) (xy 398.105406 -412.979978)
			(xy 398.090053 -412.92769) (xy 398.082298 -412.873748) (xy 396.644642 -412.873748) (xy 396.644642 -412.873752)
			(xy 396.636886 -412.9277) (xy 396.621531 -412.979996) (xy 396.59889 -413.029574) (xy 396.569425 -413.075426)
			(xy 396.533734 -413.116618) (xy 396.492544 -413.152311) (xy 396.446694 -413.18178) (xy 396.397117 -413.204423)
			(xy 396.344822 -413.219781) (xy 396.290874 -413.227541) (xy 396.263622 -413.228028) (xy 395.400022 -413.228028)
			(xy 395.37277 -413.227526) (xy 395.318819 -413.219772) (xy 395.266521 -413.204419) (xy 395.216941 -413.181779)
			(xy 395.171088 -413.152313) (xy 395.129894 -413.116621) (xy 395.0942 -413.07543) (xy 395.064732 -413.029578)
			(xy 395.042089 -412.979999) (xy 395.026732 -412.927702) (xy 395.018975 -412.873752) (xy 393.581465 -412.873752)
			(xy 393.581465 -412.873755) (xy 393.573707 -412.927711) (xy 393.558349 -412.980013) (xy 393.535704 -413.029597)
			(xy 393.506233 -413.075453) (xy 393.470536 -413.116648) (xy 393.429339 -413.152344) (xy 393.383481 -413.181813)
			(xy 393.333896 -413.204456) (xy 393.281593 -413.219811) (xy 393.227637 -413.227566) (xy 393.200382 -413.228028)
			(xy 392.336782 -413.228028) (xy 392.309533 -413.227501) (xy 392.25559 -413.219742) (xy 392.2033 -413.204387)
			(xy 392.153728 -413.181746) (xy 392.107882 -413.15228) (xy 392.066697 -413.116591) (xy 392.031009 -413.075403)
			(xy 392.001546 -413.029556) (xy 391.978907 -412.979983) (xy 391.963554 -412.927692) (xy 391.955798 -412.873749)
			(xy 390.518142 -412.873749) (xy 390.518142 -412.873751) (xy 390.510386 -412.927698) (xy 390.495033 -412.979992)
			(xy 390.472393 -413.029569) (xy 390.442929 -413.07542) (xy 390.407241 -413.116611) (xy 390.366053 -413.152304)
			(xy 390.320206 -413.181773) (xy 390.270631 -413.204418) (xy 390.218339 -413.219778) (xy 390.164393 -413.227539)
			(xy 390.137142 -413.228028) (xy 389.273542 -413.228028) (xy 389.246289 -413.227528) (xy 389.192336 -413.219776)
			(xy 389.140036 -413.204424) (xy 389.090453 -413.181785) (xy 389.044597 -413.15232) (xy 389.003401 -413.116628)
			(xy 388.967705 -413.075437) (xy 388.938235 -413.029584) (xy 388.91559 -412.980004) (xy 388.900233 -412.927705)
			(xy 388.892475 -412.873753) (xy 387.454942 -412.873753) (xy 387.447185 -412.927703) (xy 387.431829 -412.98)
			(xy 387.409187 -413.02958) (xy 387.37972 -413.075433) (xy 387.344026 -413.116625) (xy 387.302834 -413.152318)
			(xy 387.256982 -413.181786) (xy 387.207402 -413.204429) (xy 387.155105 -413.219785) (xy 387.101155 -413.227542)
			(xy 387.073902 -413.228028) (xy 386.210302 -413.228028) (xy 386.18305 -413.227525) (xy 386.129102 -413.219769)
			(xy 386.076807 -413.204413) (xy 386.027229 -413.181772) (xy 385.981378 -413.152306) (xy 385.940187 -413.116614)
			(xy 385.904495 -413.075424) (xy 385.875029 -413.029573) (xy 385.852387 -412.979995) (xy 385.837032 -412.9277)
			(xy 385.829275 -412.873752) (xy 384.391765 -412.873752) (xy 384.391765 -412.873756) (xy 384.384007 -412.927713)
			(xy 384.368648 -412.980017) (xy 384.346001 -413.029602) (xy 384.316528 -413.07546) (xy 384.280829 -413.116655)
			(xy 384.239629 -413.152351) (xy 384.193769 -413.18182) (xy 384.144181 -413.204461) (xy 384.091876 -413.219815)
			(xy 384.037918 -413.227568) (xy 384.010662 -413.228028) (xy 383.147062 -413.228028) (xy 383.119814 -413.227499)
			(xy 383.065873 -413.219739) (xy 383.013586 -413.204381) (xy 382.964016 -413.181739) (xy 382.918173 -413.152273)
			(xy 382.876989 -413.116584) (xy 382.841304 -413.075397) (xy 382.811843 -413.029551) (xy 382.789206 -412.979978)
			(xy 382.773853 -412.92769) (xy 382.766098 -412.873748) (xy 381.328442 -412.873748) (xy 381.328442 -412.873752)
			(xy 381.320686 -412.9277) (xy 381.305331 -412.979996) (xy 381.28269 -413.029574) (xy 381.253225 -413.075426)
			(xy 381.217534 -413.116618) (xy 381.176344 -413.152311) (xy 381.130494 -413.18178) (xy 381.080917 -413.204423)
			(xy 381.028622 -413.219781) (xy 380.974674 -413.227541) (xy 380.947422 -413.228028) (xy 380.083822 -413.228028)
			(xy 380.05657 -413.227526) (xy 380.002619 -413.219772) (xy 379.950321 -413.204419) (xy 379.900741 -413.181779)
			(xy 379.854888 -413.152313) (xy 379.813694 -413.116621) (xy 379.778 -413.07543) (xy 379.748532 -413.029578)
			(xy 379.725889 -412.979999) (xy 379.710532 -412.927702) (xy 379.702775 -412.873752) (xy 378.265265 -412.873752)
			(xy 378.265265 -412.873755) (xy 378.257507 -412.927711) (xy 378.242149 -412.980013) (xy 378.219504 -413.029597)
			(xy 378.190033 -413.075453) (xy 378.154336 -413.116648) (xy 378.113139 -413.152344) (xy 378.067281 -413.181813)
			(xy 378.017696 -413.204456) (xy 377.965393 -413.219811) (xy 377.911437 -413.227566) (xy 377.884182 -413.228028)
			(xy 377.020582 -413.228028) (xy 376.993333 -413.227501) (xy 376.93939 -413.219742) (xy 376.8871 -413.204387)
			(xy 376.837528 -413.181746) (xy 376.791682 -413.15228) (xy 376.750497 -413.116591) (xy 376.714809 -413.075403)
			(xy 376.685346 -413.029556) (xy 376.662707 -412.979983) (xy 376.647354 -412.927692) (xy 376.639598 -412.873749)
			(xy 375.201942 -412.873749) (xy 375.201942 -412.873751) (xy 375.194186 -412.927698) (xy 375.178833 -412.979992)
			(xy 375.156193 -413.029569) (xy 375.126729 -413.07542) (xy 375.091041 -413.116611) (xy 375.049853 -413.152304)
			(xy 375.004006 -413.181773) (xy 374.954431 -413.204418) (xy 374.902139 -413.219778) (xy 374.848193 -413.227539)
			(xy 374.820942 -413.228028) (xy 373.957342 -413.228028) (xy 373.930089 -413.227528) (xy 373.876136 -413.219776)
			(xy 373.823836 -413.204424) (xy 373.774253 -413.181785) (xy 373.728397 -413.15232) (xy 373.687201 -413.116628)
			(xy 373.651505 -413.075437) (xy 373.622035 -413.029584) (xy 373.59939 -412.980004) (xy 373.584033 -412.927705)
			(xy 373.576275 -412.873753) (xy 372.138742 -412.873753) (xy 372.130985 -412.927703) (xy 372.115629 -412.98)
			(xy 372.092987 -413.02958) (xy 372.06352 -413.075433) (xy 372.027826 -413.116625) (xy 371.986634 -413.152318)
			(xy 371.940782 -413.181786) (xy 371.891202 -413.204429) (xy 371.838905 -413.219785) (xy 371.784955 -413.227542)
			(xy 371.757702 -413.228028) (xy 370.894102 -413.228028) (xy 370.86685 -413.227525) (xy 370.812902 -413.219769)
			(xy 370.760607 -413.204413) (xy 370.711029 -413.181772) (xy 370.665178 -413.152306) (xy 370.623987 -413.116614)
			(xy 370.588295 -413.075424) (xy 370.558829 -413.029573) (xy 370.536187 -412.979995) (xy 370.520832 -412.9277)
			(xy 370.513075 -412.873752) (xy 350.987142 -412.873752) (xy 350.979385 -412.927702) (xy 350.96403 -412.979999)
			(xy 350.941388 -413.029579) (xy 350.911921 -413.075431) (xy 350.876228 -413.116624) (xy 350.835036 -413.152317)
			(xy 350.789184 -413.181785) (xy 350.739605 -413.204428) (xy 350.687308 -413.219784) (xy 350.633358 -413.227542)
			(xy 350.606106 -413.228028) (xy 349.742506 -413.228028) (xy 349.715254 -413.227525) (xy 349.661306 -413.219769)
			(xy 349.60901 -413.204415) (xy 349.559431 -413.181774) (xy 349.51358 -413.152307) (xy 349.472389 -413.116616)
			(xy 349.436696 -413.075425) (xy 349.407229 -413.029574) (xy 349.384588 -412.979996) (xy 349.369232 -412.9277)
			(xy 349.361475 -412.873752) (xy 347.923965 -412.873752) (xy 347.923965 -412.873756) (xy 347.916207 -412.927713)
			(xy 347.900848 -412.980016) (xy 347.878202 -413.029601) (xy 347.848729 -413.075458) (xy 347.81303 -413.116654)
			(xy 347.771831 -413.15235) (xy 347.725971 -413.181818) (xy 347.676384 -413.20446) (xy 347.624079 -413.219814)
			(xy 347.570122 -413.227567) (xy 347.542866 -413.228028) (xy 346.679266 -413.228028) (xy 346.652018 -413.227499)
			(xy 346.598077 -413.219739) (xy 346.545789 -413.204382) (xy 346.496218 -413.18174) (xy 346.450375 -413.152275)
			(xy 346.409191 -413.116585) (xy 346.373505 -413.075398) (xy 346.344043 -413.029552) (xy 346.321406 -412.979979)
			(xy 346.306053 -412.92769) (xy 346.298298 -412.873748) (xy 344.860642 -412.873748) (xy 344.860642 -412.873751)
			(xy 344.852886 -412.9277) (xy 344.837531 -412.979995) (xy 344.814891 -413.029573) (xy 344.785426 -413.075425)
			(xy 344.749735 -413.116617) (xy 344.708546 -413.15231) (xy 344.662696 -413.181778) (xy 344.61312 -413.204422)
			(xy 344.560825 -413.21978) (xy 344.506877 -413.22754) (xy 344.479626 -413.228028) (xy 343.616026 -413.228028)
			(xy 343.588773 -413.227526) (xy 343.534822 -413.219773) (xy 343.482524 -413.20442) (xy 343.432943 -413.18178)
			(xy 343.387089 -413.152314) (xy 343.345896 -413.116623) (xy 343.310201 -413.075431) (xy 343.280732 -413.029579)
			(xy 343.258089 -412.98) (xy 343.242733 -412.927703) (xy 343.234975 -412.873753) (xy 341.797465 -412.873753)
			(xy 341.797465 -412.873755) (xy 341.789707 -412.92771) (xy 341.77435 -412.980012) (xy 341.751705 -413.029595)
			(xy 341.722234 -413.075452) (xy 341.686537 -413.116647) (xy 341.645341 -413.152343) (xy 341.599483 -413.181812)
			(xy 341.549899 -413.204455) (xy 341.497596 -413.21981) (xy 341.443641 -413.227566) (xy 341.416386 -413.228028)
			(xy 340.552786 -413.228028) (xy 340.525537 -413.227501) (xy 340.471594 -413.219743) (xy 340.419303 -413.204388)
			(xy 340.36973 -413.181747) (xy 340.323884 -413.152282) (xy 340.282698 -413.116592) (xy 340.24701 -413.075404)
			(xy 340.217546 -413.029557) (xy 340.194908 -412.979984) (xy 340.179554 -412.927693) (xy 340.171798 -412.873749)
			(xy 338.734142 -412.873749) (xy 338.734142 -412.873751) (xy 338.726387 -412.927697) (xy 338.711033 -412.979991)
			(xy 338.688394 -413.029568) (xy 338.65893 -413.075418) (xy 338.623242 -413.116609) (xy 338.582055 -413.152303)
			(xy 338.536208 -413.181772) (xy 338.486634 -413.204417) (xy 338.434342 -413.219777) (xy 338.380397 -413.227539)
			(xy 338.353146 -413.228028) (xy 337.489546 -413.228028) (xy 337.462292 -413.227528) (xy 337.408339 -413.219777)
			(xy 337.356039 -413.204425) (xy 337.306455 -413.181787) (xy 337.260599 -413.152321) (xy 337.219403 -413.11663)
			(xy 337.183706 -413.075438) (xy 337.154235 -413.029585) (xy 337.131591 -412.980004) (xy 337.116233 -412.927706)
			(xy 337.108475 -412.873754) (xy 335.670942 -412.873754) (xy 335.663185 -412.927702) (xy 335.64783 -412.979999)
			(xy 335.625188 -413.029579) (xy 335.595721 -413.075431) (xy 335.560028 -413.116624) (xy 335.518836 -413.152317)
			(xy 335.472984 -413.181785) (xy 335.423405 -413.204428) (xy 335.371108 -413.219784) (xy 335.317158 -413.227542)
			(xy 335.289906 -413.228028) (xy 334.426306 -413.228028) (xy 334.399054 -413.227525) (xy 334.345106 -413.219769)
			(xy 334.29281 -413.204415) (xy 334.243231 -413.181774) (xy 334.19738 -413.152307) (xy 334.156189 -413.116616)
			(xy 334.120496 -413.075425) (xy 334.091029 -413.029574) (xy 334.068388 -412.979996) (xy 334.053032 -412.9277)
			(xy 334.045275 -412.873752) (xy 332.607765 -412.873752) (xy 332.607765 -412.873756) (xy 332.600007 -412.927713)
			(xy 332.584648 -412.980016) (xy 332.562002 -413.029601) (xy 332.532529 -413.075458) (xy 332.49683 -413.116654)
			(xy 332.455631 -413.15235) (xy 332.409771 -413.181818) (xy 332.360184 -413.20446) (xy 332.307879 -413.219814)
			(xy 332.253922 -413.227567) (xy 332.226666 -413.228028) (xy 331.363066 -413.228028) (xy 331.335818 -413.227499)
			(xy 331.281877 -413.219739) (xy 331.229589 -413.204382) (xy 331.180018 -413.18174) (xy 331.134175 -413.152275)
			(xy 331.092991 -413.116585) (xy 331.057305 -413.075398) (xy 331.027843 -413.029552) (xy 331.005206 -412.979979)
			(xy 330.989853 -412.92769) (xy 330.982098 -412.873748) (xy 329.544442 -412.873748) (xy 329.544442 -412.873751)
			(xy 329.536686 -412.9277) (xy 329.521331 -412.979995) (xy 329.498691 -413.029573) (xy 329.469226 -413.075425)
			(xy 329.433535 -413.116617) (xy 329.392346 -413.15231) (xy 329.346496 -413.181778) (xy 329.29692 -413.204422)
			(xy 329.244625 -413.21978) (xy 329.190677 -413.22754) (xy 329.163426 -413.228028) (xy 328.299826 -413.228028)
			(xy 328.272573 -413.227526) (xy 328.218622 -413.219773) (xy 328.166324 -413.20442) (xy 328.116743 -413.18178)
			(xy 328.070889 -413.152314) (xy 328.029696 -413.116623) (xy 327.994001 -413.075431) (xy 327.964532 -413.029579)
			(xy 327.941889 -412.98) (xy 327.926533 -412.927703) (xy 327.918775 -412.873753) (xy 326.481265 -412.873753)
			(xy 326.481265 -412.873755) (xy 326.473507 -412.92771) (xy 326.45815 -412.980012) (xy 326.435505 -413.029595)
			(xy 326.406034 -413.075452) (xy 326.370337 -413.116647) (xy 326.329141 -413.152343) (xy 326.283283 -413.181812)
			(xy 326.233699 -413.204455) (xy 326.181396 -413.21981) (xy 326.127441 -413.227566) (xy 326.100186 -413.228028)
			(xy 325.236586 -413.228028) (xy 325.209337 -413.227501) (xy 325.155394 -413.219743) (xy 325.103103 -413.204388)
			(xy 325.05353 -413.181747) (xy 325.007684 -413.152282) (xy 324.966498 -413.116592) (xy 324.93081 -413.075404)
			(xy 324.901346 -413.029557) (xy 324.878708 -412.979984) (xy 324.863354 -412.927693) (xy 324.855598 -412.873749)
			(xy 323.417942 -412.873749) (xy 323.417942 -412.873751) (xy 323.410187 -412.927697) (xy 323.394833 -412.979991)
			(xy 323.372194 -413.029568) (xy 323.34273 -413.075418) (xy 323.307042 -413.116609) (xy 323.265855 -413.152303)
			(xy 323.220008 -413.181772) (xy 323.170434 -413.204417) (xy 323.118142 -413.219777) (xy 323.064197 -413.227539)
			(xy 323.036946 -413.228028) (xy 322.173346 -413.228028) (xy 322.146092 -413.227528) (xy 322.092139 -413.219777)
			(xy 322.039839 -413.204425) (xy 321.990255 -413.181787) (xy 321.944399 -413.152321) (xy 321.903203 -413.11663)
			(xy 321.867506 -413.075438) (xy 321.838035 -413.029585) (xy 321.815391 -412.980004) (xy 321.800033 -412.927706)
			(xy 321.792275 -412.873754) (xy 320.354742 -412.873754) (xy 320.346985 -412.927702) (xy 320.33163 -412.979999)
			(xy 320.308988 -413.029579) (xy 320.279521 -413.075431) (xy 320.243828 -413.116624) (xy 320.202636 -413.152317)
			(xy 320.156784 -413.181785) (xy 320.107205 -413.204428) (xy 320.054908 -413.219784) (xy 320.000958 -413.227542)
			(xy 319.973706 -413.228028) (xy 319.110106 -413.228028) (xy 319.082854 -413.227525) (xy 319.028906 -413.219769)
			(xy 318.97661 -413.204415) (xy 318.927031 -413.181774) (xy 318.88118 -413.152307) (xy 318.839989 -413.116616)
			(xy 318.804296 -413.075425) (xy 318.774829 -413.029574) (xy 318.752188 -412.979996) (xy 318.736832 -412.9277)
			(xy 318.729075 -412.873752) (xy 317.291565 -412.873752) (xy 317.291565 -412.873756) (xy 317.283807 -412.927713)
			(xy 317.268448 -412.980016) (xy 317.245802 -413.029601) (xy 317.216329 -413.075458) (xy 317.18063 -413.116654)
			(xy 317.139431 -413.15235) (xy 317.093571 -413.181818) (xy 317.043984 -413.20446) (xy 316.991679 -413.219814)
			(xy 316.937722 -413.227567) (xy 316.910466 -413.228028) (xy 316.046866 -413.228028) (xy 316.019618 -413.227499)
			(xy 315.965677 -413.219739) (xy 315.913389 -413.204382) (xy 315.863818 -413.18174) (xy 315.817975 -413.152275)
			(xy 315.776791 -413.116585) (xy 315.741105 -413.075398) (xy 315.711643 -413.029552) (xy 315.689006 -412.979979)
			(xy 315.673653 -412.92769) (xy 315.665898 -412.873748) (xy 314.228242 -412.873748) (xy 314.228242 -412.873751)
			(xy 314.220486 -412.9277) (xy 314.205131 -412.979995) (xy 314.182491 -413.029573) (xy 314.153026 -413.075425)
			(xy 314.117335 -413.116617) (xy 314.076146 -413.15231) (xy 314.030296 -413.181778) (xy 313.98072 -413.204422)
			(xy 313.928425 -413.21978) (xy 313.874477 -413.22754) (xy 313.847226 -413.228028) (xy 312.983626 -413.228028)
			(xy 312.956373 -413.227526) (xy 312.902422 -413.219773) (xy 312.850124 -413.20442) (xy 312.800543 -413.18178)
			(xy 312.754689 -413.152314) (xy 312.713496 -413.116623) (xy 312.677801 -413.075431) (xy 312.648332 -413.029579)
			(xy 312.625689 -412.98) (xy 312.610333 -412.927703) (xy 312.602575 -412.873753) (xy 311.165065 -412.873753)
			(xy 311.165065 -412.873755) (xy 311.157307 -412.92771) (xy 311.14195 -412.980012) (xy 311.119305 -413.029595)
			(xy 311.089834 -413.075452) (xy 311.054137 -413.116647) (xy 311.012941 -413.152343) (xy 310.967083 -413.181812)
			(xy 310.917499 -413.204455) (xy 310.865196 -413.21981) (xy 310.811241 -413.227566) (xy 310.783986 -413.228028)
			(xy 309.920386 -413.228028) (xy 309.893137 -413.227501) (xy 309.839194 -413.219743) (xy 309.786903 -413.204388)
			(xy 309.73733 -413.181747) (xy 309.691484 -413.152282) (xy 309.650298 -413.116592) (xy 309.61461 -413.075404)
			(xy 309.585146 -413.029557) (xy 309.562508 -412.979984) (xy 309.547154 -412.927693) (xy 309.539398 -412.873749)
			(xy 308.101742 -412.873749) (xy 308.101742 -412.873751) (xy 308.093987 -412.927697) (xy 308.078633 -412.979991)
			(xy 308.055994 -413.029568) (xy 308.02653 -413.075418) (xy 307.990842 -413.116609) (xy 307.949655 -413.152303)
			(xy 307.903808 -413.181772) (xy 307.854234 -413.204417) (xy 307.801942 -413.219777) (xy 307.747997 -413.227539)
			(xy 307.720746 -413.228028) (xy 306.857146 -413.228028) (xy 306.829892 -413.227528) (xy 306.775939 -413.219777)
			(xy 306.723639 -413.204425) (xy 306.674055 -413.181787) (xy 306.628199 -413.152321) (xy 306.587003 -413.11663)
			(xy 306.551306 -413.075438) (xy 306.521835 -413.029585) (xy 306.499191 -412.980004) (xy 306.483833 -412.927706)
			(xy 306.476075 -412.873754) (xy 305.038542 -412.873754) (xy 305.030785 -412.927702) (xy 305.01543 -412.979999)
			(xy 304.992788 -413.029579) (xy 304.963321 -413.075431) (xy 304.927628 -413.116624) (xy 304.886436 -413.152317)
			(xy 304.840584 -413.181785) (xy 304.791005 -413.204428) (xy 304.738708 -413.219784) (xy 304.684758 -413.227542)
			(xy 304.657506 -413.228028) (xy 303.793906 -413.228028) (xy 303.766654 -413.227525) (xy 303.712706 -413.219769)
			(xy 303.66041 -413.204415) (xy 303.610831 -413.181774) (xy 303.56498 -413.152307) (xy 303.523789 -413.116616)
			(xy 303.488096 -413.075425) (xy 303.458629 -413.029574) (xy 303.435988 -412.979996) (xy 303.420632 -412.9277)
			(xy 303.412875 -412.873752) (xy 301.559858 -412.873752) (xy 301.562459 -412.902862) (xy 301.570401 -413.080972)
			(xy 301.570898 -413.170116) (xy 301.570401 -413.25926) (xy 301.562459 -413.43737) (xy 301.546591 -413.61495)
			(xy 301.522827 -413.791646) (xy 301.491216 -413.967109) (xy 301.45182 -414.140989) (xy 301.404718 -414.312942)
			(xy 301.350002 -414.482626) (xy 301.287781 -414.649703) (xy 301.21818 -414.813844) (xy 301.141335 -414.97472)
			(xy 301.057401 -415.132014) (xy 300.966543 -415.285413) (xy 300.882586 -415.413753) (xy 304.944475 -415.413753)
			(xy 304.944475 -415.359247) (xy 304.952233 -415.305297) (xy 304.967589 -415.253) (xy 304.990232 -415.203421)
			(xy 305.019701 -415.157569) (xy 305.055396 -415.116377) (xy 305.096589 -415.080686) (xy 305.142443 -415.05122)
			(xy 305.192024 -415.02858) (xy 305.244322 -415.013227) (xy 305.298273 -415.005474) (xy 305.325526 -415.005012)
			(xy 306.189126 -415.005012) (xy 306.216377 -415.00546) (xy 306.270325 -415.01322) (xy 306.32262 -415.028578)
			(xy 306.372196 -415.051222) (xy 306.418046 -415.08069) (xy 306.459235 -415.116383) (xy 306.494926 -415.157575)
			(xy 306.524391 -415.203427) (xy 306.547031 -415.253005) (xy 306.562386 -415.3053) (xy 306.570142 -415.359249)
			(xy 306.570142 -415.413748) (xy 308.007798 -415.413748) (xy 308.007798 -415.359252) (xy 308.015553 -415.30531)
			(xy 308.030906 -415.253021) (xy 308.053543 -415.203448) (xy 308.083005 -415.157602) (xy 308.118691 -415.116415)
			(xy 308.159875 -415.080725) (xy 308.205718 -415.05126) (xy 308.255289 -415.028618) (xy 308.307577 -415.013261)
			(xy 308.361518 -415.005501) (xy 308.388766 -415.005012) (xy 309.252366 -415.005012) (xy 309.279622 -415.005433)
			(xy 309.333579 -415.013186) (xy 309.385884 -415.02854) (xy 309.435471 -415.051182) (xy 309.481331 -415.08065)
			(xy 309.52253 -415.116346) (xy 309.558229 -415.157542) (xy 309.587702 -415.203399) (xy 309.610348 -415.252984)
			(xy 309.625707 -415.305287) (xy 309.633465 -415.359244) (xy 309.633465 -415.413752) (xy 311.070975 -415.413752)
			(xy 311.070975 -415.359248) (xy 311.078732 -415.3053) (xy 311.094088 -415.253004) (xy 311.116729 -415.203426)
			(xy 311.146196 -415.157575) (xy 311.181889 -415.116384) (xy 311.22308 -415.080693) (xy 311.268931 -415.051226)
			(xy 311.31851 -415.028585) (xy 311.370806 -415.013231) (xy 311.424754 -415.005475) (xy 311.452006 -415.005012)
			(xy 312.315606 -415.005012) (xy 312.342858 -415.005458) (xy 312.396808 -415.013216) (xy 312.449105 -415.028572)
			(xy 312.498684 -415.051215) (xy 312.544536 -415.080683) (xy 312.585728 -415.116376) (xy 312.621421 -415.157569)
			(xy 312.650888 -415.203421) (xy 312.67353 -415.253001) (xy 312.688885 -415.305298) (xy 312.696642 -415.359248)
			(xy 312.696642 -415.413752) (xy 312.696642 -415.413754) (xy 314.134175 -415.413754) (xy 314.134175 -415.359246)
			(xy 314.141933 -415.305294) (xy 314.157291 -415.252996) (xy 314.179935 -415.203415) (xy 314.209406 -415.157562)
			(xy 314.245103 -415.11637) (xy 314.286299 -415.080679) (xy 314.332155 -415.051213) (xy 314.381739 -415.028575)
			(xy 314.434039 -415.013223) (xy 314.487992 -415.005472) (xy 314.515246 -415.005012) (xy 315.378846 -415.005012)
			(xy 315.406097 -415.005461) (xy 315.460042 -415.013223) (xy 315.512334 -415.028583) (xy 315.561908 -415.051228)
			(xy 315.607755 -415.080697) (xy 315.648942 -415.116391) (xy 315.68463 -415.157582) (xy 315.714094 -415.203432)
			(xy 315.736733 -415.253009) (xy 315.752087 -415.305303) (xy 315.759842 -415.359249) (xy 315.759842 -415.413749)
			(xy 317.197498 -415.413749) (xy 317.197498 -415.359251) (xy 317.205254 -415.305307) (xy 317.220608 -415.253016)
			(xy 317.243246 -415.203443) (xy 317.27271 -415.157596) (xy 317.308398 -415.116408) (xy 317.349584 -415.080718)
			(xy 317.39543 -415.051253) (xy 317.445003 -415.028612) (xy 317.497294 -415.013257) (xy 317.551237 -415.005499)
			(xy 317.578486 -415.005012) (xy 318.442086 -415.005012) (xy 318.469341 -415.005434) (xy 318.523296 -415.01319)
			(xy 318.575599 -415.028545) (xy 318.625183 -415.051188) (xy 318.671041 -415.080657) (xy 318.712237 -415.116353)
			(xy 318.747934 -415.157548) (xy 318.777405 -415.203405) (xy 318.80005 -415.252988) (xy 318.815407 -415.30529)
			(xy 318.823165 -415.359245) (xy 318.823165 -415.413753) (xy 320.260675 -415.413753) (xy 320.260675 -415.359247)
			(xy 320.268433 -415.305297) (xy 320.283789 -415.253) (xy 320.306432 -415.203421) (xy 320.335901 -415.157569)
			(xy 320.371596 -415.116377) (xy 320.412789 -415.080686) (xy 320.458643 -415.05122) (xy 320.508224 -415.02858)
			(xy 320.560522 -415.013227) (xy 320.614473 -415.005474) (xy 320.641726 -415.005012) (xy 321.505326 -415.005012)
			(xy 321.532577 -415.00546) (xy 321.586525 -415.01322) (xy 321.63882 -415.028578) (xy 321.688396 -415.051222)
			(xy 321.734246 -415.08069) (xy 321.775435 -415.116383) (xy 321.811126 -415.157575) (xy 321.840591 -415.203427)
			(xy 321.863231 -415.253005) (xy 321.878586 -415.3053) (xy 321.886342 -415.359249) (xy 321.886342 -415.413748)
			(xy 323.323998 -415.413748) (xy 323.323998 -415.359252) (xy 323.331753 -415.30531) (xy 323.347106 -415.253021)
			(xy 323.369743 -415.203448) (xy 323.399205 -415.157602) (xy 323.434891 -415.116415) (xy 323.476075 -415.080725)
			(xy 323.521918 -415.05126) (xy 323.571489 -415.028618) (xy 323.623777 -415.013261) (xy 323.677718 -415.005501)
			(xy 323.704966 -415.005012) (xy 324.568566 -415.005012) (xy 324.595822 -415.005433) (xy 324.649779 -415.013186)
			(xy 324.702084 -415.02854) (xy 324.751671 -415.051182) (xy 324.797531 -415.08065) (xy 324.83873 -415.116346)
			(xy 324.874429 -415.157542) (xy 324.903902 -415.203399) (xy 324.926548 -415.252984) (xy 324.941907 -415.305287)
			(xy 324.949665 -415.359244) (xy 324.949665 -415.413752) (xy 326.387175 -415.413752) (xy 326.387175 -415.359248)
			(xy 326.394932 -415.3053) (xy 326.410288 -415.253004) (xy 326.432929 -415.203426) (xy 326.462396 -415.157575)
			(xy 326.498089 -415.116384) (xy 326.53928 -415.080693) (xy 326.585131 -415.051226) (xy 326.63471 -415.028585)
			(xy 326.687006 -415.013231) (xy 326.740954 -415.005475) (xy 326.768206 -415.005012) (xy 327.631806 -415.005012)
			(xy 327.659058 -415.005458) (xy 327.713008 -415.013216) (xy 327.765305 -415.028572) (xy 327.814884 -415.051215)
			(xy 327.860736 -415.080683) (xy 327.901928 -415.116376) (xy 327.937621 -415.157569) (xy 327.967088 -415.203421)
			(xy 327.98973 -415.253001) (xy 328.005085 -415.305298) (xy 328.012842 -415.359248) (xy 328.012842 -415.413752)
			(xy 328.012842 -415.413754) (xy 329.450375 -415.413754) (xy 329.450375 -415.359246) (xy 329.458133 -415.305294)
			(xy 329.473491 -415.252996) (xy 329.496135 -415.203415) (xy 329.525606 -415.157562) (xy 329.561303 -415.11637)
			(xy 329.602499 -415.080679) (xy 329.648355 -415.051213) (xy 329.697939 -415.028575) (xy 329.750239 -415.013223)
			(xy 329.804192 -415.005472) (xy 329.831446 -415.005012) (xy 330.695046 -415.005012) (xy 330.722297 -415.005461)
			(xy 330.776242 -415.013223) (xy 330.828534 -415.028583) (xy 330.878108 -415.051228) (xy 330.923955 -415.080697)
			(xy 330.965142 -415.116391) (xy 331.00083 -415.157582) (xy 331.030294 -415.203432) (xy 331.052933 -415.253009)
			(xy 331.068287 -415.305303) (xy 331.076042 -415.359249) (xy 331.076042 -415.413749) (xy 332.513698 -415.413749)
			(xy 332.513698 -415.359251) (xy 332.521454 -415.305307) (xy 332.536808 -415.253016) (xy 332.559446 -415.203443)
			(xy 332.58891 -415.157596) (xy 332.624598 -415.116408) (xy 332.665784 -415.080718) (xy 332.71163 -415.051253)
			(xy 332.761203 -415.028612) (xy 332.813494 -415.013257) (xy 332.867437 -415.005499) (xy 332.894686 -415.005012)
			(xy 333.758286 -415.005012) (xy 333.785541 -415.005434) (xy 333.839496 -415.01319) (xy 333.891799 -415.028545)
			(xy 333.941383 -415.051188) (xy 333.987241 -415.080657) (xy 334.028437 -415.116353) (xy 334.064134 -415.157548)
			(xy 334.093605 -415.203405) (xy 334.11625 -415.252988) (xy 334.131607 -415.30529) (xy 334.139365 -415.359245)
			(xy 334.139365 -415.413753) (xy 335.576875 -415.413753) (xy 335.576875 -415.359247) (xy 335.584633 -415.305297)
			(xy 335.599989 -415.253) (xy 335.622632 -415.203421) (xy 335.652101 -415.157569) (xy 335.687796 -415.116377)
			(xy 335.728989 -415.080686) (xy 335.774843 -415.05122) (xy 335.824424 -415.02858) (xy 335.876722 -415.013227)
			(xy 335.930673 -415.005474) (xy 335.957926 -415.005012) (xy 336.821526 -415.005012) (xy 336.848777 -415.00546)
			(xy 336.902725 -415.01322) (xy 336.95502 -415.028578) (xy 337.004596 -415.051222) (xy 337.050446 -415.08069)
			(xy 337.091635 -415.116383) (xy 337.127326 -415.157575) (xy 337.156791 -415.203427) (xy 337.179431 -415.253005)
			(xy 337.194786 -415.3053) (xy 337.202542 -415.359249) (xy 337.202542 -415.413748) (xy 338.640198 -415.413748)
			(xy 338.640198 -415.359252) (xy 338.647953 -415.30531) (xy 338.663306 -415.253021) (xy 338.685943 -415.203448)
			(xy 338.715405 -415.157602) (xy 338.751091 -415.116415) (xy 338.792275 -415.080725) (xy 338.838118 -415.05126)
			(xy 338.887689 -415.028618) (xy 338.939977 -415.013261) (xy 338.993918 -415.005501) (xy 339.021166 -415.005012)
			(xy 339.884766 -415.005012) (xy 339.912022 -415.005433) (xy 339.965979 -415.013186) (xy 340.018284 -415.02854)
			(xy 340.067871 -415.051182) (xy 340.113731 -415.08065) (xy 340.15493 -415.116346) (xy 340.190629 -415.157542)
			(xy 340.220102 -415.203399) (xy 340.242748 -415.252984) (xy 340.258107 -415.305287) (xy 340.265865 -415.359244)
			(xy 340.265865 -415.413752) (xy 341.703375 -415.413752) (xy 341.703375 -415.359248) (xy 341.711132 -415.3053)
			(xy 341.726488 -415.253004) (xy 341.749129 -415.203426) (xy 341.778596 -415.157575) (xy 341.814289 -415.116384)
			(xy 341.85548 -415.080693) (xy 341.901331 -415.051226) (xy 341.95091 -415.028585) (xy 342.003206 -415.013231)
			(xy 342.057154 -415.005475) (xy 342.084406 -415.005012) (xy 342.948006 -415.005012) (xy 342.975258 -415.005458)
			(xy 343.029208 -415.013216) (xy 343.081505 -415.028572) (xy 343.131084 -415.051215) (xy 343.176936 -415.080683)
			(xy 343.218128 -415.116376) (xy 343.253821 -415.157569) (xy 343.283288 -415.203421) (xy 343.30593 -415.253001)
			(xy 343.321285 -415.305298) (xy 343.329042 -415.359248) (xy 343.329042 -415.413752) (xy 343.329042 -415.413754)
			(xy 344.766575 -415.413754) (xy 344.766575 -415.359246) (xy 344.774333 -415.305294) (xy 344.789691 -415.252996)
			(xy 344.812335 -415.203415) (xy 344.841806 -415.157562) (xy 344.877503 -415.11637) (xy 344.918699 -415.080679)
			(xy 344.964555 -415.051213) (xy 345.014139 -415.028575) (xy 345.066439 -415.013223) (xy 345.120392 -415.005472)
			(xy 345.147646 -415.005012) (xy 346.011246 -415.005012) (xy 346.038497 -415.005461) (xy 346.092442 -415.013223)
			(xy 346.144734 -415.028583) (xy 346.194308 -415.051228) (xy 346.240155 -415.080697) (xy 346.281342 -415.116391)
			(xy 346.31703 -415.157582) (xy 346.346494 -415.203432) (xy 346.369133 -415.253009) (xy 346.384487 -415.305303)
			(xy 346.392242 -415.359249) (xy 346.392242 -415.413749) (xy 347.829898 -415.413749) (xy 347.829898 -415.359251)
			(xy 347.837654 -415.305307) (xy 347.853008 -415.253016) (xy 347.875646 -415.203443) (xy 347.90511 -415.157596)
			(xy 347.940798 -415.116408) (xy 347.981984 -415.080718) (xy 348.02783 -415.051253) (xy 348.077403 -415.028612)
			(xy 348.129694 -415.013257) (xy 348.183637 -415.005499) (xy 348.210886 -415.005012) (xy 349.074486 -415.005012)
			(xy 349.101741 -415.005434) (xy 349.155696 -415.01319) (xy 349.207999 -415.028545) (xy 349.257583 -415.051188)
			(xy 349.303441 -415.080657) (xy 349.344637 -415.116353) (xy 349.380334 -415.157548) (xy 349.409805 -415.203405)
			(xy 349.43245 -415.252988) (xy 349.447807 -415.30529) (xy 349.455565 -415.359245) (xy 349.455565 -415.413753)
			(xy 350.893075 -415.413753) (xy 350.893075 -415.359247) (xy 350.900833 -415.305297) (xy 350.916189 -415.253)
			(xy 350.938832 -415.203421) (xy 350.968301 -415.157569) (xy 351.003996 -415.116377) (xy 351.045189 -415.080686)
			(xy 351.091043 -415.05122) (xy 351.140624 -415.02858) (xy 351.192922 -415.013227) (xy 351.246873 -415.005474)
			(xy 351.274126 -415.005012) (xy 352.137726 -415.005012) (xy 352.164977 -415.00546) (xy 352.218925 -415.01322)
			(xy 352.27122 -415.028578) (xy 352.320796 -415.051222) (xy 352.366646 -415.08069) (xy 352.407835 -415.116383)
			(xy 352.443526 -415.157575) (xy 352.472991 -415.203427) (xy 352.495631 -415.253005) (xy 352.510986 -415.3053)
			(xy 352.518742 -415.359249) (xy 352.518742 -415.413751) (xy 352.518742 -415.413752) (xy 372.044675 -415.413752)
			(xy 372.044675 -415.359248) (xy 372.052432 -415.305298) (xy 372.067789 -415.253001) (xy 372.090432 -415.203422)
			(xy 372.1199 -415.15757) (xy 372.155594 -415.116379) (xy 372.196788 -415.080687) (xy 372.242641 -415.051221)
			(xy 372.292221 -415.028581) (xy 372.344519 -415.013228) (xy 372.39847 -415.005474) (xy 372.425722 -415.005012)
			(xy 373.289322 -415.005012) (xy 373.316574 -415.005459) (xy 373.370522 -415.013219) (xy 373.422817 -415.028577)
			(xy 373.472394 -415.05122) (xy 373.518244 -415.080689) (xy 373.559434 -415.116382) (xy 373.595125 -415.157574)
			(xy 373.62459 -415.203426) (xy 373.647231 -415.253004) (xy 373.662586 -415.3053) (xy 373.670342 -415.359248)
			(xy 373.670342 -415.413748) (xy 375.107998 -415.413748) (xy 375.107998 -415.359252) (xy 375.115753 -415.30531)
			(xy 375.131106 -415.253022) (xy 375.153743 -415.203449) (xy 375.183204 -415.157603) (xy 375.218889 -415.116416)
			(xy 375.260073 -415.080727) (xy 375.305916 -415.051261) (xy 375.355486 -415.028619) (xy 375.407773 -415.013261)
			(xy 375.461714 -415.005501) (xy 375.488962 -415.005012) (xy 376.352562 -415.005012) (xy 376.379818 -415.005432)
			(xy 376.433776 -415.013185) (xy 376.486081 -415.028539) (xy 376.535669 -415.05118) (xy 376.581529 -415.080649)
			(xy 376.622729 -415.116345) (xy 376.658428 -415.15754) (xy 376.687901 -415.203398) (xy 376.710548 -415.252983)
			(xy 376.725907 -415.305287) (xy 376.733665 -415.359244) (xy 376.733665 -415.413752) (xy 378.171175 -415.413752)
			(xy 378.171175 -415.359248) (xy 378.178932 -415.3053) (xy 378.194287 -415.253005) (xy 378.216929 -415.203427)
			(xy 378.246395 -415.157576) (xy 378.282087 -415.116386) (xy 378.323278 -415.080694) (xy 378.369129 -415.051228)
			(xy 378.418707 -415.028587) (xy 378.471002 -415.013231) (xy 378.52495 -415.005475) (xy 378.552202 -415.005012)
			(xy 379.415802 -415.005012) (xy 379.443055 -415.005458) (xy 379.497005 -415.013215) (xy 379.549302 -415.028571)
			(xy 379.598882 -415.051214) (xy 379.644734 -415.080682) (xy 379.685926 -415.116375) (xy 379.72162 -415.157567)
			(xy 379.751087 -415.20342) (xy 379.773729 -415.253) (xy 379.789085 -415.305297) (xy 379.796842 -415.359247)
			(xy 379.796842 -415.413753) (xy 381.234375 -415.413753) (xy 381.234375 -415.359247) (xy 381.242133 -415.305295)
			(xy 381.25749 -415.252996) (xy 381.280135 -415.203416) (xy 381.309605 -415.157563) (xy 381.345301 -415.116372)
			(xy 381.386497 -415.08068) (xy 381.432353 -415.051215) (xy 381.481936 -415.028576) (xy 381.534236 -415.013224)
			(xy 381.588189 -415.005472) (xy 381.615442 -415.005012) (xy 382.479042 -415.005012) (xy 382.506293 -415.005461)
			(xy 382.560239 -415.013222) (xy 382.612531 -415.028582) (xy 382.662106 -415.051227) (xy 382.707953 -415.080696)
			(xy 382.749141 -415.116389) (xy 382.784829 -415.15758) (xy 382.814293 -415.203431) (xy 382.836933 -415.253008)
			(xy 382.852286 -415.305302) (xy 382.860042 -415.359249) (xy 382.860042 -415.413749) (xy 384.297698 -415.413749)
			(xy 384.297698 -415.359251) (xy 384.305454 -415.305308) (xy 384.320807 -415.253017) (xy 384.343446 -415.203444)
			(xy 384.372909 -415.157597) (xy 384.408597 -415.116409) (xy 384.449782 -415.08072) (xy 384.495628 -415.051254)
			(xy 384.5452 -415.028613) (xy 384.59749 -415.013258) (xy 384.651433 -415.005499) (xy 384.678682 -415.005012)
			(xy 385.542282 -415.005012) (xy 385.569537 -415.005434) (xy 385.623493 -415.013189) (xy 385.675796 -415.028544)
			(xy 385.725381 -415.051187) (xy 385.771239 -415.080656) (xy 385.812436 -415.116352) (xy 385.848133 -415.157547)
			(xy 385.877604 -415.203403) (xy 385.900249 -415.252987) (xy 385.915607 -415.305289) (xy 385.923365 -415.359245)
			(xy 385.923365 -415.413752) (xy 387.360875 -415.413752) (xy 387.360875 -415.359248) (xy 387.368632 -415.305298)
			(xy 387.383989 -415.253001) (xy 387.406632 -415.203422) (xy 387.4361 -415.15757) (xy 387.471794 -415.116379)
			(xy 387.512988 -415.080687) (xy 387.558841 -415.051221) (xy 387.608421 -415.028581) (xy 387.660719 -415.013228)
			(xy 387.71467 -415.005474) (xy 387.741922 -415.005012) (xy 388.605522 -415.005012) (xy 388.632774 -415.005459)
			(xy 388.686722 -415.013219) (xy 388.739017 -415.028577) (xy 388.788594 -415.05122) (xy 388.834444 -415.080689)
			(xy 388.875634 -415.116382) (xy 388.911325 -415.157574) (xy 388.94079 -415.203426) (xy 388.963431 -415.253004)
			(xy 388.978786 -415.3053) (xy 388.986542 -415.359248) (xy 388.986542 -415.413748) (xy 390.424198 -415.413748)
			(xy 390.424198 -415.359252) (xy 390.431953 -415.30531) (xy 390.447306 -415.253022) (xy 390.469943 -415.203449)
			(xy 390.499404 -415.157603) (xy 390.535089 -415.116416) (xy 390.576273 -415.080727) (xy 390.622116 -415.051261)
			(xy 390.671686 -415.028619) (xy 390.723973 -415.013261) (xy 390.777914 -415.005501) (xy 390.805162 -415.005012)
			(xy 391.668762 -415.005012) (xy 391.696018 -415.005432) (xy 391.749976 -415.013185) (xy 391.802281 -415.028539)
			(xy 391.851869 -415.05118) (xy 391.897729 -415.080649) (xy 391.938929 -415.116345) (xy 391.974628 -415.15754)
			(xy 392.004101 -415.203398) (xy 392.026748 -415.252983) (xy 392.042107 -415.305287) (xy 392.049865 -415.359244)
			(xy 392.049865 -415.413752) (xy 393.487375 -415.413752) (xy 393.487375 -415.359248) (xy 393.495132 -415.3053)
			(xy 393.510487 -415.253005) (xy 393.533129 -415.203427) (xy 393.562595 -415.157576) (xy 393.598287 -415.116386)
			(xy 393.639478 -415.080694) (xy 393.685329 -415.051228) (xy 393.734907 -415.028587) (xy 393.787202 -415.013231)
			(xy 393.84115 -415.005475) (xy 393.868402 -415.005012) (xy 394.732002 -415.005012) (xy 394.759255 -415.005458)
			(xy 394.813205 -415.013215) (xy 394.865502 -415.028571) (xy 394.915082 -415.051214) (xy 394.960934 -415.080682)
			(xy 395.002126 -415.116375) (xy 395.03782 -415.157567) (xy 395.067287 -415.20342) (xy 395.089929 -415.253)
			(xy 395.105285 -415.305297) (xy 395.113042 -415.359247) (xy 395.113042 -415.413753) (xy 396.550575 -415.413753)
			(xy 396.550575 -415.359247) (xy 396.558333 -415.305295) (xy 396.57369 -415.252996) (xy 396.596335 -415.203416)
			(xy 396.625805 -415.157563) (xy 396.661501 -415.116372) (xy 396.702697 -415.08068) (xy 396.748553 -415.051215)
			(xy 396.798136 -415.028576) (xy 396.850436 -415.013224) (xy 396.904389 -415.005472) (xy 396.931642 -415.005012)
			(xy 397.795242 -415.005012) (xy 397.822493 -415.005461) (xy 397.876439 -415.013222) (xy 397.928731 -415.028582)
			(xy 397.978306 -415.051227) (xy 398.024153 -415.080696) (xy 398.065341 -415.116389) (xy 398.101029 -415.15758)
			(xy 398.130493 -415.203431) (xy 398.153133 -415.253008) (xy 398.168486 -415.305302) (xy 398.176242 -415.359249)
			(xy 398.176242 -415.413749) (xy 399.613898 -415.413749) (xy 399.613898 -415.359251) (xy 399.621654 -415.305308)
			(xy 399.637007 -415.253017) (xy 399.659646 -415.203444) (xy 399.689109 -415.157597) (xy 399.724797 -415.116409)
			(xy 399.765982 -415.08072) (xy 399.811828 -415.051254) (xy 399.8614 -415.028613) (xy 399.91369 -415.013258)
			(xy 399.967633 -415.005499) (xy 399.994882 -415.005012) (xy 400.858482 -415.005012) (xy 400.885737 -415.005434)
			(xy 400.939693 -415.013189) (xy 400.991996 -415.028544) (xy 401.041581 -415.051187) (xy 401.087439 -415.080656)
			(xy 401.128636 -415.116352) (xy 401.164333 -415.157547) (xy 401.193804 -415.203403) (xy 401.216449 -415.252987)
			(xy 401.231807 -415.305289) (xy 401.239565 -415.359245) (xy 401.239565 -415.413752) (xy 402.677075 -415.413752)
			(xy 402.677075 -415.359248) (xy 402.684832 -415.305298) (xy 402.700189 -415.253001) (xy 402.722832 -415.203422)
			(xy 402.7523 -415.15757) (xy 402.787994 -415.116379) (xy 402.829188 -415.080687) (xy 402.875041 -415.051221)
			(xy 402.924621 -415.028581) (xy 402.976919 -415.013228) (xy 403.03087 -415.005474) (xy 403.058122 -415.005012)
			(xy 403.921722 -415.005012) (xy 403.948974 -415.005459) (xy 404.002922 -415.013219) (xy 404.055217 -415.028577)
			(xy 404.104794 -415.05122) (xy 404.150644 -415.080689) (xy 404.191834 -415.116382) (xy 404.227525 -415.157574)
			(xy 404.25699 -415.203426) (xy 404.279631 -415.253004) (xy 404.294986 -415.3053) (xy 404.302742 -415.359248)
			(xy 404.302742 -415.413748) (xy 405.740398 -415.413748) (xy 405.740398 -415.359252) (xy 405.748153 -415.30531)
			(xy 405.763506 -415.253022) (xy 405.786143 -415.203449) (xy 405.815604 -415.157603) (xy 405.851289 -415.116416)
			(xy 405.892473 -415.080727) (xy 405.938316 -415.051261) (xy 405.987886 -415.028619) (xy 406.040173 -415.013261)
			(xy 406.094114 -415.005501) (xy 406.121362 -415.005012) (xy 406.984962 -415.005012) (xy 407.012218 -415.005432)
			(xy 407.066176 -415.013185) (xy 407.118481 -415.028539) (xy 407.168069 -415.05118) (xy 407.213929 -415.080649)
			(xy 407.255129 -415.116345) (xy 407.290828 -415.15754) (xy 407.320301 -415.203398) (xy 407.342948 -415.252983)
			(xy 407.358307 -415.305287) (xy 407.366065 -415.359244) (xy 407.366065 -415.413752) (xy 408.803575 -415.413752)
			(xy 408.803575 -415.359248) (xy 408.811332 -415.3053) (xy 408.826687 -415.253005) (xy 408.849329 -415.203427)
			(xy 408.878795 -415.157576) (xy 408.914487 -415.116386) (xy 408.955678 -415.080694) (xy 409.001529 -415.051228)
			(xy 409.051107 -415.028587) (xy 409.103402 -415.013231) (xy 409.15735 -415.005475) (xy 409.184602 -415.005012)
			(xy 410.048202 -415.005012) (xy 410.075455 -415.005458) (xy 410.129405 -415.013215) (xy 410.181702 -415.028571)
			(xy 410.231282 -415.051214) (xy 410.277134 -415.080682) (xy 410.318326 -415.116375) (xy 410.35402 -415.157567)
			(xy 410.383487 -415.20342) (xy 410.406129 -415.253) (xy 410.421485 -415.305297) (xy 410.429242 -415.359247)
			(xy 410.429242 -415.413753) (xy 411.866775 -415.413753) (xy 411.866775 -415.359247) (xy 411.874533 -415.305295)
			(xy 411.88989 -415.252996) (xy 411.912535 -415.203416) (xy 411.942005 -415.157563) (xy 411.977701 -415.116372)
			(xy 412.018897 -415.08068) (xy 412.064753 -415.051215) (xy 412.114336 -415.028576) (xy 412.166636 -415.013224)
			(xy 412.220589 -415.005472) (xy 412.247842 -415.005012) (xy 413.111442 -415.005012) (xy 413.138693 -415.005461)
			(xy 413.192639 -415.013222) (xy 413.244931 -415.028582) (xy 413.294506 -415.051227) (xy 413.340353 -415.080696)
			(xy 413.381541 -415.116389) (xy 413.417229 -415.15758) (xy 413.446693 -415.203431) (xy 413.469333 -415.253008)
			(xy 413.484686 -415.305302) (xy 413.492442 -415.359249) (xy 413.492442 -415.413749) (xy 414.930098 -415.413749)
			(xy 414.930098 -415.359251) (xy 414.937854 -415.305308) (xy 414.953207 -415.253017) (xy 414.975846 -415.203444)
			(xy 415.005309 -415.157597) (xy 415.040997 -415.116409) (xy 415.082182 -415.08072) (xy 415.128028 -415.051254)
			(xy 415.1776 -415.028613) (xy 415.22989 -415.013258) (xy 415.283833 -415.005499) (xy 415.311082 -415.005012)
			(xy 416.174682 -415.005012) (xy 416.201937 -415.005434) (xy 416.255893 -415.013189) (xy 416.308196 -415.028544)
			(xy 416.357781 -415.051187) (xy 416.403639 -415.080656) (xy 416.444836 -415.116352) (xy 416.480533 -415.157547)
			(xy 416.510004 -415.203403) (xy 416.532649 -415.252987) (xy 416.548007 -415.305289) (xy 416.555765 -415.359245)
			(xy 416.555765 -415.413752) (xy 417.993275 -415.413752) (xy 417.993275 -415.359248) (xy 418.001032 -415.305298)
			(xy 418.016389 -415.253001) (xy 418.039032 -415.203422) (xy 418.0685 -415.15757) (xy 418.104194 -415.116379)
			(xy 418.145388 -415.080687) (xy 418.191241 -415.051221) (xy 418.240821 -415.028581) (xy 418.293119 -415.013228)
			(xy 418.34707 -415.005474) (xy 418.374322 -415.005012) (xy 419.237922 -415.005012) (xy 419.265174 -415.005459)
			(xy 419.319122 -415.013219) (xy 419.371417 -415.028577) (xy 419.420994 -415.05122) (xy 419.466844 -415.080689)
			(xy 419.508034 -415.116382) (xy 419.543725 -415.157574) (xy 419.57319 -415.203426) (xy 419.595831 -415.253004)
			(xy 419.611186 -415.3053) (xy 419.618942 -415.359248) (xy 419.618942 -415.413752) (xy 419.611186 -415.4677)
			(xy 419.595831 -415.519996) (xy 419.57319 -415.569574) (xy 419.543725 -415.615426) (xy 419.508034 -415.656618)
			(xy 419.466844 -415.692311) (xy 419.420994 -415.72178) (xy 419.371417 -415.744423) (xy 419.319122 -415.759781)
			(xy 419.265174 -415.767541) (xy 419.237922 -415.768028) (xy 418.374322 -415.768028) (xy 418.34707 -415.767526)
			(xy 418.293119 -415.759772) (xy 418.240821 -415.744419) (xy 418.191241 -415.721779) (xy 418.145388 -415.692313)
			(xy 418.104194 -415.656621) (xy 418.0685 -415.61543) (xy 418.039032 -415.569578) (xy 418.016389 -415.519999)
			(xy 418.001032 -415.467702) (xy 417.993275 -415.413752) (xy 416.555765 -415.413752) (xy 416.555765 -415.413755)
			(xy 416.548007 -415.467711) (xy 416.532649 -415.520013) (xy 416.510004 -415.569597) (xy 416.480533 -415.615453)
			(xy 416.444836 -415.656648) (xy 416.403639 -415.692344) (xy 416.357781 -415.721813) (xy 416.308196 -415.744456)
			(xy 416.255893 -415.759811) (xy 416.201937 -415.767566) (xy 416.174682 -415.768028) (xy 415.311082 -415.768028)
			(xy 415.283833 -415.767501) (xy 415.22989 -415.759742) (xy 415.1776 -415.744387) (xy 415.128028 -415.721746)
			(xy 415.082182 -415.69228) (xy 415.040997 -415.656591) (xy 415.005309 -415.615403) (xy 414.975846 -415.569556)
			(xy 414.953207 -415.519983) (xy 414.937854 -415.467692) (xy 414.930098 -415.413749) (xy 413.492442 -415.413749)
			(xy 413.492442 -415.413751) (xy 413.484686 -415.467698) (xy 413.469333 -415.519992) (xy 413.446693 -415.569569)
			(xy 413.417229 -415.61542) (xy 413.381541 -415.656611) (xy 413.340353 -415.692304) (xy 413.294506 -415.721773)
			(xy 413.244931 -415.744418) (xy 413.192639 -415.759778) (xy 413.138693 -415.767539) (xy 413.111442 -415.768028)
			(xy 412.247842 -415.768028) (xy 412.220589 -415.767528) (xy 412.166636 -415.759776) (xy 412.114336 -415.744424)
			(xy 412.064753 -415.721785) (xy 412.018897 -415.69232) (xy 411.977701 -415.656628) (xy 411.942005 -415.615437)
			(xy 411.912535 -415.569584) (xy 411.88989 -415.520004) (xy 411.874533 -415.467705) (xy 411.866775 -415.413753)
			(xy 410.429242 -415.413753) (xy 410.421485 -415.467703) (xy 410.406129 -415.52) (xy 410.383487 -415.56958)
			(xy 410.35402 -415.615433) (xy 410.318326 -415.656625) (xy 410.277134 -415.692318) (xy 410.231282 -415.721786)
			(xy 410.181702 -415.744429) (xy 410.129405 -415.759785) (xy 410.075455 -415.767542) (xy 410.048202 -415.768028)
			(xy 409.184602 -415.768028) (xy 409.15735 -415.767525) (xy 409.103402 -415.759769) (xy 409.051107 -415.744413)
			(xy 409.001529 -415.721772) (xy 408.955678 -415.692306) (xy 408.914487 -415.656614) (xy 408.878795 -415.615424)
			(xy 408.849329 -415.569573) (xy 408.826687 -415.519995) (xy 408.811332 -415.4677) (xy 408.803575 -415.413752)
			(xy 407.366065 -415.413752) (xy 407.366065 -415.413756) (xy 407.358307 -415.467713) (xy 407.342948 -415.520017)
			(xy 407.320301 -415.569602) (xy 407.290828 -415.61546) (xy 407.255129 -415.656655) (xy 407.213929 -415.692351)
			(xy 407.168069 -415.72182) (xy 407.118481 -415.744461) (xy 407.066176 -415.759815) (xy 407.012218 -415.767568)
			(xy 406.984962 -415.768028) (xy 406.121362 -415.768028) (xy 406.094114 -415.767499) (xy 406.040173 -415.759739)
			(xy 405.987886 -415.744381) (xy 405.938316 -415.721739) (xy 405.892473 -415.692273) (xy 405.851289 -415.656584)
			(xy 405.815604 -415.615397) (xy 405.786143 -415.569551) (xy 405.763506 -415.519978) (xy 405.748153 -415.46769)
			(xy 405.740398 -415.413748) (xy 404.302742 -415.413748) (xy 404.302742 -415.413752) (xy 404.294986 -415.4677)
			(xy 404.279631 -415.519996) (xy 404.25699 -415.569574) (xy 404.227525 -415.615426) (xy 404.191834 -415.656618)
			(xy 404.150644 -415.692311) (xy 404.104794 -415.72178) (xy 404.055217 -415.744423) (xy 404.002922 -415.759781)
			(xy 403.948974 -415.767541) (xy 403.921722 -415.768028) (xy 403.058122 -415.768028) (xy 403.03087 -415.767526)
			(xy 402.976919 -415.759772) (xy 402.924621 -415.744419) (xy 402.875041 -415.721779) (xy 402.829188 -415.692313)
			(xy 402.787994 -415.656621) (xy 402.7523 -415.61543) (xy 402.722832 -415.569578) (xy 402.700189 -415.519999)
			(xy 402.684832 -415.467702) (xy 402.677075 -415.413752) (xy 401.239565 -415.413752) (xy 401.239565 -415.413755)
			(xy 401.231807 -415.467711) (xy 401.216449 -415.520013) (xy 401.193804 -415.569597) (xy 401.164333 -415.615453)
			(xy 401.128636 -415.656648) (xy 401.087439 -415.692344) (xy 401.041581 -415.721813) (xy 400.991996 -415.744456)
			(xy 400.939693 -415.759811) (xy 400.885737 -415.767566) (xy 400.858482 -415.768028) (xy 399.994882 -415.768028)
			(xy 399.967633 -415.767501) (xy 399.91369 -415.759742) (xy 399.8614 -415.744387) (xy 399.811828 -415.721746)
			(xy 399.765982 -415.69228) (xy 399.724797 -415.656591) (xy 399.689109 -415.615403) (xy 399.659646 -415.569556)
			(xy 399.637007 -415.519983) (xy 399.621654 -415.467692) (xy 399.613898 -415.413749) (xy 398.176242 -415.413749)
			(xy 398.176242 -415.413751) (xy 398.168486 -415.467698) (xy 398.153133 -415.519992) (xy 398.130493 -415.569569)
			(xy 398.101029 -415.61542) (xy 398.065341 -415.656611) (xy 398.024153 -415.692304) (xy 397.978306 -415.721773)
			(xy 397.928731 -415.744418) (xy 397.876439 -415.759778) (xy 397.822493 -415.767539) (xy 397.795242 -415.768028)
			(xy 396.931642 -415.768028) (xy 396.904389 -415.767528) (xy 396.850436 -415.759776) (xy 396.798136 -415.744424)
			(xy 396.748553 -415.721785) (xy 396.702697 -415.69232) (xy 396.661501 -415.656628) (xy 396.625805 -415.615437)
			(xy 396.596335 -415.569584) (xy 396.57369 -415.520004) (xy 396.558333 -415.467705) (xy 396.550575 -415.413753)
			(xy 395.113042 -415.413753) (xy 395.105285 -415.467703) (xy 395.089929 -415.52) (xy 395.067287 -415.56958)
			(xy 395.03782 -415.615433) (xy 395.002126 -415.656625) (xy 394.960934 -415.692318) (xy 394.915082 -415.721786)
			(xy 394.865502 -415.744429) (xy 394.813205 -415.759785) (xy 394.759255 -415.767542) (xy 394.732002 -415.768028)
			(xy 393.868402 -415.768028) (xy 393.84115 -415.767525) (xy 393.787202 -415.759769) (xy 393.734907 -415.744413)
			(xy 393.685329 -415.721772) (xy 393.639478 -415.692306) (xy 393.598287 -415.656614) (xy 393.562595 -415.615424)
			(xy 393.533129 -415.569573) (xy 393.510487 -415.519995) (xy 393.495132 -415.4677) (xy 393.487375 -415.413752)
			(xy 392.049865 -415.413752) (xy 392.049865 -415.413756) (xy 392.042107 -415.467713) (xy 392.026748 -415.520017)
			(xy 392.004101 -415.569602) (xy 391.974628 -415.61546) (xy 391.938929 -415.656655) (xy 391.897729 -415.692351)
			(xy 391.851869 -415.72182) (xy 391.802281 -415.744461) (xy 391.749976 -415.759815) (xy 391.696018 -415.767568)
			(xy 391.668762 -415.768028) (xy 390.805162 -415.768028) (xy 390.777914 -415.767499) (xy 390.723973 -415.759739)
			(xy 390.671686 -415.744381) (xy 390.622116 -415.721739) (xy 390.576273 -415.692273) (xy 390.535089 -415.656584)
			(xy 390.499404 -415.615397) (xy 390.469943 -415.569551) (xy 390.447306 -415.519978) (xy 390.431953 -415.46769)
			(xy 390.424198 -415.413748) (xy 388.986542 -415.413748) (xy 388.986542 -415.413752) (xy 388.978786 -415.4677)
			(xy 388.963431 -415.519996) (xy 388.94079 -415.569574) (xy 388.911325 -415.615426) (xy 388.875634 -415.656618)
			(xy 388.834444 -415.692311) (xy 388.788594 -415.72178) (xy 388.739017 -415.744423) (xy 388.686722 -415.759781)
			(xy 388.632774 -415.767541) (xy 388.605522 -415.768028) (xy 387.741922 -415.768028) (xy 387.71467 -415.767526)
			(xy 387.660719 -415.759772) (xy 387.608421 -415.744419) (xy 387.558841 -415.721779) (xy 387.512988 -415.692313)
			(xy 387.471794 -415.656621) (xy 387.4361 -415.61543) (xy 387.406632 -415.569578) (xy 387.383989 -415.519999)
			(xy 387.368632 -415.467702) (xy 387.360875 -415.413752) (xy 385.923365 -415.413752) (xy 385.923365 -415.413755)
			(xy 385.915607 -415.467711) (xy 385.900249 -415.520013) (xy 385.877604 -415.569597) (xy 385.848133 -415.615453)
			(xy 385.812436 -415.656648) (xy 385.771239 -415.692344) (xy 385.725381 -415.721813) (xy 385.675796 -415.744456)
			(xy 385.623493 -415.759811) (xy 385.569537 -415.767566) (xy 385.542282 -415.768028) (xy 384.678682 -415.768028)
			(xy 384.651433 -415.767501) (xy 384.59749 -415.759742) (xy 384.5452 -415.744387) (xy 384.495628 -415.721746)
			(xy 384.449782 -415.69228) (xy 384.408597 -415.656591) (xy 384.372909 -415.615403) (xy 384.343446 -415.569556)
			(xy 384.320807 -415.519983) (xy 384.305454 -415.467692) (xy 384.297698 -415.413749) (xy 382.860042 -415.413749)
			(xy 382.860042 -415.413751) (xy 382.852286 -415.467698) (xy 382.836933 -415.519992) (xy 382.814293 -415.569569)
			(xy 382.784829 -415.61542) (xy 382.749141 -415.656611) (xy 382.707953 -415.692304) (xy 382.662106 -415.721773)
			(xy 382.612531 -415.744418) (xy 382.560239 -415.759778) (xy 382.506293 -415.767539) (xy 382.479042 -415.768028)
			(xy 381.615442 -415.768028) (xy 381.588189 -415.767528) (xy 381.534236 -415.759776) (xy 381.481936 -415.744424)
			(xy 381.432353 -415.721785) (xy 381.386497 -415.69232) (xy 381.345301 -415.656628) (xy 381.309605 -415.615437)
			(xy 381.280135 -415.569584) (xy 381.25749 -415.520004) (xy 381.242133 -415.467705) (xy 381.234375 -415.413753)
			(xy 379.796842 -415.413753) (xy 379.789085 -415.467703) (xy 379.773729 -415.52) (xy 379.751087 -415.56958)
			(xy 379.72162 -415.615433) (xy 379.685926 -415.656625) (xy 379.644734 -415.692318) (xy 379.598882 -415.721786)
			(xy 379.549302 -415.744429) (xy 379.497005 -415.759785) (xy 379.443055 -415.767542) (xy 379.415802 -415.768028)
			(xy 378.552202 -415.768028) (xy 378.52495 -415.767525) (xy 378.471002 -415.759769) (xy 378.418707 -415.744413)
			(xy 378.369129 -415.721772) (xy 378.323278 -415.692306) (xy 378.282087 -415.656614) (xy 378.246395 -415.615424)
			(xy 378.216929 -415.569573) (xy 378.194287 -415.519995) (xy 378.178932 -415.4677) (xy 378.171175 -415.413752)
			(xy 376.733665 -415.413752) (xy 376.733665 -415.413756) (xy 376.725907 -415.467713) (xy 376.710548 -415.520017)
			(xy 376.687901 -415.569602) (xy 376.658428 -415.61546) (xy 376.622729 -415.656655) (xy 376.581529 -415.692351)
			(xy 376.535669 -415.72182) (xy 376.486081 -415.744461) (xy 376.433776 -415.759815) (xy 376.379818 -415.767568)
			(xy 376.352562 -415.768028) (xy 375.488962 -415.768028) (xy 375.461714 -415.767499) (xy 375.407773 -415.759739)
			(xy 375.355486 -415.744381) (xy 375.305916 -415.721739) (xy 375.260073 -415.692273) (xy 375.218889 -415.656584)
			(xy 375.183204 -415.615397) (xy 375.153743 -415.569551) (xy 375.131106 -415.519978) (xy 375.115753 -415.46769)
			(xy 375.107998 -415.413748) (xy 373.670342 -415.413748) (xy 373.670342 -415.413752) (xy 373.662586 -415.4677)
			(xy 373.647231 -415.519996) (xy 373.62459 -415.569574) (xy 373.595125 -415.615426) (xy 373.559434 -415.656618)
			(xy 373.518244 -415.692311) (xy 373.472394 -415.72178) (xy 373.422817 -415.744423) (xy 373.370522 -415.759781)
			(xy 373.316574 -415.767541) (xy 373.289322 -415.768028) (xy 372.425722 -415.768028) (xy 372.39847 -415.767526)
			(xy 372.344519 -415.759772) (xy 372.292221 -415.744419) (xy 372.242641 -415.721779) (xy 372.196788 -415.692313)
			(xy 372.155594 -415.656621) (xy 372.1199 -415.61543) (xy 372.090432 -415.569578) (xy 372.067789 -415.519999)
			(xy 372.052432 -415.467702) (xy 372.044675 -415.413752) (xy 352.518742 -415.413752) (xy 352.510986 -415.4677)
			(xy 352.495631 -415.519995) (xy 352.472991 -415.569573) (xy 352.443526 -415.615425) (xy 352.407835 -415.656617)
			(xy 352.366646 -415.69231) (xy 352.320796 -415.721778) (xy 352.27122 -415.744422) (xy 352.218925 -415.75978)
			(xy 352.164977 -415.76754) (xy 352.137726 -415.768028) (xy 351.274126 -415.768028) (xy 351.246873 -415.767526)
			(xy 351.192922 -415.759773) (xy 351.140624 -415.74442) (xy 351.091043 -415.72178) (xy 351.045189 -415.692314)
			(xy 351.003996 -415.656623) (xy 350.968301 -415.615431) (xy 350.938832 -415.569579) (xy 350.916189 -415.52)
			(xy 350.900833 -415.467703) (xy 350.893075 -415.413753) (xy 349.455565 -415.413753) (xy 349.455565 -415.413755)
			(xy 349.447807 -415.46771) (xy 349.43245 -415.520012) (xy 349.409805 -415.569595) (xy 349.380334 -415.615452)
			(xy 349.344637 -415.656647) (xy 349.303441 -415.692343) (xy 349.257583 -415.721812) (xy 349.207999 -415.744455)
			(xy 349.155696 -415.75981) (xy 349.101741 -415.767566) (xy 349.074486 -415.768028) (xy 348.210886 -415.768028)
			(xy 348.183637 -415.767501) (xy 348.129694 -415.759743) (xy 348.077403 -415.744388) (xy 348.02783 -415.721747)
			(xy 347.981984 -415.692282) (xy 347.940798 -415.656592) (xy 347.90511 -415.615404) (xy 347.875646 -415.569557)
			(xy 347.853008 -415.519984) (xy 347.837654 -415.467693) (xy 347.829898 -415.413749) (xy 346.392242 -415.413749)
			(xy 346.392242 -415.413751) (xy 346.384487 -415.467697) (xy 346.369133 -415.519991) (xy 346.346494 -415.569568)
			(xy 346.31703 -415.615418) (xy 346.281342 -415.656609) (xy 346.240155 -415.692303) (xy 346.194308 -415.721772)
			(xy 346.144734 -415.744417) (xy 346.092442 -415.759777) (xy 346.038497 -415.767539) (xy 346.011246 -415.768028)
			(xy 345.147646 -415.768028) (xy 345.120392 -415.767528) (xy 345.066439 -415.759777) (xy 345.014139 -415.744425)
			(xy 344.964555 -415.721787) (xy 344.918699 -415.692321) (xy 344.877503 -415.65663) (xy 344.841806 -415.615438)
			(xy 344.812335 -415.569585) (xy 344.789691 -415.520004) (xy 344.774333 -415.467706) (xy 344.766575 -415.413754)
			(xy 343.329042 -415.413754) (xy 343.321285 -415.467702) (xy 343.30593 -415.519999) (xy 343.283288 -415.569579)
			(xy 343.253821 -415.615431) (xy 343.218128 -415.656624) (xy 343.176936 -415.692317) (xy 343.131084 -415.721785)
			(xy 343.081505 -415.744428) (xy 343.029208 -415.759784) (xy 342.975258 -415.767542) (xy 342.948006 -415.768028)
			(xy 342.084406 -415.768028) (xy 342.057154 -415.767525) (xy 342.003206 -415.759769) (xy 341.95091 -415.744415)
			(xy 341.901331 -415.721774) (xy 341.85548 -415.692307) (xy 341.814289 -415.656616) (xy 341.778596 -415.615425)
			(xy 341.749129 -415.569574) (xy 341.726488 -415.519996) (xy 341.711132 -415.4677) (xy 341.703375 -415.413752)
			(xy 340.265865 -415.413752) (xy 340.265865 -415.413756) (xy 340.258107 -415.467713) (xy 340.242748 -415.520016)
			(xy 340.220102 -415.569601) (xy 340.190629 -415.615458) (xy 340.15493 -415.656654) (xy 340.113731 -415.69235)
			(xy 340.067871 -415.721818) (xy 340.018284 -415.74446) (xy 339.965979 -415.759814) (xy 339.912022 -415.767567)
			(xy 339.884766 -415.768028) (xy 339.021166 -415.768028) (xy 338.993918 -415.767499) (xy 338.939977 -415.759739)
			(xy 338.887689 -415.744382) (xy 338.838118 -415.72174) (xy 338.792275 -415.692275) (xy 338.751091 -415.656585)
			(xy 338.715405 -415.615398) (xy 338.685943 -415.569552) (xy 338.663306 -415.519979) (xy 338.647953 -415.46769)
			(xy 338.640198 -415.413748) (xy 337.202542 -415.413748) (xy 337.202542 -415.413751) (xy 337.194786 -415.4677)
			(xy 337.179431 -415.519995) (xy 337.156791 -415.569573) (xy 337.127326 -415.615425) (xy 337.091635 -415.656617)
			(xy 337.050446 -415.69231) (xy 337.004596 -415.721778) (xy 336.95502 -415.744422) (xy 336.902725 -415.75978)
			(xy 336.848777 -415.76754) (xy 336.821526 -415.768028) (xy 335.957926 -415.768028) (xy 335.930673 -415.767526)
			(xy 335.876722 -415.759773) (xy 335.824424 -415.74442) (xy 335.774843 -415.72178) (xy 335.728989 -415.692314)
			(xy 335.687796 -415.656623) (xy 335.652101 -415.615431) (xy 335.622632 -415.569579) (xy 335.599989 -415.52)
			(xy 335.584633 -415.467703) (xy 335.576875 -415.413753) (xy 334.139365 -415.413753) (xy 334.139365 -415.413755)
			(xy 334.131607 -415.46771) (xy 334.11625 -415.520012) (xy 334.093605 -415.569595) (xy 334.064134 -415.615452)
			(xy 334.028437 -415.656647) (xy 333.987241 -415.692343) (xy 333.941383 -415.721812) (xy 333.891799 -415.744455)
			(xy 333.839496 -415.75981) (xy 333.785541 -415.767566) (xy 333.758286 -415.768028) (xy 332.894686 -415.768028)
			(xy 332.867437 -415.767501) (xy 332.813494 -415.759743) (xy 332.761203 -415.744388) (xy 332.71163 -415.721747)
			(xy 332.665784 -415.692282) (xy 332.624598 -415.656592) (xy 332.58891 -415.615404) (xy 332.559446 -415.569557)
			(xy 332.536808 -415.519984) (xy 332.521454 -415.467693) (xy 332.513698 -415.413749) (xy 331.076042 -415.413749)
			(xy 331.076042 -415.413751) (xy 331.068287 -415.467697) (xy 331.052933 -415.519991) (xy 331.030294 -415.569568)
			(xy 331.00083 -415.615418) (xy 330.965142 -415.656609) (xy 330.923955 -415.692303) (xy 330.878108 -415.721772)
			(xy 330.828534 -415.744417) (xy 330.776242 -415.759777) (xy 330.722297 -415.767539) (xy 330.695046 -415.768028)
			(xy 329.831446 -415.768028) (xy 329.804192 -415.767528) (xy 329.750239 -415.759777) (xy 329.697939 -415.744425)
			(xy 329.648355 -415.721787) (xy 329.602499 -415.692321) (xy 329.561303 -415.65663) (xy 329.525606 -415.615438)
			(xy 329.496135 -415.569585) (xy 329.473491 -415.520004) (xy 329.458133 -415.467706) (xy 329.450375 -415.413754)
			(xy 328.012842 -415.413754) (xy 328.005085 -415.467702) (xy 327.98973 -415.519999) (xy 327.967088 -415.569579)
			(xy 327.937621 -415.615431) (xy 327.901928 -415.656624) (xy 327.860736 -415.692317) (xy 327.814884 -415.721785)
			(xy 327.765305 -415.744428) (xy 327.713008 -415.759784) (xy 327.659058 -415.767542) (xy 327.631806 -415.768028)
			(xy 326.768206 -415.768028) (xy 326.740954 -415.767525) (xy 326.687006 -415.759769) (xy 326.63471 -415.744415)
			(xy 326.585131 -415.721774) (xy 326.53928 -415.692307) (xy 326.498089 -415.656616) (xy 326.462396 -415.615425)
			(xy 326.432929 -415.569574) (xy 326.410288 -415.519996) (xy 326.394932 -415.4677) (xy 326.387175 -415.413752)
			(xy 324.949665 -415.413752) (xy 324.949665 -415.413756) (xy 324.941907 -415.467713) (xy 324.926548 -415.520016)
			(xy 324.903902 -415.569601) (xy 324.874429 -415.615458) (xy 324.83873 -415.656654) (xy 324.797531 -415.69235)
			(xy 324.751671 -415.721818) (xy 324.702084 -415.74446) (xy 324.649779 -415.759814) (xy 324.595822 -415.767567)
			(xy 324.568566 -415.768028) (xy 323.704966 -415.768028) (xy 323.677718 -415.767499) (xy 323.623777 -415.759739)
			(xy 323.571489 -415.744382) (xy 323.521918 -415.72174) (xy 323.476075 -415.692275) (xy 323.434891 -415.656585)
			(xy 323.399205 -415.615398) (xy 323.369743 -415.569552) (xy 323.347106 -415.519979) (xy 323.331753 -415.46769)
			(xy 323.323998 -415.413748) (xy 321.886342 -415.413748) (xy 321.886342 -415.413751) (xy 321.878586 -415.4677)
			(xy 321.863231 -415.519995) (xy 321.840591 -415.569573) (xy 321.811126 -415.615425) (xy 321.775435 -415.656617)
			(xy 321.734246 -415.69231) (xy 321.688396 -415.721778) (xy 321.63882 -415.744422) (xy 321.586525 -415.75978)
			(xy 321.532577 -415.76754) (xy 321.505326 -415.768028) (xy 320.641726 -415.768028) (xy 320.614473 -415.767526)
			(xy 320.560522 -415.759773) (xy 320.508224 -415.74442) (xy 320.458643 -415.72178) (xy 320.412789 -415.692314)
			(xy 320.371596 -415.656623) (xy 320.335901 -415.615431) (xy 320.306432 -415.569579) (xy 320.283789 -415.52)
			(xy 320.268433 -415.467703) (xy 320.260675 -415.413753) (xy 318.823165 -415.413753) (xy 318.823165 -415.413755)
			(xy 318.815407 -415.46771) (xy 318.80005 -415.520012) (xy 318.777405 -415.569595) (xy 318.747934 -415.615452)
			(xy 318.712237 -415.656647) (xy 318.671041 -415.692343) (xy 318.625183 -415.721812) (xy 318.575599 -415.744455)
			(xy 318.523296 -415.75981) (xy 318.469341 -415.767566) (xy 318.442086 -415.768028) (xy 317.578486 -415.768028)
			(xy 317.551237 -415.767501) (xy 317.497294 -415.759743) (xy 317.445003 -415.744388) (xy 317.39543 -415.721747)
			(xy 317.349584 -415.692282) (xy 317.308398 -415.656592) (xy 317.27271 -415.615404) (xy 317.243246 -415.569557)
			(xy 317.220608 -415.519984) (xy 317.205254 -415.467693) (xy 317.197498 -415.413749) (xy 315.759842 -415.413749)
			(xy 315.759842 -415.413751) (xy 315.752087 -415.467697) (xy 315.736733 -415.519991) (xy 315.714094 -415.569568)
			(xy 315.68463 -415.615418) (xy 315.648942 -415.656609) (xy 315.607755 -415.692303) (xy 315.561908 -415.721772)
			(xy 315.512334 -415.744417) (xy 315.460042 -415.759777) (xy 315.406097 -415.767539) (xy 315.378846 -415.768028)
			(xy 314.515246 -415.768028) (xy 314.487992 -415.767528) (xy 314.434039 -415.759777) (xy 314.381739 -415.744425)
			(xy 314.332155 -415.721787) (xy 314.286299 -415.692321) (xy 314.245103 -415.65663) (xy 314.209406 -415.615438)
			(xy 314.179935 -415.569585) (xy 314.157291 -415.520004) (xy 314.141933 -415.467706) (xy 314.134175 -415.413754)
			(xy 312.696642 -415.413754) (xy 312.688885 -415.467702) (xy 312.67353 -415.519999) (xy 312.650888 -415.569579)
			(xy 312.621421 -415.615431) (xy 312.585728 -415.656624) (xy 312.544536 -415.692317) (xy 312.498684 -415.721785)
			(xy 312.449105 -415.744428) (xy 312.396808 -415.759784) (xy 312.342858 -415.767542) (xy 312.315606 -415.768028)
			(xy 311.452006 -415.768028) (xy 311.424754 -415.767525) (xy 311.370806 -415.759769) (xy 311.31851 -415.744415)
			(xy 311.268931 -415.721774) (xy 311.22308 -415.692307) (xy 311.181889 -415.656616) (xy 311.146196 -415.615425)
			(xy 311.116729 -415.569574) (xy 311.094088 -415.519996) (xy 311.078732 -415.4677) (xy 311.070975 -415.413752)
			(xy 309.633465 -415.413752) (xy 309.633465 -415.413756) (xy 309.625707 -415.467713) (xy 309.610348 -415.520016)
			(xy 309.587702 -415.569601) (xy 309.558229 -415.615458) (xy 309.52253 -415.656654) (xy 309.481331 -415.69235)
			(xy 309.435471 -415.721818) (xy 309.385884 -415.74446) (xy 309.333579 -415.759814) (xy 309.279622 -415.767567)
			(xy 309.252366 -415.768028) (xy 308.388766 -415.768028) (xy 308.361518 -415.767499) (xy 308.307577 -415.759739)
			(xy 308.255289 -415.744382) (xy 308.205718 -415.72174) (xy 308.159875 -415.692275) (xy 308.118691 -415.656585)
			(xy 308.083005 -415.615398) (xy 308.053543 -415.569552) (xy 308.030906 -415.519979) (xy 308.015553 -415.46769)
			(xy 308.007798 -415.413748) (xy 306.570142 -415.413748) (xy 306.570142 -415.413751) (xy 306.562386 -415.4677)
			(xy 306.547031 -415.519995) (xy 306.524391 -415.569573) (xy 306.494926 -415.615425) (xy 306.459235 -415.656617)
			(xy 306.418046 -415.69231) (xy 306.372196 -415.721778) (xy 306.32262 -415.744422) (xy 306.270325 -415.75978)
			(xy 306.216377 -415.76754) (xy 306.189126 -415.768028) (xy 305.325526 -415.768028) (xy 305.298273 -415.767526)
			(xy 305.244322 -415.759773) (xy 305.192024 -415.74442) (xy 305.142443 -415.72178) (xy 305.096589 -415.692314)
			(xy 305.055396 -415.656623) (xy 305.019701 -415.615431) (xy 304.990232 -415.569579) (xy 304.967589 -415.52)
			(xy 304.952233 -415.467703) (xy 304.944475 -415.413753) (xy 300.882586 -415.413753) (xy 300.868941 -415.434612)
			(xy 300.76479 -415.579315) (xy 300.654297 -415.719235) (xy 300.53768 -415.854094) (xy 300.415171 -415.983624)
			(xy 300.287014 -416.107568) (xy 300.153463 -416.22568) (xy 300.014783 -416.337725) (xy 299.871249 -416.443482)
			(xy 299.723146 -416.542739) (xy 299.570769 -416.635301) (xy 299.41442 -416.720982) (xy 299.254409 -416.799614)
			(xy 299.091055 -416.87104) (xy 298.92468 -416.935118) (xy 298.755617 -416.99172) (xy 298.5842 -417.040736)
			(xy 298.410769 -417.082066) (xy 298.235669 -417.11563) (xy 298.059249 -417.14136) (xy 297.881857 -417.159206)
			(xy 297.703846 -417.169132) (xy 297.525569 -417.171118) (xy 297.347382 -417.165161) (xy 297.169636 -417.151271)
			(xy 296.992686 -417.129478) (xy 296.816882 -417.099824) (xy 296.642574 -417.062367) (xy 296.470107 -417.017183)
			(xy 296.299824 -416.964361) (xy 296.132063 -416.904005) (xy 295.967158 -416.836237) (xy 295.805435 -416.761189)
			(xy 295.647216 -416.679012) (xy 295.492815 -416.589869) (xy 295.342538 -416.493935) (xy 295.196683 -416.391403)
			(xy 295.055541 -416.282475) (xy 294.919392 -416.167368) (xy 294.788505 -416.04631) (xy 294.663141 -415.919541)
			(xy 294.543548 -415.787314) (xy 294.429965 -415.649891) (xy 294.322616 -415.507544) (xy 294.221715 -415.360556)
			(xy 294.127462 -415.20922) (xy 294.040044 -415.053835) (xy 293.959634 -414.89471) (xy 293.886393 -414.732161)
			(xy 293.820466 -414.566511) (xy 293.761983 -414.398089) (xy 293.711061 -414.227228) (xy 293.667801 -414.054269)
			(xy 293.632289 -413.879554) (xy 293.604595 -413.70343) (xy 293.584774 -413.526248) (xy 293.572866 -413.348359)
			(xy 293.568894 -413.170116) (xy 276.749256 -413.170116) (xy 272.414746 -417.504626) (xy 272.396783 -417.521953)
			(xy 272.356401 -417.55128) (xy 272.311928 -417.573928) (xy 272.264459 -417.589339) (xy 272.215164 -417.597133)
			(xy 272.19021 -417.59759) (xy 235.05033 -417.59759) (xy 235.040259 -417.598007) (xy 235.02166 -417.605731)
			(xy 235.014262 -417.612576) (xy 233.545126 -419.081712) (xy 276.721824 -419.081712) (xy 276.721824 -418.218112)
			(xy 276.72231 -418.190861) (xy 276.730066 -418.136913) (xy 276.745421 -418.084618) (xy 276.768063 -418.035041)
			(xy 276.797529 -417.989191) (xy 276.83322 -417.948) (xy 276.874411 -417.912309) (xy 276.920261 -417.882843)
			(xy 276.969838 -417.860201) (xy 277.022133 -417.844846) (xy 277.076081 -417.83709) (xy 277.130583 -417.83709)
			(xy 277.184531 -417.844846) (xy 277.236826 -417.860201) (xy 277.286403 -417.882843) (xy 277.332253 -417.912309)
			(xy 277.373444 -417.948) (xy 277.409135 -417.989191) (xy 277.438601 -418.035041) (xy 277.461243 -418.084618)
			(xy 277.476598 -418.136913) (xy 277.484354 -418.190861) (xy 277.48484 -418.218112) (xy 277.48484 -418.254688)
			(xy 289.453828 -418.254688) (xy 289.453828 -417.391088) (xy 289.454314 -417.363837) (xy 289.46207 -417.309889)
			(xy 289.477425 -417.257594) (xy 289.500067 -417.208017) (xy 289.529533 -417.162167) (xy 289.565224 -417.120976)
			(xy 289.606415 -417.085285) (xy 289.652265 -417.055819) (xy 289.701842 -417.033177) (xy 289.754137 -417.017822)
			(xy 289.808085 -417.010066) (xy 289.862587 -417.010066) (xy 289.916535 -417.017822) (xy 289.96883 -417.033177)
			(xy 290.018407 -417.055819) (xy 290.064257 -417.085285) (xy 290.105448 -417.120976) (xy 290.141139 -417.162167)
			(xy 290.170605 -417.208017) (xy 290.193247 -417.257594) (xy 290.208602 -417.309889) (xy 290.216358 -417.363837)
			(xy 290.216844 -417.391088) (xy 290.216844 -418.254688) (xy 290.216358 -418.281939) (xy 290.208602 -418.335887)
			(xy 290.193247 -418.388182) (xy 290.170605 -418.437759) (xy 290.169514 -418.439456) (xy 304.944423 -418.439456)
			(xy 304.944423 -418.384944) (xy 304.952181 -418.330986) (xy 304.96754 -418.278681) (xy 304.990186 -418.229095)
			(xy 305.019659 -418.183237) (xy 305.055359 -418.14204) (xy 305.096558 -418.106344) (xy 305.142418 -418.076874)
			(xy 305.192006 -418.054231) (xy 305.244311 -418.038876) (xy 305.29827 -418.031121) (xy 305.325526 -418.03066)
			(xy 306.189126 -418.03066) (xy 306.216374 -418.031212) (xy 306.270314 -418.038971) (xy 306.322601 -418.054327)
			(xy 306.372171 -418.076968) (xy 306.418014 -418.106432) (xy 306.459198 -418.142121) (xy 306.494884 -418.183307)
			(xy 306.524345 -418.229152) (xy 306.546982 -418.278723) (xy 306.562335 -418.331011) (xy 306.57009 -418.384952)
			(xy 306.57009 -418.439448) (xy 306.570089 -418.439452) (xy 308.007746 -418.439452) (xy 308.007746 -418.384948)
			(xy 308.015502 -418.330999) (xy 308.030857 -418.278702) (xy 308.053497 -418.229123) (xy 308.082963 -418.183271)
			(xy 308.118654 -418.142078) (xy 308.159843 -418.106383) (xy 308.205693 -418.076914) (xy 308.25527 -418.054269)
			(xy 308.307565 -418.038909) (xy 308.361514 -418.031148) (xy 308.388766 -418.03066) (xy 309.252366 -418.03066)
			(xy 309.279618 -418.031185) (xy 309.333568 -418.038937) (xy 309.385866 -418.054289) (xy 309.435446 -418.076928)
			(xy 309.4813 -418.106392) (xy 309.522493 -418.142083) (xy 309.558187 -418.183273) (xy 309.587656 -418.229124)
			(xy 309.610299 -418.278702) (xy 309.625655 -418.330999) (xy 309.633413 -418.384948) (xy 309.633413 -418.439452)
			(xy 309.633413 -418.439455) (xy 311.070923 -418.439455) (xy 311.070923 -418.384945) (xy 311.078681 -418.330989)
			(xy 311.094038 -418.278686) (xy 311.116683 -418.229101) (xy 311.146154 -418.183244) (xy 311.181852 -418.142047)
			(xy 311.223049 -418.106351) (xy 311.268906 -418.07688) (xy 311.318491 -418.054236) (xy 311.370794 -418.038879)
			(xy 311.424751 -418.031123) (xy 311.452006 -418.03066) (xy 312.315606 -418.03066) (xy 312.342855 -418.031211)
			(xy 312.396797 -418.038967) (xy 312.449087 -418.054321) (xy 312.498659 -418.076961) (xy 312.544505 -418.106425)
			(xy 312.585691 -418.142113) (xy 312.621379 -418.1833) (xy 312.650842 -418.229146) (xy 312.673481 -418.278719)
			(xy 312.688834 -418.331009) (xy 312.69659 -418.384951) (xy 312.69659 -418.439449) (xy 312.696589 -418.439457)
			(xy 314.134123 -418.439457) (xy 314.134123 -418.384943) (xy 314.141882 -418.330983) (xy 314.157242 -418.278677)
			(xy 314.179889 -418.22909) (xy 314.209364 -418.183231) (xy 314.245066 -418.142033) (xy 314.286267 -418.106337)
			(xy 314.33213 -418.076867) (xy 314.38172 -418.054225) (xy 314.434028 -418.038872) (xy 314.487989 -418.03112)
			(xy 314.515246 -418.03066) (xy 315.378846 -418.03066) (xy 315.406093 -418.031213) (xy 315.460031 -418.038975)
			(xy 315.512316 -418.054332) (xy 315.561883 -418.076974) (xy 315.607724 -418.106439) (xy 315.648905 -418.142128)
			(xy 315.684588 -418.183313) (xy 315.714048 -418.229157) (xy 315.736684 -418.278727) (xy 315.752035 -418.331014)
			(xy 315.75979 -418.384953) (xy 315.75979 -418.439447) (xy 315.759789 -418.439453) (xy 317.197446 -418.439453)
			(xy 317.197446 -418.384947) (xy 317.205203 -418.330996) (xy 317.220558 -418.278698) (xy 317.2432 -418.229118)
			(xy 317.272668 -418.183264) (xy 317.308361 -418.142071) (xy 317.349553 -418.106376) (xy 317.395405 -418.076907)
			(xy 317.444985 -418.054263) (xy 317.497282 -418.038906) (xy 317.551233 -418.031147) (xy 317.578486 -418.03066)
			(xy 318.442086 -418.03066) (xy 318.469337 -418.031186) (xy 318.523285 -418.038941) (xy 318.57558 -418.054295)
			(xy 318.625158 -418.076934) (xy 318.671009 -418.106399) (xy 318.7122 -418.14209) (xy 318.747892 -418.18328)
			(xy 318.777359 -418.22913) (xy 318.800001 -418.278707) (xy 318.815356 -418.331001) (xy 318.823113 -418.384949)
			(xy 318.823113 -418.439451) (xy 318.823112 -418.439456) (xy 320.260623 -418.439456) (xy 320.260623 -418.384944)
			(xy 320.268381 -418.330986) (xy 320.28374 -418.278681) (xy 320.306386 -418.229095) (xy 320.335859 -418.183237)
			(xy 320.371559 -418.14204) (xy 320.412758 -418.106344) (xy 320.458618 -418.076874) (xy 320.508206 -418.054231)
			(xy 320.560511 -418.038876) (xy 320.61447 -418.031121) (xy 320.641726 -418.03066) (xy 321.505326 -418.03066)
			(xy 321.532574 -418.031212) (xy 321.586514 -418.038971) (xy 321.638801 -418.054327) (xy 321.688371 -418.076968)
			(xy 321.734214 -418.106432) (xy 321.775398 -418.142121) (xy 321.811084 -418.183307) (xy 321.840545 -418.229152)
			(xy 321.863182 -418.278723) (xy 321.878535 -418.331011) (xy 321.88629 -418.384952) (xy 321.88629 -418.439448)
			(xy 321.886289 -418.439452) (xy 323.323946 -418.439452) (xy 323.323946 -418.384948) (xy 323.331702 -418.330999)
			(xy 323.347057 -418.278702) (xy 323.369697 -418.229123) (xy 323.399163 -418.183271) (xy 323.434854 -418.142078)
			(xy 323.476043 -418.106383) (xy 323.521893 -418.076914) (xy 323.57147 -418.054269) (xy 323.623765 -418.038909)
			(xy 323.677714 -418.031148) (xy 323.704966 -418.03066) (xy 324.568566 -418.03066) (xy 324.595818 -418.031185)
			(xy 324.649768 -418.038937) (xy 324.702066 -418.054289) (xy 324.751646 -418.076928) (xy 324.7975 -418.106392)
			(xy 324.838693 -418.142083) (xy 324.874387 -418.183273) (xy 324.903856 -418.229124) (xy 324.926499 -418.278702)
			(xy 324.941855 -418.330999) (xy 324.949613 -418.384948) (xy 324.949613 -418.439452) (xy 324.949613 -418.439455)
			(xy 326.387123 -418.439455) (xy 326.387123 -418.384945) (xy 326.394881 -418.330989) (xy 326.410238 -418.278686)
			(xy 326.432883 -418.229101) (xy 326.462354 -418.183244) (xy 326.498052 -418.142047) (xy 326.539249 -418.106351)
			(xy 326.585106 -418.07688) (xy 326.634691 -418.054236) (xy 326.686994 -418.038879) (xy 326.740951 -418.031123)
			(xy 326.768206 -418.03066) (xy 327.631806 -418.03066) (xy 327.659055 -418.031211) (xy 327.712997 -418.038967)
			(xy 327.765287 -418.054321) (xy 327.814859 -418.076961) (xy 327.860705 -418.106425) (xy 327.901891 -418.142113)
			(xy 327.937579 -418.1833) (xy 327.967042 -418.229146) (xy 327.989681 -418.278719) (xy 328.005034 -418.331009)
			(xy 328.01279 -418.384951) (xy 328.01279 -418.439449) (xy 328.012789 -418.439457) (xy 329.450323 -418.439457)
			(xy 329.450323 -418.384943) (xy 329.458082 -418.330983) (xy 329.473442 -418.278677) (xy 329.496089 -418.22909)
			(xy 329.525564 -418.183231) (xy 329.561266 -418.142033) (xy 329.602467 -418.106337) (xy 329.64833 -418.076867)
			(xy 329.69792 -418.054225) (xy 329.750228 -418.038872) (xy 329.804189 -418.03112) (xy 329.831446 -418.03066)
			(xy 330.695046 -418.03066) (xy 330.722293 -418.031213) (xy 330.776231 -418.038975) (xy 330.828516 -418.054332)
			(xy 330.878083 -418.076974) (xy 330.923924 -418.106439) (xy 330.965105 -418.142128) (xy 331.000788 -418.183313)
			(xy 331.030248 -418.229157) (xy 331.052884 -418.278727) (xy 331.068235 -418.331014) (xy 331.07599 -418.384953)
			(xy 331.07599 -418.439447) (xy 331.075989 -418.439453) (xy 332.513646 -418.439453) (xy 332.513646 -418.384947)
			(xy 332.521403 -418.330996) (xy 332.536758 -418.278698) (xy 332.5594 -418.229118) (xy 332.588868 -418.183264)
			(xy 332.624561 -418.142071) (xy 332.665753 -418.106376) (xy 332.711605 -418.076907) (xy 332.761185 -418.054263)
			(xy 332.813482 -418.038906) (xy 332.867433 -418.031147) (xy 332.894686 -418.03066) (xy 333.758286 -418.03066)
			(xy 333.785537 -418.031186) (xy 333.839485 -418.038941) (xy 333.89178 -418.054295) (xy 333.941358 -418.076934)
			(xy 333.987209 -418.106399) (xy 334.0284 -418.14209) (xy 334.064092 -418.18328) (xy 334.093559 -418.22913)
			(xy 334.116201 -418.278707) (xy 334.131556 -418.331001) (xy 334.139313 -418.384949) (xy 334.139313 -418.439451)
			(xy 334.139312 -418.439456) (xy 335.576823 -418.439456) (xy 335.576823 -418.384944) (xy 335.584581 -418.330986)
			(xy 335.59994 -418.278681) (xy 335.622586 -418.229095) (xy 335.652059 -418.183237) (xy 335.687759 -418.14204)
			(xy 335.728958 -418.106344) (xy 335.774818 -418.076874) (xy 335.824406 -418.054231) (xy 335.876711 -418.038876)
			(xy 335.93067 -418.031121) (xy 335.957926 -418.03066) (xy 336.821526 -418.03066) (xy 336.848774 -418.031212)
			(xy 336.902714 -418.038971) (xy 336.955001 -418.054327) (xy 337.004571 -418.076968) (xy 337.050414 -418.106432)
			(xy 337.091598 -418.142121) (xy 337.127284 -418.183307) (xy 337.156745 -418.229152) (xy 337.179382 -418.278723)
			(xy 337.194735 -418.331011) (xy 337.20249 -418.384952) (xy 337.20249 -418.439448) (xy 337.202489 -418.439452)
			(xy 338.640146 -418.439452) (xy 338.640146 -418.384948) (xy 338.647902 -418.330999) (xy 338.663257 -418.278702)
			(xy 338.685897 -418.229123) (xy 338.715363 -418.183271) (xy 338.751054 -418.142078) (xy 338.792243 -418.106383)
			(xy 338.838093 -418.076914) (xy 338.88767 -418.054269) (xy 338.939965 -418.038909) (xy 338.993914 -418.031148)
			(xy 339.021166 -418.03066) (xy 339.884766 -418.03066) (xy 339.912018 -418.031185) (xy 339.965968 -418.038937)
			(xy 340.018266 -418.054289) (xy 340.067846 -418.076928) (xy 340.1137 -418.106392) (xy 340.154893 -418.142083)
			(xy 340.190587 -418.183273) (xy 340.220056 -418.229124) (xy 340.242699 -418.278702) (xy 340.258055 -418.330999)
			(xy 340.265813 -418.384948) (xy 340.265813 -418.439452) (xy 340.265813 -418.439455) (xy 341.703323 -418.439455)
			(xy 341.703323 -418.384945) (xy 341.711081 -418.330989) (xy 341.726438 -418.278686) (xy 341.749083 -418.229101)
			(xy 341.778554 -418.183244) (xy 341.814252 -418.142047) (xy 341.855449 -418.106351) (xy 341.901306 -418.07688)
			(xy 341.950891 -418.054236) (xy 342.003194 -418.038879) (xy 342.057151 -418.031123) (xy 342.084406 -418.03066)
			(xy 342.948006 -418.03066) (xy 342.975255 -418.031211) (xy 343.029197 -418.038967) (xy 343.081487 -418.054321)
			(xy 343.131059 -418.076961) (xy 343.176905 -418.106425) (xy 343.218091 -418.142113) (xy 343.253779 -418.1833)
			(xy 343.283242 -418.229146) (xy 343.305881 -418.278719) (xy 343.321234 -418.331009) (xy 343.32899 -418.384951)
			(xy 343.32899 -418.439449) (xy 343.328989 -418.439457) (xy 344.766523 -418.439457) (xy 344.766523 -418.384943)
			(xy 344.774282 -418.330983) (xy 344.789642 -418.278677) (xy 344.812289 -418.22909) (xy 344.841764 -418.183231)
			(xy 344.877466 -418.142033) (xy 344.918667 -418.106337) (xy 344.96453 -418.076867) (xy 345.01412 -418.054225)
			(xy 345.066428 -418.038872) (xy 345.120389 -418.03112) (xy 345.147646 -418.03066) (xy 346.011246 -418.03066)
			(xy 346.038493 -418.031213) (xy 346.092431 -418.038975) (xy 346.144716 -418.054332) (xy 346.194283 -418.076974)
			(xy 346.240124 -418.106439) (xy 346.281305 -418.142128) (xy 346.316988 -418.183313) (xy 346.346448 -418.229157)
			(xy 346.369084 -418.278727) (xy 346.384435 -418.331014) (xy 346.39219 -418.384953) (xy 346.39219 -418.439447)
			(xy 346.392189 -418.439453) (xy 347.829846 -418.439453) (xy 347.829846 -418.384947) (xy 347.837603 -418.330996)
			(xy 347.852958 -418.278698) (xy 347.8756 -418.229118) (xy 347.905068 -418.183264) (xy 347.940761 -418.142071)
			(xy 347.981953 -418.106376) (xy 348.027805 -418.076907) (xy 348.077385 -418.054263) (xy 348.129682 -418.038906)
			(xy 348.183633 -418.031147) (xy 348.210886 -418.03066) (xy 349.074486 -418.03066) (xy 349.101737 -418.031186)
			(xy 349.155685 -418.038941) (xy 349.20798 -418.054295) (xy 349.257558 -418.076934) (xy 349.303409 -418.106399)
			(xy 349.3446 -418.14209) (xy 349.380292 -418.18328) (xy 349.409759 -418.22913) (xy 349.432401 -418.278707)
			(xy 349.447756 -418.331001) (xy 349.455513 -418.384949) (xy 349.455513 -418.439451) (xy 349.455512 -418.439456)
			(xy 350.893023 -418.439456) (xy 350.893023 -418.384944) (xy 350.900781 -418.330986) (xy 350.91614 -418.278681)
			(xy 350.938786 -418.229095) (xy 350.968259 -418.183237) (xy 351.003959 -418.14204) (xy 351.045158 -418.106344)
			(xy 351.091018 -418.076874) (xy 351.140606 -418.054231) (xy 351.192911 -418.038876) (xy 351.24687 -418.031121)
			(xy 351.274126 -418.03066) (xy 352.137726 -418.03066) (xy 352.164974 -418.031212) (xy 352.218914 -418.038971)
			(xy 352.271201 -418.054327) (xy 352.320771 -418.076968) (xy 352.366614 -418.106432) (xy 352.407798 -418.142121)
			(xy 352.443484 -418.183307) (xy 352.472945 -418.229152) (xy 352.495582 -418.278723) (xy 352.510935 -418.331011)
			(xy 352.51869 -418.384952) (xy 352.51869 -418.439448) (xy 352.510935 -418.493389) (xy 352.495582 -418.545677)
			(xy 352.472945 -418.595248) (xy 352.443484 -418.641093) (xy 352.407798 -418.682279) (xy 352.366614 -418.717968)
			(xy 352.320771 -418.747432) (xy 352.271201 -418.770073) (xy 352.218914 -418.785429) (xy 352.164974 -418.793188)
			(xy 352.137726 -418.793676) (xy 351.274126 -418.793676) (xy 351.24687 -418.793279) (xy 351.192911 -418.785524)
			(xy 351.140606 -418.770169) (xy 351.091018 -418.747526) (xy 351.045158 -418.718056) (xy 351.003959 -418.68236)
			(xy 350.968259 -418.641163) (xy 350.938786 -418.595305) (xy 350.91614 -418.545719) (xy 350.900781 -418.493414)
			(xy 350.893023 -418.439456) (xy 349.455512 -418.439456) (xy 349.447756 -418.493399) (xy 349.432401 -418.545693)
			(xy 349.409759 -418.59527) (xy 349.380292 -418.64112) (xy 349.3446 -418.68231) (xy 349.303409 -418.718001)
			(xy 349.257558 -418.747466) (xy 349.20798 -418.770105) (xy 349.155685 -418.785459) (xy 349.101737 -418.793214)
			(xy 349.074486 -418.793676) (xy 348.210886 -418.793676) (xy 348.183633 -418.793253) (xy 348.129682 -418.785494)
			(xy 348.077385 -418.770137) (xy 348.027805 -418.747493) (xy 347.981953 -418.718024) (xy 347.940761 -418.682329)
			(xy 347.905068 -418.641136) (xy 347.8756 -418.595282) (xy 347.852958 -418.545702) (xy 347.837603 -418.493404)
			(xy 347.829846 -418.439453) (xy 346.392189 -418.439453) (xy 346.384435 -418.493386) (xy 346.369084 -418.545673)
			(xy 346.346448 -418.595243) (xy 346.316988 -418.641087) (xy 346.281305 -418.682272) (xy 346.240124 -418.717961)
			(xy 346.194283 -418.747426) (xy 346.144716 -418.770068) (xy 346.092431 -418.785425) (xy 346.038493 -418.793187)
			(xy 346.011246 -418.793676) (xy 345.147646 -418.793676) (xy 345.120389 -418.79328) (xy 345.066428 -418.785528)
			(xy 345.01412 -418.770175) (xy 344.96453 -418.747533) (xy 344.918667 -418.718063) (xy 344.877466 -418.682367)
			(xy 344.841764 -418.641169) (xy 344.812289 -418.59531) (xy 344.789642 -418.545723) (xy 344.774282 -418.493417)
			(xy 344.766523 -418.439457) (xy 343.328989 -418.439457) (xy 343.321234 -418.493391) (xy 343.305881 -418.545681)
			(xy 343.283242 -418.595254) (xy 343.253779 -418.6411) (xy 343.218091 -418.682287) (xy 343.176905 -418.717975)
			(xy 343.131059 -418.747439) (xy 343.081487 -418.770079) (xy 343.029197 -418.785433) (xy 342.975255 -418.793189)
			(xy 342.948006 -418.793676) (xy 342.084406 -418.793676) (xy 342.057151 -418.793277) (xy 342.003194 -418.785521)
			(xy 341.950891 -418.770164) (xy 341.901306 -418.74752) (xy 341.855449 -418.718049) (xy 341.814252 -418.682353)
			(xy 341.778554 -418.641156) (xy 341.749083 -418.595299) (xy 341.726438 -418.545714) (xy 341.711081 -418.493411)
			(xy 341.703323 -418.439455) (xy 340.265813 -418.439455) (xy 340.258055 -418.493402) (xy 340.242699 -418.545698)
			(xy 340.220056 -418.595276) (xy 340.190587 -418.641127) (xy 340.154893 -418.682317) (xy 340.1137 -418.718008)
			(xy 340.067846 -418.747472) (xy 340.018266 -418.770111) (xy 339.965968 -418.785463) (xy 339.912018 -418.793215)
			(xy 339.884766 -418.793676) (xy 339.021166 -418.793676) (xy 338.993914 -418.793252) (xy 338.939965 -418.785491)
			(xy 338.88767 -418.770131) (xy 338.838093 -418.747486) (xy 338.792243 -418.718017) (xy 338.751054 -418.682322)
			(xy 338.715363 -418.641129) (xy 338.685897 -418.595277) (xy 338.663257 -418.545698) (xy 338.647902 -418.493401)
			(xy 338.640146 -418.439452) (xy 337.202489 -418.439452) (xy 337.194735 -418.493389) (xy 337.179382 -418.545677)
			(xy 337.156745 -418.595248) (xy 337.127284 -418.641093) (xy 337.091598 -418.682279) (xy 337.050414 -418.717968)
			(xy 337.004571 -418.747432) (xy 336.955001 -418.770073) (xy 336.902714 -418.785429) (xy 336.848774 -418.793188)
			(xy 336.821526 -418.793676) (xy 335.957926 -418.793676) (xy 335.93067 -418.793279) (xy 335.876711 -418.785524)
			(xy 335.824406 -418.770169) (xy 335.774818 -418.747526) (xy 335.728958 -418.718056) (xy 335.687759 -418.68236)
			(xy 335.652059 -418.641163) (xy 335.622586 -418.595305) (xy 335.59994 -418.545719) (xy 335.584581 -418.493414)
			(xy 335.576823 -418.439456) (xy 334.139312 -418.439456) (xy 334.131556 -418.493399) (xy 334.116201 -418.545693)
			(xy 334.093559 -418.59527) (xy 334.064092 -418.64112) (xy 334.0284 -418.68231) (xy 333.987209 -418.718001)
			(xy 333.941358 -418.747466) (xy 333.89178 -418.770105) (xy 333.839485 -418.785459) (xy 333.785537 -418.793214)
			(xy 333.758286 -418.793676) (xy 332.894686 -418.793676) (xy 332.867433 -418.793253) (xy 332.813482 -418.785494)
			(xy 332.761185 -418.770137) (xy 332.711605 -418.747493) (xy 332.665753 -418.718024) (xy 332.624561 -418.682329)
			(xy 332.588868 -418.641136) (xy 332.5594 -418.595282) (xy 332.536758 -418.545702) (xy 332.521403 -418.493404)
			(xy 332.513646 -418.439453) (xy 331.075989 -418.439453) (xy 331.068235 -418.493386) (xy 331.052884 -418.545673)
			(xy 331.030248 -418.595243) (xy 331.000788 -418.641087) (xy 330.965105 -418.682272) (xy 330.923924 -418.717961)
			(xy 330.878083 -418.747426) (xy 330.828516 -418.770068) (xy 330.776231 -418.785425) (xy 330.722293 -418.793187)
			(xy 330.695046 -418.793676) (xy 329.831446 -418.793676) (xy 329.804189 -418.79328) (xy 329.750228 -418.785528)
			(xy 329.69792 -418.770175) (xy 329.64833 -418.747533) (xy 329.602467 -418.718063) (xy 329.561266 -418.682367)
			(xy 329.525564 -418.641169) (xy 329.496089 -418.59531) (xy 329.473442 -418.545723) (xy 329.458082 -418.493417)
			(xy 329.450323 -418.439457) (xy 328.012789 -418.439457) (xy 328.005034 -418.493391) (xy 327.989681 -418.545681)
			(xy 327.967042 -418.595254) (xy 327.937579 -418.6411) (xy 327.901891 -418.682287) (xy 327.860705 -418.717975)
			(xy 327.814859 -418.747439) (xy 327.765287 -418.770079) (xy 327.712997 -418.785433) (xy 327.659055 -418.793189)
			(xy 327.631806 -418.793676) (xy 326.768206 -418.793676) (xy 326.740951 -418.793277) (xy 326.686994 -418.785521)
			(xy 326.634691 -418.770164) (xy 326.585106 -418.74752) (xy 326.539249 -418.718049) (xy 326.498052 -418.682353)
			(xy 326.462354 -418.641156) (xy 326.432883 -418.595299) (xy 326.410238 -418.545714) (xy 326.394881 -418.493411)
			(xy 326.387123 -418.439455) (xy 324.949613 -418.439455) (xy 324.941855 -418.493402) (xy 324.926499 -418.545698)
			(xy 324.903856 -418.595276) (xy 324.874387 -418.641127) (xy 324.838693 -418.682317) (xy 324.7975 -418.718008)
			(xy 324.751646 -418.747472) (xy 324.702066 -418.770111) (xy 324.649768 -418.785463) (xy 324.595818 -418.793215)
			(xy 324.568566 -418.793676) (xy 323.704966 -418.793676) (xy 323.677714 -418.793252) (xy 323.623765 -418.785491)
			(xy 323.57147 -418.770131) (xy 323.521893 -418.747486) (xy 323.476043 -418.718017) (xy 323.434854 -418.682322)
			(xy 323.399163 -418.641129) (xy 323.369697 -418.595277) (xy 323.347057 -418.545698) (xy 323.331702 -418.493401)
			(xy 323.323946 -418.439452) (xy 321.886289 -418.439452) (xy 321.878535 -418.493389) (xy 321.863182 -418.545677)
			(xy 321.840545 -418.595248) (xy 321.811084 -418.641093) (xy 321.775398 -418.682279) (xy 321.734214 -418.717968)
			(xy 321.688371 -418.747432) (xy 321.638801 -418.770073) (xy 321.586514 -418.785429) (xy 321.532574 -418.793188)
			(xy 321.505326 -418.793676) (xy 320.641726 -418.793676) (xy 320.61447 -418.793279) (xy 320.560511 -418.785524)
			(xy 320.508206 -418.770169) (xy 320.458618 -418.747526) (xy 320.412758 -418.718056) (xy 320.371559 -418.68236)
			(xy 320.335859 -418.641163) (xy 320.306386 -418.595305) (xy 320.28374 -418.545719) (xy 320.268381 -418.493414)
			(xy 320.260623 -418.439456) (xy 318.823112 -418.439456) (xy 318.815356 -418.493399) (xy 318.800001 -418.545693)
			(xy 318.777359 -418.59527) (xy 318.747892 -418.64112) (xy 318.7122 -418.68231) (xy 318.671009 -418.718001)
			(xy 318.625158 -418.747466) (xy 318.57558 -418.770105) (xy 318.523285 -418.785459) (xy 318.469337 -418.793214)
			(xy 318.442086 -418.793676) (xy 317.578486 -418.793676) (xy 317.551233 -418.793253) (xy 317.497282 -418.785494)
			(xy 317.444985 -418.770137) (xy 317.395405 -418.747493) (xy 317.349553 -418.718024) (xy 317.308361 -418.682329)
			(xy 317.272668 -418.641136) (xy 317.2432 -418.595282) (xy 317.220558 -418.545702) (xy 317.205203 -418.493404)
			(xy 317.197446 -418.439453) (xy 315.759789 -418.439453) (xy 315.752035 -418.493386) (xy 315.736684 -418.545673)
			(xy 315.714048 -418.595243) (xy 315.684588 -418.641087) (xy 315.648905 -418.682272) (xy 315.607724 -418.717961)
			(xy 315.561883 -418.747426) (xy 315.512316 -418.770068) (xy 315.460031 -418.785425) (xy 315.406093 -418.793187)
			(xy 315.378846 -418.793676) (xy 314.515246 -418.793676) (xy 314.487989 -418.79328) (xy 314.434028 -418.785528)
			(xy 314.38172 -418.770175) (xy 314.33213 -418.747533) (xy 314.286267 -418.718063) (xy 314.245066 -418.682367)
			(xy 314.209364 -418.641169) (xy 314.179889 -418.59531) (xy 314.157242 -418.545723) (xy 314.141882 -418.493417)
			(xy 314.134123 -418.439457) (xy 312.696589 -418.439457) (xy 312.688834 -418.493391) (xy 312.673481 -418.545681)
			(xy 312.650842 -418.595254) (xy 312.621379 -418.6411) (xy 312.585691 -418.682287) (xy 312.544505 -418.717975)
			(xy 312.498659 -418.747439) (xy 312.449087 -418.770079) (xy 312.396797 -418.785433) (xy 312.342855 -418.793189)
			(xy 312.315606 -418.793676) (xy 311.452006 -418.793676) (xy 311.424751 -418.793277) (xy 311.370794 -418.785521)
			(xy 311.318491 -418.770164) (xy 311.268906 -418.74752) (xy 311.223049 -418.718049) (xy 311.181852 -418.682353)
			(xy 311.146154 -418.641156) (xy 311.116683 -418.595299) (xy 311.094038 -418.545714) (xy 311.078681 -418.493411)
			(xy 311.070923 -418.439455) (xy 309.633413 -418.439455) (xy 309.625655 -418.493402) (xy 309.610299 -418.545698)
			(xy 309.587656 -418.595276) (xy 309.558187 -418.641127) (xy 309.522493 -418.682317) (xy 309.4813 -418.718008)
			(xy 309.435446 -418.747472) (xy 309.385866 -418.770111) (xy 309.333568 -418.785463) (xy 309.279618 -418.793215)
			(xy 309.252366 -418.793676) (xy 308.388766 -418.793676) (xy 308.361514 -418.793252) (xy 308.307565 -418.785491)
			(xy 308.25527 -418.770131) (xy 308.205693 -418.747486) (xy 308.159843 -418.718017) (xy 308.118654 -418.682322)
			(xy 308.082963 -418.641129) (xy 308.053497 -418.595277) (xy 308.030857 -418.545698) (xy 308.015502 -418.493401)
			(xy 308.007746 -418.439452) (xy 306.570089 -418.439452) (xy 306.562335 -418.493389) (xy 306.546982 -418.545677)
			(xy 306.524345 -418.595248) (xy 306.494884 -418.641093) (xy 306.459198 -418.682279) (xy 306.418014 -418.717968)
			(xy 306.372171 -418.747432) (xy 306.322601 -418.770073) (xy 306.270314 -418.785429) (xy 306.216374 -418.793188)
			(xy 306.189126 -418.793676) (xy 305.325526 -418.793676) (xy 305.29827 -418.793279) (xy 305.244311 -418.785524)
			(xy 305.192006 -418.770169) (xy 305.142418 -418.747526) (xy 305.096558 -418.718056) (xy 305.055359 -418.68236)
			(xy 305.019659 -418.641163) (xy 304.990186 -418.595305) (xy 304.96754 -418.545719) (xy 304.952181 -418.493414)
			(xy 304.944423 -418.439456) (xy 290.169514 -418.439456) (xy 290.141139 -418.483609) (xy 290.105448 -418.5248)
			(xy 290.064257 -418.560491) (xy 290.018407 -418.589957) (xy 289.96883 -418.612599) (xy 289.916535 -418.627954)
			(xy 289.862587 -418.63571) (xy 289.808085 -418.63571) (xy 289.754137 -418.627954) (xy 289.701842 -418.612599)
			(xy 289.652265 -418.589957) (xy 289.606415 -418.560491) (xy 289.565224 -418.5248) (xy 289.529533 -418.483609)
			(xy 289.500067 -418.437759) (xy 289.477425 -418.388182) (xy 289.46207 -418.335887) (xy 289.454314 -418.281939)
			(xy 289.453828 -418.254688) (xy 277.48484 -418.254688) (xy 277.48484 -419.081712) (xy 277.484354 -419.108963)
			(xy 277.476598 -419.162911) (xy 277.461243 -419.215206) (xy 277.438601 -419.264783) (xy 277.409135 -419.310633)
			(xy 277.373444 -419.351824) (xy 277.332253 -419.387515) (xy 277.286403 -419.416981) (xy 277.236826 -419.439623)
			(xy 277.184531 -419.454978) (xy 277.130583 -419.462734) (xy 277.076081 -419.462734) (xy 277.022133 -419.454978)
			(xy 276.969838 -419.439623) (xy 276.920261 -419.416981) (xy 276.874411 -419.387515) (xy 276.83322 -419.351824)
			(xy 276.797529 -419.310633) (xy 276.768063 -419.264783) (xy 276.745421 -419.215206) (xy 276.730066 -419.162911)
			(xy 276.72231 -419.108963) (xy 276.721824 -419.081712) (xy 233.545126 -419.081712) (xy 232.102406 -420.524432)
			(xy 290.829492 -420.524432) (xy 290.829492 -419.660832) (xy 290.829978 -419.633563) (xy 290.83774 -419.579579)
			(xy 290.853105 -419.527249) (xy 290.875762 -419.477639) (xy 290.905248 -419.431758) (xy 290.940963 -419.390541)
			(xy 290.98218 -419.354826) (xy 291.028061 -419.32534) (xy 291.077671 -419.302683) (xy 291.130001 -419.287318)
			(xy 291.183985 -419.279556) (xy 291.238523 -419.279556) (xy 291.292507 -419.287318) (xy 291.344837 -419.302683)
			(xy 291.394447 -419.32534) (xy 291.440328 -419.354826) (xy 291.481545 -419.390541) (xy 291.51726 -419.431758)
			(xy 291.546746 -419.477639) (xy 291.569403 -419.527249) (xy 291.584768 -419.579579) (xy 291.59253 -419.633563)
			(xy 291.593016 -419.660832) (xy 291.593016 -420.524432) (xy 291.59253 -420.551701) (xy 291.584768 -420.605685)
			(xy 291.569403 -420.658015) (xy 291.546746 -420.707625) (xy 291.51726 -420.753506) (xy 291.481545 -420.794723)
			(xy 291.440328 -420.830438) (xy 291.394447 -420.859924) (xy 291.344837 -420.882581) (xy 291.292507 -420.897946)
			(xy 291.238523 -420.905708) (xy 291.183985 -420.905708) (xy 291.130001 -420.897946) (xy 291.077671 -420.882581)
			(xy 291.028061 -420.859924) (xy 290.98218 -420.830438) (xy 290.940963 -420.794723) (xy 290.905248 -420.753506)
			(xy 290.875762 -420.707625) (xy 290.853105 -420.658015) (xy 290.83774 -420.605685) (xy 290.829978 -420.551701)
			(xy 290.829492 -420.524432) (xy 232.102406 -420.524432) (xy 231.647383 -420.979455) (xy 303.412823 -420.979455)
			(xy 303.412823 -420.924945) (xy 303.420581 -420.870989) (xy 303.435938 -420.818686) (xy 303.458583 -420.769101)
			(xy 303.488054 -420.723244) (xy 303.523752 -420.682047) (xy 303.564949 -420.646351) (xy 303.610806 -420.61688)
			(xy 303.660391 -420.594236) (xy 303.712694 -420.578879) (xy 303.766651 -420.571123) (xy 303.793906 -420.57066)
			(xy 304.657506 -420.57066) (xy 304.684755 -420.571211) (xy 304.738697 -420.578967) (xy 304.790987 -420.594321)
			(xy 304.840559 -420.616961) (xy 304.886405 -420.646425) (xy 304.927591 -420.682113) (xy 304.963279 -420.7233)
			(xy 304.992742 -420.769146) (xy 305.015381 -420.818719) (xy 305.030734 -420.871009) (xy 305.03849 -420.924951)
			(xy 305.03849 -420.979449) (xy 305.038489 -420.979457) (xy 306.476023 -420.979457) (xy 306.476023 -420.924943)
			(xy 306.483782 -420.870983) (xy 306.499142 -420.818677) (xy 306.521789 -420.76909) (xy 306.551264 -420.723231)
			(xy 306.586966 -420.682033) (xy 306.628167 -420.646337) (xy 306.67403 -420.616867) (xy 306.72362 -420.594225)
			(xy 306.775928 -420.578872) (xy 306.829889 -420.57112) (xy 306.857146 -420.57066) (xy 307.720746 -420.57066)
			(xy 307.747993 -420.571213) (xy 307.801931 -420.578975) (xy 307.854216 -420.594332) (xy 307.903783 -420.616974)
			(xy 307.949624 -420.646439) (xy 307.990805 -420.682128) (xy 308.026488 -420.723313) (xy 308.055948 -420.769157)
			(xy 308.078584 -420.818727) (xy 308.093935 -420.871014) (xy 308.10169 -420.924953) (xy 308.10169 -420.979447)
			(xy 308.101689 -420.979453) (xy 309.539346 -420.979453) (xy 309.539346 -420.924947) (xy 309.547103 -420.870996)
			(xy 309.562458 -420.818698) (xy 309.5851 -420.769118) (xy 309.614568 -420.723264) (xy 309.650261 -420.682071)
			(xy 309.691453 -420.646376) (xy 309.737305 -420.616907) (xy 309.786885 -420.594263) (xy 309.839182 -420.578906)
			(xy 309.893133 -420.571147) (xy 309.920386 -420.57066) (xy 310.783986 -420.57066) (xy 310.811237 -420.571186)
			(xy 310.865185 -420.578941) (xy 310.91748 -420.594295) (xy 310.967058 -420.616934) (xy 311.012909 -420.646399)
			(xy 311.0541 -420.68209) (xy 311.089792 -420.72328) (xy 311.119259 -420.76913) (xy 311.141901 -420.818707)
			(xy 311.157256 -420.871001) (xy 311.165013 -420.924949) (xy 311.165013 -420.979451) (xy 311.165012 -420.979456)
			(xy 312.602523 -420.979456) (xy 312.602523 -420.924944) (xy 312.610281 -420.870986) (xy 312.62564 -420.818681)
			(xy 312.648286 -420.769095) (xy 312.677759 -420.723237) (xy 312.713459 -420.68204) (xy 312.754658 -420.646344)
			(xy 312.800518 -420.616874) (xy 312.850106 -420.594231) (xy 312.902411 -420.578876) (xy 312.95637 -420.571121)
			(xy 312.983626 -420.57066) (xy 313.847226 -420.57066) (xy 313.874474 -420.571212) (xy 313.928414 -420.578971)
			(xy 313.980701 -420.594327) (xy 314.030271 -420.616968) (xy 314.076114 -420.646432) (xy 314.117298 -420.682121)
			(xy 314.152984 -420.723307) (xy 314.182445 -420.769152) (xy 314.205082 -420.818723) (xy 314.220435 -420.871011)
			(xy 314.22819 -420.924952) (xy 314.22819 -420.979448) (xy 314.228189 -420.979452) (xy 315.665846 -420.979452)
			(xy 315.665846 -420.924948) (xy 315.673602 -420.870999) (xy 315.688957 -420.818702) (xy 315.711597 -420.769123)
			(xy 315.741063 -420.723271) (xy 315.776754 -420.682078) (xy 315.817943 -420.646383) (xy 315.863793 -420.616914)
			(xy 315.91337 -420.594269) (xy 315.965665 -420.578909) (xy 316.019614 -420.571148) (xy 316.046866 -420.57066)
			(xy 316.910466 -420.57066) (xy 316.937718 -420.571185) (xy 316.991668 -420.578937) (xy 317.043966 -420.594289)
			(xy 317.093546 -420.616928) (xy 317.1394 -420.646392) (xy 317.180593 -420.682083) (xy 317.216287 -420.723273)
			(xy 317.245756 -420.769124) (xy 317.268399 -420.818702) (xy 317.283755 -420.870999) (xy 317.291513 -420.924948)
			(xy 317.291513 -420.979452) (xy 317.291513 -420.979455) (xy 318.729023 -420.979455) (xy 318.729023 -420.924945)
			(xy 318.736781 -420.870989) (xy 318.752138 -420.818686) (xy 318.774783 -420.769101) (xy 318.804254 -420.723244)
			(xy 318.839952 -420.682047) (xy 318.881149 -420.646351) (xy 318.927006 -420.61688) (xy 318.976591 -420.594236)
			(xy 319.028894 -420.578879) (xy 319.082851 -420.571123) (xy 319.110106 -420.57066) (xy 319.973706 -420.57066)
			(xy 320.000955 -420.571211) (xy 320.054897 -420.578967) (xy 320.107187 -420.594321) (xy 320.156759 -420.616961)
			(xy 320.202605 -420.646425) (xy 320.243791 -420.682113) (xy 320.279479 -420.7233) (xy 320.308942 -420.769146)
			(xy 320.331581 -420.818719) (xy 320.346934 -420.871009) (xy 320.35469 -420.924951) (xy 320.35469 -420.979449)
			(xy 320.354689 -420.979457) (xy 321.792223 -420.979457) (xy 321.792223 -420.924943) (xy 321.799982 -420.870983)
			(xy 321.815342 -420.818677) (xy 321.837989 -420.76909) (xy 321.867464 -420.723231) (xy 321.903166 -420.682033)
			(xy 321.944367 -420.646337) (xy 321.99023 -420.616867) (xy 322.03982 -420.594225) (xy 322.092128 -420.578872)
			(xy 322.146089 -420.57112) (xy 322.173346 -420.57066) (xy 323.036946 -420.57066) (xy 323.064193 -420.571213)
			(xy 323.118131 -420.578975) (xy 323.170416 -420.594332) (xy 323.219983 -420.616974) (xy 323.265824 -420.646439)
			(xy 323.307005 -420.682128) (xy 323.342688 -420.723313) (xy 323.372148 -420.769157) (xy 323.394784 -420.818727)
			(xy 323.410135 -420.871014) (xy 323.41789 -420.924953) (xy 323.41789 -420.979447) (xy 323.417889 -420.979453)
			(xy 324.855546 -420.979453) (xy 324.855546 -420.924947) (xy 324.863303 -420.870996) (xy 324.878658 -420.818698)
			(xy 324.9013 -420.769118) (xy 324.930768 -420.723264) (xy 324.966461 -420.682071) (xy 325.007653 -420.646376)
			(xy 325.053505 -420.616907) (xy 325.103085 -420.594263) (xy 325.155382 -420.578906) (xy 325.209333 -420.571147)
			(xy 325.236586 -420.57066) (xy 326.100186 -420.57066) (xy 326.127437 -420.571186) (xy 326.181385 -420.578941)
			(xy 326.23368 -420.594295) (xy 326.283258 -420.616934) (xy 326.329109 -420.646399) (xy 326.3703 -420.68209)
			(xy 326.405992 -420.72328) (xy 326.435459 -420.76913) (xy 326.458101 -420.818707) (xy 326.473456 -420.871001)
			(xy 326.481213 -420.924949) (xy 326.481213 -420.979451) (xy 326.481212 -420.979456) (xy 327.918723 -420.979456)
			(xy 327.918723 -420.924944) (xy 327.926481 -420.870986) (xy 327.94184 -420.818681) (xy 327.964486 -420.769095)
			(xy 327.993959 -420.723237) (xy 328.029659 -420.68204) (xy 328.070858 -420.646344) (xy 328.116718 -420.616874)
			(xy 328.166306 -420.594231) (xy 328.218611 -420.578876) (xy 328.27257 -420.571121) (xy 328.299826 -420.57066)
			(xy 329.163426 -420.57066) (xy 329.190674 -420.571212) (xy 329.244614 -420.578971) (xy 329.296901 -420.594327)
			(xy 329.346471 -420.616968) (xy 329.392314 -420.646432) (xy 329.433498 -420.682121) (xy 329.469184 -420.723307)
			(xy 329.498645 -420.769152) (xy 329.521282 -420.818723) (xy 329.536635 -420.871011) (xy 329.54439 -420.924952)
			(xy 329.54439 -420.979448) (xy 329.544389 -420.979452) (xy 330.982046 -420.979452) (xy 330.982046 -420.924948)
			(xy 330.989802 -420.870999) (xy 331.005157 -420.818702) (xy 331.027797 -420.769123) (xy 331.057263 -420.723271)
			(xy 331.092954 -420.682078) (xy 331.134143 -420.646383) (xy 331.179993 -420.616914) (xy 331.22957 -420.594269)
			(xy 331.281865 -420.578909) (xy 331.335814 -420.571148) (xy 331.363066 -420.57066) (xy 332.226666 -420.57066)
			(xy 332.253918 -420.571185) (xy 332.307868 -420.578937) (xy 332.360166 -420.594289) (xy 332.409746 -420.616928)
			(xy 332.4556 -420.646392) (xy 332.496793 -420.682083) (xy 332.532487 -420.723273) (xy 332.561956 -420.769124)
			(xy 332.584599 -420.818702) (xy 332.599955 -420.870999) (xy 332.607713 -420.924948) (xy 332.607713 -420.979452)
			(xy 332.607713 -420.979455) (xy 334.045223 -420.979455) (xy 334.045223 -420.924945) (xy 334.052981 -420.870989)
			(xy 334.068338 -420.818686) (xy 334.090983 -420.769101) (xy 334.120454 -420.723244) (xy 334.156152 -420.682047)
			(xy 334.197349 -420.646351) (xy 334.243206 -420.61688) (xy 334.292791 -420.594236) (xy 334.345094 -420.578879)
			(xy 334.399051 -420.571123) (xy 334.426306 -420.57066) (xy 335.289906 -420.57066) (xy 335.317155 -420.571211)
			(xy 335.371097 -420.578967) (xy 335.423387 -420.594321) (xy 335.472959 -420.616961) (xy 335.518805 -420.646425)
			(xy 335.559991 -420.682113) (xy 335.595679 -420.7233) (xy 335.625142 -420.769146) (xy 335.647781 -420.818719)
			(xy 335.663134 -420.871009) (xy 335.67089 -420.924951) (xy 335.67089 -420.979449) (xy 335.670889 -420.979457)
			(xy 337.108423 -420.979457) (xy 337.108423 -420.924943) (xy 337.116182 -420.870983) (xy 337.131542 -420.818677)
			(xy 337.154189 -420.76909) (xy 337.183664 -420.723231) (xy 337.219366 -420.682033) (xy 337.260567 -420.646337)
			(xy 337.30643 -420.616867) (xy 337.35602 -420.594225) (xy 337.408328 -420.578872) (xy 337.462289 -420.57112)
			(xy 337.489546 -420.57066) (xy 338.353146 -420.57066) (xy 338.380393 -420.571213) (xy 338.434331 -420.578975)
			(xy 338.486616 -420.594332) (xy 338.536183 -420.616974) (xy 338.582024 -420.646439) (xy 338.623205 -420.682128)
			(xy 338.658888 -420.723313) (xy 338.688348 -420.769157) (xy 338.710984 -420.818727) (xy 338.726335 -420.871014)
			(xy 338.73409 -420.924953) (xy 338.73409 -420.979447) (xy 338.734089 -420.979453) (xy 340.171746 -420.979453)
			(xy 340.171746 -420.924947) (xy 340.179503 -420.870996) (xy 340.194858 -420.818698) (xy 340.2175 -420.769118)
			(xy 340.246968 -420.723264) (xy 340.282661 -420.682071) (xy 340.323853 -420.646376) (xy 340.369705 -420.616907)
			(xy 340.419285 -420.594263) (xy 340.471582 -420.578906) (xy 340.525533 -420.571147) (xy 340.552786 -420.57066)
			(xy 341.416386 -420.57066) (xy 341.443637 -420.571186) (xy 341.497585 -420.578941) (xy 341.54988 -420.594295)
			(xy 341.599458 -420.616934) (xy 341.645309 -420.646399) (xy 341.6865 -420.68209) (xy 341.722192 -420.72328)
			(xy 341.751659 -420.76913) (xy 341.774301 -420.818707) (xy 341.789656 -420.871001) (xy 341.797413 -420.924949)
			(xy 341.797413 -420.979451) (xy 341.797412 -420.979456) (xy 343.234923 -420.979456) (xy 343.234923 -420.924944)
			(xy 343.242681 -420.870986) (xy 343.25804 -420.818681) (xy 343.280686 -420.769095) (xy 343.310159 -420.723237)
			(xy 343.345859 -420.68204) (xy 343.387058 -420.646344) (xy 343.432918 -420.616874) (xy 343.482506 -420.594231)
			(xy 343.534811 -420.578876) (xy 343.58877 -420.571121) (xy 343.616026 -420.57066) (xy 344.479626 -420.57066)
			(xy 344.506874 -420.571212) (xy 344.560814 -420.578971) (xy 344.613101 -420.594327) (xy 344.662671 -420.616968)
			(xy 344.708514 -420.646432) (xy 344.749698 -420.682121) (xy 344.785384 -420.723307) (xy 344.814845 -420.769152)
			(xy 344.837482 -420.818723) (xy 344.852835 -420.871011) (xy 344.86059 -420.924952) (xy 344.86059 -420.979448)
			(xy 344.860589 -420.979452) (xy 346.298246 -420.979452) (xy 346.298246 -420.924948) (xy 346.306002 -420.870999)
			(xy 346.321357 -420.818702) (xy 346.343997 -420.769123) (xy 346.373463 -420.723271) (xy 346.409154 -420.682078)
			(xy 346.450343 -420.646383) (xy 346.496193 -420.616914) (xy 346.54577 -420.594269) (xy 346.598065 -420.578909)
			(xy 346.652014 -420.571148) (xy 346.679266 -420.57066) (xy 347.542866 -420.57066) (xy 347.570118 -420.571185)
			(xy 347.624068 -420.578937) (xy 347.676366 -420.594289) (xy 347.725946 -420.616928) (xy 347.7718 -420.646392)
			(xy 347.812993 -420.682083) (xy 347.848687 -420.723273) (xy 347.878156 -420.769124) (xy 347.900799 -420.818702)
			(xy 347.916155 -420.870999) (xy 347.923913 -420.924948) (xy 347.923913 -420.979452) (xy 347.923913 -420.979455)
			(xy 349.361423 -420.979455) (xy 349.361423 -420.924945) (xy 349.369181 -420.870989) (xy 349.384538 -420.818686)
			(xy 349.407183 -420.769101) (xy 349.436654 -420.723244) (xy 349.472352 -420.682047) (xy 349.513549 -420.646351)
			(xy 349.559406 -420.61688) (xy 349.608991 -420.594236) (xy 349.661294 -420.578879) (xy 349.715251 -420.571123)
			(xy 349.742506 -420.57066) (xy 350.606106 -420.57066) (xy 350.633355 -420.571211) (xy 350.687297 -420.578967)
			(xy 350.739587 -420.594321) (xy 350.789159 -420.616961) (xy 350.835005 -420.646425) (xy 350.876191 -420.682113)
			(xy 350.911879 -420.7233) (xy 350.941342 -420.769146) (xy 350.963981 -420.818719) (xy 350.979334 -420.871009)
			(xy 350.98709 -420.924951) (xy 350.98709 -420.979449) (xy 350.979334 -421.033391) (xy 350.963981 -421.085681)
			(xy 350.941342 -421.135254) (xy 350.911879 -421.1811) (xy 350.876191 -421.222287) (xy 350.835005 -421.257975)
			(xy 350.789159 -421.287439) (xy 350.739587 -421.310079) (xy 350.687297 -421.325433) (xy 350.633355 -421.333189)
			(xy 350.606106 -421.333676) (xy 349.742506 -421.333676) (xy 349.715251 -421.333277) (xy 349.661294 -421.325521)
			(xy 349.608991 -421.310164) (xy 349.559406 -421.28752) (xy 349.513549 -421.258049) (xy 349.472352 -421.222353)
			(xy 349.436654 -421.181156) (xy 349.407183 -421.135299) (xy 349.384538 -421.085714) (xy 349.369181 -421.033411)
			(xy 349.361423 -420.979455) (xy 347.923913 -420.979455) (xy 347.916155 -421.033402) (xy 347.900799 -421.085698)
			(xy 347.878156 -421.135276) (xy 347.848687 -421.181127) (xy 347.812993 -421.222317) (xy 347.7718 -421.258008)
			(xy 347.725946 -421.287472) (xy 347.676366 -421.310111) (xy 347.624068 -421.325463) (xy 347.570118 -421.333215)
			(xy 347.542866 -421.333676) (xy 346.679266 -421.333676) (xy 346.652014 -421.333252) (xy 346.598065 -421.325491)
			(xy 346.54577 -421.310131) (xy 346.496193 -421.287486) (xy 346.450343 -421.258017) (xy 346.409154 -421.222322)
			(xy 346.373463 -421.181129) (xy 346.343997 -421.135277) (xy 346.321357 -421.085698) (xy 346.306002 -421.033401)
			(xy 346.298246 -420.979452) (xy 344.860589 -420.979452) (xy 344.852835 -421.033389) (xy 344.837482 -421.085677)
			(xy 344.814845 -421.135248) (xy 344.785384 -421.181093) (xy 344.749698 -421.222279) (xy 344.708514 -421.257968)
			(xy 344.662671 -421.287432) (xy 344.613101 -421.310073) (xy 344.560814 -421.325429) (xy 344.506874 -421.333188)
			(xy 344.479626 -421.333676) (xy 343.616026 -421.333676) (xy 343.58877 -421.333279) (xy 343.534811 -421.325524)
			(xy 343.482506 -421.310169) (xy 343.432918 -421.287526) (xy 343.387058 -421.258056) (xy 343.345859 -421.22236)
			(xy 343.310159 -421.181163) (xy 343.280686 -421.135305) (xy 343.25804 -421.085719) (xy 343.242681 -421.033414)
			(xy 343.234923 -420.979456) (xy 341.797412 -420.979456) (xy 341.789656 -421.033399) (xy 341.774301 -421.085693)
			(xy 341.751659 -421.13527) (xy 341.722192 -421.18112) (xy 341.6865 -421.22231) (xy 341.645309 -421.258001)
			(xy 341.599458 -421.287466) (xy 341.54988 -421.310105) (xy 341.497585 -421.325459) (xy 341.443637 -421.333214)
			(xy 341.416386 -421.333676) (xy 340.552786 -421.333676) (xy 340.525533 -421.333253) (xy 340.471582 -421.325494)
			(xy 340.419285 -421.310137) (xy 340.369705 -421.287493) (xy 340.323853 -421.258024) (xy 340.282661 -421.222329)
			(xy 340.246968 -421.181136) (xy 340.2175 -421.135282) (xy 340.194858 -421.085702) (xy 340.179503 -421.033404)
			(xy 340.171746 -420.979453) (xy 338.734089 -420.979453) (xy 338.726335 -421.033386) (xy 338.710984 -421.085673)
			(xy 338.688348 -421.135243) (xy 338.658888 -421.181087) (xy 338.623205 -421.222272) (xy 338.582024 -421.257961)
			(xy 338.536183 -421.287426) (xy 338.486616 -421.310068) (xy 338.434331 -421.325425) (xy 338.380393 -421.333187)
			(xy 338.353146 -421.333676) (xy 337.489546 -421.333676) (xy 337.462289 -421.33328) (xy 337.408328 -421.325528)
			(xy 337.35602 -421.310175) (xy 337.30643 -421.287533) (xy 337.260567 -421.258063) (xy 337.219366 -421.222367)
			(xy 337.183664 -421.181169) (xy 337.154189 -421.13531) (xy 337.131542 -421.085723) (xy 337.116182 -421.033417)
			(xy 337.108423 -420.979457) (xy 335.670889 -420.979457) (xy 335.663134 -421.033391) (xy 335.647781 -421.085681)
			(xy 335.625142 -421.135254) (xy 335.595679 -421.1811) (xy 335.559991 -421.222287) (xy 335.518805 -421.257975)
			(xy 335.472959 -421.287439) (xy 335.423387 -421.310079) (xy 335.371097 -421.325433) (xy 335.317155 -421.333189)
			(xy 335.289906 -421.333676) (xy 334.426306 -421.333676) (xy 334.399051 -421.333277) (xy 334.345094 -421.325521)
			(xy 334.292791 -421.310164) (xy 334.243206 -421.28752) (xy 334.197349 -421.258049) (xy 334.156152 -421.222353)
			(xy 334.120454 -421.181156) (xy 334.090983 -421.135299) (xy 334.068338 -421.085714) (xy 334.052981 -421.033411)
			(xy 334.045223 -420.979455) (xy 332.607713 -420.979455) (xy 332.599955 -421.033402) (xy 332.584599 -421.085698)
			(xy 332.561956 -421.135276) (xy 332.532487 -421.181127) (xy 332.496793 -421.222317) (xy 332.4556 -421.258008)
			(xy 332.409746 -421.287472) (xy 332.360166 -421.310111) (xy 332.307868 -421.325463) (xy 332.253918 -421.333215)
			(xy 332.226666 -421.333676) (xy 331.363066 -421.333676) (xy 331.335814 -421.333252) (xy 331.281865 -421.325491)
			(xy 331.22957 -421.310131) (xy 331.179993 -421.287486) (xy 331.134143 -421.258017) (xy 331.092954 -421.222322)
			(xy 331.057263 -421.181129) (xy 331.027797 -421.135277) (xy 331.005157 -421.085698) (xy 330.989802 -421.033401)
			(xy 330.982046 -420.979452) (xy 329.544389 -420.979452) (xy 329.536635 -421.033389) (xy 329.521282 -421.085677)
			(xy 329.498645 -421.135248) (xy 329.469184 -421.181093) (xy 329.433498 -421.222279) (xy 329.392314 -421.257968)
			(xy 329.346471 -421.287432) (xy 329.296901 -421.310073) (xy 329.244614 -421.325429) (xy 329.190674 -421.333188)
			(xy 329.163426 -421.333676) (xy 328.299826 -421.333676) (xy 328.27257 -421.333279) (xy 328.218611 -421.325524)
			(xy 328.166306 -421.310169) (xy 328.116718 -421.287526) (xy 328.070858 -421.258056) (xy 328.029659 -421.22236)
			(xy 327.993959 -421.181163) (xy 327.964486 -421.135305) (xy 327.94184 -421.085719) (xy 327.926481 -421.033414)
			(xy 327.918723 -420.979456) (xy 326.481212 -420.979456) (xy 326.473456 -421.033399) (xy 326.458101 -421.085693)
			(xy 326.435459 -421.13527) (xy 326.405992 -421.18112) (xy 326.3703 -421.22231) (xy 326.329109 -421.258001)
			(xy 326.283258 -421.287466) (xy 326.23368 -421.310105) (xy 326.181385 -421.325459) (xy 326.127437 -421.333214)
			(xy 326.100186 -421.333676) (xy 325.236586 -421.333676) (xy 325.209333 -421.333253) (xy 325.155382 -421.325494)
			(xy 325.103085 -421.310137) (xy 325.053505 -421.287493) (xy 325.007653 -421.258024) (xy 324.966461 -421.222329)
			(xy 324.930768 -421.181136) (xy 324.9013 -421.135282) (xy 324.878658 -421.085702) (xy 324.863303 -421.033404)
			(xy 324.855546 -420.979453) (xy 323.417889 -420.979453) (xy 323.410135 -421.033386) (xy 323.394784 -421.085673)
			(xy 323.372148 -421.135243) (xy 323.342688 -421.181087) (xy 323.307005 -421.222272) (xy 323.265824 -421.257961)
			(xy 323.219983 -421.287426) (xy 323.170416 -421.310068) (xy 323.118131 -421.325425) (xy 323.064193 -421.333187)
			(xy 323.036946 -421.333676) (xy 322.173346 -421.333676) (xy 322.146089 -421.33328) (xy 322.092128 -421.325528)
			(xy 322.03982 -421.310175) (xy 321.99023 -421.287533) (xy 321.944367 -421.258063) (xy 321.903166 -421.222367)
			(xy 321.867464 -421.181169) (xy 321.837989 -421.13531) (xy 321.815342 -421.085723) (xy 321.799982 -421.033417)
			(xy 321.792223 -420.979457) (xy 320.354689 -420.979457) (xy 320.346934 -421.033391) (xy 320.331581 -421.085681)
			(xy 320.308942 -421.135254) (xy 320.279479 -421.1811) (xy 320.243791 -421.222287) (xy 320.202605 -421.257975)
			(xy 320.156759 -421.287439) (xy 320.107187 -421.310079) (xy 320.054897 -421.325433) (xy 320.000955 -421.333189)
			(xy 319.973706 -421.333676) (xy 319.110106 -421.333676) (xy 319.082851 -421.333277) (xy 319.028894 -421.325521)
			(xy 318.976591 -421.310164) (xy 318.927006 -421.28752) (xy 318.881149 -421.258049) (xy 318.839952 -421.222353)
			(xy 318.804254 -421.181156) (xy 318.774783 -421.135299) (xy 318.752138 -421.085714) (xy 318.736781 -421.033411)
			(xy 318.729023 -420.979455) (xy 317.291513 -420.979455) (xy 317.283755 -421.033402) (xy 317.268399 -421.085698)
			(xy 317.245756 -421.135276) (xy 317.216287 -421.181127) (xy 317.180593 -421.222317) (xy 317.1394 -421.258008)
			(xy 317.093546 -421.287472) (xy 317.043966 -421.310111) (xy 316.991668 -421.325463) (xy 316.937718 -421.333215)
			(xy 316.910466 -421.333676) (xy 316.046866 -421.333676) (xy 316.019614 -421.333252) (xy 315.965665 -421.325491)
			(xy 315.91337 -421.310131) (xy 315.863793 -421.287486) (xy 315.817943 -421.258017) (xy 315.776754 -421.222322)
			(xy 315.741063 -421.181129) (xy 315.711597 -421.135277) (xy 315.688957 -421.085698) (xy 315.673602 -421.033401)
			(xy 315.665846 -420.979452) (xy 314.228189 -420.979452) (xy 314.220435 -421.033389) (xy 314.205082 -421.085677)
			(xy 314.182445 -421.135248) (xy 314.152984 -421.181093) (xy 314.117298 -421.222279) (xy 314.076114 -421.257968)
			(xy 314.030271 -421.287432) (xy 313.980701 -421.310073) (xy 313.928414 -421.325429) (xy 313.874474 -421.333188)
			(xy 313.847226 -421.333676) (xy 312.983626 -421.333676) (xy 312.95637 -421.333279) (xy 312.902411 -421.325524)
			(xy 312.850106 -421.310169) (xy 312.800518 -421.287526) (xy 312.754658 -421.258056) (xy 312.713459 -421.22236)
			(xy 312.677759 -421.181163) (xy 312.648286 -421.135305) (xy 312.62564 -421.085719) (xy 312.610281 -421.033414)
			(xy 312.602523 -420.979456) (xy 311.165012 -420.979456) (xy 311.157256 -421.033399) (xy 311.141901 -421.085693)
			(xy 311.119259 -421.13527) (xy 311.089792 -421.18112) (xy 311.0541 -421.22231) (xy 311.012909 -421.258001)
			(xy 310.967058 -421.287466) (xy 310.91748 -421.310105) (xy 310.865185 -421.325459) (xy 310.811237 -421.333214)
			(xy 310.783986 -421.333676) (xy 309.920386 -421.333676) (xy 309.893133 -421.333253) (xy 309.839182 -421.325494)
			(xy 309.786885 -421.310137) (xy 309.737305 -421.287493) (xy 309.691453 -421.258024) (xy 309.650261 -421.222329)
			(xy 309.614568 -421.181136) (xy 309.5851 -421.135282) (xy 309.562458 -421.085702) (xy 309.547103 -421.033404)
			(xy 309.539346 -420.979453) (xy 308.101689 -420.979453) (xy 308.093935 -421.033386) (xy 308.078584 -421.085673)
			(xy 308.055948 -421.135243) (xy 308.026488 -421.181087) (xy 307.990805 -421.222272) (xy 307.949624 -421.257961)
			(xy 307.903783 -421.287426) (xy 307.854216 -421.310068) (xy 307.801931 -421.325425) (xy 307.747993 -421.333187)
			(xy 307.720746 -421.333676) (xy 306.857146 -421.333676) (xy 306.829889 -421.33328) (xy 306.775928 -421.325528)
			(xy 306.72362 -421.310175) (xy 306.67403 -421.287533) (xy 306.628167 -421.258063) (xy 306.586966 -421.222367)
			(xy 306.551264 -421.181169) (xy 306.521789 -421.13531) (xy 306.499142 -421.085723) (xy 306.483782 -421.033417)
			(xy 306.476023 -420.979457) (xy 305.038489 -420.979457) (xy 305.030734 -421.033391) (xy 305.015381 -421.085681)
			(xy 304.992742 -421.135254) (xy 304.963279 -421.1811) (xy 304.927591 -421.222287) (xy 304.886405 -421.257975)
			(xy 304.840559 -421.287439) (xy 304.790987 -421.310079) (xy 304.738697 -421.325433) (xy 304.684755 -421.333189)
			(xy 304.657506 -421.333676) (xy 303.793906 -421.333676) (xy 303.766651 -421.333277) (xy 303.712694 -421.325521)
			(xy 303.660391 -421.310164) (xy 303.610806 -421.28752) (xy 303.564949 -421.258049) (xy 303.523752 -421.222353)
			(xy 303.488054 -421.181156) (xy 303.458583 -421.135299) (xy 303.435938 -421.085714) (xy 303.420581 -421.033411)
			(xy 303.412823 -420.979455) (xy 231.647383 -420.979455) (xy 230.329486 -422.297352) (xy 230.322673 -422.304773)
			(xy 230.314938 -422.323356) (xy 230.3145 -422.33342) (xy 230.3145 -422.354375) (xy 285.567772 -422.354375)
			(xy 285.567772 -422.299825) (xy 285.575535 -422.245831) (xy 285.590905 -422.193491) (xy 285.613567 -422.143872)
			(xy 285.64306 -422.097983) (xy 285.678784 -422.056759) (xy 285.720012 -422.021038) (xy 285.765903 -421.991549)
			(xy 285.815525 -421.968892) (xy 285.867866 -421.953528) (xy 285.921861 -421.945769) (xy 285.949136 -421.945308)
			(xy 286.812736 -421.945308) (xy 286.840002 -421.945857) (xy 286.893977 -421.953622) (xy 286.946298 -421.968989)
			(xy 286.9959 -421.991646) (xy 287.041773 -422.02113) (xy 287.082983 -422.056843) (xy 287.118691 -422.098056)
			(xy 287.148172 -422.143932) (xy 287.170823 -422.193536) (xy 287.186186 -422.245858) (xy 287.193946 -422.299834)
			(xy 287.193946 -422.354366) (xy 287.186186 -422.408342) (xy 287.170823 -422.460664) (xy 287.148172 -422.510268)
			(xy 287.118691 -422.556144) (xy 287.082983 -422.597357) (xy 287.041773 -422.63307) (xy 286.9959 -422.662554)
			(xy 286.946298 -422.685211) (xy 286.893977 -422.700578) (xy 286.840002 -422.708343) (xy 286.812736 -422.708832)
			(xy 285.949136 -422.708832) (xy 285.921861 -422.708431) (xy 285.867866 -422.700672) (xy 285.815525 -422.685308)
			(xy 285.765903 -422.662651) (xy 285.720012 -422.633162) (xy 285.678784 -422.597441) (xy 285.64306 -422.556217)
			(xy 285.613567 -422.510328) (xy 285.590905 -422.460709) (xy 285.575535 -422.408369) (xy 285.567772 -422.354375)
			(xy 230.3145 -422.354375) (xy 230.3145 -424.80464) (xy 357.679233 -424.80464) (xy 357.679233 -424.6755)
			(xy 357.687183 -424.546605) (xy 357.703053 -424.418445) (xy 357.726782 -424.291504) (xy 357.758281 -424.166265)
			(xy 357.79743 -424.043202) (xy 357.844081 -423.922783) (xy 357.898056 -423.805464) (xy 357.959151 -423.69169)
			(xy 358.027134 -423.581893) (xy 358.101748 -423.47649) (xy 358.182709 -423.37588) (xy 358.269709 -423.280445)
			(xy 358.36242 -423.190546) (xy 358.46049 -423.106525) (xy 358.563545 -423.028701) (xy 358.671196 -422.957369)
			(xy 358.783035 -422.892799) (xy 358.898636 -422.835237) (xy 359.017561 -422.7849) (xy 359.13936 -422.74198)
			(xy 359.26357 -422.706639) (xy 359.389719 -422.679012) (xy 359.517331 -422.659203) (xy 359.64592 -422.647287)
			(xy 359.774998 -422.643311) (xy 359.904076 -422.647287) (xy 360.032665 -422.659203) (xy 360.160277 -422.679012)
			(xy 360.222212 -422.692576) (xy 365.310928 -422.692576) (xy 365.310928 -415.898584) (xy 365.3113 -415.888356)
			(xy 365.319137 -415.86946) (xy 365.33361 -415.855003) (xy 365.352515 -415.847188) (xy 365.362744 -415.846768)
			(xy 370.261388 -415.846768) (xy 370.271593 -415.847291) (xy 370.290451 -415.855097) (xy 370.304887 -415.869525)
			(xy 370.312703 -415.888379) (xy 370.313204 -415.898584) (xy 370.313204 -418.439456) (xy 372.044623 -418.439456)
			(xy 372.044623 -418.384944) (xy 372.052381 -418.330986) (xy 372.06774 -418.278682) (xy 372.090386 -418.229097)
			(xy 372.119858 -418.183238) (xy 372.155557 -418.142042) (xy 372.196756 -418.106345) (xy 372.242616 -418.076875)
			(xy 372.292203 -418.054232) (xy 372.344508 -418.038877) (xy 372.398466 -418.031121) (xy 372.425722 -418.03066)
			(xy 373.289322 -418.03066) (xy 373.31657 -418.031212) (xy 373.370511 -418.03897) (xy 373.422798 -418.054326)
			(xy 373.472369 -418.076966) (xy 373.518212 -418.106431) (xy 373.559396 -418.142119) (xy 373.595083 -418.183305)
			(xy 373.624544 -418.229151) (xy 373.647182 -418.278722) (xy 373.662535 -418.331011) (xy 373.67029 -418.384952)
			(xy 373.67029 -418.439448) (xy 373.670289 -418.439452) (xy 375.107946 -418.439452) (xy 375.107946 -418.384948)
			(xy 375.115702 -418.330999) (xy 375.131056 -418.278703) (xy 375.153697 -418.229124) (xy 375.183162 -418.183272)
			(xy 375.218852 -418.142079) (xy 375.260041 -418.106385) (xy 375.305891 -418.076915) (xy 375.355468 -418.05427)
			(xy 375.407762 -418.03891) (xy 375.46171 -418.031148) (xy 375.488962 -418.03066) (xy 376.352562 -418.03066)
			(xy 376.379814 -418.031185) (xy 376.433765 -418.038937) (xy 376.486063 -418.054288) (xy 376.535644 -418.076926)
			(xy 376.581498 -418.106391) (xy 376.622691 -418.142082) (xy 376.658386 -418.183272) (xy 376.687855 -418.229123)
			(xy 376.710499 -418.278701) (xy 376.725855 -418.330998) (xy 376.733613 -418.384948) (xy 376.733613 -418.439452)
			(xy 376.733613 -418.439455) (xy 378.171123 -418.439455) (xy 378.171123 -418.384945) (xy 378.178881 -418.330989)
			(xy 378.194238 -418.278687) (xy 378.216883 -418.229102) (xy 378.246353 -418.183245) (xy 378.28205 -418.142049)
			(xy 378.323247 -418.106352) (xy 378.369104 -418.076882) (xy 378.418688 -418.054237) (xy 378.470991 -418.03888)
			(xy 378.524947 -418.031123) (xy 378.552202 -418.03066) (xy 379.415802 -418.03066) (xy 379.443051 -418.03121)
			(xy 379.496994 -418.038966) (xy 379.549284 -418.05432) (xy 379.598857 -418.07696) (xy 379.644703 -418.106424)
			(xy 379.685889 -418.142112) (xy 379.721578 -418.183299) (xy 379.751041 -418.229145) (xy 379.77368 -418.278718)
			(xy 379.789034 -418.331008) (xy 379.79679 -418.384951) (xy 379.79679 -418.439449) (xy 379.796789 -418.439457)
			(xy 381.234323 -418.439457) (xy 381.234323 -418.384943) (xy 381.242082 -418.330984) (xy 381.257441 -418.278678)
			(xy 381.280089 -418.229091) (xy 381.309563 -418.183232) (xy 381.345264 -418.142035) (xy 381.386466 -418.106338)
			(xy 381.432328 -418.076869) (xy 381.481917 -418.054227) (xy 381.534225 -418.038873) (xy 381.588185 -418.03112)
			(xy 381.615442 -418.03066) (xy 382.479042 -418.03066) (xy 382.506289 -418.031213) (xy 382.560228 -418.038974)
			(xy 382.612513 -418.054331) (xy 382.662081 -418.076973) (xy 382.707922 -418.106438) (xy 382.749103 -418.142126)
			(xy 382.784787 -418.183312) (xy 382.814247 -418.229156) (xy 382.836883 -418.278727) (xy 382.852235 -418.331014)
			(xy 382.85999 -418.384953) (xy 382.85999 -418.439447) (xy 382.859989 -418.439453) (xy 384.297646 -418.439453)
			(xy 384.297646 -418.384947) (xy 384.305403 -418.330997) (xy 384.320758 -418.278699) (xy 384.3434 -418.229119)
			(xy 384.372867 -418.183265) (xy 384.408559 -418.142072) (xy 384.449751 -418.106378) (xy 384.495603 -418.076908)
			(xy 384.545182 -418.054264) (xy 384.597479 -418.038906) (xy 384.651429 -418.031147) (xy 384.678682 -418.03066)
			(xy 385.542282 -418.03066) (xy 385.569533 -418.031186) (xy 385.623482 -418.03894) (xy 385.675777 -418.054293)
			(xy 385.725356 -418.076933) (xy 385.771207 -418.106398) (xy 385.812399 -418.142089) (xy 385.848091 -418.183278)
			(xy 385.877558 -418.229129) (xy 385.9002 -418.278706) (xy 385.915556 -418.331001) (xy 385.923313 -418.384949)
			(xy 385.923313 -418.439451) (xy 385.923312 -418.439456) (xy 387.360823 -418.439456) (xy 387.360823 -418.384944)
			(xy 387.368581 -418.330986) (xy 387.38394 -418.278682) (xy 387.406586 -418.229097) (xy 387.436058 -418.183238)
			(xy 387.471757 -418.142042) (xy 387.512956 -418.106345) (xy 387.558816 -418.076875) (xy 387.608403 -418.054232)
			(xy 387.660708 -418.038877) (xy 387.714666 -418.031121) (xy 387.741922 -418.03066) (xy 388.605522 -418.03066)
			(xy 388.63277 -418.031212) (xy 388.686711 -418.03897) (xy 388.738998 -418.054326) (xy 388.788569 -418.076966)
			(xy 388.834412 -418.106431) (xy 388.875596 -418.142119) (xy 388.911283 -418.183305) (xy 388.940744 -418.229151)
			(xy 388.963382 -418.278722) (xy 388.978735 -418.331011) (xy 388.98649 -418.384952) (xy 388.98649 -418.439448)
			(xy 388.986489 -418.439452) (xy 390.424146 -418.439452) (xy 390.424146 -418.384948) (xy 390.431902 -418.330999)
			(xy 390.447256 -418.278703) (xy 390.469897 -418.229124) (xy 390.499362 -418.183272) (xy 390.535052 -418.142079)
			(xy 390.576241 -418.106385) (xy 390.622091 -418.076915) (xy 390.671668 -418.05427) (xy 390.723962 -418.03891)
			(xy 390.77791 -418.031148) (xy 390.805162 -418.03066) (xy 391.668762 -418.03066) (xy 391.696014 -418.031185)
			(xy 391.749965 -418.038937) (xy 391.802263 -418.054288) (xy 391.851844 -418.076926) (xy 391.897698 -418.106391)
			(xy 391.938891 -418.142082) (xy 391.974586 -418.183272) (xy 392.004055 -418.229123) (xy 392.026699 -418.278701)
			(xy 392.042055 -418.330998) (xy 392.049813 -418.384948) (xy 392.049813 -418.439452) (xy 392.049813 -418.439455)
			(xy 393.487323 -418.439455) (xy 393.487323 -418.384945) (xy 393.495081 -418.330989) (xy 393.510438 -418.278687)
			(xy 393.533083 -418.229102) (xy 393.562553 -418.183245) (xy 393.59825 -418.142049) (xy 393.639447 -418.106352)
			(xy 393.685304 -418.076882) (xy 393.734888 -418.054237) (xy 393.787191 -418.03888) (xy 393.841147 -418.031123)
			(xy 393.868402 -418.03066) (xy 394.732002 -418.03066) (xy 394.759251 -418.03121) (xy 394.813194 -418.038966)
			(xy 394.865484 -418.05432) (xy 394.915057 -418.07696) (xy 394.960903 -418.106424) (xy 395.002089 -418.142112)
			(xy 395.037778 -418.183299) (xy 395.067241 -418.229145) (xy 395.08988 -418.278718) (xy 395.105234 -418.331008)
			(xy 395.11299 -418.384951) (xy 395.11299 -418.439449) (xy 395.112989 -418.439457) (xy 396.550523 -418.439457)
			(xy 396.550523 -418.384943) (xy 396.558282 -418.330984) (xy 396.573641 -418.278678) (xy 396.596289 -418.229091)
			(xy 396.625763 -418.183232) (xy 396.661464 -418.142035) (xy 396.702666 -418.106338) (xy 396.748528 -418.076869)
			(xy 396.798117 -418.054227) (xy 396.850425 -418.038873) (xy 396.904385 -418.03112) (xy 396.931642 -418.03066)
			(xy 397.795242 -418.03066) (xy 397.822489 -418.031213) (xy 397.876428 -418.038974) (xy 397.928713 -418.054331)
			(xy 397.978281 -418.076973) (xy 398.024122 -418.106438) (xy 398.065303 -418.142126) (xy 398.100987 -418.183312)
			(xy 398.130447 -418.229156) (xy 398.153083 -418.278727) (xy 398.168435 -418.331014) (xy 398.17619 -418.384953)
			(xy 398.17619 -418.439447) (xy 398.176189 -418.439453) (xy 399.613846 -418.439453) (xy 399.613846 -418.384947)
			(xy 399.621603 -418.330997) (xy 399.636958 -418.278699) (xy 399.6596 -418.229119) (xy 399.689067 -418.183265)
			(xy 399.724759 -418.142072) (xy 399.765951 -418.106378) (xy 399.811803 -418.076908) (xy 399.861382 -418.054264)
			(xy 399.913679 -418.038906) (xy 399.967629 -418.031147) (xy 399.994882 -418.03066) (xy 400.858482 -418.03066)
			(xy 400.885733 -418.031186) (xy 400.939682 -418.03894) (xy 400.991977 -418.054293) (xy 401.041556 -418.076933)
			(xy 401.087407 -418.106398) (xy 401.128599 -418.142089) (xy 401.164291 -418.183278) (xy 401.193758 -418.229129)
			(xy 401.2164 -418.278706) (xy 401.231756 -418.331001) (xy 401.239513 -418.384949) (xy 401.239513 -418.439451)
			(xy 401.239512 -418.439456) (xy 402.677023 -418.439456) (xy 402.677023 -418.384944) (xy 402.684781 -418.330986)
			(xy 402.70014 -418.278682) (xy 402.722786 -418.229097) (xy 402.752258 -418.183238) (xy 402.787957 -418.142042)
			(xy 402.829156 -418.106345) (xy 402.875016 -418.076875) (xy 402.924603 -418.054232) (xy 402.976908 -418.038877)
			(xy 403.030866 -418.031121) (xy 403.058122 -418.03066) (xy 403.921722 -418.03066) (xy 403.94897 -418.031212)
			(xy 404.002911 -418.03897) (xy 404.055198 -418.054326) (xy 404.104769 -418.076966) (xy 404.150612 -418.106431)
			(xy 404.191796 -418.142119) (xy 404.227483 -418.183305) (xy 404.256944 -418.229151) (xy 404.279582 -418.278722)
			(xy 404.294935 -418.331011) (xy 404.30269 -418.384952) (xy 404.30269 -418.439448) (xy 404.302689 -418.439452)
			(xy 405.740346 -418.439452) (xy 405.740346 -418.384948) (xy 405.748102 -418.330999) (xy 405.763456 -418.278703)
			(xy 405.786097 -418.229124) (xy 405.815562 -418.183272) (xy 405.851252 -418.142079) (xy 405.892441 -418.106385)
			(xy 405.938291 -418.076915) (xy 405.987868 -418.05427) (xy 406.040162 -418.03891) (xy 406.09411 -418.031148)
			(xy 406.121362 -418.03066) (xy 406.984962 -418.03066) (xy 407.012214 -418.031185) (xy 407.066165 -418.038937)
			(xy 407.118463 -418.054288) (xy 407.168044 -418.076926) (xy 407.213898 -418.106391) (xy 407.255091 -418.142082)
			(xy 407.290786 -418.183272) (xy 407.320255 -418.229123) (xy 407.342899 -418.278701) (xy 407.358255 -418.330998)
			(xy 407.366013 -418.384948) (xy 407.366013 -418.439452) (xy 407.366013 -418.439455) (xy 408.803523 -418.439455)
			(xy 408.803523 -418.384945) (xy 408.811281 -418.330989) (xy 408.826638 -418.278687) (xy 408.849283 -418.229102)
			(xy 408.878753 -418.183245) (xy 408.91445 -418.142049) (xy 408.955647 -418.106352) (xy 409.001504 -418.076882)
			(xy 409.051088 -418.054237) (xy 409.103391 -418.03888) (xy 409.157347 -418.031123) (xy 409.184602 -418.03066)
			(xy 410.048202 -418.03066) (xy 410.075451 -418.03121) (xy 410.129394 -418.038966) (xy 410.181684 -418.05432)
			(xy 410.231257 -418.07696) (xy 410.277103 -418.106424) (xy 410.318289 -418.142112) (xy 410.353978 -418.183299)
			(xy 410.383441 -418.229145) (xy 410.40608 -418.278718) (xy 410.421434 -418.331008) (xy 410.42919 -418.384951)
			(xy 410.42919 -418.439449) (xy 410.429189 -418.439457) (xy 411.866723 -418.439457) (xy 411.866723 -418.384943)
			(xy 411.874482 -418.330984) (xy 411.889841 -418.278678) (xy 411.912489 -418.229091) (xy 411.941963 -418.183232)
			(xy 411.977664 -418.142035) (xy 412.018866 -418.106338) (xy 412.064728 -418.076869) (xy 412.114317 -418.054227)
			(xy 412.166625 -418.038873) (xy 412.220585 -418.03112) (xy 412.247842 -418.03066) (xy 413.111442 -418.03066)
			(xy 413.138689 -418.031213) (xy 413.192628 -418.038974) (xy 413.244913 -418.054331) (xy 413.294481 -418.076973)
			(xy 413.340322 -418.106438) (xy 413.381503 -418.142126) (xy 413.417187 -418.183312) (xy 413.446647 -418.229156)
			(xy 413.469283 -418.278727) (xy 413.484635 -418.331014) (xy 413.49239 -418.384953) (xy 413.49239 -418.439447)
			(xy 413.492389 -418.439453) (xy 414.930046 -418.439453) (xy 414.930046 -418.384947) (xy 414.937803 -418.330997)
			(xy 414.953158 -418.278699) (xy 414.9758 -418.229119) (xy 415.005267 -418.183265) (xy 415.040959 -418.142072)
			(xy 415.082151 -418.106378) (xy 415.128003 -418.076908) (xy 415.177582 -418.054264) (xy 415.229879 -418.038906)
			(xy 415.283829 -418.031147) (xy 415.311082 -418.03066) (xy 416.174682 -418.03066) (xy 416.201933 -418.031186)
			(xy 416.255882 -418.03894) (xy 416.308177 -418.054293) (xy 416.357756 -418.076933) (xy 416.403607 -418.106398)
			(xy 416.444799 -418.142089) (xy 416.480491 -418.183278) (xy 416.509958 -418.229129) (xy 416.5326 -418.278706)
			(xy 416.547956 -418.331001) (xy 416.555713 -418.384949) (xy 416.555713 -418.439451) (xy 416.555712 -418.439456)
			(xy 417.993223 -418.439456) (xy 417.993223 -418.384944) (xy 418.000981 -418.330986) (xy 418.01634 -418.278682)
			(xy 418.038986 -418.229097) (xy 418.068458 -418.183238) (xy 418.104157 -418.142042) (xy 418.145356 -418.106345)
			(xy 418.191216 -418.076875) (xy 418.240803 -418.054232) (xy 418.293108 -418.038877) (xy 418.347066 -418.031121)
			(xy 418.374322 -418.03066) (xy 419.237922 -418.03066) (xy 419.26517 -418.031212) (xy 419.319111 -418.03897)
			(xy 419.371398 -418.054326) (xy 419.420969 -418.076966) (xy 419.466812 -418.106431) (xy 419.507996 -418.142119)
			(xy 419.543683 -418.183305) (xy 419.573144 -418.229151) (xy 419.595782 -418.278722) (xy 419.611135 -418.331011)
			(xy 419.61889 -418.384952) (xy 419.61889 -418.439448) (xy 419.611135 -418.493389) (xy 419.595782 -418.545678)
			(xy 419.573144 -418.595249) (xy 419.543683 -418.641095) (xy 419.507996 -418.682281) (xy 419.466812 -418.717969)
			(xy 419.420969 -418.747434) (xy 419.371398 -418.770074) (xy 419.319111 -418.78543) (xy 419.26517 -418.793188)
			(xy 419.237922 -418.793676) (xy 418.374322 -418.793676) (xy 418.347066 -418.793279) (xy 418.293108 -418.785523)
			(xy 418.240803 -418.770168) (xy 418.191216 -418.747525) (xy 418.145356 -418.718055) (xy 418.104157 -418.682358)
			(xy 418.068458 -418.641162) (xy 418.038986 -418.595303) (xy 418.01634 -418.545718) (xy 418.000981 -418.493414)
			(xy 417.993223 -418.439456) (xy 416.555712 -418.439456) (xy 416.547956 -418.493399) (xy 416.5326 -418.545694)
			(xy 416.509958 -418.595271) (xy 416.480491 -418.641122) (xy 416.444799 -418.682311) (xy 416.403607 -418.718002)
			(xy 416.357756 -418.747467) (xy 416.308177 -418.770107) (xy 416.255882 -418.78546) (xy 416.201933 -418.793214)
			(xy 416.174682 -418.793676) (xy 415.311082 -418.793676) (xy 415.283829 -418.793253) (xy 415.229879 -418.785494)
			(xy 415.177582 -418.770136) (xy 415.128003 -418.747492) (xy 415.082151 -418.718022) (xy 415.040959 -418.682328)
			(xy 415.005267 -418.641135) (xy 414.9758 -418.595281) (xy 414.953158 -418.545701) (xy 414.937803 -418.493403)
			(xy 414.930046 -418.439453) (xy 413.492389 -418.439453) (xy 413.484635 -418.493386) (xy 413.469283 -418.545673)
			(xy 413.446647 -418.595244) (xy 413.417187 -418.641088) (xy 413.381503 -418.682274) (xy 413.340322 -418.717962)
			(xy 413.294481 -418.747427) (xy 413.244913 -418.770069) (xy 413.192628 -418.785426) (xy 413.138689 -418.793187)
			(xy 413.111442 -418.793676) (xy 412.247842 -418.793676) (xy 412.220585 -418.79328) (xy 412.166625 -418.785527)
			(xy 412.114317 -418.770173) (xy 412.064728 -418.747531) (xy 412.018866 -418.718062) (xy 411.977664 -418.682365)
			(xy 411.941963 -418.641168) (xy 411.912489 -418.595309) (xy 411.889841 -418.545722) (xy 411.874482 -418.493416)
			(xy 411.866723 -418.439457) (xy 410.429189 -418.439457) (xy 410.421434 -418.493392) (xy 410.40608 -418.545682)
			(xy 410.383441 -418.595255) (xy 410.353978 -418.641101) (xy 410.318289 -418.682288) (xy 410.277103 -418.717976)
			(xy 410.231257 -418.74744) (xy 410.181684 -418.77008) (xy 410.129394 -418.785434) (xy 410.075451 -418.79319)
			(xy 410.048202 -418.793676) (xy 409.184602 -418.793676) (xy 409.157347 -418.793277) (xy 409.103391 -418.78552)
			(xy 409.051088 -418.770163) (xy 409.001504 -418.747518) (xy 408.955647 -418.718048) (xy 408.91445 -418.682351)
			(xy 408.878753 -418.641155) (xy 408.849283 -418.595298) (xy 408.826638 -418.545713) (xy 408.811281 -418.493411)
			(xy 408.803523 -418.439455) (xy 407.366013 -418.439455) (xy 407.358255 -418.493402) (xy 407.342899 -418.545699)
			(xy 407.320255 -418.595277) (xy 407.290786 -418.641128) (xy 407.255091 -418.682318) (xy 407.213898 -418.718009)
			(xy 407.168044 -418.747474) (xy 407.118463 -418.770112) (xy 407.066165 -418.785463) (xy 407.012214 -418.793215)
			(xy 406.984962 -418.793676) (xy 406.121362 -418.793676) (xy 406.09411 -418.793252) (xy 406.040162 -418.78549)
			(xy 405.987868 -418.77013) (xy 405.938291 -418.747485) (xy 405.892441 -418.718015) (xy 405.851252 -418.682321)
			(xy 405.815562 -418.641128) (xy 405.786097 -418.595276) (xy 405.763456 -418.545697) (xy 405.748102 -418.493401)
			(xy 405.740346 -418.439452) (xy 404.302689 -418.439452) (xy 404.294935 -418.493389) (xy 404.279582 -418.545678)
			(xy 404.256944 -418.595249) (xy 404.227483 -418.641095) (xy 404.191796 -418.682281) (xy 404.150612 -418.717969)
			(xy 404.104769 -418.747434) (xy 404.055198 -418.770074) (xy 404.002911 -418.78543) (xy 403.94897 -418.793188)
			(xy 403.921722 -418.793676) (xy 403.058122 -418.793676) (xy 403.030866 -418.793279) (xy 402.976908 -418.785523)
			(xy 402.924603 -418.770168) (xy 402.875016 -418.747525) (xy 402.829156 -418.718055) (xy 402.787957 -418.682358)
			(xy 402.752258 -418.641162) (xy 402.722786 -418.595303) (xy 402.70014 -418.545718) (xy 402.684781 -418.493414)
			(xy 402.677023 -418.439456) (xy 401.239512 -418.439456) (xy 401.231756 -418.493399) (xy 401.2164 -418.545694)
			(xy 401.193758 -418.595271) (xy 401.164291 -418.641122) (xy 401.128599 -418.682311) (xy 401.087407 -418.718002)
			(xy 401.041556 -418.747467) (xy 400.991977 -418.770107) (xy 400.939682 -418.78546) (xy 400.885733 -418.793214)
			(xy 400.858482 -418.793676) (xy 399.994882 -418.793676) (xy 399.967629 -418.793253) (xy 399.913679 -418.785494)
			(xy 399.861382 -418.770136) (xy 399.811803 -418.747492) (xy 399.765951 -418.718022) (xy 399.724759 -418.682328)
			(xy 399.689067 -418.641135) (xy 399.6596 -418.595281) (xy 399.636958 -418.545701) (xy 399.621603 -418.493403)
			(xy 399.613846 -418.439453) (xy 398.176189 -418.439453) (xy 398.168435 -418.493386) (xy 398.153083 -418.545673)
			(xy 398.130447 -418.595244) (xy 398.100987 -418.641088) (xy 398.065303 -418.682274) (xy 398.024122 -418.717962)
			(xy 397.978281 -418.747427) (xy 397.928713 -418.770069) (xy 397.876428 -418.785426) (xy 397.822489 -418.793187)
			(xy 397.795242 -418.793676) (xy 396.931642 -418.793676) (xy 396.904385 -418.79328) (xy 396.850425 -418.785527)
			(xy 396.798117 -418.770173) (xy 396.748528 -418.747531) (xy 396.702666 -418.718062) (xy 396.661464 -418.682365)
			(xy 396.625763 -418.641168) (xy 396.596289 -418.595309) (xy 396.573641 -418.545722) (xy 396.558282 -418.493416)
			(xy 396.550523 -418.439457) (xy 395.112989 -418.439457) (xy 395.105234 -418.493392) (xy 395.08988 -418.545682)
			(xy 395.067241 -418.595255) (xy 395.037778 -418.641101) (xy 395.002089 -418.682288) (xy 394.960903 -418.717976)
			(xy 394.915057 -418.74744) (xy 394.865484 -418.77008) (xy 394.813194 -418.785434) (xy 394.759251 -418.79319)
			(xy 394.732002 -418.793676) (xy 393.868402 -418.793676) (xy 393.841147 -418.793277) (xy 393.787191 -418.78552)
			(xy 393.734888 -418.770163) (xy 393.685304 -418.747518) (xy 393.639447 -418.718048) (xy 393.59825 -418.682351)
			(xy 393.562553 -418.641155) (xy 393.533083 -418.595298) (xy 393.510438 -418.545713) (xy 393.495081 -418.493411)
			(xy 393.487323 -418.439455) (xy 392.049813 -418.439455) (xy 392.042055 -418.493402) (xy 392.026699 -418.545699)
			(xy 392.004055 -418.595277) (xy 391.974586 -418.641128) (xy 391.938891 -418.682318) (xy 391.897698 -418.718009)
			(xy 391.851844 -418.747474) (xy 391.802263 -418.770112) (xy 391.749965 -418.785463) (xy 391.696014 -418.793215)
			(xy 391.668762 -418.793676) (xy 390.805162 -418.793676) (xy 390.77791 -418.793252) (xy 390.723962 -418.78549)
			(xy 390.671668 -418.77013) (xy 390.622091 -418.747485) (xy 390.576241 -418.718015) (xy 390.535052 -418.682321)
			(xy 390.499362 -418.641128) (xy 390.469897 -418.595276) (xy 390.447256 -418.545697) (xy 390.431902 -418.493401)
			(xy 390.424146 -418.439452) (xy 388.986489 -418.439452) (xy 388.978735 -418.493389) (xy 388.963382 -418.545678)
			(xy 388.940744 -418.595249) (xy 388.911283 -418.641095) (xy 388.875596 -418.682281) (xy 388.834412 -418.717969)
			(xy 388.788569 -418.747434) (xy 388.738998 -418.770074) (xy 388.686711 -418.78543) (xy 388.63277 -418.793188)
			(xy 388.605522 -418.793676) (xy 387.741922 -418.793676) (xy 387.714666 -418.793279) (xy 387.660708 -418.785523)
			(xy 387.608403 -418.770168) (xy 387.558816 -418.747525) (xy 387.512956 -418.718055) (xy 387.471757 -418.682358)
			(xy 387.436058 -418.641162) (xy 387.406586 -418.595303) (xy 387.38394 -418.545718) (xy 387.368581 -418.493414)
			(xy 387.360823 -418.439456) (xy 385.923312 -418.439456) (xy 385.915556 -418.493399) (xy 385.9002 -418.545694)
			(xy 385.877558 -418.595271) (xy 385.848091 -418.641122) (xy 385.812399 -418.682311) (xy 385.771207 -418.718002)
			(xy 385.725356 -418.747467) (xy 385.675777 -418.770107) (xy 385.623482 -418.78546) (xy 385.569533 -418.793214)
			(xy 385.542282 -418.793676) (xy 384.678682 -418.793676) (xy 384.651429 -418.793253) (xy 384.597479 -418.785494)
			(xy 384.545182 -418.770136) (xy 384.495603 -418.747492) (xy 384.449751 -418.718022) (xy 384.408559 -418.682328)
			(xy 384.372867 -418.641135) (xy 384.3434 -418.595281) (xy 384.320758 -418.545701) (xy 384.305403 -418.493403)
			(xy 384.297646 -418.439453) (xy 382.859989 -418.439453) (xy 382.852235 -418.493386) (xy 382.836883 -418.545673)
			(xy 382.814247 -418.595244) (xy 382.784787 -418.641088) (xy 382.749103 -418.682274) (xy 382.707922 -418.717962)
			(xy 382.662081 -418.747427) (xy 382.612513 -418.770069) (xy 382.560228 -418.785426) (xy 382.506289 -418.793187)
			(xy 382.479042 -418.793676) (xy 381.615442 -418.793676) (xy 381.588185 -418.79328) (xy 381.534225 -418.785527)
			(xy 381.481917 -418.770173) (xy 381.432328 -418.747531) (xy 381.386466 -418.718062) (xy 381.345264 -418.682365)
			(xy 381.309563 -418.641168) (xy 381.280089 -418.595309) (xy 381.257441 -418.545722) (xy 381.242082 -418.493416)
			(xy 381.234323 -418.439457) (xy 379.796789 -418.439457) (xy 379.789034 -418.493392) (xy 379.77368 -418.545682)
			(xy 379.751041 -418.595255) (xy 379.721578 -418.641101) (xy 379.685889 -418.682288) (xy 379.644703 -418.717976)
			(xy 379.598857 -418.74744) (xy 379.549284 -418.77008) (xy 379.496994 -418.785434) (xy 379.443051 -418.79319)
			(xy 379.415802 -418.793676) (xy 378.552202 -418.793676) (xy 378.524947 -418.793277) (xy 378.470991 -418.78552)
			(xy 378.418688 -418.770163) (xy 378.369104 -418.747518) (xy 378.323247 -418.718048) (xy 378.28205 -418.682351)
			(xy 378.246353 -418.641155) (xy 378.216883 -418.595298) (xy 378.194238 -418.545713) (xy 378.178881 -418.493411)
			(xy 378.171123 -418.439455) (xy 376.733613 -418.439455) (xy 376.725855 -418.493402) (xy 376.710499 -418.545699)
			(xy 376.687855 -418.595277) (xy 376.658386 -418.641128) (xy 376.622691 -418.682318) (xy 376.581498 -418.718009)
			(xy 376.535644 -418.747474) (xy 376.486063 -418.770112) (xy 376.433765 -418.785463) (xy 376.379814 -418.793215)
			(xy 376.352562 -418.793676) (xy 375.488962 -418.793676) (xy 375.46171 -418.793252) (xy 375.407762 -418.78549)
			(xy 375.355468 -418.77013) (xy 375.305891 -418.747485) (xy 375.260041 -418.718015) (xy 375.218852 -418.682321)
			(xy 375.183162 -418.641128) (xy 375.153697 -418.595276) (xy 375.131056 -418.545697) (xy 375.115702 -418.493401)
			(xy 375.107946 -418.439452) (xy 373.670289 -418.439452) (xy 373.662535 -418.493389) (xy 373.647182 -418.545678)
			(xy 373.624544 -418.595249) (xy 373.595083 -418.641095) (xy 373.559396 -418.682281) (xy 373.518212 -418.717969)
			(xy 373.472369 -418.747434) (xy 373.422798 -418.770074) (xy 373.370511 -418.78543) (xy 373.31657 -418.793188)
			(xy 373.289322 -418.793676) (xy 372.425722 -418.793676) (xy 372.398466 -418.793279) (xy 372.344508 -418.785523)
			(xy 372.292203 -418.770168) (xy 372.242616 -418.747525) (xy 372.196756 -418.718055) (xy 372.155557 -418.682358)
			(xy 372.119858 -418.641162) (xy 372.090386 -418.595303) (xy 372.06774 -418.545718) (xy 372.052381 -418.493414)
			(xy 372.044623 -418.439456) (xy 370.313204 -418.439456) (xy 370.313204 -420.739316) (xy 370.16182 -420.739316)
			(xy 370.150859 -420.741086) (xy 370.131853 -420.752509) (xy 370.11943 -420.770877) (xy 370.117116 -420.781734)
			(xy 370.117116 -420.979455) (xy 370.513023 -420.979455) (xy 370.513023 -420.924945) (xy 370.520781 -420.870989)
			(xy 370.536138 -420.818687) (xy 370.558783 -420.769102) (xy 370.588253 -420.723245) (xy 370.62395 -420.682049)
			(xy 370.665147 -420.646352) (xy 370.711004 -420.616882) (xy 370.760588 -420.594237) (xy 370.812891 -420.57888)
			(xy 370.866847 -420.571123) (xy 370.894102 -420.57066) (xy 371.757702 -420.57066) (xy 371.784951 -420.57121)
			(xy 371.838894 -420.578966) (xy 371.891184 -420.59432) (xy 371.940757 -420.61696) (xy 371.986603 -420.646424)
			(xy 372.027789 -420.682112) (xy 372.063478 -420.723299) (xy 372.092941 -420.769145) (xy 372.11558 -420.818718)
			(xy 372.130934 -420.871008) (xy 372.13869 -420.924951) (xy 372.13869 -420.979449) (xy 372.138689 -420.979457)
			(xy 373.576223 -420.979457) (xy 373.576223 -420.924943) (xy 373.583982 -420.870984) (xy 373.599341 -420.818678)
			(xy 373.621989 -420.769091) (xy 373.651463 -420.723232) (xy 373.687164 -420.682035) (xy 373.728366 -420.646338)
			(xy 373.774228 -420.616869) (xy 373.823817 -420.594227) (xy 373.876125 -420.578873) (xy 373.930085 -420.57112)
			(xy 373.957342 -420.57066) (xy 374.820942 -420.57066) (xy 374.848189 -420.571213) (xy 374.902128 -420.578974)
			(xy 374.954413 -420.594331) (xy 375.003981 -420.616973) (xy 375.049822 -420.646438) (xy 375.091003 -420.682126)
			(xy 375.126687 -420.723312) (xy 375.156147 -420.769156) (xy 375.178783 -420.818727) (xy 375.194135 -420.871014)
			(xy 375.20189 -420.924953) (xy 375.20189 -420.979447) (xy 375.201889 -420.979453) (xy 376.639546 -420.979453)
			(xy 376.639546 -420.924947) (xy 376.647303 -420.870997) (xy 376.662658 -420.818699) (xy 376.6853 -420.769119)
			(xy 376.714767 -420.723265) (xy 376.750459 -420.682072) (xy 376.791651 -420.646378) (xy 376.837503 -420.616908)
			(xy 376.887082 -420.594264) (xy 376.939379 -420.578906) (xy 376.993329 -420.571147) (xy 377.020582 -420.57066)
			(xy 377.884182 -420.57066) (xy 377.911433 -420.571186) (xy 377.965382 -420.57894) (xy 378.017677 -420.594293)
			(xy 378.067256 -420.616933) (xy 378.113107 -420.646398) (xy 378.154299 -420.682089) (xy 378.189991 -420.723278)
			(xy 378.219458 -420.769129) (xy 378.2421 -420.818706) (xy 378.257456 -420.871001) (xy 378.265213 -420.924949)
			(xy 378.265213 -420.979451) (xy 378.265212 -420.979456) (xy 379.702723 -420.979456) (xy 379.702723 -420.924944)
			(xy 379.710481 -420.870986) (xy 379.72584 -420.818682) (xy 379.748486 -420.769097) (xy 379.777958 -420.723238)
			(xy 379.813657 -420.682042) (xy 379.854856 -420.646345) (xy 379.900716 -420.616875) (xy 379.950303 -420.594232)
			(xy 380.002608 -420.578877) (xy 380.056566 -420.571121) (xy 380.083822 -420.57066) (xy 380.947422 -420.57066)
			(xy 380.97467 -420.571212) (xy 381.028611 -420.57897) (xy 381.080898 -420.594326) (xy 381.130469 -420.616966)
			(xy 381.176312 -420.646431) (xy 381.217496 -420.682119) (xy 381.253183 -420.723305) (xy 381.282644 -420.769151)
			(xy 381.305282 -420.818722) (xy 381.320635 -420.871011) (xy 381.32839 -420.924952) (xy 381.32839 -420.979448)
			(xy 381.328389 -420.979452) (xy 382.766046 -420.979452) (xy 382.766046 -420.924948) (xy 382.773802 -420.870999)
			(xy 382.789156 -420.818703) (xy 382.811797 -420.769124) (xy 382.841262 -420.723272) (xy 382.876952 -420.682079)
			(xy 382.918141 -420.646385) (xy 382.963991 -420.616915) (xy 383.013568 -420.59427) (xy 383.065862 -420.57891)
			(xy 383.11981 -420.571148) (xy 383.147062 -420.57066) (xy 384.010662 -420.57066) (xy 384.037914 -420.571185)
			(xy 384.091865 -420.578937) (xy 384.144163 -420.594288) (xy 384.193744 -420.616926) (xy 384.239598 -420.646391)
			(xy 384.280791 -420.682082) (xy 384.316486 -420.723272) (xy 384.345955 -420.769123) (xy 384.368599 -420.818701)
			(xy 384.383955 -420.870998) (xy 384.391713 -420.924948) (xy 384.391713 -420.979452) (xy 384.391713 -420.979455)
			(xy 385.829223 -420.979455) (xy 385.829223 -420.924945) (xy 385.836981 -420.870989) (xy 385.852338 -420.818687)
			(xy 385.874983 -420.769102) (xy 385.904453 -420.723245) (xy 385.94015 -420.682049) (xy 385.981347 -420.646352)
			(xy 386.027204 -420.616882) (xy 386.076788 -420.594237) (xy 386.129091 -420.57888) (xy 386.183047 -420.571123)
			(xy 386.210302 -420.57066) (xy 387.073902 -420.57066) (xy 387.101151 -420.57121) (xy 387.155094 -420.578966)
			(xy 387.207384 -420.59432) (xy 387.256957 -420.61696) (xy 387.302803 -420.646424) (xy 387.343989 -420.682112)
			(xy 387.379678 -420.723299) (xy 387.409141 -420.769145) (xy 387.43178 -420.818718) (xy 387.447134 -420.871008)
			(xy 387.45489 -420.924951) (xy 387.45489 -420.979449) (xy 387.454889 -420.979457) (xy 388.892423 -420.979457)
			(xy 388.892423 -420.924943) (xy 388.900182 -420.870984) (xy 388.915541 -420.818678) (xy 388.938189 -420.769091)
			(xy 388.967663 -420.723232) (xy 389.003364 -420.682035) (xy 389.044566 -420.646338) (xy 389.090428 -420.616869)
			(xy 389.140017 -420.594227) (xy 389.192325 -420.578873) (xy 389.246285 -420.57112) (xy 389.273542 -420.57066)
			(xy 390.137142 -420.57066) (xy 390.164389 -420.571213) (xy 390.218328 -420.578974) (xy 390.270613 -420.594331)
			(xy 390.320181 -420.616973) (xy 390.366022 -420.646438) (xy 390.407203 -420.682126) (xy 390.442887 -420.723312)
			(xy 390.472347 -420.769156) (xy 390.494983 -420.818727) (xy 390.510335 -420.871014) (xy 390.51809 -420.924953)
			(xy 390.51809 -420.979447) (xy 390.518089 -420.979453) (xy 391.955746 -420.979453) (xy 391.955746 -420.924947)
			(xy 391.963503 -420.870997) (xy 391.978858 -420.818699) (xy 392.0015 -420.769119) (xy 392.030967 -420.723265)
			(xy 392.066659 -420.682072) (xy 392.107851 -420.646378) (xy 392.153703 -420.616908) (xy 392.203282 -420.594264)
			(xy 392.255579 -420.578906) (xy 392.309529 -420.571147) (xy 392.336782 -420.57066) (xy 393.200382 -420.57066)
			(xy 393.227633 -420.571186) (xy 393.281582 -420.57894) (xy 393.333877 -420.594293) (xy 393.383456 -420.616933)
			(xy 393.429307 -420.646398) (xy 393.470499 -420.682089) (xy 393.506191 -420.723278) (xy 393.535658 -420.769129)
			(xy 393.5583 -420.818706) (xy 393.573656 -420.871001) (xy 393.581413 -420.924949) (xy 393.581413 -420.979451)
			(xy 393.581412 -420.979456) (xy 395.018923 -420.979456) (xy 395.018923 -420.924944) (xy 395.026681 -420.870986)
			(xy 395.04204 -420.818682) (xy 395.064686 -420.769097) (xy 395.094158 -420.723238) (xy 395.129857 -420.682042)
			(xy 395.171056 -420.646345) (xy 395.216916 -420.616875) (xy 395.266503 -420.594232) (xy 395.318808 -420.578877)
			(xy 395.372766 -420.571121) (xy 395.400022 -420.57066) (xy 396.263622 -420.57066) (xy 396.29087 -420.571212)
			(xy 396.344811 -420.57897) (xy 396.397098 -420.594326) (xy 396.446669 -420.616966) (xy 396.492512 -420.646431)
			(xy 396.533696 -420.682119) (xy 396.569383 -420.723305) (xy 396.598844 -420.769151) (xy 396.621482 -420.818722)
			(xy 396.636835 -420.871011) (xy 396.64459 -420.924952) (xy 396.64459 -420.979448) (xy 396.644589 -420.979452)
			(xy 398.082246 -420.979452) (xy 398.082246 -420.924948) (xy 398.090002 -420.870999) (xy 398.105356 -420.818703)
			(xy 398.127997 -420.769124) (xy 398.157462 -420.723272) (xy 398.193152 -420.682079) (xy 398.234341 -420.646385)
			(xy 398.280191 -420.616915) (xy 398.329768 -420.59427) (xy 398.382062 -420.57891) (xy 398.43601 -420.571148)
			(xy 398.463262 -420.57066) (xy 399.326862 -420.57066) (xy 399.354114 -420.571185) (xy 399.408065 -420.578937)
			(xy 399.460363 -420.594288) (xy 399.509944 -420.616926) (xy 399.555798 -420.646391) (xy 399.596991 -420.682082)
			(xy 399.632686 -420.723272) (xy 399.662155 -420.769123) (xy 399.684799 -420.818701) (xy 399.700155 -420.870998)
			(xy 399.707913 -420.924948) (xy 399.707913 -420.979452) (xy 399.707913 -420.979455) (xy 401.145423 -420.979455)
			(xy 401.145423 -420.924945) (xy 401.153181 -420.870989) (xy 401.168538 -420.818687) (xy 401.191183 -420.769102)
			(xy 401.220653 -420.723245) (xy 401.25635 -420.682049) (xy 401.297547 -420.646352) (xy 401.343404 -420.616882)
			(xy 401.392988 -420.594237) (xy 401.445291 -420.57888) (xy 401.499247 -420.571123) (xy 401.526502 -420.57066)
			(xy 402.390102 -420.57066) (xy 402.417351 -420.57121) (xy 402.471294 -420.578966) (xy 402.523584 -420.59432)
			(xy 402.573157 -420.61696) (xy 402.619003 -420.646424) (xy 402.660189 -420.682112) (xy 402.695878 -420.723299)
			(xy 402.725341 -420.769145) (xy 402.74798 -420.818718) (xy 402.763334 -420.871008) (xy 402.77109 -420.924951)
			(xy 402.77109 -420.979449) (xy 402.771089 -420.979457) (xy 404.208623 -420.979457) (xy 404.208623 -420.924943)
			(xy 404.216382 -420.870984) (xy 404.231741 -420.818678) (xy 404.254389 -420.769091) (xy 404.283863 -420.723232)
			(xy 404.319564 -420.682035) (xy 404.360766 -420.646338) (xy 404.406628 -420.616869) (xy 404.456217 -420.594227)
			(xy 404.508525 -420.578873) (xy 404.562485 -420.57112) (xy 404.589742 -420.57066) (xy 405.453342 -420.57066)
			(xy 405.480589 -420.571213) (xy 405.534528 -420.578974) (xy 405.586813 -420.594331) (xy 405.636381 -420.616973)
			(xy 405.682222 -420.646438) (xy 405.723403 -420.682126) (xy 405.759087 -420.723312) (xy 405.788547 -420.769156)
			(xy 405.811183 -420.818727) (xy 405.826535 -420.871014) (xy 405.83429 -420.924953) (xy 405.83429 -420.979447)
			(xy 405.834289 -420.979453) (xy 407.271946 -420.979453) (xy 407.271946 -420.924947) (xy 407.279703 -420.870997)
			(xy 407.295058 -420.818699) (xy 407.3177 -420.769119) (xy 407.347167 -420.723265) (xy 407.382859 -420.682072)
			(xy 407.424051 -420.646378) (xy 407.469903 -420.616908) (xy 407.519482 -420.594264) (xy 407.571779 -420.578906)
			(xy 407.625729 -420.571147) (xy 407.652982 -420.57066) (xy 408.516582 -420.57066) (xy 408.543833 -420.571186)
			(xy 408.597782 -420.57894) (xy 408.650077 -420.594293) (xy 408.699656 -420.616933) (xy 408.745507 -420.646398)
			(xy 408.786699 -420.682089) (xy 408.822391 -420.723278) (xy 408.851858 -420.769129) (xy 408.8745 -420.818706)
			(xy 408.889856 -420.871001) (xy 408.897613 -420.924949) (xy 408.897613 -420.979451) (xy 408.897612 -420.979456)
			(xy 410.335123 -420.979456) (xy 410.335123 -420.924944) (xy 410.342881 -420.870986) (xy 410.35824 -420.818682)
			(xy 410.380886 -420.769097) (xy 410.410358 -420.723238) (xy 410.446057 -420.682042) (xy 410.487256 -420.646345)
			(xy 410.533116 -420.616875) (xy 410.582703 -420.594232) (xy 410.635008 -420.578877) (xy 410.688966 -420.571121)
			(xy 410.716222 -420.57066) (xy 411.579822 -420.57066) (xy 411.60707 -420.571212) (xy 411.661011 -420.57897)
			(xy 411.713298 -420.594326) (xy 411.762869 -420.616966) (xy 411.808712 -420.646431) (xy 411.849896 -420.682119)
			(xy 411.885583 -420.723305) (xy 411.915044 -420.769151) (xy 411.937682 -420.818722) (xy 411.953035 -420.871011)
			(xy 411.96079 -420.924952) (xy 411.96079 -420.979448) (xy 411.960789 -420.979452) (xy 413.398446 -420.979452)
			(xy 413.398446 -420.924948) (xy 413.406202 -420.870999) (xy 413.421556 -420.818703) (xy 413.444197 -420.769124)
			(xy 413.473662 -420.723272) (xy 413.509352 -420.682079) (xy 413.550541 -420.646385) (xy 413.596391 -420.616915)
			(xy 413.645968 -420.59427) (xy 413.698262 -420.57891) (xy 413.75221 -420.571148) (xy 413.779462 -420.57066)
			(xy 414.643062 -420.57066) (xy 414.670314 -420.571185) (xy 414.724265 -420.578937) (xy 414.776563 -420.594288)
			(xy 414.826144 -420.616926) (xy 414.871998 -420.646391) (xy 414.913191 -420.682082) (xy 414.948886 -420.723272)
			(xy 414.978355 -420.769123) (xy 415.000999 -420.818701) (xy 415.016355 -420.870998) (xy 415.024113 -420.924948)
			(xy 415.024113 -420.979452) (xy 415.024113 -420.979455) (xy 416.461623 -420.979455) (xy 416.461623 -420.924945)
			(xy 416.469381 -420.870989) (xy 416.484738 -420.818687) (xy 416.507383 -420.769102) (xy 416.536853 -420.723245)
			(xy 416.57255 -420.682049) (xy 416.613747 -420.646352) (xy 416.659604 -420.616882) (xy 416.709188 -420.594237)
			(xy 416.761491 -420.57888) (xy 416.815447 -420.571123) (xy 416.842702 -420.57066) (xy 417.706302 -420.57066)
			(xy 417.733551 -420.57121) (xy 417.787494 -420.578966) (xy 417.839784 -420.59432) (xy 417.889357 -420.61696)
			(xy 417.935203 -420.646424) (xy 417.976389 -420.682112) (xy 418.012078 -420.723299) (xy 418.041541 -420.769145)
			(xy 418.06418 -420.818718) (xy 418.079534 -420.871008) (xy 418.08729 -420.924951) (xy 418.08729 -420.979449)
			(xy 418.079534 -421.033392) (xy 418.06418 -421.085682) (xy 418.041541 -421.135255) (xy 418.012078 -421.181101)
			(xy 417.976389 -421.222288) (xy 417.935203 -421.257976) (xy 417.889357 -421.28744) (xy 417.839784 -421.31008)
			(xy 417.787494 -421.325434) (xy 417.733551 -421.33319) (xy 417.706302 -421.333676) (xy 416.842702 -421.333676)
			(xy 416.815447 -421.333277) (xy 416.761491 -421.32552) (xy 416.709188 -421.310163) (xy 416.659604 -421.287518)
			(xy 416.613747 -421.258048) (xy 416.57255 -421.222351) (xy 416.536853 -421.181155) (xy 416.507383 -421.135298)
			(xy 416.484738 -421.085713) (xy 416.469381 -421.033411) (xy 416.461623 -420.979455) (xy 415.024113 -420.979455)
			(xy 415.016355 -421.033402) (xy 415.000999 -421.085699) (xy 414.978355 -421.135277) (xy 414.948886 -421.181128)
			(xy 414.913191 -421.222318) (xy 414.871998 -421.258009) (xy 414.826144 -421.287474) (xy 414.776563 -421.310112)
			(xy 414.724265 -421.325463) (xy 414.670314 -421.333215) (xy 414.643062 -421.333676) (xy 413.779462 -421.333676)
			(xy 413.75221 -421.333252) (xy 413.698262 -421.32549) (xy 413.645968 -421.31013) (xy 413.596391 -421.287485)
			(xy 413.550541 -421.258015) (xy 413.509352 -421.222321) (xy 413.473662 -421.181128) (xy 413.444197 -421.135276)
			(xy 413.421556 -421.085697) (xy 413.406202 -421.033401) (xy 413.398446 -420.979452) (xy 411.960789 -420.979452)
			(xy 411.953035 -421.033389) (xy 411.937682 -421.085678) (xy 411.915044 -421.135249) (xy 411.885583 -421.181095)
			(xy 411.849896 -421.222281) (xy 411.808712 -421.257969) (xy 411.762869 -421.287434) (xy 411.713298 -421.310074)
			(xy 411.661011 -421.32543) (xy 411.60707 -421.333188) (xy 411.579822 -421.333676) (xy 410.716222 -421.333676)
			(xy 410.688966 -421.333279) (xy 410.635008 -421.325523) (xy 410.582703 -421.310168) (xy 410.533116 -421.287525)
			(xy 410.487256 -421.258055) (xy 410.446057 -421.222358) (xy 410.410358 -421.181162) (xy 410.380886 -421.135303)
			(xy 410.35824 -421.085718) (xy 410.342881 -421.033414) (xy 410.335123 -420.979456) (xy 408.897612 -420.979456)
			(xy 408.889856 -421.033399) (xy 408.8745 -421.085694) (xy 408.851858 -421.135271) (xy 408.822391 -421.181122)
			(xy 408.786699 -421.222311) (xy 408.745507 -421.258002) (xy 408.699656 -421.287467) (xy 408.650077 -421.310107)
			(xy 408.597782 -421.32546) (xy 408.543833 -421.333214) (xy 408.516582 -421.333676) (xy 407.652982 -421.333676)
			(xy 407.625729 -421.333253) (xy 407.571779 -421.325494) (xy 407.519482 -421.310136) (xy 407.469903 -421.287492)
			(xy 407.424051 -421.258022) (xy 407.382859 -421.222328) (xy 407.347167 -421.181135) (xy 407.3177 -421.135281)
			(xy 407.295058 -421.085701) (xy 407.279703 -421.033403) (xy 407.271946 -420.979453) (xy 405.834289 -420.979453)
			(xy 405.826535 -421.033386) (xy 405.811183 -421.085673) (xy 405.788547 -421.135244) (xy 405.759087 -421.181088)
			(xy 405.723403 -421.222274) (xy 405.682222 -421.257962) (xy 405.636381 -421.287427) (xy 405.586813 -421.310069)
			(xy 405.534528 -421.325426) (xy 405.480589 -421.333187) (xy 405.453342 -421.333676) (xy 404.589742 -421.333676)
			(xy 404.562485 -421.33328) (xy 404.508525 -421.325527) (xy 404.456217 -421.310173) (xy 404.406628 -421.287531)
			(xy 404.360766 -421.258062) (xy 404.319564 -421.222365) (xy 404.283863 -421.181168) (xy 404.254389 -421.135309)
			(xy 404.231741 -421.085722) (xy 404.216382 -421.033416) (xy 404.208623 -420.979457) (xy 402.771089 -420.979457)
			(xy 402.763334 -421.033392) (xy 402.74798 -421.085682) (xy 402.725341 -421.135255) (xy 402.695878 -421.181101)
			(xy 402.660189 -421.222288) (xy 402.619003 -421.257976) (xy 402.573157 -421.28744) (xy 402.523584 -421.31008)
			(xy 402.471294 -421.325434) (xy 402.417351 -421.33319) (xy 402.390102 -421.333676) (xy 401.526502 -421.333676)
			(xy 401.499247 -421.333277) (xy 401.445291 -421.32552) (xy 401.392988 -421.310163) (xy 401.343404 -421.287518)
			(xy 401.297547 -421.258048) (xy 401.25635 -421.222351) (xy 401.220653 -421.181155) (xy 401.191183 -421.135298)
			(xy 401.168538 -421.085713) (xy 401.153181 -421.033411) (xy 401.145423 -420.979455) (xy 399.707913 -420.979455)
			(xy 399.700155 -421.033402) (xy 399.684799 -421.085699) (xy 399.662155 -421.135277) (xy 399.632686 -421.181128)
			(xy 399.596991 -421.222318) (xy 399.555798 -421.258009) (xy 399.509944 -421.287474) (xy 399.460363 -421.310112)
			(xy 399.408065 -421.325463) (xy 399.354114 -421.333215) (xy 399.326862 -421.333676) (xy 398.463262 -421.333676)
			(xy 398.43601 -421.333252) (xy 398.382062 -421.32549) (xy 398.329768 -421.31013) (xy 398.280191 -421.287485)
			(xy 398.234341 -421.258015) (xy 398.193152 -421.222321) (xy 398.157462 -421.181128) (xy 398.127997 -421.135276)
			(xy 398.105356 -421.085697) (xy 398.090002 -421.033401) (xy 398.082246 -420.979452) (xy 396.644589 -420.979452)
			(xy 396.636835 -421.033389) (xy 396.621482 -421.085678) (xy 396.598844 -421.135249) (xy 396.569383 -421.181095)
			(xy 396.533696 -421.222281) (xy 396.492512 -421.257969) (xy 396.446669 -421.287434) (xy 396.397098 -421.310074)
			(xy 396.344811 -421.32543) (xy 396.29087 -421.333188) (xy 396.263622 -421.333676) (xy 395.400022 -421.333676)
			(xy 395.372766 -421.333279) (xy 395.318808 -421.325523) (xy 395.266503 -421.310168) (xy 395.216916 -421.287525)
			(xy 395.171056 -421.258055) (xy 395.129857 -421.222358) (xy 395.094158 -421.181162) (xy 395.064686 -421.135303)
			(xy 395.04204 -421.085718) (xy 395.026681 -421.033414) (xy 395.018923 -420.979456) (xy 393.581412 -420.979456)
			(xy 393.573656 -421.033399) (xy 393.5583 -421.085694) (xy 393.535658 -421.135271) (xy 393.506191 -421.181122)
			(xy 393.470499 -421.222311) (xy 393.429307 -421.258002) (xy 393.383456 -421.287467) (xy 393.333877 -421.310107)
			(xy 393.281582 -421.32546) (xy 393.227633 -421.333214) (xy 393.200382 -421.333676) (xy 392.336782 -421.333676)
			(xy 392.309529 -421.333253) (xy 392.255579 -421.325494) (xy 392.203282 -421.310136) (xy 392.153703 -421.287492)
			(xy 392.107851 -421.258022) (xy 392.066659 -421.222328) (xy 392.030967 -421.181135) (xy 392.0015 -421.135281)
			(xy 391.978858 -421.085701) (xy 391.963503 -421.033403) (xy 391.955746 -420.979453) (xy 390.518089 -420.979453)
			(xy 390.510335 -421.033386) (xy 390.494983 -421.085673) (xy 390.472347 -421.135244) (xy 390.442887 -421.181088)
			(xy 390.407203 -421.222274) (xy 390.366022 -421.257962) (xy 390.320181 -421.287427) (xy 390.270613 -421.310069)
			(xy 390.218328 -421.325426) (xy 390.164389 -421.333187) (xy 390.137142 -421.333676) (xy 389.273542 -421.333676)
			(xy 389.246285 -421.33328) (xy 389.192325 -421.325527) (xy 389.140017 -421.310173) (xy 389.090428 -421.287531)
			(xy 389.044566 -421.258062) (xy 389.003364 -421.222365) (xy 388.967663 -421.181168) (xy 388.938189 -421.135309)
			(xy 388.915541 -421.085722) (xy 388.900182 -421.033416) (xy 388.892423 -420.979457) (xy 387.454889 -420.979457)
			(xy 387.447134 -421.033392) (xy 387.43178 -421.085682) (xy 387.409141 -421.135255) (xy 387.379678 -421.181101)
			(xy 387.343989 -421.222288) (xy 387.302803 -421.257976) (xy 387.256957 -421.28744) (xy 387.207384 -421.31008)
			(xy 387.155094 -421.325434) (xy 387.101151 -421.33319) (xy 387.073902 -421.333676) (xy 386.210302 -421.333676)
			(xy 386.183047 -421.333277) (xy 386.129091 -421.32552) (xy 386.076788 -421.310163) (xy 386.027204 -421.287518)
			(xy 385.981347 -421.258048) (xy 385.94015 -421.222351) (xy 385.904453 -421.181155) (xy 385.874983 -421.135298)
			(xy 385.852338 -421.085713) (xy 385.836981 -421.033411) (xy 385.829223 -420.979455) (xy 384.391713 -420.979455)
			(xy 384.383955 -421.033402) (xy 384.368599 -421.085699) (xy 384.345955 -421.135277) (xy 384.316486 -421.181128)
			(xy 384.280791 -421.222318) (xy 384.239598 -421.258009) (xy 384.193744 -421.287474) (xy 384.144163 -421.310112)
			(xy 384.091865 -421.325463) (xy 384.037914 -421.333215) (xy 384.010662 -421.333676) (xy 383.147062 -421.333676)
			(xy 383.11981 -421.333252) (xy 383.065862 -421.32549) (xy 383.013568 -421.31013) (xy 382.963991 -421.287485)
			(xy 382.918141 -421.258015) (xy 382.876952 -421.222321) (xy 382.841262 -421.181128) (xy 382.811797 -421.135276)
			(xy 382.789156 -421.085697) (xy 382.773802 -421.033401) (xy 382.766046 -420.979452) (xy 381.328389 -420.979452)
			(xy 381.320635 -421.033389) (xy 381.305282 -421.085678) (xy 381.282644 -421.135249) (xy 381.253183 -421.181095)
			(xy 381.217496 -421.222281) (xy 381.176312 -421.257969) (xy 381.130469 -421.287434) (xy 381.080898 -421.310074)
			(xy 381.028611 -421.32543) (xy 380.97467 -421.333188) (xy 380.947422 -421.333676) (xy 380.083822 -421.333676)
			(xy 380.056566 -421.333279) (xy 380.002608 -421.325523) (xy 379.950303 -421.310168) (xy 379.900716 -421.287525)
			(xy 379.854856 -421.258055) (xy 379.813657 -421.222358) (xy 379.777958 -421.181162) (xy 379.748486 -421.135303)
			(xy 379.72584 -421.085718) (xy 379.710481 -421.033414) (xy 379.702723 -420.979456) (xy 378.265212 -420.979456)
			(xy 378.257456 -421.033399) (xy 378.2421 -421.085694) (xy 378.219458 -421.135271) (xy 378.189991 -421.181122)
			(xy 378.154299 -421.222311) (xy 378.113107 -421.258002) (xy 378.067256 -421.287467) (xy 378.017677 -421.310107)
			(xy 377.965382 -421.32546) (xy 377.911433 -421.333214) (xy 377.884182 -421.333676) (xy 377.020582 -421.333676)
			(xy 376.993329 -421.333253) (xy 376.939379 -421.325494) (xy 376.887082 -421.310136) (xy 376.837503 -421.287492)
			(xy 376.791651 -421.258022) (xy 376.750459 -421.222328) (xy 376.714767 -421.181135) (xy 376.6853 -421.135281)
			(xy 376.662658 -421.085701) (xy 376.647303 -421.033403) (xy 376.639546 -420.979453) (xy 375.201889 -420.979453)
			(xy 375.194135 -421.033386) (xy 375.178783 -421.085673) (xy 375.156147 -421.135244) (xy 375.126687 -421.181088)
			(xy 375.091003 -421.222274) (xy 375.049822 -421.257962) (xy 375.003981 -421.287427) (xy 374.954413 -421.310069)
			(xy 374.902128 -421.325426) (xy 374.848189 -421.333187) (xy 374.820942 -421.333676) (xy 373.957342 -421.333676)
			(xy 373.930085 -421.33328) (xy 373.876125 -421.325527) (xy 373.823817 -421.310173) (xy 373.774228 -421.287531)
			(xy 373.728366 -421.258062) (xy 373.687164 -421.222365) (xy 373.651463 -421.181168) (xy 373.621989 -421.135309)
			(xy 373.599341 -421.085722) (xy 373.583982 -421.033416) (xy 373.576223 -420.979457) (xy 372.138689 -420.979457)
			(xy 372.130934 -421.033392) (xy 372.11558 -421.085682) (xy 372.092941 -421.135255) (xy 372.063478 -421.181101)
			(xy 372.027789 -421.222288) (xy 371.986603 -421.257976) (xy 371.940757 -421.28744) (xy 371.891184 -421.31008)
			(xy 371.838894 -421.325434) (xy 371.784951 -421.33319) (xy 371.757702 -421.333676) (xy 370.894102 -421.333676)
			(xy 370.866847 -421.333277) (xy 370.812891 -421.32552) (xy 370.760588 -421.310163) (xy 370.711004 -421.287518)
			(xy 370.665147 -421.258048) (xy 370.62395 -421.222351) (xy 370.588253 -421.181155) (xy 370.558783 -421.135298)
			(xy 370.536138 -421.085713) (xy 370.520781 -421.033411) (xy 370.513023 -420.979455) (xy 370.117116 -420.979455)
			(xy 370.117116 -421.136826) (xy 370.119466 -421.147668) (xy 370.131899 -421.166013) (xy 370.150869 -421.17747)
			(xy 370.16182 -421.179244) (xy 370.313204 -421.179244) (xy 370.313204 -422.692576) (xy 370.312768 -422.702798)
			(xy 370.30495 -422.721687) (xy 370.290497 -422.736144) (xy 370.27161 -422.743966) (xy 370.261388 -422.744392)
			(xy 365.362744 -422.744392) (xy 365.352522 -422.743952) (xy 365.333631 -422.736138) (xy 365.319173 -422.721686)
			(xy 365.311352 -422.702798) (xy 365.310928 -422.692576) (xy 360.222212 -422.692576) (xy 360.286426 -422.706639)
			(xy 360.410636 -422.74198) (xy 360.532435 -422.7849) (xy 360.65136 -422.835237) (xy 360.766961 -422.892799)
			(xy 360.8788 -422.957369) (xy 360.986451 -423.028701) (xy 361.089506 -423.106525) (xy 361.187576 -423.190546)
			(xy 361.280287 -423.280445) (xy 361.367287 -423.37588) (xy 361.448248 -423.47649) (xy 361.505055 -423.556738)
			(xy 456.285335 -423.556738) (xy 456.285335 -423.427598) (xy 456.293285 -423.298703) (xy 456.309155 -423.170543)
			(xy 456.332884 -423.043602) (xy 456.364383 -422.918363) (xy 456.403532 -422.7953) (xy 456.450183 -422.674881)
			(xy 456.504158 -422.557562) (xy 456.565253 -422.443788) (xy 456.633236 -422.333991) (xy 456.70785 -422.228588)
			(xy 456.788811 -422.127978) (xy 456.875811 -422.032543) (xy 456.968522 -421.942644) (xy 457.066592 -421.858623)
			(xy 457.169647 -421.780799) (xy 457.277298 -421.709467) (xy 457.389137 -421.644897) (xy 457.504738 -421.587335)
			(xy 457.623663 -421.536998) (xy 457.745462 -421.494078) (xy 457.869672 -421.458737) (xy 457.995821 -421.43111)
			(xy 458.123433 -421.411301) (xy 458.252022 -421.399385) (xy 458.3811 -421.395409) (xy 458.510178 -421.399385)
			(xy 458.638767 -421.411301) (xy 458.766379 -421.43111) (xy 458.892528 -421.458737) (xy 459.016738 -421.494078)
			(xy 459.138537 -421.536998) (xy 459.257462 -421.587335) (xy 459.373063 -421.644897) (xy 459.484902 -421.709467)
			(xy 459.592553 -421.780799) (xy 459.695608 -421.858623) (xy 459.793678 -421.942644) (xy 459.886389 -422.032543)
			(xy 459.973389 -422.127978) (xy 460.05435 -422.228588) (xy 460.128964 -422.333991) (xy 460.196947 -422.443788)
			(xy 460.258042 -422.557562) (xy 460.312017 -422.674881) (xy 460.358668 -422.7953) (xy 460.397817 -422.918363)
			(xy 460.429316 -423.043602) (xy 460.453045 -423.170543) (xy 460.468915 -423.298703) (xy 460.476865 -423.427598)
			(xy 460.477362 -423.492168) (xy 460.476865 -423.556738) (xy 460.468915 -423.685633) (xy 460.453045 -423.813793)
			(xy 460.429316 -423.940734) (xy 460.397817 -424.065973) (xy 460.358668 -424.189036) (xy 460.312017 -424.309455)
			(xy 460.258042 -424.426774) (xy 460.196947 -424.540548) (xy 460.128964 -424.650345) (xy 460.05435 -424.755748)
			(xy 459.973389 -424.856358) (xy 459.886389 -424.951793) (xy 459.793678 -425.041692) (xy 459.695608 -425.125713)
			(xy 459.592553 -425.203537) (xy 459.484902 -425.274869) (xy 459.373063 -425.339439) (xy 459.257462 -425.397001)
			(xy 459.138537 -425.447338) (xy 459.016738 -425.490258) (xy 458.892528 -425.525599) (xy 458.766379 -425.553226)
			(xy 458.638767 -425.573035) (xy 458.510178 -425.584951) (xy 458.3811 -425.588928) (xy 458.252022 -425.584951)
			(xy 458.123433 -425.573035) (xy 457.995821 -425.553226) (xy 457.869672 -425.525599) (xy 457.745462 -425.490258)
			(xy 457.623663 -425.447338) (xy 457.504738 -425.397001) (xy 457.389137 -425.339439) (xy 457.277298 -425.274869)
			(xy 457.169647 -425.203537) (xy 457.066592 -425.125713) (xy 456.968522 -425.041692) (xy 456.875811 -424.951793)
			(xy 456.788811 -424.856358) (xy 456.70785 -424.755748) (xy 456.633236 -424.650345) (xy 456.565253 -424.540548)
			(xy 456.504158 -424.426774) (xy 456.450183 -424.309455) (xy 456.403532 -424.189036) (xy 456.364383 -424.065973)
			(xy 456.332884 -423.940734) (xy 456.309155 -423.813793) (xy 456.293285 -423.685633) (xy 456.285335 -423.556738)
			(xy 361.505055 -423.556738) (xy 361.522862 -423.581893) (xy 361.590845 -423.69169) (xy 361.65194 -423.805464)
			(xy 361.705915 -423.922783) (xy 361.752566 -424.043202) (xy 361.791715 -424.166265) (xy 361.823214 -424.291504)
			(xy 361.846943 -424.418445) (xy 361.862813 -424.546605) (xy 361.870763 -424.6755) (xy 361.87126 -424.74007)
			(xy 361.870763 -424.80464) (xy 361.862813 -424.933535) (xy 361.846943 -425.061695) (xy 361.823214 -425.188636)
			(xy 361.791715 -425.313875) (xy 361.752566 -425.436938) (xy 361.705915 -425.557357) (xy 361.65194 -425.674676)
			(xy 361.590845 -425.78845) (xy 361.522862 -425.898247) (xy 361.448248 -426.00365) (xy 361.367287 -426.10426)
			(xy 361.280287 -426.199695) (xy 361.187576 -426.289594) (xy 361.089506 -426.373615) (xy 360.986451 -426.451439)
			(xy 360.8788 -426.522771) (xy 360.766961 -426.587341) (xy 360.65136 -426.644903) (xy 360.532435 -426.69524)
			(xy 360.410636 -426.73816) (xy 360.286426 -426.773501) (xy 360.160277 -426.801128) (xy 360.032665 -426.820937)
			(xy 359.904076 -426.832853) (xy 359.774998 -426.83683) (xy 359.64592 -426.832853) (xy 359.517331 -426.820937)
			(xy 359.389719 -426.801128) (xy 359.26357 -426.773501) (xy 359.13936 -426.73816) (xy 359.017561 -426.69524)
			(xy 358.898636 -426.644903) (xy 358.783035 -426.587341) (xy 358.671196 -426.522771) (xy 358.563545 -426.451439)
			(xy 358.46049 -426.373615) (xy 358.36242 -426.289594) (xy 358.269709 -426.199695) (xy 358.182709 -426.10426)
			(xy 358.101748 -426.00365) (xy 358.027134 -425.898247) (xy 357.959151 -425.78845) (xy 357.898056 -425.674676)
			(xy 357.844081 -425.557357) (xy 357.79743 -425.436938) (xy 357.758281 -425.313875) (xy 357.726782 -425.188636)
			(xy 357.703053 -425.061695) (xy 357.687183 -424.933535) (xy 357.679233 -424.80464) (xy 230.3145 -424.80464)
			(xy 230.3145 -427.960536) (xy 314.141104 -427.960536) (xy 314.141104 -427.233334) (xy 314.141374 -427.224578)
			(xy 314.145341 -427.207521) (xy 314.148978 -427.199552) (xy 314.382404 -426.723302) (xy 314.387092 -426.71278)
			(xy 314.390587 -426.690025) (xy 314.387107 -426.667268) (xy 314.382404 -426.656754) (xy 314.148978 -426.180504)
			(xy 314.145316 -426.172543) (xy 314.14134 -426.155482) (xy 314.141104 -426.146722) (xy 314.141104 -425.419012)
			(xy 314.141523 -425.406929) (xy 314.148989 -425.383944) (xy 314.163193 -425.364393) (xy 314.182744 -425.350189)
			(xy 314.205729 -425.342723) (xy 314.217812 -425.342304) (xy 315.157612 -425.342304) (xy 315.169688 -425.342754)
			(xy 315.192658 -425.350222) (xy 315.212196 -425.364421) (xy 315.226389 -425.383964) (xy 315.233849 -425.406935)
			(xy 315.23432 -425.419012) (xy 315.23432 -427.960536) (xy 315.233867 -427.972611) (xy 315.226396 -427.995578)
			(xy 315.212196 -428.015113) (xy 315.192656 -428.029307) (xy 315.169687 -428.036771) (xy 315.157612 -428.037244)
			(xy 314.217812 -428.037244) (xy 314.205742 -428.036726) (xy 314.182781 -428.029271) (xy 314.163247 -428.015087)
			(xy 314.149051 -427.995562) (xy 314.141581 -427.972606) (xy 314.141104 -427.960536) (xy 230.3145 -427.960536)
			(xy 230.3145 -433.130695) (xy 266.885917 -433.130695) (xy 266.885917 -432.953425) (xy 266.89387 -432.776334)
			(xy 266.909761 -432.599778) (xy 266.933556 -432.424113) (xy 266.965209 -432.249692) (xy 267.004655 -432.076867)
			(xy 267.051815 -431.905986) (xy 267.106594 -431.737392) (xy 267.168882 -431.571427) (xy 267.238554 -431.408422)
			(xy 267.315468 -431.248708) (xy 267.399471 -431.092605) (xy 267.490392 -430.940428) (xy 267.588049 -430.792484)
			(xy 267.692246 -430.64907) (xy 267.802772 -430.510475) (xy 267.919404 -430.376978) (xy 268.041909 -430.248849)
			(xy 268.170038 -430.126344) (xy 268.303535 -430.009712) (xy 268.44213 -429.899186) (xy 268.585544 -429.794989)
			(xy 268.733488 -429.697332) (xy 268.885665 -429.606411) (xy 269.041768 -429.522408) (xy 269.201482 -429.445494)
			(xy 269.364487 -429.375822) (xy 269.530452 -429.313534) (xy 269.699046 -429.258755) (xy 269.869927 -429.211595)
			(xy 270.042752 -429.172149) (xy 270.217173 -429.140496) (xy 270.392838 -429.116701) (xy 270.569394 -429.10081)
			(xy 270.746485 -429.092857) (xy 270.923755 -429.092857) (xy 271.100846 -429.10081) (xy 271.277402 -429.116701)
			(xy 271.453067 -429.140496) (xy 271.627488 -429.172149) (xy 271.800313 -429.211595) (xy 271.971194 -429.258755)
			(xy 272.139788 -429.313534) (xy 272.305753 -429.375822) (xy 272.468758 -429.445494) (xy 272.628472 -429.522408)
			(xy 272.784575 -429.606411) (xy 272.936752 -429.697332) (xy 273.084696 -429.794989) (xy 273.22811 -429.899186)
			(xy 273.366705 -430.009712) (xy 273.500202 -430.126344) (xy 273.628331 -430.248849) (xy 273.750836 -430.376978)
			(xy 273.867468 -430.510475) (xy 273.977994 -430.64907) (xy 274.082191 -430.792484) (xy 274.179848 -430.940428)
			(xy 274.270769 -431.092605) (xy 274.354772 -431.248708) (xy 274.431686 -431.408422) (xy 274.496678 -431.560478)
			(xy 314.141104 -431.560478) (xy 314.141104 -429.018954) (xy 314.141572 -429.00684) (xy 314.149068 -428.983801)
			(xy 314.163312 -428.964203) (xy 314.182912 -428.949962) (xy 314.205952 -428.94247) (xy 314.218066 -428.941992)
			(xy 315.157866 -428.941992) (xy 315.169974 -428.94254) (xy 315.193009 -428.950012) (xy 315.207156 -428.96028)
			(xy 316.1411 -428.96028) (xy 316.1411 -428.233078) (xy 316.141352 -428.224321) (xy 316.145331 -428.207263)
			(xy 316.148974 -428.199296) (xy 316.3824 -427.723046) (xy 316.387127 -427.712539) (xy 316.390608 -427.689775)
			(xy 316.387112 -427.667012) (xy 316.3824 -427.656498) (xy 316.148974 -427.180248) (xy 316.145325 -427.172282)
			(xy 316.141341 -427.155224) (xy 316.1411 -427.146466) (xy 316.1411 -426.418756) (xy 316.141527 -426.406678)
			(xy 316.149002 -426.383708) (xy 316.163208 -426.364171) (xy 316.182755 -426.349979) (xy 316.20573 -426.342519)
			(xy 316.217808 -426.342048) (xy 317.157608 -426.342048) (xy 317.169679 -426.342557) (xy 317.192639 -426.350016)
			(xy 317.212172 -426.364203) (xy 317.226367 -426.383729) (xy 317.233838 -426.406686) (xy 317.234316 -426.418756)
			(xy 317.234316 -427.960536) (xy 318.141096 -427.960536) (xy 318.141096 -427.233334) (xy 318.141367 -427.224578)
			(xy 318.145333 -427.207521) (xy 318.14897 -427.199552) (xy 318.382396 -426.723302) (xy 318.387084 -426.71278)
			(xy 318.390579 -426.690025) (xy 318.387099 -426.667268) (xy 318.382396 -426.656754) (xy 318.14897 -426.180504)
			(xy 318.145307 -426.172544) (xy 318.141332 -426.155482) (xy 318.141096 -426.146722) (xy 318.141096 -425.419012)
			(xy 318.141523 -425.40693) (xy 318.148988 -425.383947) (xy 318.16319 -425.364396) (xy 318.182739 -425.350191)
			(xy 318.205722 -425.342724) (xy 318.217804 -425.342304) (xy 319.157604 -425.342304) (xy 319.169688 -425.342709)
			(xy 319.192673 -425.350179) (xy 319.212224 -425.364387) (xy 319.226428 -425.383941) (xy 319.233893 -425.406928)
			(xy 319.234312 -425.419012) (xy 319.234312 -427.960536) (xy 319.233867 -427.972612) (xy 319.226395 -427.99558)
			(xy 319.212193 -428.015116) (xy 319.192651 -428.029309) (xy 319.16968 -428.036772) (xy 319.157604 -428.037244)
			(xy 318.217804 -428.037244) (xy 318.205733 -428.036733) (xy 318.182772 -428.029276) (xy 318.163238 -428.01509)
			(xy 318.149042 -427.995564) (xy 318.141573 -427.972607) (xy 318.141096 -427.960536) (xy 317.234316 -427.960536)
			(xy 317.234316 -428.96028) (xy 317.23387 -428.972361) (xy 317.226409 -428.995342) (xy 317.212211 -429.014891)
			(xy 317.192667 -429.029096) (xy 317.169689 -429.036566) (xy 317.157608 -429.036988) (xy 316.217808 -429.036988)
			(xy 316.205724 -429.03658) (xy 316.182738 -429.029113) (xy 316.163186 -429.014906) (xy 316.148982 -428.995352)
			(xy 316.141518 -428.972364) (xy 316.1411 -428.96028) (xy 315.207156 -428.96028) (xy 315.212607 -428.964236)
			(xy 315.226851 -428.98382) (xy 315.234347 -429.006846) (xy 315.234828 -429.018954) (xy 315.234828 -431.560478)
			(xy 315.234421 -431.572603) (xy 315.22693 -431.595667) (xy 315.212677 -431.615285) (xy 315.193056 -431.629536)
			(xy 315.169991 -431.637023) (xy 315.157866 -431.63744) (xy 314.218066 -431.63744) (xy 314.205947 -431.637017)
			(xy 314.182899 -431.629518) (xy 314.163296 -431.615264) (xy 314.149057 -431.59565) (xy 314.141574 -431.572597)
			(xy 314.141104 -431.560478) (xy 274.496678 -431.560478) (xy 274.501358 -431.571427) (xy 274.563646 -431.737392)
			(xy 274.618425 -431.905986) (xy 274.665585 -432.076867) (xy 274.705031 -432.249692) (xy 274.736684 -432.424113)
			(xy 274.760479 -432.599778) (xy 274.77637 -432.776334) (xy 274.784323 -432.953425) (xy 274.78482 -433.04206)
			(xy 274.784323 -433.130695) (xy 274.77637 -433.307786) (xy 274.760479 -433.484342) (xy 274.736684 -433.660007)
			(xy 274.705031 -433.834428) (xy 274.665585 -434.007253) (xy 274.618425 -434.178134) (xy 274.563646 -434.346728)
			(xy 274.501358 -434.512693) (xy 274.431686 -434.675698) (xy 274.354772 -434.835412) (xy 274.270769 -434.991515)
			(xy 274.179848 -435.143692) (xy 274.168806 -435.16042) (xy 314.141104 -435.16042) (xy 314.141104 -432.618896)
			(xy 314.141513 -432.606787) (xy 314.149014 -432.583758) (xy 314.163277 -432.564185) (xy 314.182901 -432.549991)
			(xy 314.205955 -432.542571) (xy 314.218066 -432.542188) (xy 315.157866 -432.542188) (xy 315.169959 -432.542637)
			(xy 315.192966 -432.55009) (xy 315.207301 -432.560476) (xy 316.1411 -432.560476) (xy 316.1411 -430.018952)
			(xy 316.141476 -430.006841) (xy 316.148988 -429.983812) (xy 316.16326 -429.96424) (xy 316.18289 -429.950047)
			(xy 316.205949 -429.942627) (xy 316.218062 -429.942244) (xy 317.157862 -429.942244) (xy 317.16995 -429.94274)
			(xy 317.19295 -429.950187) (xy 317.212531 -429.964366) (xy 317.226783 -429.983894) (xy 317.234315 -430.006866)
			(xy 317.234824 -430.018952) (xy 317.234824 -431.560478) (xy 318.141096 -431.560478) (xy 318.141096 -429.018954)
			(xy 318.141572 -429.006841) (xy 318.149067 -428.983804) (xy 318.163309 -428.964206) (xy 318.182907 -428.949965)
			(xy 318.205945 -428.942471) (xy 318.218058 -428.941992) (xy 319.157858 -428.941992) (xy 319.169966 -428.942547)
			(xy 319.193 -428.950017) (xy 319.207142 -428.96028) (xy 320.141092 -428.96028) (xy 320.141092 -428.233078)
			(xy 320.141345 -428.224321) (xy 320.145323 -428.207264) (xy 320.148966 -428.199296) (xy 320.382392 -427.723046)
			(xy 320.387119 -427.712539) (xy 320.3906 -427.689775) (xy 320.387104 -427.667012) (xy 320.382392 -427.656498)
			(xy 320.148966 -427.180248) (xy 320.145317 -427.172282) (xy 320.141333 -427.155224) (xy 320.141092 -427.146466)
			(xy 320.141092 -426.418756) (xy 320.141527 -426.406679) (xy 320.149001 -426.38371) (xy 320.163205 -426.364174)
			(xy 320.18275 -426.349981) (xy 320.205723 -426.34252) (xy 320.2178 -426.342048) (xy 321.1576 -426.342048)
			(xy 321.16967 -426.342564) (xy 321.19263 -426.350021) (xy 321.212163 -426.364206) (xy 321.226359 -426.383731)
			(xy 321.233829 -426.406686) (xy 321.234308 -426.418756) (xy 321.234308 -427.960536) (xy 322.141088 -427.960536)
			(xy 322.141088 -427.233334) (xy 322.14136 -427.224578) (xy 322.145325 -427.207521) (xy 322.148962 -427.199552)
			(xy 322.382388 -426.723302) (xy 322.387076 -426.71278) (xy 322.390572 -426.690025) (xy 322.387092 -426.667268)
			(xy 322.382388 -426.656754) (xy 322.148962 -426.180504) (xy 322.145299 -426.172544) (xy 322.141324 -426.155482)
			(xy 322.141088 -426.146722) (xy 322.141088 -425.419012) (xy 322.141523 -425.40693) (xy 322.148987 -425.383949)
			(xy 322.163187 -425.364399) (xy 322.182734 -425.350194) (xy 322.205714 -425.342726) (xy 322.217796 -425.342304)
			(xy 323.157596 -425.342304) (xy 323.16968 -425.342716) (xy 323.192664 -425.350184) (xy 323.212216 -425.36439)
			(xy 323.22642 -425.383943) (xy 323.233885 -425.406928) (xy 323.234304 -425.419012) (xy 323.234304 -427.960536)
			(xy 323.233867 -427.972613) (xy 323.226394 -427.995582) (xy 323.21219 -428.015119) (xy 323.192646 -428.029312)
			(xy 323.169673 -428.036773) (xy 323.157596 -428.037244) (xy 322.217796 -428.037244) (xy 322.205725 -428.03674)
			(xy 322.182764 -428.02928) (xy 322.16323 -428.015093) (xy 322.149034 -427.995565) (xy 322.141565 -427.972607)
			(xy 322.141088 -427.960536) (xy 321.234308 -427.960536) (xy 321.234308 -428.96028) (xy 321.23387 -428.972362)
			(xy 321.226408 -428.995344) (xy 321.212208 -429.014894) (xy 321.192662 -429.029099) (xy 321.169682 -429.036567)
			(xy 321.1576 -429.036988) (xy 320.2178 -429.036988) (xy 320.205715 -429.036587) (xy 320.182729 -429.029117)
			(xy 320.163177 -429.014909) (xy 320.148974 -428.995353) (xy 320.14151 -428.972365) (xy 320.141092 -428.96028)
			(xy 319.207142 -428.96028) (xy 319.212598 -428.964239) (xy 319.226843 -428.983821) (xy 319.234339 -429.006847)
			(xy 319.23482 -429.018954) (xy 319.23482 -431.560478) (xy 319.234421 -431.572604) (xy 319.226929 -431.595669)
			(xy 319.212674 -431.615288) (xy 319.193051 -431.629538) (xy 319.169984 -431.637024) (xy 319.157858 -431.63744)
			(xy 318.218058 -431.63744) (xy 318.205939 -431.637024) (xy 318.182891 -431.629522) (xy 318.163288 -431.615267)
			(xy 318.149048 -431.595652) (xy 318.141566 -431.572597) (xy 318.141096 -431.560478) (xy 317.234824 -431.560478)
			(xy 317.234824 -432.560476) (xy 317.234363 -432.572581) (xy 317.226874 -432.595604) (xy 317.212623 -432.615175)
			(xy 317.193012 -432.629371) (xy 317.169968 -432.636797) (xy 317.157862 -432.637184) (xy 316.218062 -432.637184)
			(xy 316.205973 -432.636726) (xy 316.182975 -432.629261) (xy 316.163398 -432.615072) (xy 316.149148 -432.595538)
			(xy 316.141612 -432.572564) (xy 316.1411 -432.560476) (xy 315.207301 -432.560476) (xy 315.212551 -432.56428)
			(xy 315.226801 -432.583821) (xy 315.234325 -432.606805) (xy 315.234828 -432.618896) (xy 315.234828 -435.16042)
			(xy 315.234401 -435.172527) (xy 315.2269 -435.19555) (xy 315.21264 -435.215121) (xy 315.193022 -435.229316)
			(xy 315.169974 -435.236741) (xy 315.157866 -435.237128) (xy 314.218066 -435.237128) (xy 314.205971 -435.236721)
			(xy 314.182964 -435.229251) (xy 314.163382 -435.21505) (xy 314.149134 -435.195502) (xy 314.141608 -435.172513)
			(xy 314.141104 -435.16042) (xy 274.168806 -435.16042) (xy 274.082191 -435.291636) (xy 273.977994 -435.43505)
			(xy 273.867468 -435.573645) (xy 273.750836 -435.707142) (xy 273.628331 -435.835271) (xy 273.500202 -435.957776)
			(xy 273.366705 -436.074408) (xy 273.22811 -436.184934) (xy 273.084696 -436.289131) (xy 272.936752 -436.386788)
			(xy 272.784575 -436.477709) (xy 272.628472 -436.561712) (xy 272.468758 -436.638626) (xy 272.305753 -436.708298)
			(xy 272.139788 -436.770586) (xy 271.971194 -436.825365) (xy 271.800313 -436.872525) (xy 271.627488 -436.911971)
			(xy 271.453067 -436.943624) (xy 271.277402 -436.967419) (xy 271.100846 -436.98331) (xy 270.923755 -436.991263)
			(xy 270.746485 -436.991263) (xy 270.569394 -436.98331) (xy 270.392838 -436.967419) (xy 270.217173 -436.943624)
			(xy 270.042752 -436.911971) (xy 269.869927 -436.872525) (xy 269.699046 -436.825365) (xy 269.530452 -436.770586)
			(xy 269.364487 -436.708298) (xy 269.201482 -436.638626) (xy 269.041768 -436.561712) (xy 268.885665 -436.477709)
			(xy 268.733488 -436.386788) (xy 268.585544 -436.289131) (xy 268.44213 -436.184934) (xy 268.303535 -436.074408)
			(xy 268.170038 -435.957776) (xy 268.041909 -435.835271) (xy 267.919404 -435.707142) (xy 267.802772 -435.573645)
			(xy 267.692246 -435.43505) (xy 267.588049 -435.291636) (xy 267.490392 -435.143692) (xy 267.399471 -434.991515)
			(xy 267.315468 -434.835412) (xy 267.238554 -434.675698) (xy 267.168882 -434.512693) (xy 267.106594 -434.346728)
			(xy 267.051815 -434.178134) (xy 267.004655 -434.007253) (xy 266.965209 -433.834428) (xy 266.933556 -433.660007)
			(xy 266.909761 -433.484342) (xy 266.89387 -433.307786) (xy 266.885917 -433.130695) (xy 230.3145 -433.130695)
			(xy 230.3145 -435.873652) (xy 230.314033 -435.898602) (xy 230.306213 -435.947887) (xy 230.29079 -435.995345)
			(xy 230.268141 -436.03981) (xy 230.238824 -436.080191) (xy 230.221536 -436.098188) (xy 229.299008 -437.020716)
			(xy 229.281016 -437.03801) (xy 229.240639 -437.067332) (xy 229.196172 -437.089979) (xy 229.148711 -437.105393)
			(xy 229.099423 -437.113193) (xy 229.074472 -437.11368) (xy 207.302608 -437.11368) (xy 207.27766 -437.113152)
			(xy 207.22838 -437.105344) (xy 207.180923 -437.089933) (xy 207.136457 -437.067299) (xy 207.096072 -437.037997)
			(xy 207.078072 -437.020716) (xy 205.512924 -435.455568) (xy 205.495618 -435.437587) (xy 205.466295 -435.397208)
			(xy 205.44365 -435.352738) (xy 205.42824 -435.305274) (xy 205.420444 -435.255984) (xy 205.41996 -435.231032)
			(xy 205.41996 -431.16881) (xy 205.41954 -431.15874) (xy 205.411817 -431.140141) (xy 205.404974 -431.132742)
			(xy 196.207888 -421.935656) (xy 196.19057 -421.917686) (xy 196.16125 -421.877303) (xy 196.138608 -421.832831)
			(xy 196.1232 -421.785364) (xy 196.115407 -421.736072) (xy 196.114924 -421.71112) (xy 196.114924 -413.329374)
			(xy 196.114532 -413.319301) (xy 196.10679 -413.300702) (xy 196.099938 -413.293306) (xy 195.154296 -412.347664)
			(xy 195.146896 -412.340825) (xy 195.128296 -412.333106) (xy 195.118228 -412.332678) (xy 188.720222 -412.332678)
			(xy 188.695275 -412.332142) (xy 188.645994 -412.324336) (xy 188.598538 -412.308927) (xy 188.554072 -412.286295)
			(xy 188.513686 -412.256994) (xy 188.495686 -412.239714) (xy 187.848748 -411.592776) (xy 187.841328 -411.585961)
			(xy 187.822744 -411.578227) (xy 187.81268 -411.57779) (xy 184.8104 -411.57779) (xy 184.785451 -411.577293)
			(xy 184.736167 -411.569481) (xy 184.68871 -411.554065) (xy 184.644244 -411.531423) (xy 184.603862 -411.502111)
			(xy 184.585864 -411.484826) (xy 184.033922 -410.932884) (xy 184.016624 -410.914896) (xy 183.9873 -410.874519)
			(xy 183.964653 -410.830051) (xy 183.949241 -410.782588) (xy 183.941443 -410.733299) (xy 183.940958 -410.708348)
			(xy 7.00913 -410.708348) (xy 7.00913 -413.4485) (xy 38.974268 -413.4485) (xy 38.974268 -412.5849)
			(xy 38.974754 -412.557631) (xy 38.982516 -412.503647) (xy 38.997881 -412.451317) (xy 39.020538 -412.401707)
			(xy 39.050024 -412.355826) (xy 39.085739 -412.314609) (xy 39.126956 -412.278894) (xy 39.172837 -412.249408)
			(xy 39.222447 -412.226751) (xy 39.274777 -412.211386) (xy 39.328761 -412.203624) (xy 39.383299 -412.203624)
			(xy 39.437283 -412.211386) (xy 39.489613 -412.226751) (xy 39.539223 -412.249408) (xy 39.585104 -412.278894)
			(xy 39.626321 -412.314609) (xy 39.662036 -412.355826) (xy 39.691522 -412.401707) (xy 39.714179 -412.451317)
			(xy 39.729544 -412.503647) (xy 39.737306 -412.557631) (xy 39.737792 -412.5849) (xy 39.737792 -412.597452)
			(xy 47.413146 -412.597452) (xy 47.413146 -412.542948) (xy 47.420902 -412.488999) (xy 47.436257 -412.436703)
			(xy 47.458897 -412.387124) (xy 47.488362 -412.341271) (xy 47.524053 -412.300079) (xy 47.565242 -412.264384)
			(xy 47.611092 -412.234914) (xy 47.660669 -412.212269) (xy 47.712964 -412.19691) (xy 47.766912 -412.189148)
			(xy 47.794164 -412.18866) (xy 48.657764 -412.18866) (xy 48.685016 -412.189185) (xy 48.738967 -412.196937)
			(xy 48.791264 -412.212289) (xy 48.840845 -412.234927) (xy 48.886699 -412.264392) (xy 48.927892 -412.300082)
			(xy 48.963587 -412.341273) (xy 48.993056 -412.387124) (xy 49.015699 -412.436702) (xy 49.031055 -412.488998)
			(xy 49.038813 -412.542948) (xy 49.038813 -412.597452) (xy 49.038813 -412.597455) (xy 50.476323 -412.597455)
			(xy 50.476323 -412.542945) (xy 50.484081 -412.488989) (xy 50.499438 -412.436686) (xy 50.522083 -412.387102)
			(xy 50.551554 -412.341244) (xy 50.587251 -412.300048) (xy 50.628448 -412.264351) (xy 50.674305 -412.234881)
			(xy 50.72389 -412.212237) (xy 50.776193 -412.19688) (xy 50.830149 -412.189123) (xy 50.857404 -412.18866)
			(xy 51.721004 -412.18866) (xy 51.748253 -412.18921) (xy 51.802195 -412.196967) (xy 51.854485 -412.212321)
			(xy 51.904058 -412.23496) (xy 51.949904 -412.264424) (xy 51.99109 -412.300113) (xy 52.026778 -412.341299)
			(xy 52.056242 -412.387146) (xy 52.07888 -412.436718) (xy 52.094234 -412.489008) (xy 52.10199 -412.542951)
			(xy 52.10199 -412.597449) (xy 52.101989 -412.597457) (xy 53.539523 -412.597457) (xy 53.539523 -412.542943)
			(xy 53.547282 -412.488983) (xy 53.562641 -412.436678) (xy 53.585289 -412.38709) (xy 53.614764 -412.341231)
			(xy 53.650465 -412.300034) (xy 53.691667 -412.264337) (xy 53.737529 -412.234868) (xy 53.787119 -412.212226)
			(xy 53.839427 -412.196872) (xy 53.893387 -412.18912) (xy 53.920644 -412.18866) (xy 54.784244 -412.18866)
			(xy 54.811491 -412.189213) (xy 54.865429 -412.196974) (xy 54.917714 -412.212332) (xy 54.967282 -412.234973)
			(xy 55.013123 -412.264438) (xy 55.054304 -412.300127) (xy 55.089988 -412.341313) (xy 55.119448 -412.387157)
			(xy 55.142084 -412.436727) (xy 55.157435 -412.489014) (xy 55.16519 -412.542953) (xy 55.16519 -412.597447)
			(xy 55.165189 -412.597453) (xy 56.602846 -412.597453) (xy 56.602846 -412.542947) (xy 56.610603 -412.488996)
			(xy 56.625958 -412.436698) (xy 56.6486 -412.387118) (xy 56.678067 -412.341265) (xy 56.71376 -412.300071)
			(xy 56.754952 -412.264377) (xy 56.800804 -412.234908) (xy 56.850383 -412.212264) (xy 56.902681 -412.196906)
			(xy 56.956631 -412.189147) (xy 56.983884 -412.18866) (xy 57.847484 -412.18866) (xy 57.874735 -412.189186)
			(xy 57.928683 -412.196941) (xy 57.980979 -412.212294) (xy 58.030557 -412.234934) (xy 58.076408 -412.264399)
			(xy 58.117599 -412.300089) (xy 58.153292 -412.341279) (xy 58.182759 -412.387129) (xy 58.2054 -412.436706)
			(xy 58.220756 -412.489001) (xy 58.228513 -412.542949) (xy 58.228513 -412.597451) (xy 58.228512 -412.597456)
			(xy 59.666023 -412.597456) (xy 59.666023 -412.542944) (xy 59.673781 -412.488986) (xy 59.68914 -412.436682)
			(xy 59.711786 -412.387096) (xy 59.741259 -412.341238) (xy 59.776958 -412.300041) (xy 59.818157 -412.264344)
			(xy 59.864017 -412.234874) (xy 59.913604 -412.212231) (xy 59.96591 -412.196876) (xy 60.019868 -412.189121)
			(xy 60.047124 -412.18866) (xy 60.910724 -412.18866) (xy 60.937972 -412.189212) (xy 60.991912 -412.19697)
			(xy 61.0442 -412.212326) (xy 61.09377 -412.234967) (xy 61.139613 -412.264431) (xy 61.180797 -412.30012)
			(xy 61.216483 -412.341306) (xy 61.245945 -412.387151) (xy 61.268582 -412.436723) (xy 61.283935 -412.489011)
			(xy 61.29169 -412.542952) (xy 61.29169 -412.597448) (xy 61.291689 -412.597452) (xy 62.729346 -412.597452)
			(xy 62.729346 -412.542948) (xy 62.737102 -412.488999) (xy 62.752457 -412.436703) (xy 62.775097 -412.387124)
			(xy 62.804562 -412.341271) (xy 62.840253 -412.300079) (xy 62.881442 -412.264384) (xy 62.927292 -412.234914)
			(xy 62.976869 -412.212269) (xy 63.029164 -412.19691) (xy 63.083112 -412.189148) (xy 63.110364 -412.18866)
			(xy 63.973964 -412.18866) (xy 64.001216 -412.189185) (xy 64.055167 -412.196937) (xy 64.107464 -412.212289)
			(xy 64.157045 -412.234927) (xy 64.202899 -412.264392) (xy 64.244092 -412.300082) (xy 64.279787 -412.341273)
			(xy 64.309256 -412.387124) (xy 64.331899 -412.436702) (xy 64.347255 -412.488998) (xy 64.355013 -412.542948)
			(xy 64.355013 -412.597452) (xy 64.355013 -412.597455) (xy 65.792523 -412.597455) (xy 65.792523 -412.542945)
			(xy 65.800281 -412.488989) (xy 65.815638 -412.436686) (xy 65.838283 -412.387102) (xy 65.867754 -412.341244)
			(xy 65.903451 -412.300048) (xy 65.944648 -412.264351) (xy 65.990505 -412.234881) (xy 66.04009 -412.212237)
			(xy 66.092393 -412.19688) (xy 66.146349 -412.189123) (xy 66.173604 -412.18866) (xy 67.037204 -412.18866)
			(xy 67.064453 -412.18921) (xy 67.118395 -412.196967) (xy 67.170685 -412.212321) (xy 67.220258 -412.23496)
			(xy 67.266104 -412.264424) (xy 67.30729 -412.300113) (xy 67.342978 -412.341299) (xy 67.372442 -412.387146)
			(xy 67.39508 -412.436718) (xy 67.410434 -412.489008) (xy 67.41819 -412.542951) (xy 67.41819 -412.597449)
			(xy 67.418189 -412.597457) (xy 68.855723 -412.597457) (xy 68.855723 -412.542943) (xy 68.863482 -412.488983)
			(xy 68.878841 -412.436678) (xy 68.901489 -412.38709) (xy 68.930964 -412.341231) (xy 68.966665 -412.300034)
			(xy 69.007867 -412.264337) (xy 69.053729 -412.234868) (xy 69.103319 -412.212226) (xy 69.155627 -412.196872)
			(xy 69.209587 -412.18912) (xy 69.236844 -412.18866) (xy 70.100444 -412.18866) (xy 70.127691 -412.189213)
			(xy 70.181629 -412.196974) (xy 70.233914 -412.212332) (xy 70.283482 -412.234973) (xy 70.329323 -412.264438)
			(xy 70.370504 -412.300127) (xy 70.406188 -412.341313) (xy 70.435648 -412.387157) (xy 70.458284 -412.436727)
			(xy 70.473635 -412.489014) (xy 70.48139 -412.542953) (xy 70.48139 -412.597447) (xy 70.481389 -412.597453)
			(xy 71.919046 -412.597453) (xy 71.919046 -412.542947) (xy 71.926803 -412.488996) (xy 71.942158 -412.436698)
			(xy 71.9648 -412.387118) (xy 71.994267 -412.341265) (xy 72.02996 -412.300071) (xy 72.071152 -412.264377)
			(xy 72.117004 -412.234908) (xy 72.166583 -412.212264) (xy 72.218881 -412.196906) (xy 72.272831 -412.189147)
			(xy 72.300084 -412.18866) (xy 73.163684 -412.18866) (xy 73.190935 -412.189186) (xy 73.244883 -412.196941)
			(xy 73.297179 -412.212294) (xy 73.346757 -412.234934) (xy 73.392608 -412.264399) (xy 73.433799 -412.300089)
			(xy 73.469492 -412.341279) (xy 73.498959 -412.387129) (xy 73.5216 -412.436706) (xy 73.536956 -412.489001)
			(xy 73.544713 -412.542949) (xy 73.544713 -412.597451) (xy 73.544712 -412.597456) (xy 74.982223 -412.597456)
			(xy 74.982223 -412.542944) (xy 74.989981 -412.488986) (xy 75.00534 -412.436682) (xy 75.027986 -412.387096)
			(xy 75.057459 -412.341238) (xy 75.093158 -412.300041) (xy 75.134357 -412.264344) (xy 75.180217 -412.234874)
			(xy 75.229804 -412.212231) (xy 75.28211 -412.196876) (xy 75.336068 -412.189121) (xy 75.363324 -412.18866)
			(xy 76.226924 -412.18866) (xy 76.254172 -412.189212) (xy 76.308112 -412.19697) (xy 76.3604 -412.212326)
			(xy 76.40997 -412.234967) (xy 76.455813 -412.264431) (xy 76.496997 -412.30012) (xy 76.532683 -412.341306)
			(xy 76.562145 -412.387151) (xy 76.584782 -412.436723) (xy 76.600135 -412.489011) (xy 76.60789 -412.542952)
			(xy 76.60789 -412.597448) (xy 76.607889 -412.597452) (xy 78.045546 -412.597452) (xy 78.045546 -412.542948)
			(xy 78.053302 -412.488999) (xy 78.068657 -412.436703) (xy 78.091297 -412.387124) (xy 78.120762 -412.341271)
			(xy 78.156453 -412.300079) (xy 78.197642 -412.264384) (xy 78.243492 -412.234914) (xy 78.293069 -412.212269)
			(xy 78.345364 -412.19691) (xy 78.399312 -412.189148) (xy 78.426564 -412.18866) (xy 79.290164 -412.18866)
			(xy 79.317416 -412.189185) (xy 79.371367 -412.196937) (xy 79.423664 -412.212289) (xy 79.473245 -412.234927)
			(xy 79.519099 -412.264392) (xy 79.560292 -412.300082) (xy 79.595987 -412.341273) (xy 79.625456 -412.387124)
			(xy 79.648099 -412.436702) (xy 79.663455 -412.488998) (xy 79.671213 -412.542948) (xy 79.671213 -412.597452)
			(xy 79.671213 -412.597455) (xy 81.108723 -412.597455) (xy 81.108723 -412.542945) (xy 81.116481 -412.488989)
			(xy 81.131838 -412.436686) (xy 81.154483 -412.387102) (xy 81.183954 -412.341244) (xy 81.219651 -412.300048)
			(xy 81.260848 -412.264351) (xy 81.306705 -412.234881) (xy 81.35629 -412.212237) (xy 81.408593 -412.19688)
			(xy 81.462549 -412.189123) (xy 81.489804 -412.18866) (xy 82.353404 -412.18866) (xy 82.380653 -412.18921)
			(xy 82.434595 -412.196967) (xy 82.486885 -412.212321) (xy 82.536458 -412.23496) (xy 82.582304 -412.264424)
			(xy 82.62349 -412.300113) (xy 82.659178 -412.341299) (xy 82.688642 -412.387146) (xy 82.71128 -412.436718)
			(xy 82.726634 -412.489008) (xy 82.73439 -412.542951) (xy 82.73439 -412.597449) (xy 82.734389 -412.597457)
			(xy 84.171923 -412.597457) (xy 84.171923 -412.542943) (xy 84.179682 -412.488983) (xy 84.195041 -412.436678)
			(xy 84.217689 -412.38709) (xy 84.247164 -412.341231) (xy 84.282865 -412.300034) (xy 84.324067 -412.264337)
			(xy 84.369929 -412.234868) (xy 84.419519 -412.212226) (xy 84.471827 -412.196872) (xy 84.525787 -412.18912)
			(xy 84.553044 -412.18866) (xy 85.416644 -412.18866) (xy 85.443891 -412.189213) (xy 85.497829 -412.196974)
			(xy 85.550114 -412.212332) (xy 85.599682 -412.234973) (xy 85.645523 -412.264438) (xy 85.686704 -412.300127)
			(xy 85.722388 -412.341313) (xy 85.751848 -412.387157) (xy 85.774484 -412.436727) (xy 85.789835 -412.489014)
			(xy 85.79759 -412.542953) (xy 85.79759 -412.597447) (xy 85.797589 -412.597453) (xy 87.235246 -412.597453)
			(xy 87.235246 -412.542947) (xy 87.243003 -412.488996) (xy 87.258358 -412.436698) (xy 87.281 -412.387118)
			(xy 87.310467 -412.341265) (xy 87.34616 -412.300071) (xy 87.387352 -412.264377) (xy 87.433204 -412.234908)
			(xy 87.482783 -412.212264) (xy 87.535081 -412.196906) (xy 87.589031 -412.189147) (xy 87.616284 -412.18866)
			(xy 88.479884 -412.18866) (xy 88.507135 -412.189186) (xy 88.561083 -412.196941) (xy 88.613379 -412.212294)
			(xy 88.662957 -412.234934) (xy 88.708808 -412.264399) (xy 88.749999 -412.300089) (xy 88.785692 -412.341279)
			(xy 88.815159 -412.387129) (xy 88.8378 -412.436706) (xy 88.853156 -412.489001) (xy 88.860913 -412.542949)
			(xy 88.860913 -412.597451) (xy 88.860912 -412.597456) (xy 90.298423 -412.597456) (xy 90.298423 -412.542944)
			(xy 90.306181 -412.488986) (xy 90.32154 -412.436682) (xy 90.344186 -412.387096) (xy 90.373659 -412.341238)
			(xy 90.409358 -412.300041) (xy 90.450557 -412.264344) (xy 90.496417 -412.234874) (xy 90.546004 -412.212231)
			(xy 90.59831 -412.196876) (xy 90.652268 -412.189121) (xy 90.679524 -412.18866) (xy 91.543124 -412.18866)
			(xy 91.570372 -412.189212) (xy 91.624312 -412.19697) (xy 91.6766 -412.212326) (xy 91.72617 -412.234967)
			(xy 91.772013 -412.264431) (xy 91.813197 -412.30012) (xy 91.848883 -412.341306) (xy 91.878345 -412.387151)
			(xy 91.900982 -412.436723) (xy 91.916335 -412.489011) (xy 91.92409 -412.542952) (xy 91.92409 -412.597448)
			(xy 91.924089 -412.597452) (xy 93.361746 -412.597452) (xy 93.361746 -412.542948) (xy 93.369502 -412.488999)
			(xy 93.384857 -412.436703) (xy 93.407497 -412.387124) (xy 93.436962 -412.341271) (xy 93.472653 -412.300079)
			(xy 93.513842 -412.264384) (xy 93.559692 -412.234914) (xy 93.609269 -412.212269) (xy 93.661564 -412.19691)
			(xy 93.715512 -412.189148) (xy 93.742764 -412.18866) (xy 94.606364 -412.18866) (xy 94.633616 -412.189185)
			(xy 94.687567 -412.196937) (xy 94.739864 -412.212289) (xy 94.789445 -412.234927) (xy 94.835299 -412.264392)
			(xy 94.876492 -412.300082) (xy 94.912187 -412.341273) (xy 94.941656 -412.387124) (xy 94.964299 -412.436702)
			(xy 94.979655 -412.488998) (xy 94.987413 -412.542948) (xy 94.987413 -412.597452) (xy 94.987413 -412.597455)
			(xy 114.513023 -412.597455) (xy 114.513023 -412.542945) (xy 114.520781 -412.488989) (xy 114.536138 -412.436686)
			(xy 114.558783 -412.387101) (xy 114.588254 -412.341244) (xy 114.623952 -412.300047) (xy 114.665149 -412.264351)
			(xy 114.711006 -412.23488) (xy 114.760591 -412.212236) (xy 114.812894 -412.196879) (xy 114.866851 -412.189123)
			(xy 114.894106 -412.18866) (xy 115.757706 -412.18866) (xy 115.784955 -412.189211) (xy 115.838897 -412.196967)
			(xy 115.891187 -412.212321) (xy 115.940759 -412.234961) (xy 115.986605 -412.264425) (xy 116.027791 -412.300113)
			(xy 116.063479 -412.3413) (xy 116.092942 -412.387146) (xy 116.115581 -412.436719) (xy 116.130934 -412.489009)
			(xy 116.13869 -412.542951) (xy 116.13869 -412.597449) (xy 116.138689 -412.597457) (xy 117.576223 -412.597457)
			(xy 117.576223 -412.542943) (xy 117.583982 -412.488983) (xy 117.599342 -412.436677) (xy 117.621989 -412.38709)
			(xy 117.651464 -412.341231) (xy 117.687166 -412.300033) (xy 117.728367 -412.264337) (xy 117.77423 -412.234867)
			(xy 117.82382 -412.212225) (xy 117.876128 -412.196872) (xy 117.930089 -412.18912) (xy 117.957346 -412.18866)
			(xy 118.820946 -412.18866) (xy 118.848193 -412.189213) (xy 118.902131 -412.196975) (xy 118.954416 -412.212332)
			(xy 119.003983 -412.234974) (xy 119.049824 -412.264439) (xy 119.091005 -412.300128) (xy 119.126688 -412.341313)
			(xy 119.156148 -412.387157) (xy 119.178784 -412.436727) (xy 119.194135 -412.489014) (xy 119.20189 -412.542953)
			(xy 119.20189 -412.597447) (xy 119.201889 -412.597453) (xy 120.639546 -412.597453) (xy 120.639546 -412.542947)
			(xy 120.647303 -412.488996) (xy 120.662658 -412.436698) (xy 120.6853 -412.387118) (xy 120.714768 -412.341264)
			(xy 120.750461 -412.300071) (xy 120.791653 -412.264376) (xy 120.837505 -412.234907) (xy 120.887085 -412.212263)
			(xy 120.939382 -412.196906) (xy 120.993333 -412.189147) (xy 121.020586 -412.18866) (xy 121.884186 -412.18866)
			(xy 121.911437 -412.189186) (xy 121.965385 -412.196941) (xy 122.01768 -412.212295) (xy 122.067258 -412.234934)
			(xy 122.113109 -412.264399) (xy 122.1543 -412.30009) (xy 122.189992 -412.34128) (xy 122.219459 -412.38713)
			(xy 122.242101 -412.436707) (xy 122.257456 -412.489001) (xy 122.265213 -412.542949) (xy 122.265213 -412.597451)
			(xy 122.265212 -412.597456) (xy 123.702723 -412.597456) (xy 123.702723 -412.542944) (xy 123.710481 -412.488986)
			(xy 123.72584 -412.436681) (xy 123.748486 -412.387095) (xy 123.777959 -412.341237) (xy 123.813659 -412.30004)
			(xy 123.854858 -412.264344) (xy 123.900718 -412.234874) (xy 123.950306 -412.212231) (xy 124.002611 -412.196876)
			(xy 124.05657 -412.189121) (xy 124.083826 -412.18866) (xy 124.947426 -412.18866) (xy 124.974674 -412.189212)
			(xy 125.028614 -412.196971) (xy 125.080901 -412.212327) (xy 125.130471 -412.234968) (xy 125.176314 -412.264432)
			(xy 125.217498 -412.300121) (xy 125.253184 -412.341307) (xy 125.282645 -412.387152) (xy 125.305282 -412.436723)
			(xy 125.320635 -412.489011) (xy 125.32839 -412.542952) (xy 125.32839 -412.597448) (xy 125.328389 -412.597452)
			(xy 126.766046 -412.597452) (xy 126.766046 -412.542948) (xy 126.773802 -412.488999) (xy 126.789157 -412.436702)
			(xy 126.811797 -412.387123) (xy 126.841263 -412.341271) (xy 126.876954 -412.300078) (xy 126.918143 -412.264383)
			(xy 126.963993 -412.234914) (xy 127.01357 -412.212269) (xy 127.065865 -412.196909) (xy 127.119814 -412.189148)
			(xy 127.147066 -412.18866) (xy 128.010666 -412.18866) (xy 128.037918 -412.189185) (xy 128.091868 -412.196937)
			(xy 128.144166 -412.212289) (xy 128.193746 -412.234928) (xy 128.2396 -412.264392) (xy 128.280793 -412.300083)
			(xy 128.316487 -412.341273) (xy 128.345956 -412.387124) (xy 128.368599 -412.436702) (xy 128.383955 -412.488999)
			(xy 128.391713 -412.542948) (xy 128.391713 -412.597452) (xy 128.391713 -412.597455) (xy 129.829223 -412.597455)
			(xy 129.829223 -412.542945) (xy 129.836981 -412.488989) (xy 129.852338 -412.436686) (xy 129.874983 -412.387101)
			(xy 129.904454 -412.341244) (xy 129.940152 -412.300047) (xy 129.981349 -412.264351) (xy 130.027206 -412.23488)
			(xy 130.076791 -412.212236) (xy 130.129094 -412.196879) (xy 130.183051 -412.189123) (xy 130.210306 -412.18866)
			(xy 131.073906 -412.18866) (xy 131.101155 -412.189211) (xy 131.155097 -412.196967) (xy 131.207387 -412.212321)
			(xy 131.256959 -412.234961) (xy 131.302805 -412.264425) (xy 131.343991 -412.300113) (xy 131.379679 -412.3413)
			(xy 131.409142 -412.387146) (xy 131.431781 -412.436719) (xy 131.447134 -412.489009) (xy 131.45489 -412.542951)
			(xy 131.45489 -412.597449) (xy 131.454889 -412.597457) (xy 132.892423 -412.597457) (xy 132.892423 -412.542943)
			(xy 132.900182 -412.488983) (xy 132.915542 -412.436677) (xy 132.938189 -412.38709) (xy 132.967664 -412.341231)
			(xy 133.003366 -412.300033) (xy 133.044567 -412.264337) (xy 133.09043 -412.234867) (xy 133.14002 -412.212225)
			(xy 133.192328 -412.196872) (xy 133.246289 -412.18912) (xy 133.273546 -412.18866) (xy 134.137146 -412.18866)
			(xy 134.164393 -412.189213) (xy 134.218331 -412.196975) (xy 134.270616 -412.212332) (xy 134.320183 -412.234974)
			(xy 134.366024 -412.264439) (xy 134.407205 -412.300128) (xy 134.442888 -412.341313) (xy 134.472348 -412.387157)
			(xy 134.494984 -412.436727) (xy 134.510335 -412.489014) (xy 134.51809 -412.542953) (xy 134.51809 -412.597447)
			(xy 134.518089 -412.597453) (xy 135.955746 -412.597453) (xy 135.955746 -412.542947) (xy 135.963503 -412.488996)
			(xy 135.978858 -412.436698) (xy 136.0015 -412.387118) (xy 136.030968 -412.341264) (xy 136.066661 -412.300071)
			(xy 136.107853 -412.264376) (xy 136.153705 -412.234907) (xy 136.203285 -412.212263) (xy 136.255582 -412.196906)
			(xy 136.309533 -412.189147) (xy 136.336786 -412.18866) (xy 137.200386 -412.18866) (xy 137.227637 -412.189186)
			(xy 137.281585 -412.196941) (xy 137.33388 -412.212295) (xy 137.383458 -412.234934) (xy 137.429309 -412.264399)
			(xy 137.4705 -412.30009) (xy 137.506192 -412.34128) (xy 137.535659 -412.38713) (xy 137.558301 -412.436707)
			(xy 137.573656 -412.489001) (xy 137.581413 -412.542949) (xy 137.581413 -412.597451) (xy 137.581412 -412.597456)
			(xy 139.018923 -412.597456) (xy 139.018923 -412.542944) (xy 139.026681 -412.488986) (xy 139.04204 -412.436681)
			(xy 139.064686 -412.387095) (xy 139.094159 -412.341237) (xy 139.129859 -412.30004) (xy 139.171058 -412.264344)
			(xy 139.216918 -412.234874) (xy 139.266506 -412.212231) (xy 139.318811 -412.196876) (xy 139.37277 -412.189121)
			(xy 139.400026 -412.18866) (xy 140.263626 -412.18866) (xy 140.290874 -412.189212) (xy 140.344814 -412.196971)
			(xy 140.397101 -412.212327) (xy 140.446671 -412.234968) (xy 140.492514 -412.264432) (xy 140.533698 -412.300121)
			(xy 140.569384 -412.341307) (xy 140.598845 -412.387152) (xy 140.621482 -412.436723) (xy 140.636835 -412.489011)
			(xy 140.64459 -412.542952) (xy 140.64459 -412.597448) (xy 140.644589 -412.597452) (xy 142.082246 -412.597452)
			(xy 142.082246 -412.542948) (xy 142.090002 -412.488999) (xy 142.105357 -412.436702) (xy 142.127997 -412.387123)
			(xy 142.157463 -412.341271) (xy 142.193154 -412.300078) (xy 142.234343 -412.264383) (xy 142.280193 -412.234914)
			(xy 142.32977 -412.212269) (xy 142.382065 -412.196909) (xy 142.436014 -412.189148) (xy 142.463266 -412.18866)
			(xy 143.326866 -412.18866) (xy 143.354118 -412.189185) (xy 143.408068 -412.196937) (xy 143.460366 -412.212289)
			(xy 143.509946 -412.234928) (xy 143.5558 -412.264392) (xy 143.596993 -412.300083) (xy 143.632687 -412.341273)
			(xy 143.662156 -412.387124) (xy 143.684799 -412.436702) (xy 143.700155 -412.488999) (xy 143.707913 -412.542948)
			(xy 143.707913 -412.597452) (xy 143.707913 -412.597455) (xy 145.145423 -412.597455) (xy 145.145423 -412.542945)
			(xy 145.153181 -412.488989) (xy 145.168538 -412.436686) (xy 145.191183 -412.387101) (xy 145.220654 -412.341244)
			(xy 145.256352 -412.300047) (xy 145.297549 -412.264351) (xy 145.343406 -412.23488) (xy 145.392991 -412.212236)
			(xy 145.445294 -412.196879) (xy 145.499251 -412.189123) (xy 145.526506 -412.18866) (xy 146.390106 -412.18866)
			(xy 146.417355 -412.189211) (xy 146.471297 -412.196967) (xy 146.523587 -412.212321) (xy 146.573159 -412.234961)
			(xy 146.619005 -412.264425) (xy 146.660191 -412.300113) (xy 146.695879 -412.3413) (xy 146.725342 -412.387146)
			(xy 146.747981 -412.436719) (xy 146.763334 -412.489009) (xy 146.77109 -412.542951) (xy 146.77109 -412.597449)
			(xy 146.771089 -412.597457) (xy 148.208623 -412.597457) (xy 148.208623 -412.542943) (xy 148.216382 -412.488983)
			(xy 148.231742 -412.436677) (xy 148.254389 -412.38709) (xy 148.283864 -412.341231) (xy 148.319566 -412.300033)
			(xy 148.360767 -412.264337) (xy 148.40663 -412.234867) (xy 148.45622 -412.212225) (xy 148.508528 -412.196872)
			(xy 148.562489 -412.18912) (xy 148.589746 -412.18866) (xy 149.453346 -412.18866) (xy 149.480593 -412.189213)
			(xy 149.534531 -412.196975) (xy 149.586816 -412.212332) (xy 149.636383 -412.234974) (xy 149.682224 -412.264439)
			(xy 149.723405 -412.300128) (xy 149.759088 -412.341313) (xy 149.788548 -412.387157) (xy 149.811184 -412.436727)
			(xy 149.826535 -412.489014) (xy 149.83429 -412.542953) (xy 149.83429 -412.597447) (xy 149.834289 -412.597453)
			(xy 151.271946 -412.597453) (xy 151.271946 -412.542947) (xy 151.279703 -412.488996) (xy 151.295058 -412.436698)
			(xy 151.3177 -412.387118) (xy 151.347168 -412.341264) (xy 151.382861 -412.300071) (xy 151.424053 -412.264376)
			(xy 151.469905 -412.234907) (xy 151.519485 -412.212263) (xy 151.571782 -412.196906) (xy 151.625733 -412.189147)
			(xy 151.652986 -412.18866) (xy 152.516586 -412.18866) (xy 152.543837 -412.189186) (xy 152.597785 -412.196941)
			(xy 152.65008 -412.212295) (xy 152.699658 -412.234934) (xy 152.745509 -412.264399) (xy 152.7867 -412.30009)
			(xy 152.822392 -412.34128) (xy 152.851859 -412.38713) (xy 152.874501 -412.436707) (xy 152.889856 -412.489001)
			(xy 152.897613 -412.542949) (xy 152.897613 -412.597451) (xy 152.897612 -412.597456) (xy 154.335123 -412.597456)
			(xy 154.335123 -412.542944) (xy 154.342881 -412.488986) (xy 154.35824 -412.436681) (xy 154.380886 -412.387095)
			(xy 154.410359 -412.341237) (xy 154.446059 -412.30004) (xy 154.487258 -412.264344) (xy 154.533118 -412.234874)
			(xy 154.582706 -412.212231) (xy 154.635011 -412.196876) (xy 154.68897 -412.189121) (xy 154.716226 -412.18866)
			(xy 155.579826 -412.18866) (xy 155.607074 -412.189212) (xy 155.661014 -412.196971) (xy 155.713301 -412.212327)
			(xy 155.762871 -412.234968) (xy 155.808714 -412.264432) (xy 155.849898 -412.300121) (xy 155.885584 -412.341307)
			(xy 155.915045 -412.387152) (xy 155.937682 -412.436723) (xy 155.953035 -412.489011) (xy 155.96079 -412.542952)
			(xy 155.96079 -412.597448) (xy 155.960789 -412.597452) (xy 157.398446 -412.597452) (xy 157.398446 -412.542948)
			(xy 157.406202 -412.488999) (xy 157.421557 -412.436702) (xy 157.444197 -412.387123) (xy 157.473663 -412.341271)
			(xy 157.509354 -412.300078) (xy 157.550543 -412.264383) (xy 157.596393 -412.234914) (xy 157.64597 -412.212269)
			(xy 157.698265 -412.196909) (xy 157.752214 -412.189148) (xy 157.779466 -412.18866) (xy 158.643066 -412.18866)
			(xy 158.670318 -412.189185) (xy 158.724268 -412.196937) (xy 158.776566 -412.212289) (xy 158.826146 -412.234928)
			(xy 158.872 -412.264392) (xy 158.913193 -412.300083) (xy 158.948887 -412.341273) (xy 158.978356 -412.387124)
			(xy 159.000999 -412.436702) (xy 159.016355 -412.488999) (xy 159.024113 -412.542948) (xy 159.024113 -412.597452)
			(xy 159.024113 -412.597455) (xy 160.461623 -412.597455) (xy 160.461623 -412.542945) (xy 160.469381 -412.488989)
			(xy 160.484738 -412.436686) (xy 160.507383 -412.387101) (xy 160.536854 -412.341244) (xy 160.572552 -412.300047)
			(xy 160.613749 -412.264351) (xy 160.659606 -412.23488) (xy 160.709191 -412.212236) (xy 160.761494 -412.196879)
			(xy 160.815451 -412.189123) (xy 160.842706 -412.18866) (xy 161.706306 -412.18866) (xy 161.733555 -412.189211)
			(xy 161.787497 -412.196967) (xy 161.839787 -412.212321) (xy 161.889359 -412.234961) (xy 161.935205 -412.264425)
			(xy 161.976391 -412.300113) (xy 162.012079 -412.3413) (xy 162.041542 -412.387146) (xy 162.064181 -412.436719)
			(xy 162.079534 -412.489009) (xy 162.08729 -412.542951) (xy 162.08729 -412.597449) (xy 162.079534 -412.651391)
			(xy 162.064181 -412.703681) (xy 162.041542 -412.753254) (xy 162.012079 -412.7991) (xy 161.976391 -412.840287)
			(xy 161.935205 -412.875975) (xy 161.889359 -412.905439) (xy 161.839787 -412.928079) (xy 161.787497 -412.943433)
			(xy 161.733555 -412.951189) (xy 161.706306 -412.951676) (xy 160.842706 -412.951676) (xy 160.815451 -412.951277)
			(xy 160.761494 -412.943521) (xy 160.709191 -412.928164) (xy 160.659606 -412.90552) (xy 160.613749 -412.876049)
			(xy 160.572552 -412.840353) (xy 160.536854 -412.799156) (xy 160.507383 -412.753299) (xy 160.484738 -412.703714)
			(xy 160.469381 -412.651411) (xy 160.461623 -412.597455) (xy 159.024113 -412.597455) (xy 159.016355 -412.651402)
			(xy 159.000999 -412.703698) (xy 158.978356 -412.753276) (xy 158.948887 -412.799127) (xy 158.913193 -412.840317)
			(xy 158.872 -412.876008) (xy 158.826146 -412.905472) (xy 158.776566 -412.928111) (xy 158.724268 -412.943463)
			(xy 158.670318 -412.951215) (xy 158.643066 -412.951676) (xy 157.779466 -412.951676) (xy 157.752214 -412.951252)
			(xy 157.698265 -412.943491) (xy 157.64597 -412.928131) (xy 157.596393 -412.905486) (xy 157.550543 -412.876017)
			(xy 157.509354 -412.840322) (xy 157.473663 -412.799129) (xy 157.444197 -412.753277) (xy 157.421557 -412.703698)
			(xy 157.406202 -412.651401) (xy 157.398446 -412.597452) (xy 155.960789 -412.597452) (xy 155.953035 -412.651389)
			(xy 155.937682 -412.703677) (xy 155.915045 -412.753248) (xy 155.885584 -412.799093) (xy 155.849898 -412.840279)
			(xy 155.808714 -412.875968) (xy 155.762871 -412.905432) (xy 155.713301 -412.928073) (xy 155.661014 -412.943429)
			(xy 155.607074 -412.951188) (xy 155.579826 -412.951676) (xy 154.716226 -412.951676) (xy 154.68897 -412.951279)
			(xy 154.635011 -412.943524) (xy 154.582706 -412.928169) (xy 154.533118 -412.905526) (xy 154.487258 -412.876056)
			(xy 154.446059 -412.84036) (xy 154.410359 -412.799163) (xy 154.380886 -412.753305) (xy 154.35824 -412.703719)
			(xy 154.342881 -412.651414) (xy 154.335123 -412.597456) (xy 152.897612 -412.597456) (xy 152.889856 -412.651399)
			(xy 152.874501 -412.703693) (xy 152.851859 -412.75327) (xy 152.822392 -412.79912) (xy 152.7867 -412.84031)
			(xy 152.745509 -412.876001) (xy 152.699658 -412.905466) (xy 152.65008 -412.928105) (xy 152.597785 -412.943459)
			(xy 152.543837 -412.951214) (xy 152.516586 -412.951676) (xy 151.652986 -412.951676) (xy 151.625733 -412.951253)
			(xy 151.571782 -412.943494) (xy 151.519485 -412.928137) (xy 151.469905 -412.905493) (xy 151.424053 -412.876024)
			(xy 151.382861 -412.840329) (xy 151.347168 -412.799136) (xy 151.3177 -412.753282) (xy 151.295058 -412.703702)
			(xy 151.279703 -412.651404) (xy 151.271946 -412.597453) (xy 149.834289 -412.597453) (xy 149.826535 -412.651386)
			(xy 149.811184 -412.703673) (xy 149.788548 -412.753243) (xy 149.759088 -412.799087) (xy 149.723405 -412.840272)
			(xy 149.682224 -412.875961) (xy 149.636383 -412.905426) (xy 149.586816 -412.928068) (xy 149.534531 -412.943425)
			(xy 149.480593 -412.951187) (xy 149.453346 -412.951676) (xy 148.589746 -412.951676) (xy 148.562489 -412.95128)
			(xy 148.508528 -412.943528) (xy 148.45622 -412.928175) (xy 148.40663 -412.905533) (xy 148.360767 -412.876063)
			(xy 148.319566 -412.840367) (xy 148.283864 -412.799169) (xy 148.254389 -412.75331) (xy 148.231742 -412.703723)
			(xy 148.216382 -412.651417) (xy 148.208623 -412.597457) (xy 146.771089 -412.597457) (xy 146.763334 -412.651391)
			(xy 146.747981 -412.703681) (xy 146.725342 -412.753254) (xy 146.695879 -412.7991) (xy 146.660191 -412.840287)
			(xy 146.619005 -412.875975) (xy 146.573159 -412.905439) (xy 146.523587 -412.928079) (xy 146.471297 -412.943433)
			(xy 146.417355 -412.951189) (xy 146.390106 -412.951676) (xy 145.526506 -412.951676) (xy 145.499251 -412.951277)
			(xy 145.445294 -412.943521) (xy 145.392991 -412.928164) (xy 145.343406 -412.90552) (xy 145.297549 -412.876049)
			(xy 145.256352 -412.840353) (xy 145.220654 -412.799156) (xy 145.191183 -412.753299) (xy 145.168538 -412.703714)
			(xy 145.153181 -412.651411) (xy 145.145423 -412.597455) (xy 143.707913 -412.597455) (xy 143.700155 -412.651402)
			(xy 143.684799 -412.703698) (xy 143.662156 -412.753276) (xy 143.632687 -412.799127) (xy 143.596993 -412.840317)
			(xy 143.5558 -412.876008) (xy 143.509946 -412.905472) (xy 143.460366 -412.928111) (xy 143.408068 -412.943463)
			(xy 143.354118 -412.951215) (xy 143.326866 -412.951676) (xy 142.463266 -412.951676) (xy 142.436014 -412.951252)
			(xy 142.382065 -412.943491) (xy 142.32977 -412.928131) (xy 142.280193 -412.905486) (xy 142.234343 -412.876017)
			(xy 142.193154 -412.840322) (xy 142.157463 -412.799129) (xy 142.127997 -412.753277) (xy 142.105357 -412.703698)
			(xy 142.090002 -412.651401) (xy 142.082246 -412.597452) (xy 140.644589 -412.597452) (xy 140.636835 -412.651389)
			(xy 140.621482 -412.703677) (xy 140.598845 -412.753248) (xy 140.569384 -412.799093) (xy 140.533698 -412.840279)
			(xy 140.492514 -412.875968) (xy 140.446671 -412.905432) (xy 140.397101 -412.928073) (xy 140.344814 -412.943429)
			(xy 140.290874 -412.951188) (xy 140.263626 -412.951676) (xy 139.400026 -412.951676) (xy 139.37277 -412.951279)
			(xy 139.318811 -412.943524) (xy 139.266506 -412.928169) (xy 139.216918 -412.905526) (xy 139.171058 -412.876056)
			(xy 139.129859 -412.84036) (xy 139.094159 -412.799163) (xy 139.064686 -412.753305) (xy 139.04204 -412.703719)
			(xy 139.026681 -412.651414) (xy 139.018923 -412.597456) (xy 137.581412 -412.597456) (xy 137.573656 -412.651399)
			(xy 137.558301 -412.703693) (xy 137.535659 -412.75327) (xy 137.506192 -412.79912) (xy 137.4705 -412.84031)
			(xy 137.429309 -412.876001) (xy 137.383458 -412.905466) (xy 137.33388 -412.928105) (xy 137.281585 -412.943459)
			(xy 137.227637 -412.951214) (xy 137.200386 -412.951676) (xy 136.336786 -412.951676) (xy 136.309533 -412.951253)
			(xy 136.255582 -412.943494) (xy 136.203285 -412.928137) (xy 136.153705 -412.905493) (xy 136.107853 -412.876024)
			(xy 136.066661 -412.840329) (xy 136.030968 -412.799136) (xy 136.0015 -412.753282) (xy 135.978858 -412.703702)
			(xy 135.963503 -412.651404) (xy 135.955746 -412.597453) (xy 134.518089 -412.597453) (xy 134.510335 -412.651386)
			(xy 134.494984 -412.703673) (xy 134.472348 -412.753243) (xy 134.442888 -412.799087) (xy 134.407205 -412.840272)
			(xy 134.366024 -412.875961) (xy 134.320183 -412.905426) (xy 134.270616 -412.928068) (xy 134.218331 -412.943425)
			(xy 134.164393 -412.951187) (xy 134.137146 -412.951676) (xy 133.273546 -412.951676) (xy 133.246289 -412.95128)
			(xy 133.192328 -412.943528) (xy 133.14002 -412.928175) (xy 133.09043 -412.905533) (xy 133.044567 -412.876063)
			(xy 133.003366 -412.840367) (xy 132.967664 -412.799169) (xy 132.938189 -412.75331) (xy 132.915542 -412.703723)
			(xy 132.900182 -412.651417) (xy 132.892423 -412.597457) (xy 131.454889 -412.597457) (xy 131.447134 -412.651391)
			(xy 131.431781 -412.703681) (xy 131.409142 -412.753254) (xy 131.379679 -412.7991) (xy 131.343991 -412.840287)
			(xy 131.302805 -412.875975) (xy 131.256959 -412.905439) (xy 131.207387 -412.928079) (xy 131.155097 -412.943433)
			(xy 131.101155 -412.951189) (xy 131.073906 -412.951676) (xy 130.210306 -412.951676) (xy 130.183051 -412.951277)
			(xy 130.129094 -412.943521) (xy 130.076791 -412.928164) (xy 130.027206 -412.90552) (xy 129.981349 -412.876049)
			(xy 129.940152 -412.840353) (xy 129.904454 -412.799156) (xy 129.874983 -412.753299) (xy 129.852338 -412.703714)
			(xy 129.836981 -412.651411) (xy 129.829223 -412.597455) (xy 128.391713 -412.597455) (xy 128.383955 -412.651402)
			(xy 128.368599 -412.703698) (xy 128.345956 -412.753276) (xy 128.316487 -412.799127) (xy 128.280793 -412.840317)
			(xy 128.2396 -412.876008) (xy 128.193746 -412.905472) (xy 128.144166 -412.928111) (xy 128.091868 -412.943463)
			(xy 128.037918 -412.951215) (xy 128.010666 -412.951676) (xy 127.147066 -412.951676) (xy 127.119814 -412.951252)
			(xy 127.065865 -412.943491) (xy 127.01357 -412.928131) (xy 126.963993 -412.905486) (xy 126.918143 -412.876017)
			(xy 126.876954 -412.840322) (xy 126.841263 -412.799129) (xy 126.811797 -412.753277) (xy 126.789157 -412.703698)
			(xy 126.773802 -412.651401) (xy 126.766046 -412.597452) (xy 125.328389 -412.597452) (xy 125.320635 -412.651389)
			(xy 125.305282 -412.703677) (xy 125.282645 -412.753248) (xy 125.253184 -412.799093) (xy 125.217498 -412.840279)
			(xy 125.176314 -412.875968) (xy 125.130471 -412.905432) (xy 125.080901 -412.928073) (xy 125.028614 -412.943429)
			(xy 124.974674 -412.951188) (xy 124.947426 -412.951676) (xy 124.083826 -412.951676) (xy 124.05657 -412.951279)
			(xy 124.002611 -412.943524) (xy 123.950306 -412.928169) (xy 123.900718 -412.905526) (xy 123.854858 -412.876056)
			(xy 123.813659 -412.84036) (xy 123.777959 -412.799163) (xy 123.748486 -412.753305) (xy 123.72584 -412.703719)
			(xy 123.710481 -412.651414) (xy 123.702723 -412.597456) (xy 122.265212 -412.597456) (xy 122.257456 -412.651399)
			(xy 122.242101 -412.703693) (xy 122.219459 -412.75327) (xy 122.189992 -412.79912) (xy 122.1543 -412.84031)
			(xy 122.113109 -412.876001) (xy 122.067258 -412.905466) (xy 122.01768 -412.928105) (xy 121.965385 -412.943459)
			(xy 121.911437 -412.951214) (xy 121.884186 -412.951676) (xy 121.020586 -412.951676) (xy 120.993333 -412.951253)
			(xy 120.939382 -412.943494) (xy 120.887085 -412.928137) (xy 120.837505 -412.905493) (xy 120.791653 -412.876024)
			(xy 120.750461 -412.840329) (xy 120.714768 -412.799136) (xy 120.6853 -412.753282) (xy 120.662658 -412.703702)
			(xy 120.647303 -412.651404) (xy 120.639546 -412.597453) (xy 119.201889 -412.597453) (xy 119.194135 -412.651386)
			(xy 119.178784 -412.703673) (xy 119.156148 -412.753243) (xy 119.126688 -412.799087) (xy 119.091005 -412.840272)
			(xy 119.049824 -412.875961) (xy 119.003983 -412.905426) (xy 118.954416 -412.928068) (xy 118.902131 -412.943425)
			(xy 118.848193 -412.951187) (xy 118.820946 -412.951676) (xy 117.957346 -412.951676) (xy 117.930089 -412.95128)
			(xy 117.876128 -412.943528) (xy 117.82382 -412.928175) (xy 117.77423 -412.905533) (xy 117.728367 -412.876063)
			(xy 117.687166 -412.840367) (xy 117.651464 -412.799169) (xy 117.621989 -412.75331) (xy 117.599342 -412.703723)
			(xy 117.583982 -412.651417) (xy 117.576223 -412.597457) (xy 116.138689 -412.597457) (xy 116.130934 -412.651391)
			(xy 116.115581 -412.703681) (xy 116.092942 -412.753254) (xy 116.063479 -412.7991) (xy 116.027791 -412.840287)
			(xy 115.986605 -412.875975) (xy 115.940759 -412.905439) (xy 115.891187 -412.928079) (xy 115.838897 -412.943433)
			(xy 115.784955 -412.951189) (xy 115.757706 -412.951676) (xy 114.894106 -412.951676) (xy 114.866851 -412.951277)
			(xy 114.812894 -412.943521) (xy 114.760591 -412.928164) (xy 114.711006 -412.90552) (xy 114.665149 -412.876049)
			(xy 114.623952 -412.840353) (xy 114.588254 -412.799156) (xy 114.558783 -412.753299) (xy 114.536138 -412.703714)
			(xy 114.520781 -412.651411) (xy 114.513023 -412.597455) (xy 94.987413 -412.597455) (xy 94.979655 -412.651402)
			(xy 94.964299 -412.703698) (xy 94.941656 -412.753276) (xy 94.912187 -412.799127) (xy 94.876492 -412.840318)
			(xy 94.835299 -412.876008) (xy 94.789445 -412.905473) (xy 94.739864 -412.928111) (xy 94.687567 -412.943463)
			(xy 94.633616 -412.951215) (xy 94.606364 -412.951676) (xy 93.742764 -412.951676) (xy 93.715512 -412.951252)
			(xy 93.661564 -412.94349) (xy 93.609269 -412.928131) (xy 93.559692 -412.905486) (xy 93.513842 -412.876016)
			(xy 93.472653 -412.840321) (xy 93.436962 -412.799129) (xy 93.407497 -412.753276) (xy 93.384857 -412.703697)
			(xy 93.369502 -412.651401) (xy 93.361746 -412.597452) (xy 91.924089 -412.597452) (xy 91.916335 -412.651389)
			(xy 91.900982 -412.703677) (xy 91.878345 -412.753249) (xy 91.848883 -412.799094) (xy 91.813197 -412.84028)
			(xy 91.772013 -412.875969) (xy 91.72617 -412.905433) (xy 91.6766 -412.928074) (xy 91.624312 -412.94343)
			(xy 91.570372 -412.951188) (xy 91.543124 -412.951676) (xy 90.679524 -412.951676) (xy 90.652268 -412.951279)
			(xy 90.59831 -412.943524) (xy 90.546004 -412.928169) (xy 90.496417 -412.905526) (xy 90.450557 -412.876056)
			(xy 90.409358 -412.840359) (xy 90.373659 -412.799162) (xy 90.344186 -412.753304) (xy 90.32154 -412.703718)
			(xy 90.306181 -412.651414) (xy 90.298423 -412.597456) (xy 88.860912 -412.597456) (xy 88.853156 -412.651399)
			(xy 88.8378 -412.703694) (xy 88.815159 -412.753271) (xy 88.785692 -412.799121) (xy 88.749999 -412.840311)
			(xy 88.708808 -412.876001) (xy 88.662957 -412.905466) (xy 88.613379 -412.928106) (xy 88.561083 -412.943459)
			(xy 88.507135 -412.951214) (xy 88.479884 -412.951676) (xy 87.616284 -412.951676) (xy 87.589031 -412.951253)
			(xy 87.535081 -412.943494) (xy 87.482783 -412.928136) (xy 87.433204 -412.905492) (xy 87.387352 -412.876023)
			(xy 87.34616 -412.840329) (xy 87.310467 -412.799135) (xy 87.281 -412.753282) (xy 87.258358 -412.703702)
			(xy 87.243003 -412.651404) (xy 87.235246 -412.597453) (xy 85.797589 -412.597453) (xy 85.789835 -412.651386)
			(xy 85.774484 -412.703673) (xy 85.751848 -412.753243) (xy 85.722388 -412.799087) (xy 85.686704 -412.840273)
			(xy 85.645523 -412.875962) (xy 85.599682 -412.905427) (xy 85.550114 -412.928068) (xy 85.497829 -412.943426)
			(xy 85.443891 -412.951187) (xy 85.416644 -412.951676) (xy 84.553044 -412.951676) (xy 84.525787 -412.95128)
			(xy 84.471827 -412.943528) (xy 84.419519 -412.928174) (xy 84.369929 -412.905532) (xy 84.324067 -412.876063)
			(xy 84.282865 -412.840366) (xy 84.247164 -412.799169) (xy 84.217689 -412.75331) (xy 84.195041 -412.703722)
			(xy 84.179682 -412.651417) (xy 84.171923 -412.597457) (xy 82.734389 -412.597457) (xy 82.726634 -412.651392)
			(xy 82.71128 -412.703682) (xy 82.688642 -412.753254) (xy 82.659178 -412.799101) (xy 82.62349 -412.840287)
			(xy 82.582304 -412.875976) (xy 82.536458 -412.90544) (xy 82.486885 -412.928079) (xy 82.434595 -412.943433)
			(xy 82.380653 -412.95119) (xy 82.353404 -412.951676) (xy 81.489804 -412.951676) (xy 81.462549 -412.951277)
			(xy 81.408593 -412.94352) (xy 81.35629 -412.928163) (xy 81.306705 -412.905519) (xy 81.260848 -412.876049)
			(xy 81.219651 -412.840352) (xy 81.183954 -412.799156) (xy 81.154483 -412.753298) (xy 81.131838 -412.703714)
			(xy 81.116481 -412.651411) (xy 81.108723 -412.597455) (xy 79.671213 -412.597455) (xy 79.663455 -412.651402)
			(xy 79.648099 -412.703698) (xy 79.625456 -412.753276) (xy 79.595987 -412.799127) (xy 79.560292 -412.840318)
			(xy 79.519099 -412.876008) (xy 79.473245 -412.905473) (xy 79.423664 -412.928111) (xy 79.371367 -412.943463)
			(xy 79.317416 -412.951215) (xy 79.290164 -412.951676) (xy 78.426564 -412.951676) (xy 78.399312 -412.951252)
			(xy 78.345364 -412.94349) (xy 78.293069 -412.928131) (xy 78.243492 -412.905486) (xy 78.197642 -412.876016)
			(xy 78.156453 -412.840321) (xy 78.120762 -412.799129) (xy 78.091297 -412.753276) (xy 78.068657 -412.703697)
			(xy 78.053302 -412.651401) (xy 78.045546 -412.597452) (xy 76.607889 -412.597452) (xy 76.600135 -412.651389)
			(xy 76.584782 -412.703677) (xy 76.562145 -412.753249) (xy 76.532683 -412.799094) (xy 76.496997 -412.84028)
			(xy 76.455813 -412.875969) (xy 76.40997 -412.905433) (xy 76.3604 -412.928074) (xy 76.308112 -412.94343)
			(xy 76.254172 -412.951188) (xy 76.226924 -412.951676) (xy 75.363324 -412.951676) (xy 75.336068 -412.951279)
			(xy 75.28211 -412.943524) (xy 75.229804 -412.928169) (xy 75.180217 -412.905526) (xy 75.134357 -412.876056)
			(xy 75.093158 -412.840359) (xy 75.057459 -412.799162) (xy 75.027986 -412.753304) (xy 75.00534 -412.703718)
			(xy 74.989981 -412.651414) (xy 74.982223 -412.597456) (xy 73.544712 -412.597456) (xy 73.536956 -412.651399)
			(xy 73.5216 -412.703694) (xy 73.498959 -412.753271) (xy 73.469492 -412.799121) (xy 73.433799 -412.840311)
			(xy 73.392608 -412.876001) (xy 73.346757 -412.905466) (xy 73.297179 -412.928106) (xy 73.244883 -412.943459)
			(xy 73.190935 -412.951214) (xy 73.163684 -412.951676) (xy 72.300084 -412.951676) (xy 72.272831 -412.951253)
			(xy 72.218881 -412.943494) (xy 72.166583 -412.928136) (xy 72.117004 -412.905492) (xy 72.071152 -412.876023)
			(xy 72.02996 -412.840329) (xy 71.994267 -412.799135) (xy 71.9648 -412.753282) (xy 71.942158 -412.703702)
			(xy 71.926803 -412.651404) (xy 71.919046 -412.597453) (xy 70.481389 -412.597453) (xy 70.473635 -412.651386)
			(xy 70.458284 -412.703673) (xy 70.435648 -412.753243) (xy 70.406188 -412.799087) (xy 70.370504 -412.840273)
			(xy 70.329323 -412.875962) (xy 70.283482 -412.905427) (xy 70.233914 -412.928068) (xy 70.181629 -412.943426)
			(xy 70.127691 -412.951187) (xy 70.100444 -412.951676) (xy 69.236844 -412.951676) (xy 69.209587 -412.95128)
			(xy 69.155627 -412.943528) (xy 69.103319 -412.928174) (xy 69.053729 -412.905532) (xy 69.007867 -412.876063)
			(xy 68.966665 -412.840366) (xy 68.930964 -412.799169) (xy 68.901489 -412.75331) (xy 68.878841 -412.703722)
			(xy 68.863482 -412.651417) (xy 68.855723 -412.597457) (xy 67.418189 -412.597457) (xy 67.410434 -412.651392)
			(xy 67.39508 -412.703682) (xy 67.372442 -412.753254) (xy 67.342978 -412.799101) (xy 67.30729 -412.840287)
			(xy 67.266104 -412.875976) (xy 67.220258 -412.90544) (xy 67.170685 -412.928079) (xy 67.118395 -412.943433)
			(xy 67.064453 -412.95119) (xy 67.037204 -412.951676) (xy 66.173604 -412.951676) (xy 66.146349 -412.951277)
			(xy 66.092393 -412.94352) (xy 66.04009 -412.928163) (xy 65.990505 -412.905519) (xy 65.944648 -412.876049)
			(xy 65.903451 -412.840352) (xy 65.867754 -412.799156) (xy 65.838283 -412.753298) (xy 65.815638 -412.703714)
			(xy 65.800281 -412.651411) (xy 65.792523 -412.597455) (xy 64.355013 -412.597455) (xy 64.347255 -412.651402)
			(xy 64.331899 -412.703698) (xy 64.309256 -412.753276) (xy 64.279787 -412.799127) (xy 64.244092 -412.840318)
			(xy 64.202899 -412.876008) (xy 64.157045 -412.905473) (xy 64.107464 -412.928111) (xy 64.055167 -412.943463)
			(xy 64.001216 -412.951215) (xy 63.973964 -412.951676) (xy 63.110364 -412.951676) (xy 63.083112 -412.951252)
			(xy 63.029164 -412.94349) (xy 62.976869 -412.928131) (xy 62.927292 -412.905486) (xy 62.881442 -412.876016)
			(xy 62.840253 -412.840321) (xy 62.804562 -412.799129) (xy 62.775097 -412.753276) (xy 62.752457 -412.703697)
			(xy 62.737102 -412.651401) (xy 62.729346 -412.597452) (xy 61.291689 -412.597452) (xy 61.283935 -412.651389)
			(xy 61.268582 -412.703677) (xy 61.245945 -412.753249) (xy 61.216483 -412.799094) (xy 61.180797 -412.84028)
			(xy 61.139613 -412.875969) (xy 61.09377 -412.905433) (xy 61.0442 -412.928074) (xy 60.991912 -412.94343)
			(xy 60.937972 -412.951188) (xy 60.910724 -412.951676) (xy 60.047124 -412.951676) (xy 60.019868 -412.951279)
			(xy 59.96591 -412.943524) (xy 59.913604 -412.928169) (xy 59.864017 -412.905526) (xy 59.818157 -412.876056)
			(xy 59.776958 -412.840359) (xy 59.741259 -412.799162) (xy 59.711786 -412.753304) (xy 59.68914 -412.703718)
			(xy 59.673781 -412.651414) (xy 59.666023 -412.597456) (xy 58.228512 -412.597456) (xy 58.220756 -412.651399)
			(xy 58.2054 -412.703694) (xy 58.182759 -412.753271) (xy 58.153292 -412.799121) (xy 58.117599 -412.840311)
			(xy 58.076408 -412.876001) (xy 58.030557 -412.905466) (xy 57.980979 -412.928106) (xy 57.928683 -412.943459)
			(xy 57.874735 -412.951214) (xy 57.847484 -412.951676) (xy 56.983884 -412.951676) (xy 56.956631 -412.951253)
			(xy 56.902681 -412.943494) (xy 56.850383 -412.928136) (xy 56.800804 -412.905492) (xy 56.754952 -412.876023)
			(xy 56.71376 -412.840329) (xy 56.678067 -412.799135) (xy 56.6486 -412.753282) (xy 56.625958 -412.703702)
			(xy 56.610603 -412.651404) (xy 56.602846 -412.597453) (xy 55.165189 -412.597453) (xy 55.157435 -412.651386)
			(xy 55.142084 -412.703673) (xy 55.119448 -412.753243) (xy 55.089988 -412.799087) (xy 55.054304 -412.840273)
			(xy 55.013123 -412.875962) (xy 54.967282 -412.905427) (xy 54.917714 -412.928068) (xy 54.865429 -412.943426)
			(xy 54.811491 -412.951187) (xy 54.784244 -412.951676) (xy 53.920644 -412.951676) (xy 53.893387 -412.95128)
			(xy 53.839427 -412.943528) (xy 53.787119 -412.928174) (xy 53.737529 -412.905532) (xy 53.691667 -412.876063)
			(xy 53.650465 -412.840366) (xy 53.614764 -412.799169) (xy 53.585289 -412.75331) (xy 53.562641 -412.703722)
			(xy 53.547282 -412.651417) (xy 53.539523 -412.597457) (xy 52.101989 -412.597457) (xy 52.094234 -412.651392)
			(xy 52.07888 -412.703682) (xy 52.056242 -412.753254) (xy 52.026778 -412.799101) (xy 51.99109 -412.840287)
			(xy 51.949904 -412.875976) (xy 51.904058 -412.90544) (xy 51.854485 -412.928079) (xy 51.802195 -412.943433)
			(xy 51.748253 -412.95119) (xy 51.721004 -412.951676) (xy 50.857404 -412.951676) (xy 50.830149 -412.951277)
			(xy 50.776193 -412.94352) (xy 50.72389 -412.928163) (xy 50.674305 -412.905519) (xy 50.628448 -412.876049)
			(xy 50.587251 -412.840352) (xy 50.551554 -412.799156) (xy 50.522083 -412.753298) (xy 50.499438 -412.703714)
			(xy 50.484081 -412.651411) (xy 50.476323 -412.597455) (xy 49.038813 -412.597455) (xy 49.031055 -412.651402)
			(xy 49.015699 -412.703698) (xy 48.993056 -412.753276) (xy 48.963587 -412.799127) (xy 48.927892 -412.840318)
			(xy 48.886699 -412.876008) (xy 48.840845 -412.905473) (xy 48.791264 -412.928111) (xy 48.738967 -412.943463)
			(xy 48.685016 -412.951215) (xy 48.657764 -412.951676) (xy 47.794164 -412.951676) (xy 47.766912 -412.951252)
			(xy 47.712964 -412.94349) (xy 47.660669 -412.928131) (xy 47.611092 -412.905486) (xy 47.565242 -412.876016)
			(xy 47.524053 -412.840321) (xy 47.488362 -412.799129) (xy 47.458897 -412.753276) (xy 47.436257 -412.703697)
			(xy 47.420902 -412.651401) (xy 47.413146 -412.597452) (xy 39.737792 -412.597452) (xy 39.737792 -413.4485)
			(xy 39.737556 -413.461769) (xy 105.629431 -413.461769) (xy 105.629431 -413.407231) (xy 105.637193 -413.353247)
			(xy 105.652559 -413.300918) (xy 105.675215 -413.251308) (xy 105.704702 -413.205427) (xy 105.740417 -413.16421)
			(xy 105.781635 -413.128496) (xy 105.827517 -413.099011) (xy 105.877127 -413.076355) (xy 105.929457 -413.060991)
			(xy 105.983441 -413.053231) (xy 106.01071 -413.052768) (xy 106.87431 -413.052768) (xy 106.901581 -413.053195)
			(xy 106.955568 -413.060959) (xy 107.0079 -413.076326) (xy 107.057513 -413.098985) (xy 107.103396 -413.128473)
			(xy 107.144616 -413.164191) (xy 107.180333 -413.205412) (xy 107.20982 -413.251296) (xy 107.232477 -413.300909)
			(xy 107.247844 -413.353242) (xy 107.255606 -413.407229) (xy 107.255606 -413.461771) (xy 107.247844 -413.515758)
			(xy 107.232477 -413.568091) (xy 107.20982 -413.617704) (xy 107.180333 -413.663588) (xy 107.144616 -413.704809)
			(xy 107.103396 -413.740527) (xy 107.057513 -413.770015) (xy 107.0079 -413.792674) (xy 106.955568 -413.808041)
			(xy 106.901581 -413.815805) (xy 106.87431 -413.816292) (xy 106.01071 -413.816292) (xy 105.983441 -413.815769)
			(xy 105.929457 -413.808009) (xy 105.877127 -413.792645) (xy 105.827517 -413.769989) (xy 105.781635 -413.740504)
			(xy 105.740417 -413.70479) (xy 105.704702 -413.663573) (xy 105.675215 -413.617692) (xy 105.652559 -413.568082)
			(xy 105.637193 -413.515753) (xy 105.629431 -413.461769) (xy 39.737556 -413.461769) (xy 39.737306 -413.475769)
			(xy 39.729544 -413.529753) (xy 39.714179 -413.582083) (xy 39.691522 -413.631693) (xy 39.662036 -413.677574)
			(xy 39.626321 -413.718791) (xy 39.585104 -413.754506) (xy 39.539223 -413.783992) (xy 39.489613 -413.806649)
			(xy 39.437283 -413.822014) (xy 39.383299 -413.829776) (xy 39.328761 -413.829776) (xy 39.274777 -413.822014)
			(xy 39.222447 -413.806649) (xy 39.172837 -413.783992) (xy 39.126956 -413.754506) (xy 39.085739 -413.718791)
			(xy 39.050024 -413.677574) (xy 39.020538 -413.631693) (xy 38.997881 -413.582083) (xy 38.982516 -413.529753)
			(xy 38.974754 -413.475769) (xy 38.974268 -413.4485) (xy 7.00913 -413.4485) (xy 7.00913 -415.383726)
			(xy 41.206928 -415.383726) (xy 41.206928 -414.520126) (xy 41.207414 -414.492857) (xy 41.215176 -414.438873)
			(xy 41.230541 -414.386543) (xy 41.253198 -414.336933) (xy 41.282684 -414.291052) (xy 41.318399 -414.249835)
			(xy 41.359616 -414.21412) (xy 41.405497 -414.184634) (xy 41.455107 -414.161977) (xy 41.507437 -414.146612)
			(xy 41.561421 -414.13885) (xy 41.615959 -414.13885) (xy 41.669943 -414.146612) (xy 41.722273 -414.161977)
			(xy 41.771883 -414.184634) (xy 41.817764 -414.21412) (xy 41.858981 -414.249835) (xy 41.894696 -414.291052)
			(xy 41.924182 -414.336933) (xy 41.946839 -414.386543) (xy 41.962204 -414.438873) (xy 41.969966 -414.492857)
			(xy 41.970452 -414.520126) (xy 41.970452 -415.383726) (xy 41.969966 -415.410995) (xy 41.962204 -415.464979)
			(xy 41.946839 -415.517309) (xy 41.924182 -415.566919) (xy 41.894696 -415.6128) (xy 41.858981 -415.654017)
			(xy 41.817764 -415.689732) (xy 41.771883 -415.719218) (xy 41.722273 -415.741875) (xy 41.669943 -415.75724)
			(xy 41.615959 -415.765002) (xy 41.561421 -415.765002) (xy 41.507437 -415.75724) (xy 41.455107 -415.741875)
			(xy 41.405497 -415.719218) (xy 41.359616 -415.689732) (xy 41.318399 -415.654017) (xy 41.282684 -415.6128)
			(xy 41.253198 -415.566919) (xy 41.230541 -415.517309) (xy 41.215176 -415.464979) (xy 41.207414 -415.410995)
			(xy 41.206928 -415.383726) (xy 7.00913 -415.383726) (xy 7.00913 -417.465002) (xy 35.832796 -417.465002)
			(xy 35.832796 -416.601402) (xy 35.833282 -416.574151) (xy 35.841038 -416.520203) (xy 35.856393 -416.467908)
			(xy 35.879035 -416.418331) (xy 35.908501 -416.372481) (xy 35.944192 -416.33129) (xy 35.985383 -416.295599)
			(xy 36.031233 -416.266133) (xy 36.08081 -416.243491) (xy 36.133105 -416.228136) (xy 36.187053 -416.22038)
			(xy 36.241555 -416.22038) (xy 36.295503 -416.228136) (xy 36.347798 -416.243491) (xy 36.397375 -416.266133)
			(xy 36.443225 -416.295599) (xy 36.484416 -416.33129) (xy 36.520107 -416.372481) (xy 36.549573 -416.418331)
			(xy 36.572215 -416.467908) (xy 36.58757 -416.520203) (xy 36.595326 -416.574151) (xy 36.595812 -416.601402)
			(xy 36.595812 -417.436808) (xy 48.812704 -417.436808) (xy 48.812704 -416.573208) (xy 48.81319 -416.545939)
			(xy 48.820952 -416.491955) (xy 48.836317 -416.439625) (xy 48.858974 -416.390015) (xy 48.88846 -416.344134)
			(xy 48.924175 -416.302917) (xy 48.965392 -416.267202) (xy 49.011273 -416.237716) (xy 49.060883 -416.215059)
			(xy 49.113213 -416.199694) (xy 49.167197 -416.191932) (xy 49.221735 -416.191932) (xy 49.275719 -416.199694)
			(xy 49.328049 -416.215059) (xy 49.377659 -416.237716) (xy 49.42354 -416.267202) (xy 49.464757 -416.302917)
			(xy 49.500472 -416.344134) (xy 49.529958 -416.390015) (xy 49.552615 -416.439625) (xy 49.56798 -416.491955)
			(xy 49.575742 -416.545939) (xy 49.576228 -416.573208) (xy 49.576228 -417.436808) (xy 49.575742 -417.464077)
			(xy 49.56798 -417.518061) (xy 49.552615 -417.570391) (xy 49.529958 -417.620001) (xy 49.500472 -417.665882)
			(xy 49.464757 -417.707099) (xy 49.42354 -417.742814) (xy 49.377659 -417.7723) (xy 49.328049 -417.794957)
			(xy 49.275719 -417.810322) (xy 49.221735 -417.818084) (xy 49.167197 -417.818084) (xy 49.113213 -417.810322)
			(xy 49.060883 -417.794957) (xy 49.011273 -417.7723) (xy 48.965392 -417.742814) (xy 48.924175 -417.707099)
			(xy 48.88846 -417.665882) (xy 48.858974 -417.620001) (xy 48.836317 -417.570391) (xy 48.820952 -417.518061)
			(xy 48.81319 -417.464077) (xy 48.812704 -417.436808) (xy 36.595812 -417.436808) (xy 36.595812 -417.465002)
			(xy 36.595326 -417.492253) (xy 36.58757 -417.546201) (xy 36.572215 -417.598496) (xy 36.549573 -417.648073)
			(xy 36.520107 -417.693923) (xy 36.484416 -417.735114) (xy 36.443225 -417.770805) (xy 36.397375 -417.800271)
			(xy 36.347798 -417.822913) (xy 36.295503 -417.838268) (xy 36.241555 -417.846024) (xy 36.187053 -417.846024)
			(xy 36.133105 -417.838268) (xy 36.08081 -417.822913) (xy 36.031233 -417.800271) (xy 35.985383 -417.770805)
			(xy 35.944192 -417.735114) (xy 35.908501 -417.693923) (xy 35.879035 -417.648073) (xy 35.856393 -417.598496)
			(xy 35.841038 -417.546201) (xy 35.833282 -417.492253) (xy 35.832796 -417.465002) (xy 7.00913 -417.465002)
			(xy 7.00913 -419.64102) (xy 51.809904 -419.64102) (xy 51.809904 -418.77742) (xy 51.81039 -418.750151)
			(xy 51.818152 -418.696167) (xy 51.833517 -418.643837) (xy 51.856174 -418.594227) (xy 51.88566 -418.548346)
			(xy 51.921375 -418.507129) (xy 51.962592 -418.471414) (xy 52.008473 -418.441928) (xy 52.058083 -418.419271)
			(xy 52.110413 -418.403906) (xy 52.164397 -418.396144) (xy 52.218935 -418.396144) (xy 52.272919 -418.403906)
			(xy 52.325249 -418.419271) (xy 52.374859 -418.441928) (xy 52.42074 -418.471414) (xy 52.461957 -418.507129)
			(xy 52.497672 -418.548346) (xy 52.527158 -418.594227) (xy 52.549815 -418.643837) (xy 52.56518 -418.696167)
			(xy 52.572942 -418.750151) (xy 52.573428 -418.77742) (xy 52.573428 -419.64102) (xy 52.572942 -419.668289)
			(xy 52.56518 -419.722273) (xy 52.549815 -419.774603) (xy 52.527158 -419.824213) (xy 52.497672 -419.870094)
			(xy 52.461957 -419.911311) (xy 52.42074 -419.947026) (xy 52.374859 -419.976512) (xy 52.325249 -419.999169)
			(xy 52.272919 -420.014534) (xy 52.218935 -420.022296) (xy 52.164397 -420.022296) (xy 52.110413 -420.014534)
			(xy 52.058083 -419.999169) (xy 52.008473 -419.976512) (xy 51.962592 -419.947026) (xy 51.921375 -419.911311)
			(xy 51.88566 -419.870094) (xy 51.856174 -419.824213) (xy 51.833517 -419.774603) (xy 51.818152 -419.722273)
			(xy 51.81039 -419.668289) (xy 51.809904 -419.64102) (xy 7.00913 -419.64102) (xy 7.00913 -421.200326)
			(xy 10.01268 -421.200326) (xy 10.01268 -420.336726) (xy 10.013166 -420.309475) (xy 10.020922 -420.255527)
			(xy 10.036277 -420.203232) (xy 10.058919 -420.153655) (xy 10.088385 -420.107805) (xy 10.124076 -420.066614)
			(xy 10.165267 -420.030923) (xy 10.211117 -420.001457) (xy 10.260694 -419.978815) (xy 10.312989 -419.96346)
			(xy 10.366937 -419.955704) (xy 10.421439 -419.955704) (xy 10.475387 -419.96346) (xy 10.527682 -419.978815)
			(xy 10.577259 -420.001457) (xy 10.623109 -420.030923) (xy 10.6643 -420.066614) (xy 10.699991 -420.107805)
			(xy 10.729457 -420.153655) (xy 10.752099 -420.203232) (xy 10.767454 -420.255527) (xy 10.77521 -420.309475)
			(xy 10.775696 -420.336726) (xy 10.775696 -421.200326) (xy 10.77521 -421.227577) (xy 10.769122 -421.269922)
			(xy 21.420836 -421.269922) (xy 21.420836 -420.406322) (xy 21.421322 -420.379071) (xy 21.429078 -420.325123)
			(xy 21.444433 -420.272828) (xy 21.467075 -420.223251) (xy 21.496541 -420.177401) (xy 21.532232 -420.13621)
			(xy 21.573423 -420.100519) (xy 21.619273 -420.071053) (xy 21.66885 -420.048411) (xy 21.721145 -420.033056)
			(xy 21.775093 -420.0253) (xy 21.829595 -420.0253) (xy 21.883543 -420.033056) (xy 21.935838 -420.048411)
			(xy 21.985415 -420.071053) (xy 22.031265 -420.100519) (xy 22.072456 -420.13621) (xy 22.108147 -420.177401)
			(xy 22.137613 -420.223251) (xy 22.160255 -420.272828) (xy 22.17561 -420.325123) (xy 22.183366 -420.379071)
			(xy 22.183852 -420.406322) (xy 22.183852 -420.760398) (xy 58.141108 -420.760398) (xy 58.141108 -418.218874)
			(xy 58.141589 -418.206761) (xy 58.14908 -418.183722) (xy 58.16332 -418.164123) (xy 58.182918 -418.149882)
			(xy 58.205957 -418.14239) (xy 58.21807 -418.141912) (xy 59.15787 -418.141912) (xy 59.169989 -418.142385)
			(xy 59.193042 -418.149866) (xy 59.212655 -418.164105) (xy 59.226908 -418.183708) (xy 59.234406 -418.206756)
			(xy 59.234832 -418.218874) (xy 59.234832 -420.760398) (xy 59.234438 -420.772524) (xy 59.226942 -420.795587)
			(xy 59.212685 -420.815205) (xy 59.193062 -420.829455) (xy 59.169996 -420.836942) (xy 59.15787 -420.83736)
			(xy 58.21807 -420.83736) (xy 58.205954 -420.836914) (xy 58.182909 -420.829418) (xy 58.163308 -420.81517)
			(xy 58.149067 -420.795562) (xy 58.141581 -420.772515) (xy 58.141108 -420.760398) (xy 22.183852 -420.760398)
			(xy 22.183852 -421.269922) (xy 22.183366 -421.297173) (xy 22.17561 -421.351121) (xy 22.160255 -421.403416)
			(xy 22.137613 -421.452993) (xy 22.108147 -421.498843) (xy 22.072456 -421.540034) (xy 22.031265 -421.575725)
			(xy 21.985415 -421.605191) (xy 21.935838 -421.627833) (xy 21.883543 -421.643188) (xy 21.829595 -421.650944)
			(xy 21.775093 -421.650944) (xy 21.721145 -421.643188) (xy 21.66885 -421.627833) (xy 21.619273 -421.605191)
			(xy 21.573423 -421.575725) (xy 21.532232 -421.540034) (xy 21.496541 -421.498843) (xy 21.467075 -421.452993)
			(xy 21.444433 -421.403416) (xy 21.429078 -421.351121) (xy 21.421322 -421.297173) (xy 21.420836 -421.269922)
			(xy 10.769122 -421.269922) (xy 10.767454 -421.281525) (xy 10.752099 -421.33382) (xy 10.729457 -421.383397)
			(xy 10.699991 -421.429247) (xy 10.6643 -421.470438) (xy 10.623109 -421.506129) (xy 10.577259 -421.535595)
			(xy 10.527682 -421.558237) (xy 10.475387 -421.573592) (xy 10.421439 -421.581348) (xy 10.366937 -421.581348)
			(xy 10.312989 -421.573592) (xy 10.260694 -421.558237) (xy 10.211117 -421.535595) (xy 10.165267 -421.506129)
			(xy 10.124076 -421.470438) (xy 10.088385 -421.429247) (xy 10.058919 -421.383397) (xy 10.036277 -421.33382)
			(xy 10.020922 -421.281525) (xy 10.013166 -421.227577) (xy 10.01268 -421.200326) (xy 7.00913 -421.200326)
			(xy 7.00913 -422.130474) (xy 24.87676 -422.130474) (xy 24.87676 -421.266874) (xy 24.877246 -421.239605)
			(xy 24.885008 -421.185621) (xy 24.900373 -421.133291) (xy 24.92303 -421.083681) (xy 24.952516 -421.0378)
			(xy 24.988231 -420.996583) (xy 25.029448 -420.960868) (xy 25.075329 -420.931382) (xy 25.124939 -420.908725)
			(xy 25.177269 -420.89336) (xy 25.231253 -420.885598) (xy 25.285791 -420.885598) (xy 25.339775 -420.89336)
			(xy 25.392105 -420.908725) (xy 25.441715 -420.931382) (xy 25.487596 -420.960868) (xy 25.528813 -420.996583)
			(xy 25.564528 -421.0378) (xy 25.594014 -421.083681) (xy 25.616671 -421.133291) (xy 25.632036 -421.185621)
			(xy 25.639798 -421.239605) (xy 25.640284 -421.266874) (xy 25.640284 -421.726974) (xy 27.323192 -421.726974)
			(xy 27.323192 -421.672426) (xy 27.330955 -421.618434) (xy 27.346324 -421.566097) (xy 27.368985 -421.51648)
			(xy 27.398477 -421.470593) (xy 27.4342 -421.429371) (xy 27.475427 -421.393652) (xy 27.521317 -421.364165)
			(xy 27.570936 -421.341509) (xy 27.623276 -421.326146) (xy 27.677268 -421.318389) (xy 27.704542 -421.317928)
			(xy 28.568142 -421.317928) (xy 28.595409 -421.318437) (xy 28.649386 -421.326204) (xy 28.701709 -421.341572)
			(xy 28.751313 -421.36423) (xy 28.797187 -421.393716) (xy 28.838399 -421.429431) (xy 28.874109 -421.470646)
			(xy 28.90359 -421.516524) (xy 28.926243 -421.56613) (xy 28.941605 -421.618455) (xy 28.949366 -421.672433)
			(xy 28.949366 -421.726967) (xy 28.941605 -421.780945) (xy 28.926243 -421.83327) (xy 28.90359 -421.882876)
			(xy 28.874109 -421.928754) (xy 28.838399 -421.969969) (xy 28.797187 -422.005684) (xy 28.751313 -422.03517)
			(xy 28.701709 -422.057828) (xy 28.649386 -422.073196) (xy 28.595409 -422.080963) (xy 28.568142 -422.081452)
			(xy 27.704542 -422.081452) (xy 27.677268 -422.081011) (xy 27.623276 -422.073254) (xy 27.570936 -422.057891)
			(xy 27.521317 -422.035235) (xy 27.475427 -422.005748) (xy 27.4342 -421.970029) (xy 27.398477 -421.928807)
			(xy 27.368985 -421.88292) (xy 27.346324 -421.833303) (xy 27.330955 -421.780966) (xy 27.323192 -421.726974)
			(xy 25.640284 -421.726974) (xy 25.640284 -422.130474) (xy 25.639798 -422.157743) (xy 25.632036 -422.211727)
			(xy 25.616671 -422.264057) (xy 25.594014 -422.313667) (xy 25.564528 -422.359548) (xy 25.528813 -422.400765)
			(xy 25.487596 -422.43648) (xy 25.441715 -422.465966) (xy 25.392105 -422.488623) (xy 25.339775 -422.503988)
			(xy 25.285791 -422.51175) (xy 25.231253 -422.51175) (xy 25.177269 -422.503988) (xy 25.124939 -422.488623)
			(xy 25.075329 -422.465966) (xy 25.029448 -422.43648) (xy 24.988231 -422.400765) (xy 24.952516 -422.359548)
			(xy 24.92303 -422.313667) (xy 24.900373 -422.264057) (xy 24.885008 -422.211727) (xy 24.877246 -422.157743)
			(xy 24.87676 -422.130474) (xy 7.00913 -422.130474) (xy 7.00913 -422.66627) (xy 38.762906 -422.66627)
			(xy 38.762906 -422.61173) (xy 38.770668 -422.557744) (xy 38.786034 -422.505412) (xy 38.808691 -422.4558)
			(xy 38.838178 -422.409918) (xy 38.873894 -422.368698) (xy 38.915113 -422.332981) (xy 38.960995 -422.303494)
			(xy 39.010607 -422.280836) (xy 39.062938 -422.26547) (xy 39.116924 -422.257707) (xy 39.144194 -422.25722)
			(xy 40.007794 -422.25722) (xy 40.035064 -422.257719) (xy 40.089049 -422.26548) (xy 40.14138 -422.280845)
			(xy 40.190991 -422.303501) (xy 40.236874 -422.332987) (xy 40.278093 -422.368703) (xy 40.313809 -422.409921)
			(xy 40.343296 -422.455803) (xy 40.365953 -422.505414) (xy 40.381319 -422.557745) (xy 40.389081 -422.61173)
			(xy 40.389081 -422.66627) (xy 40.381319 -422.720255) (xy 40.365953 -422.772586) (xy 40.343296 -422.822197)
			(xy 40.313809 -422.868079) (xy 40.278093 -422.909297) (xy 40.236874 -422.945013) (xy 40.190991 -422.974499)
			(xy 40.14138 -422.997155) (xy 40.089049 -423.01252) (xy 40.035064 -423.020281) (xy 40.007794 -423.020744)
			(xy 39.144194 -423.020744) (xy 39.116924 -423.020293) (xy 39.062938 -423.01253) (xy 39.010607 -422.997164)
			(xy 38.960995 -422.974506) (xy 38.915113 -422.945019) (xy 38.873894 -422.909302) (xy 38.838178 -422.868082)
			(xy 38.808691 -422.8222) (xy 38.786034 -422.772588) (xy 38.770668 -422.720256) (xy 38.762906 -422.66627)
			(xy 7.00913 -422.66627) (xy 7.00913 -423.057828) (xy 41.652952 -423.057828) (xy 41.652952 -422.194228)
			(xy 41.653438 -422.166959) (xy 41.6612 -422.112975) (xy 41.676565 -422.060645) (xy 41.699222 -422.011035)
			(xy 41.728708 -421.965154) (xy 41.764423 -421.923937) (xy 41.80564 -421.888222) (xy 41.851521 -421.858736)
			(xy 41.901131 -421.836079) (xy 41.953461 -421.820714) (xy 42.007445 -421.812952) (xy 42.061983 -421.812952)
			(xy 42.115967 -421.820714) (xy 42.168297 -421.836079) (xy 42.217907 -421.858736) (xy 42.263788 -421.888222)
			(xy 42.305005 -421.923937) (xy 42.34072 -421.965154) (xy 42.370206 -422.011035) (xy 42.392863 -422.060645)
			(xy 42.408228 -422.112975) (xy 42.41599 -422.166959) (xy 42.416476 -422.194228) (xy 42.416476 -423.057828)
			(xy 42.41599 -423.085097) (xy 42.408228 -423.139081) (xy 42.392863 -423.191411) (xy 42.370206 -423.241021)
			(xy 42.34072 -423.286902) (xy 42.305005 -423.328119) (xy 42.263788 -423.363834) (xy 42.217907 -423.39332)
			(xy 42.168297 -423.415977) (xy 42.115967 -423.431342) (xy 42.061983 -423.439104) (xy 42.007445 -423.439104)
			(xy 41.953461 -423.431342) (xy 41.901131 -423.415977) (xy 41.851521 -423.39332) (xy 41.80564 -423.363834)
			(xy 41.764423 -423.328119) (xy 41.728708 -423.286902) (xy 41.699222 -423.241021) (xy 41.676565 -423.191411)
			(xy 41.6612 -423.139081) (xy 41.653438 -423.085097) (xy 41.652952 -423.057828) (xy 7.00913 -423.057828)
			(xy 7.00913 -425.887642) (xy 10.204704 -425.887642) (xy 10.204704 -425.024042) (xy 10.20519 -424.996773)
			(xy 10.212952 -424.942789) (xy 10.228317 -424.890459) (xy 10.250974 -424.840849) (xy 10.28046 -424.794968)
			(xy 10.316175 -424.753751) (xy 10.357392 -424.718036) (xy 10.403273 -424.68855) (xy 10.452883 -424.665893)
			(xy 10.505213 -424.650528) (xy 10.559197 -424.642766) (xy 10.613735 -424.642766) (xy 10.667719 -424.650528)
			(xy 10.720049 -424.665893) (xy 10.769659 -424.68855) (xy 10.81554 -424.718036) (xy 10.856757 -424.753751)
			(xy 10.892472 -424.794968) (xy 10.921958 -424.840849) (xy 10.944615 -424.890459) (xy 10.95998 -424.942789)
			(xy 10.967742 -424.996773) (xy 10.968228 -425.024042) (xy 10.968228 -425.328334) (xy 21.942552 -425.328334)
			(xy 21.942552 -424.464734) (xy 21.943038 -424.437465) (xy 21.9508 -424.383481) (xy 21.966165 -424.331151)
			(xy 21.988822 -424.281541) (xy 22.018308 -424.23566) (xy 22.054023 -424.194443) (xy 22.09524 -424.158728)
			(xy 22.141121 -424.129242) (xy 22.190731 -424.106585) (xy 22.243061 -424.09122) (xy 22.297045 -424.083458)
			(xy 22.351583 -424.083458) (xy 22.405567 -424.09122) (xy 22.457897 -424.106585) (xy 22.507507 -424.129242)
			(xy 22.553388 -424.158728) (xy 22.594605 -424.194443) (xy 22.63032 -424.23566) (xy 22.659806 -424.281541)
			(xy 22.682463 -424.331151) (xy 22.691108 -424.360594) (xy 58.141108 -424.360594) (xy 58.141108 -421.81907)
			(xy 58.141586 -421.806957) (xy 58.149077 -421.783918) (xy 58.163319 -421.764319) (xy 58.182918 -421.750077)
			(xy 58.205957 -421.742586) (xy 58.21807 -421.742108) (xy 59.15787 -421.742108) (xy 59.16998 -421.742637)
			(xy 59.193017 -421.750112) (xy 59.207184 -421.760396) (xy 60.141104 -421.760396) (xy 60.141104 -419.218872)
			(xy 60.141493 -419.206761) (xy 60.149 -419.183732) (xy 60.163269 -419.164159) (xy 60.182896 -419.149966)
			(xy 60.205954 -419.142547) (xy 60.218066 -419.142164) (xy 61.157866 -419.142164) (xy 61.169956 -419.142637)
			(xy 61.19296 -419.150087) (xy 61.212542 -419.164271) (xy 61.226793 -419.183805) (xy 61.234322 -419.206783)
			(xy 61.234828 -419.218872) (xy 61.234828 -421.760396) (xy 61.234381 -421.772502) (xy 61.226886 -421.795524)
			(xy 61.212631 -421.815095) (xy 61.193018 -421.829291) (xy 61.169973 -421.836717) (xy 61.157866 -421.837104)
			(xy 60.218066 -421.837104) (xy 60.205979 -421.836623) (xy 60.182985 -421.829162) (xy 60.163409 -421.814977)
			(xy 60.149158 -421.79545) (xy 60.141619 -421.772481) (xy 60.141104 -421.760396) (xy 59.207184 -421.760396)
			(xy 59.212617 -421.76434) (xy 59.22686 -421.783929) (xy 59.234354 -421.80696) (xy 59.234832 -421.81907)
			(xy 59.234832 -424.360594) (xy 62.1411 -424.360594) (xy 62.1411 -421.81907) (xy 62.141585 -421.806958)
			(xy 62.149076 -421.78392) (xy 62.163316 -421.764322) (xy 62.182913 -421.75008) (xy 62.20595 -421.742587)
			(xy 62.218062 -421.742108) (xy 63.157862 -421.742108) (xy 63.16998 -421.742592) (xy 63.193032 -421.75007)
			(xy 63.207258 -421.760396) (xy 68.141088 -421.760396) (xy 68.141088 -419.218872) (xy 68.141492 -419.206763)
			(xy 68.148998 -419.183737) (xy 68.163263 -419.164165) (xy 68.182886 -419.149971) (xy 68.205939 -419.142549)
			(xy 68.21805 -419.142164) (xy 69.15785 -419.142164) (xy 69.169939 -419.14265) (xy 69.192942 -419.150096)
			(xy 69.212525 -419.164277) (xy 69.226777 -419.183808) (xy 69.234306 -419.206784) (xy 69.234812 -419.218872)
			(xy 69.234812 -420.760398) (xy 70.141084 -420.760398) (xy 70.141084 -418.218874) (xy 70.141438 -418.206745)
			(xy 70.148943 -418.183678) (xy 70.16321 -418.164059) (xy 70.182842 -418.14981) (xy 70.205917 -418.142327)
			(xy 70.218046 -418.141912) (xy 71.157846 -418.141912) (xy 71.16996 -418.142372) (xy 71.193001 -418.149869)
			(xy 71.212599 -418.164115) (xy 71.22684 -418.183717) (xy 71.234331 -418.20676) (xy 71.234808 -418.218874)
			(xy 71.234808 -418.3761) (xy 77.661008 -418.3761) (xy 77.661008 -417.5125) (xy 77.661494 -417.485231)
			(xy 77.669256 -417.431247) (xy 77.684621 -417.378917) (xy 77.707278 -417.329307) (xy 77.736764 -417.283426)
			(xy 77.772479 -417.242209) (xy 77.813696 -417.206494) (xy 77.859577 -417.177008) (xy 77.909187 -417.154351)
			(xy 77.961517 -417.138986) (xy 78.015501 -417.131224) (xy 78.070039 -417.131224) (xy 78.124023 -417.138986)
			(xy 78.176353 -417.154351) (xy 78.225963 -417.177008) (xy 78.271844 -417.206494) (xy 78.313061 -417.242209)
			(xy 78.348776 -417.283426) (xy 78.378262 -417.329307) (xy 78.400919 -417.378917) (xy 78.416284 -417.431247)
			(xy 78.424046 -417.485231) (xy 78.424532 -417.5125) (xy 78.424532 -418.3761) (xy 78.424046 -418.403369)
			(xy 78.416284 -418.457353) (xy 78.400919 -418.509683) (xy 78.378262 -418.559293) (xy 78.348776 -418.605174)
			(xy 78.313061 -418.646391) (xy 78.271844 -418.682106) (xy 78.225963 -418.711592) (xy 78.176353 -418.734249)
			(xy 78.124023 -418.749614) (xy 78.070039 -418.757376) (xy 78.015501 -418.757376) (xy 77.961517 -418.749614)
			(xy 77.909187 -418.734249) (xy 77.859577 -418.711592) (xy 77.813696 -418.682106) (xy 77.772479 -418.646391)
			(xy 77.736764 -418.605174) (xy 77.707278 -418.559293) (xy 77.684621 -418.509683) (xy 77.669256 -418.457353)
			(xy 77.661494 -418.403369) (xy 77.661008 -418.3761) (xy 71.234808 -418.3761) (xy 71.234808 -420.760398)
			(xy 71.234287 -420.772508) (xy 71.226806 -420.795543) (xy 71.212575 -420.815141) (xy 71.192986 -420.829384)
			(xy 71.169956 -420.83688) (xy 71.157846 -420.83736) (xy 70.218046 -420.83736) (xy 70.205925 -420.836901)
			(xy 70.182868 -420.829421) (xy 70.163252 -420.81518) (xy 70.148999 -420.795572) (xy 70.141506 -420.772518)
			(xy 70.141084 -420.760398) (xy 69.234812 -420.760398) (xy 69.234812 -421.760396) (xy 69.234381 -421.772503)
			(xy 69.226884 -421.795529) (xy 69.212626 -421.815101) (xy 69.193008 -421.829296) (xy 69.169959 -421.836719)
			(xy 69.15785 -421.837104) (xy 68.21805 -421.837104) (xy 68.205967 -421.836551) (xy 68.182976 -421.829113)
			(xy 68.163399 -421.814947) (xy 68.149145 -421.795434) (xy 68.141604 -421.772476) (xy 68.141088 -421.760396)
			(xy 63.207258 -421.760396) (xy 63.212645 -421.764306) (xy 63.226899 -421.783907) (xy 63.234398 -421.806953)
			(xy 63.234824 -421.81907) (xy 63.234824 -424.360594) (xy 63.234434 -424.37272) (xy 63.226939 -424.395785)
			(xy 63.212681 -424.415404) (xy 63.193057 -424.429654) (xy 63.169988 -424.437139) (xy 63.157862 -424.437556)
			(xy 62.218062 -424.437556) (xy 62.205945 -424.437121) (xy 62.182899 -424.429622) (xy 62.163298 -424.415371)
			(xy 62.149058 -424.395761) (xy 62.141572 -424.372711) (xy 62.1411 -424.360594) (xy 59.234832 -424.360594)
			(xy 59.234434 -424.372719) (xy 59.22694 -424.395783) (xy 59.212684 -424.415401) (xy 59.193062 -424.429651)
			(xy 59.169996 -424.437138) (xy 59.15787 -424.437556) (xy 58.21807 -424.437556) (xy 58.205953 -424.437114)
			(xy 58.182908 -424.429618) (xy 58.163306 -424.415368) (xy 58.149066 -424.39576) (xy 58.14158 -424.372711)
			(xy 58.141108 -424.360594) (xy 22.691108 -424.360594) (xy 22.697828 -424.383481) (xy 22.70559 -424.437465)
			(xy 22.706076 -424.464734) (xy 22.706076 -425.328334) (xy 22.70559 -425.355603) (xy 22.697828 -425.409587)
			(xy 22.682463 -425.461917) (xy 22.659806 -425.511527) (xy 22.63032 -425.557408) (xy 22.594605 -425.598625)
			(xy 22.553388 -425.63434) (xy 22.507507 -425.663826) (xy 22.457897 -425.686483) (xy 22.405567 -425.701848)
			(xy 22.351583 -425.70961) (xy 22.297045 -425.70961) (xy 22.243061 -425.701848) (xy 22.190731 -425.686483)
			(xy 22.141121 -425.663826) (xy 22.09524 -425.63434) (xy 22.054023 -425.598625) (xy 22.018308 -425.557408)
			(xy 21.988822 -425.511527) (xy 21.966165 -425.461917) (xy 21.9508 -425.409587) (xy 21.943038 -425.355603)
			(xy 21.942552 -425.328334) (xy 10.968228 -425.328334) (xy 10.968228 -425.887642) (xy 10.967742 -425.914911)
			(xy 10.964527 -425.937273) (xy 38.737196 -425.937273) (xy 38.737196 -425.882727) (xy 38.744959 -425.828736)
			(xy 38.760327 -425.776399) (xy 38.782988 -425.726782) (xy 38.81248 -425.680896) (xy 38.848202 -425.639674)
			(xy 38.889428 -425.603956) (xy 38.935317 -425.574469) (xy 38.984936 -425.551813) (xy 39.037275 -425.53645)
			(xy 39.091267 -425.528693) (xy 39.11854 -425.528232) (xy 39.98214 -425.528232) (xy 40.009407 -425.528733)
			(xy 40.063385 -425.536499) (xy 40.115709 -425.551868) (xy 40.165314 -425.574526) (xy 40.211189 -425.604012)
			(xy 40.252401 -425.639727) (xy 40.288112 -425.680943) (xy 40.317593 -425.726821) (xy 40.340246 -425.776428)
			(xy 40.355609 -425.828754) (xy 40.36337 -425.882733) (xy 40.36337 -425.937267) (xy 40.355609 -425.991246)
			(xy 40.340246 -426.043572) (xy 40.317593 -426.093179) (xy 40.288112 -426.139057) (xy 40.252401 -426.180273)
			(xy 40.211189 -426.215988) (xy 40.165314 -426.245474) (xy 40.115709 -426.268132) (xy 40.063385 -426.283501)
			(xy 40.009407 -426.291267) (xy 39.98214 -426.291756) (xy 39.11854 -426.291756) (xy 39.091267 -426.291307)
			(xy 39.037275 -426.28355) (xy 38.984936 -426.268187) (xy 38.935317 -426.245531) (xy 38.889428 -426.216044)
			(xy 38.848202 -426.180326) (xy 38.81248 -426.139104) (xy 38.782988 -426.093218) (xy 38.760327 -426.043601)
			(xy 38.744959 -425.991264) (xy 38.737196 -425.937273) (xy 10.964527 -425.937273) (xy 10.95998 -425.968895)
			(xy 10.944615 -426.021225) (xy 10.921958 -426.070835) (xy 10.892472 -426.116716) (xy 10.856757 -426.157933)
			(xy 10.81554 -426.193648) (xy 10.769659 -426.223134) (xy 10.720049 -426.245791) (xy 10.667719 -426.261156)
			(xy 10.613735 -426.268918) (xy 10.559197 -426.268918) (xy 10.505213 -426.261156) (xy 10.452883 -426.245791)
			(xy 10.403273 -426.223134) (xy 10.357392 -426.193648) (xy 10.316175 -426.157933) (xy 10.28046 -426.116716)
			(xy 10.250974 -426.070835) (xy 10.228317 -426.021225) (xy 10.212952 -425.968895) (xy 10.20519 -425.914911)
			(xy 10.204704 -425.887642) (xy 7.00913 -425.887642) (xy 7.00913 -426.333158) (xy 41.613836 -426.333158)
			(xy 41.613836 -425.469558) (xy 41.614322 -425.442307) (xy 41.622078 -425.388359) (xy 41.637433 -425.336064)
			(xy 41.660075 -425.286487) (xy 41.689541 -425.240637) (xy 41.725232 -425.199446) (xy 41.766423 -425.163755)
			(xy 41.812273 -425.134289) (xy 41.86185 -425.111647) (xy 41.914145 -425.096292) (xy 41.968093 -425.088536)
			(xy 42.022595 -425.088536) (xy 42.076543 -425.096292) (xy 42.128838 -425.111647) (xy 42.178415 -425.134289)
			(xy 42.224265 -425.163755) (xy 42.265456 -425.199446) (xy 42.301147 -425.240637) (xy 42.330613 -425.286487)
			(xy 42.353255 -425.336064) (xy 42.36861 -425.388359) (xy 42.376366 -425.442307) (xy 42.376852 -425.469558)
			(xy 42.376852 -426.333158) (xy 42.376366 -426.360409) (xy 42.36861 -426.414357) (xy 42.353255 -426.466652)
			(xy 42.330613 -426.516229) (xy 42.301147 -426.562079) (xy 42.265456 -426.60327) (xy 42.224265 -426.638961)
			(xy 42.178415 -426.668427) (xy 42.128838 -426.691069) (xy 42.076543 -426.706424) (xy 42.022595 -426.71418)
			(xy 41.968093 -426.71418) (xy 41.914145 -426.706424) (xy 41.86185 -426.691069) (xy 41.812273 -426.668427)
			(xy 41.766423 -426.638961) (xy 41.725232 -426.60327) (xy 41.689541 -426.562079) (xy 41.660075 -426.516229)
			(xy 41.637433 -426.466652) (xy 41.622078 -426.414357) (xy 41.614322 -426.360409) (xy 41.613836 -426.333158)
			(xy 7.00913 -426.333158) (xy 7.00913 -428.615602) (xy 25.13076 -428.615602) (xy 25.13076 -427.752002)
			(xy 25.131246 -427.724733) (xy 25.139008 -427.670749) (xy 25.154373 -427.618419) (xy 25.17703 -427.568809)
			(xy 25.206516 -427.522928) (xy 25.242231 -427.481711) (xy 25.283448 -427.445996) (xy 25.329329 -427.41651)
			(xy 25.378939 -427.393853) (xy 25.431269 -427.378488) (xy 25.485253 -427.370726) (xy 25.539791 -427.370726)
			(xy 25.593775 -427.378488) (xy 25.646105 -427.393853) (xy 25.695715 -427.41651) (xy 25.741596 -427.445996)
			(xy 25.782813 -427.481711) (xy 25.818528 -427.522928) (xy 25.848014 -427.568809) (xy 25.870671 -427.618419)
			(xy 25.886036 -427.670749) (xy 25.893798 -427.724733) (xy 25.894284 -427.752002) (xy 25.894284 -428.211072)
			(xy 26.941204 -428.211072) (xy 26.941204 -428.156528) (xy 26.948966 -428.102539) (xy 26.964334 -428.050205)
			(xy 26.986993 -428.00059) (xy 27.016483 -427.954705) (xy 27.052203 -427.913485) (xy 27.093426 -427.877767)
			(xy 27.139313 -427.848281) (xy 27.188929 -427.825625) (xy 27.241265 -427.810261) (xy 27.295254 -427.802502)
			(xy 27.322526 -427.80204) (xy 28.186126 -427.80204) (xy 28.213394 -427.802524) (xy 28.267375 -427.810289)
			(xy 28.319702 -427.825657) (xy 28.369309 -427.848314) (xy 28.415187 -427.877801) (xy 28.456402 -427.913517)
			(xy 28.492114 -427.954734) (xy 28.495843 -427.960536) (xy 58.141108 -427.960536) (xy 58.141108 -427.233588)
			(xy 58.14139 -427.224753) (xy 58.145504 -427.207565) (xy 58.149236 -427.199552) (xy 58.382662 -426.723302)
			(xy 58.387347 -426.712779) (xy 58.390839 -426.690025) (xy 58.387362 -426.667269) (xy 58.382662 -426.656754)
			(xy 58.149236 -426.180504) (xy 58.145483 -426.172497) (xy 58.141364 -426.155306) (xy 58.141108 -426.146468)
			(xy 58.141108 -425.419012) (xy 58.141527 -425.406903) (xy 58.149024 -425.383875) (xy 58.163285 -425.364301)
			(xy 58.182906 -425.350106) (xy 58.20596 -425.342687) (xy 58.21807 -425.342304) (xy 59.15787 -425.342304)
			(xy 59.169954 -425.342832) (xy 59.192948 -425.350276) (xy 59.212525 -425.364448) (xy 59.226778 -425.383967)
			(xy 59.234317 -425.40693) (xy 59.234832 -425.419012) (xy 59.234832 -427.960536) (xy 59.234415 -427.972644)
			(xy 59.226909 -427.995667) (xy 59.212647 -428.015236) (xy 59.193028 -428.029431) (xy 59.169979 -428.036856)
			(xy 59.15787 -428.037244) (xy 58.21807 -428.037244) (xy 58.205977 -428.036818) (xy 58.182973 -428.029351)
			(xy 58.163392 -428.015154) (xy 58.149143 -427.995612) (xy 58.141615 -427.972627) (xy 58.141108 -427.960536)
			(xy 28.495843 -427.960536) (xy 28.521598 -428.000614) (xy 28.544253 -428.050222) (xy 28.559617 -428.10255)
			(xy 28.567378 -428.156532) (xy 28.567378 -428.211068) (xy 28.559617 -428.26505) (xy 28.544253 -428.317378)
			(xy 28.521598 -428.366986) (xy 28.492114 -428.412866) (xy 28.456402 -428.454083) (xy 28.415187 -428.489799)
			(xy 28.369309 -428.519286) (xy 28.319702 -428.541943) (xy 28.267375 -428.557311) (xy 28.213394 -428.565076)
			(xy 28.186126 -428.565564) (xy 27.322526 -428.565564) (xy 27.295254 -428.565098) (xy 27.241265 -428.557339)
			(xy 27.188929 -428.541975) (xy 27.139313 -428.519319) (xy 27.093426 -428.489833) (xy 27.052203 -428.454115)
			(xy 27.016483 -428.412895) (xy 26.986993 -428.36701) (xy 26.964334 -428.317395) (xy 26.948966 -428.265061)
			(xy 26.941204 -428.211072) (xy 25.894284 -428.211072) (xy 25.894284 -428.615602) (xy 25.893798 -428.642871)
			(xy 25.886036 -428.696855) (xy 25.870671 -428.749185) (xy 25.848014 -428.798795) (xy 25.818528 -428.844676)
			(xy 25.782813 -428.885893) (xy 25.741596 -428.921608) (xy 25.695715 -428.951094) (xy 25.646105 -428.973751)
			(xy 25.593775 -428.989116) (xy 25.539791 -428.996878) (xy 25.485253 -428.996878) (xy 25.431269 -428.989116)
			(xy 25.378939 -428.973751) (xy 25.329329 -428.951094) (xy 25.283448 -428.921608) (xy 25.242231 -428.885893)
			(xy 25.206516 -428.844676) (xy 25.17703 -428.798795) (xy 25.154373 -428.749185) (xy 25.139008 -428.696855)
			(xy 25.131246 -428.642871) (xy 25.13076 -428.615602) (xy 7.00913 -428.615602) (xy 7.00913 -431.560478)
			(xy 58.141108 -431.560478) (xy 58.141108 -429.018954) (xy 58.141572 -429.00684) (xy 58.149068 -428.9838)
			(xy 58.163313 -428.964202) (xy 58.182915 -428.949961) (xy 58.205956 -428.94247) (xy 58.21807 -428.941992)
			(xy 59.15787 -428.941992) (xy 59.169978 -428.942537) (xy 59.193013 -428.95001) (xy 59.207512 -428.960534)
			(xy 60.141104 -428.960534) (xy 60.141104 -428.233586) (xy 60.141385 -428.224751) (xy 60.1455 -428.207563)
			(xy 60.149232 -428.19955) (xy 60.382658 -427.7233) (xy 60.387344 -427.712778) (xy 60.390836 -427.690023)
			(xy 60.387359 -427.667267) (xy 60.382658 -427.656752) (xy 60.149232 -427.180502) (xy 60.145478 -427.172496)
			(xy 60.14136 -427.155304) (xy 60.141104 -427.146466) (xy 60.141104 -426.41901) (xy 60.14162 -426.406899)
			(xy 60.1491 -426.383862) (xy 60.163332 -426.364263) (xy 60.182923 -426.35002) (xy 60.205956 -426.342527)
			(xy 60.218066 -426.342048) (xy 61.157866 -426.342048) (xy 61.169988 -426.342489) (xy 61.193047 -426.349973)
			(xy 61.212664 -426.364219) (xy 61.226916 -426.383831) (xy 61.234407 -426.406888) (xy 61.234828 -426.41901)
			(xy 61.234828 -427.960536) (xy 62.1411 -427.960536) (xy 62.1411 -427.233588) (xy 62.141382 -427.224753)
			(xy 62.145496 -427.207565) (xy 62.149228 -427.199552) (xy 62.382654 -426.723302) (xy 62.387339 -426.71278)
			(xy 62.390832 -426.690025) (xy 62.387354 -426.667269) (xy 62.382654 -426.656754) (xy 62.149228 -426.180504)
			(xy 62.145474 -426.172498) (xy 62.141356 -426.155306) (xy 62.1411 -426.146468) (xy 62.1411 -425.419012)
			(xy 62.141527 -425.406904) (xy 62.149023 -425.383877) (xy 62.163282 -425.364304) (xy 62.182901 -425.350109)
			(xy 62.205952 -425.342688) (xy 62.218062 -425.342304) (xy 63.157862 -425.342304) (xy 63.169946 -425.342839)
			(xy 63.192939 -425.350281) (xy 63.207185 -425.360592) (xy 64.141096 -425.360592) (xy 64.141096 -422.819068)
			(xy 64.141489 -422.806958) (xy 64.148997 -422.78393) (xy 64.163265 -422.764358) (xy 64.18289 -422.750164)
			(xy 64.205946 -422.742744) (xy 64.218058 -422.74236) (xy 65.157858 -422.74236) (xy 65.169947 -422.742843)
			(xy 65.19295 -422.750291) (xy 65.212532 -422.764473) (xy 65.226784 -422.784004) (xy 65.234313 -422.80698)
			(xy 65.23482 -422.819068) (xy 65.23482 -425.360592) (xy 65.234377 -425.372698) (xy 65.226883 -425.395722)
			(xy 65.212627 -425.415294) (xy 65.193012 -425.429489) (xy 65.169966 -425.436914) (xy 65.157858 -425.4373)
			(xy 64.218058 -425.4373) (xy 64.20597 -425.436829) (xy 64.182975 -425.429366) (xy 64.163399 -425.415179)
			(xy 64.149149 -425.395649) (xy 64.141611 -425.372678) (xy 64.141096 -425.360592) (xy 63.207185 -425.360592)
			(xy 63.212517 -425.364451) (xy 63.22677 -425.383968) (xy 63.234309 -425.40693) (xy 63.234824 -425.419012)
			(xy 63.234824 -427.960536) (xy 63.234415 -427.972644) (xy 63.226908 -427.995669) (xy 63.212644 -428.015239)
			(xy 63.193023 -428.029433) (xy 63.169972 -428.036857) (xy 63.157862 -428.037244) (xy 62.218062 -428.037244)
			(xy 62.205969 -428.036825) (xy 62.182964 -428.029356) (xy 62.163384 -428.015157) (xy 62.149135 -427.995613)
			(xy 62.141607 -427.972628) (xy 62.1411 -427.960536) (xy 61.234828 -427.960536) (xy 61.234828 -428.960534)
			(xy 61.234417 -428.972654) (xy 61.226916 -428.995704) (xy 61.21266 -429.015308) (xy 61.193043 -429.029547)
			(xy 61.169986 -429.037027) (xy 61.157866 -429.037496) (xy 60.218066 -429.037496) (xy 60.205953 -429.037018)
			(xy 60.182914 -429.029525) (xy 60.163316 -429.015284) (xy 60.149075 -428.995686) (xy 60.141582 -428.972647)
			(xy 60.141104 -428.960534) (xy 59.207512 -428.960534) (xy 59.212611 -428.964235) (xy 59.226855 -428.983819)
			(xy 59.234351 -429.006846) (xy 59.234832 -429.018954) (xy 59.234832 -431.560478) (xy 59.234421 -431.572603)
			(xy 59.226931 -431.595666) (xy 59.212678 -431.615284) (xy 59.193059 -431.629535) (xy 59.169995 -431.637022)
			(xy 59.15787 -431.63744) (xy 58.21807 -431.63744) (xy 58.205952 -431.637014) (xy 58.182904 -431.629515)
			(xy 58.163301 -431.615262) (xy 58.149061 -431.59565) (xy 58.141578 -431.572597) (xy 58.141108 -431.560478)
			(xy 7.00913 -431.560478) (xy 7.00913 -435.16042) (xy 58.141108 -435.16042) (xy 58.141108 -432.618896)
			(xy 58.141513 -432.606786) (xy 58.149014 -432.583757) (xy 58.163279 -432.564184) (xy 58.182903 -432.549989)
			(xy 58.205959 -432.54257) (xy 58.21807 -432.542188) (xy 59.15787 -432.542188) (xy 59.169963 -432.542634)
			(xy 59.19297 -432.550088) (xy 59.207307 -432.560476) (xy 60.141104 -432.560476) (xy 60.141104 -430.018952)
			(xy 60.141476 -430.00684) (xy 60.148989 -429.983811) (xy 60.163262 -429.964238) (xy 60.182893 -429.950045)
			(xy 60.205953 -429.942626) (xy 60.218066 -429.942244) (xy 61.157866 -429.942244) (xy 61.169954 -429.942736)
			(xy 61.192954 -429.950184) (xy 61.212535 -429.964364) (xy 61.226787 -429.983893) (xy 61.234319 -430.006866)
			(xy 61.234828 -430.018952) (xy 61.234828 -431.560478) (xy 62.1411 -431.560478) (xy 62.1411 -429.018954)
			(xy 62.141572 -429.006841) (xy 62.149067 -428.983803) (xy 62.163311 -428.964205) (xy 62.18291 -428.949964)
			(xy 62.205949 -428.942471) (xy 62.218062 -428.941992) (xy 63.157862 -428.941992) (xy 63.16997 -428.942543)
			(xy 63.193004 -428.950015) (xy 63.207499 -428.960534) (xy 64.141096 -428.960534) (xy 64.141096 -428.233586)
			(xy 64.141378 -428.224751) (xy 64.145492 -428.207563) (xy 64.149224 -428.19955) (xy 64.38265 -427.7233)
			(xy 64.387337 -427.712778) (xy 64.390829 -427.690023) (xy 64.387351 -427.667267) (xy 64.38265 -427.656752)
			(xy 64.149224 -427.180502) (xy 64.145469 -427.172496) (xy 64.141352 -427.155304) (xy 64.141096 -427.146466)
			(xy 64.141096 -426.41901) (xy 64.14162 -426.4069) (xy 64.149099 -426.383864) (xy 64.163329 -426.364266)
			(xy 64.182918 -426.350023) (xy 64.205948 -426.342528) (xy 64.218058 -426.342048) (xy 65.157858 -426.342048)
			(xy 65.16998 -426.342496) (xy 65.193039 -426.349978) (xy 65.212655 -426.364222) (xy 65.226908 -426.383833)
			(xy 65.234399 -426.406889) (xy 65.23482 -426.41901) (xy 65.23482 -427.960536) (xy 66.141092 -427.960536)
			(xy 66.141092 -427.233588) (xy 66.141375 -427.224753) (xy 66.145488 -427.207566) (xy 66.14922 -427.199552)
			(xy 66.382646 -426.723302) (xy 66.387332 -426.71278) (xy 66.390825 -426.690025) (xy 66.387347 -426.667269)
			(xy 66.382646 -426.656754) (xy 66.14922 -426.180504) (xy 66.145466 -426.172498) (xy 66.141348 -426.155306)
			(xy 66.141092 -426.146468) (xy 66.141092 -425.419012) (xy 66.141527 -425.406905) (xy 66.149022 -425.383879)
			(xy 66.163279 -425.364307) (xy 66.182896 -425.350111) (xy 66.205945 -425.342689) (xy 66.218054 -425.342304)
			(xy 67.157854 -425.342304) (xy 67.169938 -425.342846) (xy 67.192931 -425.350286) (xy 67.207172 -425.360592)
			(xy 68.141088 -425.360592) (xy 68.141088 -422.819068) (xy 68.141489 -422.806959) (xy 68.148996 -422.783932)
			(xy 68.163262 -422.764361) (xy 68.182885 -422.750167) (xy 68.205939 -422.742745) (xy 68.21805 -422.74236)
			(xy 69.15785 -422.74236) (xy 69.169939 -422.74285) (xy 69.192941 -422.750296) (xy 69.212524 -422.764475)
			(xy 69.226775 -422.784006) (xy 69.234305 -422.806981) (xy 69.234812 -422.819068) (xy 69.234812 -424.360594)
			(xy 70.141084 -424.360594) (xy 70.141084 -421.81907) (xy 70.141435 -421.806941) (xy 70.148941 -421.783873)
			(xy 70.163209 -421.764255) (xy 70.182842 -421.750006) (xy 70.205917 -421.742523) (xy 70.218046 -421.742108)
			(xy 71.157846 -421.742108) (xy 71.16996 -421.742572) (xy 71.193 -421.750068) (xy 71.207209 -421.760396)
			(xy 72.14108 -421.760396) (xy 72.14108 -419.218872) (xy 72.141492 -419.206764) (xy 72.148997 -419.183739)
			(xy 72.16326 -419.164168) (xy 72.182881 -419.149974) (xy 72.205932 -419.14255) (xy 72.218042 -419.142164)
			(xy 73.157842 -419.142164) (xy 73.169936 -419.142572) (xy 73.192942 -419.150043) (xy 73.212524 -419.164244)
			(xy 73.226772 -419.183791) (xy 73.234298 -419.206779) (xy 73.234804 -419.218872) (xy 73.234804 -420.921688)
			(xy 75.13828 -420.921688) (xy 75.13828 -420.058088) (xy 75.138766 -420.030819) (xy 75.146528 -419.976835)
			(xy 75.161893 -419.924505) (xy 75.18455 -419.874895) (xy 75.214036 -419.829014) (xy 75.249751 -419.787797)
			(xy 75.290968 -419.752082) (xy 75.336849 -419.722596) (xy 75.386459 -419.699939) (xy 75.438789 -419.684574)
			(xy 75.492773 -419.676812) (xy 75.547311 -419.676812) (xy 75.601295 -419.684574) (xy 75.653625 -419.699939)
			(xy 75.703235 -419.722596) (xy 75.749116 -419.752082) (xy 75.790333 -419.787797) (xy 75.826048 -419.829014)
			(xy 75.855534 -419.874895) (xy 75.878191 -419.924505) (xy 75.893556 -419.976835) (xy 75.901318 -420.030819)
			(xy 75.901804 -420.058088) (xy 75.901804 -420.921688) (xy 75.901318 -420.948957) (xy 75.893556 -421.002941)
			(xy 75.878191 -421.055271) (xy 75.855534 -421.104881) (xy 75.844472 -421.122094) (xy 97.149412 -421.122094)
			(xy 97.149412 -414.328102) (xy 97.149934 -414.317948) (xy 97.157703 -414.299183) (xy 97.17206 -414.284819)
			(xy 97.19082 -414.27704) (xy 97.200974 -414.27654) (xy 102.099618 -414.27654) (xy 102.109777 -414.277018)
			(xy 102.128547 -414.284799) (xy 102.142912 -414.29917) (xy 102.150685 -414.317943) (xy 102.15118 -414.328102)
			(xy 102.15118 -421.122094) (xy 102.150662 -421.132249) (xy 102.142893 -421.151015) (xy 102.128535 -421.16538)
			(xy 102.109773 -421.173157) (xy 102.099618 -421.173656) (xy 97.200974 -421.173656) (xy 97.190814 -421.173188)
			(xy 97.172043 -421.165404) (xy 97.157678 -421.15103) (xy 97.149906 -421.132255) (xy 97.149412 -421.122094)
			(xy 75.844472 -421.122094) (xy 75.826048 -421.150762) (xy 75.790333 -421.191979) (xy 75.749116 -421.227694)
			(xy 75.703235 -421.25718) (xy 75.653625 -421.279837) (xy 75.601295 -421.295202) (xy 75.547311 -421.302964)
			(xy 75.492773 -421.302964) (xy 75.438789 -421.295202) (xy 75.386459 -421.279837) (xy 75.336849 -421.25718)
			(xy 75.290968 -421.227694) (xy 75.249751 -421.191979) (xy 75.214036 -421.150762) (xy 75.18455 -421.104881)
			(xy 75.161893 -421.055271) (xy 75.146528 -421.002941) (xy 75.138766 -420.948957) (xy 75.13828 -420.921688)
			(xy 73.234804 -420.921688) (xy 73.234804 -421.760396) (xy 73.234381 -421.772504) (xy 73.226883 -421.795531)
			(xy 73.212623 -421.815104) (xy 73.193003 -421.829299) (xy 73.169952 -421.83672) (xy 73.157842 -421.837104)
			(xy 72.218042 -421.837104) (xy 72.205959 -421.836558) (xy 72.182967 -421.829118) (xy 72.16339 -421.81495)
			(xy 72.149137 -421.795436) (xy 72.141596 -421.772477) (xy 72.14108 -421.760396) (xy 71.207209 -421.760396)
			(xy 71.212598 -421.764313) (xy 71.226839 -421.783915) (xy 71.23433 -421.806956) (xy 71.234808 -421.81907)
			(xy 71.234808 -424.360594) (xy 71.234284 -424.372704) (xy 71.226804 -424.395739) (xy 71.212574 -424.415337)
			(xy 71.192985 -424.42958) (xy 71.169955 -424.437076) (xy 71.157846 -424.437556) (xy 70.218046 -424.437556)
			(xy 70.205925 -424.437101) (xy 70.182867 -424.429621) (xy 70.16325 -424.415378) (xy 70.148998 -424.395769)
			(xy 70.141505 -424.372715) (xy 70.141084 -424.360594) (xy 69.234812 -424.360594) (xy 69.234812 -425.360592)
			(xy 69.234377 -425.372699) (xy 69.226881 -425.395724) (xy 69.212624 -425.415297) (xy 69.193007 -425.429492)
			(xy 69.169959 -425.436915) (xy 69.15785 -425.4373) (xy 68.21805 -425.4373) (xy 68.205967 -425.436751)
			(xy 68.182975 -425.429313) (xy 68.163397 -425.415146) (xy 68.149144 -425.395632) (xy 68.141603 -425.372673)
			(xy 68.141088 -425.360592) (xy 67.207172 -425.360592) (xy 67.212508 -425.364454) (xy 67.226762 -425.38397)
			(xy 67.234301 -425.40693) (xy 67.234816 -425.419012) (xy 67.234816 -427.960536) (xy 67.234415 -427.972645)
			(xy 67.226907 -427.995671) (xy 67.212641 -428.015242) (xy 67.193018 -428.029436) (xy 67.169965 -428.036859)
			(xy 67.157854 -428.037244) (xy 66.218054 -428.037244) (xy 66.20596 -428.036832) (xy 66.182956 -428.02936)
			(xy 66.163375 -428.01516) (xy 66.149127 -427.995615) (xy 66.141599 -427.972628) (xy 66.141092 -427.960536)
			(xy 65.23482 -427.960536) (xy 65.23482 -428.960534) (xy 65.234469 -428.972663) (xy 65.226962 -428.99573)
			(xy 65.212694 -429.015348) (xy 65.193062 -429.029597) (xy 65.169987 -429.03708) (xy 65.157858 -429.037496)
			(xy 64.218058 -429.037496) (xy 64.205945 -429.037025) (xy 64.182906 -429.02953) (xy 64.163308 -429.015287)
			(xy 64.149066 -428.995687) (xy 64.141574 -428.972647) (xy 64.141096 -428.960534) (xy 63.207499 -428.960534)
			(xy 63.212603 -428.964238) (xy 63.226847 -428.98382) (xy 63.234343 -429.006847) (xy 63.234824 -429.018954)
			(xy 63.234824 -431.560478) (xy 63.234421 -431.572603) (xy 63.22693 -431.595668) (xy 63.212675 -431.615287)
			(xy 63.193054 -431.629537) (xy 63.169987 -431.637023) (xy 63.157862 -431.63744) (xy 62.218062 -431.63744)
			(xy 62.205943 -431.63702) (xy 62.182895 -431.62952) (xy 62.163292 -431.615265) (xy 62.149053 -431.595651)
			(xy 62.14157 -431.572597) (xy 62.1411 -431.560478) (xy 61.234828 -431.560478) (xy 61.234828 -432.560476)
			(xy 61.234363 -432.572581) (xy 61.226874 -432.595602) (xy 61.212624 -432.615174) (xy 61.193014 -432.62937)
			(xy 61.169972 -432.636796) (xy 61.157866 -432.637184) (xy 60.218066 -432.637184) (xy 60.205977 -432.636722)
			(xy 60.182979 -432.629259) (xy 60.163402 -432.61507) (xy 60.149152 -432.595538) (xy 60.141616 -432.572563)
			(xy 60.141104 -432.560476) (xy 59.207307 -432.560476) (xy 59.212555 -432.564278) (xy 59.226805 -432.58382)
			(xy 59.234329 -432.606805) (xy 59.234832 -432.618896) (xy 59.234832 -435.16042) (xy 59.234401 -435.172527)
			(xy 59.2269 -435.195549) (xy 59.212641 -435.215119) (xy 59.193025 -435.229314) (xy 59.169978 -435.23674)
			(xy 59.15787 -435.237128) (xy 58.21807 -435.237128) (xy 58.205976 -435.236718) (xy 58.182969 -435.229249)
			(xy 58.163386 -435.215049) (xy 58.149138 -435.195502) (xy 58.141612 -435.172513) (xy 58.141108 -435.16042)
			(xy 7.00913 -435.16042) (xy 7.00913 -438.760616) (xy 58.141108 -438.760616) (xy 58.141108 -436.219092)
			(xy 58.141509 -436.206982) (xy 58.149012 -436.183953) (xy 58.163277 -436.164379) (xy 58.182902 -436.150185)
			(xy 58.205958 -436.142766) (xy 58.21807 -436.142384) (xy 59.15787 -436.142384) (xy 59.169962 -436.142834)
			(xy 59.192969 -436.150288) (xy 59.206951 -436.160418) (xy 60.141104 -436.160418) (xy 60.141104 -433.618894)
			(xy 60.141606 -433.606783) (xy 60.149091 -433.583745) (xy 60.163326 -433.564146) (xy 60.18292 -433.549904)
			(xy 60.205955 -433.542411) (xy 60.218066 -433.541932) (xy 61.157866 -433.541932) (xy 61.169986 -433.542389)
			(xy 61.193043 -433.549871) (xy 61.212658 -433.564113) (xy 61.226911 -433.583721) (xy 61.234405 -433.606774)
			(xy 61.234828 -433.618894) (xy 61.234828 -435.16042) (xy 62.1411 -435.16042) (xy 62.1411 -432.618896)
			(xy 62.141513 -432.606787) (xy 62.149013 -432.583759) (xy 62.163276 -432.564186) (xy 62.182898 -432.549992)
			(xy 62.205952 -432.542571) (xy 62.218062 -432.542188) (xy 63.157862 -432.542188) (xy 63.169954 -432.542641)
			(xy 63.192962 -432.550093) (xy 63.207295 -432.560476) (xy 64.141096 -432.560476) (xy 64.141096 -430.018952)
			(xy 64.141476 -430.006841) (xy 64.148988 -429.983813) (xy 64.163259 -429.964241) (xy 64.182888 -429.950048)
			(xy 64.205945 -429.942628) (xy 64.218058 -429.942244) (xy 65.157858 -429.942244) (xy 65.169946 -429.942743)
			(xy 65.192946 -429.950189) (xy 65.212527 -429.964367) (xy 65.226779 -429.983894) (xy 65.234311 -430.006866)
			(xy 65.23482 -430.018952) (xy 65.23482 -431.560478) (xy 66.141092 -431.560478) (xy 66.141092 -429.018954)
			(xy 66.141572 -429.006842) (xy 66.149066 -428.983805) (xy 66.163308 -428.964208) (xy 66.182905 -428.949966)
			(xy 66.205942 -428.942472) (xy 66.218054 -428.941992) (xy 67.157854 -428.941992) (xy 67.169962 -428.94255)
			(xy 67.192996 -428.950019) (xy 67.207487 -428.960534) (xy 68.141088 -428.960534) (xy 68.141088 -428.233586)
			(xy 68.141371 -428.224751) (xy 68.145484 -428.207564) (xy 68.149216 -428.19955) (xy 68.382642 -427.7233)
			(xy 68.387329 -427.712778) (xy 68.390822 -427.690023) (xy 68.387343 -427.667267) (xy 68.382642 -427.656752)
			(xy 68.149216 -427.180502) (xy 68.145461 -427.172496) (xy 68.141344 -427.155304) (xy 68.141088 -427.146466)
			(xy 68.141088 -426.41901) (xy 68.14162 -426.406901) (xy 68.149098 -426.383867) (xy 68.163326 -426.364269)
			(xy 68.182913 -426.350025) (xy 68.205941 -426.342529) (xy 68.21805 -426.342048) (xy 69.15785 -426.342048)
			(xy 69.169968 -426.342469) (xy 69.193015 -426.349972) (xy 69.212616 -426.364226) (xy 69.226856 -426.383839)
			(xy 69.23434 -426.406891) (xy 69.234812 -426.41901) (xy 69.234812 -427.960536) (xy 70.141084 -427.960536)
			(xy 70.141084 -427.233588) (xy 70.141368 -427.224753) (xy 70.145481 -427.207566) (xy 70.149212 -427.199552)
			(xy 70.382638 -426.723302) (xy 70.387324 -426.71278) (xy 70.390818 -426.690025) (xy 70.387339 -426.667268)
			(xy 70.382638 -426.656754) (xy 70.149212 -426.180504) (xy 70.145457 -426.172498) (xy 70.14134 -426.155306)
			(xy 70.141084 -426.146468) (xy 70.141084 -425.419012) (xy 70.141527 -425.406905) (xy 70.149021 -425.383881)
			(xy 70.163276 -425.364309) (xy 70.182891 -425.350114) (xy 70.205938 -425.34269) (xy 70.218046 -425.342304)
			(xy 71.157846 -425.342304) (xy 71.169934 -425.342767) (xy 71.19293 -425.350232) (xy 71.207224 -425.360592)
			(xy 72.14108 -425.360592) (xy 72.14108 -422.819068) (xy 72.141489 -422.806959) (xy 72.148995 -422.783935)
			(xy 72.163259 -422.764364) (xy 72.18288 -422.75017) (xy 72.205932 -422.742746) (xy 72.218042 -422.74236)
			(xy 73.157842 -422.74236) (xy 73.169936 -422.742772) (xy 73.192941 -422.750243) (xy 73.212522 -422.764443)
			(xy 73.226771 -422.783989) (xy 73.234298 -422.806975) (xy 73.234804 -422.819068) (xy 73.234804 -424.80464)
			(xy 109.929157 -424.80464) (xy 109.929157 -424.6755) (xy 109.937107 -424.546605) (xy 109.952977 -424.418445)
			(xy 109.976706 -424.291504) (xy 110.008205 -424.166265) (xy 110.047354 -424.043202) (xy 110.094005 -423.922783)
			(xy 110.14798 -423.805464) (xy 110.209075 -423.69169) (xy 110.277058 -423.581893) (xy 110.351672 -423.47649)
			(xy 110.432633 -423.37588) (xy 110.519633 -423.280445) (xy 110.612344 -423.190546) (xy 110.710414 -423.106525)
			(xy 110.813469 -423.028701) (xy 110.92112 -422.957369) (xy 111.032959 -422.892799) (xy 111.14856 -422.835237)
			(xy 111.267485 -422.7849) (xy 111.389284 -422.74198) (xy 111.513494 -422.706639) (xy 111.639643 -422.679012)
			(xy 111.767255 -422.659203) (xy 111.895844 -422.647287) (xy 112.024922 -422.643311) (xy 112.154 -422.647287)
			(xy 112.282589 -422.659203) (xy 112.410201 -422.679012) (xy 112.53635 -422.706639) (xy 112.66056 -422.74198)
			(xy 112.782359 -422.7849) (xy 112.901284 -422.835237) (xy 113.016885 -422.892799) (xy 113.128724 -422.957369)
			(xy 113.236375 -423.028701) (xy 113.33943 -423.106525) (xy 113.4375 -423.190546) (xy 113.530211 -423.280445)
			(xy 113.617211 -423.37588) (xy 113.698172 -423.47649) (xy 113.772786 -423.581893) (xy 113.840769 -423.69169)
			(xy 113.901864 -423.805464) (xy 113.955839 -423.922783) (xy 114.00249 -424.043202) (xy 114.041639 -424.166265)
			(xy 114.073138 -424.291504) (xy 114.096867 -424.418445) (xy 114.112737 -424.546605) (xy 114.120687 -424.6755)
			(xy 114.121184 -424.74007) (xy 114.120687 -424.80464) (xy 114.112737 -424.933535) (xy 114.096867 -425.061695)
			(xy 114.073138 -425.188636) (xy 114.041639 -425.313875) (xy 114.00249 -425.436938) (xy 113.955839 -425.557357)
			(xy 113.901864 -425.674676) (xy 113.840769 -425.78845) (xy 113.772786 -425.898247) (xy 113.698172 -426.00365)
			(xy 113.617211 -426.10426) (xy 113.530211 -426.199695) (xy 113.4375 -426.289594) (xy 113.33943 -426.373615)
			(xy 113.236375 -426.451439) (xy 113.128724 -426.522771) (xy 113.016885 -426.587341) (xy 112.901284 -426.644903)
			(xy 112.782359 -426.69524) (xy 112.66056 -426.73816) (xy 112.53635 -426.773501) (xy 112.410201 -426.801128)
			(xy 112.282589 -426.820937) (xy 112.154 -426.832853) (xy 112.024922 -426.83683) (xy 111.895844 -426.832853)
			(xy 111.767255 -426.820937) (xy 111.639643 -426.801128) (xy 111.513494 -426.773501) (xy 111.389284 -426.73816)
			(xy 111.267485 -426.69524) (xy 111.14856 -426.644903) (xy 111.032959 -426.587341) (xy 110.92112 -426.522771)
			(xy 110.813469 -426.451439) (xy 110.710414 -426.373615) (xy 110.612344 -426.289594) (xy 110.519633 -426.199695)
			(xy 110.432633 -426.10426) (xy 110.351672 -426.00365) (xy 110.277058 -425.898247) (xy 110.209075 -425.78845)
			(xy 110.14798 -425.674676) (xy 110.094005 -425.557357) (xy 110.047354 -425.436938) (xy 110.008205 -425.313875)
			(xy 109.976706 -425.188636) (xy 109.952977 -425.061695) (xy 109.937107 -424.933535) (xy 109.929157 -424.80464)
			(xy 73.234804 -424.80464) (xy 73.234804 -425.360592) (xy 73.234377 -425.3727) (xy 73.22688 -425.395727)
			(xy 73.212621 -425.415299) (xy 73.193002 -425.429495) (xy 73.169951 -425.436916) (xy 73.157842 -425.4373)
			(xy 72.218042 -425.4373) (xy 72.205959 -425.436758) (xy 72.182966 -425.429317) (xy 72.163389 -425.415149)
			(xy 72.149135 -425.395633) (xy 72.141595 -425.372673) (xy 72.14108 -425.360592) (xy 71.207224 -425.360592)
			(xy 71.212507 -425.364421) (xy 71.226757 -425.383953) (xy 71.234294 -425.406925) (xy 71.234808 -425.419012)
			(xy 71.234808 -427.960536) (xy 71.234414 -427.972646) (xy 71.226906 -427.995673) (xy 71.212638 -428.015245)
			(xy 71.193013 -428.029438) (xy 71.169957 -428.03686) (xy 71.157846 -428.037244) (xy 70.218046 -428.037244)
			(xy 70.205957 -428.036753) (xy 70.182955 -428.029307) (xy 70.163373 -428.015127) (xy 70.149122 -427.995597)
			(xy 70.141591 -427.972623) (xy 70.141084 -427.960536) (xy 69.234812 -427.960536) (xy 69.234812 -428.960534)
			(xy 69.234318 -428.972645) (xy 69.226828 -428.995681) (xy 69.21259 -429.015278) (xy 69.192996 -429.02952)
			(xy 69.169961 -429.037016) (xy 69.15785 -429.037496) (xy 68.21805 -429.037496) (xy 68.205936 -429.037031)
			(xy 68.182897 -429.029535) (xy 68.163299 -429.015289) (xy 68.149058 -428.995689) (xy 68.141566 -428.972648)
			(xy 68.141088 -428.960534) (xy 67.207487 -428.960534) (xy 67.212594 -428.96424) (xy 67.226839 -428.983822)
			(xy 67.234335 -429.006847) (xy 67.234816 -429.018954) (xy 67.234816 -431.560478) (xy 67.234421 -431.572604)
			(xy 67.226929 -431.59567) (xy 67.212672 -431.61529) (xy 67.193049 -431.62954) (xy 67.16998 -431.637024)
			(xy 67.157854 -431.63744) (xy 66.218054 -431.63744) (xy 66.205935 -431.637027) (xy 66.182886 -431.629525)
			(xy 66.163284 -431.615268) (xy 66.149044 -431.595653) (xy 66.141562 -431.572598) (xy 66.141092 -431.560478)
			(xy 65.23482 -431.560478) (xy 65.23482 -432.560476) (xy 65.234363 -432.572582) (xy 65.226873 -432.595605)
			(xy 65.212621 -432.615176) (xy 65.193009 -432.629373) (xy 65.169965 -432.636797) (xy 65.157858 -432.637184)
			(xy 64.218058 -432.637184) (xy 64.205969 -432.636729) (xy 64.182971 -432.629264) (xy 64.163393 -432.615073)
			(xy 64.149143 -432.595539) (xy 64.141608 -432.572564) (xy 64.141096 -432.560476) (xy 63.207295 -432.560476)
			(xy 63.212547 -432.564281) (xy 63.226797 -432.583821) (xy 63.234321 -432.606805) (xy 63.234824 -432.618896)
			(xy 63.234824 -435.16042) (xy 63.234401 -435.172528) (xy 63.226899 -435.195551) (xy 63.212638 -435.215122)
			(xy 63.19302 -435.229317) (xy 63.169971 -435.236741) (xy 63.157862 -435.237128) (xy 62.218062 -435.237128)
			(xy 62.205967 -435.236724) (xy 62.18296 -435.229253) (xy 62.163378 -435.215052) (xy 62.14913 -435.195503)
			(xy 62.141604 -435.172514) (xy 62.1411 -435.16042) (xy 61.234828 -435.16042) (xy 61.234828 -436.160418)
			(xy 61.234455 -436.172545) (xy 61.226953 -436.19561) (xy 61.212691 -436.215228) (xy 61.193064 -436.229477)
			(xy 61.169993 -436.236963) (xy 61.157866 -436.23738) (xy 60.218066 -436.23738) (xy 60.205951 -436.236918)
			(xy 60.18291 -436.229423) (xy 60.16331 -436.215178) (xy 60.149069 -436.195576) (xy 60.14158 -436.172533)
			(xy 60.141104 -436.160418) (xy 59.206951 -436.160418) (xy 59.212554 -436.164477) (xy 59.226804 -436.184017)
			(xy 59.234329 -436.207001) (xy 59.234832 -436.219092) (xy 59.234832 -438.760616) (xy 59.234398 -438.772723)
			(xy 59.226898 -438.795745) (xy 59.21264 -438.815315) (xy 59.193024 -438.82951) (xy 59.169978 -438.836936)
			(xy 59.15787 -438.837324) (xy 58.21807 -438.837324) (xy 58.205975 -438.836918) (xy 58.182968 -438.829448)
			(xy 58.163385 -438.815247) (xy 58.149137 -438.795699) (xy 58.141612 -438.77271) (xy 58.141108 -438.760616)
			(xy 7.00913 -438.760616) (xy 7.00913 -439.760614) (xy 60.141104 -439.760614) (xy 60.141104 -437.21909)
			(xy 60.141603 -437.206978) (xy 60.149089 -437.183941) (xy 60.163325 -437.164342) (xy 60.182919 -437.1501)
			(xy 60.205954 -437.142607) (xy 60.218066 -437.142128) (xy 61.157866 -437.142128) (xy 61.169986 -437.142589)
			(xy 61.193042 -437.15007) (xy 61.212657 -437.164312) (xy 61.22691 -437.183918) (xy 61.234404 -437.20697)
			(xy 61.234828 -437.21909) (xy 61.234828 -438.760616) (xy 62.1411 -438.760616) (xy 62.1411 -436.219092)
			(xy 62.141509 -436.206983) (xy 62.149011 -436.183955) (xy 62.163274 -436.164382) (xy 62.182897 -436.150188)
			(xy 62.205951 -436.142767) (xy 62.218062 -436.142384) (xy 63.157862 -436.142384) (xy 63.169954 -436.142841)
			(xy 63.192961 -436.150292) (xy 63.206938 -436.160418) (xy 64.141096 -436.160418) (xy 64.141096 -433.618894)
			(xy 64.141606 -433.606783) (xy 64.14909 -433.583747) (xy 64.163324 -433.564149) (xy 64.182915 -433.549906)
			(xy 64.205948 -433.542412) (xy 64.218058 -433.541932) (xy 65.157858 -433.541932) (xy 65.169978 -433.542396)
			(xy 65.193034 -433.549876) (xy 65.21265 -433.564116) (xy 65.226903 -433.583722) (xy 65.234397 -433.606774)
			(xy 65.23482 -433.618894) (xy 65.23482 -435.16042) (xy 66.141092 -435.16042) (xy 66.141092 -432.618896)
			(xy 66.141513 -432.606788) (xy 66.149012 -432.583762) (xy 66.163273 -432.564189) (xy 66.182893 -432.549994)
			(xy 66.205944 -432.542572) (xy 66.218054 -432.542188) (xy 67.157854 -432.542188) (xy 67.169946 -432.542647)
			(xy 67.192953 -432.550097) (xy 67.207281 -432.560476) (xy 68.141088 -432.560476) (xy 68.141088 -430.018952)
			(xy 68.141475 -430.006842) (xy 68.148987 -429.983815) (xy 68.163256 -429.964244) (xy 68.182883 -429.95005)
			(xy 68.205938 -429.942629) (xy 68.21805 -429.942244) (xy 69.15785 -429.942244) (xy 69.169937 -429.94275)
			(xy 69.192937 -429.950193) (xy 69.212518 -429.96437) (xy 69.22677 -429.983896) (xy 69.234303 -430.006866)
			(xy 69.234812 -430.018952) (xy 69.234812 -431.560478) (xy 70.141084 -431.560478) (xy 70.141084 -429.018954)
			(xy 70.141473 -429.006832) (xy 70.148979 -428.98378) (xy 70.16324 -428.964175) (xy 70.182862 -428.949937)
			(xy 70.205924 -428.942459) (xy 70.218046 -428.941992) (xy 71.157846 -428.941992) (xy 71.169958 -428.942472)
			(xy 71.192995 -428.949966) (xy 71.207537 -428.960534) (xy 72.14108 -428.960534) (xy 72.14108 -428.233586)
			(xy 72.141364 -428.224751) (xy 72.145477 -428.207564) (xy 72.149208 -428.19955) (xy 72.382634 -427.7233)
			(xy 72.387322 -427.712778) (xy 72.390815 -427.690023) (xy 72.387336 -427.667266) (xy 72.382634 -427.656752)
			(xy 72.149208 -427.180502) (xy 72.145452 -427.172496) (xy 72.141336 -427.155304) (xy 72.14108 -427.146466)
			(xy 72.14108 -426.41901) (xy 72.141469 -426.406884) (xy 72.148964 -426.383818) (xy 72.163222 -426.364199)
			(xy 72.182847 -426.349949) (xy 72.205915 -426.342464) (xy 72.218042 -426.342048) (xy 73.157842 -426.342048)
			(xy 73.16996 -426.342476) (xy 73.193006 -426.349976) (xy 73.212608 -426.364229) (xy 73.226848 -426.383841)
			(xy 73.234332 -426.406892) (xy 73.234804 -426.41901) (xy 73.234804 -427.960536) (xy 75.141328 -427.960536)
			(xy 75.141328 -427.233334) (xy 75.141596 -427.224578) (xy 75.145564 -427.20752) (xy 75.149202 -427.199552)
			(xy 75.382628 -426.723302) (xy 75.387315 -426.71278) (xy 75.390809 -426.690025) (xy 75.38733 -426.667268)
			(xy 75.382628 -426.656754) (xy 75.149202 -426.180504) (xy 75.145541 -426.172543) (xy 75.141564 -426.155482)
			(xy 75.141328 -426.146722) (xy 75.141328 -425.419012) (xy 75.141724 -425.406926) (xy 75.149192 -425.383938)
			(xy 75.163402 -425.364384) (xy 75.18296 -425.350181) (xy 75.20595 -425.34272) (xy 75.218036 -425.342304)
			(xy 76.157836 -425.342304) (xy 76.169914 -425.342734) (xy 76.192884 -425.350207) (xy 76.212422 -425.364413)
			(xy 76.226615 -425.383959) (xy 76.234074 -425.406934) (xy 76.234544 -425.419012) (xy 76.234544 -427.960536)
			(xy 76.234067 -427.972609) (xy 76.226599 -427.995571) (xy 76.212405 -428.015105) (xy 76.192871 -428.029299)
			(xy 76.169909 -428.036767) (xy 76.157836 -428.037244) (xy 75.218036 -428.037244) (xy 75.205967 -428.036706)
			(xy 75.183007 -428.029258) (xy 75.163472 -428.015079) (xy 75.149275 -427.995558) (xy 75.141806 -427.972605)
			(xy 75.141328 -427.960536) (xy 73.234804 -427.960536) (xy 73.234804 -428.960534) (xy 73.234318 -428.972646)
			(xy 73.226827 -428.995683) (xy 73.212587 -429.015281) (xy 73.192991 -429.029523) (xy 73.169954 -429.037017)
			(xy 73.157842 -429.037496) (xy 72.218042 -429.037496) (xy 72.205925 -429.037005) (xy 72.182873 -429.029528)
			(xy 72.16326 -429.015294) (xy 72.149006 -428.995695) (xy 72.141507 -428.972651) (xy 72.14108 -428.960534)
			(xy 71.207537 -428.960534) (xy 71.212592 -428.964208) (xy 71.226834 -428.983805) (xy 71.234328 -429.006842)
			(xy 71.234808 -429.018954) (xy 71.234808 -431.560478) (xy 71.23427 -431.572587) (xy 71.226795 -431.595622)
			(xy 71.212568 -431.61522) (xy 71.192983 -431.629464) (xy 71.169954 -431.636959) (xy 71.157846 -431.63744)
			(xy 70.218046 -431.63744) (xy 70.205923 -431.637001) (xy 70.182862 -431.629518) (xy 70.163245 -431.615273)
			(xy 70.148993 -431.595659) (xy 70.141503 -431.5726) (xy 70.141084 -431.560478) (xy 69.234812 -431.560478)
			(xy 69.234812 -432.560476) (xy 69.234363 -432.572582) (xy 69.226872 -432.595607) (xy 69.212618 -432.615179)
			(xy 69.193004 -432.629375) (xy 69.169958 -432.636799) (xy 69.15785 -432.637184) (xy 68.21805 -432.637184)
			(xy 68.205965 -432.636651) (xy 68.18297 -432.62921) (xy 68.163392 -432.61504) (xy 68.149139 -432.595522)
			(xy 68.141601 -432.572559) (xy 68.141088 -432.560476) (xy 67.207281 -432.560476) (xy 67.212538 -432.564284)
			(xy 67.226788 -432.583823) (xy 67.234313 -432.606806) (xy 67.234816 -432.618896) (xy 67.234816 -435.16042)
			(xy 67.234401 -435.172528) (xy 67.226898 -435.195554) (xy 67.212636 -435.215125) (xy 67.193015 -435.229319)
			(xy 67.169964 -435.236743) (xy 67.157854 -435.237128) (xy 66.218054 -435.237128) (xy 66.205959 -435.236731)
			(xy 66.182951 -435.229258) (xy 66.163369 -435.215054) (xy 66.149122 -435.195505) (xy 66.141596 -435.172514)
			(xy 66.141092 -435.16042) (xy 65.23482 -435.16042) (xy 65.23482 -436.160418) (xy 65.234454 -436.172546)
			(xy 65.226952 -436.195612) (xy 65.212688 -436.215231) (xy 65.193058 -436.22948) (xy 65.169986 -436.236964)
			(xy 65.157858 -436.23738) (xy 64.218058 -436.23738) (xy 64.205943 -436.236924) (xy 64.182901 -436.229428)
			(xy 64.163302 -436.215181) (xy 64.149061 -436.195577) (xy 64.141572 -436.172533) (xy 64.141096 -436.160418)
			(xy 63.206938 -436.160418) (xy 63.212545 -436.16448) (xy 63.226795 -436.184019) (xy 63.234321 -436.207002)
			(xy 63.234824 -436.219092) (xy 63.234824 -438.760616) (xy 63.234398 -438.772723) (xy 63.226897 -438.795747)
			(xy 63.212637 -438.815318) (xy 63.193019 -438.829513) (xy 63.169971 -438.836937) (xy 63.157862 -438.837324)
			(xy 62.218062 -438.837324) (xy 62.205967 -438.836924) (xy 62.182959 -438.829453) (xy 62.163377 -438.81525)
			(xy 62.149129 -438.795701) (xy 62.141604 -438.77271) (xy 62.1411 -438.760616) (xy 61.234828 -438.760616)
			(xy 61.234828 -439.760614) (xy 64.141096 -439.760614) (xy 64.141096 -437.21909) (xy 64.141603 -437.206979)
			(xy 64.149088 -437.183943) (xy 64.163322 -437.164345) (xy 64.182914 -437.150102) (xy 64.205947 -437.142608)
			(xy 64.218058 -437.142128) (xy 65.157858 -437.142128) (xy 65.169978 -437.142595) (xy 65.193033 -437.150075)
			(xy 65.212648 -437.164315) (xy 65.226901 -437.18392) (xy 65.234396 -437.206971) (xy 65.23482 -437.21909)
			(xy 65.23482 -438.760616) (xy 66.141092 -438.760616) (xy 66.141092 -436.219092) (xy 66.141509 -436.206983)
			(xy 66.14901 -436.183957) (xy 66.163272 -436.164385) (xy 66.182892 -436.15019) (xy 66.205944 -436.142768)
			(xy 66.218054 -436.142384) (xy 67.157854 -436.142384) (xy 67.169946 -436.142847) (xy 67.192952 -436.150297)
			(xy 67.206925 -436.160418) (xy 68.141088 -436.160418) (xy 68.141088 -433.618894) (xy 68.141606 -433.606784)
			(xy 68.149089 -433.583749) (xy 68.163321 -433.564152) (xy 68.18291 -433.549909) (xy 68.20594 -433.542413)
			(xy 68.21805 -433.541932) (xy 69.15785 -433.541932) (xy 69.169967 -433.542369) (xy 69.19301 -433.549869)
			(xy 69.212611 -433.564121) (xy 69.226851 -433.583729) (xy 69.234338 -433.606777) (xy 69.234812 -433.618894)
			(xy 69.234812 -435.16042) (xy 70.141084 -435.16042) (xy 70.141084 -432.618896) (xy 70.141513 -432.606789)
			(xy 70.149011 -432.583764) (xy 70.16327 -432.564192) (xy 70.182888 -432.549997) (xy 70.205937 -432.542573)
			(xy 70.218046 -432.542188) (xy 71.157846 -432.542188) (xy 71.169943 -432.542569) (xy 71.192953 -432.550044)
			(xy 71.207333 -432.560476) (xy 72.14108 -432.560476) (xy 72.14108 -430.018952) (xy 72.141475 -430.006843)
			(xy 72.148986 -429.983817) (xy 72.163253 -429.964247) (xy 72.182877 -429.950053) (xy 72.205931 -429.94263)
			(xy 72.218042 -429.942244) (xy 73.157842 -429.942244) (xy 73.169934 -429.942672) (xy 73.192937 -429.95014)
			(xy 73.212516 -429.964337) (xy 73.226765 -429.983879) (xy 73.234296 -430.006861) (xy 73.234804 -430.018952)
			(xy 73.234804 -431.560478) (xy 75.141328 -431.560478) (xy 75.141328 -429.018954) (xy 75.141768 -429.006863)
			(xy 75.149236 -428.983863) (xy 75.16343 -428.964285) (xy 75.182968 -428.950036) (xy 75.205947 -428.942503)
			(xy 75.218036 -428.941992) (xy 76.157836 -428.941992) (xy 76.169946 -428.942386) (xy 76.192973 -428.949894)
			(xy 76.207568 -428.960534) (xy 77.141324 -428.960534) (xy 77.141324 -428.233332) (xy 77.141591 -428.224576)
			(xy 77.14556 -428.207518) (xy 77.149198 -428.19955) (xy 77.382624 -427.7233) (xy 77.387312 -427.712778)
			(xy 77.390806 -427.690023) (xy 77.387326 -427.667266) (xy 77.382624 -427.656752) (xy 77.149198 -427.180502)
			(xy 77.145536 -427.172541) (xy 77.14156 -427.15548) (xy 77.141324 -427.14672) (xy 77.141324 -426.41901)
			(xy 77.141816 -426.406923) (xy 77.149268 -426.383925) (xy 77.163449 -426.364346) (xy 77.182976 -426.350095)
			(xy 77.205946 -426.34256) (xy 77.218032 -426.342048) (xy 78.157832 -426.342048) (xy 78.169937 -426.342488)
			(xy 78.192957 -426.34999) (xy 78.212525 -426.364248) (xy 78.22672 -426.38386) (xy 78.234149 -426.406903)
			(xy 78.23454 -426.41901) (xy 78.23454 -427.960536) (xy 79.14132 -427.960536) (xy 79.14132 -427.233334)
			(xy 79.141589 -427.224578) (xy 79.145556 -427.20752) (xy 79.149194 -427.199552) (xy 79.38262 -426.723302)
			(xy 79.387307 -426.71278) (xy 79.390801 -426.690025) (xy 79.387322 -426.667268) (xy 79.38262 -426.656754)
			(xy 79.149194 -426.180504) (xy 79.145532 -426.172543) (xy 79.141556 -426.155482) (xy 79.14132 -426.146722)
			(xy 79.14132 -425.419012) (xy 79.141724 -425.406927) (xy 79.149191 -425.38394) (xy 79.163399 -425.364387)
			(xy 79.182954 -425.350184) (xy 79.205943 -425.342721) (xy 79.218028 -425.342304) (xy 80.157828 -425.342304)
			(xy 80.169905 -425.34274) (xy 80.192875 -425.350212) (xy 80.212413 -425.364415) (xy 80.226606 -425.38396)
			(xy 80.234066 -425.406935) (xy 80.234536 -425.419012) (xy 80.234536 -427.960536) (xy 80.234067 -427.97261)
			(xy 80.226598 -427.995573) (xy 80.212402 -428.015107) (xy 80.192866 -428.029302) (xy 80.169902 -428.036768)
			(xy 80.157828 -428.037244) (xy 79.218028 -428.037244) (xy 79.205958 -428.036713) (xy 79.182998 -428.029262)
			(xy 79.163464 -428.015082) (xy 79.149267 -427.995559) (xy 79.141797 -427.972605) (xy 79.14132 -427.960536)
			(xy 78.23454 -427.960536) (xy 78.23454 -428.960534) (xy 78.234121 -428.972627) (xy 78.226653 -428.995632)
			(xy 78.212454 -429.015214) (xy 78.19291 -429.029462) (xy 78.169924 -429.03699) (xy 78.157832 -429.037496)
			(xy 77.218032 -429.037496) (xy 77.205924 -429.037056) (xy 77.182898 -429.029565) (xy 77.163324 -429.01531)
			(xy 77.149128 -428.995692) (xy 77.141707 -428.972643) (xy 77.141324 -428.960534) (xy 76.207568 -428.960534)
			(xy 76.212545 -428.964162) (xy 76.226738 -428.983787) (xy 76.23416 -429.006843) (xy 76.234544 -429.018954)
			(xy 76.234544 -431.560478) (xy 76.234074 -431.572568) (xy 76.226621 -431.595571) (xy 76.212436 -431.615152)
			(xy 76.192902 -431.629403) (xy 76.169924 -431.636933) (xy 76.157836 -431.63744) (xy 75.218036 -431.63744)
			(xy 75.205933 -431.636953) (xy 75.182914 -431.629469) (xy 75.163344 -431.615224) (xy 75.149146 -431.595619)
			(xy 75.141718 -431.572582) (xy 75.141328 -431.560478) (xy 73.234804 -431.560478) (xy 73.234804 -432.560476)
			(xy 73.234363 -432.572583) (xy 73.226871 -432.595609) (xy 73.212615 -432.615182) (xy 73.192999 -432.629378)
			(xy 73.16995 -432.6368) (xy 73.157842 -432.637184) (xy 72.218042 -432.637184) (xy 72.205957 -432.636657)
			(xy 72.182962 -432.629215) (xy 72.163383 -432.615043) (xy 72.14913 -432.595523) (xy 72.141593 -432.572559)
			(xy 72.14108 -432.560476) (xy 71.207333 -432.560476) (xy 71.212536 -432.564251) (xy 71.226784 -432.583805)
			(xy 71.234306 -432.6068) (xy 71.234808 -432.618896) (xy 71.234808 -435.16042) (xy 71.234401 -435.172529)
			(xy 71.226897 -435.195556) (xy 71.212633 -435.215128) (xy 71.19301 -435.229322) (xy 71.169957 -435.236744)
			(xy 71.157846 -435.237128) (xy 70.218046 -435.237128) (xy 70.205956 -435.236653) (xy 70.182951 -435.229205)
			(xy 70.163368 -435.215022) (xy 70.149117 -435.195487) (xy 70.141589 -435.172509) (xy 70.141084 -435.16042)
			(xy 69.234812 -435.16042) (xy 69.234812 -436.160418) (xy 69.234305 -436.172529) (xy 69.226818 -436.195564)
			(xy 69.212584 -436.215161) (xy 69.192993 -436.229404) (xy 69.16996 -436.2369) (xy 69.15785 -436.23738)
			(xy 68.21805 -436.23738) (xy 68.205935 -436.236931) (xy 68.182893 -436.229432) (xy 68.163293 -436.215184)
			(xy 68.149053 -436.195578) (xy 68.141564 -436.172534) (xy 68.141088 -436.160418) (xy 67.206925 -436.160418)
			(xy 67.212537 -436.164483) (xy 67.226787 -436.18402) (xy 67.234312 -436.207002) (xy 67.234816 -436.219092)
			(xy 67.234816 -438.760616) (xy 67.234398 -438.772724) (xy 67.226896 -438.795749) (xy 67.212634 -438.815321)
			(xy 67.193014 -438.829515) (xy 67.169963 -438.836939) (xy 67.157854 -438.837324) (xy 66.218054 -438.837324)
			(xy 66.205958 -438.836931) (xy 66.18295 -438.829457) (xy 66.163368 -438.815253) (xy 66.14912 -438.795702)
			(xy 66.141596 -438.77271) (xy 66.141092 -438.760616) (xy 65.23482 -438.760616) (xy 65.23482 -439.760614)
			(xy 68.141088 -439.760614) (xy 68.141088 -437.21909) (xy 68.141603 -437.20698) (xy 68.149087 -437.183945)
			(xy 68.163319 -437.164348) (xy 68.182909 -437.150105) (xy 68.20594 -437.142609) (xy 68.21805 -437.142128)
			(xy 69.15785 -437.142128) (xy 69.169966 -437.142569) (xy 69.193009 -437.150069) (xy 69.212609 -437.164319)
			(xy 69.22685 -437.183927) (xy 69.234337 -437.206974) (xy 69.234812 -437.21909) (xy 69.234812 -438.760616)
			(xy 70.141084 -438.760616) (xy 70.141084 -436.219092) (xy 70.141509 -436.206984) (xy 70.149009 -436.183959)
			(xy 70.163269 -436.164388) (xy 70.182887 -436.150193) (xy 70.205937 -436.142769) (xy 70.218046 -436.142384)
			(xy 71.157846 -436.142384) (xy 71.169942 -436.142769) (xy 71.192952 -436.150244) (xy 71.206977 -436.160418)
			(xy 72.14108 -436.160418) (xy 72.14108 -433.618894) (xy 72.141456 -433.606767) (xy 72.148955 -433.583701)
			(xy 72.163216 -433.564082) (xy 72.182844 -433.549833) (xy 72.205915 -433.542348) (xy 72.218042 -433.541932)
			(xy 73.157842 -433.541932) (xy 73.169958 -433.542376) (xy 73.193002 -433.549874) (xy 73.212602 -433.564123)
			(xy 73.226843 -433.583731) (xy 73.23433 -433.606778) (xy 73.234804 -433.618894) (xy 73.234804 -435.16042)
			(xy 75.141328 -435.16042) (xy 75.141328 -432.618896) (xy 75.14171 -432.606809) (xy 75.149183 -432.58382)
			(xy 75.163396 -432.564267) (xy 75.182956 -432.550064) (xy 75.205949 -432.542603) (xy 75.218036 -432.542188)
			(xy 76.157836 -432.542188) (xy 76.169912 -432.542633) (xy 76.19288 -432.550105) (xy 76.207146 -432.560476)
			(xy 77.141324 -432.560476) (xy 77.141324 -430.018952) (xy 77.141724 -430.006872) (xy 77.149203 -429.983898)
			(xy 77.163415 -429.964358) (xy 77.182969 -429.950167) (xy 77.205951 -429.942711) (xy 77.218032 -429.942244)
			(xy 78.157832 -429.942244) (xy 78.169903 -429.942736) (xy 78.192864 -429.950201) (xy 78.212396 -429.964393)
			(xy 78.226591 -429.983922) (xy 78.234062 -430.006881) (xy 78.23454 -430.018952) (xy 78.23454 -431.560478)
			(xy 79.14132 -431.560478) (xy 79.14132 -429.018954) (xy 79.141768 -429.006864) (xy 79.149235 -428.983865)
			(xy 79.163427 -428.964288) (xy 79.182963 -428.950038) (xy 79.205939 -428.942504) (xy 79.218028 -428.941992)
			(xy 80.157828 -428.941992) (xy 80.169938 -428.942392) (xy 80.192964 -428.949899) (xy 80.207555 -428.960534)
			(xy 81.141316 -428.960534) (xy 81.141316 -428.233332) (xy 81.141584 -428.224576) (xy 81.145552 -428.207518)
			(xy 81.14919 -428.19955) (xy 81.382616 -427.7233) (xy 81.387304 -427.712778) (xy 81.390798 -427.690023)
			(xy 81.387318 -427.667266) (xy 81.382616 -427.656752) (xy 81.14919 -427.180502) (xy 81.145528 -427.172541)
			(xy 81.141552 -427.15548) (xy 81.141316 -427.14672) (xy 81.141316 -426.41901) (xy 81.141816 -426.406923)
			(xy 81.149267 -426.383927) (xy 81.163446 -426.364349) (xy 81.182971 -426.350097) (xy 81.205939 -426.342561)
			(xy 81.218024 -426.342048) (xy 82.157824 -426.342048) (xy 82.169929 -426.342495) (xy 82.192948 -426.349995)
			(xy 82.212516 -426.36425) (xy 82.226712 -426.383862) (xy 82.234141 -426.406904) (xy 82.234532 -426.41901)
			(xy 82.234532 -427.960536) (xy 83.141312 -427.960536) (xy 83.141312 -427.233334) (xy 83.141581 -427.224578)
			(xy 83.145548 -427.20752) (xy 83.149186 -427.199552) (xy 83.382612 -426.723302) (xy 83.387299 -426.71278)
			(xy 83.390794 -426.690025) (xy 83.387314 -426.667268) (xy 83.382612 -426.656754) (xy 83.149186 -426.180504)
			(xy 83.145524 -426.172543) (xy 83.141548 -426.155482) (xy 83.141312 -426.146722) (xy 83.141312 -425.419012)
			(xy 83.141723 -425.406928) (xy 83.14919 -425.383942) (xy 83.163396 -425.36439) (xy 83.182949 -425.350186)
			(xy 83.205936 -425.342722) (xy 83.21802 -425.342304) (xy 84.15782 -425.342304) (xy 84.169897 -425.342748)
			(xy 84.192867 -425.350217) (xy 84.212404 -425.364419) (xy 84.226598 -425.383962) (xy 84.234057 -425.406935)
			(xy 84.234528 -425.419012) (xy 84.234528 -427.960536) (xy 84.234067 -427.97261) (xy 84.226597 -427.995576)
			(xy 84.212399 -428.01511) (xy 84.192861 -428.029304) (xy 84.169895 -428.036769) (xy 84.15782 -428.037244)
			(xy 83.21802 -428.037244) (xy 83.20595 -428.036719) (xy 83.18299 -428.029267) (xy 83.163455 -428.015085)
			(xy 83.149259 -427.995561) (xy 83.141789 -427.972606) (xy 83.141312 -427.960536) (xy 82.234532 -427.960536)
			(xy 82.234532 -428.960534) (xy 82.234121 -428.972628) (xy 82.226652 -428.995635) (xy 82.212452 -429.015216)
			(xy 82.192905 -429.029465) (xy 82.169917 -429.036991) (xy 82.157824 -429.037496) (xy 81.218024 -429.037496)
			(xy 81.205916 -429.037063) (xy 81.182889 -429.02957) (xy 81.163315 -429.015313) (xy 81.14912 -428.995694)
			(xy 81.141699 -428.972643) (xy 81.141316 -428.960534) (xy 80.207555 -428.960534) (xy 80.212536 -428.964165)
			(xy 80.22673 -428.983789) (xy 80.234152 -429.006843) (xy 80.234536 -429.018954) (xy 80.234536 -431.560478)
			(xy 80.234073 -431.572569) (xy 80.22662 -431.595573) (xy 80.212433 -431.615155) (xy 80.192897 -431.629405)
			(xy 80.169917 -431.636934) (xy 80.157828 -431.63744) (xy 79.218028 -431.63744) (xy 79.205925 -431.63696)
			(xy 79.182905 -431.629473) (xy 79.163335 -431.615227) (xy 79.149138 -431.595621) (xy 79.141709 -431.572582)
			(xy 79.14132 -431.560478) (xy 78.23454 -431.560478) (xy 78.23454 -432.560476) (xy 78.234016 -432.572546)
			(xy 78.226564 -432.595507) (xy 78.212382 -432.615042) (xy 78.192857 -432.629238) (xy 78.169902 -432.636707)
			(xy 78.157832 -432.637184) (xy 77.218032 -432.637184) (xy 77.205949 -432.63676) (xy 77.182963 -432.629298)
			(xy 77.16341 -432.615096) (xy 77.149206 -432.595544) (xy 77.141742 -432.572559) (xy 77.141324 -432.560476)
			(xy 76.207146 -432.560476) (xy 76.212416 -432.564307) (xy 76.226609 -432.583849) (xy 76.234072 -432.60682)
			(xy 76.234544 -432.618896) (xy 76.234544 -435.16042) (xy 76.234053 -435.172492) (xy 76.22659 -435.195454)
			(xy 76.212399 -435.214987) (xy 76.192868 -435.229182) (xy 76.169908 -435.236651) (xy 76.157836 -435.237128)
			(xy 75.218036 -435.237128) (xy 75.205957 -435.236657) (xy 75.182979 -435.229202) (xy 75.16343 -435.21501)
			(xy 75.149224 -435.195471) (xy 75.141752 -435.172499) (xy 75.141328 -435.16042) (xy 73.234804 -435.16042)
			(xy 73.234804 -436.160418) (xy 73.234304 -436.172529) (xy 73.226817 -436.195566) (xy 73.212581 -436.215164)
			(xy 73.192988 -436.229406) (xy 73.169953 -436.236901) (xy 73.157842 -436.23738) (xy 72.218042 -436.23738)
			(xy 72.205923 -436.236905) (xy 72.182869 -436.229426) (xy 72.163255 -436.215188) (xy 72.149001 -436.195585)
			(xy 72.141505 -436.172536) (xy 72.14108 -436.160418) (xy 71.206977 -436.160418) (xy 71.212535 -436.16445)
			(xy 71.226782 -436.184003) (xy 71.234305 -436.206997) (xy 71.234808 -436.219092) (xy 71.234808 -438.760616)
			(xy 71.234398 -438.772725) (xy 71.226895 -438.795751) (xy 71.212631 -438.815324) (xy 71.193009 -438.829518)
			(xy 71.169956 -438.83694) (xy 71.157846 -438.837324) (xy 70.218046 -438.837324) (xy 70.205955 -438.836853)
			(xy 70.18295 -438.829404) (xy 70.163366 -438.81522) (xy 70.149115 -438.795685) (xy 70.141589 -438.772705)
			(xy 70.141084 -438.760616) (xy 69.234812 -438.760616) (xy 69.234812 -439.760614) (xy 72.14108 -439.760614)
			(xy 72.14108 -437.21909) (xy 72.141452 -437.206963) (xy 72.148952 -437.183896) (xy 72.163215 -437.164278)
			(xy 72.182843 -437.150029) (xy 72.205914 -437.142544) (xy 72.218042 -437.142128) (xy 73.157842 -437.142128)
			(xy 73.169958 -437.142576) (xy 73.193001 -437.150073) (xy 73.212601 -437.164322) (xy 73.226841 -437.183928)
			(xy 73.234329 -437.206974) (xy 73.234804 -437.21909) (xy 73.234804 -438.760616) (xy 75.141328 -438.760616)
			(xy 75.141328 -436.219092) (xy 75.141706 -436.207005) (xy 75.14918 -436.184016) (xy 75.163394 -436.164463)
			(xy 75.182956 -436.15026) (xy 75.205949 -436.142799) (xy 75.218036 -436.142384) (xy 76.157836 -436.142384)
			(xy 76.169912 -436.142833) (xy 76.192879 -436.150305) (xy 76.206792 -436.160418) (xy 77.141324 -436.160418)
			(xy 77.141324 -433.618894) (xy 77.141802 -433.606806) (xy 77.149259 -433.583808) (xy 77.163443 -433.564229)
			(xy 77.182973 -433.549978) (xy 77.205945 -433.542444) (xy 77.218032 -433.541932) (xy 78.157832 -433.541932)
			(xy 78.169946 -433.542289) (xy 78.19298 -433.549802) (xy 78.212555 -433.564077) (xy 78.226747 -433.583713)
			(xy 78.234161 -433.606779) (xy 78.23454 -433.618894) (xy 78.23454 -435.16042) (xy 79.14132 -435.16042)
			(xy 79.14132 -432.618896) (xy 79.141709 -432.60681) (xy 79.149182 -432.583823) (xy 79.163393 -432.56427)
			(xy 79.182951 -432.550067) (xy 79.205942 -432.542604) (xy 79.218028 -432.542188) (xy 80.157828 -432.542188)
			(xy 80.169904 -432.54264) (xy 80.192871 -432.55011) (xy 80.207132 -432.560476) (xy 81.141316 -432.560476)
			(xy 81.141316 -430.018952) (xy 81.141724 -430.006873) (xy 81.149202 -429.9839) (xy 81.163413 -429.964361)
			(xy 81.182964 -429.950169) (xy 81.205944 -429.942712) (xy 81.218024 -429.942244) (xy 82.157824 -429.942244)
			(xy 82.169895 -429.942743) (xy 82.192855 -429.950206) (xy 82.212387 -429.964396) (xy 82.226583 -429.983924)
			(xy 82.234053 -430.006881) (xy 82.234532 -430.018952) (xy 82.234532 -431.560478) (xy 83.141312 -431.560478)
			(xy 83.141312 -429.018954) (xy 83.141768 -429.006865) (xy 83.149234 -428.983867) (xy 83.163424 -428.964291)
			(xy 83.182958 -428.950041) (xy 83.205932 -428.942505) (xy 83.21802 -428.941992) (xy 84.15782 -428.941992)
			(xy 84.169929 -428.942399) (xy 84.192956 -428.949903) (xy 84.207543 -428.960534) (xy 85.141308 -428.960534)
			(xy 85.141308 -428.233332) (xy 85.141577 -428.224576) (xy 85.145544 -428.207518) (xy 85.149182 -428.19955)
			(xy 85.382608 -427.7233) (xy 85.387297 -427.712779) (xy 85.390791 -427.690023) (xy 85.387311 -427.667266)
			(xy 85.382608 -427.656752) (xy 85.149182 -427.180502) (xy 85.145519 -427.172542) (xy 85.141544 -427.15548)
			(xy 85.141308 -427.14672) (xy 85.141308 -426.41901) (xy 85.141815 -426.406924) (xy 85.149265 -426.383929)
			(xy 85.163443 -426.364352) (xy 85.182966 -426.3501) (xy 85.205932 -426.342562) (xy 85.218016 -426.342048)
			(xy 86.157816 -426.342048) (xy 86.169921 -426.342502) (xy 86.192939 -426.349999) (xy 86.212508 -426.364253)
			(xy 86.226704 -426.383863) (xy 86.234133 -426.406904) (xy 86.234524 -426.41901) (xy 86.234524 -427.960536)
			(xy 87.141304 -427.960536) (xy 87.141304 -427.233334) (xy 87.141574 -427.224578) (xy 87.145541 -427.207521)
			(xy 87.149178 -427.199552) (xy 87.382604 -426.723302) (xy 87.387292 -426.71278) (xy 87.390787 -426.690025)
			(xy 87.387307 -426.667268) (xy 87.382604 -426.656754) (xy 87.149178 -426.180504) (xy 87.145516 -426.172543)
			(xy 87.14154 -426.155482) (xy 87.141304 -426.146722) (xy 87.141304 -425.419012) (xy 87.141723 -425.406929)
			(xy 87.149189 -425.383944) (xy 87.163393 -425.364393) (xy 87.182944 -425.350189) (xy 87.205929 -425.342723)
			(xy 87.218012 -425.342304) (xy 88.157812 -425.342304) (xy 88.169888 -425.342754) (xy 88.192858 -425.350222)
			(xy 88.212396 -425.364421) (xy 88.226589 -425.383964) (xy 88.234049 -425.406935) (xy 88.23452 -425.419012)
			(xy 88.23452 -427.960536) (xy 88.234067 -427.972611) (xy 88.226596 -427.995578) (xy 88.212396 -428.015113)
			(xy 88.192856 -428.029307) (xy 88.169887 -428.036771) (xy 88.157812 -428.037244) (xy 87.218012 -428.037244)
			(xy 87.205942 -428.036726) (xy 87.182981 -428.029271) (xy 87.163447 -428.015087) (xy 87.149251 -427.995562)
			(xy 87.141781 -427.972606) (xy 87.141304 -427.960536) (xy 86.234524 -427.960536) (xy 86.234524 -428.960534)
			(xy 86.234121 -428.972629) (xy 86.226651 -428.995637) (xy 86.212449 -429.015219) (xy 86.1929 -429.029467)
			(xy 86.16991 -429.036992) (xy 86.157816 -429.037496) (xy 85.218016 -429.037496) (xy 85.205908 -429.03707)
			(xy 85.18288 -429.029574) (xy 85.163307 -429.015315) (xy 85.149112 -428.995695) (xy 85.141691 -428.972644)
			(xy 85.141308 -428.960534) (xy 84.207543 -428.960534) (xy 84.212528 -428.964167) (xy 84.226722 -428.98379)
			(xy 84.234144 -429.006843) (xy 84.234528 -429.018954) (xy 84.234528 -431.560478) (xy 84.234073 -431.57257)
			(xy 84.226619 -431.595575) (xy 84.21243 -431.615158) (xy 84.192892 -431.629408) (xy 84.16991 -431.636935)
			(xy 84.15782 -431.63744) (xy 83.21802 -431.63744) (xy 83.205916 -431.636967) (xy 83.182896 -431.629478)
			(xy 83.163327 -431.61523) (xy 83.14913 -431.595622) (xy 83.141701 -431.572583) (xy 83.141312 -431.560478)
			(xy 82.234532 -431.560478) (xy 82.234532 -432.560476) (xy 82.234016 -432.572547) (xy 82.226563 -432.595509)
			(xy 82.212379 -432.615045) (xy 82.192852 -432.629241) (xy 82.169895 -432.636708) (xy 82.157824 -432.637184)
			(xy 81.218024 -432.637184) (xy 81.20594 -432.636766) (xy 81.182954 -432.629303) (xy 81.163401 -432.615099)
			(xy 81.149197 -432.595546) (xy 81.141734 -432.57256) (xy 81.141316 -432.560476) (xy 80.207132 -432.560476)
			(xy 80.212407 -432.56431) (xy 80.226601 -432.58385) (xy 80.234064 -432.60682) (xy 80.234536 -432.618896)
			(xy 80.234536 -435.16042) (xy 80.234053 -435.172493) (xy 80.226588 -435.195456) (xy 80.212396 -435.21499)
			(xy 80.192863 -435.229185) (xy 80.169901 -435.236652) (xy 80.157828 -435.237128) (xy 79.218028 -435.237128)
			(xy 79.205949 -435.236664) (xy 79.18297 -435.229206) (xy 79.163421 -435.215013) (xy 79.149216 -435.195473)
			(xy 79.141744 -435.172499) (xy 79.14132 -435.16042) (xy 78.23454 -435.16042) (xy 78.23454 -436.160418)
			(xy 78.234108 -436.172511) (xy 78.226644 -436.195515) (xy 78.212449 -436.215097) (xy 78.192907 -436.229346)
			(xy 78.169923 -436.236874) (xy 78.157832 -436.23738) (xy 77.218032 -436.23738) (xy 77.205923 -436.236956)
			(xy 77.182893 -436.229463) (xy 77.163318 -436.215204) (xy 77.149123 -436.195582) (xy 77.141705 -436.172528)
			(xy 77.141324 -436.160418) (xy 76.206792 -436.160418) (xy 76.212415 -436.164505) (xy 76.226608 -436.184046)
			(xy 76.234071 -436.207016) (xy 76.234544 -436.219092) (xy 76.234544 -438.760616) (xy 76.23405 -438.772688)
			(xy 76.226587 -438.795649) (xy 76.212397 -438.815183) (xy 76.192867 -438.829378) (xy 76.169908 -438.836847)
			(xy 76.157836 -438.837324) (xy 75.218036 -438.837324) (xy 75.205957 -438.836857) (xy 75.182978 -438.829401)
			(xy 75.163428 -438.815209) (xy 75.149223 -438.795669) (xy 75.141751 -438.772695) (xy 75.141328 -438.760616)
			(xy 73.234804 -438.760616) (xy 73.234804 -439.760614) (xy 77.141324 -439.760614) (xy 77.141324 -437.21909)
			(xy 77.141799 -437.207002) (xy 77.149256 -437.184003) (xy 77.163441 -437.164425) (xy 77.182972 -437.150174)
			(xy 77.205945 -437.14264) (xy 77.218032 -437.142128) (xy 78.157832 -437.142128) (xy 78.169945 -437.142489)
			(xy 78.192978 -437.150001) (xy 78.212553 -437.164276) (xy 78.226746 -437.183911) (xy 78.234161 -437.206975)
			(xy 78.23454 -437.21909) (xy 78.23454 -438.760616) (xy 79.14132 -438.760616) (xy 79.14132 -436.219092)
			(xy 79.141706 -436.207006) (xy 79.149179 -436.184018) (xy 79.163391 -436.164466) (xy 79.182951 -436.150263)
			(xy 79.205942 -436.1428) (xy 79.218028 -436.142384) (xy 80.157828 -436.142384) (xy 80.169903 -436.14284)
			(xy 80.19287 -436.150309) (xy 80.206779 -436.160418) (xy 81.141316 -436.160418) (xy 81.141316 -433.618894)
			(xy 81.141802 -433.606807) (xy 81.149257 -433.58381) (xy 81.16344 -433.564232) (xy 81.182968 -433.549981)
			(xy 81.205938 -433.542445) (xy 81.218024 -433.541932) (xy 82.157824 -433.541932) (xy 82.169937 -433.542296)
			(xy 82.192971 -433.549806) (xy 82.212546 -433.56408) (xy 82.226739 -433.583715) (xy 82.234153 -433.606779)
			(xy 82.234532 -433.618894) (xy 82.234532 -435.16042) (xy 83.141312 -435.16042) (xy 83.141312 -432.618896)
			(xy 83.141709 -432.606811) (xy 83.14918 -432.583825) (xy 83.16339 -432.564273) (xy 83.182946 -432.550069)
			(xy 83.205935 -432.542606) (xy 83.21802 -432.542188) (xy 84.15782 -432.542188) (xy 84.169895 -432.542647)
			(xy 84.192862 -432.550115) (xy 84.207119 -432.560476) (xy 85.141308 -432.560476) (xy 85.141308 -430.018952)
			(xy 85.141723 -430.006873) (xy 85.149201 -429.983902) (xy 85.16341 -429.964364) (xy 85.182959 -429.950172)
			(xy 85.205937 -429.942713) (xy 85.218016 -429.942244) (xy 86.157816 -429.942244) (xy 86.169887 -429.94275)
			(xy 86.192846 -429.950211) (xy 86.212379 -429.964399) (xy 86.226574 -429.983925) (xy 86.234045 -430.006882)
			(xy 86.234524 -430.018952) (xy 86.234524 -431.560478) (xy 87.141304 -431.560478) (xy 87.141304 -429.018954)
			(xy 87.141767 -429.006866) (xy 87.149232 -428.98387) (xy 87.163421 -428.964293) (xy 87.182953 -428.950043)
			(xy 87.205925 -428.942506) (xy 87.218012 -428.941992) (xy 88.157812 -428.941992) (xy 88.169921 -428.942406)
			(xy 88.192947 -428.949908) (xy 88.207529 -428.960534) (xy 89.1413 -428.960534) (xy 89.1413 -428.233332)
			(xy 89.14157 -428.224576) (xy 89.145537 -428.207519) (xy 89.149174 -428.19955) (xy 89.3826 -427.7233)
			(xy 89.387289 -427.712779) (xy 89.390784 -427.690023) (xy 89.387303 -427.667266) (xy 89.3826 -427.656752)
			(xy 89.149174 -427.180502) (xy 89.145511 -427.172542) (xy 89.141536 -427.15548) (xy 89.1413 -427.14672)
			(xy 89.1413 -426.41901) (xy 89.141815 -426.406925) (xy 89.149264 -426.383931) (xy 89.16344 -426.364355)
			(xy 89.182961 -426.350103) (xy 89.205925 -426.342563) (xy 89.218008 -426.342048) (xy 90.157808 -426.342048)
			(xy 90.169912 -426.342509) (xy 90.192931 -426.350004) (xy 90.212499 -426.364256) (xy 90.226696 -426.383865)
			(xy 90.234125 -426.406905) (xy 90.234516 -426.41901) (xy 90.234516 -428.960534) (xy 90.234121 -428.97263)
			(xy 90.226649 -428.995639) (xy 90.212446 -429.015222) (xy 90.192895 -429.02947) (xy 90.169903 -429.036993)
			(xy 90.157808 -429.037496) (xy 89.218008 -429.037496) (xy 89.205899 -429.037077) (xy 89.182871 -429.029579)
			(xy 89.163298 -429.015319) (xy 89.149103 -428.995697) (xy 89.141683 -428.972644) (xy 89.1413 -428.960534)
			(xy 88.207529 -428.960534) (xy 88.212519 -428.96417) (xy 88.226714 -428.983792) (xy 88.234136 -429.006844)
			(xy 88.23452 -429.018954) (xy 88.23452 -431.560478) (xy 88.234073 -431.57257) (xy 88.226618 -431.595577)
			(xy 88.212427 -431.615161) (xy 88.192887 -431.629411) (xy 88.169903 -431.636936) (xy 88.157812 -431.63744)
			(xy 87.218012 -431.63744) (xy 87.205908 -431.636974) (xy 87.182888 -431.629483) (xy 87.163318 -431.615232)
			(xy 87.149122 -431.595624) (xy 87.141693 -431.572583) (xy 87.141304 -431.560478) (xy 86.234524 -431.560478)
			(xy 86.234524 -432.560476) (xy 86.234067 -432.572556) (xy 86.226608 -432.595535) (xy 86.212413 -432.615084)
			(xy 86.192871 -432.62929) (xy 86.169896 -432.636761) (xy 86.157816 -432.637184) (xy 85.218016 -432.637184)
			(xy 85.205932 -432.636773) (xy 85.182946 -432.629307) (xy 85.163393 -432.615101) (xy 85.149189 -432.595547)
			(xy 85.141726 -432.57256) (xy 85.141308 -432.560476) (xy 84.207119 -432.560476) (xy 84.212399 -432.564313)
			(xy 84.226593 -432.583852) (xy 84.234055 -432.606821) (xy 84.234528 -432.618896) (xy 84.234528 -435.16042)
			(xy 84.234053 -435.172494) (xy 84.226587 -435.195458) (xy 84.212393 -435.214993) (xy 84.192858 -435.229187)
			(xy 84.169894 -435.236653) (xy 84.15782 -435.237128) (xy 83.21802 -435.237128) (xy 83.205948 -435.236619)
			(xy 83.182985 -435.229165) (xy 83.16345 -435.214979) (xy 83.149254 -435.195451) (xy 83.141787 -435.172491)
			(xy 83.141312 -435.16042) (xy 82.234532 -435.16042) (xy 82.234532 -436.160418) (xy 82.234108 -436.172511)
			(xy 82.226643 -436.195517) (xy 82.212446 -436.215099) (xy 82.192902 -436.229348) (xy 82.169916 -436.236875)
			(xy 82.157824 -436.23738) (xy 81.218024 -436.23738) (xy 81.205914 -436.236963) (xy 81.182885 -436.229468)
			(xy 81.163309 -436.215207) (xy 81.149115 -436.195584) (xy 81.141697 -436.172529) (xy 81.141316 -436.160418)
			(xy 80.206779 -436.160418) (xy 80.212406 -436.164508) (xy 80.2266 -436.184048) (xy 80.234063 -436.207017)
			(xy 80.234536 -436.219092) (xy 80.234536 -438.760616) (xy 80.23405 -438.772689) (xy 80.226586 -438.795651)
			(xy 80.212394 -438.815186) (xy 80.192862 -438.829381) (xy 80.169901 -438.836848) (xy 80.157828 -438.837324)
			(xy 79.218028 -438.837324) (xy 79.205948 -438.836864) (xy 79.182969 -438.829406) (xy 79.16342 -438.815211)
			(xy 79.149214 -438.79567) (xy 79.141743 -438.772695) (xy 79.14132 -438.760616) (xy 78.23454 -438.760616)
			(xy 78.23454 -439.760614) (xy 81.141316 -439.760614) (xy 81.141316 -437.21909) (xy 81.141799 -437.207002)
			(xy 81.149255 -437.184006) (xy 81.163439 -437.164428) (xy 81.182967 -437.150177) (xy 81.205938 -437.142641)
			(xy 81.218024 -437.142128) (xy 82.157824 -437.142128) (xy 82.169937 -437.142496) (xy 82.19297 -437.150006)
			(xy 82.212545 -437.164279) (xy 82.226738 -437.183912) (xy 82.234153 -437.206975) (xy 82.234532 -437.21909)
			(xy 82.234532 -438.760616) (xy 83.141312 -438.760616) (xy 83.141312 -436.219092) (xy 83.141706 -436.207007)
			(xy 83.149178 -436.18402) (xy 83.163388 -436.164469) (xy 83.182946 -436.150265) (xy 83.205935 -436.142802)
			(xy 83.21802 -436.142384) (xy 84.15782 -436.142384) (xy 84.169895 -436.142847) (xy 84.192861 -436.150314)
			(xy 84.206765 -436.160418) (xy 85.141308 -436.160418) (xy 85.141308 -433.618894) (xy 85.141802 -433.606807)
			(xy 85.149256 -433.583812) (xy 85.163437 -433.564235) (xy 85.182963 -433.549984) (xy 85.205931 -433.542446)
			(xy 85.218016 -433.541932) (xy 86.157816 -433.541932) (xy 86.169929 -433.542303) (xy 86.192962 -433.549811)
			(xy 86.212538 -433.564083) (xy 86.226731 -433.583716) (xy 86.234145 -433.606779) (xy 86.234524 -433.618894)
			(xy 86.234524 -435.16042) (xy 87.141304 -435.16042) (xy 87.141304 -432.618896) (xy 87.141709 -432.606812)
			(xy 87.149179 -432.583827) (xy 87.163387 -432.564276) (xy 87.182941 -432.550072) (xy 87.205928 -432.542607)
			(xy 87.218012 -432.542188) (xy 88.157812 -432.542188) (xy 88.169887 -432.542654) (xy 88.192854 -432.550119)
			(xy 88.207106 -432.560476) (xy 89.1413 -432.560476) (xy 89.1413 -430.018952) (xy 89.141723 -430.006874)
			(xy 89.1492 -429.983904) (xy 89.163407 -429.964367) (xy 89.182954 -429.950174) (xy 89.20593 -429.942714)
			(xy 89.218008 -429.942244) (xy 90.157808 -429.942244) (xy 90.169878 -429.942757) (xy 90.192837 -429.950216)
			(xy 90.21237 -429.964401) (xy 90.226566 -429.983927) (xy 90.234037 -430.006882) (xy 90.234516 -430.018952)
			(xy 90.234516 -431.360072) (xy 108.40466 -431.360072) (xy 108.405158 -431.275192) (xy 108.413115 -431.105619)
			(xy 108.429011 -430.936605) (xy 108.452812 -430.768522) (xy 108.484466 -430.601739) (xy 108.523902 -430.436623)
			(xy 108.571034 -430.273538) (xy 108.625758 -430.11284) (xy 108.687955 -429.954885) (xy 108.757487 -429.800018)
			(xy 108.834202 -429.648581) (xy 108.91793 -429.500905) (xy 109.008488 -429.357317) (xy 109.105677 -429.218131)
			(xy 109.209284 -429.083654) (xy 109.319079 -428.954181) (xy 109.434823 -428.829996) (xy 109.55626 -428.711373)
			(xy 109.683124 -428.598572) (xy 109.815135 -428.491842) (xy 109.952005 -428.391417) (xy 110.09343 -428.297518)
			(xy 110.239102 -428.21035) (xy 110.3887 -428.130107) (xy 110.541894 -428.056963) (xy 110.698348 -427.991081)
			(xy 110.857718 -427.932604) (xy 111.019654 -427.881662) (xy 111.1838 -427.838366) (xy 111.349795 -427.802811)
			(xy 111.517274 -427.775076) (xy 111.685869 -427.755222) (xy 111.855209 -427.743292) (xy 112.024922 -427.739313)
			(xy 112.194635 -427.743292) (xy 112.363975 -427.755222) (xy 112.53257 -427.775076) (xy 112.700049 -427.802811)
			(xy 112.866044 -427.838366) (xy 113.03019 -427.881662) (xy 113.192126 -427.932604) (xy 113.26825 -427.960536)
			(xy 125.241304 -427.960536) (xy 125.241304 -427.233334) (xy 125.241574 -427.224578) (xy 125.245541 -427.207521)
			(xy 125.249178 -427.199552) (xy 125.482604 -426.723302) (xy 125.487292 -426.71278) (xy 125.490787 -426.690025)
			(xy 125.487307 -426.667268) (xy 125.482604 -426.656754) (xy 125.249178 -426.180504) (xy 125.245516 -426.172543)
			(xy 125.24154 -426.155482) (xy 125.241304 -426.146722) (xy 125.241304 -425.419012) (xy 125.241723 -425.406929)
			(xy 125.249189 -425.383944) (xy 125.263393 -425.364393) (xy 125.282944 -425.350189) (xy 125.305929 -425.342723)
			(xy 125.318012 -425.342304) (xy 126.257812 -425.342304) (xy 126.269888 -425.342754) (xy 126.292858 -425.350222)
			(xy 126.312396 -425.364421) (xy 126.326589 -425.383964) (xy 126.334049 -425.406935) (xy 126.33452 -425.419012)
			(xy 126.33452 -427.960536) (xy 126.334067 -427.972611) (xy 126.326596 -427.995578) (xy 126.312396 -428.015113)
			(xy 126.292856 -428.029307) (xy 126.269887 -428.036771) (xy 126.257812 -428.037244) (xy 125.318012 -428.037244)
			(xy 125.305942 -428.036726) (xy 125.282981 -428.029271) (xy 125.263447 -428.015087) (xy 125.249251 -427.995562)
			(xy 125.241781 -427.972606) (xy 125.241304 -427.960536) (xy 113.26825 -427.960536) (xy 113.351496 -427.991081)
			(xy 113.50795 -428.056963) (xy 113.661144 -428.130107) (xy 113.810742 -428.21035) (xy 113.956414 -428.297518)
			(xy 114.097839 -428.391417) (xy 114.234709 -428.491842) (xy 114.36672 -428.598572) (xy 114.493584 -428.711373)
			(xy 114.615021 -428.829996) (xy 114.730765 -428.954181) (xy 114.84056 -429.083654) (xy 114.944167 -429.218131)
			(xy 115.041356 -429.357317) (xy 115.131914 -429.500905) (xy 115.215642 -429.648581) (xy 115.292357 -429.800018)
			(xy 115.361889 -429.954885) (xy 115.424086 -430.11284) (xy 115.47881 -430.273538) (xy 115.525942 -430.436623)
			(xy 115.565378 -430.601739) (xy 115.597032 -430.768522) (xy 115.620833 -430.936605) (xy 115.636729 -431.105619)
			(xy 115.644686 -431.275192) (xy 115.645184 -431.360072) (xy 115.644698 -431.445674) (xy 115.639268 -431.560478)
			(xy 125.241304 -431.560478) (xy 125.241304 -429.018954) (xy 125.241767 -429.006866) (xy 125.249232 -428.98387)
			(xy 125.263421 -428.964293) (xy 125.282953 -428.950043) (xy 125.305925 -428.942506) (xy 125.318012 -428.941992)
			(xy 126.257812 -428.941992) (xy 126.269921 -428.942406) (xy 126.292947 -428.949908) (xy 126.307181 -428.96028)
			(xy 127.2413 -428.96028) (xy 127.2413 -428.233078) (xy 127.241552 -428.224321) (xy 127.245531 -428.207263)
			(xy 127.249174 -428.199296) (xy 127.4826 -427.723046) (xy 127.487327 -427.712539) (xy 127.490808 -427.689775)
			(xy 127.487312 -427.667012) (xy 127.4826 -427.656498) (xy 127.249174 -427.180248) (xy 127.245525 -427.172282)
			(xy 127.241541 -427.155224) (xy 127.2413 -427.146466) (xy 127.2413 -426.418756) (xy 127.241727 -426.406678)
			(xy 127.249202 -426.383708) (xy 127.263408 -426.364171) (xy 127.282955 -426.349979) (xy 127.30593 -426.342519)
			(xy 127.318008 -426.342048) (xy 128.257808 -426.342048) (xy 128.269879 -426.342557) (xy 128.292839 -426.350016)
			(xy 128.312372 -426.364203) (xy 128.326567 -426.383729) (xy 128.334038 -426.406686) (xy 128.334516 -426.418756)
			(xy 128.334516 -427.960536) (xy 129.241296 -427.960536) (xy 129.241296 -427.233334) (xy 129.241567 -427.224578)
			(xy 129.245533 -427.207521) (xy 129.24917 -427.199552) (xy 129.482596 -426.723302) (xy 129.487284 -426.71278)
			(xy 129.490779 -426.690025) (xy 129.487299 -426.667268) (xy 129.482596 -426.656754) (xy 129.24917 -426.180504)
			(xy 129.245507 -426.172544) (xy 129.241532 -426.155482) (xy 129.241296 -426.146722) (xy 129.241296 -425.419012)
			(xy 129.241723 -425.40693) (xy 129.249188 -425.383947) (xy 129.26339 -425.364396) (xy 129.282939 -425.350191)
			(xy 129.305922 -425.342724) (xy 129.318004 -425.342304) (xy 130.257804 -425.342304) (xy 130.269888 -425.342709)
			(xy 130.292873 -425.350179) (xy 130.312424 -425.364387) (xy 130.326628 -425.383941) (xy 130.334093 -425.406928)
			(xy 130.334512 -425.419012) (xy 130.334512 -427.960536) (xy 130.334067 -427.972612) (xy 130.326595 -427.99558)
			(xy 130.312393 -428.015116) (xy 130.292851 -428.029309) (xy 130.26988 -428.036772) (xy 130.257804 -428.037244)
			(xy 129.318004 -428.037244) (xy 129.305933 -428.036733) (xy 129.282972 -428.029276) (xy 129.263438 -428.01509)
			(xy 129.249242 -427.995564) (xy 129.241773 -427.972607) (xy 129.241296 -427.960536) (xy 128.334516 -427.960536)
			(xy 128.334516 -428.96028) (xy 128.33407 -428.972361) (xy 128.326609 -428.995342) (xy 128.312411 -429.014891)
			(xy 128.292867 -429.029096) (xy 128.269889 -429.036566) (xy 128.257808 -429.036988) (xy 127.318008 -429.036988)
			(xy 127.305924 -429.03658) (xy 127.282938 -429.029113) (xy 127.263386 -429.014906) (xy 127.249182 -428.995352)
			(xy 127.241718 -428.972364) (xy 127.2413 -428.96028) (xy 126.307181 -428.96028) (xy 126.312519 -428.96417)
			(xy 126.326714 -428.983792) (xy 126.334136 -429.006844) (xy 126.33452 -429.018954) (xy 126.33452 -431.560478)
			(xy 126.334073 -431.57257) (xy 126.326618 -431.595577) (xy 126.312427 -431.615161) (xy 126.292887 -431.629411)
			(xy 126.269903 -431.636936) (xy 126.257812 -431.63744) (xy 125.318012 -431.63744) (xy 125.305908 -431.636974)
			(xy 125.282888 -431.629483) (xy 125.263318 -431.615232) (xy 125.249122 -431.595624) (xy 125.241693 -431.572583)
			(xy 125.241304 -431.560478) (xy 115.639268 -431.560478) (xy 115.63661 -431.616688) (xy 115.620446 -431.787128)
			(xy 115.596243 -431.956613) (xy 115.564055 -432.124765) (xy 115.523953 -432.291207) (xy 115.476027 -432.455567)
			(xy 115.420385 -432.617477) (xy 115.35715 -432.776576) (xy 115.286464 -432.932508) (xy 115.208486 -433.084923)
			(xy 115.12339 -433.233482) (xy 115.031365 -433.377851) (xy 114.932619 -433.517709) (xy 114.82737 -433.652742)
			(xy 114.715856 -433.782648) (xy 114.598325 -433.907137) (xy 114.47504 -434.02593) (xy 114.346277 -434.138763)
			(xy 114.212324 -434.245381) (xy 114.07348 -434.345548) (xy 113.930056 -434.439039) (xy 113.782372 -434.525645)
			(xy 113.630759 -434.605172) (xy 113.475556 -434.677443) (xy 113.396522 -434.710332) (xy 113.388621 -434.713964)
			(xy 113.375731 -434.725623) (xy 113.367472 -434.740915) (xy 113.365788 -434.749448) (xy 113.35004 -434.849016)
			(xy 113.359438 -434.873654) (xy 113.369852 -434.88229) (xy 113.419298 -434.924299) (xy 113.513487 -435.013553)
			(xy 113.601975 -435.108462) (xy 113.644727 -435.16042) (xy 125.241304 -435.16042) (xy 125.241304 -432.618896)
			(xy 125.241709 -432.606812) (xy 125.249179 -432.583827) (xy 125.263387 -432.564276) (xy 125.282941 -432.550072)
			(xy 125.305928 -432.542607) (xy 125.318012 -432.542188) (xy 126.257812 -432.542188) (xy 126.269887 -432.542654)
			(xy 126.292854 -432.550119) (xy 126.307106 -432.560476) (xy 127.2413 -432.560476) (xy 127.2413 -430.018952)
			(xy 127.241723 -430.006874) (xy 127.2492 -429.983904) (xy 127.263407 -429.964367) (xy 127.282954 -429.950174)
			(xy 127.30593 -429.942714) (xy 127.318008 -429.942244) (xy 128.257808 -429.942244) (xy 128.269878 -429.942757)
			(xy 128.292837 -429.950216) (xy 128.31237 -429.964401) (xy 128.326566 -429.983927) (xy 128.334037 -430.006882)
			(xy 128.334516 -430.018952) (xy 128.334516 -431.560478) (xy 129.241296 -431.560478) (xy 129.241296 -429.018954)
			(xy 129.241767 -429.006866) (xy 129.249231 -428.983872) (xy 129.263418 -428.964296) (xy 129.282948 -428.950046)
			(xy 129.305918 -428.942507) (xy 129.318004 -428.941992) (xy 130.257804 -428.941992) (xy 130.269912 -428.942413)
			(xy 130.292938 -428.949912) (xy 130.307168 -428.96028) (xy 131.241292 -428.96028) (xy 131.241292 -428.233078)
			(xy 131.241545 -428.224321) (xy 131.245523 -428.207264) (xy 131.249166 -428.199296) (xy 131.482592 -427.723046)
			(xy 131.487319 -427.712539) (xy 131.4908 -427.689775) (xy 131.487304 -427.667012) (xy 131.482592 -427.656498)
			(xy 131.249166 -427.180248) (xy 131.245517 -427.172282) (xy 131.241533 -427.155224) (xy 131.241292 -427.146466)
			(xy 131.241292 -426.418756) (xy 131.241727 -426.406679) (xy 131.249201 -426.38371) (xy 131.263405 -426.364174)
			(xy 131.28295 -426.349981) (xy 131.305923 -426.34252) (xy 131.318 -426.342048) (xy 132.2578 -426.342048)
			(xy 132.26987 -426.342564) (xy 132.29283 -426.350021) (xy 132.312363 -426.364206) (xy 132.326559 -426.383731)
			(xy 132.334029 -426.406686) (xy 132.334508 -426.418756) (xy 132.334508 -427.960536) (xy 133.241288 -427.960536)
			(xy 133.241288 -427.233334) (xy 133.24156 -427.224578) (xy 133.245525 -427.207521) (xy 133.249162 -427.199552)
			(xy 133.482588 -426.723302) (xy 133.487276 -426.71278) (xy 133.490772 -426.690025) (xy 133.487292 -426.667268)
			(xy 133.482588 -426.656754) (xy 133.249162 -426.180504) (xy 133.245499 -426.172544) (xy 133.241524 -426.155482)
			(xy 133.241288 -426.146722) (xy 133.241288 -425.419012) (xy 133.241723 -425.40693) (xy 133.249187 -425.383949)
			(xy 133.263387 -425.364399) (xy 133.282934 -425.350194) (xy 133.305914 -425.342726) (xy 133.317996 -425.342304)
			(xy 134.257796 -425.342304) (xy 134.26988 -425.342716) (xy 134.292864 -425.350184) (xy 134.312416 -425.36439)
			(xy 134.32662 -425.383943) (xy 134.334085 -425.406928) (xy 134.334504 -425.419012) (xy 134.334504 -427.960536)
			(xy 134.334067 -427.972613) (xy 134.326594 -427.995582) (xy 134.31239 -428.015119) (xy 134.292846 -428.029312)
			(xy 134.269873 -428.036773) (xy 134.257796 -428.037244) (xy 133.317996 -428.037244) (xy 133.305925 -428.03674)
			(xy 133.282964 -428.02928) (xy 133.26343 -428.015093) (xy 133.249234 -427.995565) (xy 133.241765 -427.972607)
			(xy 133.241288 -427.960536) (xy 132.334508 -427.960536) (xy 132.334508 -428.96028) (xy 132.33407 -428.972362)
			(xy 132.326608 -428.995344) (xy 132.312408 -429.014894) (xy 132.292862 -429.029099) (xy 132.269882 -429.036567)
			(xy 132.2578 -429.036988) (xy 131.318 -429.036988) (xy 131.305915 -429.036587) (xy 131.282929 -429.029117)
			(xy 131.263377 -429.014909) (xy 131.249174 -428.995353) (xy 131.24171 -428.972365) (xy 131.241292 -428.96028)
			(xy 130.307168 -428.96028) (xy 130.312511 -428.964173) (xy 130.326706 -428.983793) (xy 130.334128 -429.006844)
			(xy 130.334512 -429.018954) (xy 130.334512 -431.560478) (xy 130.334073 -431.572571) (xy 130.326616 -431.595579)
			(xy 130.312424 -431.615164) (xy 130.292882 -431.629413) (xy 130.269896 -431.636937) (xy 130.257804 -431.63744)
			(xy 129.318004 -431.63744) (xy 129.305899 -431.636981) (xy 129.282879 -431.629488) (xy 129.263309 -431.615236)
			(xy 129.249113 -431.595625) (xy 129.241685 -431.572584) (xy 129.241296 -431.560478) (xy 128.334516 -431.560478)
			(xy 128.334516 -432.560476) (xy 128.334067 -432.572557) (xy 128.326607 -432.595537) (xy 128.31241 -432.615087)
			(xy 128.292866 -432.629292) (xy 128.269888 -432.636762) (xy 128.257808 -432.637184) (xy 127.318008 -432.637184)
			(xy 127.305923 -432.63678) (xy 127.282937 -432.629312) (xy 127.263384 -432.615105) (xy 127.249181 -432.595549)
			(xy 127.241717 -432.572561) (xy 127.2413 -432.560476) (xy 126.307106 -432.560476) (xy 126.31239 -432.564316)
			(xy 126.326584 -432.583854) (xy 126.334047 -432.606821) (xy 126.33452 -432.618896) (xy 126.33452 -435.16042)
			(xy 126.334053 -435.172494) (xy 126.326586 -435.19546) (xy 126.31239 -435.214996) (xy 126.292853 -435.22919)
			(xy 126.269886 -435.236654) (xy 126.257812 -435.237128) (xy 125.318012 -435.237128) (xy 125.30594 -435.236626)
			(xy 125.282977 -435.229169) (xy 125.263441 -435.214982) (xy 125.249246 -435.195452) (xy 125.241779 -435.172492)
			(xy 125.241304 -435.16042) (xy 113.644727 -435.16042) (xy 113.684422 -435.208663) (xy 113.760513 -435.313772)
			(xy 113.829956 -435.423387) (xy 113.892486 -435.537087) (xy 113.947862 -435.654438) (xy 113.995874 -435.77499)
			(xy 114.036336 -435.89828) (xy 114.069094 -436.023838) (xy 114.094022 -436.151181) (xy 114.111025 -436.279823)
			(xy 114.120038 -436.40927) (xy 114.121027 -436.539027) (xy 114.113986 -436.668596) (xy 114.098945 -436.797482)
			(xy 114.075959 -436.92519) (xy 114.045118 -437.051232) (xy 114.006538 -437.175125) (xy 113.960369 -437.296394)
			(xy 113.906786 -437.414574) (xy 113.845996 -437.529214) (xy 113.77823 -437.639874) (xy 113.703749 -437.74613)
			(xy 113.622838 -437.847575) (xy 113.535806 -437.943821) (xy 113.442988 -438.034499) (xy 113.344738 -438.119261)
			(xy 113.241432 -438.197784) (xy 113.133467 -438.269766) (xy 113.021257 -438.334931) (xy 112.90523 -438.39303)
			(xy 112.785831 -438.443841) (xy 112.663518 -438.487169) (xy 112.538759 -438.522847) (xy 112.412032 -438.550739)
			(xy 112.283822 -438.570739) (xy 112.15462 -438.58277) (xy 112.024922 -438.586785) (xy 111.895224 -438.58277)
			(xy 111.766022 -438.570739) (xy 111.637812 -438.550739) (xy 111.511085 -438.522847) (xy 111.386326 -438.487169)
			(xy 111.264013 -438.443841) (xy 111.144614 -438.39303) (xy 111.028587 -438.334931) (xy 110.916377 -438.269766)
			(xy 110.808412 -438.197784) (xy 110.705106 -438.119261) (xy 110.606856 -438.034499) (xy 110.514038 -437.943821)
			(xy 110.427006 -437.847575) (xy 110.346095 -437.74613) (xy 110.271614 -437.639874) (xy 110.203848 -437.529214)
			(xy 110.143058 -437.414574) (xy 110.089475 -437.296394) (xy 110.043306 -437.175125) (xy 110.004726 -437.051232)
			(xy 109.973885 -436.92519) (xy 109.950899 -436.797482) (xy 109.935858 -436.668596) (xy 109.928817 -436.539027)
			(xy 109.929806 -436.40927) (xy 109.938819 -436.279823) (xy 109.955822 -436.151181) (xy 109.98075 -436.023838)
			(xy 110.013508 -435.89828) (xy 110.05397 -435.77499) (xy 110.101982 -435.654438) (xy 110.157358 -435.537087)
			(xy 110.219888 -435.423387) (xy 110.289331 -435.313772) (xy 110.365422 -435.208663) (xy 110.447869 -435.108462)
			(xy 110.536357 -435.013553) (xy 110.630546 -434.924299) (xy 110.679992 -434.88229) (xy 110.690406 -434.873654)
			(xy 110.699804 -434.849016) (xy 110.682024 -434.73624) (xy 110.665768 -434.715412) (xy 110.653322 -434.710332)
			(xy 110.574304 -434.677407) (xy 110.419107 -434.605131) (xy 110.267499 -434.5256) (xy 110.119821 -434.438991)
			(xy 109.976402 -434.345497) (xy 109.837562 -434.245328) (xy 109.703613 -434.138709) (xy 109.574854 -434.025876)
			(xy 109.451573 -433.907083) (xy 109.334045 -433.782595) (xy 109.222533 -433.65269) (xy 109.117287 -433.517659)
			(xy 109.018541 -433.377804) (xy 108.926517 -433.233438) (xy 108.84142 -433.084883) (xy 108.763441 -432.932471)
			(xy 108.692754 -432.776543) (xy 108.629516 -432.617449) (xy 108.57387 -432.455542) (xy 108.52594 -432.291187)
			(xy 108.485833 -432.124749) (xy 108.453638 -431.956601) (xy 108.429428 -431.78712) (xy 108.413257 -431.616683)
			(xy 108.405161 -431.445673) (xy 108.40466 -431.360072) (xy 90.234516 -431.360072) (xy 90.234516 -432.560476)
			(xy 90.234067 -432.572557) (xy 90.226607 -432.595537) (xy 90.21241 -432.615087) (xy 90.192866 -432.629292)
			(xy 90.169888 -432.636762) (xy 90.157808 -432.637184) (xy 89.218008 -432.637184) (xy 89.205923 -432.63678)
			(xy 89.182937 -432.629312) (xy 89.163384 -432.615105) (xy 89.149181 -432.595549) (xy 89.141717 -432.572561)
			(xy 89.1413 -432.560476) (xy 88.207106 -432.560476) (xy 88.21239 -432.564316) (xy 88.226584 -432.583854)
			(xy 88.234047 -432.606821) (xy 88.23452 -432.618896) (xy 88.23452 -435.16042) (xy 88.234053 -435.172494)
			(xy 88.226586 -435.19546) (xy 88.21239 -435.214996) (xy 88.192853 -435.22919) (xy 88.169886 -435.236654)
			(xy 88.157812 -435.237128) (xy 87.218012 -435.237128) (xy 87.20594 -435.236626) (xy 87.182977 -435.229169)
			(xy 87.163441 -435.214982) (xy 87.149246 -435.195452) (xy 87.141779 -435.172492) (xy 87.141304 -435.16042)
			(xy 86.234524 -435.16042) (xy 86.234524 -436.160418) (xy 86.234107 -436.172512) (xy 86.226641 -436.195519)
			(xy 86.212443 -436.215102) (xy 86.192897 -436.229351) (xy 86.169909 -436.236876) (xy 86.157816 -436.23738)
			(xy 85.218016 -436.23738) (xy 85.205906 -436.23697) (xy 85.182876 -436.229472) (xy 85.163301 -436.21521)
			(xy 85.149106 -436.195585) (xy 85.141689 -436.172529) (xy 85.141308 -436.160418) (xy 84.206765 -436.160418)
			(xy 84.212397 -436.164511) (xy 84.226591 -436.18405) (xy 84.234055 -436.207017) (xy 84.234528 -436.219092)
			(xy 84.234528 -438.760616) (xy 84.23405 -438.772689) (xy 84.226585 -438.795654) (xy 84.212391 -438.815189)
			(xy 84.192857 -438.829383) (xy 84.169893 -438.836849) (xy 84.15782 -438.837324) (xy 83.21802 -438.837324)
			(xy 83.20594 -438.83687) (xy 83.182961 -438.82941) (xy 83.163411 -438.815214) (xy 83.149206 -438.795672)
			(xy 83.141735 -438.772696) (xy 83.141312 -438.760616) (xy 82.234532 -438.760616) (xy 82.234532 -439.760614)
			(xy 85.141308 -439.760614) (xy 85.141308 -437.21909) (xy 85.141798 -437.207003) (xy 85.149254 -437.184008)
			(xy 85.163436 -437.164431) (xy 85.182962 -437.150179) (xy 85.205931 -437.142642) (xy 85.218016 -437.142128)
			(xy 86.157816 -437.142128) (xy 86.169929 -437.142503) (xy 86.192961 -437.15001) (xy 86.212536 -437.164281)
			(xy 86.226729 -437.183914) (xy 86.234145 -437.206976) (xy 86.234524 -437.21909) (xy 86.234524 -438.760616)
			(xy 87.141304 -438.760616) (xy 87.141304 -436.219092) (xy 87.141706 -436.207008) (xy 87.149177 -436.184023)
			(xy 87.163386 -436.164471) (xy 87.182941 -436.150268) (xy 87.205928 -436.142803) (xy 87.218012 -436.142384)
			(xy 88.157812 -436.142384) (xy 88.169886 -436.142854) (xy 88.192853 -436.150319) (xy 88.206752 -436.160418)
			(xy 89.1413 -436.160418) (xy 89.1413 -433.618894) (xy 89.141802 -433.606808) (xy 89.149255 -433.583814)
			(xy 89.163434 -433.564238) (xy 89.182958 -433.549986) (xy 89.205924 -433.542447) (xy 89.218008 -433.541932)
			(xy 90.157808 -433.541932) (xy 90.169921 -433.54231) (xy 90.192954 -433.549815) (xy 90.212529 -433.564086)
			(xy 90.226723 -433.583717) (xy 90.234137 -433.60678) (xy 90.234516 -433.618894) (xy 90.234516 -436.160418)
			(xy 90.234107 -436.172513) (xy 90.22664 -436.195522) (xy 90.21244 -436.215105) (xy 90.192892 -436.229353)
			(xy 90.169902 -436.236877) (xy 90.157808 -436.23738) (xy 89.218008 -436.23738) (xy 89.205898 -436.236977)
			(xy 89.182867 -436.229477) (xy 89.163292 -436.215213) (xy 89.149098 -436.195587) (xy 89.14168 -436.17253)
			(xy 89.1413 -436.160418) (xy 88.206752 -436.160418) (xy 88.212389 -436.164514) (xy 88.226583 -436.184051)
			(xy 88.234047 -436.207018) (xy 88.23452 -436.219092) (xy 88.23452 -438.760616) (xy 88.234049 -438.77269)
			(xy 88.226584 -438.795656) (xy 88.212389 -438.815191) (xy 88.192852 -438.829386) (xy 88.169886 -438.83685)
			(xy 88.157812 -438.837324) (xy 87.218012 -438.837324) (xy 87.20594 -438.836826) (xy 87.182976 -438.829369)
			(xy 87.16344 -438.81518) (xy 87.149244 -438.79565) (xy 87.141779 -438.772688) (xy 87.141304 -438.760616)
			(xy 86.234524 -438.760616) (xy 86.234524 -439.760614) (xy 89.1413 -439.760614) (xy 89.1413 -437.21909)
			(xy 89.141798 -437.207004) (xy 89.149253 -437.18401) (xy 89.163433 -437.164434) (xy 89.182957 -437.150182)
			(xy 89.205924 -437.142643) (xy 89.218008 -437.142128) (xy 90.157808 -437.142128) (xy 90.16992 -437.14251)
			(xy 90.192952 -437.150015) (xy 90.212528 -437.164284) (xy 90.226721 -437.183915) (xy 90.234137 -437.206976)
			(xy 90.234516 -437.21909) (xy 90.234516 -438.760362) (xy 125.241304 -438.760362) (xy 125.241304 -436.218838)
			(xy 125.241839 -436.206754) (xy 125.249281 -436.183761) (xy 125.263451 -436.164183) (xy 125.282968 -436.14993)
			(xy 125.30593 -436.142391) (xy 125.318012 -436.141876) (xy 126.257812 -436.141876) (xy 126.269919 -436.142306)
			(xy 126.292943 -436.149805) (xy 126.30751 -436.160418) (xy 127.2413 -436.160418) (xy 127.2413 -433.618894)
			(xy 127.241802 -433.606808) (xy 127.249255 -433.583814) (xy 127.263434 -433.564238) (xy 127.282958 -433.549986)
			(xy 127.305924 -433.542447) (xy 127.318008 -433.541932) (xy 128.257808 -433.541932) (xy 128.269921 -433.54231)
			(xy 128.292954 -433.549815) (xy 128.312529 -433.564086) (xy 128.326723 -433.583717) (xy 128.334137 -433.60678)
			(xy 128.334516 -433.618894) (xy 128.334516 -435.16042) (xy 129.241296 -435.16042) (xy 129.241296 -432.618896)
			(xy 129.241761 -432.606821) (xy 129.249225 -432.583853) (xy 129.263421 -432.564316) (xy 129.28296 -432.550121)
			(xy 129.305929 -432.54266) (xy 129.318004 -432.542188) (xy 130.257804 -432.542188) (xy 130.269878 -432.542661)
			(xy 130.292845 -432.550124) (xy 130.307094 -432.560476) (xy 131.241292 -432.560476) (xy 131.241292 -430.018952)
			(xy 131.241723 -430.006875) (xy 131.249199 -429.983906) (xy 131.263404 -429.96437) (xy 131.282949 -429.950177)
			(xy 131.305923 -429.942716) (xy 131.318 -429.942244) (xy 132.2578 -429.942244) (xy 132.26987 -429.942764)
			(xy 132.292829 -429.95022) (xy 132.312362 -429.964404) (xy 132.326558 -429.983928) (xy 132.334029 -430.006883)
			(xy 132.334508 -430.018952) (xy 132.334508 -431.560478) (xy 133.241288 -431.560478) (xy 133.241288 -429.018954)
			(xy 133.241669 -429.006857) (xy 133.249144 -428.983847) (xy 133.263351 -428.964264) (xy 133.282905 -428.950016)
			(xy 133.3059 -428.942494) (xy 133.317996 -428.941992) (xy 134.257796 -428.941992) (xy 134.269904 -428.942419)
			(xy 134.29293 -428.949917) (xy 134.307154 -428.96028) (xy 135.241284 -428.96028) (xy 135.241284 -428.233078)
			(xy 135.241538 -428.224321) (xy 135.245516 -428.207264) (xy 135.249158 -428.199296) (xy 135.482584 -427.723046)
			(xy 135.487311 -427.712539) (xy 135.490793 -427.689775) (xy 135.487296 -427.667012) (xy 135.482584 -427.656498)
			(xy 135.249158 -427.180248) (xy 135.245508 -427.172282) (xy 135.241525 -427.155224) (xy 135.241284 -427.146466)
			(xy 135.241284 -426.418756) (xy 135.241726 -426.40668) (xy 135.2492 -426.383713) (xy 135.263403 -426.364177)
			(xy 135.282945 -426.349984) (xy 135.305916 -426.342521) (xy 135.317992 -426.342048) (xy 136.257792 -426.342048)
			(xy 136.269862 -426.34257) (xy 136.292821 -426.350025) (xy 136.312355 -426.364208) (xy 136.326551 -426.383732)
			(xy 136.334021 -426.406687) (xy 136.3345 -426.418756) (xy 136.3345 -427.960536) (xy 137.24128 -427.960536)
			(xy 137.24128 -427.233334) (xy 137.241552 -427.224578) (xy 137.245518 -427.207521) (xy 137.249154 -427.199552)
			(xy 137.48258 -426.723302) (xy 137.487269 -426.71278) (xy 137.490765 -426.690025) (xy 137.487284 -426.667268)
			(xy 137.48258 -426.656754) (xy 137.249154 -426.180504) (xy 137.24549 -426.172544) (xy 137.241516 -426.155482)
			(xy 137.24128 -426.146722) (xy 137.24128 -425.419012) (xy 137.241774 -425.406939) (xy 137.249232 -425.383974)
			(xy 137.263421 -425.364438) (xy 137.282953 -425.350243) (xy 137.305915 -425.342778) (xy 137.317988 -425.342304)
			(xy 138.257788 -425.342304) (xy 138.269871 -425.342723) (xy 138.292856 -425.350189) (xy 138.312407 -425.364393)
			(xy 138.326611 -425.383944) (xy 138.334077 -425.406929) (xy 138.334496 -425.419012) (xy 138.334496 -427.960536)
			(xy 138.334066 -427.972614) (xy 138.326593 -427.995584) (xy 138.312387 -428.015122) (xy 138.292841 -428.029315)
			(xy 138.269866 -428.036774) (xy 138.257788 -428.037244) (xy 137.317988 -428.037244) (xy 137.305916 -428.036746)
			(xy 137.282955 -428.029285) (xy 137.263421 -428.015096) (xy 137.249226 -427.995567) (xy 137.241757 -427.972607)
			(xy 137.24128 -427.960536) (xy 136.3345 -427.960536) (xy 136.3345 -428.96028) (xy 136.33407 -428.972362)
			(xy 136.326607 -428.995346) (xy 136.312406 -429.014897) (xy 136.292857 -429.029102) (xy 136.269874 -429.036568)
			(xy 136.257792 -429.036988) (xy 135.317992 -429.036988) (xy 135.305907 -429.036594) (xy 135.28292 -429.029122)
			(xy 135.263369 -429.014912) (xy 135.249165 -428.995354) (xy 135.241702 -428.972365) (xy 135.241284 -428.96028)
			(xy 134.307154 -428.96028) (xy 134.312502 -428.964176) (xy 134.326697 -428.983795) (xy 134.33412 -429.006845)
			(xy 134.334504 -429.018954) (xy 134.334504 -431.560478) (xy 134.333975 -431.572562) (xy 134.326529 -431.595555)
			(xy 134.312357 -431.615131) (xy 134.29284 -431.629384) (xy 134.269878 -431.636924) (xy 134.257796 -431.63744)
			(xy 133.317996 -431.63744) (xy 133.305891 -431.636988) (xy 133.28287 -431.629492) (xy 133.263301 -431.615238)
			(xy 133.249105 -431.595627) (xy 133.241677 -431.572584) (xy 133.241288 -431.560478) (xy 132.334508 -431.560478)
			(xy 132.334508 -432.560476) (xy 132.334067 -432.572557) (xy 132.326606 -432.595539) (xy 132.312407 -432.61509)
			(xy 132.292861 -432.629295) (xy 132.269881 -432.636763) (xy 132.2578 -432.637184) (xy 131.318 -432.637184)
			(xy 131.305915 -432.636787) (xy 131.282928 -432.629317) (xy 131.263376 -432.615107) (xy 131.249172 -432.59555)
			(xy 131.241709 -432.572561) (xy 131.241292 -432.560476) (xy 130.307094 -432.560476) (xy 130.312382 -432.564318)
			(xy 130.326576 -432.583855) (xy 130.334039 -432.606822) (xy 130.334512 -432.618896) (xy 130.334512 -435.16042)
			(xy 130.334053 -435.172495) (xy 130.326585 -435.195462) (xy 130.312387 -435.214999) (xy 130.292848 -435.229193)
			(xy 130.269879 -435.236655) (xy 130.257804 -435.237128) (xy 129.318004 -435.237128) (xy 129.305932 -435.236633)
			(xy 129.282968 -435.229174) (xy 129.263433 -435.214984) (xy 129.249237 -435.195454) (xy 129.241771 -435.172492)
			(xy 129.241296 -435.16042) (xy 128.334516 -435.16042) (xy 128.334516 -436.160418) (xy 128.334107 -436.172513)
			(xy 128.32664 -436.195522) (xy 128.31244 -436.215105) (xy 128.292892 -436.229353) (xy 128.269902 -436.236877)
			(xy 128.257808 -436.23738) (xy 127.318008 -436.23738) (xy 127.305898 -436.236977) (xy 127.282867 -436.229477)
			(xy 127.263292 -436.215213) (xy 127.249098 -436.195587) (xy 127.24168 -436.17253) (xy 127.2413 -436.160418)
			(xy 126.30751 -436.160418) (xy 126.312514 -436.164064) (xy 126.326709 -436.183682) (xy 126.334133 -436.20673)
			(xy 126.33452 -436.218838) (xy 126.33452 -438.760362) (xy 126.33406 -438.772454) (xy 126.326608 -438.79546)
			(xy 126.312422 -438.815044) (xy 126.292884 -438.829294) (xy 126.269902 -438.83682) (xy 126.257812 -438.837324)
			(xy 125.318012 -438.837324) (xy 125.305906 -438.836874) (xy 125.282883 -438.82938) (xy 125.263312 -438.815127)
			(xy 125.249116 -438.795514) (xy 125.241691 -438.772469) (xy 125.241304 -438.760362) (xy 90.234516 -438.760362)
			(xy 90.234516 -439.76036) (xy 127.2413 -439.76036) (xy 127.2413 -437.218836) (xy 127.241744 -437.206754)
			(xy 127.249202 -437.183771) (xy 127.2634 -437.16422) (xy 127.282946 -437.150015) (xy 127.305927 -437.142548)
			(xy 127.318008 -437.142128) (xy 128.257808 -437.142128) (xy 128.269895 -437.142506) (xy 128.292884 -437.14998)
			(xy 128.312437 -437.164194) (xy 128.32664 -437.183756) (xy 128.334101 -437.206749) (xy 128.334516 -437.218836)
			(xy 128.334516 -438.760362) (xy 129.241296 -438.760362) (xy 129.241296 -436.218838) (xy 129.241839 -436.206755)
			(xy 129.24928 -436.183763) (xy 129.263448 -436.164186) (xy 129.282963 -436.149933) (xy 129.305923 -436.142392)
			(xy 129.318004 -436.141876) (xy 130.257804 -436.141876) (xy 130.269911 -436.142312) (xy 130.292934 -436.14981)
			(xy 130.307496 -436.160418) (xy 131.241292 -436.160418) (xy 131.241292 -433.618894) (xy 131.241802 -433.606809)
			(xy 131.249254 -433.583816) (xy 131.263431 -433.564241) (xy 131.282953 -433.549989) (xy 131.305917 -433.542448)
			(xy 131.318 -433.541932) (xy 132.2578 -433.541932) (xy 132.269912 -433.542317) (xy 132.292945 -433.54982)
			(xy 132.312521 -433.564088) (xy 132.326714 -433.583719) (xy 132.334129 -433.60678) (xy 132.334508 -433.618894)
			(xy 132.334508 -435.16042) (xy 133.241288 -435.16042) (xy 133.241288 -432.618896) (xy 133.241761 -432.606822)
			(xy 133.249224 -432.583855) (xy 133.263418 -432.564318) (xy 133.282955 -432.550124) (xy 133.305922 -432.542661)
			(xy 133.317996 -432.542188) (xy 134.257796 -432.542188) (xy 134.26987 -432.542668) (xy 134.292836 -432.550129)
			(xy 134.30708 -432.560476) (xy 135.241284 -432.560476) (xy 135.241284 -430.018952) (xy 135.241723 -430.006876)
			(xy 135.249198 -429.983908) (xy 135.263401 -429.964373) (xy 135.282944 -429.95018) (xy 135.305915 -429.942717)
			(xy 135.317992 -429.942244) (xy 136.257792 -429.942244) (xy 136.269861 -429.94277) (xy 136.29282 -429.950225)
			(xy 136.312353 -429.964407) (xy 136.32655 -429.98393) (xy 136.334021 -430.006883) (xy 136.3345 -430.018952)
			(xy 136.3345 -431.560478) (xy 137.24128 -431.560478) (xy 137.24128 -429.018954) (xy 137.241669 -429.006858)
			(xy 137.249143 -428.983849) (xy 137.263348 -428.964267) (xy 137.2829 -428.950019) (xy 137.305893 -428.942495)
			(xy 137.317988 -428.941992) (xy 138.257788 -428.941992) (xy 138.269895 -428.942427) (xy 138.292921 -428.949922)
			(xy 138.30714 -428.96028) (xy 139.241276 -428.96028) (xy 139.241276 -428.233078) (xy 139.241531 -428.224321)
			(xy 139.245508 -428.207264) (xy 139.24915 -428.199296) (xy 139.482576 -427.723046) (xy 139.487304 -427.71254)
			(xy 139.490786 -427.689775) (xy 139.487289 -427.667012) (xy 139.482576 -427.656498) (xy 139.24915 -427.180248)
			(xy 139.2455 -427.172282) (xy 139.241517 -427.155224) (xy 139.241276 -427.146466) (xy 139.241276 -426.418756)
			(xy 139.241726 -426.406681) (xy 139.249199 -426.383715) (xy 139.2634 -426.36418) (xy 139.28294 -426.349986)
			(xy 139.305909 -426.342522) (xy 139.317984 -426.342048) (xy 140.257784 -426.342048) (xy 140.269853 -426.342577)
			(xy 140.292813 -426.35003) (xy 140.312346 -426.364211) (xy 140.326543 -426.383734) (xy 140.334013 -426.406687)
			(xy 140.334492 -426.418756) (xy 140.334492 -427.960536) (xy 142.241524 -427.960536) (xy 142.241524 -427.233334)
			(xy 142.241792 -427.224578) (xy 142.24576 -427.20752) (xy 142.249398 -427.199552) (xy 142.482824 -426.723302)
			(xy 142.487511 -426.71278) (xy 142.491005 -426.690025) (xy 142.487526 -426.667268) (xy 142.482824 -426.656754)
			(xy 142.249398 -426.180504) (xy 142.245737 -426.172543) (xy 142.24176 -426.155482) (xy 142.241524 -426.146722)
			(xy 142.241524 -425.419012) (xy 142.241924 -425.406927) (xy 142.249392 -425.383939) (xy 142.2636 -425.364386)
			(xy 142.283157 -425.350183) (xy 142.306147 -425.34272) (xy 142.318232 -425.342304) (xy 143.258032 -425.342304)
			(xy 143.270109 -425.342737) (xy 143.29308 -425.35021) (xy 143.312617 -425.364414) (xy 143.32681 -425.38396)
			(xy 143.33427 -425.406934) (xy 143.33474 -425.419012) (xy 143.33474 -427.960536) (xy 143.334267 -427.972609)
			(xy 143.326799 -427.995572) (xy 143.312603 -428.015106) (xy 143.293069 -428.0293) (xy 143.270105 -428.036768)
			(xy 143.258032 -428.037244) (xy 142.318232 -428.037244) (xy 142.306163 -428.036709) (xy 142.283203 -428.02926)
			(xy 142.263668 -428.01508) (xy 142.249471 -427.995558) (xy 142.242001 -427.972605) (xy 142.241524 -427.960536)
			(xy 140.334492 -427.960536) (xy 140.334492 -428.96028) (xy 140.33407 -428.972363) (xy 140.326606 -428.995348)
			(xy 140.312403 -429.0149) (xy 140.292852 -429.029104) (xy 140.269867 -429.036569) (xy 140.257784 -429.036988)
			(xy 139.317984 -429.036988) (xy 139.305898 -429.036601) (xy 139.282912 -429.029126) (xy 139.26336 -429.014914)
			(xy 139.249157 -428.995356) (xy 139.241694 -428.972366) (xy 139.241276 -428.96028) (xy 138.30714 -428.96028)
			(xy 138.312493 -428.964179) (xy 138.326689 -428.983796) (xy 138.334111 -429.006845) (xy 138.334496 -429.018954)
			(xy 138.334496 -431.560478) (xy 138.333975 -431.572563) (xy 138.326528 -431.595557) (xy 138.312354 -431.615134)
			(xy 138.292834 -431.629386) (xy 138.269871 -431.636925) (xy 138.257788 -431.63744) (xy 137.317988 -431.63744)
			(xy 137.305882 -431.636995) (xy 137.282862 -431.629497) (xy 137.263292 -431.615241) (xy 137.249096 -431.595628)
			(xy 137.241669 -431.572585) (xy 137.24128 -431.560478) (xy 136.3345 -431.560478) (xy 136.3345 -432.560476)
			(xy 136.334067 -432.572558) (xy 136.326605 -432.595542) (xy 136.312404 -432.615093) (xy 136.292856 -432.629297)
			(xy 136.269874 -432.636764) (xy 136.257792 -432.637184) (xy 135.317992 -432.637184) (xy 135.305906 -432.636794)
			(xy 135.282919 -432.629321) (xy 135.263367 -432.61511) (xy 135.249164 -432.595552) (xy 135.241701 -432.572562)
			(xy 135.241284 -432.560476) (xy 134.30708 -432.560476) (xy 134.312373 -432.564321) (xy 134.326568 -432.583857)
			(xy 134.334031 -432.606822) (xy 134.334504 -432.618896) (xy 134.334504 -435.16042) (xy 134.334053 -435.172496)
			(xy 134.326584 -435.195464) (xy 134.312384 -435.215001) (xy 134.292843 -435.229195) (xy 134.269872 -435.236656)
			(xy 134.257796 -435.237128) (xy 133.317996 -435.237128) (xy 133.305923 -435.236639) (xy 133.282959 -435.229178)
			(xy 133.263424 -435.214987) (xy 133.249229 -435.195455) (xy 133.241763 -435.172493) (xy 133.241288 -435.16042)
			(xy 132.334508 -435.16042) (xy 132.334508 -436.160418) (xy 132.334009 -436.172504) (xy 132.326553 -436.195497)
			(xy 132.312373 -436.215072) (xy 132.29285 -436.229324) (xy 132.269884 -436.236864) (xy 132.2578 -436.23738)
			(xy 131.318 -436.23738) (xy 131.305889 -436.236984) (xy 131.282858 -436.229482) (xy 131.263283 -436.215216)
			(xy 131.24909 -436.195589) (xy 131.241672 -436.17253) (xy 131.241292 -436.160418) (xy 130.307496 -436.160418)
			(xy 130.312505 -436.164067) (xy 130.3267 -436.183683) (xy 130.334125 -436.20673) (xy 130.334512 -436.218838)
			(xy 130.334512 -438.760362) (xy 130.334059 -438.772454) (xy 130.326607 -438.795462) (xy 130.312419 -438.815047)
			(xy 130.292879 -438.829297) (xy 130.269895 -438.836821) (xy 130.257804 -438.837324) (xy 129.318004 -438.837324)
			(xy 129.305898 -438.836881) (xy 129.282875 -438.829385) (xy 129.263303 -438.81513) (xy 129.249108 -438.795515)
			(xy 129.241683 -438.77247) (xy 129.241296 -438.760362) (xy 128.334516 -438.760362) (xy 128.334516 -439.76036)
			(xy 131.241292 -439.76036) (xy 131.241292 -437.218836) (xy 131.241743 -437.206755) (xy 131.249201 -437.183774)
			(xy 131.263397 -437.164223) (xy 131.282941 -437.150017) (xy 131.305919 -437.142549) (xy 131.318 -437.142128)
			(xy 132.2578 -437.142128) (xy 132.269886 -437.142513) (xy 132.292875 -437.149985) (xy 132.312429 -437.164197)
			(xy 132.326632 -437.183757) (xy 132.334093 -437.206749) (xy 132.334508 -437.218836) (xy 132.334508 -438.760362)
			(xy 133.241288 -438.760362) (xy 133.241288 -436.218838) (xy 133.241741 -436.206746) (xy 133.249193 -436.183738)
			(xy 133.263381 -436.164153) (xy 133.282921 -436.149903) (xy 133.305905 -436.142379) (xy 133.317996 -436.141876)
			(xy 134.257796 -436.141876) (xy 134.269902 -436.142319) (xy 134.292925 -436.149815) (xy 134.307483 -436.160418)
			(xy 135.241284 -436.160418) (xy 135.241284 -433.618894) (xy 135.241703 -433.6068) (xy 135.249167 -433.583792)
			(xy 135.263364 -433.564208) (xy 135.282911 -433.549959) (xy 135.305899 -433.542435) (xy 135.317992 -433.541932)
			(xy 136.257792 -433.541932) (xy 136.269904 -433.542323) (xy 136.292936 -433.549824) (xy 136.312512 -433.564091)
			(xy 136.326706 -433.58372) (xy 136.334121 -433.606781) (xy 136.3345 -433.618894) (xy 136.3345 -435.16042)
			(xy 137.24128 -435.16042) (xy 137.24128 -432.618896) (xy 137.241761 -432.606822) (xy 137.249223 -432.583857)
			(xy 137.263416 -432.564321) (xy 137.28295 -432.550126) (xy 137.305914 -432.542662) (xy 137.317988 -432.542188)
			(xy 138.257788 -432.542188) (xy 138.26987 -432.542623) (xy 138.292851 -432.550087) (xy 138.307154 -432.560476)
			(xy 139.241276 -432.560476) (xy 139.241276 -430.018952) (xy 139.241723 -430.006877) (xy 139.249197 -429.98391)
			(xy 139.263398 -429.964376) (xy 139.282939 -429.950182) (xy 139.305908 -429.942718) (xy 139.317984 -429.942244)
			(xy 140.257784 -429.942244) (xy 140.269853 -429.942777) (xy 140.292812 -429.950229) (xy 140.312345 -429.96441)
			(xy 140.326541 -429.983931) (xy 140.334013 -430.006883) (xy 140.334492 -430.018952) (xy 140.334492 -431.560478)
			(xy 142.241524 -431.560478) (xy 142.241524 -429.018954) (xy 142.241968 -429.006864) (xy 142.249435 -428.983864)
			(xy 142.263628 -428.964286) (xy 142.283165 -428.950037) (xy 142.306143 -428.942503) (xy 142.318232 -428.941992)
			(xy 143.258032 -428.941992) (xy 143.270142 -428.942389) (xy 143.293169 -428.949896) (xy 143.307414 -428.96028)
			(xy 144.24152 -428.96028) (xy 144.24152 -428.233078) (xy 144.24177 -428.224321) (xy 144.24575 -428.207263)
			(xy 144.249394 -428.199296) (xy 144.48282 -427.723046) (xy 144.487546 -427.712539) (xy 144.491026 -427.689775)
			(xy 144.487531 -427.667013) (xy 144.48282 -427.656498) (xy 144.249394 -427.180248) (xy 144.245746 -427.172281)
			(xy 144.241761 -427.155224) (xy 144.24152 -427.146466) (xy 144.24152 -426.418756) (xy 144.241927 -426.406676)
			(xy 144.249405 -426.383703) (xy 144.263615 -426.364164) (xy 144.283168 -426.349972) (xy 144.306148 -426.342516)
			(xy 144.318228 -426.342048) (xy 145.258028 -426.342048) (xy 145.2701 -426.342539) (xy 145.29306 -426.350004)
			(xy 145.312593 -426.364195) (xy 145.326788 -426.383725) (xy 145.334258 -426.406684) (xy 145.334736 -426.418756)
			(xy 145.334736 -427.960536) (xy 146.241516 -427.960536) (xy 146.241516 -427.233334) (xy 146.241785 -427.224578)
			(xy 146.245752 -427.20752) (xy 146.24939 -427.199552) (xy 146.482816 -426.723302) (xy 146.487503 -426.71278)
			(xy 146.490997 -426.690025) (xy 146.487518 -426.667268) (xy 146.482816 -426.656754) (xy 146.24939 -426.180504)
			(xy 146.245728 -426.172543) (xy 146.241752 -426.155482) (xy 146.241516 -426.146722) (xy 146.241516 -425.419012)
			(xy 146.241923 -425.406928) (xy 146.249391 -425.383941) (xy 146.263597 -425.364389) (xy 146.283152 -425.350185)
			(xy 146.306139 -425.342722) (xy 146.318224 -425.342304) (xy 147.258024 -425.342304) (xy 147.270101 -425.342744)
			(xy 147.293071 -425.350215) (xy 147.312609 -425.364417) (xy 147.326802 -425.383961) (xy 147.334261 -425.406935)
			(xy 147.334732 -425.419012) (xy 147.334732 -427.960536) (xy 147.334267 -427.97261) (xy 147.326798 -427.995574)
			(xy 147.3126 -428.015109) (xy 147.293064 -428.029303) (xy 147.270098 -428.036769) (xy 147.258024 -428.037244)
			(xy 146.318224 -428.037244) (xy 146.306154 -428.036716) (xy 146.283194 -428.029264) (xy 146.26366 -428.015083)
			(xy 146.249463 -427.99556) (xy 146.241993 -427.972605) (xy 146.241516 -427.960536) (xy 145.334736 -427.960536)
			(xy 145.334736 -428.96028) (xy 145.334219 -428.972351) (xy 145.326766 -428.995313) (xy 145.312582 -429.014848)
			(xy 145.293056 -429.029044) (xy 145.270098 -429.036512) (xy 145.258028 -429.036988) (xy 144.318228 -429.036988)
			(xy 144.306145 -429.036563) (xy 144.28316 -429.029101) (xy 144.263607 -429.014899) (xy 144.249403 -428.995348)
			(xy 144.241938 -428.972363) (xy 144.24152 -428.96028) (xy 143.307414 -428.96028) (xy 143.312741 -428.964163)
			(xy 143.326934 -428.983788) (xy 143.334356 -429.006843) (xy 143.33474 -429.018954) (xy 143.33474 -431.560478)
			(xy 143.334273 -431.572568) (xy 143.32682 -431.595572) (xy 143.312634 -431.615154) (xy 143.293099 -431.629404)
			(xy 143.270121 -431.636933) (xy 143.258032 -431.63744) (xy 142.318232 -431.63744) (xy 142.306129 -431.636957)
			(xy 142.283109 -431.629471) (xy 142.263539 -431.615225) (xy 142.249342 -431.59562) (xy 142.241913 -431.572582)
			(xy 142.241524 -431.560478) (xy 140.334492 -431.560478) (xy 140.334492 -432.560476) (xy 140.334067 -432.572559)
			(xy 140.326604 -432.595544) (xy 140.312401 -432.615096) (xy 140.292851 -432.6293) (xy 140.269867 -432.636765)
			(xy 140.257784 -432.637184) (xy 139.317984 -432.637184) (xy 139.305898 -432.636801) (xy 139.282911 -432.629326)
			(xy 139.263359 -432.615113) (xy 139.249156 -432.595553) (xy 139.241693 -432.572562) (xy 139.241276 -432.560476)
			(xy 138.307154 -432.560476) (xy 138.312401 -432.564287) (xy 138.326606 -432.583834) (xy 138.334074 -432.606814)
			(xy 138.334496 -432.618896) (xy 138.334496 -435.16042) (xy 138.334052 -435.172497) (xy 138.326583 -435.195467)
			(xy 138.312381 -435.215004) (xy 138.292838 -435.229198) (xy 138.269865 -435.236657) (xy 138.257788 -435.237128)
			(xy 137.317988 -435.237128) (xy 137.305915 -435.236646) (xy 137.282951 -435.229183) (xy 137.263416 -435.21499)
			(xy 137.249221 -435.195456) (xy 137.241755 -435.172493) (xy 137.24128 -435.16042) (xy 136.3345 -435.16042)
			(xy 136.3345 -436.160418) (xy 136.334009 -436.172505) (xy 136.326552 -436.195499) (xy 136.31237 -436.215075)
			(xy 136.292845 -436.229327) (xy 136.269877 -436.236865) (xy 136.257792 -436.23738) (xy 135.317992 -436.23738)
			(xy 135.305881 -436.23699) (xy 135.28285 -436.229486) (xy 135.263275 -436.215219) (xy 135.249081 -436.19559)
			(xy 135.241664 -436.172531) (xy 135.241284 -436.160418) (xy 134.307483 -436.160418) (xy 134.312497 -436.16407)
			(xy 134.326692 -436.183685) (xy 134.334117 -436.20673) (xy 134.334504 -436.218838) (xy 134.334504 -438.760362)
			(xy 134.333961 -438.772445) (xy 134.32652 -438.795437) (xy 134.312352 -438.815014) (xy 134.292837 -438.829267)
			(xy 134.269877 -438.836808) (xy 134.257796 -438.837324) (xy 133.317996 -438.837324) (xy 133.305889 -438.836888)
			(xy 133.282866 -438.82939) (xy 133.263295 -438.815133) (xy 133.2491 -438.795517) (xy 133.241675 -438.77247)
			(xy 133.241288 -438.760362) (xy 132.334508 -438.760362) (xy 132.334508 -439.76036) (xy 135.241284 -439.76036)
			(xy 135.241284 -437.218836) (xy 135.241743 -437.206756) (xy 135.2492 -437.183776) (xy 135.263394 -437.164226)
			(xy 135.282936 -437.15002) (xy 135.305912 -437.14255) (xy 135.317992 -437.142128) (xy 136.257792 -437.142128)
			(xy 136.269878 -437.14252) (xy 136.292867 -437.149989) (xy 136.31242 -437.1642) (xy 136.326623 -437.183759)
			(xy 136.334085 -437.20675) (xy 136.3345 -437.218836) (xy 136.3345 -438.760362) (xy 137.24128 -438.760362)
			(xy 137.24128 -436.218838) (xy 137.24174 -436.206746) (xy 137.249192 -436.18374) (xy 137.263378 -436.164156)
			(xy 137.282916 -436.149906) (xy 137.305898 -436.14238) (xy 137.317988 -436.141876) (xy 138.257788 -436.141876)
			(xy 138.269894 -436.142326) (xy 138.292917 -436.14982) (xy 138.307469 -436.160418) (xy 139.241276 -436.160418)
			(xy 139.241276 -433.618894) (xy 139.241703 -433.606801) (xy 139.249166 -433.583794) (xy 139.263361 -433.564211)
			(xy 139.282906 -433.549962) (xy 139.305892 -433.542436) (xy 139.317984 -433.541932) (xy 140.257784 -433.541932)
			(xy 140.269895 -433.542331) (xy 140.292927 -433.549829) (xy 140.312503 -433.564094) (xy 140.326697 -433.583722)
			(xy 140.334113 -433.606781) (xy 140.334492 -433.618894) (xy 140.334492 -435.16042) (xy 142.241016 -435.16042)
			(xy 142.241016 -432.618896) (xy 142.241413 -432.606785) (xy 142.248915 -432.583755) (xy 142.263181 -432.564181)
			(xy 142.282808 -432.549987) (xy 142.305866 -432.542569) (xy 142.317978 -432.542188) (xy 143.257778 -432.542188)
			(xy 143.269871 -432.542627) (xy 143.292879 -432.550084) (xy 143.30722 -432.560476) (xy 144.24152 -432.560476)
			(xy 144.24152 -430.018952) (xy 144.241924 -430.006872) (xy 144.249403 -429.983899) (xy 144.263614 -429.96436)
			(xy 144.283167 -429.950168) (xy 144.306148 -429.942712) (xy 144.318228 -429.942244) (xy 145.258028 -429.942244)
			(xy 145.270099 -429.942739) (xy 145.293059 -429.950204) (xy 145.312592 -429.964394) (xy 145.326787 -429.983923)
			(xy 145.334258 -430.006881) (xy 145.334736 -430.018952) (xy 145.334736 -431.560478) (xy 146.241516 -431.560478)
			(xy 146.241516 -429.018954) (xy 146.241968 -429.006864) (xy 146.249434 -428.983866) (xy 146.263626 -428.964289)
			(xy 146.28316 -428.950039) (xy 146.306136 -428.942504) (xy 146.318224 -428.941992) (xy 147.258024 -428.941992)
			(xy 147.270133 -428.942396) (xy 147.29316 -428.949901) (xy 147.3074 -428.96028) (xy 148.241512 -428.96028)
			(xy 148.241512 -428.233078) (xy 148.241763 -428.224321) (xy 148.245743 -428.207263) (xy 148.249386 -428.199296)
			(xy 148.482812 -427.723046) (xy 148.487538 -427.712539) (xy 148.491019 -427.689775) (xy 148.487523 -427.667012)
			(xy 148.482812 -427.656498) (xy 148.249386 -427.180248) (xy 148.245738 -427.172281) (xy 148.241753 -427.155224)
			(xy 148.241512 -427.146466) (xy 148.241512 -426.418756) (xy 148.241927 -426.406677) (xy 148.249404 -426.383705)
			(xy 148.263613 -426.364167) (xy 148.283162 -426.349975) (xy 148.306141 -426.342517) (xy 148.31822 -426.342048)
			(xy 149.25802 -426.342048) (xy 149.270091 -426.342547) (xy 149.293052 -426.350009) (xy 149.312584 -426.364199)
			(xy 149.32678 -426.383727) (xy 149.33425 -426.406685) (xy 149.334728 -426.418756) (xy 149.334728 -427.960536)
			(xy 150.241508 -427.960536) (xy 150.241508 -427.233334) (xy 150.241778 -427.224578) (xy 150.245744 -427.207521)
			(xy 150.249382 -427.199552) (xy 150.482808 -426.723302) (xy 150.487495 -426.71278) (xy 150.49099 -426.690025)
			(xy 150.487511 -426.667268) (xy 150.482808 -426.656754) (xy 150.249382 -426.180504) (xy 150.24572 -426.172543)
			(xy 150.241744 -426.155482) (xy 150.241508 -426.146722) (xy 150.241508 -425.419012) (xy 150.241923 -425.406928)
			(xy 150.249389 -425.383943) (xy 150.263594 -425.364392) (xy 150.283147 -425.350188) (xy 150.306132 -425.342723)
			(xy 150.318216 -425.342304) (xy 151.258016 -425.342304) (xy 151.270093 -425.342751) (xy 151.293062 -425.350219)
			(xy 151.3126 -425.36442) (xy 151.326794 -425.383963) (xy 151.334253 -425.406935) (xy 151.334724 -425.419012)
			(xy 151.334724 -427.960536) (xy 151.334267 -427.972611) (xy 151.326796 -427.995577) (xy 151.312597 -428.015112)
			(xy 151.293059 -428.029306) (xy 151.270091 -428.03677) (xy 151.258016 -428.037244) (xy 150.318216 -428.037244)
			(xy 150.306146 -428.036723) (xy 150.283185 -428.029269) (xy 150.263651 -428.015086) (xy 150.249455 -427.995561)
			(xy 150.241985 -427.972606) (xy 150.241508 -427.960536) (xy 149.334728 -427.960536) (xy 149.334728 -428.96028)
			(xy 149.334219 -428.972352) (xy 149.326765 -428.995315) (xy 149.312579 -429.01485) (xy 149.293051 -429.029046)
			(xy 149.270091 -429.036513) (xy 149.25802 -429.036988) (xy 148.31822 -429.036988) (xy 148.306136 -429.03657)
			(xy 148.283151 -429.029105) (xy 148.263599 -429.014901) (xy 148.249395 -428.995349) (xy 148.24193 -428.972364)
			(xy 148.241512 -428.96028) (xy 147.3074 -428.96028) (xy 147.312732 -428.964166) (xy 147.326926 -428.983789)
			(xy 147.334348 -429.006843) (xy 147.334732 -429.018954) (xy 147.334732 -431.560478) (xy 147.334273 -431.572569)
			(xy 147.326819 -431.595574) (xy 147.312632 -431.615156) (xy 147.293094 -431.629407) (xy 147.270114 -431.636934)
			(xy 147.258024 -431.63744) (xy 146.318224 -431.63744) (xy 146.30612 -431.636964) (xy 146.283101 -431.629476)
			(xy 146.263531 -431.615228) (xy 146.249334 -431.595622) (xy 146.241905 -431.572583) (xy 146.241516 -431.560478)
			(xy 145.334736 -431.560478) (xy 145.334736 -432.560476) (xy 145.334216 -432.572547) (xy 145.326763 -432.595508)
			(xy 145.31258 -432.615043) (xy 145.293055 -432.62924) (xy 145.270098 -432.636708) (xy 145.258028 -432.637184)
			(xy 144.318228 -432.637184) (xy 144.306144 -432.636763) (xy 144.283159 -432.6293) (xy 144.263606 -432.615097)
			(xy 144.249402 -432.595545) (xy 144.241938 -432.57256) (xy 144.24152 -432.560476) (xy 143.30722 -432.560476)
			(xy 143.312464 -432.564276) (xy 143.326713 -432.583818) (xy 143.334237 -432.606804) (xy 143.33474 -432.618896)
			(xy 143.33474 -435.16042) (xy 143.334301 -435.172526) (xy 143.326801 -435.195547) (xy 143.312544 -435.215116)
			(xy 143.29293 -435.229312) (xy 143.269885 -435.236739) (xy 143.257778 -435.237128) (xy 142.317978 -435.237128)
			(xy 142.305884 -435.236711) (xy 142.282877 -435.229244) (xy 142.263295 -435.215046) (xy 142.249046 -435.1955)
			(xy 142.24152 -435.172513) (xy 142.241016 -435.16042) (xy 140.334492 -435.16042) (xy 140.334492 -436.160418)
			(xy 140.334009 -436.172505) (xy 140.326551 -436.195501) (xy 140.312367 -436.215078) (xy 140.29284 -436.229329)
			(xy 140.26987 -436.236866) (xy 140.257784 -436.23738) (xy 139.317984 -436.23738) (xy 139.305872 -436.236997)
			(xy 139.282841 -436.229491) (xy 139.263266 -436.215221) (xy 139.249073 -436.195592) (xy 139.241656 -436.172531)
			(xy 139.241276 -436.160418) (xy 138.307469 -436.160418) (xy 138.312488 -436.164073) (xy 138.326684 -436.183686)
			(xy 138.334109 -436.206731) (xy 138.334496 -436.218838) (xy 138.334496 -438.760362) (xy 138.333961 -438.772446)
			(xy 138.326519 -438.795439) (xy 138.312349 -438.815017) (xy 138.292832 -438.82927) (xy 138.26987 -438.836809)
			(xy 138.257788 -438.837324) (xy 137.317988 -438.837324) (xy 137.305881 -438.836894) (xy 137.282857 -438.829395)
			(xy 137.263286 -438.815136) (xy 137.249091 -438.795518) (xy 137.241667 -438.77247) (xy 137.24128 -438.760362)
			(xy 136.3345 -438.760362) (xy 136.3345 -439.76036) (xy 139.241276 -439.76036) (xy 139.241276 -437.218836)
			(xy 139.241743 -437.206757) (xy 139.249199 -437.183778) (xy 139.263391 -437.164228) (xy 139.282931 -437.150023)
			(xy 139.305905 -437.142551) (xy 139.317984 -437.142128) (xy 140.257784 -437.142128) (xy 140.269869 -437.142527)
			(xy 140.292858 -437.149995) (xy 140.312411 -437.164203) (xy 140.326615 -437.18376) (xy 140.334076 -437.20675)
			(xy 140.334492 -437.218836) (xy 140.334492 -438.760362) (xy 142.241016 -438.760362) (xy 142.241016 -436.218838)
			(xy 142.241492 -436.206719) (xy 142.248971 -436.183665) (xy 142.263209 -436.164052) (xy 142.282812 -436.149798)
			(xy 142.30586 -436.142301) (xy 142.317978 -436.141876) (xy 143.257778 -436.141876) (xy 143.269903 -436.142279)
			(xy 143.292968 -436.14977) (xy 143.307623 -436.160418) (xy 144.241012 -436.160418) (xy 144.241012 -433.618894)
			(xy 144.241506 -433.606782) (xy 144.248992 -433.583743) (xy 144.263229 -433.564143) (xy 144.282825 -433.549901)
			(xy 144.305862 -433.54241) (xy 144.317974 -433.541932) (xy 145.257774 -433.541932) (xy 145.269895 -433.542382)
			(xy 145.292952 -433.549866) (xy 145.312567 -433.56411) (xy 145.326819 -433.58372) (xy 145.334313 -433.606773)
			(xy 145.334736 -433.618894) (xy 145.334736 -435.16042) (xy 146.241008 -435.16042) (xy 146.241008 -432.618896)
			(xy 146.241413 -432.606786) (xy 146.248914 -432.583757) (xy 146.263179 -432.564184) (xy 146.282803 -432.549989)
			(xy 146.305859 -432.54257) (xy 146.31797 -432.542188) (xy 147.25777 -432.542188) (xy 147.269863 -432.542634)
			(xy 147.29287 -432.550088) (xy 147.307207 -432.560476) (xy 148.241512 -432.560476) (xy 148.241512 -430.018952)
			(xy 148.241924 -430.006873) (xy 148.249402 -429.983901) (xy 148.263611 -429.964363) (xy 148.283162 -429.950171)
			(xy 148.306141 -429.942713) (xy 148.31822 -429.942244) (xy 149.25802 -429.942244) (xy 149.270091 -429.942747)
			(xy 149.29305 -429.950209) (xy 149.312583 -429.964397) (xy 149.326778 -429.983924) (xy 149.334249 -430.006881)
			(xy 149.334728 -430.018952) (xy 149.334728 -431.560478) (xy 150.241508 -431.560478) (xy 150.241508 -429.018954)
			(xy 150.241968 -429.006865) (xy 150.249433 -428.983868) (xy 150.263623 -428.964292) (xy 150.283155 -428.950042)
			(xy 150.306129 -428.942505) (xy 150.318216 -428.941992) (xy 151.258016 -428.941992) (xy 151.270125 -428.942402)
			(xy 151.293151 -428.949905) (xy 151.307388 -428.96028) (xy 152.241504 -428.96028) (xy 152.241504 -428.233078)
			(xy 152.241756 -428.224321) (xy 152.245735 -428.207263) (xy 152.249378 -428.199296) (xy 152.482804 -427.723046)
			(xy 152.487531 -427.712539) (xy 152.491012 -427.689775) (xy 152.487516 -427.667012) (xy 152.482804 -427.656498)
			(xy 152.249378 -427.180248) (xy 152.245729 -427.172282) (xy 152.241745 -427.155224) (xy 152.241504 -427.146466)
			(xy 152.241504 -426.418756) (xy 152.241927 -426.406678) (xy 152.249403 -426.383707) (xy 152.26361 -426.36417)
			(xy 152.283157 -426.349977) (xy 152.306134 -426.342518) (xy 152.318212 -426.342048) (xy 153.258012 -426.342048)
			(xy 153.270083 -426.342553) (xy 153.293043 -426.350014) (xy 153.312576 -426.364201) (xy 153.326772 -426.383728)
			(xy 153.334242 -426.406685) (xy 153.33472 -426.418756) (xy 153.33472 -427.960536) (xy 154.2415 -427.960536)
			(xy 154.2415 -427.233334) (xy 154.24177 -427.224578) (xy 154.245737 -427.207521) (xy 154.249374 -427.199552)
			(xy 154.4828 -426.723302) (xy 154.487488 -426.71278) (xy 154.490983 -426.690025) (xy 154.487503 -426.667268)
			(xy 154.4828 -426.656754) (xy 154.249374 -426.180504) (xy 154.245711 -426.172543) (xy 154.241736 -426.155482)
			(xy 154.2415 -426.146722) (xy 154.2415 -425.419012) (xy 154.241923 -425.406929) (xy 154.249388 -425.383946)
			(xy 154.263592 -425.364394) (xy 154.283142 -425.35019) (xy 154.306125 -425.342724) (xy 154.318208 -425.342304)
			(xy 155.258008 -425.342304) (xy 155.270092 -425.342706) (xy 155.293077 -425.350177) (xy 155.312629 -425.364386)
			(xy 155.326832 -425.383941) (xy 155.334297 -425.406928) (xy 155.334716 -425.419012) (xy 155.334716 -427.960536)
			(xy 155.334267 -427.972612) (xy 155.326795 -427.995579) (xy 155.312595 -428.015115) (xy 155.293054 -428.029308)
			(xy 155.270084 -428.036771) (xy 155.258008 -428.037244) (xy 154.318208 -428.037244) (xy 154.306137 -428.03673)
			(xy 154.283177 -428.029274) (xy 154.263643 -428.015089) (xy 154.249447 -427.995563) (xy 154.241977 -427.972606)
			(xy 154.2415 -427.960536) (xy 153.33472 -427.960536) (xy 153.33472 -428.96028) (xy 153.33427 -428.97236)
			(xy 153.32681 -428.99534) (xy 153.312613 -429.01489) (xy 153.293069 -429.029095) (xy 153.270092 -429.036565)
			(xy 153.258012 -429.036988) (xy 152.318212 -429.036988) (xy 152.306128 -429.036577) (xy 152.283142 -429.02911)
			(xy 152.26359 -429.014904) (xy 152.249386 -428.995351) (xy 152.241922 -428.972364) (xy 152.241504 -428.96028)
			(xy 151.307388 -428.96028) (xy 151.312724 -428.964169) (xy 151.326918 -428.983791) (xy 151.33434 -429.006844)
			(xy 151.334724 -429.018954) (xy 151.334724 -431.560478) (xy 151.334273 -431.57257) (xy 151.326818 -431.595576)
			(xy 151.312629 -431.615159) (xy 151.293089 -431.629409) (xy 151.270106 -431.636935) (xy 151.258016 -431.63744)
			(xy 150.318216 -431.63744) (xy 150.306112 -431.63697) (xy 150.283092 -431.62948) (xy 150.263522 -431.615231)
			(xy 150.249326 -431.595623) (xy 150.241897 -431.572583) (xy 150.241508 -431.560478) (xy 149.334728 -431.560478)
			(xy 149.334728 -432.560476) (xy 149.334267 -432.572555) (xy 149.326809 -432.595534) (xy 149.312614 -432.615083)
			(xy 149.293073 -432.629288) (xy 149.270099 -432.63676) (xy 149.25802 -432.637184) (xy 148.31822 -432.637184)
			(xy 148.306136 -432.63677) (xy 148.28315 -432.629305) (xy 148.263597 -432.6151) (xy 148.249393 -432.595547)
			(xy 148.24193 -432.57256) (xy 148.241512 -432.560476) (xy 147.307207 -432.560476) (xy 147.312455 -432.564278)
			(xy 147.326705 -432.58382) (xy 147.334229 -432.606805) (xy 147.334732 -432.618896) (xy 147.334732 -435.16042)
			(xy 147.334301 -435.172527) (xy 147.3268 -435.195549) (xy 147.312541 -435.215119) (xy 147.292925 -435.229314)
			(xy 147.269878 -435.23674) (xy 147.25777 -435.237128) (xy 146.31797 -435.237128) (xy 146.305876 -435.236718)
			(xy 146.282869 -435.229249) (xy 146.263286 -435.215049) (xy 146.249038 -435.195502) (xy 146.241512 -435.172513)
			(xy 146.241008 -435.16042) (xy 145.334736 -435.16042) (xy 145.334736 -436.160418) (xy 145.334355 -436.172544)
			(xy 145.326854 -436.195608) (xy 145.312594 -436.215225) (xy 145.292969 -436.229474) (xy 145.2699 -436.236962)
			(xy 145.257774 -436.23738) (xy 144.317974 -436.23738) (xy 144.30586 -436.236911) (xy 144.282819 -436.229419)
			(xy 144.263219 -436.215175) (xy 144.248978 -436.195574) (xy 144.241488 -436.172532) (xy 144.241012 -436.160418)
			(xy 143.307623 -436.160418) (xy 143.312587 -436.164025) (xy 143.326837 -436.183646) (xy 143.334323 -436.206713)
			(xy 143.33474 -436.218838) (xy 143.33474 -438.760362) (xy 143.334307 -438.772485) (xy 143.326823 -438.795546)
			(xy 143.312575 -438.815164) (xy 143.292961 -438.829416) (xy 143.269901 -438.836905) (xy 143.257778 -438.837324)
			(xy 142.317978 -438.837324) (xy 142.30585 -438.836958) (xy 142.282784 -438.829455) (xy 142.263167 -438.815191)
			(xy 142.248918 -438.795562) (xy 142.241433 -438.77249) (xy 142.241016 -438.760362) (xy 140.334492 -438.760362)
			(xy 140.334492 -439.76036) (xy 144.241012 -439.76036) (xy 144.241012 -437.218836) (xy 144.241447 -437.206728)
			(xy 144.248938 -437.1837) (xy 144.263194 -437.164125) (xy 144.282813 -437.14993) (xy 144.305865 -437.14251)
			(xy 144.317974 -437.142128) (xy 145.257774 -437.142128) (xy 145.269861 -437.142629) (xy 145.292859 -437.150077)
			(xy 145.312438 -437.164256) (xy 145.32669 -437.183781) (xy 145.334225 -437.206751) (xy 145.334736 -437.218836)
			(xy 145.334736 -438.760362) (xy 146.241008 -438.760362) (xy 146.241008 -436.218838) (xy 146.241492 -436.20672)
			(xy 146.24897 -436.183668) (xy 146.263206 -436.164055) (xy 146.282807 -436.149801) (xy 146.305853 -436.142302)
			(xy 146.31797 -436.141876) (xy 147.25777 -436.141876) (xy 147.269895 -436.142286) (xy 147.292959 -436.149775)
			(xy 147.307609 -436.160418) (xy 148.241004 -436.160418) (xy 148.241004 -433.618894) (xy 148.241506 -433.606783)
			(xy 148.248991 -433.583745) (xy 148.263226 -433.564146) (xy 148.28282 -433.549904) (xy 148.305855 -433.542411)
			(xy 148.317966 -433.541932) (xy 149.257766 -433.541932) (xy 149.269886 -433.542389) (xy 149.292943 -433.549871)
			(xy 149.312558 -433.564113) (xy 149.326811 -433.583721) (xy 149.334305 -433.606774) (xy 149.334728 -433.618894)
			(xy 149.334728 -435.16042) (xy 150.241 -435.16042) (xy 150.241 -432.618896) (xy 150.241413 -432.606787)
			(xy 150.248913 -432.583759) (xy 150.263176 -432.564186) (xy 150.282798 -432.549992) (xy 150.305852 -432.542571)
			(xy 150.317962 -432.542188) (xy 151.257762 -432.542188) (xy 151.269854 -432.542641) (xy 151.292862 -432.550093)
			(xy 151.307195 -432.560476) (xy 152.241504 -432.560476) (xy 152.241504 -430.018952) (xy 152.241923 -430.006874)
			(xy 152.249401 -429.983903) (xy 152.263608 -429.964366) (xy 152.283157 -429.950173) (xy 152.306133 -429.942714)
			(xy 152.318212 -429.942244) (xy 153.258012 -429.942244) (xy 153.270082 -429.942753) (xy 153.293042 -429.950213)
			(xy 153.312574 -429.9644) (xy 153.32677 -429.983926) (xy 153.334241 -430.006882) (xy 153.33472 -430.018952)
			(xy 153.33472 -431.560478) (xy 154.2415 -431.560478) (xy 154.2415 -429.018954) (xy 154.241967 -429.006866)
			(xy 154.249432 -428.983871) (xy 154.26362 -428.964295) (xy 154.28315 -428.950044) (xy 154.306122 -428.942507)
			(xy 154.318208 -428.941992) (xy 155.258008 -428.941992) (xy 155.270117 -428.942409) (xy 155.293143 -428.94991)
			(xy 155.307374 -428.96028) (xy 156.241496 -428.96028) (xy 156.241496 -428.233078) (xy 156.241749 -428.224321)
			(xy 156.245727 -428.207264) (xy 156.24937 -428.199296) (xy 156.482796 -427.723046) (xy 156.487523 -427.712539)
			(xy 156.491005 -427.689775) (xy 156.487508 -427.667012) (xy 156.482796 -427.656498) (xy 156.24937 -427.180248)
			(xy 156.245721 -427.172282) (xy 156.241737 -427.155224) (xy 156.241496 -427.146466) (xy 156.241496 -426.418756)
			(xy 156.241927 -426.406679) (xy 156.249402 -426.383709) (xy 156.263607 -426.364173) (xy 156.283152 -426.34998)
			(xy 156.306126 -426.342519) (xy 156.318204 -426.342048) (xy 157.258004 -426.342048) (xy 157.270074 -426.34256)
			(xy 157.293034 -426.350018) (xy 157.312567 -426.364204) (xy 157.326763 -426.38373) (xy 157.334233 -426.406686)
			(xy 157.334712 -426.418756) (xy 157.334712 -428.96028) (xy 157.33427 -428.972361) (xy 157.326809 -428.995343)
			(xy 157.31261 -429.014893) (xy 157.293064 -429.029098) (xy 157.270085 -429.036566) (xy 157.258004 -429.036988)
			(xy 156.318204 -429.036988) (xy 156.306119 -429.036584) (xy 156.283133 -429.029115) (xy 156.263581 -429.014907)
			(xy 156.249378 -428.995352) (xy 156.241914 -428.972365) (xy 156.241496 -428.96028) (xy 155.307374 -428.96028)
			(xy 155.312715 -428.964172) (xy 155.32691 -428.983792) (xy 155.334332 -429.006844) (xy 155.334716 -429.018954)
			(xy 155.334716 -431.560478) (xy 155.334273 -431.572571) (xy 155.326817 -431.595578) (xy 155.312626 -431.615162)
			(xy 155.293084 -431.629412) (xy 155.270099 -431.636937) (xy 155.258008 -431.63744) (xy 154.318208 -431.63744)
			(xy 154.306104 -431.636978) (xy 154.283083 -431.629485) (xy 154.263513 -431.615234) (xy 154.249317 -431.595625)
			(xy 154.241889 -431.572584) (xy 154.2415 -431.560478) (xy 153.33472 -431.560478) (xy 153.33472 -432.560476)
			(xy 153.334267 -432.572556) (xy 153.326807 -432.595536) (xy 153.312611 -432.615086) (xy 153.293068 -432.629291)
			(xy 153.270092 -432.636761) (xy 153.258012 -432.637184) (xy 152.318212 -432.637184) (xy 152.306128 -432.636777)
			(xy 152.283141 -432.629309) (xy 152.263589 -432.615103) (xy 152.249385 -432.595548) (xy 152.241922 -432.572561)
			(xy 152.241504 -432.560476) (xy 151.307195 -432.560476) (xy 151.312447 -432.564281) (xy 151.326697 -432.583821)
			(xy 151.334221 -432.606805) (xy 151.334724 -432.618896) (xy 151.334724 -435.16042) (xy 151.334301 -435.172528)
			(xy 151.326799 -435.195551) (xy 151.312538 -435.215122) (xy 151.29292 -435.229317) (xy 151.269871 -435.236741)
			(xy 151.257762 -435.237128) (xy 150.317962 -435.237128) (xy 150.305867 -435.236724) (xy 150.28286 -435.229253)
			(xy 150.263278 -435.215052) (xy 150.24903 -435.195503) (xy 150.241504 -435.172514) (xy 150.241 -435.16042)
			(xy 149.334728 -435.16042) (xy 149.334728 -436.160418) (xy 149.334355 -436.172545) (xy 149.326853 -436.19561)
			(xy 149.312591 -436.215228) (xy 149.292964 -436.229477) (xy 149.269893 -436.236963) (xy 149.257766 -436.23738)
			(xy 148.317966 -436.23738) (xy 148.305851 -436.236918) (xy 148.28281 -436.229423) (xy 148.26321 -436.215178)
			(xy 148.248969 -436.195576) (xy 148.24148 -436.172533) (xy 148.241004 -436.160418) (xy 147.307609 -436.160418)
			(xy 147.312578 -436.164028) (xy 147.326829 -436.183648) (xy 147.334315 -436.206713) (xy 147.334732 -436.218838)
			(xy 147.334732 -438.760362) (xy 147.334307 -438.772486) (xy 147.326822 -438.795549) (xy 147.312573 -438.815167)
			(xy 147.292956 -438.829418) (xy 147.269894 -438.836906) (xy 147.25777 -438.837324) (xy 146.31797 -438.837324)
			(xy 146.305842 -438.836965) (xy 146.282776 -438.82946) (xy 146.263158 -438.815194) (xy 146.248909 -438.795563)
			(xy 146.241424 -438.772491) (xy 146.241008 -438.760362) (xy 145.334736 -438.760362) (xy 145.334736 -439.76036)
			(xy 148.241004 -439.76036) (xy 148.241004 -437.218836) (xy 148.241447 -437.206729) (xy 148.248937 -437.183702)
			(xy 148.263192 -437.164128) (xy 148.282808 -437.149932) (xy 148.305857 -437.142511) (xy 148.317966 -437.142128)
			(xy 149.257766 -437.142128) (xy 149.269853 -437.142636) (xy 149.29285 -437.150082) (xy 149.31243 -437.164258)
			(xy 149.326682 -437.183783) (xy 149.334217 -437.206751) (xy 149.334728 -437.218836) (xy 149.334728 -438.760362)
			(xy 150.241 -438.760362) (xy 150.241 -436.218838) (xy 150.241543 -436.206729) (xy 150.249016 -436.183694)
			(xy 150.26324 -436.164094) (xy 150.282825 -436.14985) (xy 150.305854 -436.142355) (xy 150.317962 -436.141876)
			(xy 151.257762 -436.141876) (xy 151.269887 -436.142293) (xy 151.292951 -436.149779) (xy 151.307597 -436.160418)
			(xy 152.240996 -436.160418) (xy 152.240996 -433.618894) (xy 152.241506 -433.606783) (xy 152.24899 -433.583747)
			(xy 152.263224 -433.564149) (xy 152.282815 -433.549906) (xy 152.305848 -433.542412) (xy 152.317958 -433.541932)
			(xy 153.257758 -433.541932) (xy 153.269878 -433.542396) (xy 153.292934 -433.549876) (xy 153.31255 -433.564116)
			(xy 153.326803 -433.583722) (xy 153.334297 -433.606774) (xy 153.33472 -433.618894) (xy 153.33472 -435.16042)
			(xy 154.240992 -435.16042) (xy 154.240992 -432.618896) (xy 154.241413 -432.606788) (xy 154.248912 -432.583762)
			(xy 154.263173 -432.564189) (xy 154.282793 -432.549994) (xy 154.305844 -432.542572) (xy 154.317954 -432.542188)
			(xy 155.257754 -432.542188) (xy 155.269846 -432.542647) (xy 155.292853 -432.550097) (xy 155.307181 -432.560476)
			(xy 156.241496 -432.560476) (xy 156.241496 -430.018952) (xy 156.241923 -430.006875) (xy 156.249399 -429.983905)
			(xy 156.263605 -429.964368) (xy 156.283152 -429.950176) (xy 156.306126 -429.942715) (xy 156.318204 -429.942244)
			(xy 157.258004 -429.942244) (xy 157.270074 -429.94276) (xy 157.293033 -429.950218) (xy 157.312566 -429.964403)
			(xy 157.326762 -429.983927) (xy 157.334233 -430.006882) (xy 157.334712 -430.018952) (xy 157.334712 -432.560476)
			(xy 157.334267 -432.572557) (xy 157.326806 -432.595538) (xy 157.312609 -432.615089) (xy 157.293063 -432.629294)
			(xy 157.270085 -432.636762) (xy 157.258004 -432.637184) (xy 156.318204 -432.637184) (xy 156.306119 -432.636784)
			(xy 156.283132 -432.629314) (xy 156.26358 -432.615106) (xy 156.249376 -432.59555) (xy 156.241913 -432.572561)
			(xy 156.241496 -432.560476) (xy 155.307181 -432.560476) (xy 155.312438 -432.564284) (xy 155.326688 -432.583823)
			(xy 155.334213 -432.606806) (xy 155.334716 -432.618896) (xy 155.334716 -433.130695) (xy 197.035917 -433.130695)
			(xy 197.035917 -432.953425) (xy 197.04387 -432.776334) (xy 197.059761 -432.599778) (xy 197.083556 -432.424113)
			(xy 197.115209 -432.249692) (xy 197.154655 -432.076867) (xy 197.201815 -431.905986) (xy 197.256594 -431.737392)
			(xy 197.318882 -431.571427) (xy 197.388554 -431.408422) (xy 197.465468 -431.248708) (xy 197.549471 -431.092605)
			(xy 197.640392 -430.940428) (xy 197.738049 -430.792484) (xy 197.842246 -430.64907) (xy 197.952772 -430.510475)
			(xy 198.069404 -430.376978) (xy 198.191909 -430.248849) (xy 198.320038 -430.126344) (xy 198.453535 -430.009712)
			(xy 198.59213 -429.899186) (xy 198.735544 -429.794989) (xy 198.883488 -429.697332) (xy 199.035665 -429.606411)
			(xy 199.191768 -429.522408) (xy 199.351482 -429.445494) (xy 199.514487 -429.375822) (xy 199.680452 -429.313534)
			(xy 199.849046 -429.258755) (xy 200.019927 -429.211595) (xy 200.192752 -429.172149) (xy 200.367173 -429.140496)
			(xy 200.542838 -429.116701) (xy 200.719394 -429.10081) (xy 200.896485 -429.092857) (xy 201.073755 -429.092857)
			(xy 201.250846 -429.10081) (xy 201.427402 -429.116701) (xy 201.603067 -429.140496) (xy 201.777488 -429.172149)
			(xy 201.950313 -429.211595) (xy 202.121194 -429.258755) (xy 202.289788 -429.313534) (xy 202.455753 -429.375822)
			(xy 202.618758 -429.445494) (xy 202.778472 -429.522408) (xy 202.934575 -429.606411) (xy 203.086752 -429.697332)
			(xy 203.234696 -429.794989) (xy 203.37811 -429.899186) (xy 203.516705 -430.009712) (xy 203.650202 -430.126344)
			(xy 203.778331 -430.248849) (xy 203.900836 -430.376978) (xy 204.017468 -430.510475) (xy 204.127994 -430.64907)
			(xy 204.232191 -430.792484) (xy 204.329848 -430.940428) (xy 204.420769 -431.092605) (xy 204.504772 -431.248708)
			(xy 204.581686 -431.408422) (xy 204.651358 -431.571427) (xy 204.713646 -431.737392) (xy 204.768425 -431.905986)
			(xy 204.815585 -432.076867) (xy 204.855031 -432.249692) (xy 204.886684 -432.424113) (xy 204.910479 -432.599778)
			(xy 204.92637 -432.776334) (xy 204.934323 -432.953425) (xy 204.93482 -433.04206) (xy 204.934323 -433.130695)
			(xy 204.92637 -433.307786) (xy 204.910479 -433.484342) (xy 204.886684 -433.660007) (xy 204.855031 -433.834428)
			(xy 204.815585 -434.007253) (xy 204.768425 -434.178134) (xy 204.713646 -434.346728) (xy 204.651358 -434.512693)
			(xy 204.581686 -434.675698) (xy 204.504772 -434.835412) (xy 204.420769 -434.991515) (xy 204.329848 -435.143692)
			(xy 204.232191 -435.291636) (xy 204.127994 -435.43505) (xy 204.017468 -435.573645) (xy 203.900836 -435.707142)
			(xy 203.778331 -435.835271) (xy 203.650202 -435.957776) (xy 203.516705 -436.074408) (xy 203.37811 -436.184934)
			(xy 203.234696 -436.289131) (xy 203.086752 -436.386788) (xy 202.934575 -436.477709) (xy 202.778472 -436.561712)
			(xy 202.618758 -436.638626) (xy 202.455753 -436.708298) (xy 202.289788 -436.770586) (xy 202.121194 -436.825365)
			(xy 201.950313 -436.872525) (xy 201.777488 -436.911971) (xy 201.603067 -436.943624) (xy 201.427402 -436.967419)
			(xy 201.250846 -436.98331) (xy 201.073755 -436.991263) (xy 200.896485 -436.991263) (xy 200.719394 -436.98331)
			(xy 200.542838 -436.967419) (xy 200.367173 -436.943624) (xy 200.192752 -436.911971) (xy 200.019927 -436.872525)
			(xy 199.849046 -436.825365) (xy 199.680452 -436.770586) (xy 199.514487 -436.708298) (xy 199.351482 -436.638626)
			(xy 199.191768 -436.561712) (xy 199.035665 -436.477709) (xy 198.883488 -436.386788) (xy 198.735544 -436.289131)
			(xy 198.59213 -436.184934) (xy 198.453535 -436.074408) (xy 198.320038 -435.957776) (xy 198.191909 -435.835271)
			(xy 198.069404 -435.707142) (xy 197.952772 -435.573645) (xy 197.842246 -435.43505) (xy 197.738049 -435.291636)
			(xy 197.640392 -435.143692) (xy 197.549471 -434.991515) (xy 197.465468 -434.835412) (xy 197.388554 -434.675698)
			(xy 197.318882 -434.512693) (xy 197.256594 -434.346728) (xy 197.201815 -434.178134) (xy 197.154655 -434.007253)
			(xy 197.115209 -433.834428) (xy 197.083556 -433.660007) (xy 197.059761 -433.484342) (xy 197.04387 -433.307786)
			(xy 197.035917 -433.130695) (xy 155.334716 -433.130695) (xy 155.334716 -435.16042) (xy 155.334301 -435.172528)
			(xy 155.326798 -435.195554) (xy 155.312536 -435.215125) (xy 155.292915 -435.229319) (xy 155.269864 -435.236743)
			(xy 155.257754 -435.237128) (xy 154.317954 -435.237128) (xy 154.305859 -435.236731) (xy 154.282851 -435.229258)
			(xy 154.263269 -435.215054) (xy 154.249022 -435.195505) (xy 154.241496 -435.172514) (xy 154.240992 -435.16042)
			(xy 153.33472 -435.16042) (xy 153.33472 -436.160418) (xy 153.334354 -436.172546) (xy 153.326852 -436.195612)
			(xy 153.312588 -436.215231) (xy 153.292958 -436.22948) (xy 153.269886 -436.236964) (xy 153.257758 -436.23738)
			(xy 152.317958 -436.23738) (xy 152.305843 -436.236924) (xy 152.282801 -436.229428) (xy 152.263202 -436.215181)
			(xy 152.248961 -436.195577) (xy 152.241472 -436.172533) (xy 152.240996 -436.160418) (xy 151.307597 -436.160418)
			(xy 151.31257 -436.16403) (xy 151.326821 -436.183649) (xy 151.334307 -436.206713) (xy 151.334724 -436.218838)
			(xy 151.334724 -438.760362) (xy 151.334307 -438.772487) (xy 151.326821 -438.795551) (xy 151.31257 -438.81517)
			(xy 151.292951 -438.829421) (xy 151.269887 -438.836907) (xy 151.257762 -438.837324) (xy 150.317962 -438.837324)
			(xy 150.305842 -438.83692) (xy 150.282791 -438.829418) (xy 150.263186 -438.81516) (xy 150.248947 -438.795541)
			(xy 150.241468 -438.772483) (xy 150.241 -438.760362) (xy 149.334728 -438.760362) (xy 149.334728 -439.76036)
			(xy 152.240996 -439.76036) (xy 152.240996 -437.218836) (xy 152.241447 -437.206729) (xy 152.248936 -437.183704)
			(xy 152.263189 -437.164131) (xy 152.282803 -437.149935) (xy 152.30585 -437.142512) (xy 152.317958 -437.142128)
			(xy 153.257758 -437.142128) (xy 153.269844 -437.142643) (xy 153.292841 -437.150087) (xy 153.312421 -437.164261)
			(xy 153.326673 -437.183784) (xy 153.334209 -437.206752) (xy 153.33472 -437.218836) (xy 153.33472 -438.760362)
			(xy 154.240992 -438.760362) (xy 154.240992 -436.218838) (xy 154.241543 -436.20673) (xy 154.249015 -436.183696)
			(xy 154.263238 -436.164097) (xy 154.28282 -436.149853) (xy 154.305847 -436.142357) (xy 154.317954 -436.141876)
			(xy 155.257754 -436.141876) (xy 155.269878 -436.1423) (xy 155.292942 -436.149784) (xy 155.307584 -436.160418)
			(xy 156.240988 -436.160418) (xy 156.240988 -433.618894) (xy 156.241506 -433.606784) (xy 156.248989 -433.583749)
			(xy 156.263221 -433.564152) (xy 156.28281 -433.549909) (xy 156.30584 -433.542413) (xy 156.31795 -433.541932)
			(xy 157.25775 -433.541932) (xy 157.269867 -433.542369) (xy 157.29291 -433.549869) (xy 157.312511 -433.564121)
			(xy 157.326751 -433.583729) (xy 157.334238 -433.606777) (xy 157.334712 -433.618894) (xy 157.334712 -436.160418)
			(xy 157.334205 -436.172529) (xy 157.326718 -436.195564) (xy 157.312484 -436.215161) (xy 157.292893 -436.229404)
			(xy 157.26986 -436.2369) (xy 157.25775 -436.23738) (xy 156.31795 -436.23738) (xy 156.305835 -436.236931)
			(xy 156.282793 -436.229432) (xy 156.263193 -436.215184) (xy 156.248953 -436.195578) (xy 156.241464 -436.172534)
			(xy 156.240988 -436.160418) (xy 155.307584 -436.160418) (xy 155.312561 -436.164033) (xy 155.326813 -436.183651)
			(xy 155.334299 -436.206714) (xy 155.334716 -436.218838) (xy 155.334716 -438.760362) (xy 155.334307 -438.772487)
			(xy 155.32682 -438.795553) (xy 155.312567 -438.815173) (xy 155.292946 -438.829423) (xy 155.269879 -438.836908)
			(xy 155.257754 -438.837324) (xy 154.317954 -438.837324) (xy 154.305833 -438.836927) (xy 154.282782 -438.829422)
			(xy 154.263178 -438.815162) (xy 154.248939 -438.795543) (xy 154.24146 -438.772483) (xy 154.240992 -438.760362)
			(xy 153.33472 -438.760362) (xy 153.33472 -439.76036) (xy 156.240988 -439.76036) (xy 156.240988 -437.218836)
			(xy 156.241447 -437.20673) (xy 156.248935 -437.183706) (xy 156.263186 -437.164134) (xy 156.282798 -437.149937)
			(xy 156.305843 -437.142514) (xy 156.31795 -437.142128) (xy 157.25775 -437.142128) (xy 157.269836 -437.14265)
			(xy 157.292833 -437.150091) (xy 157.312413 -437.164264) (xy 157.326665 -437.183786) (xy 157.334201 -437.206752)
			(xy 157.334712 -437.218836) (xy 157.334712 -438.760616) (xy 314.141104 -438.760616) (xy 314.141104 -436.219092)
			(xy 314.141509 -436.206982) (xy 314.149012 -436.183954) (xy 314.163276 -436.164381) (xy 314.1829 -436.150186)
			(xy 314.205955 -436.142767) (xy 314.218066 -436.142384) (xy 315.157866 -436.142384) (xy 315.169958 -436.142837)
			(xy 315.192965 -436.15029) (xy 315.206945 -436.160418) (xy 316.1411 -436.160418) (xy 316.1411 -433.618894)
			(xy 316.141606 -433.606783) (xy 316.14909 -433.583746) (xy 316.163325 -433.564148) (xy 316.182917 -433.549905)
			(xy 316.205951 -433.542411) (xy 316.218062 -433.541932) (xy 317.157862 -433.541932) (xy 317.169982 -433.542392)
			(xy 317.193039 -433.549873) (xy 317.212654 -433.564115) (xy 317.226907 -433.583722) (xy 317.234401 -433.606774)
			(xy 317.234824 -433.618894) (xy 317.234824 -435.16042) (xy 318.141096 -435.16042) (xy 318.141096 -432.618896)
			(xy 318.141513 -432.606787) (xy 318.149013 -432.583761) (xy 318.163274 -432.564188) (xy 318.182896 -432.549993)
			(xy 318.205948 -432.542572) (xy 318.218058 -432.542188) (xy 319.157858 -432.542188) (xy 319.16995 -432.542644)
			(xy 319.192958 -432.550095) (xy 319.207287 -432.560476) (xy 320.141092 -432.560476) (xy 320.141092 -430.018952)
			(xy 320.141475 -430.006841) (xy 320.148987 -429.983814) (xy 320.163258 -429.964242) (xy 320.182885 -429.950049)
			(xy 320.205942 -429.942628) (xy 320.218054 -429.942244) (xy 321.157854 -429.942244) (xy 321.169942 -429.942747)
			(xy 321.192941 -429.950191) (xy 321.212522 -429.964368) (xy 321.226774 -429.983895) (xy 321.234307 -430.006866)
			(xy 321.234816 -430.018952) (xy 321.234816 -431.560478) (xy 322.141088 -431.560478) (xy 322.141088 -429.018954)
			(xy 322.141572 -429.006842) (xy 322.149066 -428.983806) (xy 322.163306 -428.964209) (xy 322.182902 -428.949967)
			(xy 322.205938 -428.942472) (xy 322.21805 -428.941992) (xy 323.15785 -428.941992) (xy 323.169963 -428.942468)
			(xy 323.193 -428.949964) (xy 323.207195 -428.96028) (xy 324.141084 -428.96028) (xy 324.141084 -428.233078)
			(xy 324.141338 -428.224321) (xy 324.145316 -428.207264) (xy 324.148958 -428.199296) (xy 324.382384 -427.723046)
			(xy 324.387111 -427.712539) (xy 324.390593 -427.689775) (xy 324.387096 -427.667012) (xy 324.382384 -427.656498)
			(xy 324.148958 -427.180248) (xy 324.145308 -427.172282) (xy 324.141325 -427.155224) (xy 324.141084 -427.146466)
			(xy 324.141084 -426.418756) (xy 324.141526 -426.40668) (xy 324.149 -426.383713) (xy 324.163203 -426.364177)
			(xy 324.182745 -426.349984) (xy 324.205716 -426.342521) (xy 324.217792 -426.342048) (xy 325.157592 -426.342048)
			(xy 325.169662 -426.34257) (xy 325.192621 -426.350025) (xy 325.212155 -426.364208) (xy 325.226351 -426.383732)
			(xy 325.233821 -426.406687) (xy 325.2343 -426.418756) (xy 325.2343 -427.960536) (xy 326.14108 -427.960536)
			(xy 326.14108 -427.233334) (xy 326.141352 -427.224578) (xy 326.145318 -427.207521) (xy 326.148954 -427.199552)
			(xy 326.38238 -426.723302) (xy 326.387069 -426.71278) (xy 326.390565 -426.690025) (xy 326.387084 -426.667268)
			(xy 326.38238 -426.656754) (xy 326.148954 -426.180504) (xy 326.14529 -426.172544) (xy 326.141316 -426.155482)
			(xy 326.14108 -426.146722) (xy 326.14108 -425.419012) (xy 326.141574 -425.406939) (xy 326.149032 -425.383974)
			(xy 326.163221 -425.364438) (xy 326.182753 -425.350243) (xy 326.205715 -425.342778) (xy 326.217788 -425.342304)
			(xy 327.157588 -425.342304) (xy 327.169671 -425.342723) (xy 327.192656 -425.350189) (xy 327.212207 -425.364393)
			(xy 327.226411 -425.383944) (xy 327.233877 -425.406929) (xy 327.234296 -425.419012) (xy 327.234296 -427.960536)
			(xy 327.233866 -427.972614) (xy 327.226393 -427.995584) (xy 327.212187 -428.015122) (xy 327.192641 -428.029315)
			(xy 327.169666 -428.036774) (xy 327.157588 -428.037244) (xy 326.217788 -428.037244) (xy 326.205716 -428.036746)
			(xy 326.182755 -428.029285) (xy 326.163221 -428.015096) (xy 326.149026 -427.995567) (xy 326.141557 -427.972607)
			(xy 326.14108 -427.960536) (xy 325.2343 -427.960536) (xy 325.2343 -428.96028) (xy 325.23387 -428.972362)
			(xy 325.226407 -428.995346) (xy 325.212206 -429.014897) (xy 325.192657 -429.029102) (xy 325.169674 -429.036568)
			(xy 325.157592 -429.036988) (xy 324.217792 -429.036988) (xy 324.205707 -429.036594) (xy 324.18272 -429.029122)
			(xy 324.163169 -429.014912) (xy 324.148965 -428.995354) (xy 324.141502 -428.972365) (xy 324.141084 -428.96028)
			(xy 323.207195 -428.96028) (xy 323.212597 -428.964206) (xy 323.226838 -428.983804) (xy 323.234332 -429.006841)
			(xy 323.234812 -429.018954) (xy 323.234812 -431.560478) (xy 323.23427 -431.572586) (xy 323.226795 -431.59562)
			(xy 323.212569 -431.615218) (xy 323.192985 -431.629462) (xy 323.169958 -431.636959) (xy 323.15785 -431.63744)
			(xy 322.21805 -431.63744) (xy 322.205931 -431.63703) (xy 322.182882 -431.629527) (xy 322.163279 -431.615269)
			(xy 322.14904 -431.595653) (xy 322.141558 -431.572598) (xy 322.141088 -431.560478) (xy 321.234816 -431.560478)
			(xy 321.234816 -432.560476) (xy 321.234363 -432.572582) (xy 321.226872 -432.595606) (xy 321.21262 -432.615178)
			(xy 321.193006 -432.629374) (xy 321.169961 -432.636798) (xy 321.157854 -432.637184) (xy 320.218054 -432.637184)
			(xy 320.205964 -432.636732) (xy 320.182966 -432.629266) (xy 320.163389 -432.615074) (xy 320.149139 -432.59554)
			(xy 320.141604 -432.572564) (xy 320.141092 -432.560476) (xy 319.207287 -432.560476) (xy 319.212542 -432.564283)
			(xy 319.226793 -432.583822) (xy 319.234317 -432.606805) (xy 319.23482 -432.618896) (xy 319.23482 -435.16042)
			(xy 319.234401 -435.172528) (xy 319.226899 -435.195552) (xy 319.212637 -435.215123) (xy 319.193017 -435.229318)
			(xy 319.169967 -435.236742) (xy 319.157858 -435.237128) (xy 318.218058 -435.237128) (xy 318.205963 -435.236728)
			(xy 318.182956 -435.229256) (xy 318.163374 -435.215053) (xy 318.149126 -435.195504) (xy 318.1416 -435.172514)
			(xy 318.141096 -435.16042) (xy 317.234824 -435.16042) (xy 317.234824 -436.160418) (xy 317.234455 -436.172545)
			(xy 317.226953 -436.195611) (xy 317.212689 -436.215229) (xy 317.193061 -436.229478) (xy 317.16999 -436.236963)
			(xy 317.157862 -436.23738) (xy 316.218062 -436.23738) (xy 316.205947 -436.236921) (xy 316.182906 -436.229425)
			(xy 316.163306 -436.21518) (xy 316.149065 -436.195576) (xy 316.141576 -436.172533) (xy 316.1411 -436.160418)
			(xy 315.206945 -436.160418) (xy 315.212549 -436.164478) (xy 315.2268 -436.184018) (xy 315.234325 -436.207001)
			(xy 315.234828 -436.219092) (xy 315.234828 -438.760616) (xy 315.234398 -438.772723) (xy 315.226897 -438.795746)
			(xy 315.212638 -438.815316) (xy 315.193022 -438.829511) (xy 315.169974 -438.836937) (xy 315.157866 -438.837324)
			(xy 314.218066 -438.837324) (xy 314.205971 -438.836921) (xy 314.182963 -438.829451) (xy 314.163381 -438.815249)
			(xy 314.149133 -438.7957) (xy 314.141608 -438.77271) (xy 314.141104 -438.760616) (xy 157.334712 -438.760616)
			(xy 157.334712 -439.76036) (xy 157.334702 -439.760614) (xy 316.1411 -439.760614) (xy 316.1411 -437.21909)
			(xy 316.141603 -437.206979) (xy 316.149088 -437.183942) (xy 316.163324 -437.164343) (xy 316.182917 -437.150101)
			(xy 316.205951 -437.142607) (xy 316.218062 -437.142128) (xy 317.157862 -437.142128) (xy 317.169982 -437.142592)
			(xy 317.193038 -437.150073) (xy 317.212653 -437.164313) (xy 317.226905 -437.183919) (xy 317.2344 -437.20697)
			(xy 317.234824 -437.21909) (xy 317.234824 -438.760616) (xy 318.141096 -438.760616) (xy 318.141096 -436.219092)
			(xy 318.141509 -436.206983) (xy 318.14901 -436.183956) (xy 318.163273 -436.164384) (xy 318.182895 -436.150189)
			(xy 318.205948 -436.142768) (xy 318.218058 -436.142384) (xy 319.157858 -436.142384) (xy 319.16995 -436.142844)
			(xy 319.192956 -436.150294) (xy 319.206932 -436.160418) (xy 320.141092 -436.160418) (xy 320.141092 -433.618894)
			(xy 320.141606 -433.606784) (xy 320.149089 -433.583748) (xy 320.163322 -433.564151) (xy 320.182912 -433.549908)
			(xy 320.205944 -433.542412) (xy 320.218054 -433.541932) (xy 321.157854 -433.541932) (xy 321.169974 -433.542399)
			(xy 321.19303 -433.549878) (xy 321.212646 -433.564117) (xy 321.226898 -433.583723) (xy 321.234393 -433.606775)
			(xy 321.234816 -433.618894) (xy 321.234816 -435.16042) (xy 322.141088 -435.16042) (xy 322.141088 -432.618896)
			(xy 322.141513 -432.606788) (xy 322.149012 -432.583763) (xy 322.163272 -432.564191) (xy 322.182891 -432.549996)
			(xy 322.205941 -432.542573) (xy 322.21805 -432.542188) (xy 323.15785 -432.542188) (xy 323.169942 -432.542651)
			(xy 323.192949 -432.5501) (xy 323.207275 -432.560476) (xy 324.141084 -432.560476) (xy 324.141084 -430.018952)
			(xy 324.141475 -430.006842) (xy 324.148986 -429.983816) (xy 324.163255 -429.964245) (xy 324.18288 -429.950052)
			(xy 324.205935 -429.942629) (xy 324.218046 -429.942244) (xy 325.157846 -429.942244) (xy 325.169938 -429.942668)
			(xy 325.192941 -429.950138) (xy 325.212521 -429.964336) (xy 325.22677 -429.983878) (xy 325.2343 -430.006861)
			(xy 325.234808 -430.018952) (xy 325.234808 -431.560478) (xy 326.14108 -431.560478) (xy 326.14108 -429.018954)
			(xy 326.141473 -429.006833) (xy 326.148978 -428.983781) (xy 326.163239 -428.964176) (xy 326.18286 -428.949938)
			(xy 326.20592 -428.942459) (xy 326.218042 -428.941992) (xy 327.157842 -428.941992) (xy 327.169954 -428.942475)
			(xy 327.192991 -428.949968) (xy 327.207181 -428.96028) (xy 328.141076 -428.96028) (xy 328.141076 -428.233078)
			(xy 328.141331 -428.224321) (xy 328.145308 -428.207264) (xy 328.14895 -428.199296) (xy 328.382376 -427.723046)
			(xy 328.387104 -427.71254) (xy 328.390586 -427.689775) (xy 328.387089 -427.667012) (xy 328.382376 -427.656498)
			(xy 328.14895 -427.180248) (xy 328.1453 -427.172282) (xy 328.141317 -427.155224) (xy 328.141076 -427.146466)
			(xy 328.141076 -426.418756) (xy 328.141526 -426.406681) (xy 328.148999 -426.383715) (xy 328.1632 -426.36418)
			(xy 328.18274 -426.349986) (xy 328.205709 -426.342522) (xy 328.217784 -426.342048) (xy 329.157584 -426.342048)
			(xy 329.169653 -426.342577) (xy 329.192613 -426.35003) (xy 329.212146 -426.364211) (xy 329.226343 -426.383734)
			(xy 329.233813 -426.406687) (xy 329.234292 -426.418756) (xy 329.234292 -427.960536) (xy 331.141324 -427.960536)
			(xy 331.141324 -427.233334) (xy 331.141592 -427.224578) (xy 331.14556 -427.20752) (xy 331.149198 -427.199552)
			(xy 331.382624 -426.723302) (xy 331.387311 -426.71278) (xy 331.390805 -426.690025) (xy 331.387326 -426.667268)
			(xy 331.382624 -426.656754) (xy 331.149198 -426.180504) (xy 331.145537 -426.172543) (xy 331.14156 -426.155482)
			(xy 331.141324 -426.146722) (xy 331.141324 -425.419012) (xy 331.141724 -425.406927) (xy 331.149192 -425.383939)
			(xy 331.1634 -425.364386) (xy 331.182957 -425.350183) (xy 331.205947 -425.34272) (xy 331.218032 -425.342304)
			(xy 332.157832 -425.342304) (xy 332.169909 -425.342737) (xy 332.19288 -425.35021) (xy 332.212417 -425.364414)
			(xy 332.22661 -425.38396) (xy 332.23407 -425.406934) (xy 332.23454 -425.419012) (xy 332.23454 -427.960536)
			(xy 332.234067 -427.972609) (xy 332.226599 -427.995572) (xy 332.212403 -428.015106) (xy 332.192869 -428.0293)
			(xy 332.169905 -428.036768) (xy 332.157832 -428.037244) (xy 331.218032 -428.037244) (xy 331.205963 -428.036709)
			(xy 331.183003 -428.02926) (xy 331.163468 -428.01508) (xy 331.149271 -427.995558) (xy 331.141801 -427.972605)
			(xy 331.141324 -427.960536) (xy 329.234292 -427.960536) (xy 329.234292 -428.96028) (xy 329.23387 -428.972363)
			(xy 329.226406 -428.995348) (xy 329.212203 -429.0149) (xy 329.192652 -429.029104) (xy 329.169667 -429.036569)
			(xy 329.157584 -429.036988) (xy 328.217784 -429.036988) (xy 328.205698 -429.036601) (xy 328.182712 -429.029126)
			(xy 328.16316 -429.014914) (xy 328.148957 -428.995356) (xy 328.141494 -428.972366) (xy 328.141076 -428.96028)
			(xy 327.207181 -428.96028) (xy 327.212588 -428.964209) (xy 327.22683 -428.983805) (xy 327.234324 -429.006842)
			(xy 327.234804 -429.018954) (xy 327.234804 -431.560478) (xy 327.23427 -431.572587) (xy 327.226794 -431.595623)
			(xy 327.212567 -431.615221) (xy 327.19298 -431.629465) (xy 327.169951 -431.63696) (xy 327.157842 -431.63744)
			(xy 326.218042 -431.63744) (xy 326.205919 -431.637004) (xy 326.182858 -431.629521) (xy 326.16324 -431.615274)
			(xy 326.148988 -431.59566) (xy 326.141499 -431.572601) (xy 326.14108 -431.560478) (xy 325.234808 -431.560478)
			(xy 325.234808 -432.560476) (xy 325.234363 -432.572583) (xy 325.226871 -432.595608) (xy 325.212617 -432.615181)
			(xy 325.193001 -432.629376) (xy 325.169954 -432.636799) (xy 325.157846 -432.637184) (xy 324.218046 -432.637184)
			(xy 324.205961 -432.636654) (xy 324.182966 -432.629213) (xy 324.163387 -432.615042) (xy 324.149134 -432.595522)
			(xy 324.141597 -432.572559) (xy 324.141084 -432.560476) (xy 323.207275 -432.560476) (xy 323.212534 -432.564285)
			(xy 323.226784 -432.583823) (xy 323.234309 -432.606806) (xy 323.234812 -432.618896) (xy 323.234812 -435.16042)
			(xy 323.234401 -435.172529) (xy 323.226897 -435.195555) (xy 323.212634 -435.215126) (xy 323.193012 -435.229321)
			(xy 323.16996 -435.236743) (xy 323.15785 -435.237128) (xy 322.21805 -435.237128) (xy 322.20596 -435.23665)
			(xy 322.182955 -435.229203) (xy 322.163372 -435.21502) (xy 322.149121 -435.195487) (xy 322.141593 -435.172508)
			(xy 322.141088 -435.16042) (xy 321.234816 -435.16042) (xy 321.234816 -436.160418) (xy 321.234454 -436.172546)
			(xy 321.226952 -436.195613) (xy 321.212686 -436.215232) (xy 321.193056 -436.229481) (xy 321.169983 -436.236965)
			(xy 321.157854 -436.23738) (xy 320.218054 -436.23738) (xy 320.205939 -436.236928) (xy 320.182897 -436.22943)
			(xy 320.163298 -436.215182) (xy 320.149057 -436.195578) (xy 320.141568 -436.172533) (xy 320.141092 -436.160418)
			(xy 319.206932 -436.160418) (xy 319.212541 -436.164481) (xy 319.226791 -436.184019) (xy 319.234316 -436.207002)
			(xy 319.23482 -436.219092) (xy 319.23482 -438.760616) (xy 319.234398 -438.772724) (xy 319.226896 -438.795748)
			(xy 319.212636 -438.815319) (xy 319.193017 -438.829514) (xy 319.169967 -438.836938) (xy 319.157858 -438.837324)
			(xy 318.218058 -438.837324) (xy 318.205963 -438.836928) (xy 318.182955 -438.829455) (xy 318.163372 -438.815252)
			(xy 318.149124 -438.795701) (xy 318.1416 -438.77271) (xy 318.141096 -438.760616) (xy 317.234824 -438.760616)
			(xy 317.234824 -439.760614) (xy 320.141092 -439.760614) (xy 320.141092 -437.21909) (xy 320.141603 -437.20698)
			(xy 320.149087 -437.183944) (xy 320.163321 -437.164346) (xy 320.182912 -437.150104) (xy 320.205944 -437.142608)
			(xy 320.218054 -437.142128) (xy 321.157854 -437.142128) (xy 321.169973 -437.142599) (xy 321.193029 -437.150077)
			(xy 321.212644 -437.164316) (xy 321.226897 -437.183921) (xy 321.234392 -437.206971) (xy 321.234816 -437.21909)
			(xy 321.234816 -438.760616) (xy 322.141088 -438.760616) (xy 322.141088 -436.219092) (xy 322.141509 -436.206984)
			(xy 322.149009 -436.183958) (xy 322.16327 -436.164386) (xy 322.18289 -436.150192) (xy 322.205941 -436.142769)
			(xy 322.21805 -436.142384) (xy 323.15785 -436.142384) (xy 323.169941 -436.142851) (xy 323.192948 -436.150299)
			(xy 323.206918 -436.160418) (xy 324.141084 -436.160418) (xy 324.141084 -433.618894) (xy 324.141456 -433.606766)
			(xy 324.148955 -433.5837) (xy 324.163218 -433.564081) (xy 324.182846 -433.549831) (xy 324.205918 -433.542348)
			(xy 324.218046 -433.541932) (xy 325.157846 -433.541932) (xy 325.169962 -433.542372) (xy 325.193006 -433.549872)
			(xy 325.212607 -433.564122) (xy 325.226847 -433.58373) (xy 325.234334 -433.606777) (xy 325.234808 -433.618894)
			(xy 325.234808 -435.16042) (xy 326.14108 -435.16042) (xy 326.14108 -432.618896) (xy 326.141512 -432.606789)
			(xy 326.149011 -432.583765) (xy 326.163269 -432.564194) (xy 326.182886 -432.549998) (xy 326.205934 -432.542574)
			(xy 326.218042 -432.542188) (xy 327.157842 -432.542188) (xy 327.169939 -432.542572) (xy 327.192949 -432.550047)
			(xy 327.207325 -432.560476) (xy 328.141076 -432.560476) (xy 328.141076 -430.018952) (xy 328.141475 -430.006843)
			(xy 328.148985 -429.983818) (xy 328.163252 -429.964248) (xy 328.182875 -429.950054) (xy 328.205928 -429.94263)
			(xy 328.218038 -429.942244) (xy 329.157838 -429.942244) (xy 329.16993 -429.942675) (xy 329.192933 -429.950143)
			(xy 329.212512 -429.964338) (xy 329.226761 -429.983879) (xy 329.234292 -430.006861) (xy 329.2348 -430.018952)
			(xy 329.2348 -431.560478) (xy 331.141324 -431.560478) (xy 331.141324 -429.018954) (xy 331.141772 -429.006838)
			(xy 331.14927 -428.983796) (xy 331.163519 -428.964196) (xy 331.183125 -428.949956) (xy 331.20617 -428.942467)
			(xy 331.218286 -428.941992) (xy 332.158086 -428.941992) (xy 332.170195 -428.942523) (xy 332.19323 -428.950001)
			(xy 332.207389 -428.96028) (xy 333.14132 -428.96028) (xy 333.14132 -428.233078) (xy 333.14157 -428.224321)
			(xy 333.14555 -428.207263) (xy 333.149194 -428.199296) (xy 333.38262 -427.723046) (xy 333.387346 -427.712539)
			(xy 333.390826 -427.689775) (xy 333.387331 -427.667013) (xy 333.38262 -427.656498) (xy 333.149194 -427.180248)
			(xy 333.145546 -427.172281) (xy 333.141561 -427.155224) (xy 333.14132 -427.146466) (xy 333.14132 -426.418756)
			(xy 333.141727 -426.406676) (xy 333.149205 -426.383703) (xy 333.163415 -426.364164) (xy 333.182968 -426.349972)
			(xy 333.205948 -426.342516) (xy 333.218028 -426.342048) (xy 334.157828 -426.342048) (xy 334.1699 -426.342539)
			(xy 334.19286 -426.350004) (xy 334.212393 -426.364195) (xy 334.226588 -426.383725) (xy 334.234058 -426.406684)
			(xy 334.234536 -426.418756) (xy 334.234536 -427.960536) (xy 335.141316 -427.960536) (xy 335.141316 -427.233334)
			(xy 335.141585 -427.224578) (xy 335.145552 -427.20752) (xy 335.14919 -427.199552) (xy 335.382616 -426.723302)
			(xy 335.387303 -426.71278) (xy 335.390797 -426.690025) (xy 335.387318 -426.667268) (xy 335.382616 -426.656754)
			(xy 335.14919 -426.180504) (xy 335.145528 -426.172543) (xy 335.141552 -426.155482) (xy 335.141316 -426.146722)
			(xy 335.141316 -425.419012) (xy 335.141723 -425.406928) (xy 335.149191 -425.383941) (xy 335.163397 -425.364389)
			(xy 335.182952 -425.350185) (xy 335.205939 -425.342722) (xy 335.218024 -425.342304) (xy 336.157824 -425.342304)
			(xy 336.169901 -425.342744) (xy 336.192871 -425.350215) (xy 336.212409 -425.364417) (xy 336.226602 -425.383961)
			(xy 336.234061 -425.406935) (xy 336.234532 -425.419012) (xy 336.234532 -427.960536) (xy 336.234067 -427.97261)
			(xy 336.226598 -427.995574) (xy 336.2124 -428.015109) (xy 336.192864 -428.029303) (xy 336.169898 -428.036769)
			(xy 336.157824 -428.037244) (xy 335.218024 -428.037244) (xy 335.205954 -428.036716) (xy 335.182994 -428.029264)
			(xy 335.16346 -428.015083) (xy 335.149263 -427.99556) (xy 335.141793 -427.972605) (xy 335.141316 -427.960536)
			(xy 334.234536 -427.960536) (xy 334.234536 -428.96028) (xy 334.234019 -428.972351) (xy 334.226566 -428.995313)
			(xy 334.212382 -429.014848) (xy 334.192856 -429.029044) (xy 334.169898 -429.036512) (xy 334.157828 -429.036988)
			(xy 333.218028 -429.036988) (xy 333.205945 -429.036563) (xy 333.18296 -429.029101) (xy 333.163407 -429.014899)
			(xy 333.149203 -428.995348) (xy 333.141738 -428.972363) (xy 333.14132 -428.96028) (xy 332.207389 -428.96028)
			(xy 332.212828 -428.964229) (xy 332.227072 -428.983816) (xy 332.234568 -429.006845) (xy 332.235048 -429.018954)
			(xy 332.235048 -431.560478) (xy 332.234621 -431.572601) (xy 332.227133 -431.595662) (xy 332.212884 -431.615278)
			(xy 332.193269 -431.62953) (xy 332.170209 -431.63702) (xy 332.158086 -431.63744) (xy 331.218286 -431.63744)
			(xy 331.20616 -431.637051) (xy 331.183097 -431.629553) (xy 331.163481 -431.615294) (xy 331.149231 -431.59567)
			(xy 331.141743 -431.572604) (xy 331.141324 -431.560478) (xy 329.2348 -431.560478) (xy 329.2348 -432.560476)
			(xy 329.234363 -432.572584) (xy 329.22687 -432.59561) (xy 329.212614 -432.615184) (xy 329.192996 -432.629379)
			(xy 329.169947 -432.6368) (xy 329.157838 -432.637184) (xy 328.218038 -432.637184) (xy 328.205953 -432.636661)
			(xy 328.182957 -432.629217) (xy 328.163379 -432.615044) (xy 328.149126 -432.595524) (xy 328.141589 -432.572559)
			(xy 328.141076 -432.560476) (xy 327.207325 -432.560476) (xy 327.212532 -432.564253) (xy 327.226779 -432.583806)
			(xy 327.234302 -432.606801) (xy 327.234804 -432.618896) (xy 327.234804 -435.16042) (xy 327.234401 -435.17253)
			(xy 327.226896 -435.195557) (xy 327.212631 -435.215129) (xy 327.193007 -435.229323) (xy 327.169953 -435.236744)
			(xy 327.157842 -435.237128) (xy 326.218042 -435.237128) (xy 326.205951 -435.236656) (xy 326.182947 -435.229207)
			(xy 326.163363 -435.215023) (xy 326.149113 -435.195488) (xy 326.141585 -435.172509) (xy 326.14108 -435.16042)
			(xy 325.234808 -435.16042) (xy 325.234808 -436.160418) (xy 325.234305 -436.172529) (xy 325.226818 -436.195565)
			(xy 325.212582 -436.215163) (xy 325.19299 -436.229405) (xy 325.169957 -436.2369) (xy 325.157846 -436.23738)
			(xy 324.218046 -436.23738) (xy 324.205927 -436.236901) (xy 324.182873 -436.229424) (xy 324.163259 -436.215187)
			(xy 324.149005 -436.195584) (xy 324.141509 -436.172536) (xy 324.141084 -436.160418) (xy 323.206918 -436.160418)
			(xy 323.212532 -436.164484) (xy 323.226783 -436.184021) (xy 323.234308 -436.207002) (xy 323.234812 -436.219092)
			(xy 323.234812 -438.760616) (xy 323.234398 -438.772725) (xy 323.226895 -438.79575) (xy 323.212633 -438.815322)
			(xy 323.193012 -438.829517) (xy 323.16996 -438.836939) (xy 323.15785 -438.837324) (xy 322.21805 -438.837324)
			(xy 322.205959 -438.836849) (xy 322.182954 -438.829402) (xy 322.16337 -438.815219) (xy 322.149119 -438.795684)
			(xy 322.141593 -438.772705) (xy 322.141088 -438.760616) (xy 321.234816 -438.760616) (xy 321.234816 -439.760614)
			(xy 324.141084 -439.760614) (xy 324.141084 -437.21909) (xy 324.141452 -437.206962) (xy 324.148953 -437.183895)
			(xy 324.163216 -437.164276) (xy 324.182845 -437.150027) (xy 324.205918 -437.142544) (xy 324.218046 -437.142128)
			(xy 325.157846 -437.142128) (xy 325.169962 -437.142572) (xy 325.193005 -437.150071) (xy 325.212605 -437.164321)
			(xy 325.226845 -437.183927) (xy 325.234333 -437.206974) (xy 325.234808 -437.21909) (xy 325.234808 -438.760616)
			(xy 326.14108 -438.760616) (xy 326.14108 -436.219092) (xy 326.141509 -436.206985) (xy 326.149008 -436.183961)
			(xy 326.163267 -436.164389) (xy 326.182885 -436.150194) (xy 326.205933 -436.14277) (xy 326.218042 -436.142384)
			(xy 327.157842 -436.142384) (xy 327.169938 -436.142772) (xy 327.192948 -436.150246) (xy 327.206971 -436.160418)
			(xy 328.141076 -436.160418) (xy 328.141076 -433.618894) (xy 328.141456 -433.606767) (xy 328.148954 -433.583702)
			(xy 328.163215 -433.564084) (xy 328.182841 -433.549834) (xy 328.205911 -433.542349) (xy 328.218038 -433.541932)
			(xy 329.157838 -433.541932) (xy 329.169954 -433.542379) (xy 329.192997 -433.549876) (xy 329.212598 -433.564125)
			(xy 329.226838 -433.583731) (xy 329.234326 -433.606778) (xy 329.2348 -433.618894) (xy 329.2348 -435.16042)
			(xy 331.141324 -435.16042) (xy 331.141324 -432.618896) (xy 331.14171 -432.60681) (xy 331.149182 -432.583822)
			(xy 331.163394 -432.564268) (xy 331.182954 -432.550066) (xy 331.205946 -432.542604) (xy 331.218032 -432.542188)
			(xy 332.157832 -432.542188) (xy 332.169908 -432.542637) (xy 332.192875 -432.550108) (xy 332.20714 -432.560476)
			(xy 333.14132 -432.560476) (xy 333.14132 -430.018952) (xy 333.141676 -430.006839) (xy 333.149191 -429.983806)
			(xy 333.163467 -429.964232) (xy 333.183103 -429.95004) (xy 333.206167 -429.942624) (xy 333.218282 -429.942244)
			(xy 334.158082 -429.942244) (xy 334.170171 -429.942723) (xy 334.193172 -429.950175) (xy 334.212752 -429.964358)
			(xy 334.227003 -429.98389) (xy 334.234535 -430.006865) (xy 334.235044 -430.018952) (xy 334.235044 -431.560478)
			(xy 335.141316 -431.560478) (xy 335.141316 -429.018954) (xy 335.141772 -429.006839) (xy 335.149269 -428.983798)
			(xy 335.163516 -428.964199) (xy 335.18312 -428.949958) (xy 335.206163 -428.942468) (xy 335.218278 -428.941992)
			(xy 336.158078 -428.941992) (xy 336.170187 -428.94253) (xy 336.193222 -428.950005) (xy 336.207376 -428.96028)
			(xy 337.141312 -428.96028) (xy 337.141312 -428.233078) (xy 337.141563 -428.224321) (xy 337.145543 -428.207263)
			(xy 337.149186 -428.199296) (xy 337.382612 -427.723046) (xy 337.387338 -427.712539) (xy 337.390819 -427.689775)
			(xy 337.387323 -427.667012) (xy 337.382612 -427.656498) (xy 337.149186 -427.180248) (xy 337.145538 -427.172281)
			(xy 337.141553 -427.155224) (xy 337.141312 -427.146466) (xy 337.141312 -426.418756) (xy 337.141727 -426.406677)
			(xy 337.149204 -426.383705) (xy 337.163413 -426.364167) (xy 337.182962 -426.349975) (xy 337.205941 -426.342517)
			(xy 337.21802 -426.342048) (xy 338.15782 -426.342048) (xy 338.169891 -426.342547) (xy 338.192852 -426.350009)
			(xy 338.212384 -426.364199) (xy 338.22658 -426.383727) (xy 338.23405 -426.406685) (xy 338.234528 -426.418756)
			(xy 338.234528 -427.960536) (xy 339.141308 -427.960536) (xy 339.141308 -427.233334) (xy 339.141578 -427.224578)
			(xy 339.145544 -427.207521) (xy 339.149182 -427.199552) (xy 339.382608 -426.723302) (xy 339.387295 -426.71278)
			(xy 339.39079 -426.690025) (xy 339.387311 -426.667268) (xy 339.382608 -426.656754) (xy 339.149182 -426.180504)
			(xy 339.14552 -426.172543) (xy 339.141544 -426.155482) (xy 339.141308 -426.146722) (xy 339.141308 -425.419012)
			(xy 339.141723 -425.406928) (xy 339.149189 -425.383943) (xy 339.163394 -425.364392) (xy 339.182947 -425.350188)
			(xy 339.205932 -425.342723) (xy 339.218016 -425.342304) (xy 340.157816 -425.342304) (xy 340.169893 -425.342751)
			(xy 340.192862 -425.350219) (xy 340.2124 -425.36442) (xy 340.226594 -425.383963) (xy 340.234053 -425.406935)
			(xy 340.234524 -425.419012) (xy 340.234524 -427.960536) (xy 340.234067 -427.972611) (xy 340.226596 -427.995577)
			(xy 340.212397 -428.015112) (xy 340.192859 -428.029306) (xy 340.169891 -428.03677) (xy 340.157816 -428.037244)
			(xy 339.218016 -428.037244) (xy 339.205946 -428.036723) (xy 339.182985 -428.029269) (xy 339.163451 -428.015086)
			(xy 339.149255 -427.995561) (xy 339.141785 -427.972606) (xy 339.141308 -427.960536) (xy 338.234528 -427.960536)
			(xy 338.234528 -428.96028) (xy 338.234019 -428.972352) (xy 338.226565 -428.995315) (xy 338.212379 -429.01485)
			(xy 338.192851 -429.029046) (xy 338.169891 -429.036513) (xy 338.15782 -429.036988) (xy 337.21802 -429.036988)
			(xy 337.205936 -429.03657) (xy 337.182951 -429.029105) (xy 337.163399 -429.014901) (xy 337.149195 -428.995349)
			(xy 337.14173 -428.972364) (xy 337.141312 -428.96028) (xy 336.207376 -428.96028) (xy 336.21282 -428.964232)
			(xy 336.227064 -428.983817) (xy 336.234559 -429.006846) (xy 336.23504 -429.018954) (xy 336.23504 -431.560478)
			(xy 336.234621 -431.572602) (xy 336.227132 -431.595664) (xy 336.212881 -431.615281) (xy 336.193264 -431.629532)
			(xy 336.170202 -431.637021) (xy 336.158078 -431.63744) (xy 335.218278 -431.63744) (xy 335.20616 -431.637007)
			(xy 335.183112 -431.629511) (xy 335.163509 -431.61526) (xy 335.149269 -431.595648) (xy 335.141786 -431.572596)
			(xy 335.141316 -431.560478) (xy 334.235044 -431.560478) (xy 334.235044 -432.560476) (xy 334.234564 -432.572579)
			(xy 334.227076 -432.595598) (xy 334.21283 -432.615168) (xy 334.193224 -432.629365) (xy 334.170186 -432.636794)
			(xy 334.158082 -432.637184) (xy 333.218282 -432.637184) (xy 333.206194 -432.636709) (xy 333.183197 -432.62925)
			(xy 333.163619 -432.615065) (xy 333.149368 -432.595535) (xy 333.141832 -432.572563) (xy 333.14132 -432.560476)
			(xy 332.20714 -432.560476) (xy 332.212412 -432.564308) (xy 332.226605 -432.58385) (xy 332.234068 -432.60682)
			(xy 332.23454 -432.618896) (xy 332.23454 -435.16042) (xy 332.234053 -435.172492) (xy 332.226589 -435.195455)
			(xy 332.212397 -435.214989) (xy 332.192865 -435.229184) (xy 332.169904 -435.236651) (xy 332.157832 -435.237128)
			(xy 331.218032 -435.237128) (xy 331.205953 -435.23666) (xy 331.182975 -435.229204) (xy 331.163426 -435.215011)
			(xy 331.14922 -435.195472) (xy 331.141748 -435.172499) (xy 331.141324 -435.16042) (xy 329.2348 -435.16042)
			(xy 329.2348 -436.160418) (xy 329.234304 -436.17253) (xy 329.226817 -436.195567) (xy 329.21258 -436.215165)
			(xy 329.192985 -436.229408) (xy 329.16995 -436.236901) (xy 329.157838 -436.23738) (xy 328.218038 -436.23738)
			(xy 328.205919 -436.236908) (xy 328.182864 -436.229428) (xy 328.16325 -436.21519) (xy 328.148997 -436.195586)
			(xy 328.141501 -436.172537) (xy 328.141076 -436.160418) (xy 327.206971 -436.160418) (xy 327.212531 -436.164451)
			(xy 327.226778 -436.184004) (xy 327.234301 -436.206997) (xy 327.234804 -436.219092) (xy 327.234804 -438.760616)
			(xy 327.234397 -438.772725) (xy 327.226894 -438.795752) (xy 327.21263 -438.815325) (xy 327.193007 -438.829519)
			(xy 327.169953 -438.83694) (xy 327.157842 -438.837324) (xy 326.218042 -438.837324) (xy 326.205951 -438.836856)
			(xy 326.182946 -438.829407) (xy 326.163362 -438.815222) (xy 326.149111 -438.795686) (xy 326.141585 -438.772705)
			(xy 326.14108 -438.760616) (xy 325.234808 -438.760616) (xy 325.234808 -439.760614) (xy 328.141076 -439.760614)
			(xy 328.141076 -437.21909) (xy 328.141452 -437.206963) (xy 328.148952 -437.183897) (xy 328.163213 -437.164279)
			(xy 328.18284 -437.15003) (xy 328.205911 -437.142545) (xy 328.218038 -437.142128) (xy 329.157838 -437.142128)
			(xy 329.169954 -437.142579) (xy 329.192996 -437.150076) (xy 329.212597 -437.164323) (xy 329.226837 -437.183929)
			(xy 329.234325 -437.206974) (xy 329.2348 -437.21909) (xy 329.2348 -438.760616) (xy 331.141324 -438.760616)
			(xy 331.141324 -436.219092) (xy 331.141706 -436.207006) (xy 331.14918 -436.184017) (xy 331.163393 -436.164464)
			(xy 331.182953 -436.150262) (xy 331.205945 -436.1428) (xy 331.218032 -436.142384) (xy 332.157832 -436.142384)
			(xy 332.169907 -436.142837) (xy 332.192874 -436.150307) (xy 332.206784 -436.160418) (xy 333.14132 -436.160418)
			(xy 333.14132 -433.618894) (xy 333.141802 -433.606806) (xy 333.149258 -433.583809) (xy 333.163441 -433.564231)
			(xy 333.18297 -433.54998) (xy 333.205942 -433.542444) (xy 333.218028 -433.541932) (xy 334.157828 -433.541932)
			(xy 334.169942 -433.542293) (xy 334.192975 -433.549804) (xy 334.212551 -433.564079) (xy 334.226743 -433.583714)
			(xy 334.234157 -433.606779) (xy 334.234536 -433.618894) (xy 334.234536 -435.16042) (xy 335.141316 -435.16042)
			(xy 335.141316 -432.618896) (xy 335.141709 -432.606811) (xy 335.149181 -432.583824) (xy 335.163391 -432.564271)
			(xy 335.182949 -432.550068) (xy 335.205938 -432.542605) (xy 335.218024 -432.542188) (xy 336.157824 -432.542188)
			(xy 336.169899 -432.542644) (xy 336.192867 -432.550113) (xy 336.207126 -432.560476) (xy 337.141312 -432.560476)
			(xy 337.141312 -430.018952) (xy 337.141676 -430.006839) (xy 337.14919 -429.983809) (xy 337.163465 -429.964235)
			(xy 337.183098 -429.950043) (xy 337.20616 -429.942625) (xy 337.218274 -429.942244) (xy 338.158074 -429.942244)
			(xy 338.170163 -429.94273) (xy 338.193163 -429.95018) (xy 338.212744 -429.964361) (xy 338.226995 -429.983891)
			(xy 338.234527 -430.006865) (xy 338.235036 -430.018952) (xy 338.235036 -431.560478) (xy 339.141308 -431.560478)
			(xy 339.141308 -429.018954) (xy 339.141772 -429.00684) (xy 339.149268 -428.9838) (xy 339.163513 -428.964202)
			(xy 339.183115 -428.949961) (xy 339.206156 -428.94247) (xy 339.21827 -428.941992) (xy 340.15807 -428.941992)
			(xy 340.170178 -428.942537) (xy 340.193213 -428.95001) (xy 340.207362 -428.96028) (xy 341.141304 -428.96028)
			(xy 341.141304 -428.233078) (xy 341.141556 -428.224321) (xy 341.145535 -428.207263) (xy 341.149178 -428.199296)
			(xy 341.382604 -427.723046) (xy 341.387331 -427.712539) (xy 341.390812 -427.689775) (xy 341.387316 -427.667012)
			(xy 341.382604 -427.656498) (xy 341.149178 -427.180248) (xy 341.145529 -427.172282) (xy 341.141545 -427.155224)
			(xy 341.141304 -427.146466) (xy 341.141304 -426.418756) (xy 341.141727 -426.406678) (xy 341.149203 -426.383707)
			(xy 341.16341 -426.36417) (xy 341.182957 -426.349977) (xy 341.205934 -426.342518) (xy 341.218012 -426.342048)
			(xy 342.157812 -426.342048) (xy 342.169883 -426.342553) (xy 342.192843 -426.350014) (xy 342.212376 -426.364201)
			(xy 342.226572 -426.383728) (xy 342.234042 -426.406685) (xy 342.23452 -426.418756) (xy 342.23452 -427.960536)
			(xy 343.1413 -427.960536) (xy 343.1413 -427.233334) (xy 343.14157 -427.224578) (xy 343.145537 -427.207521)
			(xy 343.149174 -427.199552) (xy 343.3826 -426.723302) (xy 343.387288 -426.71278) (xy 343.390783 -426.690025)
			(xy 343.387303 -426.667268) (xy 343.3826 -426.656754) (xy 343.149174 -426.180504) (xy 343.145511 -426.172543)
			(xy 343.141536 -426.155482) (xy 343.1413 -426.146722) (xy 343.1413 -425.419012) (xy 343.141723 -425.406929)
			(xy 343.149188 -425.383946) (xy 343.163392 -425.364394) (xy 343.182942 -425.35019) (xy 343.205925 -425.342724)
			(xy 343.218008 -425.342304) (xy 344.157808 -425.342304) (xy 344.169892 -425.342706) (xy 344.192877 -425.350177)
			(xy 344.212429 -425.364386) (xy 344.226632 -425.383941) (xy 344.234097 -425.406928) (xy 344.234516 -425.419012)
			(xy 344.234516 -427.960536) (xy 344.234067 -427.972612) (xy 344.226595 -427.995579) (xy 344.212395 -428.015115)
			(xy 344.192854 -428.029308) (xy 344.169884 -428.036771) (xy 344.157808 -428.037244) (xy 343.218008 -428.037244)
			(xy 343.205937 -428.03673) (xy 343.182977 -428.029274) (xy 343.163443 -428.015089) (xy 343.149247 -427.995563)
			(xy 343.141777 -427.972606) (xy 343.1413 -427.960536) (xy 342.23452 -427.960536) (xy 342.23452 -428.96028)
			(xy 342.23407 -428.97236) (xy 342.22661 -428.99534) (xy 342.212413 -429.01489) (xy 342.192869 -429.029095)
			(xy 342.169892 -429.036565) (xy 342.157812 -429.036988) (xy 341.218012 -429.036988) (xy 341.205928 -429.036577)
			(xy 341.182942 -429.02911) (xy 341.16339 -429.014904) (xy 341.149186 -428.995351) (xy 341.141722 -428.972364)
			(xy 341.141304 -428.96028) (xy 340.207362 -428.96028) (xy 340.212811 -428.964235) (xy 340.227055 -428.983819)
			(xy 340.234551 -429.006846) (xy 340.235032 -429.018954) (xy 340.235032 -431.560478) (xy 340.234621 -431.572603)
			(xy 340.227131 -431.595666) (xy 340.212878 -431.615284) (xy 340.193259 -431.629535) (xy 340.170195 -431.637022)
			(xy 340.15807 -431.63744) (xy 339.21827 -431.63744) (xy 339.206152 -431.637014) (xy 339.183104 -431.629515)
			(xy 339.163501 -431.615262) (xy 339.149261 -431.59565) (xy 339.141778 -431.572597) (xy 339.141308 -431.560478)
			(xy 338.235036 -431.560478) (xy 338.235036 -432.560476) (xy 338.234564 -432.57258) (xy 338.227075 -432.5956)
			(xy 338.212827 -432.615171) (xy 338.193219 -432.629367) (xy 338.170179 -432.636795) (xy 338.158074 -432.637184)
			(xy 337.218274 -432.637184) (xy 337.206185 -432.636715) (xy 337.183188 -432.629254) (xy 337.163611 -432.615067)
			(xy 337.14936 -432.595536) (xy 337.141824 -432.572563) (xy 337.141312 -432.560476) (xy 336.207126 -432.560476)
			(xy 336.212403 -432.564311) (xy 336.226597 -432.583851) (xy 336.234059 -432.606821) (xy 336.234532 -432.618896)
			(xy 336.234532 -435.16042) (xy 336.234053 -435.172493) (xy 336.226588 -435.195457) (xy 336.212394 -435.214991)
			(xy 336.19286 -435.229186) (xy 336.169897 -435.236652) (xy 336.157824 -435.237128) (xy 335.218024 -435.237128)
			(xy 335.205945 -435.236667) (xy 335.182966 -435.229209) (xy 335.163417 -435.215014) (xy 335.149212 -435.195473)
			(xy 335.14174 -435.172499) (xy 335.141316 -435.16042) (xy 334.234536 -435.16042) (xy 334.234536 -436.160418)
			(xy 334.234108 -436.172511) (xy 334.226643 -436.195516) (xy 334.212447 -436.215098) (xy 334.192904 -436.229347)
			(xy 334.16992 -436.236874) (xy 334.157828 -436.23738) (xy 333.218028 -436.23738) (xy 333.205919 -436.236959)
			(xy 333.182889 -436.229465) (xy 333.163314 -436.215206) (xy 333.149119 -436.195583) (xy 333.141701 -436.172529)
			(xy 333.14132 -436.160418) (xy 332.206784 -436.160418) (xy 332.21241 -436.164507) (xy 332.226604 -436.184047)
			(xy 332.234067 -436.207016) (xy 332.23454 -436.219092) (xy 332.23454 -438.760616) (xy 332.23405 -438.772688)
			(xy 332.226587 -438.79565) (xy 332.212396 -438.815184) (xy 332.192865 -438.829379) (xy 332.169904 -438.836847)
			(xy 332.157832 -438.837324) (xy 331.218032 -438.837324) (xy 331.205953 -438.83686) (xy 331.182974 -438.829403)
			(xy 331.163424 -438.81521) (xy 331.149218 -438.795669) (xy 331.141747 -438.772695) (xy 331.141324 -438.760616)
			(xy 329.2348 -438.760616) (xy 329.2348 -439.760614) (xy 333.14132 -439.760614) (xy 333.14132 -437.21909)
			(xy 333.141799 -437.207002) (xy 333.149256 -437.184004) (xy 333.16344 -437.164426) (xy 333.18297 -437.150176)
			(xy 333.205942 -437.14264) (xy 333.218028 -437.142128) (xy 334.157828 -437.142128) (xy 334.169941 -437.142493)
			(xy 334.192974 -437.150003) (xy 334.212549 -437.164277) (xy 334.226742 -437.183911) (xy 334.234157 -437.206975)
			(xy 334.234536 -437.21909) (xy 334.234536 -438.760616) (xy 335.141316 -438.760616) (xy 335.141316 -436.219092)
			(xy 335.141706 -436.207006) (xy 335.149179 -436.184019) (xy 335.16339 -436.164467) (xy 335.182948 -436.150264)
			(xy 335.205938 -436.142801) (xy 335.218024 -436.142384) (xy 336.157824 -436.142384) (xy 336.169899 -436.142844)
			(xy 336.192866 -436.150312) (xy 336.206771 -436.160418) (xy 337.141312 -436.160418) (xy 337.141312 -433.618894)
			(xy 337.141802 -433.606807) (xy 337.149257 -433.583811) (xy 337.163439 -433.564234) (xy 337.182965 -433.549982)
			(xy 337.205935 -433.542445) (xy 337.21802 -433.541932) (xy 338.15782 -433.541932) (xy 338.169933 -433.5423)
			(xy 338.192967 -433.549808) (xy 338.212542 -433.564081) (xy 338.226735 -433.583715) (xy 338.234149 -433.606779)
			(xy 338.234528 -433.618894) (xy 338.234528 -435.16042) (xy 339.141308 -435.16042) (xy 339.141308 -432.618896)
			(xy 339.141709 -432.606811) (xy 339.14918 -432.583826) (xy 339.163388 -432.564274) (xy 339.182944 -432.550071)
			(xy 339.205931 -432.542606) (xy 339.218016 -432.542188) (xy 340.157816 -432.542188) (xy 340.169891 -432.542651)
			(xy 340.192858 -432.550117) (xy 340.207113 -432.560476) (xy 341.141304 -432.560476) (xy 341.141304 -430.018952)
			(xy 341.141676 -430.00684) (xy 341.149189 -429.983811) (xy 341.163462 -429.964238) (xy 341.183093 -429.950045)
			(xy 341.206153 -429.942626) (xy 341.218266 -429.942244) (xy 342.158066 -429.942244) (xy 342.170154 -429.942736)
			(xy 342.193154 -429.950184) (xy 342.212735 -429.964364) (xy 342.226987 -429.983893) (xy 342.234519 -430.006866)
			(xy 342.235028 -430.018952) (xy 342.235028 -431.560478) (xy 343.1413 -431.560478) (xy 343.1413 -429.018954)
			(xy 343.141772 -429.006841) (xy 343.149267 -428.983803) (xy 343.163511 -428.964205) (xy 343.18311 -428.949964)
			(xy 343.206149 -428.942471) (xy 343.218262 -428.941992) (xy 344.158062 -428.941992) (xy 344.17017 -428.942543)
			(xy 344.193204 -428.950015) (xy 344.207349 -428.96028) (xy 345.141296 -428.96028) (xy 345.141296 -428.233078)
			(xy 345.141549 -428.224321) (xy 345.145527 -428.207264) (xy 345.14917 -428.199296) (xy 345.382596 -427.723046)
			(xy 345.387323 -427.712539) (xy 345.390805 -427.689775) (xy 345.387308 -427.667012) (xy 345.382596 -427.656498)
			(xy 345.14917 -427.180248) (xy 345.145521 -427.172282) (xy 345.141537 -427.155224) (xy 345.141296 -427.146466)
			(xy 345.141296 -426.418756) (xy 345.141727 -426.406679) (xy 345.149202 -426.383709) (xy 345.163407 -426.364173)
			(xy 345.182952 -426.34998) (xy 345.205926 -426.342519) (xy 345.218004 -426.342048) (xy 346.157804 -426.342048)
			(xy 346.169874 -426.34256) (xy 346.192834 -426.350018) (xy 346.212367 -426.364204) (xy 346.226563 -426.38373)
			(xy 346.234033 -426.406686) (xy 346.234512 -426.418756) (xy 346.234512 -428.96028) (xy 346.23407 -428.972361)
			(xy 346.226609 -428.995343) (xy 346.21241 -429.014893) (xy 346.192864 -429.029098) (xy 346.169885 -429.036566)
			(xy 346.157804 -429.036988) (xy 345.218004 -429.036988) (xy 345.205919 -429.036584) (xy 345.182933 -429.029115)
			(xy 345.163381 -429.014907) (xy 345.149178 -428.995352) (xy 345.141714 -428.972365) (xy 345.141296 -428.96028)
			(xy 344.207349 -428.96028) (xy 344.212803 -428.964238) (xy 344.227047 -428.98382) (xy 344.234543 -429.006847)
			(xy 344.235024 -429.018954) (xy 344.235024 -431.560478) (xy 344.234621 -431.572603) (xy 344.22713 -431.595668)
			(xy 344.212875 -431.615287) (xy 344.193254 -431.629537) (xy 344.170187 -431.637023) (xy 344.158062 -431.63744)
			(xy 343.218262 -431.63744) (xy 343.206143 -431.63702) (xy 343.183095 -431.62952) (xy 343.163492 -431.615265)
			(xy 343.149253 -431.595651) (xy 343.14177 -431.572597) (xy 343.1413 -431.560478) (xy 342.235028 -431.560478)
			(xy 342.235028 -432.560476) (xy 342.234563 -432.572581) (xy 342.227074 -432.595602) (xy 342.212824 -432.615174)
			(xy 342.193214 -432.62937) (xy 342.170172 -432.636796) (xy 342.158066 -432.637184) (xy 341.218266 -432.637184)
			(xy 341.206177 -432.636722) (xy 341.183179 -432.629259) (xy 341.163602 -432.61507) (xy 341.149352 -432.595538)
			(xy 341.141816 -432.572563) (xy 341.141304 -432.560476) (xy 340.207113 -432.560476) (xy 340.212394 -432.564314)
			(xy 340.226588 -432.583853) (xy 340.234051 -432.606821) (xy 340.234524 -432.618896) (xy 340.234524 -435.16042)
			(xy 340.234053 -435.172494) (xy 340.226587 -435.195459) (xy 340.212391 -435.214994) (xy 340.192855 -435.229189)
			(xy 340.16989 -435.236654) (xy 340.157816 -435.237128) (xy 339.218016 -435.237128) (xy 339.205944 -435.236622)
			(xy 339.182981 -435.229167) (xy 339.163445 -435.21498) (xy 339.14925 -435.195451) (xy 339.141783 -435.172492)
			(xy 339.141308 -435.16042) (xy 338.234528 -435.16042) (xy 338.234528 -436.160418) (xy 338.234108 -436.172512)
			(xy 338.226642 -436.195518) (xy 338.212445 -436.215101) (xy 338.192899 -436.22935) (xy 338.169912 -436.236876)
			(xy 338.15782 -436.23738) (xy 337.21802 -436.23738) (xy 337.20591 -436.236966) (xy 337.18288 -436.22947)
			(xy 337.163305 -436.215208) (xy 337.149111 -436.195585) (xy 337.141693 -436.172529) (xy 337.141312 -436.160418)
			(xy 336.206771 -436.160418) (xy 336.212401 -436.16451) (xy 336.226595 -436.184049) (xy 336.234059 -436.207017)
			(xy 336.234532 -436.219092) (xy 336.234532 -438.760616) (xy 336.23405 -438.772689) (xy 336.226586 -438.795653)
			(xy 336.212393 -438.815187) (xy 336.19286 -438.829382) (xy 336.169897 -438.836848) (xy 336.157824 -438.837324)
			(xy 335.218024 -438.837324) (xy 335.205944 -438.836867) (xy 335.182965 -438.829408) (xy 335.163416 -438.815213)
			(xy 335.14921 -438.795671) (xy 335.141739 -438.772696) (xy 335.141316 -438.760616) (xy 334.234536 -438.760616)
			(xy 334.234536 -439.760614) (xy 337.141312 -439.760614) (xy 337.141312 -437.21909) (xy 337.141799 -437.207003)
			(xy 337.149255 -437.184007) (xy 337.163437 -437.164429) (xy 337.182965 -437.150178) (xy 337.205934 -437.142641)
			(xy 337.21802 -437.142128) (xy 338.15782 -437.142128) (xy 338.169933 -437.1425) (xy 338.192965 -437.150008)
			(xy 338.212541 -437.16428) (xy 338.226734 -437.183913) (xy 338.234149 -437.206976) (xy 338.234528 -437.21909)
			(xy 338.234528 -438.760616) (xy 339.141308 -438.760616) (xy 339.141308 -436.219092) (xy 339.141706 -436.207007)
			(xy 339.149178 -436.184021) (xy 339.163387 -436.16447) (xy 339.182943 -436.150267) (xy 339.205931 -436.142802)
			(xy 339.218016 -436.142384) (xy 340.157816 -436.142384) (xy 340.169891 -436.142851) (xy 340.192857 -436.150317)
			(xy 340.206758 -436.160418) (xy 341.141304 -436.160418) (xy 341.141304 -433.618894) (xy 341.141802 -433.606808)
			(xy 341.149256 -433.583813) (xy 341.163436 -433.564236) (xy 341.18296 -433.549985) (xy 341.205928 -433.542447)
			(xy 341.218012 -433.541932) (xy 342.157812 -433.541932) (xy 342.169925 -433.542306) (xy 342.192958 -433.549813)
			(xy 342.212534 -433.564084) (xy 342.226727 -433.583717) (xy 342.234141 -433.60678) (xy 342.23452 -433.618894)
			(xy 342.23452 -435.16042) (xy 343.1413 -435.16042) (xy 343.1413 -432.618896) (xy 343.141709 -432.606812)
			(xy 343.149179 -432.583828) (xy 343.163386 -432.564277) (xy 343.182939 -432.550073) (xy 343.205924 -432.542607)
			(xy 343.218008 -432.542188) (xy 344.157808 -432.542188) (xy 344.169883 -432.542657) (xy 344.192849 -432.550122)
			(xy 344.2071 -432.560476) (xy 345.141296 -432.560476) (xy 345.141296 -430.018952) (xy 345.141676 -430.006841)
			(xy 345.149188 -429.983813) (xy 345.163459 -429.964241) (xy 345.183088 -429.950048) (xy 345.206145 -429.942628)
			(xy 345.218258 -429.942244) (xy 346.158058 -429.942244) (xy 346.170146 -429.942743) (xy 346.193146 -429.950189)
			(xy 346.212727 -429.964367) (xy 346.226979 -429.983894) (xy 346.234511 -430.006866) (xy 346.23502 -430.018952)
			(xy 346.23502 -431.360072) (xy 356.154736 -431.360072) (xy 356.155234 -431.275192) (xy 356.163191 -431.105619)
			(xy 356.179087 -430.936605) (xy 356.202888 -430.768522) (xy 356.234542 -430.601739) (xy 356.273978 -430.436623)
			(xy 356.32111 -430.273538) (xy 356.375834 -430.11284) (xy 356.438031 -429.954885) (xy 356.507563 -429.800018)
			(xy 356.584278 -429.648581) (xy 356.668006 -429.500905) (xy 356.758564 -429.357317) (xy 356.855753 -429.218131)
			(xy 356.95936 -429.083654) (xy 357.069155 -428.954181) (xy 357.184899 -428.829996) (xy 357.306336 -428.711373)
			(xy 357.4332 -428.598572) (xy 357.565211 -428.491842) (xy 357.702081 -428.391417) (xy 357.843506 -428.297518)
			(xy 357.989178 -428.21035) (xy 358.138776 -428.130107) (xy 358.29197 -428.056963) (xy 358.448424 -427.991081)
			(xy 358.607794 -427.932604) (xy 358.76973 -427.881662) (xy 358.933876 -427.838366) (xy 359.099871 -427.802811)
			(xy 359.26735 -427.775076) (xy 359.435945 -427.755222) (xy 359.605285 -427.743292) (xy 359.774998 -427.739313)
			(xy 359.944711 -427.743292) (xy 360.114051 -427.755222) (xy 360.282646 -427.775076) (xy 360.450125 -427.802811)
			(xy 360.61612 -427.838366) (xy 360.780266 -427.881662) (xy 360.942202 -427.932604) (xy 361.018326 -427.960536)
			(xy 381.2413 -427.960536) (xy 381.2413 -427.233334) (xy 381.24157 -427.224578) (xy 381.245537 -427.207521)
			(xy 381.249174 -427.199552) (xy 381.4826 -426.723302) (xy 381.487288 -426.71278) (xy 381.490783 -426.690025)
			(xy 381.487303 -426.667268) (xy 381.4826 -426.656754) (xy 381.249174 -426.180504) (xy 381.245511 -426.172543)
			(xy 381.241536 -426.155482) (xy 381.2413 -426.146722) (xy 381.2413 -425.419012) (xy 381.241723 -425.406929)
			(xy 381.249188 -425.383946) (xy 381.263392 -425.364394) (xy 381.282942 -425.35019) (xy 381.305925 -425.342724)
			(xy 381.318008 -425.342304) (xy 382.257808 -425.342304) (xy 382.269892 -425.342706) (xy 382.292877 -425.350177)
			(xy 382.312429 -425.364386) (xy 382.326632 -425.383941) (xy 382.334097 -425.406928) (xy 382.334516 -425.419012)
			(xy 382.334516 -427.960536) (xy 382.334067 -427.972612) (xy 382.326595 -427.995579) (xy 382.312395 -428.015115)
			(xy 382.292854 -428.029308) (xy 382.269884 -428.036771) (xy 382.257808 -428.037244) (xy 381.318008 -428.037244)
			(xy 381.305937 -428.03673) (xy 381.282977 -428.029274) (xy 381.263443 -428.015089) (xy 381.249247 -427.995563)
			(xy 381.241777 -427.972606) (xy 381.2413 -427.960536) (xy 361.018326 -427.960536) (xy 361.101572 -427.991081)
			(xy 361.258026 -428.056963) (xy 361.41122 -428.130107) (xy 361.560818 -428.21035) (xy 361.70649 -428.297518)
			(xy 361.847915 -428.391417) (xy 361.984785 -428.491842) (xy 362.116796 -428.598572) (xy 362.24366 -428.711373)
			(xy 362.365097 -428.829996) (xy 362.480841 -428.954181) (xy 362.590636 -429.083654) (xy 362.694243 -429.218131)
			(xy 362.791432 -429.357317) (xy 362.88199 -429.500905) (xy 362.965718 -429.648581) (xy 363.042433 -429.800018)
			(xy 363.111965 -429.954885) (xy 363.174162 -430.11284) (xy 363.228886 -430.273538) (xy 363.276018 -430.436623)
			(xy 363.315454 -430.601739) (xy 363.347108 -430.768522) (xy 363.370909 -430.936605) (xy 363.386805 -431.105619)
			(xy 363.394762 -431.275192) (xy 363.39526 -431.360072) (xy 363.394788 -431.445675) (xy 363.389359 -431.560478)
			(xy 381.2413 -431.560478) (xy 381.2413 -429.018954) (xy 381.241772 -429.006841) (xy 381.249267 -428.983803)
			(xy 381.263511 -428.964205) (xy 381.28311 -428.949964) (xy 381.306149 -428.942471) (xy 381.318262 -428.941992)
			(xy 382.258062 -428.941992) (xy 382.27017 -428.942543) (xy 382.293204 -428.950015) (xy 382.307349 -428.96028)
			(xy 383.241296 -428.96028) (xy 383.241296 -428.233078) (xy 383.241549 -428.224321) (xy 383.245527 -428.207264)
			(xy 383.24917 -428.199296) (xy 383.482596 -427.723046) (xy 383.487323 -427.712539) (xy 383.490805 -427.689775)
			(xy 383.487308 -427.667012) (xy 383.482596 -427.656498) (xy 383.24917 -427.180248) (xy 383.245521 -427.172282)
			(xy 383.241537 -427.155224) (xy 383.241296 -427.146466) (xy 383.241296 -426.418756) (xy 383.241727 -426.406679)
			(xy 383.249202 -426.383709) (xy 383.263407 -426.364173) (xy 383.282952 -426.34998) (xy 383.305926 -426.342519)
			(xy 383.318004 -426.342048) (xy 384.257804 -426.342048) (xy 384.269874 -426.34256) (xy 384.292834 -426.350018)
			(xy 384.312367 -426.364204) (xy 384.326563 -426.38373) (xy 384.334033 -426.406686) (xy 384.334512 -426.418756)
			(xy 384.334512 -427.960536) (xy 385.241292 -427.960536) (xy 385.241292 -427.233334) (xy 385.241563 -427.224578)
			(xy 385.245529 -427.207521) (xy 385.249166 -427.199552) (xy 385.482592 -426.723302) (xy 385.48728 -426.71278)
			(xy 385.490776 -426.690025) (xy 385.487295 -426.667268) (xy 385.482592 -426.656754) (xy 385.249166 -426.180504)
			(xy 385.245503 -426.172544) (xy 385.241528 -426.155482) (xy 385.241292 -426.146722) (xy 385.241292 -425.419012)
			(xy 385.241723 -425.40693) (xy 385.249187 -425.383948) (xy 385.263389 -425.364397) (xy 385.282937 -425.350193)
			(xy 385.305918 -425.342725) (xy 385.318 -425.342304) (xy 386.2578 -425.342304) (xy 386.269884 -425.342713)
			(xy 386.292869 -425.350182) (xy 386.31242 -425.364388) (xy 386.326624 -425.383942) (xy 386.334089 -425.406928)
			(xy 386.334508 -425.419012) (xy 386.334508 -427.960536) (xy 386.334067 -427.972612) (xy 386.326594 -427.995581)
			(xy 386.312392 -428.015117) (xy 386.292849 -428.029311) (xy 386.269877 -428.036772) (xy 386.2578 -428.037244)
			(xy 385.318 -428.037244) (xy 385.305929 -428.036736) (xy 385.282968 -428.029278) (xy 385.263434 -428.015092)
			(xy 385.249238 -427.995564) (xy 385.241769 -427.972607) (xy 385.241292 -427.960536) (xy 384.334512 -427.960536)
			(xy 384.334512 -428.96028) (xy 384.33407 -428.972361) (xy 384.326609 -428.995343) (xy 384.31241 -429.014893)
			(xy 384.292864 -429.029098) (xy 384.269885 -429.036566) (xy 384.257804 -429.036988) (xy 383.318004 -429.036988)
			(xy 383.305919 -429.036584) (xy 383.282933 -429.029115) (xy 383.263381 -429.014907) (xy 383.249178 -428.995352)
			(xy 383.241714 -428.972365) (xy 383.241296 -428.96028) (xy 382.307349 -428.96028) (xy 382.312803 -428.964238)
			(xy 382.327047 -428.98382) (xy 382.334543 -429.006847) (xy 382.335024 -429.018954) (xy 382.335024 -431.560478)
			(xy 382.334621 -431.572603) (xy 382.32713 -431.595668) (xy 382.312875 -431.615287) (xy 382.293254 -431.629537)
			(xy 382.270187 -431.637023) (xy 382.258062 -431.63744) (xy 381.318262 -431.63744) (xy 381.306143 -431.63702)
			(xy 381.283095 -431.62952) (xy 381.263492 -431.615265) (xy 381.249253 -431.595651) (xy 381.24177 -431.572597)
			(xy 381.2413 -431.560478) (xy 363.389359 -431.560478) (xy 363.386701 -431.616689) (xy 363.370537 -431.787129)
			(xy 363.346334 -431.956615) (xy 363.314145 -432.124767) (xy 363.274043 -432.291209) (xy 363.226117 -432.455569)
			(xy 363.170474 -432.61748) (xy 363.107239 -432.776579) (xy 363.036553 -432.932511) (xy 362.958574 -433.084927)
			(xy 362.873477 -433.233486) (xy 362.781452 -433.377855) (xy 362.682704 -433.517713) (xy 362.577455 -433.652746)
			(xy 362.46594 -433.782652) (xy 362.348408 -433.907141) (xy 362.225123 -434.025934) (xy 362.096359 -434.138766)
			(xy 361.962404 -434.245385) (xy 361.82356 -434.345551) (xy 361.680135 -434.439042) (xy 361.53245 -434.525647)
			(xy 361.380836 -434.605174) (xy 361.225632 -434.677444) (xy 361.146598 -434.710332) (xy 361.138713 -434.713995)
			(xy 361.125816 -434.725637) (xy 361.117551 -434.740919) (xy 361.115864 -434.749448) (xy 361.100116 -434.849016)
			(xy 361.109514 -434.873654) (xy 361.119928 -434.88229) (xy 361.169374 -434.924299) (xy 361.263563 -435.013553)
			(xy 361.352051 -435.108462) (xy 361.394803 -435.16042) (xy 381.2413 -435.16042) (xy 381.2413 -432.618896)
			(xy 381.241709 -432.606812) (xy 381.249179 -432.583828) (xy 381.263386 -432.564277) (xy 381.282939 -432.550073)
			(xy 381.305924 -432.542607) (xy 381.318008 -432.542188) (xy 382.257808 -432.542188) (xy 382.269883 -432.542657)
			(xy 382.292849 -432.550122) (xy 382.3071 -432.560476) (xy 383.241296 -432.560476) (xy 383.241296 -430.018952)
			(xy 383.241676 -430.006841) (xy 383.249188 -429.983813) (xy 383.263459 -429.964241) (xy 383.283088 -429.950048)
			(xy 383.306145 -429.942628) (xy 383.318258 -429.942244) (xy 384.258058 -429.942244) (xy 384.270146 -429.942743)
			(xy 384.293146 -429.950189) (xy 384.312727 -429.964367) (xy 384.326979 -429.983894) (xy 384.334511 -430.006866)
			(xy 384.33502 -430.018952) (xy 384.33502 -431.560478) (xy 385.241292 -431.560478) (xy 385.241292 -429.018954)
			(xy 385.241772 -429.006842) (xy 385.249266 -428.983805) (xy 385.263508 -428.964208) (xy 385.283105 -428.949966)
			(xy 385.306142 -428.942472) (xy 385.318254 -428.941992) (xy 386.258054 -428.941992) (xy 386.270162 -428.94255)
			(xy 386.293196 -428.950019) (xy 386.307337 -428.96028) (xy 387.241288 -428.96028) (xy 387.241288 -428.233078)
			(xy 387.241541 -428.224321) (xy 387.24552 -428.207264) (xy 387.249162 -428.199296) (xy 387.482588 -427.723046)
			(xy 387.487315 -427.712539) (xy 387.490797 -427.689775) (xy 387.4873 -427.667012) (xy 387.482588 -427.656498)
			(xy 387.249162 -427.180248) (xy 387.245512 -427.172282) (xy 387.241529 -427.155224) (xy 387.241288 -427.146466)
			(xy 387.241288 -426.418756) (xy 387.241727 -426.40668) (xy 387.249201 -426.383712) (xy 387.263404 -426.364176)
			(xy 387.282947 -426.349982) (xy 387.305919 -426.34252) (xy 387.317996 -426.342048) (xy 388.257796 -426.342048)
			(xy 388.269866 -426.342567) (xy 388.292826 -426.350023) (xy 388.312359 -426.364207) (xy 388.326555 -426.383731)
			(xy 388.334025 -426.406686) (xy 388.334504 -426.418756) (xy 388.334504 -427.960536) (xy 389.241284 -427.960536)
			(xy 389.241284 -427.233334) (xy 389.241556 -427.224578) (xy 389.245522 -427.207521) (xy 389.249158 -427.199552)
			(xy 389.482584 -426.723302) (xy 389.487273 -426.71278) (xy 389.490769 -426.690025) (xy 389.487288 -426.667268)
			(xy 389.482584 -426.656754) (xy 389.249158 -426.180504) (xy 389.245494 -426.172544) (xy 389.24152 -426.155482)
			(xy 389.241284 -426.146722) (xy 389.241284 -425.419012) (xy 389.241723 -425.406931) (xy 389.249186 -425.38395)
			(xy 389.263386 -425.3644) (xy 389.282932 -425.350195) (xy 389.305911 -425.342726) (xy 389.317992 -425.342304)
			(xy 390.257792 -425.342304) (xy 390.269876 -425.342719) (xy 390.29286 -425.350186) (xy 390.312412 -425.364391)
			(xy 390.326616 -425.383943) (xy 390.334081 -425.406928) (xy 390.3345 -425.419012) (xy 390.3345 -427.960536)
			(xy 390.334067 -427.972613) (xy 390.326593 -427.995583) (xy 390.312389 -428.01512) (xy 390.292844 -428.029313)
			(xy 390.26987 -428.036773) (xy 390.257792 -428.037244) (xy 389.317992 -428.037244) (xy 389.305921 -428.036743)
			(xy 389.282959 -428.029283) (xy 389.263426 -428.015094) (xy 389.24923 -427.995566) (xy 389.241761 -427.972607)
			(xy 389.241284 -427.960536) (xy 388.334504 -427.960536) (xy 388.334504 -428.96028) (xy 388.33407 -428.972362)
			(xy 388.326608 -428.995345) (xy 388.312407 -429.014896) (xy 388.292859 -429.0291) (xy 388.269878 -429.036568)
			(xy 388.257796 -429.036988) (xy 387.317996 -429.036988) (xy 387.305911 -429.036591) (xy 387.282925 -429.02912)
			(xy 387.263373 -429.01491) (xy 387.249169 -428.995354) (xy 387.241706 -428.972365) (xy 387.241288 -428.96028)
			(xy 386.307337 -428.96028) (xy 386.312794 -428.96424) (xy 386.327039 -428.983822) (xy 386.334535 -429.006847)
			(xy 386.335016 -429.018954) (xy 386.335016 -431.560478) (xy 386.334621 -431.572604) (xy 386.327129 -431.59567)
			(xy 386.312872 -431.61529) (xy 386.293249 -431.62954) (xy 386.27018 -431.637024) (xy 386.258054 -431.63744)
			(xy 385.318254 -431.63744) (xy 385.306135 -431.637027) (xy 385.283086 -431.629525) (xy 385.263484 -431.615268)
			(xy 385.249244 -431.595653) (xy 385.241762 -431.572598) (xy 385.241292 -431.560478) (xy 384.33502 -431.560478)
			(xy 384.33502 -432.560476) (xy 384.334563 -432.572582) (xy 384.327073 -432.595605) (xy 384.312821 -432.615176)
			(xy 384.293209 -432.629373) (xy 384.270165 -432.636797) (xy 384.258058 -432.637184) (xy 383.318258 -432.637184)
			(xy 383.306169 -432.636729) (xy 383.283171 -432.629264) (xy 383.263593 -432.615073) (xy 383.249343 -432.595539)
			(xy 383.241808 -432.572564) (xy 383.241296 -432.560476) (xy 382.3071 -432.560476) (xy 382.312386 -432.564317)
			(xy 382.32658 -432.583854) (xy 382.334043 -432.606821) (xy 382.334516 -432.618896) (xy 382.334516 -435.16042)
			(xy 382.334053 -435.172495) (xy 382.326586 -435.195461) (xy 382.312389 -435.214997) (xy 382.29285 -435.229191)
			(xy 382.269883 -435.236655) (xy 382.257808 -435.237128) (xy 381.318008 -435.237128) (xy 381.305936 -435.236629)
			(xy 381.282972 -435.229171) (xy 381.263437 -435.214983) (xy 381.249241 -435.195453) (xy 381.241775 -435.172492)
			(xy 381.2413 -435.16042) (xy 361.394803 -435.16042) (xy 361.434498 -435.208663) (xy 361.510589 -435.313772)
			(xy 361.580032 -435.423387) (xy 361.642562 -435.537087) (xy 361.697938 -435.654438) (xy 361.74595 -435.77499)
			(xy 361.786412 -435.89828) (xy 361.81917 -436.023838) (xy 361.844098 -436.151181) (xy 361.861101 -436.279823)
			(xy 361.870114 -436.40927) (xy 361.871103 -436.539027) (xy 361.864062 -436.668596) (xy 361.849021 -436.797482)
			(xy 361.826035 -436.92519) (xy 361.795194 -437.051232) (xy 361.756614 -437.175125) (xy 361.710445 -437.296394)
			(xy 361.656862 -437.414574) (xy 361.596072 -437.529214) (xy 361.528306 -437.639874) (xy 361.453825 -437.74613)
			(xy 361.372914 -437.847575) (xy 361.285882 -437.943821) (xy 361.193064 -438.034499) (xy 361.094814 -438.119261)
			(xy 360.991508 -438.197784) (xy 360.883543 -438.269766) (xy 360.771333 -438.334931) (xy 360.655306 -438.39303)
			(xy 360.535907 -438.443841) (xy 360.413594 -438.487169) (xy 360.288835 -438.522847) (xy 360.162108 -438.550739)
			(xy 360.033898 -438.570739) (xy 359.904696 -438.58277) (xy 359.774998 -438.586785) (xy 359.6453 -438.58277)
			(xy 359.516098 -438.570739) (xy 359.387888 -438.550739) (xy 359.261161 -438.522847) (xy 359.136402 -438.487169)
			(xy 359.014089 -438.443841) (xy 358.89469 -438.39303) (xy 358.778663 -438.334931) (xy 358.666453 -438.269766)
			(xy 358.558488 -438.197784) (xy 358.455182 -438.119261) (xy 358.356932 -438.034499) (xy 358.264114 -437.943821)
			(xy 358.177082 -437.847575) (xy 358.096171 -437.74613) (xy 358.02169 -437.639874) (xy 357.953924 -437.529214)
			(xy 357.893134 -437.414574) (xy 357.839551 -437.296394) (xy 357.793382 -437.175125) (xy 357.754802 -437.051232)
			(xy 357.723961 -436.92519) (xy 357.700975 -436.797482) (xy 357.685934 -436.668596) (xy 357.678893 -436.539027)
			(xy 357.679882 -436.40927) (xy 357.688895 -436.279823) (xy 357.705898 -436.151181) (xy 357.730826 -436.023838)
			(xy 357.763584 -435.89828) (xy 357.804046 -435.77499) (xy 357.852058 -435.654438) (xy 357.907434 -435.537087)
			(xy 357.969964 -435.423387) (xy 358.039407 -435.313772) (xy 358.115498 -435.208663) (xy 358.197945 -435.108462)
			(xy 358.286433 -435.013553) (xy 358.380622 -434.924299) (xy 358.430068 -434.88229) (xy 358.440228 -434.873908)
			(xy 358.449626 -434.849016) (xy 358.4321 -434.73624) (xy 358.415844 -434.715412) (xy 358.403398 -434.710332)
			(xy 358.325295 -434.677853) (xy 358.1719 -434.606515) (xy 358.022004 -434.52809) (xy 357.875935 -434.44275)
			(xy 357.734012 -434.350681) (xy 357.596544 -434.252083) (xy 357.463831 -434.147172) (xy 357.336162 -434.036176)
			(xy 357.213818 -433.919339) (xy 357.097064 -433.796915) (xy 356.986156 -433.669172) (xy 356.881335 -433.536387)
			(xy 356.782831 -433.398852) (xy 356.690858 -433.256866) (xy 356.605617 -433.110739) (xy 356.527295 -432.96079)
			(xy 356.456061 -432.807346) (xy 356.392073 -432.650743) (xy 356.335468 -432.491322) (xy 356.286372 -432.329431)
			(xy 356.244891 -432.165424) (xy 356.211115 -431.999658) (xy 356.185119 -431.832496) (xy 356.166958 -431.664301)
			(xy 356.156674 -431.495443) (xy 356.15499 -431.410872) (xy 356.155244 -431.410872) (xy 356.154736 -431.360072)
			(xy 346.23502 -431.360072) (xy 346.23502 -432.560476) (xy 346.234563 -432.572582) (xy 346.227073 -432.595605)
			(xy 346.212821 -432.615176) (xy 346.193209 -432.629373) (xy 346.170165 -432.636797) (xy 346.158058 -432.637184)
			(xy 345.218258 -432.637184) (xy 345.206169 -432.636729) (xy 345.183171 -432.629264) (xy 345.163593 -432.615073)
			(xy 345.149343 -432.595539) (xy 345.141808 -432.572564) (xy 345.141296 -432.560476) (xy 344.2071 -432.560476)
			(xy 344.212386 -432.564317) (xy 344.22658 -432.583854) (xy 344.234043 -432.606821) (xy 344.234516 -432.618896)
			(xy 344.234516 -435.16042) (xy 344.234053 -435.172495) (xy 344.226586 -435.195461) (xy 344.212389 -435.214997)
			(xy 344.19285 -435.229191) (xy 344.169883 -435.236655) (xy 344.157808 -435.237128) (xy 343.218008 -435.237128)
			(xy 343.205936 -435.236629) (xy 343.182972 -435.229171) (xy 343.163437 -435.214983) (xy 343.149241 -435.195453)
			(xy 343.141775 -435.172492) (xy 343.1413 -435.16042) (xy 342.23452 -435.16042) (xy 342.23452 -436.160418)
			(xy 342.234107 -436.172513) (xy 342.226641 -436.195521) (xy 342.212442 -436.215104) (xy 342.192894 -436.229352)
			(xy 342.169905 -436.236877) (xy 342.157812 -436.23738) (xy 341.218012 -436.23738) (xy 341.205902 -436.236973)
			(xy 341.182872 -436.229474) (xy 341.163297 -436.215211) (xy 341.149102 -436.195586) (xy 341.141685 -436.17253)
			(xy 341.141304 -436.160418) (xy 340.206758 -436.160418) (xy 340.212393 -436.164513) (xy 340.226587 -436.18405)
			(xy 340.234051 -436.207017) (xy 340.234524 -436.219092) (xy 340.234524 -438.760616) (xy 340.23405 -438.77269)
			(xy 340.226585 -438.795655) (xy 340.21239 -438.81519) (xy 340.192855 -438.829385) (xy 340.16989 -438.83685)
			(xy 340.157816 -438.837324) (xy 339.218016 -438.837324) (xy 339.205944 -438.836822) (xy 339.18298 -438.829366)
			(xy 339.163444 -438.815179) (xy 339.149248 -438.795649) (xy 339.141783 -438.772688) (xy 339.141308 -438.760616)
			(xy 338.234528 -438.760616) (xy 338.234528 -439.760614) (xy 341.141304 -439.760614) (xy 341.141304 -437.21909)
			(xy 341.141798 -437.207004) (xy 341.149253 -437.184009) (xy 341.163434 -437.164432) (xy 341.18296 -437.150181)
			(xy 341.205927 -437.142643) (xy 341.218012 -437.142128) (xy 342.157812 -437.142128) (xy 342.169924 -437.142506)
			(xy 342.192957 -437.150012) (xy 342.212532 -437.164283) (xy 342.226725 -437.183914) (xy 342.234141 -437.206976)
			(xy 342.23452 -437.21909) (xy 342.23452 -438.760616) (xy 343.1413 -438.760616) (xy 343.1413 -436.219092)
			(xy 343.141758 -436.207016) (xy 343.149223 -436.184047) (xy 343.163421 -436.16451) (xy 343.182962 -436.150316)
			(xy 343.205932 -436.142855) (xy 343.218008 -436.142384) (xy 344.157808 -436.142384) (xy 344.169882 -436.142857)
			(xy 344.192848 -436.150321) (xy 344.206744 -436.160418) (xy 345.141296 -436.160418) (xy 345.141296 -433.618894)
			(xy 345.141802 -433.606809) (xy 345.149255 -433.583815) (xy 345.163433 -433.564239) (xy 345.182955 -433.549987)
			(xy 345.20592 -433.542448) (xy 345.218004 -433.541932) (xy 346.157804 -433.541932) (xy 346.169916 -433.542313)
			(xy 346.192949 -433.549818) (xy 346.212525 -433.564087) (xy 346.226718 -433.583718) (xy 346.234133 -433.60678)
			(xy 346.234512 -433.618894) (xy 346.234512 -436.160418) (xy 346.234107 -436.172513) (xy 346.22664 -436.195523)
			(xy 346.212439 -436.215106) (xy 346.192889 -436.229355) (xy 346.169898 -436.236878) (xy 346.157804 -436.23738)
			(xy 345.218004 -436.23738) (xy 345.205893 -436.23698) (xy 345.182863 -436.229479) (xy 345.163288 -436.215214)
			(xy 345.149094 -436.195588) (xy 345.141676 -436.17253) (xy 345.141296 -436.160418) (xy 344.206744 -436.160418)
			(xy 344.212384 -436.164516) (xy 344.226579 -436.184052) (xy 344.234043 -436.207018) (xy 344.234516 -436.219092)
			(xy 344.234516 -438.760616) (xy 344.234049 -438.772691) (xy 344.226583 -438.795657) (xy 344.212387 -438.815193)
			(xy 344.19285 -438.829387) (xy 344.169883 -438.836851) (xy 344.157808 -438.837324) (xy 343.218008 -438.837324)
			(xy 343.205935 -438.836829) (xy 343.182971 -438.829371) (xy 343.163435 -438.815182) (xy 343.14924 -438.79565)
			(xy 343.141775 -438.772688) (xy 343.1413 -438.760616) (xy 342.23452 -438.760616) (xy 342.23452 -439.760614)
			(xy 345.141296 -439.760614) (xy 345.141296 -437.21909) (xy 345.141798 -437.207004) (xy 345.149252 -437.184011)
			(xy 345.163431 -437.164435) (xy 345.182955 -437.150183) (xy 345.20592 -437.142644) (xy 345.218004 -437.142128)
			(xy 346.157804 -437.142128) (xy 346.169916 -437.142513) (xy 346.192948 -437.150017) (xy 346.212524 -437.164286)
			(xy 346.226717 -437.183916) (xy 346.234133 -437.206977) (xy 346.234512 -437.21909) (xy 346.234512 -438.760362)
			(xy 381.2413 -438.760362) (xy 381.2413 -436.218838) (xy 381.241839 -436.206754) (xy 381.24928 -436.183762)
			(xy 381.26345 -436.164185) (xy 381.282966 -436.149931) (xy 381.305926 -436.142391) (xy 381.318008 -436.141876)
			(xy 382.257808 -436.141876) (xy 382.269915 -436.142309) (xy 382.292938 -436.149808) (xy 382.307502 -436.160418)
			(xy 383.241296 -436.160418) (xy 383.241296 -433.618894) (xy 383.241802 -433.606809) (xy 383.249255 -433.583815)
			(xy 383.263433 -433.564239) (xy 383.282955 -433.549987) (xy 383.30592 -433.542448) (xy 383.318004 -433.541932)
			(xy 384.257804 -433.541932) (xy 384.269916 -433.542313) (xy 384.292949 -433.549818) (xy 384.312525 -433.564087)
			(xy 384.326718 -433.583718) (xy 384.334133 -433.60678) (xy 384.334512 -433.618894) (xy 384.334512 -435.16042)
			(xy 385.241292 -435.16042) (xy 385.241292 -432.618896) (xy 385.241761 -432.606821) (xy 385.249224 -432.583854)
			(xy 385.26342 -432.564317) (xy 385.282958 -432.550123) (xy 385.305925 -432.54266) (xy 385.318 -432.542188)
			(xy 386.2578 -432.542188) (xy 386.269874 -432.542664) (xy 386.292841 -432.550126) (xy 386.307086 -432.560476)
			(xy 387.241288 -432.560476) (xy 387.241288 -430.018952) (xy 387.241675 -430.006842) (xy 387.249187 -429.983815)
			(xy 387.263456 -429.964244) (xy 387.283083 -429.95005) (xy 387.306138 -429.942629) (xy 387.31825 -429.942244)
			(xy 388.25805 -429.942244) (xy 388.270137 -429.94275) (xy 388.293137 -429.950193) (xy 388.312718 -429.96437)
			(xy 388.32697 -429.983896) (xy 388.334503 -430.006866) (xy 388.335012 -430.018952) (xy 388.335012 -431.560478)
			(xy 389.241284 -431.560478) (xy 389.241284 -429.018954) (xy 389.241673 -429.006832) (xy 389.249179 -428.98378)
			(xy 389.26344 -428.964175) (xy 389.283062 -428.949937) (xy 389.306124 -428.942459) (xy 389.318246 -428.941992)
			(xy 390.258046 -428.941992) (xy 390.270158 -428.942472) (xy 390.293195 -428.949966) (xy 390.307387 -428.96028)
			(xy 391.24128 -428.96028) (xy 391.24128 -428.233078) (xy 391.241534 -428.224321) (xy 391.245512 -428.207264)
			(xy 391.249154 -428.199296) (xy 391.48258 -427.723046) (xy 391.487308 -427.71254) (xy 391.49079 -427.689775)
			(xy 391.487292 -427.667012) (xy 391.48258 -427.656498) (xy 391.249154 -427.180248) (xy 391.245504 -427.172282)
			(xy 391.241521 -427.155224) (xy 391.24128 -427.146466) (xy 391.24128 -426.418756) (xy 391.241726 -426.40668)
			(xy 391.2492 -426.383714) (xy 391.263401 -426.364178) (xy 391.282942 -426.349985) (xy 391.305912 -426.342521)
			(xy 391.317988 -426.342048) (xy 392.257788 -426.342048) (xy 392.269858 -426.342574) (xy 392.292817 -426.350028)
			(xy 392.31235 -426.36421) (xy 392.326547 -426.383733) (xy 392.334017 -426.406687) (xy 392.334496 -426.418756)
			(xy 392.334496 -427.960536) (xy 393.241276 -427.960536) (xy 393.241276 -427.233334) (xy 393.241549 -427.224578)
			(xy 393.245514 -427.207521) (xy 393.24915 -427.199552) (xy 393.482576 -426.723302) (xy 393.487265 -426.71278)
			(xy 393.490761 -426.690025) (xy 393.48728 -426.667268) (xy 393.482576 -426.656754) (xy 393.24915 -426.180504)
			(xy 393.245486 -426.172544) (xy 393.241512 -426.155482) (xy 393.241276 -426.146722) (xy 393.241276 -425.419012)
			(xy 393.241774 -425.40694) (xy 393.249231 -425.383976) (xy 393.26342 -425.36444) (xy 393.28295 -425.350244)
			(xy 393.305912 -425.342779) (xy 393.317984 -425.342304) (xy 394.257784 -425.342304) (xy 394.269867 -425.342727)
			(xy 394.292851 -425.350191) (xy 394.312403 -425.364394) (xy 394.326607 -425.383945) (xy 394.334073 -425.406929)
			(xy 394.334492 -425.419012) (xy 394.334492 -427.960536) (xy 394.334066 -427.972614) (xy 394.326592 -427.995585)
			(xy 394.312386 -428.015123) (xy 394.292839 -428.029316) (xy 394.269862 -428.036775) (xy 394.257784 -428.037244)
			(xy 393.317984 -428.037244) (xy 393.305912 -428.03675) (xy 393.282951 -428.029287) (xy 393.263417 -428.015097)
			(xy 393.249222 -427.995567) (xy 393.241753 -427.972608) (xy 393.241276 -427.960536) (xy 392.334496 -427.960536)
			(xy 392.334496 -428.96028) (xy 392.33407 -428.972363) (xy 392.326606 -428.995347) (xy 392.312404 -429.014899)
			(xy 392.292854 -429.029103) (xy 392.269871 -429.036569) (xy 392.257788 -429.036988) (xy 391.317988 -429.036988)
			(xy 391.305903 -429.036597) (xy 391.282916 -429.029124) (xy 391.263364 -429.014913) (xy 391.249161 -428.995355)
			(xy 391.241698 -428.972366) (xy 391.24128 -428.96028) (xy 390.307387 -428.96028) (xy 390.312792 -428.964208)
			(xy 390.327034 -428.983805) (xy 390.334528 -429.006842) (xy 390.335008 -429.018954) (xy 390.335008 -431.560478)
			(xy 390.33447 -431.572587) (xy 390.326995 -431.595622) (xy 390.312768 -431.61522) (xy 390.293183 -431.629464)
			(xy 390.270154 -431.636959) (xy 390.258046 -431.63744) (xy 389.318246 -431.63744) (xy 389.306123 -431.637001)
			(xy 389.283062 -431.629518) (xy 389.263445 -431.615273) (xy 389.249193 -431.595659) (xy 389.241703 -431.5726)
			(xy 389.241284 -431.560478) (xy 388.335012 -431.560478) (xy 388.335012 -432.560476) (xy 388.334563 -432.572582)
			(xy 388.327072 -432.595607) (xy 388.312818 -432.615179) (xy 388.293204 -432.629375) (xy 388.270158 -432.636799)
			(xy 388.25805 -432.637184) (xy 387.31825 -432.637184) (xy 387.306165 -432.636651) (xy 387.28317 -432.62921)
			(xy 387.263592 -432.61504) (xy 387.249339 -432.595522) (xy 387.241801 -432.572559) (xy 387.241288 -432.560476)
			(xy 386.307086 -432.560476) (xy 386.312377 -432.56432) (xy 386.326572 -432.583856) (xy 386.334035 -432.606822)
			(xy 386.334508 -432.618896) (xy 386.334508 -435.16042) (xy 386.334053 -435.172496) (xy 386.326585 -435.195463)
			(xy 386.312386 -435.215) (xy 386.292845 -435.229194) (xy 386.269876 -435.236656) (xy 386.2578 -435.237128)
			(xy 385.318 -435.237128) (xy 385.305927 -435.236636) (xy 385.282964 -435.229176) (xy 385.263428 -435.214986)
			(xy 385.249233 -435.195454) (xy 385.241767 -435.172492) (xy 385.241292 -435.16042) (xy 384.334512 -435.16042)
			(xy 384.334512 -436.160418) (xy 384.334107 -436.172513) (xy 384.32664 -436.195523) (xy 384.312439 -436.215106)
			(xy 384.292889 -436.229355) (xy 384.269898 -436.236878) (xy 384.257804 -436.23738) (xy 383.318004 -436.23738)
			(xy 383.305893 -436.23698) (xy 383.282863 -436.229479) (xy 383.263288 -436.215214) (xy 383.249094 -436.195588)
			(xy 383.241676 -436.17253) (xy 383.241296 -436.160418) (xy 382.307502 -436.160418) (xy 382.312509 -436.164066)
			(xy 382.326705 -436.183682) (xy 382.334129 -436.20673) (xy 382.334516 -436.218838) (xy 382.334516 -438.760362)
			(xy 382.334059 -438.772454) (xy 382.326608 -438.795461) (xy 382.31242 -438.815045) (xy 382.292881 -438.829295)
			(xy 382.269898 -438.836821) (xy 382.257808 -438.837324) (xy 381.318008 -438.837324) (xy 381.305902 -438.836877)
			(xy 381.282879 -438.829383) (xy 381.263308 -438.815129) (xy 381.249112 -438.795515) (xy 381.241687 -438.772469)
			(xy 381.2413 -438.760362) (xy 346.234512 -438.760362) (xy 346.234512 -439.76036) (xy 383.241296 -439.76036)
			(xy 383.241296 -437.218836) (xy 383.241743 -437.206755) (xy 383.249202 -437.183773) (xy 383.263399 -437.164221)
			(xy 383.282944 -437.150016) (xy 383.305923 -437.142548) (xy 383.318004 -437.142128) (xy 384.257804 -437.142128)
			(xy 384.269891 -437.14251) (xy 384.29288 -437.149983) (xy 384.312433 -437.164196) (xy 384.326636 -437.183756)
			(xy 384.334097 -437.206749) (xy 384.334512 -437.218836) (xy 384.334512 -438.760362) (xy 385.241292 -438.760362)
			(xy 385.241292 -436.218838) (xy 385.241839 -436.206755) (xy 385.249279 -436.183764) (xy 385.263447 -436.164187)
			(xy 385.282961 -436.149934) (xy 385.305919 -436.142392) (xy 385.318 -436.141876) (xy 386.2578 -436.141876)
			(xy 386.269906 -436.142316) (xy 386.29293 -436.149812) (xy 386.307489 -436.160418) (xy 387.241288 -436.160418)
			(xy 387.241288 -433.618894) (xy 387.241703 -433.606799) (xy 387.249168 -433.583791) (xy 387.263366 -433.564207)
			(xy 387.282913 -433.549958) (xy 387.305903 -433.542435) (xy 387.317996 -433.541932) (xy 388.257796 -433.541932)
			(xy 388.269908 -433.54232) (xy 388.292941 -433.549822) (xy 388.312517 -433.56409) (xy 388.32671 -433.58372)
			(xy 388.334125 -433.606781) (xy 388.334504 -433.618894) (xy 388.334504 -435.16042) (xy 389.241284 -435.16042)
			(xy 389.241284 -432.618896) (xy 389.241761 -432.606822) (xy 389.249223 -432.583856) (xy 389.263417 -432.56432)
			(xy 389.282953 -432.550125) (xy 389.305918 -432.542661) (xy 389.317992 -432.542188) (xy 390.257792 -432.542188)
			(xy 390.269874 -432.542619) (xy 390.292856 -432.550084) (xy 390.307161 -432.560476) (xy 391.24128 -432.560476)
			(xy 391.24128 -430.018952) (xy 391.241675 -430.006843) (xy 391.249186 -429.983817) (xy 391.263453 -429.964247)
			(xy 391.283077 -429.950053) (xy 391.306131 -429.94263) (xy 391.318242 -429.942244) (xy 392.258042 -429.942244)
			(xy 392.270134 -429.942672) (xy 392.293137 -429.95014) (xy 392.312716 -429.964337) (xy 392.326965 -429.983879)
			(xy 392.334496 -430.006861) (xy 392.335004 -430.018952) (xy 392.335004 -431.560478) (xy 393.241276 -431.560478)
			(xy 393.241276 -429.018954) (xy 393.241673 -429.006833) (xy 393.249178 -428.983782) (xy 393.263438 -428.964178)
			(xy 393.283057 -428.949939) (xy 393.306117 -428.94246) (xy 393.318238 -428.941992) (xy 394.258038 -428.941992)
			(xy 394.27015 -428.942479) (xy 394.293187 -428.949971) (xy 394.307374 -428.96028) (xy 395.241272 -428.96028)
			(xy 395.241272 -428.233078) (xy 395.241527 -428.224321) (xy 395.245504 -428.207264) (xy 395.249146 -428.199296)
			(xy 395.482572 -427.723046) (xy 395.4873 -427.71254) (xy 395.490783 -427.689775) (xy 395.487285 -427.667012)
			(xy 395.482572 -427.656498) (xy 395.249146 -427.180248) (xy 395.245496 -427.172282) (xy 395.241513 -427.155224)
			(xy 395.241272 -427.146466) (xy 395.241272 -426.418756) (xy 395.241726 -426.406681) (xy 395.249198 -426.383716)
			(xy 395.263398 -426.364181) (xy 395.282937 -426.349987) (xy 395.305905 -426.342522) (xy 395.31798 -426.342048)
			(xy 396.25778 -426.342048) (xy 396.269849 -426.342581) (xy 396.292808 -426.350032) (xy 396.312342 -426.364213)
			(xy 396.326539 -426.383734) (xy 396.334009 -426.406687) (xy 396.334488 -426.418756) (xy 396.334488 -427.960536)
			(xy 398.24152 -427.960536) (xy 398.24152 -427.233334) (xy 398.241789 -427.224578) (xy 398.245756 -427.20752)
			(xy 398.249394 -427.199552) (xy 398.48282 -426.723302) (xy 398.487507 -426.71278) (xy 398.491001 -426.690025)
			(xy 398.487522 -426.667268) (xy 398.48282 -426.656754) (xy 398.249394 -426.180504) (xy 398.245732 -426.172543)
			(xy 398.241756 -426.155482) (xy 398.24152 -426.146722) (xy 398.24152 -425.419012) (xy 398.241924 -425.406927)
			(xy 398.249391 -425.38394) (xy 398.263599 -425.364387) (xy 398.283154 -425.350184) (xy 398.306143 -425.342721)
			(xy 398.318228 -425.342304) (xy 399.258028 -425.342304) (xy 399.270105 -425.34274) (xy 399.293075 -425.350212)
			(xy 399.312613 -425.364415) (xy 399.326806 -425.38396) (xy 399.334266 -425.406935) (xy 399.334736 -425.419012)
			(xy 399.334736 -427.960536) (xy 399.334267 -427.97261) (xy 399.326798 -427.995573) (xy 399.312602 -428.015107)
			(xy 399.293066 -428.029302) (xy 399.270102 -428.036768) (xy 399.258028 -428.037244) (xy 398.318228 -428.037244)
			(xy 398.306158 -428.036713) (xy 398.283198 -428.029262) (xy 398.263664 -428.015082) (xy 398.249467 -427.995559)
			(xy 398.241997 -427.972605) (xy 398.24152 -427.960536) (xy 396.334488 -427.960536) (xy 396.334488 -428.96028)
			(xy 396.33407 -428.972364) (xy 396.326605 -428.995349) (xy 396.312401 -429.014901) (xy 396.292849 -429.029105)
			(xy 396.269864 -429.03657) (xy 396.25778 -429.036988) (xy 395.31798 -429.036988) (xy 395.305902 -429.036552)
			(xy 395.282931 -429.029082) (xy 395.263393 -429.014879) (xy 395.2492 -428.995333) (xy 395.241741 -428.972358)
			(xy 395.241272 -428.96028) (xy 394.307374 -428.96028) (xy 394.312784 -428.964211) (xy 394.327026 -428.983806)
			(xy 394.33452 -429.006842) (xy 394.335 -429.018954) (xy 394.335 -431.560478) (xy 394.33447 -431.572588)
			(xy 394.326994 -431.595624) (xy 394.312765 -431.615223) (xy 394.293177 -431.629466) (xy 394.270147 -431.636961)
			(xy 394.258038 -431.63744) (xy 393.318238 -431.63744) (xy 393.306115 -431.637007) (xy 393.283054 -431.629523)
			(xy 393.263436 -431.615275) (xy 393.249184 -431.595661) (xy 393.241695 -431.572601) (xy 393.241276 -431.560478)
			(xy 392.335004 -431.560478) (xy 392.335004 -432.560476) (xy 392.334563 -432.572583) (xy 392.327071 -432.595609)
			(xy 392.312815 -432.615182) (xy 392.293199 -432.629378) (xy 392.27015 -432.6368) (xy 392.258042 -432.637184)
			(xy 391.318242 -432.637184) (xy 391.306157 -432.636657) (xy 391.283162 -432.629215) (xy 391.263583 -432.615043)
			(xy 391.24933 -432.595523) (xy 391.241793 -432.572559) (xy 391.24128 -432.560476) (xy 390.307161 -432.560476)
			(xy 390.312406 -432.564286) (xy 390.326611 -432.583833) (xy 390.334079 -432.606814) (xy 390.3345 -432.618896)
			(xy 390.3345 -435.16042) (xy 390.334053 -435.172496) (xy 390.326584 -435.195465) (xy 390.312383 -435.215003)
			(xy 390.29284 -435.229196) (xy 390.269869 -435.236657) (xy 390.257792 -435.237128) (xy 389.317992 -435.237128)
			(xy 389.305919 -435.236643) (xy 389.282955 -435.229181) (xy 389.26342 -435.214989) (xy 389.249225 -435.195456)
			(xy 389.241759 -435.172493) (xy 389.241284 -435.16042) (xy 388.334504 -435.16042) (xy 388.334504 -436.160418)
			(xy 388.334009 -436.172504) (xy 388.326553 -436.195498) (xy 388.312372 -436.215074) (xy 388.292847 -436.229325)
			(xy 388.26988 -436.236865) (xy 388.257796 -436.23738) (xy 387.317996 -436.23738) (xy 387.305885 -436.236987)
			(xy 387.282854 -436.229484) (xy 387.263279 -436.215217) (xy 387.249085 -436.195589) (xy 387.241668 -436.172531)
			(xy 387.241288 -436.160418) (xy 386.307489 -436.160418) (xy 386.312501 -436.164069) (xy 386.326696 -436.183684)
			(xy 386.334121 -436.20673) (xy 386.334508 -436.218838) (xy 386.334508 -438.760362) (xy 386.333961 -438.772445)
			(xy 386.326521 -438.795436) (xy 386.312353 -438.815013) (xy 386.292839 -438.829266) (xy 386.269881 -438.836808)
			(xy 386.2578 -438.837324) (xy 385.318 -438.837324) (xy 385.305894 -438.836884) (xy 385.28287 -438.829388)
			(xy 385.263299 -438.815131) (xy 385.249104 -438.795516) (xy 385.241679 -438.77247) (xy 385.241292 -438.760362)
			(xy 384.334512 -438.760362) (xy 384.334512 -439.76036) (xy 387.241288 -439.76036) (xy 387.241288 -437.218836)
			(xy 387.241743 -437.206756) (xy 387.2492 -437.183775) (xy 387.263396 -437.164224) (xy 387.282939 -437.150019)
			(xy 387.305916 -437.14255) (xy 387.317996 -437.142128) (xy 388.257796 -437.142128) (xy 388.269882 -437.142516)
			(xy 388.292871 -437.149987) (xy 388.312424 -437.164198) (xy 388.326627 -437.183758) (xy 388.334089 -437.20675)
			(xy 388.334504 -437.218836) (xy 388.334504 -438.760362) (xy 389.241284 -438.760362) (xy 389.241284 -436.218838)
			(xy 389.241741 -436.206746) (xy 389.249192 -436.183739) (xy 389.26338 -436.164155) (xy 389.282919 -436.149905)
			(xy 389.305902 -436.142379) (xy 389.317992 -436.141876) (xy 390.257792 -436.141876) (xy 390.269898 -436.142323)
			(xy 390.292921 -436.149817) (xy 390.307476 -436.160418) (xy 391.24128 -436.160418) (xy 391.24128 -433.618894)
			(xy 391.241703 -433.6068) (xy 391.249166 -433.583793) (xy 391.263363 -433.564209) (xy 391.282908 -433.549961)
			(xy 391.305896 -433.542436) (xy 391.317988 -433.541932) (xy 392.257788 -433.541932) (xy 392.269899 -433.542327)
			(xy 392.292932 -433.549827) (xy 392.312508 -433.564093) (xy 392.326702 -433.583721) (xy 392.334117 -433.606781)
			(xy 392.334496 -433.618894) (xy 392.334496 -435.16042) (xy 393.241276 -435.16042) (xy 393.241276 -432.618896)
			(xy 393.241761 -432.606823) (xy 393.249222 -432.583858) (xy 393.263414 -432.564323) (xy 393.282948 -432.550128)
			(xy 393.305911 -432.542663) (xy 393.317984 -432.542188) (xy 394.257784 -432.542188) (xy 394.269865 -432.542626)
			(xy 394.292847 -432.550089) (xy 394.307147 -432.560476) (xy 395.241272 -432.560476) (xy 395.241272 -430.018952)
			(xy 395.241675 -430.006843) (xy 395.249184 -429.983819) (xy 395.26345 -429.96425) (xy 395.283072 -429.950056)
			(xy 395.306124 -429.942631) (xy 395.318234 -429.942244) (xy 396.258034 -429.942244) (xy 396.270126 -429.942678)
			(xy 396.293128 -429.950145) (xy 396.312708 -429.96434) (xy 396.326957 -429.98388) (xy 396.334488 -430.006862)
			(xy 396.334996 -430.018952) (xy 396.334996 -431.560478) (xy 398.24152 -431.560478) (xy 398.24152 -429.018954)
			(xy 398.241972 -429.006839) (xy 398.24947 -428.983797) (xy 398.263718 -428.964198) (xy 398.283322 -428.949957)
			(xy 398.306367 -428.942468) (xy 398.318482 -428.941992) (xy 399.258282 -428.941992) (xy 399.270391 -428.942526)
			(xy 399.293426 -428.950003) (xy 399.307582 -428.96028) (xy 400.241516 -428.96028) (xy 400.241516 -428.233078)
			(xy 400.241767 -428.224321) (xy 400.245746 -428.207263) (xy 400.24939 -428.199296) (xy 400.482816 -427.723046)
			(xy 400.487542 -427.712539) (xy 400.491023 -427.689775) (xy 400.487527 -427.667013) (xy 400.482816 -427.656498)
			(xy 400.24939 -427.180248) (xy 400.245742 -427.172281) (xy 400.241757 -427.155224) (xy 400.241516 -427.146466)
			(xy 400.241516 -426.418756) (xy 400.241927 -426.406677) (xy 400.249404 -426.383704) (xy 400.263614 -426.364166)
			(xy 400.283165 -426.349973) (xy 400.306144 -426.342516) (xy 400.318224 -426.342048) (xy 401.258024 -426.342048)
			(xy 401.270095 -426.342543) (xy 401.293056 -426.350007) (xy 401.312589 -426.364197) (xy 401.326784 -426.383726)
			(xy 401.334254 -426.406685) (xy 401.334732 -426.418756) (xy 401.334732 -427.960536) (xy 402.241512 -427.960536)
			(xy 402.241512 -427.233334) (xy 402.241781 -427.224578) (xy 402.245748 -427.20752) (xy 402.249386 -427.199552)
			(xy 402.482812 -426.723302) (xy 402.487499 -426.71278) (xy 402.490994 -426.690025) (xy 402.487514 -426.667268)
			(xy 402.482812 -426.656754) (xy 402.249386 -426.180504) (xy 402.245724 -426.172543) (xy 402.241748 -426.155482)
			(xy 402.241512 -426.146722) (xy 402.241512 -425.419012) (xy 402.241923 -425.406928) (xy 402.24939 -425.383942)
			(xy 402.263596 -425.36439) (xy 402.283149 -425.350186) (xy 402.306136 -425.342722) (xy 402.31822 -425.342304)
			(xy 403.25802 -425.342304) (xy 403.270097 -425.342748) (xy 403.293067 -425.350217) (xy 403.312604 -425.364419)
			(xy 403.326798 -425.383962) (xy 403.334257 -425.406935) (xy 403.334728 -425.419012) (xy 403.334728 -427.960536)
			(xy 403.334267 -427.97261) (xy 403.326797 -427.995576) (xy 403.312599 -428.01511) (xy 403.293061 -428.029304)
			(xy 403.270095 -428.036769) (xy 403.25802 -428.037244) (xy 402.31822 -428.037244) (xy 402.30615 -428.036719)
			(xy 402.28319 -428.029267) (xy 402.263655 -428.015085) (xy 402.249459 -427.995561) (xy 402.241989 -427.972606)
			(xy 402.241512 -427.960536) (xy 401.334732 -427.960536) (xy 401.334732 -428.96028) (xy 401.334219 -428.972351)
			(xy 401.326765 -428.995314) (xy 401.31258 -429.014849) (xy 401.293053 -429.029045) (xy 401.270095 -429.036512)
			(xy 401.258024 -429.036988) (xy 400.318224 -429.036988) (xy 400.306141 -429.036566) (xy 400.283155 -429.029103)
			(xy 400.263603 -429.0149) (xy 400.249399 -428.995348) (xy 400.241934 -428.972363) (xy 400.241516 -428.96028)
			(xy 399.307582 -428.96028) (xy 399.313024 -428.964231) (xy 399.327268 -428.983817) (xy 399.334763 -429.006845)
			(xy 399.335244 -429.018954) (xy 399.335244 -431.560478) (xy 399.334821 -431.572601) (xy 399.327333 -431.595663)
			(xy 399.313082 -431.61528) (xy 399.293466 -431.629531) (xy 399.270405 -431.63702) (xy 399.258282 -431.63744)
			(xy 398.318482 -431.63744) (xy 398.306356 -431.637055) (xy 398.283293 -431.629555) (xy 398.263676 -431.615295)
			(xy 398.249427 -431.595671) (xy 398.241939 -431.572604) (xy 398.24152 -431.560478) (xy 396.334996 -431.560478)
			(xy 396.334996 -432.560476) (xy 396.334563 -432.572584) (xy 396.32707 -432.595611) (xy 396.312813 -432.615185)
			(xy 396.293194 -432.62938) (xy 396.270143 -432.636801) (xy 396.258034 -432.637184) (xy 395.318234 -432.637184)
			(xy 395.306149 -432.636664) (xy 395.283153 -432.62922) (xy 395.263575 -432.615046) (xy 395.249322 -432.595525)
			(xy 395.241785 -432.572559) (xy 395.241272 -432.560476) (xy 394.307147 -432.560476) (xy 394.312397 -432.564289)
			(xy 394.326602 -432.583835) (xy 394.33407 -432.606815) (xy 394.334492 -432.618896) (xy 394.334492 -435.16042)
			(xy 394.334052 -435.172497) (xy 394.326582 -435.195468) (xy 394.31238 -435.215006) (xy 394.292835 -435.229199)
			(xy 394.269861 -435.236658) (xy 394.257784 -435.237128) (xy 393.317984 -435.237128) (xy 393.305911 -435.23665)
			(xy 393.282946 -435.229185) (xy 393.263411 -435.214991) (xy 393.249217 -435.195457) (xy 393.241751 -435.172493)
			(xy 393.241276 -435.16042) (xy 392.334496 -435.16042) (xy 392.334496 -436.160418) (xy 392.334009 -436.172505)
			(xy 392.326552 -436.1955) (xy 392.312369 -436.215077) (xy 392.292842 -436.229328) (xy 392.269873 -436.236866)
			(xy 392.257788 -436.23738) (xy 391.317988 -436.23738) (xy 391.305876 -436.236994) (xy 391.282845 -436.229489)
			(xy 391.263271 -436.21522) (xy 391.249077 -436.195591) (xy 391.24166 -436.172531) (xy 391.24128 -436.160418)
			(xy 390.307476 -436.160418) (xy 390.312492 -436.164071) (xy 390.326688 -436.183685) (xy 390.334113 -436.206731)
			(xy 390.3345 -436.218838) (xy 390.3345 -438.760362) (xy 390.333961 -438.772446) (xy 390.32652 -438.795438)
			(xy 390.31235 -438.815015) (xy 390.292834 -438.829269) (xy 390.269874 -438.836809) (xy 390.257792 -438.837324)
			(xy 389.317992 -438.837324) (xy 389.305885 -438.836891) (xy 389.282862 -438.829392) (xy 389.263291 -438.815134)
			(xy 389.249095 -438.795518) (xy 389.241671 -438.77247) (xy 389.241284 -438.760362) (xy 388.334504 -438.760362)
			(xy 388.334504 -439.76036) (xy 391.24128 -439.76036) (xy 391.24128 -437.218836) (xy 391.241743 -437.206756)
			(xy 391.249199 -437.183777) (xy 391.263393 -437.164227) (xy 391.282934 -437.150021) (xy 391.305909 -437.142551)
			(xy 391.317988 -437.142128) (xy 392.257788 -437.142128) (xy 392.269874 -437.142524) (xy 392.292862 -437.149992)
			(xy 392.312416 -437.164202) (xy 392.326619 -437.18376) (xy 392.33408 -437.20675) (xy 392.334496 -437.218836)
			(xy 392.334496 -438.760362) (xy 393.241276 -438.760362) (xy 393.241276 -436.218838) (xy 393.24174 -436.206747)
			(xy 393.249191 -436.183741) (xy 393.263377 -436.164158) (xy 393.282914 -436.149907) (xy 393.305894 -436.142381)
			(xy 393.317984 -436.141876) (xy 394.257784 -436.141876) (xy 394.26989 -436.14233) (xy 394.292912 -436.149822)
			(xy 394.307462 -436.160418) (xy 395.241272 -436.160418) (xy 395.241272 -433.618894) (xy 395.241703 -433.606801)
			(xy 395.249165 -433.583795) (xy 395.26336 -433.564212) (xy 395.282903 -433.549963) (xy 395.305888 -433.542437)
			(xy 395.31798 -433.541932) (xy 396.25778 -433.541932) (xy 396.269891 -433.542334) (xy 396.292923 -433.549832)
			(xy 396.312499 -433.564096) (xy 396.326693 -433.583723) (xy 396.334109 -433.606782) (xy 396.334488 -433.618894)
			(xy 396.334488 -435.16042) (xy 398.241012 -435.16042) (xy 398.241012 -432.618896) (xy 398.241413 -432.606786)
			(xy 398.248915 -432.583756) (xy 398.26318 -432.564182) (xy 398.282806 -432.549988) (xy 398.305862 -432.542569)
			(xy 398.317974 -432.542188) (xy 399.257774 -432.542188) (xy 399.269867 -432.54263) (xy 399.292875 -432.550086)
			(xy 399.307214 -432.560476) (xy 400.241516 -432.560476) (xy 400.241516 -430.018952) (xy 400.241876 -430.006839)
			(xy 400.24939 -429.983807) (xy 400.263666 -429.964234) (xy 400.2833 -429.950041) (xy 400.306363 -429.942625)
			(xy 400.318478 -429.942244) (xy 401.258278 -429.942244) (xy 401.270367 -429.942726) (xy 401.293367 -429.950177)
			(xy 401.312948 -429.96436) (xy 401.327199 -429.983891) (xy 401.334731 -430.006865) (xy 401.33524 -430.018952)
			(xy 401.33524 -431.560478) (xy 402.241512 -431.560478) (xy 402.241512 -429.018954) (xy 402.241972 -429.00684)
			(xy 402.249469 -428.983799) (xy 402.263715 -428.964201) (xy 402.283317 -428.94996) (xy 402.30636 -428.942469)
			(xy 402.318474 -428.941992) (xy 403.258274 -428.941992) (xy 403.270383 -428.942533) (xy 403.293417 -428.950008)
			(xy 403.307569 -428.96028) (xy 404.241508 -428.96028) (xy 404.241508 -428.233078) (xy 404.24176 -428.224321)
			(xy 404.245739 -428.207263) (xy 404.249382 -428.199296) (xy 404.482808 -427.723046) (xy 404.487535 -427.712539)
			(xy 404.491015 -427.689775) (xy 404.487519 -427.667012) (xy 404.482808 -427.656498) (xy 404.249382 -427.180248)
			(xy 404.245734 -427.172282) (xy 404.241749 -427.155224) (xy 404.241508 -427.146466) (xy 404.241508 -426.418756)
			(xy 404.241927 -426.406678) (xy 404.249403 -426.383706) (xy 404.263611 -426.364168) (xy 404.28316 -426.349976)
			(xy 404.306137 -426.342517) (xy 404.318216 -426.342048) (xy 405.258016 -426.342048) (xy 405.270087 -426.34255)
			(xy 405.293047 -426.350012) (xy 405.31258 -426.3642) (xy 405.326776 -426.383728) (xy 405.334246 -426.406685)
			(xy 405.334724 -426.418756) (xy 405.334724 -427.960536) (xy 406.241504 -427.960536) (xy 406.241504 -427.233334)
			(xy 406.241774 -427.224578) (xy 406.245741 -427.207521) (xy 406.249378 -427.199552) (xy 406.482804 -426.723302)
			(xy 406.487492 -426.71278) (xy 406.490987 -426.690025) (xy 406.487507 -426.667268) (xy 406.482804 -426.656754)
			(xy 406.249378 -426.180504) (xy 406.245716 -426.172543) (xy 406.24174 -426.155482) (xy 406.241504 -426.146722)
			(xy 406.241504 -425.419012) (xy 406.241923 -425.406929) (xy 406.249389 -425.383944) (xy 406.263593 -425.364393)
			(xy 406.283144 -425.350189) (xy 406.306129 -425.342723) (xy 406.318212 -425.342304) (xy 407.258012 -425.342304)
			(xy 407.270088 -425.342754) (xy 407.293058 -425.350222) (xy 407.312596 -425.364421) (xy 407.326789 -425.383964)
			(xy 407.334249 -425.406935) (xy 407.33472 -425.419012) (xy 407.33472 -427.960536) (xy 407.334267 -427.972611)
			(xy 407.326796 -427.995578) (xy 407.312596 -428.015113) (xy 407.293056 -428.029307) (xy 407.270087 -428.036771)
			(xy 407.258012 -428.037244) (xy 406.318212 -428.037244) (xy 406.306142 -428.036726) (xy 406.283181 -428.029271)
			(xy 406.263647 -428.015087) (xy 406.249451 -427.995562) (xy 406.241981 -427.972606) (xy 406.241504 -427.960536)
			(xy 405.334724 -427.960536) (xy 405.334724 -428.96028) (xy 405.33427 -428.97236) (xy 405.32681 -428.995339)
			(xy 405.312614 -429.014889) (xy 405.293072 -429.029094) (xy 405.270096 -429.036565) (xy 405.258016 -429.036988)
			(xy 404.318216 -429.036988) (xy 404.306132 -429.036573) (xy 404.283147 -429.029108) (xy 404.263594 -429.014903)
			(xy 404.24939 -428.99535) (xy 404.241926 -428.972364) (xy 404.241508 -428.96028) (xy 403.307569 -428.96028)
			(xy 403.313015 -428.964233) (xy 403.327259 -428.983818) (xy 403.334755 -429.006846) (xy 403.335236 -429.018954)
			(xy 403.335236 -431.560478) (xy 403.334821 -431.572602) (xy 403.327332 -431.595665) (xy 403.31308 -431.615282)
			(xy 403.293461 -431.629533) (xy 403.270398 -431.637022) (xy 403.258274 -431.63744) (xy 402.318474 -431.63744)
			(xy 402.306356 -431.63701) (xy 402.283308 -431.629513) (xy 402.263705 -431.615261) (xy 402.249465 -431.595649)
			(xy 402.241982 -431.572596) (xy 402.241512 -431.560478) (xy 401.33524 -431.560478) (xy 401.33524 -432.560476)
			(xy 401.334764 -432.57258) (xy 401.327276 -432.595599) (xy 401.313028 -432.615169) (xy 401.293422 -432.629366)
			(xy 401.270383 -432.636795) (xy 401.258278 -432.637184) (xy 400.318478 -432.637184) (xy 400.30639 -432.636712)
			(xy 400.283392 -432.629252) (xy 400.263815 -432.615066) (xy 400.249564 -432.595535) (xy 400.242028 -432.572563)
			(xy 400.241516 -432.560476) (xy 399.307214 -432.560476) (xy 399.312459 -432.564277) (xy 399.326709 -432.583819)
			(xy 399.334233 -432.606804) (xy 399.334736 -432.618896) (xy 399.334736 -435.16042) (xy 399.334301 -435.172526)
			(xy 399.326801 -435.195548) (xy 399.312543 -435.215118) (xy 399.292927 -435.229313) (xy 399.269882 -435.23674)
			(xy 399.257774 -435.237128) (xy 398.317974 -435.237128) (xy 398.30588 -435.236714) (xy 398.282873 -435.229247)
			(xy 398.263291 -435.215047) (xy 398.249042 -435.195501) (xy 398.241516 -435.172513) (xy 398.241012 -435.16042)
			(xy 396.334488 -435.16042) (xy 396.334488 -436.160418) (xy 396.334009 -436.172506) (xy 396.32655 -436.195502)
			(xy 396.312366 -436.21508) (xy 396.292837 -436.229331) (xy 396.269866 -436.236867) (xy 396.25778 -436.23738)
			(xy 395.31798 -436.23738) (xy 395.305868 -436.237001) (xy 395.282837 -436.229493) (xy 395.263262 -436.215223)
			(xy 395.249069 -436.195592) (xy 395.241652 -436.172532) (xy 395.241272 -436.160418) (xy 394.307462 -436.160418)
			(xy 394.312483 -436.164075) (xy 394.326679 -436.183687) (xy 394.334105 -436.206731) (xy 394.334492 -436.218838)
			(xy 394.334492 -438.760362) (xy 394.333961 -438.772446) (xy 394.326518 -438.79544) (xy 394.312347 -438.815018)
			(xy 394.292829 -438.829271) (xy 394.269866 -438.83681) (xy 394.257784 -438.837324) (xy 393.317984 -438.837324)
			(xy 393.305877 -438.836898) (xy 393.282853 -438.829397) (xy 393.263282 -438.815137) (xy 393.249087 -438.795519)
			(xy 393.241663 -438.772471) (xy 393.241276 -438.760362) (xy 392.334496 -438.760362) (xy 392.334496 -439.76036)
			(xy 395.241272 -439.76036) (xy 395.241272 -437.218836) (xy 395.241743 -437.206757) (xy 395.249198 -437.183779)
			(xy 395.26339 -437.16423) (xy 395.282929 -437.150024) (xy 395.305901 -437.142552) (xy 395.31798 -437.142128)
			(xy 396.25778 -437.142128) (xy 396.269865 -437.14253) (xy 396.292853 -437.149997) (xy 396.312407 -437.164204)
			(xy 396.326611 -437.183761) (xy 396.334072 -437.206751) (xy 396.334488 -437.218836) (xy 396.334488 -438.760362)
			(xy 398.241012 -438.760362) (xy 398.241012 -436.218838) (xy 398.241492 -436.20672) (xy 398.24897 -436.183667)
			(xy 398.263208 -436.164053) (xy 398.282809 -436.1498) (xy 398.305856 -436.142302) (xy 398.317974 -436.141876)
			(xy 399.257774 -436.141876) (xy 399.269899 -436.142283) (xy 399.292964 -436.149772) (xy 399.307616 -436.160418)
			(xy 400.241008 -436.160418) (xy 400.241008 -433.618894) (xy 400.241506 -433.606782) (xy 400.248992 -433.583744)
			(xy 400.263228 -433.564145) (xy 400.282822 -433.549903) (xy 400.305858 -433.54241) (xy 400.31797 -433.541932)
			(xy 401.25777 -433.541932) (xy 401.269891 -433.542385) (xy 401.292947 -433.549869) (xy 401.312563 -433.564112)
			(xy 401.326815 -433.58372) (xy 401.334309 -433.606774) (xy 401.334732 -433.618894) (xy 401.334732 -435.16042)
			(xy 402.241004 -435.16042) (xy 402.241004 -432.618896) (xy 402.241413 -432.606787) (xy 402.248914 -432.583758)
			(xy 402.263177 -432.564185) (xy 402.282801 -432.549991) (xy 402.305855 -432.542571) (xy 402.317966 -432.542188)
			(xy 403.257766 -432.542188) (xy 403.269859 -432.542637) (xy 403.292866 -432.55009) (xy 403.307201 -432.560476)
			(xy 404.241508 -432.560476) (xy 404.241508 -430.018952) (xy 404.241876 -430.00684) (xy 404.249389 -429.98381)
			(xy 404.263663 -429.964237) (xy 404.283295 -429.950044) (xy 404.306356 -429.942626) (xy 404.31847 -429.942244)
			(xy 405.25827 -429.942244) (xy 405.270358 -429.942733) (xy 405.293359 -429.950182) (xy 405.312939 -429.964363)
			(xy 405.327191 -429.983892) (xy 405.334723 -430.006865) (xy 405.335232 -430.018952) (xy 405.335232 -431.560478)
			(xy 406.241504 -431.560478) (xy 406.241504 -429.018954) (xy 406.241972 -429.00684) (xy 406.249468 -428.983801)
			(xy 406.263712 -428.964203) (xy 406.283312 -428.949962) (xy 406.306352 -428.94247) (xy 406.318466 -428.941992)
			(xy 407.258266 -428.941992) (xy 407.270374 -428.94254) (xy 407.293409 -428.950012) (xy 407.307556 -428.96028)
			(xy 408.2415 -428.96028) (xy 408.2415 -428.233078) (xy 408.241752 -428.224321) (xy 408.245731 -428.207263)
			(xy 408.249374 -428.199296) (xy 408.4828 -427.723046) (xy 408.487527 -427.712539) (xy 408.491008 -427.689775)
			(xy 408.487512 -427.667012) (xy 408.4828 -427.656498) (xy 408.249374 -427.180248) (xy 408.245725 -427.172282)
			(xy 408.241741 -427.155224) (xy 408.2415 -427.146466) (xy 408.2415 -426.418756) (xy 408.241927 -426.406678)
			(xy 408.249402 -426.383708) (xy 408.263608 -426.364171) (xy 408.283155 -426.349979) (xy 408.30613 -426.342519)
			(xy 408.318208 -426.342048) (xy 409.258008 -426.342048) (xy 409.270079 -426.342557) (xy 409.293039 -426.350016)
			(xy 409.312572 -426.364203) (xy 409.326767 -426.383729) (xy 409.334238 -426.406686) (xy 409.334716 -426.418756)
			(xy 409.334716 -427.960536) (xy 410.241496 -427.960536) (xy 410.241496 -427.233334) (xy 410.241767 -427.224578)
			(xy 410.245733 -427.207521) (xy 410.24937 -427.199552) (xy 410.482796 -426.723302) (xy 410.487484 -426.71278)
			(xy 410.490979 -426.690025) (xy 410.487499 -426.667268) (xy 410.482796 -426.656754) (xy 410.24937 -426.180504)
			(xy 410.245707 -426.172544) (xy 410.241732 -426.155482) (xy 410.241496 -426.146722) (xy 410.241496 -425.419012)
			(xy 410.241923 -425.40693) (xy 410.249388 -425.383947) (xy 410.26359 -425.364396) (xy 410.283139 -425.350191)
			(xy 410.306122 -425.342724) (xy 410.318204 -425.342304) (xy 411.258004 -425.342304) (xy 411.270088 -425.342709)
			(xy 411.293073 -425.350179) (xy 411.312624 -425.364387) (xy 411.326828 -425.383941) (xy 411.334293 -425.406928)
			(xy 411.334712 -425.419012) (xy 411.334712 -427.960536) (xy 411.334267 -427.972612) (xy 411.326795 -427.99558)
			(xy 411.312593 -428.015116) (xy 411.293051 -428.029309) (xy 411.27008 -428.036772) (xy 411.258004 -428.037244)
			(xy 410.318204 -428.037244) (xy 410.306133 -428.036733) (xy 410.283172 -428.029276) (xy 410.263638 -428.01509)
			(xy 410.249442 -427.995564) (xy 410.241973 -427.972607) (xy 410.241496 -427.960536) (xy 409.334716 -427.960536)
			(xy 409.334716 -428.96028) (xy 409.33427 -428.972361) (xy 409.326809 -428.995342) (xy 409.312611 -429.014891)
			(xy 409.293067 -429.029096) (xy 409.270089 -429.036566) (xy 409.258008 -429.036988) (xy 408.318208 -429.036988)
			(xy 408.306124 -429.03658) (xy 408.283138 -429.029113) (xy 408.263586 -429.014906) (xy 408.249382 -428.995352)
			(xy 408.241918 -428.972364) (xy 408.2415 -428.96028) (xy 407.307556 -428.96028) (xy 407.313007 -428.964236)
			(xy 407.327251 -428.98382) (xy 407.334747 -429.006846) (xy 407.335228 -429.018954) (xy 407.335228 -431.560478)
			(xy 407.334821 -431.572603) (xy 407.32733 -431.595667) (xy 407.313077 -431.615285) (xy 407.293456 -431.629536)
			(xy 407.270391 -431.637023) (xy 407.258266 -431.63744) (xy 406.318466 -431.63744) (xy 406.306347 -431.637017)
			(xy 406.283299 -431.629518) (xy 406.263696 -431.615264) (xy 406.249457 -431.59565) (xy 406.241974 -431.572597)
			(xy 406.241504 -431.560478) (xy 405.335232 -431.560478) (xy 405.335232 -432.560476) (xy 405.334763 -432.57258)
			(xy 405.327275 -432.595601) (xy 405.313025 -432.615172) (xy 405.293417 -432.629369) (xy 405.270375 -432.636796)
			(xy 405.25827 -432.637184) (xy 404.31847 -432.637184) (xy 404.306381 -432.636719) (xy 404.283384 -432.629257)
			(xy 404.263806 -432.615069) (xy 404.249556 -432.595537) (xy 404.24202 -432.572563) (xy 404.241508 -432.560476)
			(xy 403.307201 -432.560476) (xy 403.312451 -432.56428) (xy 403.326701 -432.583821) (xy 403.334225 -432.606805)
			(xy 403.334728 -432.618896) (xy 403.334728 -435.16042) (xy 403.334301 -435.172527) (xy 403.3268 -435.19555)
			(xy 403.31254 -435.215121) (xy 403.292922 -435.229316) (xy 403.269874 -435.236741) (xy 403.257766 -435.237128)
			(xy 402.317966 -435.237128) (xy 402.305871 -435.236721) (xy 402.282864 -435.229251) (xy 402.263282 -435.21505)
			(xy 402.249034 -435.195502) (xy 402.241508 -435.172513) (xy 402.241004 -435.16042) (xy 401.334732 -435.16042)
			(xy 401.334732 -436.160418) (xy 401.334355 -436.172545) (xy 401.326854 -436.195609) (xy 401.312592 -436.215226)
			(xy 401.292966 -436.229476) (xy 401.269897 -436.236962) (xy 401.25777 -436.23738) (xy 400.31797 -436.23738)
			(xy 400.305856 -436.236914) (xy 400.282814 -436.229421) (xy 400.263215 -436.215177) (xy 400.248974 -436.195575)
			(xy 400.241484 -436.172532) (xy 400.241008 -436.160418) (xy 399.307616 -436.160418) (xy 399.312582 -436.164026)
			(xy 399.326833 -436.183647) (xy 399.334319 -436.206713) (xy 399.334736 -436.218838) (xy 399.334736 -438.760362)
			(xy 399.334307 -438.772485) (xy 399.326822 -438.795547) (xy 399.312574 -438.815165) (xy 399.292958 -438.829417)
			(xy 399.269897 -438.836905) (xy 399.257774 -438.837324) (xy 398.317974 -438.837324) (xy 398.305846 -438.836962)
			(xy 398.28278 -438.829458) (xy 398.263162 -438.815192) (xy 398.248913 -438.795563) (xy 398.241428 -438.77249)
			(xy 398.241012 -438.760362) (xy 396.334488 -438.760362) (xy 396.334488 -439.76036) (xy 400.241008 -439.76036)
			(xy 400.241008 -437.218836) (xy 400.241447 -437.206728) (xy 400.248938 -437.183701) (xy 400.263193 -437.164126)
			(xy 400.282811 -437.149931) (xy 400.305861 -437.142511) (xy 400.31797 -437.142128) (xy 401.25777 -437.142128)
			(xy 401.269857 -437.142633) (xy 401.292854 -437.15008) (xy 401.312434 -437.164257) (xy 401.326686 -437.183782)
			(xy 401.334221 -437.206751) (xy 401.334732 -437.218836) (xy 401.334732 -438.760362) (xy 402.241004 -438.760362)
			(xy 402.241004 -436.218838) (xy 402.241492 -436.206721) (xy 402.248969 -436.183669) (xy 402.263205 -436.164056)
			(xy 402.282804 -436.149802) (xy 402.305849 -436.142303) (xy 402.317966 -436.141876) (xy 403.257766 -436.141876)
			(xy 403.269891 -436.142289) (xy 403.292955 -436.149777) (xy 403.307603 -436.160418) (xy 404.241 -436.160418)
			(xy 404.241 -433.618894) (xy 404.241506 -433.606783) (xy 404.24899 -433.583746) (xy 404.263225 -433.564148)
			(xy 404.282817 -433.549905) (xy 404.305851 -433.542411) (xy 404.317962 -433.541932) (xy 405.257762 -433.541932)
			(xy 405.269882 -433.542392) (xy 405.292939 -433.549873) (xy 405.312554 -433.564115) (xy 405.326807 -433.583722)
			(xy 405.334301 -433.606774) (xy 405.334724 -433.618894) (xy 405.334724 -435.16042) (xy 406.240996 -435.16042)
			(xy 406.240996 -432.618896) (xy 406.241413 -432.606787) (xy 406.248913 -432.583761) (xy 406.263174 -432.564188)
			(xy 406.282796 -432.549993) (xy 406.305848 -432.542572) (xy 406.317958 -432.542188) (xy 407.257758 -432.542188)
			(xy 407.26985 -432.542644) (xy 407.292858 -432.550095) (xy 407.307187 -432.560476) (xy 408.2415 -432.560476)
			(xy 408.2415 -430.018952) (xy 408.241876 -430.006841) (xy 408.249388 -429.983812) (xy 408.26366 -429.96424)
			(xy 408.28329 -429.950047) (xy 408.306349 -429.942627) (xy 408.318462 -429.942244) (xy 409.258262 -429.942244)
			(xy 409.27035 -429.94274) (xy 409.29335 -429.950187) (xy 409.312931 -429.964366) (xy 409.327183 -429.983894)
			(xy 409.334715 -430.006866) (xy 409.335224 -430.018952) (xy 409.335224 -431.560478) (xy 410.241496 -431.560478)
			(xy 410.241496 -429.018954) (xy 410.241972 -429.006841) (xy 410.249467 -428.983804) (xy 410.263709 -428.964206)
			(xy 410.283307 -428.949965) (xy 410.306345 -428.942471) (xy 410.318458 -428.941992) (xy 411.258258 -428.941992)
			(xy 411.270366 -428.942547) (xy 411.2934 -428.950017) (xy 411.307542 -428.96028) (xy 412.241492 -428.96028)
			(xy 412.241492 -428.233078) (xy 412.241745 -428.224321) (xy 412.245723 -428.207264) (xy 412.249366 -428.199296)
			(xy 412.482792 -427.723046) (xy 412.487519 -427.712539) (xy 412.491 -427.689775) (xy 412.487504 -427.667012)
			(xy 412.482792 -427.656498) (xy 412.249366 -427.180248) (xy 412.245717 -427.172282) (xy 412.241733 -427.155224)
			(xy 412.241492 -427.146466) (xy 412.241492 -426.418756) (xy 412.241927 -426.406679) (xy 412.249401 -426.38371)
			(xy 412.263605 -426.364174) (xy 412.28315 -426.349981) (xy 412.306123 -426.34252) (xy 412.3182 -426.342048)
			(xy 413.258 -426.342048) (xy 413.27007 -426.342564) (xy 413.29303 -426.350021) (xy 413.312563 -426.364206)
			(xy 413.326759 -426.383731) (xy 413.334229 -426.406686) (xy 413.334708 -426.418756) (xy 413.334708 -428.96028)
			(xy 413.33427 -428.972362) (xy 413.326808 -428.995344) (xy 413.312608 -429.014894) (xy 413.293062 -429.029099)
			(xy 413.270082 -429.036567) (xy 413.258 -429.036988) (xy 412.3182 -429.036988) (xy 412.306115 -429.036587)
			(xy 412.283129 -429.029117) (xy 412.263577 -429.014909) (xy 412.249374 -428.995353) (xy 412.24191 -428.972365)
			(xy 412.241492 -428.96028) (xy 411.307542 -428.96028) (xy 411.312998 -428.964239) (xy 411.327243 -428.983821)
			(xy 411.334739 -429.006847) (xy 411.33522 -429.018954) (xy 411.33522 -431.560478) (xy 411.334821 -431.572604)
			(xy 411.327329 -431.595669) (xy 411.313074 -431.615288) (xy 411.293451 -431.629538) (xy 411.270384 -431.637024)
			(xy 411.258258 -431.63744) (xy 410.318458 -431.63744) (xy 410.306339 -431.637024) (xy 410.283291 -431.629522)
			(xy 410.263688 -431.615267) (xy 410.249448 -431.595652) (xy 410.241966 -431.572597) (xy 410.241496 -431.560478)
			(xy 409.335224 -431.560478) (xy 409.335224 -432.560476) (xy 409.334763 -432.572581) (xy 409.327274 -432.595604)
			(xy 409.313023 -432.615175) (xy 409.293412 -432.629371) (xy 409.270368 -432.636797) (xy 409.258262 -432.637184)
			(xy 408.318462 -432.637184) (xy 408.306373 -432.636726) (xy 408.283375 -432.629261) (xy 408.263798 -432.615072)
			(xy 408.249548 -432.595538) (xy 408.242012 -432.572564) (xy 408.2415 -432.560476) (xy 407.307187 -432.560476)
			(xy 407.312442 -432.564283) (xy 407.326693 -432.583822) (xy 407.334217 -432.606805) (xy 407.33472 -432.618896)
			(xy 407.33472 -435.16042) (xy 407.334301 -435.172528) (xy 407.326799 -435.195552) (xy 407.312537 -435.215123)
			(xy 407.292917 -435.229318) (xy 407.269867 -435.236742) (xy 407.257758 -435.237128) (xy 406.317958 -435.237128)
			(xy 406.305863 -435.236728) (xy 406.282856 -435.229256) (xy 406.263274 -435.215053) (xy 406.249026 -435.195504)
			(xy 406.2415 -435.172514) (xy 406.240996 -435.16042) (xy 405.334724 -435.16042) (xy 405.334724 -436.160418)
			(xy 405.334355 -436.172545) (xy 405.326853 -436.195611) (xy 405.312589 -436.215229) (xy 405.292961 -436.229478)
			(xy 405.26989 -436.236963) (xy 405.257762 -436.23738) (xy 404.317962 -436.23738) (xy 404.305847 -436.236921)
			(xy 404.282806 -436.229425) (xy 404.263206 -436.21518) (xy 404.248965 -436.195576) (xy 404.241476 -436.172533)
			(xy 404.241 -436.160418) (xy 403.307603 -436.160418) (xy 403.312574 -436.164029) (xy 403.326825 -436.183649)
			(xy 403.334311 -436.206713) (xy 403.334728 -436.218838) (xy 403.334728 -438.760362) (xy 403.334307 -438.772486)
			(xy 403.326821 -438.79555) (xy 403.312571 -438.815168) (xy 403.292953 -438.829419) (xy 403.26989 -438.836907)
			(xy 403.257766 -438.837324) (xy 402.317966 -438.837324) (xy 402.305838 -438.836969) (xy 402.282771 -438.829462)
			(xy 402.263153 -438.815195) (xy 402.248905 -438.795564) (xy 402.24142 -438.772491) (xy 402.241004 -438.760362)
			(xy 401.334732 -438.760362) (xy 401.334732 -439.76036) (xy 404.241 -439.76036) (xy 404.241 -437.218836)
			(xy 404.241447 -437.206729) (xy 404.248937 -437.183703) (xy 404.26319 -437.164129) (xy 404.282806 -437.149933)
			(xy 404.305854 -437.142512) (xy 404.317962 -437.142128) (xy 405.257762 -437.142128) (xy 405.269848 -437.14264)
			(xy 405.292846 -437.150084) (xy 405.312425 -437.16426) (xy 405.326678 -437.183784) (xy 405.334213 -437.206752)
			(xy 405.334724 -437.218836) (xy 405.334724 -438.760362) (xy 406.240996 -438.760362) (xy 406.240996 -436.218838)
			(xy 406.241543 -436.20673) (xy 406.249015 -436.183695) (xy 406.263239 -436.164096) (xy 406.282823 -436.149852)
			(xy 406.30585 -436.142356) (xy 406.317958 -436.141876) (xy 407.257758 -436.141876) (xy 407.269882 -436.142296)
			(xy 407.292946 -436.149782) (xy 407.307589 -436.160418) (xy 408.240992 -436.160418) (xy 408.240992 -433.618894)
			(xy 408.241506 -433.606784) (xy 408.248989 -433.583748) (xy 408.263222 -433.564151) (xy 408.282812 -433.549908)
			(xy 408.305844 -433.542412) (xy 408.317954 -433.541932) (xy 409.257754 -433.541932) (xy 409.269874 -433.542399)
			(xy 409.29293 -433.549878) (xy 409.312546 -433.564117) (xy 409.326798 -433.583723) (xy 409.334293 -433.606775)
			(xy 409.334716 -433.618894) (xy 409.334716 -435.16042) (xy 410.240988 -435.16042) (xy 410.240988 -432.618896)
			(xy 410.241413 -432.606788) (xy 410.248912 -432.583763) (xy 410.263172 -432.564191) (xy 410.282791 -432.549996)
			(xy 410.305841 -432.542573) (xy 410.31795 -432.542188) (xy 411.25775 -432.542188) (xy 411.269842 -432.542651)
			(xy 411.292849 -432.5501) (xy 411.307175 -432.560476) (xy 412.241492 -432.560476) (xy 412.241492 -430.018952)
			(xy 412.241875 -430.006841) (xy 412.249387 -429.983814) (xy 412.263658 -429.964242) (xy 412.283285 -429.950049)
			(xy 412.306342 -429.942628) (xy 412.318454 -429.942244) (xy 413.258254 -429.942244) (xy 413.270342 -429.942747)
			(xy 413.293341 -429.950191) (xy 413.312922 -429.964368) (xy 413.327174 -429.983895) (xy 413.334707 -430.006866)
			(xy 413.335216 -430.018952) (xy 413.335216 -432.560476) (xy 413.334763 -432.572582) (xy 413.327272 -432.595606)
			(xy 413.31302 -432.615178) (xy 413.293406 -432.629374) (xy 413.270361 -432.636798) (xy 413.258254 -432.637184)
			(xy 412.318454 -432.637184) (xy 412.306364 -432.636732) (xy 412.283366 -432.629266) (xy 412.263789 -432.615074)
			(xy 412.249539 -432.59554) (xy 412.242004 -432.572564) (xy 412.241492 -432.560476) (xy 411.307175 -432.560476)
			(xy 411.312434 -432.564285) (xy 411.326684 -432.583823) (xy 411.334209 -432.606806) (xy 411.334712 -432.618896)
			(xy 411.334712 -435.16042) (xy 411.334301 -435.172529) (xy 411.326797 -435.195555) (xy 411.312534 -435.215126)
			(xy 411.292912 -435.229321) (xy 411.26986 -435.236743) (xy 411.25775 -435.237128) (xy 410.31795 -435.237128)
			(xy 410.30586 -435.23665) (xy 410.282855 -435.229203) (xy 410.263272 -435.21502) (xy 410.249021 -435.195487)
			(xy 410.241493 -435.172508) (xy 410.240988 -435.16042) (xy 409.334716 -435.16042) (xy 409.334716 -436.160418)
			(xy 409.334354 -436.172546) (xy 409.326852 -436.195613) (xy 409.312586 -436.215232) (xy 409.292956 -436.229481)
			(xy 409.269883 -436.236965) (xy 409.257754 -436.23738) (xy 408.317954 -436.23738) (xy 408.305839 -436.236928)
			(xy 408.282797 -436.22943) (xy 408.263198 -436.215182) (xy 408.248957 -436.195578) (xy 408.241468 -436.172533)
			(xy 408.240992 -436.160418) (xy 407.307589 -436.160418) (xy 407.312565 -436.164032) (xy 407.326817 -436.18365)
			(xy 407.334303 -436.206714) (xy 407.33472 -436.218838) (xy 407.33472 -438.760362) (xy 407.334307 -438.772487)
			(xy 407.32682 -438.795552) (xy 407.312568 -438.815171) (xy 407.292948 -438.829422) (xy 407.269883 -438.836908)
			(xy 407.257758 -438.837324) (xy 406.317958 -438.837324) (xy 406.305837 -438.836923) (xy 406.282786 -438.82942)
			(xy 406.263182 -438.815161) (xy 406.248943 -438.795542) (xy 406.241464 -438.772483) (xy 406.240996 -438.760362)
			(xy 405.334724 -438.760362) (xy 405.334724 -439.76036) (xy 408.240992 -439.76036) (xy 408.240992 -437.218836)
			(xy 408.241447 -437.20673) (xy 408.248935 -437.183705) (xy 408.263187 -437.164132) (xy 408.282801 -437.149936)
			(xy 408.305847 -437.142513) (xy 408.317954 -437.142128) (xy 409.257754 -437.142128) (xy 409.26984 -437.142646)
			(xy 409.292837 -437.150089) (xy 409.312417 -437.164263) (xy 409.326669 -437.183785) (xy 409.334205 -437.206752)
			(xy 409.334716 -437.218836) (xy 409.334716 -438.760362) (xy 410.240988 -438.760362) (xy 410.240988 -436.218838)
			(xy 410.241543 -436.20673) (xy 410.249014 -436.183697) (xy 410.263236 -436.164099) (xy 410.282818 -436.149854)
			(xy 410.305843 -436.142357) (xy 410.31795 -436.141876) (xy 411.25775 -436.141876) (xy 411.269871 -436.14227)
			(xy 411.292922 -436.149775) (xy 411.307552 -436.160418) (xy 412.240984 -436.160418) (xy 412.240984 -433.618894)
			(xy 412.241356 -433.606766) (xy 412.248855 -433.5837) (xy 412.263118 -433.564081) (xy 412.282746 -433.549831)
			(xy 412.305818 -433.542348) (xy 412.317946 -433.541932) (xy 413.257746 -433.541932) (xy 413.269862 -433.542372)
			(xy 413.292906 -433.549872) (xy 413.312507 -433.564122) (xy 413.326747 -433.58373) (xy 413.334234 -433.606777)
			(xy 413.334708 -433.618894) (xy 413.334708 -435.59984) (xy 446.741306 -435.59984) (xy 446.745288 -435.471854)
			(xy 446.75722 -435.344363) (xy 446.777054 -435.21786) (xy 446.804715 -435.092835) (xy 446.840095 -434.969772)
			(xy 446.883057 -434.849146) (xy 446.933435 -434.731425) (xy 446.991035 -434.617063) (xy 447.055633 -434.506504)
			(xy 447.12698 -434.400174) (xy 447.204799 -434.298486) (xy 447.288789 -434.201832) (xy 447.378626 -434.110587)
			(xy 447.473962 -434.025104) (xy 447.574427 -433.945713) (xy 447.679635 -433.872721) (xy 447.789176 -433.806412)
			(xy 447.902628 -433.747041) (xy 448.019552 -433.694837) (xy 448.139495 -433.650004) (xy 448.261993 -433.612715)
			(xy 448.386573 -433.583113) (xy 448.512751 -433.561314) (xy 448.640041 -433.547401) (xy 448.76795 -433.541429)
			(xy 448.895983 -433.54342) (xy 449.023644 -433.553368) (xy 449.15044 -433.571232) (xy 449.275879 -433.596945)
			(xy 449.399478 -433.630407) (xy 449.520757 -433.671488) (xy 449.639248 -433.72003) (xy 449.754492 -433.775844)
			(xy 449.866042 -433.838715) (xy 449.973469 -433.908399) (xy 450.076355 -433.984627) (xy 450.174303 -434.067104)
			(xy 450.266934 -434.155511) (xy 450.35389 -434.249506) (xy 450.434834 -434.348725) (xy 450.509453 -434.452784)
			(xy 450.577458 -434.561281) (xy 450.638586 -434.673796) (xy 450.692601 -434.789894) (xy 450.739294 -434.909125)
			(xy 450.778484 -435.031029) (xy 450.81002 -435.155133) (xy 450.833779 -435.280957) (xy 450.849669 -435.408016)
			(xy 450.85763 -435.535816) (xy 450.858128 -435.59984) (xy 450.85763 -435.663864) (xy 450.849669 -435.791664)
			(xy 450.833779 -435.918723) (xy 450.81002 -436.044547) (xy 450.778484 -436.168651) (xy 450.739294 -436.290555)
			(xy 450.692601 -436.409786) (xy 450.638586 -436.525884) (xy 450.577458 -436.638399) (xy 450.509453 -436.746896)
			(xy 450.434834 -436.850955) (xy 450.35389 -436.950174) (xy 450.266934 -437.044169) (xy 450.174303 -437.132576)
			(xy 450.076355 -437.215053) (xy 449.973469 -437.291281) (xy 449.866042 -437.360965) (xy 449.754492 -437.423836)
			(xy 449.639248 -437.47965) (xy 449.520757 -437.528192) (xy 449.399478 -437.569273) (xy 449.275879 -437.602735)
			(xy 449.15044 -437.628448) (xy 449.023644 -437.646312) (xy 448.895983 -437.65626) (xy 448.76795 -437.658251)
			(xy 448.640041 -437.652279) (xy 448.512751 -437.638366) (xy 448.386573 -437.616567) (xy 448.261993 -437.586965)
			(xy 448.139495 -437.549676) (xy 448.019552 -437.504843) (xy 447.902628 -437.452639) (xy 447.789176 -437.393268)
			(xy 447.679635 -437.326959) (xy 447.574427 -437.253967) (xy 447.473962 -437.174576) (xy 447.378626 -437.089093)
			(xy 447.288789 -436.997848) (xy 447.204799 -436.901194) (xy 447.12698 -436.799506) (xy 447.055633 -436.693176)
			(xy 446.991035 -436.582617) (xy 446.933435 -436.468255) (xy 446.883057 -436.350534) (xy 446.840095 -436.229908)
			(xy 446.804715 -436.106845) (xy 446.777054 -435.98182) (xy 446.75722 -435.855317) (xy 446.745288 -435.727826)
			(xy 446.741306 -435.59984) (xy 413.334708 -435.59984) (xy 413.334708 -436.160418) (xy 413.334205 -436.172529)
			(xy 413.326718 -436.195565) (xy 413.312482 -436.215163) (xy 413.29289 -436.229405) (xy 413.269857 -436.2369)
			(xy 413.257746 -436.23738) (xy 412.317946 -436.23738) (xy 412.305827 -436.236901) (xy 412.282773 -436.229424)
			(xy 412.263159 -436.215187) (xy 412.248905 -436.195584) (xy 412.241409 -436.172536) (xy 412.240984 -436.160418)
			(xy 411.307552 -436.160418) (xy 411.312526 -436.164036) (xy 411.326765 -436.183657) (xy 411.334244 -436.206717)
			(xy 411.334712 -436.218838) (xy 411.334712 -438.760362) (xy 411.334157 -438.77247) (xy 411.326686 -438.795503)
			(xy 411.312464 -438.815101) (xy 411.292882 -438.829346) (xy 411.269857 -438.836843) (xy 411.25775 -438.837324)
			(xy 410.31795 -438.837324) (xy 410.305829 -438.83693) (xy 410.282778 -438.829425) (xy 410.263174 -438.815164)
			(xy 410.248935 -438.795543) (xy 410.241456 -438.772483) (xy 410.240988 -438.760362) (xy 409.334716 -438.760362)
			(xy 409.334716 -439.76036) (xy 412.240984 -439.76036) (xy 412.240984 -437.218836) (xy 412.241447 -437.206731)
			(xy 412.248934 -437.183707) (xy 412.263184 -437.164135) (xy 412.282796 -437.149939) (xy 412.30584 -437.142514)
			(xy 412.317946 -437.142128) (xy 413.257746 -437.142128) (xy 413.269837 -437.142568) (xy 413.292837 -437.150036)
			(xy 413.312415 -437.16423) (xy 413.326664 -437.183768) (xy 413.334197 -437.206747) (xy 413.334708 -437.218836)
			(xy 413.334708 -439.76036) (xy 413.33425 -439.772466) (xy 413.326762 -439.795491) (xy 413.312511 -439.815064)
			(xy 413.292899 -439.82926) (xy 413.269853 -439.836683) (xy 413.257746 -439.837068) (xy 412.317946 -439.837068)
			(xy 412.30586 -439.836554) (xy 412.282862 -439.829111) (xy 412.263282 -439.814936) (xy 412.249029 -439.795412)
			(xy 412.241495 -439.772444) (xy 412.240984 -439.76036) (xy 409.334716 -439.76036) (xy 409.33425 -439.772465)
			(xy 409.326763 -439.795488) (xy 409.312514 -439.815061) (xy 409.292904 -439.829257) (xy 409.26986 -439.836682)
			(xy 409.257754 -439.837068) (xy 408.317954 -439.837068) (xy 408.305863 -439.836632) (xy 408.282862 -439.829164)
			(xy 408.263284 -439.814969) (xy 408.249034 -439.79543) (xy 408.241502 -439.77245) (xy 408.240992 -439.76036)
			(xy 405.334724 -439.76036) (xy 405.33425 -439.772464) (xy 405.326764 -439.795486) (xy 405.312517 -439.815058)
			(xy 405.292909 -439.829255) (xy 405.269867 -439.836681) (xy 405.257762 -439.837068) (xy 404.317962 -439.837068)
			(xy 404.305871 -439.836625) (xy 404.282871 -439.829159) (xy 404.263292 -439.814966) (xy 404.249043 -439.795428)
			(xy 404.24151 -439.772449) (xy 404.241 -439.76036) (xy 401.334732 -439.76036) (xy 401.33425 -439.772464)
			(xy 401.326765 -439.795484) (xy 401.31252 -439.815055) (xy 401.292914 -439.829252) (xy 401.269875 -439.83668)
			(xy 401.25777 -439.837068) (xy 400.31797 -439.837068) (xy 400.30588 -439.836618) (xy 400.282879 -439.829154)
			(xy 400.263301 -439.814963) (xy 400.249051 -439.795427) (xy 400.241518 -439.772449) (xy 400.241008 -439.76036)
			(xy 396.334488 -439.76036) (xy 396.334053 -439.772443) (xy 396.326594 -439.795427) (xy 396.312394 -439.81498)
			(xy 396.292845 -439.829185) (xy 396.269863 -439.83665) (xy 396.25778 -439.837068) (xy 395.31798 -439.837068)
			(xy 395.305892 -439.836704) (xy 395.282902 -439.829226) (xy 395.263349 -439.815009) (xy 395.249147 -439.795444)
			(xy 395.241687 -439.772448) (xy 395.241272 -439.76036) (xy 392.334496 -439.76036) (xy 392.334053 -439.772442)
			(xy 392.326595 -439.795425) (xy 392.312397 -439.814977) (xy 392.29285 -439.829182) (xy 392.26987 -439.836649)
			(xy 392.257788 -439.837068) (xy 391.317988 -439.837068) (xy 391.305901 -439.836697) (xy 391.282911 -439.829221)
			(xy 391.263357 -439.815006) (xy 391.249155 -439.795443) (xy 391.241695 -439.772448) (xy 391.24128 -439.76036)
			(xy 388.334504 -439.76036) (xy 388.334053 -439.772441) (xy 388.326596 -439.795423) (xy 388.3124 -439.814974)
			(xy 388.292855 -439.82918) (xy 388.269877 -439.836648) (xy 388.257796 -439.837068) (xy 387.317996 -439.837068)
			(xy 387.305909 -439.83669) (xy 387.282919 -439.829217) (xy 387.263366 -439.815003) (xy 387.249163 -439.795441)
			(xy 387.241703 -439.772447) (xy 387.241288 -439.76036) (xy 384.334512 -439.76036) (xy 384.334053 -439.77244)
			(xy 384.326597 -439.795421) (xy 384.312403 -439.814972) (xy 384.29286 -439.829177) (xy 384.269884 -439.836646)
			(xy 384.257804 -439.837068) (xy 383.318004 -439.837068) (xy 383.305917 -439.836684) (xy 383.282928 -439.829212)
			(xy 383.263374 -439.815) (xy 383.249171 -439.79544) (xy 383.241711 -439.772447) (xy 383.241296 -439.76036)
			(xy 346.234512 -439.76036) (xy 346.234512 -439.760614) (xy 346.234104 -439.772709) (xy 346.226638 -439.795718)
			(xy 346.212437 -439.815302) (xy 346.192889 -439.829551) (xy 346.169898 -439.837074) (xy 346.157804 -439.837576)
			(xy 345.218004 -439.837576) (xy 345.205893 -439.83718) (xy 345.182862 -439.829679) (xy 345.163286 -439.815413)
			(xy 345.149092 -439.795785) (xy 345.141676 -439.772727) (xy 345.141296 -439.760614) (xy 342.23452 -439.760614)
			(xy 342.234104 -439.772708) (xy 342.226639 -439.795716) (xy 342.21244 -439.815299) (xy 342.192894 -439.829548)
			(xy 342.169905 -439.837073) (xy 342.157812 -439.837576) (xy 341.218012 -439.837576) (xy 341.205901 -439.837173)
			(xy 341.18287 -439.829674) (xy 341.163295 -439.81541) (xy 341.149101 -439.795784) (xy 341.141684 -439.772726)
			(xy 341.141304 -439.760614) (xy 338.234528 -439.760614) (xy 338.234104 -439.772708) (xy 338.22664 -439.795714)
			(xy 338.212443 -439.815297) (xy 338.192899 -439.829546) (xy 338.169912 -439.837072) (xy 338.15782 -439.837576)
			(xy 337.21802 -439.837576) (xy 337.20591 -439.837166) (xy 337.182879 -439.829669) (xy 337.163304 -439.815407)
			(xy 337.149109 -439.795782) (xy 337.141692 -439.772726) (xy 337.141312 -439.760614) (xy 334.234536 -439.760614)
			(xy 334.234104 -439.772707) (xy 334.226641 -439.795712) (xy 334.212446 -439.815294) (xy 334.192904 -439.829543)
			(xy 334.169919 -439.83707) (xy 334.157828 -439.837576) (xy 333.218028 -439.837576) (xy 333.205918 -439.837159)
			(xy 333.182888 -439.829665) (xy 333.163312 -439.815404) (xy 333.149117 -439.795781) (xy 333.1417 -439.772725)
			(xy 333.14132 -439.760614) (xy 329.2348 -439.760614) (xy 329.234301 -439.772726) (xy 329.226815 -439.795763)
			(xy 329.212578 -439.815361) (xy 329.192984 -439.829604) (xy 329.169949 -439.837097) (xy 329.157838 -439.837576)
			(xy 328.218038 -439.837576) (xy 328.205919 -439.837108) (xy 328.182863 -439.829628) (xy 328.163249 -439.815388)
			(xy 328.148996 -439.795783) (xy 328.1415 -439.772733) (xy 328.141076 -439.760614) (xy 325.234808 -439.760614)
			(xy 325.234301 -439.772725) (xy 325.226816 -439.795761) (xy 325.212581 -439.815358) (xy 325.192989 -439.829601)
			(xy 325.169957 -439.837096) (xy 325.157846 -439.837576) (xy 324.218046 -439.837576) (xy 324.205927 -439.837101)
			(xy 324.182872 -439.829623) (xy 324.163257 -439.815385) (xy 324.149004 -439.795782) (xy 324.141508 -439.772733)
			(xy 324.141084 -439.760614) (xy 321.234816 -439.760614) (xy 321.234451 -439.772742) (xy 321.226949 -439.795809)
			(xy 321.212685 -439.815428) (xy 321.193055 -439.829677) (xy 321.169982 -439.83716) (xy 321.157854 -439.837576)
			(xy 320.218054 -439.837576) (xy 320.205938 -439.837128) (xy 320.182896 -439.82963) (xy 320.163296 -439.815381)
			(xy 320.149056 -439.795775) (xy 320.141567 -439.77273) (xy 320.141092 -439.760614) (xy 317.234824 -439.760614)
			(xy 317.234451 -439.772741) (xy 317.22695 -439.795807) (xy 317.212688 -439.815425) (xy 317.19306 -439.829674)
			(xy 317.16999 -439.837159) (xy 317.157862 -439.837576) (xy 316.218062 -439.837576) (xy 316.205947 -439.837121)
			(xy 316.182905 -439.829625) (xy 316.163305 -439.815378) (xy 316.149064 -439.795774) (xy 316.141575 -439.772729)
			(xy 316.1411 -439.760614) (xy 157.334702 -439.760614) (xy 157.33425 -439.772466) (xy 157.326763 -439.79549)
			(xy 157.312513 -439.815062) (xy 157.292901 -439.829259) (xy 157.269857 -439.836682) (xy 157.25775 -439.837068)
			(xy 156.31795 -439.837068) (xy 156.305864 -439.83655) (xy 156.282866 -439.829108) (xy 156.263286 -439.814935)
			(xy 156.249033 -439.795412) (xy 156.241499 -439.772444) (xy 156.240988 -439.76036) (xy 153.33472 -439.76036)
			(xy 153.33425 -439.772465) (xy 153.326764 -439.795487) (xy 153.312516 -439.815059) (xy 153.292906 -439.829256)
			(xy 153.269864 -439.836681) (xy 153.257758 -439.837068) (xy 152.317958 -439.837068) (xy 152.305867 -439.836629)
			(xy 152.282866 -439.829161) (xy 152.263288 -439.814967) (xy 152.249038 -439.795429) (xy 152.241506 -439.77245)
			(xy 152.240996 -439.76036) (xy 149.334728 -439.76036) (xy 149.33425 -439.772464) (xy 149.326765 -439.795485)
			(xy 149.312518 -439.815057) (xy 149.292911 -439.829254) (xy 149.269871 -439.83668) (xy 149.257766 -439.837068)
			(xy 148.317966 -439.837068) (xy 148.305875 -439.836622) (xy 148.282875 -439.829157) (xy 148.263296 -439.814964)
			(xy 148.249047 -439.795428) (xy 148.241514 -439.772449) (xy 148.241004 -439.76036) (xy 145.334736 -439.76036)
			(xy 145.33425 -439.772463) (xy 145.326766 -439.795483) (xy 145.312521 -439.815054) (xy 145.292916 -439.829251)
			(xy 145.269878 -439.836679) (xy 145.257774 -439.837068) (xy 144.317974 -439.837068) (xy 144.305884 -439.836615)
			(xy 144.282884 -439.829152) (xy 144.263305 -439.814962) (xy 144.249055 -439.795426) (xy 144.241522 -439.772449)
			(xy 144.241012 -439.76036) (xy 140.334492 -439.76036) (xy 140.334053 -439.772442) (xy 140.326595 -439.795426)
			(xy 140.312396 -439.814979) (xy 140.292848 -439.829184) (xy 140.269866 -439.836649) (xy 140.257784 -439.837068)
			(xy 139.317984 -439.837068) (xy 139.305896 -439.8367) (xy 139.282906 -439.829224) (xy 139.263353 -439.815007)
			(xy 139.249151 -439.795443) (xy 139.241691 -439.772448) (xy 139.241276 -439.76036) (xy 136.3345 -439.76036)
			(xy 136.334053 -439.772441) (xy 136.326596 -439.795424) (xy 136.312399 -439.814976) (xy 136.292853 -439.829181)
			(xy 136.269873 -439.836648) (xy 136.257792 -439.837068) (xy 135.317992 -439.837068) (xy 135.305905 -439.836694)
			(xy 135.282915 -439.829219) (xy 135.263361 -439.815004) (xy 135.249159 -439.795442) (xy 135.241699 -439.772447)
			(xy 135.241284 -439.76036) (xy 132.334508 -439.76036) (xy 132.334053 -439.772441) (xy 132.326597 -439.795422)
			(xy 132.312401 -439.814973) (xy 132.292858 -439.829178) (xy 132.26988 -439.836647) (xy 132.2578 -439.837068)
			(xy 131.318 -439.837068) (xy 131.305913 -439.836687) (xy 131.282924 -439.829215) (xy 131.26337 -439.815002)
			(xy 131.249167 -439.79544) (xy 131.241707 -439.772447) (xy 131.241292 -439.76036) (xy 128.334516 -439.76036)
			(xy 128.334053 -439.77244) (xy 128.326598 -439.79542) (xy 128.312404 -439.81497) (xy 128.292863 -439.829176)
			(xy 128.269888 -439.836646) (xy 128.257808 -439.837068) (xy 127.318008 -439.837068) (xy 127.305922 -439.83668)
			(xy 127.282932 -439.82921) (xy 127.263378 -439.814999) (xy 127.249175 -439.795439) (xy 127.241715 -439.772447)
			(xy 127.2413 -439.76036) (xy 90.234516 -439.76036) (xy 90.234516 -439.760614) (xy 90.234104 -439.772709)
			(xy 90.226638 -439.795717) (xy 90.212439 -439.815301) (xy 90.192891 -439.829549) (xy 90.169901 -439.837073)
			(xy 90.157808 -439.837576) (xy 89.218008 -439.837576) (xy 89.205897 -439.837177) (xy 89.182866 -439.829677)
			(xy 89.163291 -439.815412) (xy 89.149096 -439.795785) (xy 89.14168 -439.772726) (xy 89.1413 -439.760614)
			(xy 86.234524 -439.760614) (xy 86.234104 -439.772708) (xy 86.226639 -439.795715) (xy 86.212442 -439.815298)
			(xy 86.192896 -439.829547) (xy 86.169909 -439.837072) (xy 86.157816 -439.837576) (xy 85.218016 -439.837576)
			(xy 85.205906 -439.83717) (xy 85.182875 -439.829672) (xy 85.163299 -439.815408) (xy 85.149105 -439.795783)
			(xy 85.141688 -439.772726) (xy 85.141308 -439.760614) (xy 82.234532 -439.760614) (xy 82.234104 -439.772707)
			(xy 82.22664 -439.795713) (xy 82.212445 -439.815295) (xy 82.192901 -439.829544) (xy 82.169916 -439.837071)
			(xy 82.157824 -439.837576) (xy 81.218024 -439.837576) (xy 81.205914 -439.837163) (xy 81.182883 -439.829667)
			(xy 81.163308 -439.815406) (xy 81.149113 -439.795781) (xy 81.141696 -439.772725) (xy 81.141316 -439.760614)
			(xy 78.23454 -439.760614) (xy 78.234104 -439.772706) (xy 78.226641 -439.795711) (xy 78.212447 -439.815292)
			(xy 78.192906 -439.829542) (xy 78.169923 -439.83707) (xy 78.157832 -439.837576) (xy 77.218032 -439.837576)
			(xy 77.205922 -439.837156) (xy 77.182892 -439.829663) (xy 77.163316 -439.815403) (xy 77.149122 -439.79578)
			(xy 77.141704 -439.772725) (xy 77.141324 -439.760614) (xy 73.234804 -439.760614) (xy 73.234301 -439.772725)
			(xy 73.226815 -439.795762) (xy 73.21258 -439.81536) (xy 73.192987 -439.829602) (xy 73.169953 -439.837097)
			(xy 73.157842 -439.837576) (xy 72.218042 -439.837576) (xy 72.205923 -439.837105) (xy 72.182868 -439.829626)
			(xy 72.163253 -439.815387) (xy 72.149 -439.795783) (xy 72.141504 -439.772733) (xy 72.14108 -439.760614)
			(xy 69.234812 -439.760614) (xy 69.234301 -439.772724) (xy 69.226816 -439.79576) (xy 69.212582 -439.815357)
			(xy 69.192992 -439.8296) (xy 69.16996 -439.837096) (xy 69.15785 -439.837576) (xy 68.21805 -439.837576)
			(xy 68.205934 -439.837131) (xy 68.182892 -439.829632) (xy 68.163292 -439.815382) (xy 68.149052 -439.795776)
			(xy 68.141563 -439.77273) (xy 68.141088 -439.760614) (xy 65.23482 -439.760614) (xy 65.234451 -439.772742)
			(xy 65.22695 -439.795808) (xy 65.212686 -439.815426) (xy 65.193058 -439.829675) (xy 65.169986 -439.83716)
			(xy 65.157858 -439.837576) (xy 64.218058 -439.837576) (xy 64.205943 -439.837124) (xy 64.1829 -439.829627)
			(xy 64.163301 -439.815379) (xy 64.14906 -439.795774) (xy 64.141571 -439.77273) (xy 64.141096 -439.760614)
			(xy 61.234828 -439.760614) (xy 61.234451 -439.772741) (xy 61.226951 -439.795806) (xy 61.212689 -439.815424)
			(xy 61.193063 -439.829673) (xy 61.169993 -439.837159) (xy 61.157866 -439.837576) (xy 60.218066 -439.837576)
			(xy 60.205951 -439.837118) (xy 60.182909 -439.829623) (xy 60.163309 -439.815377) (xy 60.149068 -439.795773)
			(xy 60.141579 -439.772729) (xy 60.141104 -439.760614) (xy 7.00913 -439.760614) (xy 7.00913 -439.989976)
			(xy 7.009638 -440.045746) (xy 7.017973 -440.156973) (xy 7.034597 -440.267266) (xy 7.059417 -440.376009)
			(xy 7.092293 -440.482593) (xy 7.133043 -440.586422) (xy 7.181438 -440.686915) (xy 7.237207 -440.783511)
			(xy 7.300039 -440.87567) (xy 7.369583 -440.962874) (xy 7.445449 -441.044639) (xy 7.527212 -441.120505)
			(xy 7.614417 -441.190048) (xy 7.706575 -441.252881) (xy 7.803171 -441.30865) (xy 7.903664 -441.357045)
			(xy 8.007493 -441.397795) (xy 8.114077 -441.430672) (xy 8.22282 -441.455492) (xy 8.333113 -441.472116)
			(xy 8.44434 -441.480451) (xy 8.50011 -441.480956)
		)
		(stroke
			(width 0)
			(type solid)
		)
		(fill yes)
		(layer "In7.Cu")
		(net "GND")
	)
	(gr_line
		(start 1.414272 -79.914242)
		(end 0.585724 -79.085694)
		(stroke
			(width 1.016)
			(type default)
		)
		(layer "In7.Cu")
	)
	(gr_line
		(start 1.999996 -403.371558)
		(end 1.999996 -81.328514)
		(stroke
			(width 1.016)
			(type default)
		)
		(layer "In7.Cu")
	)
	(gr_arc
		(start 1.999996 -403.371558)
		(mid 2.152159 -404.136965)
		(end 2.58572 -404.78583)
		(stroke
			(width 1.016)
			(type default)
		)
		(layer "In7.Cu")
	)
	(gr_arc
		(start 1.999996 -81.328514)
		(mid 1.847755 -80.563149)
		(end 1.414272 -79.914242)
		(stroke
			(width 1.016)
			(type default)
		)
		(layer "In7.Cu")
	)
	(gr_arc
		(start 1.999996 -11.780012)
		(mid 0.585785 -12.365797)
		(end 0 -13.780008)
		(stroke
			(width 1.016)
			(type default)
		)
		(layer "In7.Cu")
	)
	(gr_line
		(start 1.999996 -11.780012)
		(end 11.102086 -11.780012)
		(stroke
			(width 1.016)
			(type default)
		)
		(layer "In7.Cu")
	)
	(gr_line
		(start 5.914136 -408.114246)
		(end 2.58572 -404.78583)
		(stroke
			(width 1.016)
			(type default)
		)
		(layer "In7.Cu")
	)
	(gr_line
		(start 6.500114 -439.989976)
		(end 6.500114 -409.528518)
		(stroke
			(width 1.016)
			(type default)
		)
		(layer "In7.Cu")
	)
	(gr_arc
		(start 6.500114 -439.989976)
		(mid 7.085891 -441.404199)
		(end 8.50011 -441.989972)
		(stroke
			(width 1.016)
			(type default)
		)
		(layer "In7.Cu")
	)
	(gr_arc
		(start 6.500114 -409.528518)
		(mid 6.347771 -408.763109)
		(end 5.914136 -408.114246)
		(stroke
			(width 1.016)
			(type default)
		)
		(layer "In7.Cu")
	)
	(gr_arc
		(start 11.102086 -11.780012)
		(mid 12.516297 -11.194227)
		(end 13.102082 -9.780016)
		(stroke
			(width 1.016)
			(type default)
		)
		(layer "In7.Cu")
	)
	(gr_line
		(start 13.102082 -9.780016)
		(end 13.102082 -0.500126)
		(stroke
			(width 1.016)
			(type default)
		)
		(layer "In7.Cu")
	)
	(gr_arc
		(start 13.601954 0)
		(mid 13.24848 -0.146572)
		(end 13.102082 -0.500126)
		(stroke
			(width 1.016)
			(type default)
		)
		(layer "In7.Cu")
	)
	(gr_line
		(start 13.601954 0)
		(end 81.202022 0)
		(stroke
			(width 1.016)
			(type default)
		)
		(layer "In7.Cu")
	)
	(gr_circle
		(center 25.82545 -40.816276)
		(end 26.71445 -40.816276)
		(stroke
			(width 0.2)
			(type default)
		)
		(fill no)
		(layer "In7.Cu")
	)
	(gr_circle
		(center 29.291534 -348.709488)
		(end 30.171644 -348.709488)
		(stroke
			(width 0.2)
			(type default)
		)
		(fill no)
		(layer "In7.Cu")
	)
	(gr_circle
		(center 29.908754 -348.709488)
		(end 30.788864 -348.709488)
		(stroke
			(width 0.2)
			(type default)
		)
		(fill no)
		(layer "In7.Cu")
	)
	(gr_circle
		(center 30.525974 -348.709488)
		(end 31.406084 -348.709488)
		(stroke
			(width 0.2)
			(type default)
		)
		(fill no)
		(layer "In7.Cu")
	)
	(gr_circle
		(center 30.795214 -347.966538)
		(end 31.684214 -347.966538)
		(stroke
			(width 0.2)
			(type default)
		)
		(fill no)
		(layer "In7.Cu")
	)
	(gr_circle
		(center 30.795214 -347.229938)
		(end 31.684214 -347.229938)
		(stroke
			(width 0.2)
			(type default)
		)
		(fill no)
		(layer "In7.Cu")
	)
	(gr_circle
		(center 31.22803 -350.318578)
		(end 32.11703 -350.318578)
		(stroke
			(width 0.2)
			(type default)
		)
		(fill no)
		(layer "In7.Cu")
	)
	(gr_circle
		(center 31.22803 -349.581978)
		(end 32.11703 -349.581978)
		(stroke
			(width 0.2)
			(type default)
		)
		(fill no)
		(layer "In7.Cu")
	)
	(gr_circle
		(center 31.752794 -349.142558)
		(end 32.641794 -349.142558)
		(stroke
			(width 0.2)
			(type default)
		)
		(fill no)
		(layer "In7.Cu")
	)
	(gr_circle
		(center 31.778194 -349.904558)
		(end 32.667194 -349.904558)
		(stroke
			(width 0.2)
			(type default)
		)
		(fill no)
		(layer "In7.Cu")
	)
	(gr_circle
		(center 32.311594 -350.260158)
		(end 33.200594 -350.260158)
		(stroke
			(width 0.2)
			(type default)
		)
		(fill no)
		(layer "In7.Cu")
	)
	(gr_circle
		(center 32.311594 -349.523558)
		(end 33.200594 -349.523558)
		(stroke
			(width 0.2)
			(type default)
		)
		(fill no)
		(layer "In7.Cu")
	)
	(gr_circle
		(center 32.311594 -348.786958)
		(end 33.200594 -348.786958)
		(stroke
			(width 0.2)
			(type default)
		)
		(fill no)
		(layer "In7.Cu")
	)
	(gr_circle
		(center 37.571934 -348.709488)
		(end 38.452044 -348.709488)
		(stroke
			(width 0.2)
			(type default)
		)
		(fill no)
		(layer "In7.Cu")
	)
	(gr_circle
		(center 38.189154 -348.709488)
		(end 39.069264 -348.709488)
		(stroke
			(width 0.2)
			(type default)
		)
		(fill no)
		(layer "In7.Cu")
	)
	(gr_circle
		(center 38.806374 -348.709488)
		(end 39.686484 -348.709488)
		(stroke
			(width 0.2)
			(type default)
		)
		(fill no)
		(layer "In7.Cu")
	)
	(gr_circle
		(center 39.050214 -347.974158)
		(end 39.939214 -347.974158)
		(stroke
			(width 0.2)
			(type default)
		)
		(fill no)
		(layer "In7.Cu")
	)
	(gr_circle
		(center 39.050214 -347.237558)
		(end 39.939214 -347.237558)
		(stroke
			(width 0.2)
			(type default)
		)
		(fill no)
		(layer "In7.Cu")
	)
	(gr_circle
		(center 39.50843 -350.318578)
		(end 40.39743 -350.318578)
		(stroke
			(width 0.2)
			(type default)
		)
		(fill no)
		(layer "In7.Cu")
	)
	(gr_circle
		(center 39.50843 -349.581978)
		(end 40.39743 -349.581978)
		(stroke
			(width 0.2)
			(type default)
		)
		(fill no)
		(layer "In7.Cu")
	)
	(gr_circle
		(center 40.033194 -349.142558)
		(end 40.922194 -349.142558)
		(stroke
			(width 0.2)
			(type default)
		)
		(fill no)
		(layer "In7.Cu")
	)
	(gr_circle
		(center 40.058594 -349.904558)
		(end 40.947594 -349.904558)
		(stroke
			(width 0.2)
			(type default)
		)
		(fill no)
		(layer "In7.Cu")
	)
	(gr_circle
		(center 40.591994 -350.260158)
		(end 41.480994 -350.260158)
		(stroke
			(width 0.2)
			(type default)
		)
		(fill no)
		(layer "In7.Cu")
	)
	(gr_circle
		(center 40.591994 -349.523558)
		(end 41.480994 -349.523558)
		(stroke
			(width 0.2)
			(type default)
		)
		(fill no)
		(layer "In7.Cu")
	)
	(gr_circle
		(center 40.591994 -348.786958)
		(end 41.480994 -348.786958)
		(stroke
			(width 0.2)
			(type default)
		)
		(fill no)
		(layer "In7.Cu")
	)
	(gr_circle
		(center 41.369742 -358.549194)
		(end 42.258742 -358.549194)
		(stroke
			(width 0.2)
			(type default)
		)
		(fill no)
		(layer "In7.Cu")
	)
	(gr_circle
		(center 41.417494 -357.898192)
		(end 42.306494 -357.898192)
		(stroke
			(width 0.2)
			(type default)
		)
		(fill no)
		(layer "In7.Cu")
	)
	(gr_circle
		(center 41.417494 -357.263192)
		(end 42.306494 -357.263192)
		(stroke
			(width 0.2)
			(type default)
		)
		(fill no)
		(layer "In7.Cu")
	)
	(gr_circle
		(center 41.427146 -359.2576)
		(end 42.316146 -359.2576)
		(stroke
			(width 0.2)
			(type default)
		)
		(fill no)
		(layer "In7.Cu")
	)
	(gr_circle
		(center 43.935904 -358.51084)
		(end 44.824904 -358.51084)
		(stroke
			(width 0.2)
			(type default)
		)
		(fill no)
		(layer "In7.Cu")
	)
	(gr_circle
		(center 43.983656 -357.859838)
		(end 44.872656 -357.859838)
		(stroke
			(width 0.2)
			(type default)
		)
		(fill no)
		(layer "In7.Cu")
	)
	(gr_circle
		(center 43.983656 -357.224838)
		(end 44.872656 -357.224838)
		(stroke
			(width 0.2)
			(type default)
		)
		(fill no)
		(layer "In7.Cu")
	)
	(gr_circle
		(center 43.993308 -359.219246)
		(end 44.882308 -359.219246)
		(stroke
			(width 0.2)
			(type default)
		)
		(fill no)
		(layer "In7.Cu")
	)
	(gr_circle
		(center 45.877734 -348.709488)
		(end 46.757844 -348.709488)
		(stroke
			(width 0.2)
			(type default)
		)
		(fill no)
		(layer "In7.Cu")
	)
	(gr_circle
		(center 46.494954 -348.709488)
		(end 47.375064 -348.709488)
		(stroke
			(width 0.2)
			(type default)
		)
		(fill no)
		(layer "In7.Cu")
	)
	(gr_circle
		(center 47.112174 -348.709488)
		(end 47.992284 -348.709488)
		(stroke
			(width 0.2)
			(type default)
		)
		(fill no)
		(layer "In7.Cu")
	)
	(gr_circle
		(center 47.366174 -348.017338)
		(end 48.255174 -348.017338)
		(stroke
			(width 0.2)
			(type default)
		)
		(fill no)
		(layer "In7.Cu")
	)
	(gr_circle
		(center 47.366174 -347.280738)
		(end 48.255174 -347.280738)
		(stroke
			(width 0.2)
			(type default)
		)
		(fill no)
		(layer "In7.Cu")
	)
	(gr_circle
		(center 47.81423 -350.318578)
		(end 48.70323 -350.318578)
		(stroke
			(width 0.2)
			(type default)
		)
		(fill no)
		(layer "In7.Cu")
	)
	(gr_circle
		(center 47.81423 -349.581978)
		(end 48.70323 -349.581978)
		(stroke
			(width 0.2)
			(type default)
		)
		(fill no)
		(layer "In7.Cu")
	)
	(gr_circle
		(center 47.880778 -358.108504)
		(end 48.769778 -358.108504)
		(stroke
			(width 0.2)
			(type default)
		)
		(fill no)
		(layer "In7.Cu")
	)
	(gr_circle
		(center 47.92853 -357.457502)
		(end 48.81753 -357.457502)
		(stroke
			(width 0.2)
			(type default)
		)
		(fill no)
		(layer "In7.Cu")
	)
	(gr_circle
		(center 47.92853 -356.822502)
		(end 48.81753 -356.822502)
		(stroke
			(width 0.2)
			(type default)
		)
		(fill no)
		(layer "In7.Cu")
	)
	(gr_circle
		(center 48.338994 -349.142558)
		(end 49.227994 -349.142558)
		(stroke
			(width 0.2)
			(type default)
		)
		(fill no)
		(layer "In7.Cu")
	)
	(gr_circle
		(center 48.364394 -349.904558)
		(end 49.253394 -349.904558)
		(stroke
			(width 0.2)
			(type default)
		)
		(fill no)
		(layer "In7.Cu")
	)
	(gr_circle
		(center 48.718978 -358.108504)
		(end 49.607978 -358.108504)
		(stroke
			(width 0.2)
			(type default)
		)
		(fill no)
		(layer "In7.Cu")
	)
	(gr_circle
		(center 48.76673 -357.457502)
		(end 49.65573 -357.457502)
		(stroke
			(width 0.2)
			(type default)
		)
		(fill no)
		(layer "In7.Cu")
	)
	(gr_circle
		(center 48.76673 -356.822502)
		(end 49.65573 -356.822502)
		(stroke
			(width 0.2)
			(type default)
		)
		(fill no)
		(layer "In7.Cu")
	)
	(gr_circle
		(center 48.897794 -350.260158)
		(end 49.786794 -350.260158)
		(stroke
			(width 0.2)
			(type default)
		)
		(fill no)
		(layer "In7.Cu")
	)
	(gr_circle
		(center 48.897794 -349.523558)
		(end 49.786794 -349.523558)
		(stroke
			(width 0.2)
			(type default)
		)
		(fill no)
		(layer "In7.Cu")
	)
	(gr_circle
		(center 48.897794 -348.786958)
		(end 49.786794 -348.786958)
		(stroke
			(width 0.2)
			(type default)
		)
		(fill no)
		(layer "In7.Cu")
	)
	(gr_circle
		(center 49.353978 -358.108504)
		(end 50.242978 -358.108504)
		(stroke
			(width 0.2)
			(type default)
		)
		(fill no)
		(layer "In7.Cu")
	)
	(gr_circle
		(center 49.40173 -357.457502)
		(end 50.29073 -357.457502)
		(stroke
			(width 0.2)
			(type default)
		)
		(fill no)
		(layer "In7.Cu")
	)
	(gr_circle
		(center 49.40173 -356.822502)
		(end 50.29073 -356.822502)
		(stroke
			(width 0.2)
			(type default)
		)
		(fill no)
		(layer "In7.Cu")
	)
	(gr_circle
		(center 49.988978 -358.108504)
		(end 50.877978 -358.108504)
		(stroke
			(width 0.2)
			(type default)
		)
		(fill no)
		(layer "In7.Cu")
	)
	(gr_circle
		(center 50.03673 -357.457502)
		(end 50.92573 -357.457502)
		(stroke
			(width 0.2)
			(type default)
		)
		(fill no)
		(layer "In7.Cu")
	)
	(gr_circle
		(center 50.03673 -356.822502)
		(end 50.92573 -356.822502)
		(stroke
			(width 0.2)
			(type default)
		)
		(fill no)
		(layer "In7.Cu")
	)
	(gr_circle
		(center 50.623978 -358.108504)
		(end 51.512978 -358.108504)
		(stroke
			(width 0.2)
			(type default)
		)
		(fill no)
		(layer "In7.Cu")
	)
	(gr_circle
		(center 50.67173 -357.457502)
		(end 51.56073 -357.457502)
		(stroke
			(width 0.2)
			(type default)
		)
		(fill no)
		(layer "In7.Cu")
	)
	(gr_circle
		(center 50.67173 -356.822502)
		(end 51.56073 -356.822502)
		(stroke
			(width 0.2)
			(type default)
		)
		(fill no)
		(layer "In7.Cu")
	)
	(gr_circle
		(center 54.234334 -348.709488)
		(end 55.114444 -348.709488)
		(stroke
			(width 0.2)
			(type default)
		)
		(fill no)
		(layer "In7.Cu")
	)
	(gr_circle
		(center 54.851554 -348.709488)
		(end 55.731664 -348.709488)
		(stroke
			(width 0.2)
			(type default)
		)
		(fill no)
		(layer "In7.Cu")
	)
	(gr_circle
		(center 55.468774 -348.709488)
		(end 56.348884 -348.709488)
		(stroke
			(width 0.2)
			(type default)
		)
		(fill no)
		(layer "In7.Cu")
	)
	(gr_circle
		(center 55.727854 -347.997018)
		(end 56.616854 -347.997018)
		(stroke
			(width 0.2)
			(type default)
		)
		(fill no)
		(layer "In7.Cu")
	)
	(gr_circle
		(center 55.727854 -347.260418)
		(end 56.616854 -347.260418)
		(stroke
			(width 0.2)
			(type default)
		)
		(fill no)
		(layer "In7.Cu")
	)
	(gr_circle
		(center 56.17083 -350.318578)
		(end 57.05983 -350.318578)
		(stroke
			(width 0.2)
			(type default)
		)
		(fill no)
		(layer "In7.Cu")
	)
	(gr_circle
		(center 56.17083 -349.581978)
		(end 57.05983 -349.581978)
		(stroke
			(width 0.2)
			(type default)
		)
		(fill no)
		(layer "In7.Cu")
	)
	(gr_circle
		(center 56.695594 -349.142558)
		(end 57.584594 -349.142558)
		(stroke
			(width 0.2)
			(type default)
		)
		(fill no)
		(layer "In7.Cu")
	)
	(gr_circle
		(center 56.720994 -349.904558)
		(end 57.609994 -349.904558)
		(stroke
			(width 0.2)
			(type default)
		)
		(fill no)
		(layer "In7.Cu")
	)
	(gr_circle
		(center 57.254394 -350.260158)
		(end 58.143394 -350.260158)
		(stroke
			(width 0.2)
			(type default)
		)
		(fill no)
		(layer "In7.Cu")
	)
	(gr_circle
		(center 57.254394 -349.523558)
		(end 58.143394 -349.523558)
		(stroke
			(width 0.2)
			(type default)
		)
		(fill no)
		(layer "In7.Cu")
	)
	(gr_circle
		(center 57.254394 -348.786958)
		(end 58.143394 -348.786958)
		(stroke
			(width 0.2)
			(type default)
		)
		(fill no)
		(layer "In7.Cu")
	)
	(gr_circle
		(center 61.93663 -166.86276)
		(end 62.82563 -166.86276)
		(stroke
			(width 0.2)
			(type default)
		)
		(fill no)
		(layer "In7.Cu")
	)
	(gr_circle
		(center 61.93663 -166.12616)
		(end 62.82563 -166.12616)
		(stroke
			(width 0.2)
			(type default)
		)
		(fill no)
		(layer "In7.Cu")
	)
	(gr_circle
		(center 61.93663 -165.38956)
		(end 62.82563 -165.38956)
		(stroke
			(width 0.2)
			(type default)
		)
		(fill no)
		(layer "In7.Cu")
	)
	(gr_circle
		(center 62.47003 -165.74516)
		(end 63.35903 -165.74516)
		(stroke
			(width 0.2)
			(type default)
		)
		(fill no)
		(layer "In7.Cu")
	)
	(gr_circle
		(center 62.49543 -166.50716)
		(end 63.38443 -166.50716)
		(stroke
			(width 0.2)
			(type default)
		)
		(fill no)
		(layer "In7.Cu")
	)
	(gr_circle
		(center 62.565534 -348.709488)
		(end 63.445644 -348.709488)
		(stroke
			(width 0.2)
			(type default)
		)
		(fill no)
		(layer "In7.Cu")
	)
	(gr_circle
		(center 63.020194 -166.06774)
		(end 63.909194 -166.06774)
		(stroke
			(width 0.2)
			(type default)
		)
		(fill no)
		(layer "In7.Cu")
	)
	(gr_circle
		(center 63.020194 -165.33114)
		(end 63.909194 -165.33114)
		(stroke
			(width 0.2)
			(type default)
		)
		(fill no)
		(layer "In7.Cu")
	)
	(gr_circle
		(center 63.182754 -348.709488)
		(end 64.062864 -348.709488)
		(stroke
			(width 0.2)
			(type default)
		)
		(fill no)
		(layer "In7.Cu")
	)
	(gr_circle
		(center 63.199264 -12.43711)
		(end 64.088264 -12.43711)
		(stroke
			(width 0.2)
			(type default)
		)
		(fill no)
		(layer "In7.Cu")
	)
	(gr_circle
		(center 63.579248 -168.42232)
		(end 64.468248 -168.42232)
		(stroke
			(width 0.2)
			(type default)
		)
		(fill no)
		(layer "In7.Cu")
	)
	(gr_circle
		(center 63.579248 -167.68572)
		(end 64.468248 -167.68572)
		(stroke
			(width 0.2)
			(type default)
		)
		(fill no)
		(layer "In7.Cu")
	)
	(gr_circle
		(center 63.631064 -13.09751)
		(end 64.520064 -13.09751)
		(stroke
			(width 0.2)
			(type default)
		)
		(fill no)
		(layer "In7.Cu")
	)
	(gr_circle
		(center 63.72225 -166.94023)
		(end 64.60236 -166.94023)
		(stroke
			(width 0.2)
			(type default)
		)
		(fill no)
		(layer "In7.Cu")
	)
	(gr_circle
		(center 63.799974 -348.709488)
		(end 64.680084 -348.709488)
		(stroke
			(width 0.2)
			(type default)
		)
		(fill no)
		(layer "In7.Cu")
	)
	(gr_circle
		(center 64.061594 -348.038928)
		(end 64.941704 -348.038928)
		(stroke
			(width 0.2)
			(type default)
		)
		(fill no)
		(layer "In7.Cu")
	)
	(gr_circle
		(center 64.061594 -347.302328)
		(end 64.941704 -347.302328)
		(stroke
			(width 0.2)
			(type default)
		)
		(fill no)
		(layer "In7.Cu")
	)
	(gr_circle
		(center 64.088264 -12.43711)
		(end 64.977264 -12.43711)
		(stroke
			(width 0.2)
			(type default)
		)
		(fill no)
		(layer "In7.Cu")
	)
	(gr_circle
		(center 64.33947 -166.94023)
		(end 65.21958 -166.94023)
		(stroke
			(width 0.2)
			(type default)
		)
		(fill no)
		(layer "In7.Cu")
	)
	(gr_circle
		(center 64.50203 -350.318578)
		(end 65.39103 -350.318578)
		(stroke
			(width 0.2)
			(type default)
		)
		(fill no)
		(layer "In7.Cu")
	)
	(gr_circle
		(center 64.50203 -349.581978)
		(end 65.39103 -349.581978)
		(stroke
			(width 0.2)
			(type default)
		)
		(fill no)
		(layer "In7.Cu")
	)
	(gr_circle
		(center 64.520064 -13.09751)
		(end 65.409064 -13.09751)
		(stroke
			(width 0.2)
			(type default)
		)
		(fill no)
		(layer "In7.Cu")
	)
	(gr_circle
		(center 64.95669 -166.94023)
		(end 65.8368 -166.94023)
		(stroke
			(width 0.2)
			(type default)
		)
		(fill no)
		(layer "In7.Cu")
	)
	(gr_circle
		(center 64.977264 -12.43711)
		(end 65.866264 -12.43711)
		(stroke
			(width 0.2)
			(type default)
		)
		(fill no)
		(layer "In7.Cu")
	)
	(gr_circle
		(center 65.026794 -349.142558)
		(end 65.915794 -349.142558)
		(stroke
			(width 0.2)
			(type default)
		)
		(fill no)
		(layer "In7.Cu")
	)
	(gr_circle
		(center 65.052194 -349.904558)
		(end 65.941194 -349.904558)
		(stroke
			(width 0.2)
			(type default)
		)
		(fill no)
		(layer "In7.Cu")
	)
	(gr_circle
		(center 65.409064 -13.09751)
		(end 66.298064 -13.09751)
		(stroke
			(width 0.2)
			(type default)
		)
		(fill no)
		(layer "In7.Cu")
	)
	(gr_circle
		(center 65.585594 -350.260158)
		(end 66.474594 -350.260158)
		(stroke
			(width 0.2)
			(type default)
		)
		(fill no)
		(layer "In7.Cu")
	)
	(gr_circle
		(center 65.585594 -349.523558)
		(end 66.474594 -349.523558)
		(stroke
			(width 0.2)
			(type default)
		)
		(fill no)
		(layer "In7.Cu")
	)
	(gr_circle
		(center 65.585594 -348.786958)
		(end 66.474594 -348.786958)
		(stroke
			(width 0.2)
			(type default)
		)
		(fill no)
		(layer "In7.Cu")
	)
	(gr_circle
		(center 65.866264 -12.43711)
		(end 66.755264 -12.43711)
		(stroke
			(width 0.2)
			(type default)
		)
		(fill no)
		(layer "In7.Cu")
	)
	(gr_circle
		(center 66.298064 -13.09751)
		(end 67.187064 -13.09751)
		(stroke
			(width 0.2)
			(type default)
		)
		(fill no)
		(layer "In7.Cu")
	)
	(gr_circle
		(center 66.399664 -25.56891)
		(end 67.288664 -25.56891)
		(stroke
			(width 0.2)
			(type default)
		)
		(fill no)
		(layer "In7.Cu")
	)
	(gr_circle
		(center 66.501264 -12.43711)
		(end 67.390264 -12.43711)
		(stroke
			(width 0.2)
			(type default)
		)
		(fill no)
		(layer "In7.Cu")
	)
	(gr_circle
		(center 66.774822 -20.327366)
		(end 67.663822 -20.327366)
		(stroke
			(width 0.2)
			(type default)
		)
		(fill no)
		(layer "In7.Cu")
	)
	(gr_circle
		(center 66.774822 -19.692366)
		(end 67.663822 -19.692366)
		(stroke
			(width 0.2)
			(type default)
		)
		(fill no)
		(layer "In7.Cu")
	)
	(gr_circle
		(center 66.780664 -24.88311)
		(end 67.669664 -24.88311)
		(stroke
			(width 0.2)
			(type default)
		)
		(fill no)
		(layer "In7.Cu")
	)
	(gr_circle
		(center 66.848228 -18.642584)
		(end 67.737228 -18.642584)
		(stroke
			(width 0.2)
			(type default)
		)
		(fill no)
		(layer "In7.Cu")
	)
	(gr_circle
		(center 66.882264 -22.26691)
		(end 67.771264 -22.26691)
		(stroke
			(width 0.2)
			(type default)
		)
		(fill no)
		(layer "In7.Cu")
	)
	(gr_circle
		(center 66.933064 -13.09751)
		(end 67.822064 -13.09751)
		(stroke
			(width 0.2)
			(type default)
		)
		(fill no)
		(layer "In7.Cu")
	)
	(gr_circle
		(center 67.288664 -25.56891)
		(end 68.177664 -25.56891)
		(stroke
			(width 0.2)
			(type default)
		)
		(fill no)
		(layer "In7.Cu")
	)
	(gr_circle
		(center 67.40271 -12.489434)
		(end 68.29171 -12.489434)
		(stroke
			(width 0.2)
			(type default)
		)
		(fill no)
		(layer "In7.Cu")
	)
	(gr_circle
		(center 67.669664 -24.88311)
		(end 68.558664 -24.88311)
		(stroke
			(width 0.2)
			(type default)
		)
		(fill no)
		(layer "In7.Cu")
	)
	(gr_circle
		(center 68.177664 -25.56891)
		(end 69.066664 -25.56891)
		(stroke
			(width 0.2)
			(type default)
		)
		(fill no)
		(layer "In7.Cu")
	)
	(gr_circle
		(center 68.54444 -18.476214)
		(end 69.43344 -18.476214)
		(stroke
			(width 0.2)
			(type default)
		)
		(fill no)
		(layer "In7.Cu")
	)
	(gr_circle
		(center 68.558664 -24.88311)
		(end 69.447664 -24.88311)
		(stroke
			(width 0.2)
			(type default)
		)
		(fill no)
		(layer "In7.Cu")
	)
	(gr_circle
		(center 69.498464 -24.55291)
		(end 70.387464 -24.55291)
		(stroke
			(width 0.2)
			(type default)
		)
		(fill no)
		(layer "In7.Cu")
	)
	(gr_circle
		(center 70.25005 -175.559974)
		(end 71.13905 -175.559974)
		(stroke
			(width 0.2)
			(type default)
		)
		(fill no)
		(layer "In7.Cu")
	)
	(gr_circle
		(center 70.25005 -174.823374)
		(end 71.13905 -174.823374)
		(stroke
			(width 0.2)
			(type default)
		)
		(fill no)
		(layer "In7.Cu")
	)
	(gr_circle
		(center 70.25005 -174.086774)
		(end 71.13905 -174.086774)
		(stroke
			(width 0.2)
			(type default)
		)
		(fill no)
		(layer "In7.Cu")
	)
	(gr_circle
		(center 70.78345 -174.442374)
		(end 71.67245 -174.442374)
		(stroke
			(width 0.2)
			(type default)
		)
		(fill no)
		(layer "In7.Cu")
	)
	(gr_circle
		(center 70.80885 -175.204374)
		(end 71.69785 -175.204374)
		(stroke
			(width 0.2)
			(type default)
		)
		(fill no)
		(layer "In7.Cu")
	)
	(gr_circle
		(center 71.099934 -336.988404)
		(end 71.980044 -336.988404)
		(stroke
			(width 0.2)
			(type default)
		)
		(fill no)
		(layer "In7.Cu")
	)
	(gr_circle
		(center 71.333614 -174.764954)
		(end 72.222614 -174.764954)
		(stroke
			(width 0.2)
			(type default)
		)
		(fill no)
		(layer "In7.Cu")
	)
	(gr_circle
		(center 71.333614 -174.028354)
		(end 72.222614 -174.028354)
		(stroke
			(width 0.2)
			(type default)
		)
		(fill no)
		(layer "In7.Cu")
	)
	(gr_circle
		(center 71.717154 -336.988404)
		(end 72.597264 -336.988404)
		(stroke
			(width 0.2)
			(type default)
		)
		(fill no)
		(layer "In7.Cu")
	)
	(gr_circle
		(center 71.892668 -177.10912)
		(end 72.781668 -177.10912)
		(stroke
			(width 0.2)
			(type default)
		)
		(fill no)
		(layer "In7.Cu")
	)
	(gr_circle
		(center 71.892668 -176.37252)
		(end 72.781668 -176.37252)
		(stroke
			(width 0.2)
			(type default)
		)
		(fill no)
		(layer "In7.Cu")
	)
	(gr_circle
		(center 72.03567 -175.639222)
		(end 72.91578 -175.639222)
		(stroke
			(width 0.2)
			(type default)
		)
		(fill no)
		(layer "In7.Cu")
	)
	(gr_circle
		(center 72.334374 -336.988404)
		(end 73.214484 -336.988404)
		(stroke
			(width 0.2)
			(type default)
		)
		(fill no)
		(layer "In7.Cu")
	)
	(gr_circle
		(center 72.616314 -336.255868)
		(end 73.496424 -336.255868)
		(stroke
			(width 0.2)
			(type default)
		)
		(fill no)
		(layer "In7.Cu")
	)
	(gr_circle
		(center 72.616314 -335.519268)
		(end 73.496424 -335.519268)
		(stroke
			(width 0.2)
			(type default)
		)
		(fill no)
		(layer "In7.Cu")
	)
	(gr_circle
		(center 72.65289 -175.639222)
		(end 73.533 -175.639222)
		(stroke
			(width 0.2)
			(type default)
		)
		(fill no)
		(layer "In7.Cu")
	)
	(gr_circle
		(center 73.03643 -338.597494)
		(end 73.92543 -338.597494)
		(stroke
			(width 0.2)
			(type default)
		)
		(fill no)
		(layer "In7.Cu")
	)
	(gr_circle
		(center 73.03643 -337.860894)
		(end 73.92543 -337.860894)
		(stroke
			(width 0.2)
			(type default)
		)
		(fill no)
		(layer "In7.Cu")
	)
	(gr_circle
		(center 73.27011 -175.639222)
		(end 74.15022 -175.639222)
		(stroke
			(width 0.2)
			(type default)
		)
		(fill no)
		(layer "In7.Cu")
	)
	(gr_circle
		(center 73.561194 -337.421474)
		(end 74.450194 -337.421474)
		(stroke
			(width 0.2)
			(type default)
		)
		(fill no)
		(layer "In7.Cu")
	)
	(gr_circle
		(center 73.586594 -338.183474)
		(end 74.475594 -338.183474)
		(stroke
			(width 0.2)
			(type default)
		)
		(fill no)
		(layer "In7.Cu")
	)
	(gr_circle
		(center 74.119994 -338.539074)
		(end 75.008994 -338.539074)
		(stroke
			(width 0.2)
			(type default)
		)
		(fill no)
		(layer "In7.Cu")
	)
	(gr_circle
		(center 74.119994 -337.802474)
		(end 75.008994 -337.802474)
		(stroke
			(width 0.2)
			(type default)
		)
		(fill no)
		(layer "In7.Cu")
	)
	(gr_circle
		(center 74.119994 -337.065874)
		(end 75.008994 -337.065874)
		(stroke
			(width 0.2)
			(type default)
		)
		(fill no)
		(layer "In7.Cu")
	)
	(gr_circle
		(center 74.811382 -351.637854)
		(end 75.700382 -351.637854)
		(stroke
			(width 0.2)
			(type default)
		)
		(fill no)
		(layer "In7.Cu")
	)
	(gr_circle
		(center 74.849482 -353.131374)
		(end 75.738482 -353.131374)
		(stroke
			(width 0.2)
			(type default)
		)
		(fill no)
		(layer "In7.Cu")
	)
	(gr_circle
		(center 74.849736 -352.30816)
		(end 75.738736 -352.30816)
		(stroke
			(width 0.2)
			(type default)
		)
		(fill no)
		(layer "In7.Cu")
	)
	(gr_circle
		(center 74.86015 -350.929448)
		(end 75.74915 -350.929448)
		(stroke
			(width 0.2)
			(type default)
		)
		(fill no)
		(layer "In7.Cu")
	)
	(gr_circle
		(center 77.178408 -16.520668)
		(end 78.067408 -16.520668)
		(stroke
			(width 0.2)
			(type default)
		)
		(fill no)
		(layer "In7.Cu")
	)
	(gr_circle
		(center 77.473048 -351.5995)
		(end 78.362048 -351.5995)
		(stroke
			(width 0.2)
			(type default)
		)
		(fill no)
		(layer "In7.Cu")
	)
	(gr_circle
		(center 77.511402 -352.978212)
		(end 78.400402 -352.978212)
		(stroke
			(width 0.2)
			(type default)
		)
		(fill no)
		(layer "In7.Cu")
	)
	(gr_circle
		(center 77.511402 -352.269806)
		(end 78.400402 -352.269806)
		(stroke
			(width 0.2)
			(type default)
		)
		(fill no)
		(layer "In7.Cu")
	)
	(gr_circle
		(center 77.521816 -350.891094)
		(end 78.410816 -350.891094)
		(stroke
			(width 0.2)
			(type default)
		)
		(fill no)
		(layer "In7.Cu")
	)
	(gr_circle
		(center 77.84338 -16.55064)
		(end 78.73238 -16.55064)
		(stroke
			(width 0.2)
			(type default)
		)
		(fill no)
		(layer "In7.Cu")
	)
	(gr_circle
		(center 78.85303 -178.798474)
		(end 79.74203 -178.798474)
		(stroke
			(width 0.2)
			(type default)
		)
		(fill no)
		(layer "In7.Cu")
	)
	(gr_circle
		(center 78.85303 -178.036474)
		(end 79.74203 -178.036474)
		(stroke
			(width 0.2)
			(type default)
		)
		(fill no)
		(layer "In7.Cu")
	)
	(gr_circle
		(center 79.10703 -179.560474)
		(end 79.99603 -179.560474)
		(stroke
			(width 0.2)
			(type default)
		)
		(fill no)
		(layer "In7.Cu")
	)
	(gr_circle
		(center 79.13243 -180.322474)
		(end 80.02143 -180.322474)
		(stroke
			(width 0.2)
			(type default)
		)
		(fill no)
		(layer "In7.Cu")
	)
	(gr_circle
		(center 79.403194 -178.384454)
		(end 80.292194 -178.384454)
		(stroke
			(width 0.2)
			(type default)
		)
		(fill no)
		(layer "In7.Cu")
	)
	(gr_circle
		(center 79.455518 -336.981292)
		(end 80.335628 -336.981292)
		(stroke
			(width 0.2)
			(type default)
		)
		(fill no)
		(layer "In7.Cu")
	)
	(gr_circle
		(center 79.657194 -179.883054)
		(end 80.546194 -179.883054)
		(stroke
			(width 0.2)
			(type default)
		)
		(fill no)
		(layer "In7.Cu")
	)
	(gr_circle
		(center 79.657194 -179.146454)
		(end 80.546194 -179.146454)
		(stroke
			(width 0.2)
			(type default)
		)
		(fill no)
		(layer "In7.Cu")
	)
	(gr_circle
		(center 79.921862 -18.238724)
		(end 80.810862 -18.238724)
		(stroke
			(width 0.2)
			(type default)
		)
		(fill no)
		(layer "In7.Cu")
	)
	(gr_circle
		(center 79.921862 -17.502124)
		(end 80.810862 -17.502124)
		(stroke
			(width 0.2)
			(type default)
		)
		(fill no)
		(layer "In7.Cu")
	)
	(gr_circle
		(center 80.072738 -336.981292)
		(end 80.952848 -336.981292)
		(stroke
			(width 0.2)
			(type default)
		)
		(fill no)
		(layer "In7.Cu")
	)
	(gr_circle
		(center 80.241648 -182.2196)
		(end 81.130648 -182.2196)
		(stroke
			(width 0.2)
			(type default)
		)
		(fill no)
		(layer "In7.Cu")
	)
	(gr_circle
		(center 80.241648 -181.483)
		(end 81.130648 -181.483)
		(stroke
			(width 0.2)
			(type default)
		)
		(fill no)
		(layer "In7.Cu")
	)
	(gr_circle
		(center 80.35925 -180.755544)
		(end 81.23936 -180.755544)
		(stroke
			(width 0.2)
			(type default)
		)
		(fill no)
		(layer "In7.Cu")
	)
	(gr_circle
		(center 80.689958 -336.981292)
		(end 81.570068 -336.981292)
		(stroke
			(width 0.2)
			(type default)
		)
		(fill no)
		(layer "In7.Cu")
	)
	(gr_circle
		(center 80.97647 -180.755544)
		(end 81.85658 -180.755544)
		(stroke
			(width 0.2)
			(type default)
		)
		(fill no)
		(layer "In7.Cu")
	)
	(gr_circle
		(center 80.977994 -336.245708)
		(end 81.858104 -336.245708)
		(stroke
			(width 0.2)
			(type default)
		)
		(fill no)
		(layer "In7.Cu")
	)
	(gr_circle
		(center 80.977994 -335.509108)
		(end 81.858104 -335.509108)
		(stroke
			(width 0.2)
			(type default)
		)
		(fill no)
		(layer "In7.Cu")
	)
	(gr_circle
		(center 81.392014 -338.590382)
		(end 82.281014 -338.590382)
		(stroke
			(width 0.2)
			(type default)
		)
		(fill no)
		(layer "In7.Cu")
	)
	(gr_circle
		(center 81.392014 -337.853782)
		(end 82.281014 -337.853782)
		(stroke
			(width 0.2)
			(type default)
		)
		(fill no)
		(layer "In7.Cu")
	)
	(gr_circle
		(center 81.59369 -180.755544)
		(end 82.4738 -180.755544)
		(stroke
			(width 0.2)
			(type default)
		)
		(fill no)
		(layer "In7.Cu")
	)
	(gr_arc
		(start 81.701894 -9.780016)
		(mid 82.287679 -11.194227)
		(end 83.70189 -11.780012)
		(stroke
			(width 1.016)
			(type default)
		)
		(layer "In7.Cu")
	)
	(gr_arc
		(start 81.701894 -0.500126)
		(mid 81.555625 -0.146451)
		(end 81.202022 0)
		(stroke
			(width 1.016)
			(type default)
		)
		(layer "In7.Cu")
	)
	(gr_line
		(start 81.701894 -0.500126)
		(end 81.701894 -9.780016)
		(stroke
			(width 1.016)
			(type default)
		)
		(layer "In7.Cu")
	)
	(gr_circle
		(center 81.916778 -337.414362)
		(end 82.805778 -337.414362)
		(stroke
			(width 0.2)
			(type default)
		)
		(fill no)
		(layer "In7.Cu")
	)
	(gr_circle
		(center 81.942178 -338.176362)
		(end 82.831178 -338.176362)
		(stroke
			(width 0.2)
			(type default)
		)
		(fill no)
		(layer "In7.Cu")
	)
	(gr_circle
		(center 82.183986 -348.89948)
		(end 83.072986 -348.89948)
		(stroke
			(width 0.2)
			(type default)
		)
		(fill no)
		(layer "In7.Cu")
	)
	(gr_circle
		(center 82.222086 -350.393)
		(end 83.111086 -350.393)
		(stroke
			(width 0.2)
			(type default)
		)
		(fill no)
		(layer "In7.Cu")
	)
	(gr_circle
		(center 82.22234 -349.569786)
		(end 83.11134 -349.569786)
		(stroke
			(width 0.2)
			(type default)
		)
		(fill no)
		(layer "In7.Cu")
	)
	(gr_circle
		(center 82.232754 -348.191074)
		(end 83.121754 -348.191074)
		(stroke
			(width 0.2)
			(type default)
		)
		(fill no)
		(layer "In7.Cu")
	)
	(gr_circle
		(center 82.475578 -338.531962)
		(end 83.364578 -338.531962)
		(stroke
			(width 0.2)
			(type default)
		)
		(fill no)
		(layer "In7.Cu")
	)
	(gr_circle
		(center 82.475578 -337.795362)
		(end 83.364578 -337.795362)
		(stroke
			(width 0.2)
			(type default)
		)
		(fill no)
		(layer "In7.Cu")
	)
	(gr_circle
		(center 82.475578 -337.058762)
		(end 83.364578 -337.058762)
		(stroke
			(width 0.2)
			(type default)
		)
		(fill no)
		(layer "In7.Cu")
	)
	(gr_circle
		(center 82.989674 -165.962076)
		(end 84.386674 -165.962076)
		(stroke
			(width 0.2)
			(type default)
		)
		(fill no)
		(layer "In7.Cu")
	)
	(gr_line
		(start 83.70189 -11.780012)
		(end 124.102114 -11.780012)
		(stroke
			(width 1.016)
			(type default)
		)
		(layer "In7.Cu")
	)
	(gr_circle
		(center 84.845652 -348.861126)
		(end 85.734652 -348.861126)
		(stroke
			(width 0.2)
			(type default)
		)
		(fill no)
		(layer "In7.Cu")
	)
	(gr_circle
		(center 84.884006 -350.239838)
		(end 85.773006 -350.239838)
		(stroke
			(width 0.2)
			(type default)
		)
		(fill no)
		(layer "In7.Cu")
	)
	(gr_circle
		(center 84.884006 -349.531432)
		(end 85.773006 -349.531432)
		(stroke
			(width 0.2)
			(type default)
		)
		(fill no)
		(layer "In7.Cu")
	)
	(gr_circle
		(center 84.89442 -348.15272)
		(end 85.78342 -348.15272)
		(stroke
			(width 0.2)
			(type default)
		)
		(fill no)
		(layer "In7.Cu")
	)
	(gr_circle
		(center 86.97087 -180.610002)
		(end 87.85987 -180.610002)
		(stroke
			(width 0.2)
			(type default)
		)
		(fill no)
		(layer "In7.Cu")
	)
	(gr_circle
		(center 86.97087 -179.873402)
		(end 87.85987 -179.873402)
		(stroke
			(width 0.2)
			(type default)
		)
		(fill no)
		(layer "In7.Cu")
	)
	(gr_circle
		(center 86.97087 -179.136802)
		(end 87.85987 -179.136802)
		(stroke
			(width 0.2)
			(type default)
		)
		(fill no)
		(layer "In7.Cu")
	)
	(gr_circle
		(center 87.01913 -164.097716)
		(end 87.90813 -164.097716)
		(stroke
			(width 0.2)
			(type default)
		)
		(fill no)
		(layer "In7.Cu")
	)
	(gr_circle
		(center 87.03945 -163.447476)
		(end 87.92845 -163.447476)
		(stroke
			(width 0.2)
			(type default)
		)
		(fill no)
		(layer "In7.Cu")
	)
	(gr_circle
		(center 87.03945 -162.812476)
		(end 87.92845 -162.812476)
		(stroke
			(width 0.2)
			(type default)
		)
		(fill no)
		(layer "In7.Cu")
	)
	(gr_circle
		(center 87.50427 -179.492402)
		(end 88.39327 -179.492402)
		(stroke
			(width 0.2)
			(type default)
		)
		(fill no)
		(layer "In7.Cu")
	)
	(gr_circle
		(center 87.52967 -180.254402)
		(end 88.41867 -180.254402)
		(stroke
			(width 0.2)
			(type default)
		)
		(fill no)
		(layer "In7.Cu")
	)
	(gr_circle
		(center 87.65413 -164.097716)
		(end 88.54313 -164.097716)
		(stroke
			(width 0.2)
			(type default)
		)
		(fill no)
		(layer "In7.Cu")
	)
	(gr_circle
		(center 87.67445 -163.447476)
		(end 88.56345 -163.447476)
		(stroke
			(width 0.2)
			(type default)
		)
		(fill no)
		(layer "In7.Cu")
	)
	(gr_circle
		(center 87.67445 -162.812476)
		(end 88.56345 -162.812476)
		(stroke
			(width 0.2)
			(type default)
		)
		(fill no)
		(layer "In7.Cu")
	)
	(gr_circle
		(center 87.813134 -336.966814)
		(end 88.693244 -336.966814)
		(stroke
			(width 0.2)
			(type default)
		)
		(fill no)
		(layer "In7.Cu")
	)
	(gr_circle
		(center 88.054434 -179.814982)
		(end 88.943434 -179.814982)
		(stroke
			(width 0.2)
			(type default)
		)
		(fill no)
		(layer "In7.Cu")
	)
	(gr_circle
		(center 88.054434 -179.078382)
		(end 88.943434 -179.078382)
		(stroke
			(width 0.2)
			(type default)
		)
		(fill no)
		(layer "In7.Cu")
	)
	(gr_circle
		(center 88.28913 -164.097716)
		(end 89.17813 -164.097716)
		(stroke
			(width 0.2)
			(type default)
		)
		(fill no)
		(layer "In7.Cu")
	)
	(gr_circle
		(center 88.30945 -163.447476)
		(end 89.19845 -163.447476)
		(stroke
			(width 0.2)
			(type default)
		)
		(fill no)
		(layer "In7.Cu")
	)
	(gr_circle
		(center 88.30945 -162.812476)
		(end 89.19845 -162.812476)
		(stroke
			(width 0.2)
			(type default)
		)
		(fill no)
		(layer "In7.Cu")
	)
	(gr_circle
		(center 88.430354 -336.966814)
		(end 89.310464 -336.966814)
		(stroke
			(width 0.2)
			(type default)
		)
		(fill no)
		(layer "In7.Cu")
	)
	(gr_circle
		(center 88.49233 -182.13324)
		(end 89.38133 -182.13324)
		(stroke
			(width 0.2)
			(type default)
		)
		(fill no)
		(layer "In7.Cu")
	)
	(gr_circle
		(center 88.49233 -181.39664)
		(end 89.38133 -181.39664)
		(stroke
			(width 0.2)
			(type default)
		)
		(fill no)
		(layer "In7.Cu")
	)
	(gr_circle
		(center 88.75649 -180.687472)
		(end 89.6366 -180.687472)
		(stroke
			(width 0.2)
			(type default)
		)
		(fill no)
		(layer "In7.Cu")
	)
	(gr_circle
		(center 88.92413 -164.097716)
		(end 89.81313 -164.097716)
		(stroke
			(width 0.2)
			(type default)
		)
		(fill no)
		(layer "In7.Cu")
	)
	(gr_circle
		(center 88.94445 -163.447476)
		(end 89.83345 -163.447476)
		(stroke
			(width 0.2)
			(type default)
		)
		(fill no)
		(layer "In7.Cu")
	)
	(gr_circle
		(center 88.94445 -162.812476)
		(end 89.83345 -162.812476)
		(stroke
			(width 0.2)
			(type default)
		)
		(fill no)
		(layer "In7.Cu")
	)
	(gr_circle
		(center 89.047574 -336.966814)
		(end 89.927684 -336.966814)
		(stroke
			(width 0.2)
			(type default)
		)
		(fill no)
		(layer "In7.Cu")
	)
	(gr_circle
		(center 89.314528 -345.237562)
		(end 90.203528 -345.237562)
		(stroke
			(width 0.2)
			(type default)
		)
		(fill no)
		(layer "In7.Cu")
	)
	(gr_circle
		(center 89.319354 -336.255868)
		(end 90.199464 -336.255868)
		(stroke
			(width 0.2)
			(type default)
		)
		(fill no)
		(layer "In7.Cu")
	)
	(gr_circle
		(center 89.319354 -335.519268)
		(end 90.199464 -335.519268)
		(stroke
			(width 0.2)
			(type default)
		)
		(fill no)
		(layer "In7.Cu")
	)
	(gr_circle
		(center 89.350088 -345.96959)
		(end 90.239088 -345.96959)
		(stroke
			(width 0.2)
			(type default)
		)
		(fill no)
		(layer "In7.Cu")
	)
	(gr_circle
		(center 89.37371 -180.687472)
		(end 90.25382 -180.687472)
		(stroke
			(width 0.2)
			(type default)
		)
		(fill no)
		(layer "In7.Cu")
	)
	(gr_circle
		(center 89.388442 -346.639896)
		(end 90.277442 -346.639896)
		(stroke
			(width 0.2)
			(type default)
		)
		(fill no)
		(layer "In7.Cu")
	)
	(gr_circle
		(center 89.55913 -164.097716)
		(end 90.44813 -164.097716)
		(stroke
			(width 0.2)
			(type default)
		)
		(fill no)
		(layer "In7.Cu")
	)
	(gr_circle
		(center 89.57945 -163.447476)
		(end 90.46845 -163.447476)
		(stroke
			(width 0.2)
			(type default)
		)
		(fill no)
		(layer "In7.Cu")
	)
	(gr_circle
		(center 89.57945 -162.812476)
		(end 90.46845 -162.812476)
		(stroke
			(width 0.2)
			(type default)
		)
		(fill no)
		(layer "In7.Cu")
	)
	(gr_circle
		(center 89.74963 -338.575904)
		(end 90.63863 -338.575904)
		(stroke
			(width 0.2)
			(type default)
		)
		(fill no)
		(layer "In7.Cu")
	)
	(gr_circle
		(center 89.74963 -337.839304)
		(end 90.63863 -337.839304)
		(stroke
			(width 0.2)
			(type default)
		)
		(fill no)
		(layer "In7.Cu")
	)
	(gr_circle
		(center 89.983056 -345.261184)
		(end 90.872056 -345.261184)
		(stroke
			(width 0.2)
			(type default)
		)
		(fill no)
		(layer "In7.Cu")
	)
	(gr_circle
		(center 89.985088 -345.96959)
		(end 90.874088 -345.96959)
		(stroke
			(width 0.2)
			(type default)
		)
		(fill no)
		(layer "In7.Cu")
	)
	(gr_circle
		(center 89.99093 -180.687472)
		(end 90.87104 -180.687472)
		(stroke
			(width 0.2)
			(type default)
		)
		(fill no)
		(layer "In7.Cu")
	)
	(gr_circle
		(center 90.023442 -346.639896)
		(end 90.912442 -346.639896)
		(stroke
			(width 0.2)
			(type default)
		)
		(fill no)
		(layer "In7.Cu")
	)
	(gr_circle
		(center 90.21953 -164.107876)
		(end 91.10853 -164.107876)
		(stroke
			(width 0.2)
			(type default)
		)
		(fill no)
		(layer "In7.Cu")
	)
	(gr_circle
		(center 90.23985 -163.457636)
		(end 91.12885 -163.457636)
		(stroke
			(width 0.2)
			(type default)
		)
		(fill no)
		(layer "In7.Cu")
	)
	(gr_circle
		(center 90.23985 -162.822636)
		(end 91.12885 -162.822636)
		(stroke
			(width 0.2)
			(type default)
		)
		(fill no)
		(layer "In7.Cu")
	)
	(gr_circle
		(center 90.274394 -337.399884)
		(end 91.163394 -337.399884)
		(stroke
			(width 0.2)
			(type default)
		)
		(fill no)
		(layer "In7.Cu")
	)
	(gr_circle
		(center 90.299794 -338.161884)
		(end 91.188794 -338.161884)
		(stroke
			(width 0.2)
			(type default)
		)
		(fill no)
		(layer "In7.Cu")
	)
	(gr_circle
		(center 90.618056 -345.261184)
		(end 91.507056 -345.261184)
		(stroke
			(width 0.2)
			(type default)
		)
		(fill no)
		(layer "In7.Cu")
	)
	(gr_circle
		(center 90.620088 -345.96959)
		(end 91.509088 -345.96959)
		(stroke
			(width 0.2)
			(type default)
		)
		(fill no)
		(layer "In7.Cu")
	)
	(gr_circle
		(center 90.658442 -346.639896)
		(end 91.547442 -346.639896)
		(stroke
			(width 0.2)
			(type default)
		)
		(fill no)
		(layer "In7.Cu")
	)
	(gr_circle
		(center 90.833194 -338.517484)
		(end 91.722194 -338.517484)
		(stroke
			(width 0.2)
			(type default)
		)
		(fill no)
		(layer "In7.Cu")
	)
	(gr_circle
		(center 90.833194 -337.780884)
		(end 91.722194 -337.780884)
		(stroke
			(width 0.2)
			(type default)
		)
		(fill no)
		(layer "In7.Cu")
	)
	(gr_circle
		(center 90.833194 -337.044284)
		(end 91.722194 -337.044284)
		(stroke
			(width 0.2)
			(type default)
		)
		(fill no)
		(layer "In7.Cu")
	)
	(gr_circle
		(center 91.255088 -345.96959)
		(end 92.144088 -345.96959)
		(stroke
			(width 0.2)
			(type default)
		)
		(fill no)
		(layer "In7.Cu")
	)
	(gr_circle
		(center 91.293442 -346.639896)
		(end 92.182442 -346.639896)
		(stroke
			(width 0.2)
			(type default)
		)
		(fill no)
		(layer "In7.Cu")
	)
	(gr_circle
		(center 91.380056 -345.261184)
		(end 92.269056 -345.261184)
		(stroke
			(width 0.2)
			(type default)
		)
		(fill no)
		(layer "In7.Cu")
	)
	(gr_circle
		(center 91.966288 -345.96959)
		(end 92.855288 -345.96959)
		(stroke
			(width 0.2)
			(type default)
		)
		(fill no)
		(layer "In7.Cu")
	)
	(gr_circle
		(center 92.004642 -346.639896)
		(end 92.893642 -346.639896)
		(stroke
			(width 0.2)
			(type default)
		)
		(fill no)
		(layer "In7.Cu")
	)
	(gr_circle
		(center 92.015056 -345.261184)
		(end 92.904056 -345.261184)
		(stroke
			(width 0.2)
			(type default)
		)
		(fill no)
		(layer "In7.Cu")
	)
	(gr_circle
		(center 92.387674 -165.962076)
		(end 93.784674 -165.962076)
		(stroke
			(width 0.2)
			(type default)
		)
		(fill no)
		(layer "In7.Cu")
	)
	(gr_circle
		(center 92.601288 -345.96959)
		(end 93.490288 -345.96959)
		(stroke
			(width 0.2)
			(type default)
		)
		(fill no)
		(layer "In7.Cu")
	)
	(gr_circle
		(center 92.639642 -346.639896)
		(end 93.528642 -346.639896)
		(stroke
			(width 0.2)
			(type default)
		)
		(fill no)
		(layer "In7.Cu")
	)
	(gr_circle
		(center 92.650056 -345.261184)
		(end 93.539056 -345.261184)
		(stroke
			(width 0.2)
			(type default)
		)
		(fill no)
		(layer "In7.Cu")
	)
	(gr_circle
		(center 95.36303 -180.627274)
		(end 96.25203 -180.627274)
		(stroke
			(width 0.2)
			(type default)
		)
		(fill no)
		(layer "In7.Cu")
	)
	(gr_circle
		(center 95.36303 -179.890674)
		(end 96.25203 -179.890674)
		(stroke
			(width 0.2)
			(type default)
		)
		(fill no)
		(layer "In7.Cu")
	)
	(gr_circle
		(center 95.36303 -179.154074)
		(end 96.25203 -179.154074)
		(stroke
			(width 0.2)
			(type default)
		)
		(fill no)
		(layer "In7.Cu")
	)
	(gr_circle
		(center 95.89643 -179.509674)
		(end 96.78543 -179.509674)
		(stroke
			(width 0.2)
			(type default)
		)
		(fill no)
		(layer "In7.Cu")
	)
	(gr_circle
		(center 95.92183 -180.271674)
		(end 96.81083 -180.271674)
		(stroke
			(width 0.2)
			(type default)
		)
		(fill no)
		(layer "In7.Cu")
	)
	(gr_circle
		(center 96.144334 -337.017614)
		(end 97.024444 -337.017614)
		(stroke
			(width 0.2)
			(type default)
		)
		(fill no)
		(layer "In7.Cu")
	)
	(gr_circle
		(center 96.446594 -179.832254)
		(end 97.335594 -179.832254)
		(stroke
			(width 0.2)
			(type default)
		)
		(fill no)
		(layer "In7.Cu")
	)
	(gr_circle
		(center 96.446594 -179.095654)
		(end 97.335594 -179.095654)
		(stroke
			(width 0.2)
			(type default)
		)
		(fill no)
		(layer "In7.Cu")
	)
	(gr_circle
		(center 96.761554 -337.017614)
		(end 97.641664 -337.017614)
		(stroke
			(width 0.2)
			(type default)
		)
		(fill no)
		(layer "In7.Cu")
	)
	(gr_circle
		(center 96.980248 -182.13324)
		(end 97.869248 -182.13324)
		(stroke
			(width 0.2)
			(type default)
		)
		(fill no)
		(layer "In7.Cu")
	)
	(gr_circle
		(center 96.980248 -181.39664)
		(end 97.869248 -181.39664)
		(stroke
			(width 0.2)
			(type default)
		)
		(fill no)
		(layer "In7.Cu")
	)
	(gr_circle
		(center 97.14865 -180.704744)
		(end 98.02876 -180.704744)
		(stroke
			(width 0.2)
			(type default)
		)
		(fill no)
		(layer "In7.Cu")
	)
	(gr_circle
		(center 97.378774 -337.017614)
		(end 98.258884 -337.017614)
		(stroke
			(width 0.2)
			(type default)
		)
		(fill no)
		(layer "In7.Cu")
	)
	(gr_circle
		(center 97.658174 -336.319368)
		(end 98.538284 -336.319368)
		(stroke
			(width 0.2)
			(type default)
		)
		(fill no)
		(layer "In7.Cu")
	)
	(gr_circle
		(center 97.658174 -335.582768)
		(end 98.538284 -335.582768)
		(stroke
			(width 0.2)
			(type default)
		)
		(fill no)
		(layer "In7.Cu")
	)
	(gr_circle
		(center 97.76587 -180.704744)
		(end 98.64598 -180.704744)
		(stroke
			(width 0.2)
			(type default)
		)
		(fill no)
		(layer "In7.Cu")
	)
	(gr_circle
		(center 97.981008 -278.13635)
		(end 98.235008 -278.13635)
		(stroke
			(width 0.1016)
			(type default)
		)
		(fill no)
		(layer "In7.Cu")
	)
	(gr_circle
		(center 97.981008 -276.516338)
		(end 98.235008 -276.516338)
		(stroke
			(width 0.1016)
			(type default)
		)
		(fill no)
		(layer "In7.Cu")
	)
	(gr_circle
		(center 97.981008 -274.896326)
		(end 98.235008 -274.896326)
		(stroke
			(width 0.1016)
			(type default)
		)
		(fill no)
		(layer "In7.Cu")
	)
	(gr_circle
		(center 97.981008 -273.276314)
		(end 98.235008 -273.276314)
		(stroke
			(width 0.1016)
			(type default)
		)
		(fill no)
		(layer "In7.Cu")
	)
	(gr_circle
		(center 97.981008 -271.656302)
		(end 98.235008 -271.656302)
		(stroke
			(width 0.1016)
			(type default)
		)
		(fill no)
		(layer "In7.Cu")
	)
	(gr_circle
		(center 97.981008 -270.03629)
		(end 98.235008 -270.03629)
		(stroke
			(width 0.1016)
			(type default)
		)
		(fill no)
		(layer "In7.Cu")
	)
	(gr_circle
		(center 98.08083 -338.626704)
		(end 98.96983 -338.626704)
		(stroke
			(width 0.2)
			(type default)
		)
		(fill no)
		(layer "In7.Cu")
	)
	(gr_circle
		(center 98.08083 -337.890104)
		(end 98.96983 -337.890104)
		(stroke
			(width 0.2)
			(type default)
		)
		(fill no)
		(layer "In7.Cu")
	)
	(gr_circle
		(center 98.199194 -339.358224)
		(end 99.088194 -339.358224)
		(stroke
			(width 0.2)
			(type default)
		)
		(fill no)
		(layer "In7.Cu")
	)
	(gr_circle
		(center 98.38309 -180.704744)
		(end 99.2632 -180.704744)
		(stroke
			(width 0.2)
			(type default)
		)
		(fill no)
		(layer "In7.Cu")
	)
	(gr_circle
		(center 98.605594 -337.450684)
		(end 99.494594 -337.450684)
		(stroke
			(width 0.2)
			(type default)
		)
		(fill no)
		(layer "In7.Cu")
	)
	(gr_circle
		(center 98.630994 -338.212684)
		(end 99.519994 -338.212684)
		(stroke
			(width 0.2)
			(type default)
		)
		(fill no)
		(layer "In7.Cu")
	)
	(gr_circle
		(center 98.747834 -339.736684)
		(end 99.636834 -339.736684)
		(stroke
			(width 0.2)
			(type default)
		)
		(fill no)
		(layer "In7.Cu")
	)
	(gr_circle
		(center 98.747834 -338.974684)
		(end 99.636834 -338.974684)
		(stroke
			(width 0.2)
			(type default)
		)
		(fill no)
		(layer "In7.Cu")
	)
	(gr_circle
		(center 98.921062 -278.13635)
		(end 99.175062 -278.13635)
		(stroke
			(width 0.1016)
			(type default)
		)
		(fill no)
		(layer "In7.Cu")
	)
	(gr_circle
		(center 98.921062 -276.516338)
		(end 99.175062 -276.516338)
		(stroke
			(width 0.1016)
			(type default)
		)
		(fill no)
		(layer "In7.Cu")
	)
	(gr_circle
		(center 98.921062 -274.896326)
		(end 99.175062 -274.896326)
		(stroke
			(width 0.1016)
			(type default)
		)
		(fill no)
		(layer "In7.Cu")
	)
	(gr_circle
		(center 98.921062 -273.276314)
		(end 99.175062 -273.276314)
		(stroke
			(width 0.1016)
			(type default)
		)
		(fill no)
		(layer "In7.Cu")
	)
	(gr_circle
		(center 98.921062 -271.656302)
		(end 99.175062 -271.656302)
		(stroke
			(width 0.1016)
			(type default)
		)
		(fill no)
		(layer "In7.Cu")
	)
	(gr_circle
		(center 98.921062 -270.03629)
		(end 99.175062 -270.03629)
		(stroke
			(width 0.1016)
			(type default)
		)
		(fill no)
		(layer "In7.Cu")
	)
	(gr_circle
		(center 100.800916 -278.13635)
		(end 101.054916 -278.13635)
		(stroke
			(width 0.1016)
			(type default)
		)
		(fill no)
		(layer "In7.Cu")
	)
	(gr_circle
		(center 100.800916 -276.516338)
		(end 101.054916 -276.516338)
		(stroke
			(width 0.1016)
			(type default)
		)
		(fill no)
		(layer "In7.Cu")
	)
	(gr_circle
		(center 100.800916 -274.896326)
		(end 101.054916 -274.896326)
		(stroke
			(width 0.1016)
			(type default)
		)
		(fill no)
		(layer "In7.Cu")
	)
	(gr_circle
		(center 100.800916 -273.276314)
		(end 101.054916 -273.276314)
		(stroke
			(width 0.1016)
			(type default)
		)
		(fill no)
		(layer "In7.Cu")
	)
	(gr_circle
		(center 100.800916 -271.656302)
		(end 101.054916 -271.656302)
		(stroke
			(width 0.1016)
			(type default)
		)
		(fill no)
		(layer "In7.Cu")
	)
	(gr_circle
		(center 100.800916 -270.03629)
		(end 101.054916 -270.03629)
		(stroke
			(width 0.1016)
			(type default)
		)
		(fill no)
		(layer "In7.Cu")
	)
	(gr_circle
		(center 101.74097 -278.13635)
		(end 101.99497 -278.13635)
		(stroke
			(width 0.1016)
			(type default)
		)
		(fill no)
		(layer "In7.Cu")
	)
	(gr_circle
		(center 101.74097 -276.516338)
		(end 101.99497 -276.516338)
		(stroke
			(width 0.1016)
			(type default)
		)
		(fill no)
		(layer "In7.Cu")
	)
	(gr_circle
		(center 101.74097 -274.896326)
		(end 101.99497 -274.896326)
		(stroke
			(width 0.1016)
			(type default)
		)
		(fill no)
		(layer "In7.Cu")
	)
	(gr_circle
		(center 101.74097 -273.276314)
		(end 101.99497 -273.276314)
		(stroke
			(width 0.1016)
			(type default)
		)
		(fill no)
		(layer "In7.Cu")
	)
	(gr_circle
		(center 101.74097 -271.656302)
		(end 101.99497 -271.656302)
		(stroke
			(width 0.1016)
			(type default)
		)
		(fill no)
		(layer "In7.Cu")
	)
	(gr_circle
		(center 101.74097 -270.03629)
		(end 101.99497 -270.03629)
		(stroke
			(width 0.1016)
			(type default)
		)
		(fill no)
		(layer "In7.Cu")
	)
	(gr_circle
		(center 103.621078 -278.13635)
		(end 103.875078 -278.13635)
		(stroke
			(width 0.1016)
			(type default)
		)
		(fill no)
		(layer "In7.Cu")
	)
	(gr_circle
		(center 103.621078 -276.516338)
		(end 103.875078 -276.516338)
		(stroke
			(width 0.1016)
			(type default)
		)
		(fill no)
		(layer "In7.Cu")
	)
	(gr_circle
		(center 103.621078 -274.896326)
		(end 103.875078 -274.896326)
		(stroke
			(width 0.1016)
			(type default)
		)
		(fill no)
		(layer "In7.Cu")
	)
	(gr_circle
		(center 103.621078 -273.276314)
		(end 103.875078 -273.276314)
		(stroke
			(width 0.1016)
			(type default)
		)
		(fill no)
		(layer "In7.Cu")
	)
	(gr_circle
		(center 103.621078 -271.656302)
		(end 103.875078 -271.656302)
		(stroke
			(width 0.1016)
			(type default)
		)
		(fill no)
		(layer "In7.Cu")
	)
	(gr_circle
		(center 103.621078 -270.03629)
		(end 103.875078 -270.03629)
		(stroke
			(width 0.1016)
			(type default)
		)
		(fill no)
		(layer "In7.Cu")
	)
	(gr_circle
		(center 103.74503 -176.106074)
		(end 104.63403 -176.106074)
		(stroke
			(width 0.2)
			(type default)
		)
		(fill no)
		(layer "In7.Cu")
	)
	(gr_circle
		(center 103.74503 -175.369474)
		(end 104.63403 -175.369474)
		(stroke
			(width 0.2)
			(type default)
		)
		(fill no)
		(layer "In7.Cu")
	)
	(gr_circle
		(center 103.74503 -174.632874)
		(end 104.63403 -174.632874)
		(stroke
			(width 0.2)
			(type default)
		)
		(fill no)
		(layer "In7.Cu")
	)
	(gr_circle
		(center 104.27843 -174.988474)
		(end 105.16743 -174.988474)
		(stroke
			(width 0.2)
			(type default)
		)
		(fill no)
		(layer "In7.Cu")
	)
	(gr_circle
		(center 104.30383 -175.750474)
		(end 105.19283 -175.750474)
		(stroke
			(width 0.2)
			(type default)
		)
		(fill no)
		(layer "In7.Cu")
	)
	(gr_circle
		(center 104.420162 -341.927688)
		(end 105.300272 -341.927688)
		(stroke
			(width 0.2)
			(type default)
		)
		(fill no)
		(layer "In7.Cu")
	)
	(gr_circle
		(center 104.561132 -278.13635)
		(end 104.815132 -278.13635)
		(stroke
			(width 0.1016)
			(type default)
		)
		(fill no)
		(layer "In7.Cu")
	)
	(gr_circle
		(center 104.561132 -276.516338)
		(end 104.815132 -276.516338)
		(stroke
			(width 0.1016)
			(type default)
		)
		(fill no)
		(layer "In7.Cu")
	)
	(gr_circle
		(center 104.561132 -274.896326)
		(end 104.815132 -274.896326)
		(stroke
			(width 0.1016)
			(type default)
		)
		(fill no)
		(layer "In7.Cu")
	)
	(gr_circle
		(center 104.561132 -273.276314)
		(end 104.815132 -273.276314)
		(stroke
			(width 0.1016)
			(type default)
		)
		(fill no)
		(layer "In7.Cu")
	)
	(gr_circle
		(center 104.561132 -271.656302)
		(end 104.815132 -271.656302)
		(stroke
			(width 0.1016)
			(type default)
		)
		(fill no)
		(layer "In7.Cu")
	)
	(gr_circle
		(center 104.561132 -270.03629)
		(end 104.815132 -270.03629)
		(stroke
			(width 0.1016)
			(type default)
		)
		(fill no)
		(layer "In7.Cu")
	)
	(gr_circle
		(center 104.828594 -175.311054)
		(end 105.717594 -175.311054)
		(stroke
			(width 0.2)
			(type default)
		)
		(fill no)
		(layer "In7.Cu")
	)
	(gr_circle
		(center 104.828594 -174.574454)
		(end 105.717594 -174.574454)
		(stroke
			(width 0.2)
			(type default)
		)
		(fill no)
		(layer "In7.Cu")
	)
	(gr_circle
		(center 105.037382 -341.927688)
		(end 105.917492 -341.927688)
		(stroke
			(width 0.2)
			(type default)
		)
		(fill no)
		(layer "In7.Cu")
	)
	(gr_circle
		(center 105.336848 -177.65776)
		(end 106.225848 -177.65776)
		(stroke
			(width 0.2)
			(type default)
		)
		(fill no)
		(layer "In7.Cu")
	)
	(gr_circle
		(center 105.336848 -176.92116)
		(end 106.225848 -176.92116)
		(stroke
			(width 0.2)
			(type default)
		)
		(fill no)
		(layer "In7.Cu")
	)
	(gr_circle
		(center 105.53065 -176.183544)
		(end 106.41076 -176.183544)
		(stroke
			(width 0.2)
			(type default)
		)
		(fill no)
		(layer "In7.Cu")
	)
	(gr_circle
		(center 105.654602 -341.927688)
		(end 106.534712 -341.927688)
		(stroke
			(width 0.2)
			(type default)
		)
		(fill no)
		(layer "In7.Cu")
	)
	(gr_circle
		(center 105.934002 -341.229442)
		(end 106.814112 -341.229442)
		(stroke
			(width 0.2)
			(type default)
		)
		(fill no)
		(layer "In7.Cu")
	)
	(gr_circle
		(center 105.934002 -340.492842)
		(end 106.814112 -340.492842)
		(stroke
			(width 0.2)
			(type default)
		)
		(fill no)
		(layer "In7.Cu")
	)
	(gr_circle
		(center 106.14787 -176.183544)
		(end 107.02798 -176.183544)
		(stroke
			(width 0.2)
			(type default)
		)
		(fill no)
		(layer "In7.Cu")
	)
	(gr_circle
		(center 106.34345 -343.450164)
		(end 107.23245 -343.450164)
		(stroke
			(width 0.2)
			(type default)
		)
		(fill no)
		(layer "In7.Cu")
	)
	(gr_circle
		(center 106.34345 -342.713564)
		(end 107.23245 -342.713564)
		(stroke
			(width 0.2)
			(type default)
		)
		(fill no)
		(layer "In7.Cu")
	)
	(gr_circle
		(center 106.440986 -279.756362)
		(end 106.694986 -279.756362)
		(stroke
			(width 0.1016)
			(type default)
		)
		(fill no)
		(layer "In7.Cu")
	)
	(gr_circle
		(center 106.440986 -278.13635)
		(end 106.694986 -278.13635)
		(stroke
			(width 0.1016)
			(type default)
		)
		(fill no)
		(layer "In7.Cu")
	)
	(gr_circle
		(center 106.440986 -276.516338)
		(end 106.694986 -276.516338)
		(stroke
			(width 0.1016)
			(type default)
		)
		(fill no)
		(layer "In7.Cu")
	)
	(gr_circle
		(center 106.440986 -274.896326)
		(end 106.694986 -274.896326)
		(stroke
			(width 0.1016)
			(type default)
		)
		(fill no)
		(layer "In7.Cu")
	)
	(gr_circle
		(center 106.440986 -273.276314)
		(end 106.694986 -273.276314)
		(stroke
			(width 0.1016)
			(type default)
		)
		(fill no)
		(layer "In7.Cu")
	)
	(gr_circle
		(center 106.440986 -271.656302)
		(end 106.694986 -271.656302)
		(stroke
			(width 0.1016)
			(type default)
		)
		(fill no)
		(layer "In7.Cu")
	)
	(gr_circle
		(center 106.440986 -270.03629)
		(end 106.694986 -270.03629)
		(stroke
			(width 0.1016)
			(type default)
		)
		(fill no)
		(layer "In7.Cu")
	)
	(gr_circle
		(center 106.76509 -176.183544)
		(end 107.6452 -176.183544)
		(stroke
			(width 0.2)
			(type default)
		)
		(fill no)
		(layer "In7.Cu")
	)
	(gr_circle
		(center 106.98607 -342.540844)
		(end 107.87507 -342.540844)
		(stroke
			(width 0.2)
			(type default)
		)
		(fill no)
		(layer "In7.Cu")
	)
	(gr_circle
		(center 106.98607 -341.804244)
		(end 107.87507 -341.804244)
		(stroke
			(width 0.2)
			(type default)
		)
		(fill no)
		(layer "In7.Cu")
	)
	(gr_circle
		(center 107.01401 -343.986104)
		(end 107.90301 -343.986104)
		(stroke
			(width 0.2)
			(type default)
		)
		(fill no)
		(layer "In7.Cu")
	)
	(gr_circle
		(center 107.01401 -343.249504)
		(end 107.90301 -343.249504)
		(stroke
			(width 0.2)
			(type default)
		)
		(fill no)
		(layer "In7.Cu")
	)
	(gr_circle
		(center 107.38104 -279.756362)
		(end 107.63504 -279.756362)
		(stroke
			(width 0.1016)
			(type default)
		)
		(fill no)
		(layer "In7.Cu")
	)
	(gr_circle
		(center 107.38104 -278.13635)
		(end 107.63504 -278.13635)
		(stroke
			(width 0.1016)
			(type default)
		)
		(fill no)
		(layer "In7.Cu")
	)
	(gr_circle
		(center 107.38104 -276.516338)
		(end 107.63504 -276.516338)
		(stroke
			(width 0.1016)
			(type default)
		)
		(fill no)
		(layer "In7.Cu")
	)
	(gr_circle
		(center 107.38104 -274.896326)
		(end 107.63504 -274.896326)
		(stroke
			(width 0.1016)
			(type default)
		)
		(fill no)
		(layer "In7.Cu")
	)
	(gr_circle
		(center 107.38104 -273.276314)
		(end 107.63504 -273.276314)
		(stroke
			(width 0.1016)
			(type default)
		)
		(fill no)
		(layer "In7.Cu")
	)
	(gr_circle
		(center 107.38104 -271.656302)
		(end 107.63504 -271.656302)
		(stroke
			(width 0.1016)
			(type default)
		)
		(fill no)
		(layer "In7.Cu")
	)
	(gr_circle
		(center 107.38104 -270.03629)
		(end 107.63504 -270.03629)
		(stroke
			(width 0.1016)
			(type default)
		)
		(fill no)
		(layer "In7.Cu")
	)
	(gr_circle
		(center 108.790994 -278.946356)
		(end 109.044994 -278.946356)
		(stroke
			(width 0.1016)
			(type default)
		)
		(fill no)
		(layer "In7.Cu")
	)
	(gr_circle
		(center 108.790994 -277.326344)
		(end 109.044994 -277.326344)
		(stroke
			(width 0.1016)
			(type default)
		)
		(fill no)
		(layer "In7.Cu")
	)
	(gr_circle
		(center 108.790994 -275.706332)
		(end 109.044994 -275.706332)
		(stroke
			(width 0.1016)
			(type default)
		)
		(fill no)
		(layer "In7.Cu")
	)
	(gr_circle
		(center 108.790994 -274.08632)
		(end 109.044994 -274.08632)
		(stroke
			(width 0.1016)
			(type default)
		)
		(fill no)
		(layer "In7.Cu")
	)
	(gr_circle
		(center 108.790994 -272.466308)
		(end 109.044994 -272.466308)
		(stroke
			(width 0.1016)
			(type default)
		)
		(fill no)
		(layer "In7.Cu")
	)
	(gr_circle
		(center 108.790994 -270.846296)
		(end 109.044994 -270.846296)
		(stroke
			(width 0.1016)
			(type default)
		)
		(fill no)
		(layer "In7.Cu")
	)
	(gr_circle
		(center 108.790994 -269.226284)
		(end 109.044994 -269.226284)
		(stroke
			(width 0.1016)
			(type default)
		)
		(fill no)
		(layer "In7.Cu")
	)
	(gr_circle
		(center 109.731048 -278.946356)
		(end 109.985048 -278.946356)
		(stroke
			(width 0.1016)
			(type default)
		)
		(fill no)
		(layer "In7.Cu")
	)
	(gr_circle
		(center 109.731048 -277.326344)
		(end 109.985048 -277.326344)
		(stroke
			(width 0.1016)
			(type default)
		)
		(fill no)
		(layer "In7.Cu")
	)
	(gr_circle
		(center 109.731048 -275.706332)
		(end 109.985048 -275.706332)
		(stroke
			(width 0.1016)
			(type default)
		)
		(fill no)
		(layer "In7.Cu")
	)
	(gr_circle
		(center 109.731048 -274.08632)
		(end 109.985048 -274.08632)
		(stroke
			(width 0.1016)
			(type default)
		)
		(fill no)
		(layer "In7.Cu")
	)
	(gr_circle
		(center 109.731048 -272.466308)
		(end 109.985048 -272.466308)
		(stroke
			(width 0.1016)
			(type default)
		)
		(fill no)
		(layer "In7.Cu")
	)
	(gr_circle
		(center 109.731048 -270.846296)
		(end 109.985048 -270.846296)
		(stroke
			(width 0.1016)
			(type default)
		)
		(fill no)
		(layer "In7.Cu")
	)
	(gr_circle
		(center 109.731048 -269.226284)
		(end 109.985048 -269.226284)
		(stroke
			(width 0.1016)
			(type default)
		)
		(fill no)
		(layer "In7.Cu")
	)
	(gr_circle
		(center 110.140496 -150.941786)
		(end 111.537496 -150.941786)
		(stroke
			(width 0.2)
			(type default)
		)
		(fill no)
		(layer "In7.Cu")
	)
	(gr_circle
		(center 111.97463 -169.857674)
		(end 112.86363 -169.857674)
		(stroke
			(width 0.2)
			(type default)
		)
		(fill no)
		(layer "In7.Cu")
	)
	(gr_circle
		(center 111.97463 -169.121074)
		(end 112.86363 -169.121074)
		(stroke
			(width 0.2)
			(type default)
		)
		(fill no)
		(layer "In7.Cu")
	)
	(gr_circle
		(center 111.97463 -168.384474)
		(end 112.86363 -168.384474)
		(stroke
			(width 0.2)
			(type default)
		)
		(fill no)
		(layer "In7.Cu")
	)
	(gr_circle
		(center 112.50803 -168.740074)
		(end 113.39703 -168.740074)
		(stroke
			(width 0.2)
			(type default)
		)
		(fill no)
		(layer "In7.Cu")
	)
	(gr_circle
		(center 112.53343 -169.502074)
		(end 113.42243 -169.502074)
		(stroke
			(width 0.2)
			(type default)
		)
		(fill no)
		(layer "In7.Cu")
	)
	(gr_circle
		(center 113.058194 -169.062654)
		(end 113.947194 -169.062654)
		(stroke
			(width 0.2)
			(type default)
		)
		(fill no)
		(layer "In7.Cu")
	)
	(gr_circle
		(center 113.058194 -168.326054)
		(end 113.947194 -168.326054)
		(stroke
			(width 0.2)
			(type default)
		)
		(fill no)
		(layer "In7.Cu")
	)
	(gr_circle
		(center 113.591848 -171.33316)
		(end 114.480848 -171.33316)
		(stroke
			(width 0.2)
			(type default)
		)
		(fill no)
		(layer "In7.Cu")
	)
	(gr_circle
		(center 113.591848 -170.59656)
		(end 114.480848 -170.59656)
		(stroke
			(width 0.2)
			(type default)
		)
		(fill no)
		(layer "In7.Cu")
	)
	(gr_circle
		(center 113.76025 -169.935144)
		(end 114.64036 -169.935144)
		(stroke
			(width 0.2)
			(type default)
		)
		(fill no)
		(layer "In7.Cu")
	)
	(gr_circle
		(center 114.37747 -169.935144)
		(end 115.25758 -169.935144)
		(stroke
			(width 0.2)
			(type default)
		)
		(fill no)
		(layer "In7.Cu")
	)
	(gr_circle
		(center 114.424714 -278.946356)
		(end 114.678714 -278.946356)
		(stroke
			(width 0.1016)
			(type default)
		)
		(fill no)
		(layer "In7.Cu")
	)
	(gr_circle
		(center 114.424714 -277.326344)
		(end 114.678714 -277.326344)
		(stroke
			(width 0.1016)
			(type default)
		)
		(fill no)
		(layer "In7.Cu")
	)
	(gr_circle
		(center 114.424714 -275.706332)
		(end 114.678714 -275.706332)
		(stroke
			(width 0.1016)
			(type default)
		)
		(fill no)
		(layer "In7.Cu")
	)
	(gr_circle
		(center 114.424714 -274.08632)
		(end 114.678714 -274.08632)
		(stroke
			(width 0.1016)
			(type default)
		)
		(fill no)
		(layer "In7.Cu")
	)
	(gr_circle
		(center 114.424714 -272.466308)
		(end 114.678714 -272.466308)
		(stroke
			(width 0.1016)
			(type default)
		)
		(fill no)
		(layer "In7.Cu")
	)
	(gr_circle
		(center 114.424714 -270.846296)
		(end 114.678714 -270.846296)
		(stroke
			(width 0.1016)
			(type default)
		)
		(fill no)
		(layer "In7.Cu")
	)
	(gr_circle
		(center 114.424714 -269.226284)
		(end 114.678714 -269.226284)
		(stroke
			(width 0.1016)
			(type default)
		)
		(fill no)
		(layer "In7.Cu")
	)
	(gr_circle
		(center 114.99469 -169.935144)
		(end 115.8748 -169.935144)
		(stroke
			(width 0.2)
			(type default)
		)
		(fill no)
		(layer "In7.Cu")
	)
	(gr_circle
		(center 115.364768 -278.946356)
		(end 115.618768 -278.946356)
		(stroke
			(width 0.1016)
			(type default)
		)
		(fill no)
		(layer "In7.Cu")
	)
	(gr_circle
		(center 115.364768 -277.326344)
		(end 115.618768 -277.326344)
		(stroke
			(width 0.1016)
			(type default)
		)
		(fill no)
		(layer "In7.Cu")
	)
	(gr_circle
		(center 115.364768 -275.706332)
		(end 115.618768 -275.706332)
		(stroke
			(width 0.1016)
			(type default)
		)
		(fill no)
		(layer "In7.Cu")
	)
	(gr_circle
		(center 115.364768 -274.08632)
		(end 115.618768 -274.08632)
		(stroke
			(width 0.1016)
			(type default)
		)
		(fill no)
		(layer "In7.Cu")
	)
	(gr_circle
		(center 115.364768 -272.466308)
		(end 115.618768 -272.466308)
		(stroke
			(width 0.1016)
			(type default)
		)
		(fill no)
		(layer "In7.Cu")
	)
	(gr_circle
		(center 115.364768 -270.846296)
		(end 115.618768 -270.846296)
		(stroke
			(width 0.1016)
			(type default)
		)
		(fill no)
		(layer "In7.Cu")
	)
	(gr_circle
		(center 115.364768 -269.226284)
		(end 115.618768 -269.226284)
		(stroke
			(width 0.1016)
			(type default)
		)
		(fill no)
		(layer "In7.Cu")
	)
	(gr_circle
		(center 116.258594 -152.657556)
		(end 117.147594 -152.657556)
		(stroke
			(width 0.2)
			(type default)
		)
		(fill no)
		(layer "In7.Cu")
	)
	(gr_circle
		(center 116.258594 -152.022556)
		(end 117.147594 -152.022556)
		(stroke
			(width 0.2)
			(type default)
		)
		(fill no)
		(layer "In7.Cu")
	)
	(gr_circle
		(center 116.774722 -279.756362)
		(end 117.028722 -279.756362)
		(stroke
			(width 0.1016)
			(type default)
		)
		(fill no)
		(layer "In7.Cu")
	)
	(gr_circle
		(center 116.774722 -278.13635)
		(end 117.028722 -278.13635)
		(stroke
			(width 0.1016)
			(type default)
		)
		(fill no)
		(layer "In7.Cu")
	)
	(gr_circle
		(center 116.774722 -276.516338)
		(end 117.028722 -276.516338)
		(stroke
			(width 0.1016)
			(type default)
		)
		(fill no)
		(layer "In7.Cu")
	)
	(gr_circle
		(center 116.774722 -274.896326)
		(end 117.028722 -274.896326)
		(stroke
			(width 0.1016)
			(type default)
		)
		(fill no)
		(layer "In7.Cu")
	)
	(gr_circle
		(center 116.774722 -273.276314)
		(end 117.028722 -273.276314)
		(stroke
			(width 0.1016)
			(type default)
		)
		(fill no)
		(layer "In7.Cu")
	)
	(gr_circle
		(center 116.774722 -271.656302)
		(end 117.028722 -271.656302)
		(stroke
			(width 0.1016)
			(type default)
		)
		(fill no)
		(layer "In7.Cu")
	)
	(gr_circle
		(center 116.774722 -270.03629)
		(end 117.028722 -270.03629)
		(stroke
			(width 0.1016)
			(type default)
		)
		(fill no)
		(layer "In7.Cu")
	)
	(gr_circle
		(center 116.893594 -152.657556)
		(end 117.782594 -152.657556)
		(stroke
			(width 0.2)
			(type default)
		)
		(fill no)
		(layer "In7.Cu")
	)
	(gr_circle
		(center 116.893594 -152.022556)
		(end 117.782594 -152.022556)
		(stroke
			(width 0.2)
			(type default)
		)
		(fill no)
		(layer "In7.Cu")
	)
	(gr_circle
		(center 117.559074 -152.657556)
		(end 118.448074 -152.657556)
		(stroke
			(width 0.2)
			(type default)
		)
		(fill no)
		(layer "In7.Cu")
	)
	(gr_circle
		(center 117.559074 -152.022556)
		(end 118.448074 -152.022556)
		(stroke
			(width 0.2)
			(type default)
		)
		(fill no)
		(layer "In7.Cu")
	)
	(gr_circle
		(center 117.714776 -279.756362)
		(end 117.968776 -279.756362)
		(stroke
			(width 0.1016)
			(type default)
		)
		(fill no)
		(layer "In7.Cu")
	)
	(gr_circle
		(center 117.714776 -278.13635)
		(end 117.968776 -278.13635)
		(stroke
			(width 0.1016)
			(type default)
		)
		(fill no)
		(layer "In7.Cu")
	)
	(gr_circle
		(center 117.714776 -276.516338)
		(end 117.968776 -276.516338)
		(stroke
			(width 0.1016)
			(type default)
		)
		(fill no)
		(layer "In7.Cu")
	)
	(gr_circle
		(center 117.714776 -274.896326)
		(end 117.968776 -274.896326)
		(stroke
			(width 0.1016)
			(type default)
		)
		(fill no)
		(layer "In7.Cu")
	)
	(gr_circle
		(center 117.714776 -273.276314)
		(end 117.968776 -273.276314)
		(stroke
			(width 0.1016)
			(type default)
		)
		(fill no)
		(layer "In7.Cu")
	)
	(gr_circle
		(center 117.714776 -271.656302)
		(end 117.968776 -271.656302)
		(stroke
			(width 0.1016)
			(type default)
		)
		(fill no)
		(layer "In7.Cu")
	)
	(gr_circle
		(center 117.714776 -270.03629)
		(end 117.968776 -270.03629)
		(stroke
			(width 0.1016)
			(type default)
		)
		(fill no)
		(layer "In7.Cu")
	)
	(gr_circle
		(center 118.194074 -152.657556)
		(end 119.083074 -152.657556)
		(stroke
			(width 0.2)
			(type default)
		)
		(fill no)
		(layer "In7.Cu")
	)
	(gr_circle
		(center 118.194074 -152.022556)
		(end 119.083074 -152.022556)
		(stroke
			(width 0.2)
			(type default)
		)
		(fill no)
		(layer "In7.Cu")
	)
	(gr_circle
		(center 118.829074 -152.657556)
		(end 119.718074 -152.657556)
		(stroke
			(width 0.2)
			(type default)
		)
		(fill no)
		(layer "In7.Cu")
	)
	(gr_circle
		(center 118.829074 -152.022556)
		(end 119.718074 -152.022556)
		(stroke
			(width 0.2)
			(type default)
		)
		(fill no)
		(layer "In7.Cu")
	)
	(gr_circle
		(center 119.464074 -152.657556)
		(end 120.353074 -152.657556)
		(stroke
			(width 0.2)
			(type default)
		)
		(fill no)
		(layer "In7.Cu")
	)
	(gr_circle
		(center 119.464074 -152.022556)
		(end 120.353074 -152.022556)
		(stroke
			(width 0.2)
			(type default)
		)
		(fill no)
		(layer "In7.Cu")
	)
	(gr_circle
		(center 119.59463 -278.13635)
		(end 119.84863 -278.13635)
		(stroke
			(width 0.1016)
			(type default)
		)
		(fill no)
		(layer "In7.Cu")
	)
	(gr_circle
		(center 119.59463 -276.516338)
		(end 119.84863 -276.516338)
		(stroke
			(width 0.1016)
			(type default)
		)
		(fill no)
		(layer "In7.Cu")
	)
	(gr_circle
		(center 119.59463 -274.896326)
		(end 119.84863 -274.896326)
		(stroke
			(width 0.1016)
			(type default)
		)
		(fill no)
		(layer "In7.Cu")
	)
	(gr_circle
		(center 119.59463 -273.276314)
		(end 119.84863 -273.276314)
		(stroke
			(width 0.1016)
			(type default)
		)
		(fill no)
		(layer "In7.Cu")
	)
	(gr_circle
		(center 119.59463 -271.656302)
		(end 119.84863 -271.656302)
		(stroke
			(width 0.1016)
			(type default)
		)
		(fill no)
		(layer "In7.Cu")
	)
	(gr_circle
		(center 119.59463 -270.03629)
		(end 119.84863 -270.03629)
		(stroke
			(width 0.1016)
			(type default)
		)
		(fill no)
		(layer "In7.Cu")
	)
	(gr_circle
		(center 120.25503 -163.126674)
		(end 121.14403 -163.126674)
		(stroke
			(width 0.2)
			(type default)
		)
		(fill no)
		(layer "In7.Cu")
	)
	(gr_circle
		(center 120.25503 -162.390074)
		(end 121.14403 -162.390074)
		(stroke
			(width 0.2)
			(type default)
		)
		(fill no)
		(layer "In7.Cu")
	)
	(gr_circle
		(center 120.25503 -161.653474)
		(end 121.14403 -161.653474)
		(stroke
			(width 0.2)
			(type default)
		)
		(fill no)
		(layer "In7.Cu")
	)
	(gr_circle
		(center 120.534684 -278.13635)
		(end 120.788684 -278.13635)
		(stroke
			(width 0.1016)
			(type default)
		)
		(fill no)
		(layer "In7.Cu")
	)
	(gr_circle
		(center 120.534684 -276.516338)
		(end 120.788684 -276.516338)
		(stroke
			(width 0.1016)
			(type default)
		)
		(fill no)
		(layer "In7.Cu")
	)
	(gr_circle
		(center 120.534684 -274.896326)
		(end 120.788684 -274.896326)
		(stroke
			(width 0.1016)
			(type default)
		)
		(fill no)
		(layer "In7.Cu")
	)
	(gr_circle
		(center 120.534684 -273.276314)
		(end 120.788684 -273.276314)
		(stroke
			(width 0.1016)
			(type default)
		)
		(fill no)
		(layer "In7.Cu")
	)
	(gr_circle
		(center 120.534684 -271.656302)
		(end 120.788684 -271.656302)
		(stroke
			(width 0.1016)
			(type default)
		)
		(fill no)
		(layer "In7.Cu")
	)
	(gr_circle
		(center 120.534684 -270.03629)
		(end 120.788684 -270.03629)
		(stroke
			(width 0.1016)
			(type default)
		)
		(fill no)
		(layer "In7.Cu")
	)
	(gr_circle
		(center 120.78843 -162.009074)
		(end 121.67743 -162.009074)
		(stroke
			(width 0.2)
			(type default)
		)
		(fill no)
		(layer "In7.Cu")
	)
	(gr_circle
		(center 120.81383 -162.771074)
		(end 121.70283 -162.771074)
		(stroke
			(width 0.2)
			(type default)
		)
		(fill no)
		(layer "In7.Cu")
	)
	(gr_circle
		(center 121.338594 -162.331654)
		(end 122.227594 -162.331654)
		(stroke
			(width 0.2)
			(type default)
		)
		(fill no)
		(layer "In7.Cu")
	)
	(gr_circle
		(center 121.338594 -161.595054)
		(end 122.227594 -161.595054)
		(stroke
			(width 0.2)
			(type default)
		)
		(fill no)
		(layer "In7.Cu")
	)
	(gr_circle
		(center 121.872248 -164.62756)
		(end 122.761248 -164.62756)
		(stroke
			(width 0.2)
			(type default)
		)
		(fill no)
		(layer "In7.Cu")
	)
	(gr_circle
		(center 121.872248 -163.89096)
		(end 122.761248 -163.89096)
		(stroke
			(width 0.2)
			(type default)
		)
		(fill no)
		(layer "In7.Cu")
	)
	(gr_circle
		(center 122.04065 -163.204144)
		(end 122.92076 -163.204144)
		(stroke
			(width 0.2)
			(type default)
		)
		(fill no)
		(layer "In7.Cu")
	)
	(gr_circle
		(center 122.414792 -278.13635)
		(end 122.668792 -278.13635)
		(stroke
			(width 0.1016)
			(type default)
		)
		(fill no)
		(layer "In7.Cu")
	)
	(gr_circle
		(center 122.414792 -276.516338)
		(end 122.668792 -276.516338)
		(stroke
			(width 0.1016)
			(type default)
		)
		(fill no)
		(layer "In7.Cu")
	)
	(gr_circle
		(center 122.414792 -274.896326)
		(end 122.668792 -274.896326)
		(stroke
			(width 0.1016)
			(type default)
		)
		(fill no)
		(layer "In7.Cu")
	)
	(gr_circle
		(center 122.414792 -273.276314)
		(end 122.668792 -273.276314)
		(stroke
			(width 0.1016)
			(type default)
		)
		(fill no)
		(layer "In7.Cu")
	)
	(gr_circle
		(center 122.414792 -271.656302)
		(end 122.668792 -271.656302)
		(stroke
			(width 0.1016)
			(type default)
		)
		(fill no)
		(layer "In7.Cu")
	)
	(gr_circle
		(center 122.414792 -270.03629)
		(end 122.668792 -270.03629)
		(stroke
			(width 0.1016)
			(type default)
		)
		(fill no)
		(layer "In7.Cu")
	)
	(gr_circle
		(center 122.65787 -163.204144)
		(end 123.53798 -163.204144)
		(stroke
			(width 0.2)
			(type default)
		)
		(fill no)
		(layer "In7.Cu")
	)
	(gr_circle
		(center 123.27509 -163.204144)
		(end 124.1552 -163.204144)
		(stroke
			(width 0.2)
			(type default)
		)
		(fill no)
		(layer "In7.Cu")
	)
	(gr_circle
		(center 123.354846 -278.13635)
		(end 123.608846 -278.13635)
		(stroke
			(width 0.1016)
			(type default)
		)
		(fill no)
		(layer "In7.Cu")
	)
	(gr_circle
		(center 123.354846 -276.516338)
		(end 123.608846 -276.516338)
		(stroke
			(width 0.1016)
			(type default)
		)
		(fill no)
		(layer "In7.Cu")
	)
	(gr_circle
		(center 123.354846 -274.896326)
		(end 123.608846 -274.896326)
		(stroke
			(width 0.1016)
			(type default)
		)
		(fill no)
		(layer "In7.Cu")
	)
	(gr_circle
		(center 123.354846 -273.276314)
		(end 123.608846 -273.276314)
		(stroke
			(width 0.1016)
			(type default)
		)
		(fill no)
		(layer "In7.Cu")
	)
	(gr_circle
		(center 123.354846 -271.656302)
		(end 123.608846 -271.656302)
		(stroke
			(width 0.1016)
			(type default)
		)
		(fill no)
		(layer "In7.Cu")
	)
	(gr_circle
		(center 123.354846 -270.03629)
		(end 123.608846 -270.03629)
		(stroke
			(width 0.1016)
			(type default)
		)
		(fill no)
		(layer "In7.Cu")
	)
	(gr_arc
		(start 124.102114 -11.780012)
		(mid 125.516325 -11.194227)
		(end 126.10211 -9.780016)
		(stroke
			(width 1.016)
			(type default)
		)
		(layer "In7.Cu")
	)
	(gr_circle
		(center 125.2347 -278.13635)
		(end 125.4887 -278.13635)
		(stroke
			(width 0.1016)
			(type default)
		)
		(fill no)
		(layer "In7.Cu")
	)
	(gr_circle
		(center 125.2347 -276.516338)
		(end 125.4887 -276.516338)
		(stroke
			(width 0.1016)
			(type default)
		)
		(fill no)
		(layer "In7.Cu")
	)
	(gr_circle
		(center 125.2347 -274.896326)
		(end 125.4887 -274.896326)
		(stroke
			(width 0.1016)
			(type default)
		)
		(fill no)
		(layer "In7.Cu")
	)
	(gr_circle
		(center 125.2347 -273.276314)
		(end 125.4887 -273.276314)
		(stroke
			(width 0.1016)
			(type default)
		)
		(fill no)
		(layer "In7.Cu")
	)
	(gr_circle
		(center 125.2347 -271.656302)
		(end 125.4887 -271.656302)
		(stroke
			(width 0.1016)
			(type default)
		)
		(fill no)
		(layer "In7.Cu")
	)
	(gr_circle
		(center 125.2347 -270.03629)
		(end 125.4887 -270.03629)
		(stroke
			(width 0.1016)
			(type default)
		)
		(fill no)
		(layer "In7.Cu")
	)
	(gr_line
		(start 126.10211 -9.780016)
		(end 126.10211 -5.780024)
		(stroke
			(width 1.016)
			(type default)
		)
		(layer "In7.Cu")
	)
	(gr_circle
		(center 126.174754 -278.13635)
		(end 126.428754 -278.13635)
		(stroke
			(width 0.1016)
			(type default)
		)
		(fill no)
		(layer "In7.Cu")
	)
	(gr_circle
		(center 126.174754 -276.516338)
		(end 126.428754 -276.516338)
		(stroke
			(width 0.1016)
			(type default)
		)
		(fill no)
		(layer "In7.Cu")
	)
	(gr_circle
		(center 126.174754 -274.896326)
		(end 126.428754 -274.896326)
		(stroke
			(width 0.1016)
			(type default)
		)
		(fill no)
		(layer "In7.Cu")
	)
	(gr_circle
		(center 126.174754 -273.276314)
		(end 126.428754 -273.276314)
		(stroke
			(width 0.1016)
			(type default)
		)
		(fill no)
		(layer "In7.Cu")
	)
	(gr_circle
		(center 126.174754 -271.656302)
		(end 126.428754 -271.656302)
		(stroke
			(width 0.1016)
			(type default)
		)
		(fill no)
		(layer "In7.Cu")
	)
	(gr_circle
		(center 126.174754 -270.03629)
		(end 126.428754 -270.03629)
		(stroke
			(width 0.1016)
			(type default)
		)
		(fill no)
		(layer "In7.Cu")
	)
	(gr_arc
		(start 126.601982 -5.279898)
		(mid 126.248489 -5.42646)
		(end 126.10211 -5.780024)
		(stroke
			(width 1.016)
			(type default)
		)
		(layer "In7.Cu")
	)
	(gr_line
		(start 126.601982 -5.279898)
		(end 194.20205 -5.279898)
		(stroke
			(width 1.016)
			(type default)
		)
		(layer "In7.Cu")
	)
	(gr_circle
		(center 128.71323 -154.465274)
		(end 129.60223 -154.465274)
		(stroke
			(width 0.2)
			(type default)
		)
		(fill no)
		(layer "In7.Cu")
	)
	(gr_circle
		(center 128.71323 -153.728674)
		(end 129.60223 -153.728674)
		(stroke
			(width 0.2)
			(type default)
		)
		(fill no)
		(layer "In7.Cu")
	)
	(gr_circle
		(center 128.71323 -152.992074)
		(end 129.60223 -152.992074)
		(stroke
			(width 0.2)
			(type default)
		)
		(fill no)
		(layer "In7.Cu")
	)
	(gr_circle
		(center 129.24663 -153.347674)
		(end 130.13563 -153.347674)
		(stroke
			(width 0.2)
			(type default)
		)
		(fill no)
		(layer "In7.Cu")
	)
	(gr_circle
		(center 129.27203 -154.109674)
		(end 130.16103 -154.109674)
		(stroke
			(width 0.2)
			(type default)
		)
		(fill no)
		(layer "In7.Cu")
	)
	(gr_circle
		(center 129.796794 -153.670254)
		(end 130.685794 -153.670254)
		(stroke
			(width 0.2)
			(type default)
		)
		(fill no)
		(layer "In7.Cu")
	)
	(gr_circle
		(center 129.796794 -152.933654)
		(end 130.685794 -152.933654)
		(stroke
			(width 0.2)
			(type default)
		)
		(fill no)
		(layer "In7.Cu")
	)
	(gr_circle
		(center 130.305048 -155.94076)
		(end 131.194048 -155.94076)
		(stroke
			(width 0.2)
			(type default)
		)
		(fill no)
		(layer "In7.Cu")
	)
	(gr_circle
		(center 130.305048 -155.20416)
		(end 131.194048 -155.20416)
		(stroke
			(width 0.2)
			(type default)
		)
		(fill no)
		(layer "In7.Cu")
	)
	(gr_circle
		(center 130.49885 -154.542744)
		(end 131.37896 -154.542744)
		(stroke
			(width 0.2)
			(type default)
		)
		(fill no)
		(layer "In7.Cu")
	)
	(gr_circle
		(center 131.11607 -154.542744)
		(end 131.99618 -154.542744)
		(stroke
			(width 0.2)
			(type default)
		)
		(fill no)
		(layer "In7.Cu")
	)
	(gr_circle
		(center 131.73329 -154.542744)
		(end 132.6134 -154.542744)
		(stroke
			(width 0.2)
			(type default)
		)
		(fill no)
		(layer "In7.Cu")
	)
	(gr_circle
		(center 176.332134 -26.634948)
		(end 177.221134 -26.634948)
		(stroke
			(width 0.2)
			(type default)
		)
		(fill no)
		(layer "In7.Cu")
	)
	(gr_circle
		(center 176.713134 -25.949148)
		(end 177.602134 -25.949148)
		(stroke
			(width 0.2)
			(type default)
		)
		(fill no)
		(layer "In7.Cu")
	)
	(gr_circle
		(center 176.878234 -19.942048)
		(end 177.767234 -19.942048)
		(stroke
			(width 0.2)
			(type default)
		)
		(fill no)
		(layer "In7.Cu")
	)
	(gr_circle
		(center 176.968912 -21.349208)
		(end 177.857912 -21.349208)
		(stroke
			(width 0.2)
			(type default)
		)
		(fill no)
		(layer "In7.Cu")
	)
	(gr_circle
		(center 176.968912 -20.714208)
		(end 177.857912 -20.714208)
		(stroke
			(width 0.2)
			(type default)
		)
		(fill no)
		(layer "In7.Cu")
	)
	(gr_circle
		(center 177.221134 -26.634948)
		(end 178.110134 -26.634948)
		(stroke
			(width 0.2)
			(type default)
		)
		(fill no)
		(layer "In7.Cu")
	)
	(gr_circle
		(center 177.472594 -21.85289)
		(end 178.361594 -21.85289)
		(stroke
			(width 0.2)
			(type default)
		)
		(fill no)
		(layer "In7.Cu")
	)
	(gr_circle
		(center 177.602134 -25.949148)
		(end 178.491134 -25.949148)
		(stroke
			(width 0.2)
			(type default)
		)
		(fill no)
		(layer "In7.Cu")
	)
	(gr_circle
		(center 178.110134 -26.634948)
		(end 178.999134 -26.634948)
		(stroke
			(width 0.2)
			(type default)
		)
		(fill no)
		(layer "In7.Cu")
	)
	(gr_circle
		(center 178.491134 -25.949148)
		(end 179.380134 -25.949148)
		(stroke
			(width 0.2)
			(type default)
		)
		(fill no)
		(layer "In7.Cu")
	)
	(gr_circle
		(center 179.507134 -25.517348)
		(end 180.396134 -25.517348)
		(stroke
			(width 0.2)
			(type default)
		)
		(fill no)
		(layer "In7.Cu")
	)
	(gr_circle
		(center 180.921914 -27.107388)
		(end 181.810914 -27.107388)
		(stroke
			(width 0.2)
			(type default)
		)
		(fill no)
		(layer "In7.Cu")
	)
	(gr_circle
		(center 183.610758 -353.283774)
		(end 184.490868 -353.283774)
		(stroke
			(width 0.2)
			(type default)
		)
		(fill no)
		(layer "In7.Cu")
	)
	(gr_circle
		(center 184.227978 -353.283774)
		(end 185.108088 -353.283774)
		(stroke
			(width 0.2)
			(type default)
		)
		(fill no)
		(layer "In7.Cu")
	)
	(gr_line
		(start 184.258458 -410.708348)
		(end 184.258458 -400.09572)
		(stroke
			(width 0.635)
			(type default)
		)
		(layer "In7.Cu")
	)
	(gr_line
		(start 184.258458 -400.09572)
		(end 184.463944 -399.890234)
		(stroke
			(width 0.635)
			(type default)
		)
		(layer "In7.Cu")
	)
	(gr_line
		(start 184.463944 -399.890234)
		(end 188.119004 -399.890234)
		(stroke
			(width 0.635)
			(type default)
		)
		(layer "In7.Cu")
	)
	(gr_line
		(start 184.8104 -411.26029)
		(end 184.258458 -410.708348)
		(stroke
			(width 0.635)
			(type default)
		)
		(layer "In7.Cu")
	)
	(gr_circle
		(center 184.845198 -353.283774)
		(end 185.725308 -353.283774)
		(stroke
			(width 0.2)
			(type default)
		)
		(fill no)
		(layer "In7.Cu")
	)
	(gr_circle
		(center 184.962292 -352.558604)
		(end 185.851292 -352.558604)
		(stroke
			(width 0.2)
			(type default)
		)
		(fill no)
		(layer "In7.Cu")
	)
	(gr_circle
		(center 184.962292 -351.822004)
		(end 185.851292 -351.822004)
		(stroke
			(width 0.2)
			(type default)
		)
		(fill no)
		(layer "In7.Cu")
	)
	(gr_circle
		(center 185.547254 -354.892864)
		(end 186.436254 -354.892864)
		(stroke
			(width 0.2)
			(type default)
		)
		(fill no)
		(layer "In7.Cu")
	)
	(gr_circle
		(center 185.547254 -354.156264)
		(end 186.436254 -354.156264)
		(stroke
			(width 0.2)
			(type default)
		)
		(fill no)
		(layer "In7.Cu")
	)
	(gr_circle
		(center 186.034172 -362.234988)
		(end 186.923172 -362.234988)
		(stroke
			(width 0.2)
			(type default)
		)
		(fill no)
		(layer "In7.Cu")
	)
	(gr_circle
		(center 186.034172 -361.472988)
		(end 186.923172 -361.472988)
		(stroke
			(width 0.2)
			(type default)
		)
		(fill no)
		(layer "In7.Cu")
	)
	(gr_circle
		(center 186.034172 -360.710988)
		(end 186.923172 -360.710988)
		(stroke
			(width 0.2)
			(type default)
		)
		(fill no)
		(layer "In7.Cu")
	)
	(gr_circle
		(center 186.072018 -353.716844)
		(end 186.961018 -353.716844)
		(stroke
			(width 0.2)
			(type default)
		)
		(fill no)
		(layer "In7.Cu")
	)
	(gr_circle
		(center 186.097418 -354.478844)
		(end 186.986418 -354.478844)
		(stroke
			(width 0.2)
			(type default)
		)
		(fill no)
		(layer "In7.Cu")
	)
	(gr_circle
		(center 186.630818 -354.834444)
		(end 187.519818 -354.834444)
		(stroke
			(width 0.2)
			(type default)
		)
		(fill no)
		(layer "In7.Cu")
	)
	(gr_circle
		(center 186.630818 -354.097844)
		(end 187.519818 -354.097844)
		(stroke
			(width 0.2)
			(type default)
		)
		(fill no)
		(layer "In7.Cu")
	)
	(gr_circle
		(center 186.630818 -353.361244)
		(end 187.519818 -353.361244)
		(stroke
			(width 0.2)
			(type default)
		)
		(fill no)
		(layer "In7.Cu")
	)
	(gr_circle
		(center 186.796172 -362.234988)
		(end 187.685172 -362.234988)
		(stroke
			(width 0.2)
			(type default)
		)
		(fill no)
		(layer "In7.Cu")
	)
	(gr_circle
		(center 186.796172 -361.472988)
		(end 187.685172 -361.472988)
		(stroke
			(width 0.2)
			(type default)
		)
		(fill no)
		(layer "In7.Cu")
	)
	(gr_circle
		(center 186.796172 -360.710988)
		(end 187.685172 -360.710988)
		(stroke
			(width 0.2)
			(type default)
		)
		(fill no)
		(layer "In7.Cu")
	)
	(gr_line
		(start 187.965334 -411.26029)
		(end 184.8104 -411.26029)
		(stroke
			(width 0.635)
			(type default)
		)
		(layer "In7.Cu")
	)
	(gr_line
		(start 188.119004 -399.890234)
		(end 188.303916 -400.075146)
		(stroke
			(width 0.635)
			(type default)
		)
		(layer "In7.Cu")
	)
	(gr_line
		(start 188.303916 -402.905976)
		(end 191.073786 -405.675846)
		(stroke
			(width 0.635)
			(type default)
		)
		(layer "In7.Cu")
	)
	(gr_line
		(start 188.303916 -400.075146)
		(end 188.303916 -402.905976)
		(stroke
			(width 0.635)
			(type default)
		)
		(layer "In7.Cu")
	)
	(gr_line
		(start 188.720222 -412.015178)
		(end 187.965334 -411.26029)
		(stroke
			(width 0.635)
			(type default)
		)
		(layer "In7.Cu")
	)
	(gr_circle
		(center 190.508636 -23.593552)
		(end 191.397636 -23.593552)
		(stroke
			(width 0.2)
			(type default)
		)
		(fill no)
		(layer "In7.Cu")
	)
	(gr_circle
		(center 190.508636 -22.856952)
		(end 191.397636 -22.856952)
		(stroke
			(width 0.2)
			(type default)
		)
		(fill no)
		(layer "In7.Cu")
	)
	(gr_line
		(start 191.073786 -405.675846)
		(end 195.418964 -405.675846)
		(stroke
			(width 0.635)
			(type default)
		)
		(layer "In7.Cu")
	)
	(gr_circle
		(center 191.67983 -362.430568)
		(end 193.07683 -362.430568)
		(stroke
			(width 0.2)
			(type default)
		)
		(fill no)
		(layer "In7.Cu")
	)
	(gr_circle
		(center 191.927734 -13.106908)
		(end 192.816734 -13.106908)
		(stroke
			(width 0.2)
			(type default)
		)
		(fill no)
		(layer "In7.Cu")
	)
	(gr_circle
		(center 191.937386 -353.309174)
		(end 192.817496 -353.309174)
		(stroke
			(width 0.2)
			(type default)
		)
		(fill no)
		(layer "In7.Cu")
	)
	(gr_circle
		(center 192.461134 -16.416528)
		(end 193.350134 -16.416528)
		(stroke
			(width 0.2)
			(type default)
		)
		(fill no)
		(layer "In7.Cu")
	)
	(gr_circle
		(center 192.461134 -15.781528)
		(end 193.350134 -15.781528)
		(stroke
			(width 0.2)
			(type default)
		)
		(fill no)
		(layer "In7.Cu")
	)
	(gr_circle
		(center 192.554606 -353.309174)
		(end 193.434716 -353.309174)
		(stroke
			(width 0.2)
			(type default)
		)
		(fill no)
		(layer "In7.Cu")
	)
	(gr_circle
		(center 192.689734 -13.106908)
		(end 193.578734 -13.106908)
		(stroke
			(width 0.2)
			(type default)
		)
		(fill no)
		(layer "In7.Cu")
	)
	(gr_circle
		(center 193.096134 -16.416528)
		(end 193.985134 -16.416528)
		(stroke
			(width 0.2)
			(type default)
		)
		(fill no)
		(layer "In7.Cu")
	)
	(gr_circle
		(center 193.096134 -15.781528)
		(end 193.985134 -15.781528)
		(stroke
			(width 0.2)
			(type default)
		)
		(fill no)
		(layer "In7.Cu")
	)
	(gr_circle
		(center 193.171826 -353.309174)
		(end 194.051936 -353.309174)
		(stroke
			(width 0.2)
			(type default)
		)
		(fill no)
		(layer "In7.Cu")
	)
	(gr_circle
		(center 193.28892 -352.563684)
		(end 194.17792 -352.563684)
		(stroke
			(width 0.2)
			(type default)
		)
		(fill no)
		(layer "In7.Cu")
	)
	(gr_circle
		(center 193.28892 -351.827084)
		(end 194.17792 -351.827084)
		(stroke
			(width 0.2)
			(type default)
		)
		(fill no)
		(layer "In7.Cu")
	)
	(gr_circle
		(center 193.731134 -15.781528)
		(end 194.620134 -15.781528)
		(stroke
			(width 0.2)
			(type default)
		)
		(fill no)
		(layer "In7.Cu")
	)
	(gr_circle
		(center 193.858134 -16.543528)
		(end 194.747134 -16.543528)
		(stroke
			(width 0.2)
			(type default)
		)
		(fill no)
		(layer "In7.Cu")
	)
	(gr_circle
		(center 193.873882 -354.918264)
		(end 194.762882 -354.918264)
		(stroke
			(width 0.2)
			(type default)
		)
		(fill no)
		(layer "In7.Cu")
	)
	(gr_circle
		(center 193.873882 -354.181664)
		(end 194.762882 -354.181664)
		(stroke
			(width 0.2)
			(type default)
		)
		(fill no)
		(layer "In7.Cu")
	)
	(gr_circle
		(center 194.398646 -353.742244)
		(end 195.287646 -353.742244)
		(stroke
			(width 0.2)
			(type default)
		)
		(fill no)
		(layer "In7.Cu")
	)
	(gr_circle
		(center 194.424046 -354.504244)
		(end 195.313046 -354.504244)
		(stroke
			(width 0.2)
			(type default)
		)
		(fill no)
		(layer "In7.Cu")
	)
	(gr_line
		(start 194.505072 -441.989972)
		(end 8.50011 -441.989972)
		(stroke
			(width 1.016)
			(type default)
		)
		(layer "In7.Cu")
	)
	(gr_arc
		(start 194.505072 -441.989972)
		(mid 194.858553 -441.843573)
		(end 195.004944 -441.4901)
		(stroke
			(width 1.016)
			(type default)
		)
		(layer "In7.Cu")
	)
	(gr_arc
		(start 194.701922 -9.780016)
		(mid 195.287707 -11.194227)
		(end 196.701918 -11.780012)
		(stroke
			(width 1.016)
			(type default)
		)
		(layer "In7.Cu")
	)
	(gr_arc
		(start 194.701922 -5.780024)
		(mid 194.555654 -5.42634)
		(end 194.20205 -5.279898)
		(stroke
			(width 1.016)
			(type default)
		)
		(layer "In7.Cu")
	)
	(gr_line
		(start 194.701922 -5.780024)
		(end 194.701922 -9.780016)
		(stroke
			(width 1.016)
			(type default)
		)
		(layer "In7.Cu")
	)
	(gr_circle
		(center 194.957446 -354.859844)
		(end 195.846446 -354.859844)
		(stroke
			(width 0.2)
			(type default)
		)
		(fill no)
		(layer "In7.Cu")
	)
	(gr_circle
		(center 194.957446 -354.123244)
		(end 195.846446 -354.123244)
		(stroke
			(width 0.2)
			(type default)
		)
		(fill no)
		(layer "In7.Cu")
	)
	(gr_circle
		(center 194.957446 -353.386644)
		(end 195.846446 -353.386644)
		(stroke
			(width 0.2)
			(type default)
		)
		(fill no)
		(layer "In7.Cu")
	)
	(gr_line
		(start 195.004944 -441.17006)
		(end 195.004944 -441.4901)
		(stroke
			(width 1.016)
			(type default)
		)
		(layer "In7.Cu")
	)
	(gr_line
		(start 195.270882 -412.015178)
		(end 188.720222 -412.015178)
		(stroke
			(width 0.635)
			(type default)
		)
		(layer "In7.Cu")
	)
	(gr_line
		(start 195.418964 -405.675846)
		(end 197.51167 -403.58314)
		(stroke
			(width 0.635)
			(type default)
		)
		(layer "In7.Cu")
	)
	(gr_arc
		(start 195.50507 -440.669934)
		(mid 195.151428 -440.816418)
		(end 195.004944 -441.17006)
		(stroke
			(width 1.016)
			(type default)
		)
		(layer "In7.Cu")
	)
	(gr_line
		(start 196.432424 -421.71112)
		(end 196.432424 -413.17672)
		(stroke
			(width 0.635)
			(type default)
		)
		(layer "In7.Cu")
	)
	(gr_line
		(start 196.432424 -413.17672)
		(end 195.270882 -412.015178)
		(stroke
			(width 0.635)
			(type default)
		)
		(layer "In7.Cu")
	)
	(gr_line
		(start 196.701918 -11.780012)
		(end 221.30004 -11.780012)
		(stroke
			(width 1.016)
			(type default)
		)
		(layer "In7.Cu")
	)
	(gr_line
		(start 197.51167 -403.58314)
		(end 197.51167 -400.104356)
		(stroke
			(width 0.635)
			(type default)
		)
		(layer "In7.Cu")
	)
	(gr_line
		(start 197.51167 -400.104356)
		(end 197.764146 -399.85188)
		(stroke
			(width 0.635)
			(type default)
		)
		(layer "In7.Cu")
	)
	(gr_line
		(start 197.764146 -399.85188)
		(end 201.33818 -399.85188)
		(stroke
			(width 0.635)
			(type default)
		)
		(layer "In7.Cu")
	)
	(gr_circle
		(center 198.160386 -37.328094)
		(end 199.049386 -37.328094)
		(stroke
			(width 0.2)
			(type default)
		)
		(fill no)
		(layer "In7.Cu")
	)
	(gr_circle
		(center 198.486014 -30.133798)
		(end 199.375014 -30.133798)
		(stroke
			(width 0.2)
			(type default)
		)
		(fill no)
		(layer "In7.Cu")
	)
	(gr_circle
		(center 198.836026 -37.965634)
		(end 199.725026 -37.965634)
		(stroke
			(width 0.2)
			(type default)
		)
		(fill no)
		(layer "In7.Cu")
	)
	(gr_circle
		(center 199.121014 -30.133798)
		(end 200.010014 -30.133798)
		(stroke
			(width 0.2)
			(type default)
		)
		(fill no)
		(layer "In7.Cu")
	)
	(gr_circle
		(center 199.435974 -30.720538)
		(end 200.324974 -30.720538)
		(stroke
			(width 0.2)
			(type default)
		)
		(fill no)
		(layer "In7.Cu")
	)
	(gr_circle
		(center 199.756014 -30.133798)
		(end 200.645014 -30.133798)
		(stroke
			(width 0.2)
			(type default)
		)
		(fill no)
		(layer "In7.Cu")
	)
	(gr_circle
		(center 200.070974 -30.720538)
		(end 200.959974 -30.720538)
		(stroke
			(width 0.2)
			(type default)
		)
		(fill no)
		(layer "In7.Cu")
	)
	(gr_circle
		(center 200.33234 -378.160534)
		(end 201.22134 -378.160534)
		(stroke
			(width 0.2)
			(type default)
		)
		(fill no)
		(layer "In7.Cu")
	)
	(gr_circle
		(center 200.391014 -30.133798)
		(end 201.280014 -30.133798)
		(stroke
			(width 0.2)
			(type default)
		)
		(fill no)
		(layer "In7.Cu")
	)
	(gr_circle
		(center 200.705974 -30.720538)
		(end 201.594974 -30.720538)
		(stroke
			(width 0.2)
			(type default)
		)
		(fill no)
		(layer "In7.Cu")
	)
	(gr_line
		(start 201.33818 -399.85188)
		(end 201.59853 -400.11223)
		(stroke
			(width 0.635)
			(type default)
		)
		(layer "In7.Cu")
	)
	(gr_circle
		(center 201.340974 -30.720538)
		(end 202.229974 -30.720538)
		(stroke
			(width 0.2)
			(type default)
		)
		(fill no)
		(layer "In7.Cu")
	)
	(gr_line
		(start 201.59853 -403.575266)
		(end 201.811636 -403.788372)
		(stroke
			(width 0.635)
			(type default)
		)
		(layer "In7.Cu")
	)
	(gr_line
		(start 201.59853 -400.11223)
		(end 201.59853 -403.575266)
		(stroke
			(width 0.635)
			(type default)
		)
		(layer "In7.Cu")
	)
	(gr_circle
		(center 201.745342 -346.583)
		(end 202.634342 -346.583)
		(stroke
			(width 0.2)
			(type default)
		)
		(fill no)
		(layer "In7.Cu")
	)
	(gr_circle
		(center 201.745342 -345.821)
		(end 202.634342 -345.821)
		(stroke
			(width 0.2)
			(type default)
		)
		(fill no)
		(layer "In7.Cu")
	)
	(gr_circle
		(center 201.745342 -344.8304)
		(end 202.634342 -344.8304)
		(stroke
			(width 0.2)
			(type default)
		)
		(fill no)
		(layer "In7.Cu")
	)
	(gr_circle
		(center 201.745342 -344.0684)
		(end 202.634342 -344.0684)
		(stroke
			(width 0.2)
			(type default)
		)
		(fill no)
		(layer "In7.Cu")
	)
	(gr_line
		(start 201.811636 -406.668732)
		(end 203.461112 -408.318208)
		(stroke
			(width 0.635)
			(type default)
		)
		(layer "In7.Cu")
	)
	(gr_line
		(start 201.811636 -403.788372)
		(end 201.811636 -406.668732)
		(stroke
			(width 0.635)
			(type default)
		)
		(layer "In7.Cu")
	)
	(gr_line
		(start 203.461112 -408.318208)
		(end 205.948026 -408.318208)
		(stroke
			(width 0.635)
			(type default)
		)
		(layer "In7.Cu")
	)
	(gr_line
		(start 205.73746 -435.231032)
		(end 205.73746 -431.016156)
		(stroke
			(width 0.635)
			(type default)
		)
		(layer "In7.Cu")
	)
	(gr_line
		(start 205.73746 -435.231032)
		(end 207.302608 -436.79618)
		(stroke
			(width 0.635)
			(type default)
		)
		(layer "In7.Cu")
	)
	(gr_line
		(start 205.73746 -431.016156)
		(end 196.432424 -421.71112)
		(stroke
			(width 0.635)
			(type default)
		)
		(layer "In7.Cu")
	)
	(gr_line
		(start 205.948026 -408.318208)
		(end 207.991202 -406.275032)
		(stroke
			(width 0.635)
			(type default)
		)
		(layer "In7.Cu")
	)
	(gr_line
		(start 207.302608 -436.79618)
		(end 229.074472 -436.79618)
		(stroke
			(width 0.635)
			(type default)
		)
		(layer "In7.Cu")
	)
	(gr_line
		(start 207.991202 -406.275032)
		(end 207.991202 -403.722586)
		(stroke
			(width 0.635)
			(type default)
		)
		(layer "In7.Cu")
	)
	(gr_line
		(start 207.991202 -403.722586)
		(end 208.17967 -403.534118)
		(stroke
			(width 0.635)
			(type default)
		)
		(layer "In7.Cu")
	)
	(gr_line
		(start 208.17967 -403.534118)
		(end 208.17967 -400.079464)
		(stroke
			(width 0.635)
			(type default)
		)
		(layer "In7.Cu")
	)
	(gr_line
		(start 208.17967 -400.079464)
		(end 208.42605 -399.833084)
		(stroke
			(width 0.635)
			(type default)
		)
		(layer "In7.Cu")
	)
	(gr_line
		(start 208.42605 -399.833084)
		(end 211.971128 -399.833084)
		(stroke
			(width 0.635)
			(type default)
		)
		(layer "In7.Cu")
	)
	(gr_circle
		(center 208.508854 -37.366448)
		(end 209.397854 -37.366448)
		(stroke
			(width 0.2)
			(type default)
		)
		(fill no)
		(layer "In7.Cu")
	)
	(gr_line
		(start 211.971128 -399.833084)
		(end 212.28304 -400.144996)
		(stroke
			(width 0.635)
			(type default)
		)
		(layer "In7.Cu")
	)
	(gr_line
		(start 212.28304 -403.63267)
		(end 212.414358 -403.763988)
		(stroke
			(width 0.635)
			(type default)
		)
		(layer "In7.Cu")
	)
	(gr_line
		(start 212.28304 -400.144996)
		(end 212.28304 -403.63267)
		(stroke
			(width 0.635)
			(type default)
		)
		(layer "In7.Cu")
	)
	(gr_line
		(start 212.414358 -406.410668)
		(end 214.347044 -408.343354)
		(stroke
			(width 0.635)
			(type default)
		)
		(layer "In7.Cu")
	)
	(gr_line
		(start 212.414358 -403.763988)
		(end 212.414358 -406.410668)
		(stroke
			(width 0.635)
			(type default)
		)
		(layer "In7.Cu")
	)
	(gr_line
		(start 214.347044 -408.343354)
		(end 216.541604 -408.343354)
		(stroke
			(width 0.635)
			(type default)
		)
		(layer "In7.Cu")
	)
	(gr_line
		(start 216.541604 -408.343354)
		(end 218.667584 -406.217374)
		(stroke
			(width 0.635)
			(type default)
		)
		(layer "In7.Cu")
	)
	(gr_line
		(start 218.667584 -406.217374)
		(end 218.667584 -403.755606)
		(stroke
			(width 0.635)
			(type default)
		)
		(layer "In7.Cu")
	)
	(gr_line
		(start 218.667584 -403.755606)
		(end 218.839796 -403.583394)
		(stroke
			(width 0.635)
			(type default)
		)
		(layer "In7.Cu")
	)
	(gr_line
		(start 218.839796 -403.583394)
		(end 218.839796 -400.095974)
		(stroke
			(width 0.635)
			(type default)
		)
		(layer "In7.Cu")
	)
	(gr_line
		(start 218.839796 -400.095974)
		(end 219.045282 -399.890488)
		(stroke
			(width 0.635)
			(type default)
		)
		(layer "In7.Cu")
	)
	(gr_line
		(start 219.045282 -399.890488)
		(end 222.709232 -399.890488)
		(stroke
			(width 0.635)
			(type default)
		)
		(layer "In7.Cu")
	)
	(gr_line
		(start 222.709232 -399.890488)
		(end 222.906082 -400.087338)
		(stroke
			(width 0.635)
			(type default)
		)
		(layer "In7.Cu")
	)
	(gr_line
		(start 222.906082 -403.607778)
		(end 223.099122 -403.800818)
		(stroke
			(width 0.635)
			(type default)
		)
		(layer "In7.Cu")
	)
	(gr_line
		(start 222.906082 -400.087338)
		(end 222.906082 -403.607778)
		(stroke
			(width 0.635)
			(type default)
		)
		(layer "In7.Cu")
	)
	(gr_line
		(start 223.099122 -406.414732)
		(end 224.990406 -408.306016)
		(stroke
			(width 0.635)
			(type default)
		)
		(layer "In7.Cu")
	)
	(gr_line
		(start 223.099122 -403.800818)
		(end 223.099122 -406.414732)
		(stroke
			(width 0.635)
			(type default)
		)
		(layer "In7.Cu")
	)
	(gr_arc
		(start 223.300036 -34.120074)
		(mid 223.885821 -35.534285)
		(end 225.300032 -36.12007)
		(stroke
			(width 1.016)
			(type default)
		)
		(layer "In7.Cu")
	)
	(gr_arc
		(start 223.300036 -13.780008)
		(mid 222.714256 -12.365778)
		(end 221.30004 -11.780012)
		(stroke
			(width 1.016)
			(type default)
		)
		(layer "In7.Cu")
	)
	(gr_line
		(start 223.300036 -13.780008)
		(end 223.300036 -34.120074)
		(stroke
			(width 1.016)
			(type default)
		)
		(layer "In7.Cu")
	)
	(gr_line
		(start 224.990406 -408.306016)
		(end 227.218748 -408.306016)
		(stroke
			(width 0.635)
			(type default)
		)
		(layer "In7.Cu")
	)
	(gr_line
		(start 225.300032 -36.12007)
		(end 256.800096 -36.12007)
		(stroke
			(width 1.016)
			(type default)
		)
		(layer "In7.Cu")
	)
	(gr_line
		(start 227.218748 -408.306016)
		(end 229.331774 -406.19299)
		(stroke
			(width 0.635)
			(type default)
		)
		(layer "In7.Cu")
	)
	(gr_line
		(start 229.074472 -436.79618)
		(end 229.997 -435.873652)
		(stroke
			(width 0.635)
			(type default)
		)
		(layer "In7.Cu")
	)
	(gr_line
		(start 229.331774 -406.19299)
		(end 229.331774 -403.768052)
		(stroke
			(width 0.635)
			(type default)
		)
		(layer "In7.Cu")
	)
	(gr_line
		(start 229.331774 -403.768052)
		(end 229.516178 -403.583648)
		(stroke
			(width 0.635)
			(type default)
		)
		(layer "In7.Cu")
	)
	(gr_line
		(start 229.516178 -403.583648)
		(end 229.516178 -400.11223)
		(stroke
			(width 0.635)
			(type default)
		)
		(layer "In7.Cu")
	)
	(gr_line
		(start 229.516178 -400.11223)
		(end 229.746302 -399.882106)
		(stroke
			(width 0.635)
			(type default)
		)
		(layer "In7.Cu")
	)
	(gr_line
		(start 229.746302 -399.882106)
		(end 233.352594 -399.882106)
		(stroke
			(width 0.635)
			(type default)
		)
		(layer "In7.Cu")
	)
	(gr_line
		(start 229.997 -435.873652)
		(end 229.997 -422.180766)
		(stroke
			(width 0.635)
			(type default)
		)
		(layer "In7.Cu")
	)
	(gr_line
		(start 233.352594 -399.882106)
		(end 233.574336 -400.103848)
		(stroke
			(width 0.635)
			(type default)
		)
		(layer "In7.Cu")
	)
	(gr_line
		(start 233.574336 -403.673564)
		(end 233.820462 -403.91969)
		(stroke
			(width 0.635)
			(type default)
		)
		(layer "In7.Cu")
	)
	(gr_line
		(start 233.574336 -400.103848)
		(end 233.574336 -403.673564)
		(stroke
			(width 0.635)
			(type default)
		)
		(layer "In7.Cu")
	)
	(gr_line
		(start 233.820462 -404.855172)
		(end 234.522264 -405.556974)
		(stroke
			(width 0.635)
			(type default)
		)
		(layer "In7.Cu")
	)
	(gr_line
		(start 233.820462 -403.91969)
		(end 233.820462 -404.855172)
		(stroke
			(width 0.635)
			(type default)
		)
		(layer "In7.Cu")
	)
	(gr_line
		(start 234.522264 -405.556974)
		(end 238.715804 -405.556974)
		(stroke
			(width 0.635)
			(type default)
		)
		(layer "In7.Cu")
	)
	(gr_line
		(start 234.897676 -417.28009)
		(end 229.997 -422.180766)
		(stroke
			(width 0.635)
			(type default)
		)
		(layer "In7.Cu")
	)
	(gr_circle
		(center 237.629954 -44.025566)
		(end 238.518954 -44.025566)
		(stroke
			(width 0.2)
			(type default)
		)
		(fill no)
		(layer "In7.Cu")
	)
	(gr_circle
		(center 237.640114 -44.716446)
		(end 238.529114 -44.716446)
		(stroke
			(width 0.2)
			(type default)
		)
		(fill no)
		(layer "In7.Cu")
	)
	(gr_circle
		(center 238.292894 -44.802806)
		(end 239.181894 -44.802806)
		(stroke
			(width 0.2)
			(type default)
		)
		(fill no)
		(layer "In7.Cu")
	)
	(gr_circle
		(center 238.292894 -44.040806)
		(end 239.181894 -44.040806)
		(stroke
			(width 0.2)
			(type default)
		)
		(fill no)
		(layer "In7.Cu")
	)
	(gr_arc
		(start 238.695992 -393.003532)
		(mid 238.724179 -393.144586)
		(end 238.804196 -393.264136)
		(stroke
			(width 0.635)
			(type default)
		)
		(layer "In7.Cu")
	)
	(gr_line
		(start 238.695992 -384.337306)
		(end 238.695992 -393.003532)
		(stroke
			(width 0.635)
			(type default)
		)
		(layer "In7.Cu")
	)
	(gr_line
		(start 238.715804 -405.556974)
		(end 238.882682 -405.390096)
		(stroke
			(width 0.635)
			(type default)
		)
		(layer "In7.Cu")
	)
	(gr_line
		(start 238.752126 -384.198876)
		(end 238.695992 -384.337306)
		(stroke
			(width 0.635)
			(type default)
		)
		(layer "In7.Cu")
	)
	(gr_line
		(start 238.804196 -393.264136)
		(end 239.027716 -393.487656)
		(stroke
			(width 0.635)
			(type default)
		)
		(layer "In7.Cu")
	)
	(gr_line
		(start 238.805974 -384.146806)
		(end 238.752126 -384.198876)
		(stroke
			(width 0.635)
			(type default)
		)
		(layer "In7.Cu")
	)
	(gr_line
		(start 238.882682 -405.390096)
		(end 238.882682 -394.210794)
		(stroke
			(width 0.635)
			(type default)
		)
		(layer "In7.Cu")
	)
	(gr_line
		(start 238.882682 -394.210794)
		(end 238.882682 -394.001498)
		(stroke
			(width 0.635)
			(type default)
		)
		(layer "In7.Cu")
	)
	(gr_line
		(start 238.882682 -394.210794)
		(end 279.615392 -394.210794)
		(stroke
			(width 0.635)
			(type default)
		)
		(layer "In7.Cu")
	)
	(gr_line
		(start 238.882682 -394.001498)
		(end 239.28832 -393.59586)
		(stroke
			(width 0.635)
			(type default)
		)
		(layer "In7.Cu")
	)
	(gr_circle
		(center 238.943134 -44.802806)
		(end 239.832134 -44.802806)
		(stroke
			(width 0.2)
			(type default)
		)
		(fill no)
		(layer "In7.Cu")
	)
	(gr_circle
		(center 238.943134 -44.040806)
		(end 239.832134 -44.040806)
		(stroke
			(width 0.2)
			(type default)
		)
		(fill no)
		(layer "In7.Cu")
	)
	(gr_arc
		(start 239.027716 -393.487656)
		(mid 239.147257 -393.567682)
		(end 239.28832 -393.59586)
		(stroke
			(width 0.635)
			(type default)
		)
		(layer "In7.Cu")
	)
	(gr_line
		(start 239.281716 -383.671064)
		(end 238.805974 -384.146806)
		(stroke
			(width 0.635)
			(type default)
		)
		(layer "In7.Cu")
	)
	(gr_line
		(start 239.28832 -393.59586)
		(end 273.155664 -393.59586)
		(stroke
			(width 0.635)
			(type default)
		)
		(layer "In7.Cu")
	)
	(gr_arc
		(start 239.54232 -383.56286)
		(mid 239.401266 -383.591047)
		(end 239.281716 -383.671064)
		(stroke
			(width 0.635)
			(type default)
		)
		(layer "In7.Cu")
	)
	(gr_circle
		(center 239.578134 -44.802806)
		(end 240.467134 -44.802806)
		(stroke
			(width 0.2)
			(type default)
		)
		(fill no)
		(layer "In7.Cu")
	)
	(gr_circle
		(center 239.578134 -44.040806)
		(end 240.467134 -44.040806)
		(stroke
			(width 0.2)
			(type default)
		)
		(fill no)
		(layer "In7.Cu")
	)
	(gr_circle
		(center 240.213134 -44.802806)
		(end 241.102134 -44.802806)
		(stroke
			(width 0.2)
			(type default)
		)
		(fill no)
		(layer "In7.Cu")
	)
	(gr_circle
		(center 240.213134 -44.040806)
		(end 241.102134 -44.040806)
		(stroke
			(width 0.2)
			(type default)
		)
		(fill no)
		(layer "In7.Cu")
	)
	(gr_circle
		(center 240.893854 -44.830746)
		(end 241.782854 -44.830746)
		(stroke
			(width 0.2)
			(type default)
		)
		(fill no)
		(layer "In7.Cu")
	)
	(gr_circle
		(center 244.518942 -43.246802)
		(end 245.407942 -43.246802)
		(stroke
			(width 0.2)
			(type default)
		)
		(fill no)
		(layer "In7.Cu")
	)
	(gr_circle
		(center 244.518942 -42.611802)
		(end 245.407942 -42.611802)
		(stroke
			(width 0.2)
			(type default)
		)
		(fill no)
		(layer "In7.Cu")
	)
	(gr_circle
		(center 245.857522 -52.022502)
		(end 246.746522 -52.022502)
		(stroke
			(width 0.2)
			(type default)
		)
		(fill no)
		(layer "In7.Cu")
	)
	(gr_circle
		(center 246.873522 -52.022502)
		(end 247.762522 -52.022502)
		(stroke
			(width 0.2)
			(type default)
		)
		(fill no)
		(layer "In7.Cu")
	)
	(gr_circle
		(center 247.825514 -40.94988)
		(end 248.714514 -40.94988)
		(stroke
			(width 0.2)
			(type default)
		)
		(fill no)
		(layer "In7.Cu")
	)
	(gr_circle
		(center 247.840246 -51.320446)
		(end 248.729246 -51.320446)
		(stroke
			(width 0.2)
			(type default)
		)
		(fill no)
		(layer "In7.Cu")
	)
	(gr_circle
		(center 248.214134 -52.171346)
		(end 249.103134 -52.171346)
		(stroke
			(width 0.2)
			(type default)
		)
		(fill no)
		(layer "In7.Cu")
	)
	(gr_circle
		(center 248.881646 -51.320446)
		(end 249.770646 -51.320446)
		(stroke
			(width 0.2)
			(type default)
		)
		(fill no)
		(layer "In7.Cu")
	)
	(gr_circle
		(center 249.202448 -40.945816)
		(end 250.091448 -40.945816)
		(stroke
			(width 0.2)
			(type default)
		)
		(fill no)
		(layer "In7.Cu")
	)
	(gr_circle
		(center 249.905266 -51.349148)
		(end 250.794266 -51.349148)
		(stroke
			(width 0.2)
			(type default)
		)
		(fill no)
		(layer "In7.Cu")
	)
	(gr_circle
		(center 250.449334 -49.555146)
		(end 251.338334 -49.555146)
		(stroke
			(width 0.2)
			(type default)
		)
		(fill no)
		(layer "In7.Cu")
	)
	(gr_circle
		(center 250.779534 -52.222146)
		(end 251.668534 -52.222146)
		(stroke
			(width 0.2)
			(type default)
		)
		(fill no)
		(layer "In7.Cu")
	)
	(gr_circle
		(center 250.779534 -51.333146)
		(end 251.668534 -51.333146)
		(stroke
			(width 0.2)
			(type default)
		)
		(fill no)
		(layer "In7.Cu")
	)
	(gr_circle
		(center 250.779534 -50.444146)
		(end 251.668534 -50.444146)
		(stroke
			(width 0.2)
			(type default)
		)
		(fill no)
		(layer "In7.Cu")
	)
	(gr_circle
		(center 251.516134 -52.501546)
		(end 252.405134 -52.501546)
		(stroke
			(width 0.2)
			(type default)
		)
		(fill no)
		(layer "In7.Cu")
	)
	(gr_circle
		(center 251.516134 -51.612546)
		(end 252.405134 -51.612546)
		(stroke
			(width 0.2)
			(type default)
		)
		(fill no)
		(layer "In7.Cu")
	)
	(gr_circle
		(center 251.516134 -50.723546)
		(end 252.405134 -50.723546)
		(stroke
			(width 0.2)
			(type default)
		)
		(fill no)
		(layer "In7.Cu")
	)
	(gr_circle
		(center 255.347978 -39.380922)
		(end 256.236978 -39.380922)
		(stroke
			(width 0.2)
			(type default)
		)
		(fill no)
		(layer "In7.Cu")
	)
	(gr_arc
		(start 256.800096 -36.12007)
		(mid 258.214307 -35.534285)
		(end 258.800092 -34.120074)
		(stroke
			(width 1.016)
			(type default)
		)
		(layer "In7.Cu")
	)
	(gr_line
		(start 258.800092 -34.120074)
		(end 258.800092 -13.780008)
		(stroke
			(width 1.016)
			(type default)
		)
		(layer "In7.Cu")
	)
	(gr_arc
		(start 260.800088 -11.780012)
		(mid 259.385888 -12.365802)
		(end 258.800092 -13.780008)
		(stroke
			(width 1.016)
			(type default)
		)
		(layer "In7.Cu")
	)
	(gr_line
		(start 260.800088 -11.780012)
		(end 385.601972 -11.780012)
		(stroke
			(width 1.016)
			(type default)
		)
		(layer "In7.Cu")
	)
	(gr_line
		(start 272.19021 -417.28009)
		(end 234.897676 -417.28009)
		(stroke
			(width 0.635)
			(type default)
		)
		(layer "In7.Cu")
	)
	(gr_arc
		(start 273.155664 -393.59586)
		(mid 273.296718 -393.567673)
		(end 273.416268 -393.487656)
		(stroke
			(width 0.635)
			(type default)
		)
		(layer "In7.Cu")
	)
	(gr_line
		(start 273.33067 -394.041884)
		(end 279.547066 -394.041884)
		(stroke
			(width 0.635)
			(type default)
		)
		(layer "In7.Cu")
	)
	(gr_line
		(start 273.416268 -393.487656)
		(end 273.893788 -393.010136)
		(stroke
			(width 0.635)
			(type default)
		)
		(layer "In7.Cu")
	)
	(gr_line
		(start 273.481546 -383.56286)
		(end 239.54232 -383.56286)
		(stroke
			(width 0.635)
			(type default)
		)
		(layer "In7.Cu")
	)
	(gr_line
		(start 273.619976 -383.618994)
		(end 273.481546 -383.56286)
		(stroke
			(width 0.635)
			(type default)
		)
		(layer "In7.Cu")
	)
	(gr_line
		(start 273.672046 -383.672842)
		(end 273.619976 -383.618994)
		(stroke
			(width 0.635)
			(type default)
		)
		(layer "In7.Cu")
	)
	(gr_arc
		(start 273.893788 -393.010136)
		(mid 273.97387 -392.890613)
		(end 274.001992 -392.749532)
		(stroke
			(width 0.635)
			(type default)
		)
		(layer "In7.Cu")
	)
	(gr_line
		(start 273.893788 -383.894584)
		(end 273.672046 -383.672842)
		(stroke
			(width 0.635)
			(type default)
		)
		(layer "In7.Cu")
	)
	(gr_line
		(start 274.001992 -392.749532)
		(end 274.001992 -384.155188)
		(stroke
			(width 0.635)
			(type default)
		)
		(layer "In7.Cu")
	)
	(gr_arc
		(start 274.001992 -384.155188)
		(mid 273.973805 -384.014134)
		(end 273.893788 -383.894584)
		(stroke
			(width 0.635)
			(type default)
		)
		(layer "In7.Cu")
	)
	(gr_line
		(start 274.123404 -393.697206)
		(end 279.133554 -393.697206)
		(stroke
			(width 0.635)
			(type default)
		)
		(layer "In7.Cu")
	)
	(gr_line
		(start 274.433792 -392.938762)
		(end 273.33067 -394.041884)
		(stroke
			(width 0.635)
			(type default)
		)
		(layer "In7.Cu")
	)
	(gr_line
		(start 274.433792 -392.938762)
		(end 274.50288 -392.869674)
		(stroke
			(width 0.635)
			(type default)
		)
		(layer "In7.Cu")
	)
	(gr_line
		(start 274.433792 -392.317732)
		(end 274.67052 -392.55446)
		(stroke
			(width 0.635)
			(type default)
		)
		(layer "In7.Cu")
	)
	(gr_line
		(start 274.433792 -384.002788)
		(end 274.433792 -392.938762)
		(stroke
			(width 0.635)
			(type default)
		)
		(layer "In7.Cu")
	)
	(gr_line
		(start 274.433792 -384.002788)
		(end 274.433792 -392.317732)
		(stroke
			(width 0.635)
			(type default)
		)
		(layer "In7.Cu")
	)
	(gr_line
		(start 274.50288 -392.869674)
		(end 279.110694 -392.869674)
		(stroke
			(width 0.635)
			(type default)
		)
		(layer "In7.Cu")
	)
	(gr_line
		(start 274.732496 -393.237466)
		(end 274.433792 -392.938762)
		(stroke
			(width 0.635)
			(type default)
		)
		(layer "In7.Cu")
	)
	(gr_line
		(start 274.778724 -392.605514)
		(end 274.192746 -392.019536)
		(stroke
			(width 0.635)
			(type default)
		)
		(layer "In7.Cu")
	)
	(gr_line
		(start 274.87372 -383.56286)
		(end 274.433792 -384.002788)
		(stroke
			(width 0.635)
			(type default)
		)
		(layer "In7.Cu")
	)
	(gr_circle
		(center 276.112986 -348.704662)
		(end 276.993096 -348.704662)
		(stroke
			(width 0.2)
			(type default)
		)
		(fill no)
		(layer "In7.Cu")
	)
	(gr_line
		(start 276.314916 -440.669934)
		(end 195.50507 -440.669934)
		(stroke
			(width 1.016)
			(type default)
		)
		(layer "In7.Cu")
	)
	(gr_circle
		(center 276.730206 -348.704662)
		(end 277.610316 -348.704662)
		(stroke
			(width 0.2)
			(type default)
		)
		(fill no)
		(layer "In7.Cu")
	)
	(gr_line
		(start 276.815042 -441.4901)
		(end 276.815042 -441.17006)
		(stroke
			(width 1.016)
			(type default)
		)
		(layer "In7.Cu")
	)
	(gr_arc
		(start 276.815042 -441.4901)
		(mid 276.961452 -441.843558)
		(end 277.314914 -441.989972)
		(stroke
			(width 1.016)
			(type default)
		)
		(layer "In7.Cu")
	)
	(gr_arc
		(start 276.815042 -441.17006)
		(mid 276.668558 -440.816418)
		(end 276.314916 -440.669934)
		(stroke
			(width 1.016)
			(type default)
		)
		(layer "In7.Cu")
	)
	(gr_circle
		(center 277.347426 -348.704662)
		(end 278.227536 -348.704662)
		(stroke
			(width 0.2)
			(type default)
		)
		(fill no)
		(layer "In7.Cu")
	)
	(gr_circle
		(center 277.593806 -348.025212)
		(end 278.482806 -348.025212)
		(stroke
			(width 0.2)
			(type default)
		)
		(fill no)
		(layer "In7.Cu")
	)
	(gr_circle
		(center 277.593806 -347.288612)
		(end 278.482806 -347.288612)
		(stroke
			(width 0.2)
			(type default)
		)
		(fill no)
		(layer "In7.Cu")
	)
	(gr_circle
		(center 278.049482 -350.313752)
		(end 278.938482 -350.313752)
		(stroke
			(width 0.2)
			(type default)
		)
		(fill no)
		(layer "In7.Cu")
	)
	(gr_circle
		(center 278.049482 -349.577152)
		(end 278.938482 -349.577152)
		(stroke
			(width 0.2)
			(type default)
		)
		(fill no)
		(layer "In7.Cu")
	)
	(gr_circle
		(center 278.574246 -349.137732)
		(end 279.463246 -349.137732)
		(stroke
			(width 0.2)
			(type default)
		)
		(fill no)
		(layer "In7.Cu")
	)
	(gr_circle
		(center 278.599646 -349.899732)
		(end 279.488646 -349.899732)
		(stroke
			(width 0.2)
			(type default)
		)
		(fill no)
		(layer "In7.Cu")
	)
	(gr_line
		(start 278.892508 -393.237466)
		(end 274.732496 -393.237466)
		(stroke
			(width 0.635)
			(type default)
		)
		(layer "In7.Cu")
	)
	(gr_line
		(start 279.110694 -392.869674)
		(end 279.351994 -392.628374)
		(stroke
			(width 0.635)
			(type default)
		)
		(layer "In7.Cu")
	)
	(gr_circle
		(center 279.133046 -350.255332)
		(end 280.022046 -350.255332)
		(stroke
			(width 0.2)
			(type default)
		)
		(fill no)
		(layer "In7.Cu")
	)
	(gr_circle
		(center 279.133046 -349.518732)
		(end 280.022046 -349.518732)
		(stroke
			(width 0.2)
			(type default)
		)
		(fill no)
		(layer "In7.Cu")
	)
	(gr_circle
		(center 279.133046 -348.782132)
		(end 280.022046 -348.782132)
		(stroke
			(width 0.2)
			(type default)
		)
		(fill no)
		(layer "In7.Cu")
	)
	(gr_line
		(start 279.133554 -393.697206)
		(end 279.983946 -392.846814)
		(stroke
			(width 0.635)
			(type default)
		)
		(layer "In7.Cu")
	)
	(gr_line
		(start 279.329134 -392.605514)
		(end 274.778724 -392.605514)
		(stroke
			(width 0.635)
			(type default)
		)
		(layer "In7.Cu")
	)
	(gr_line
		(start 279.351994 -392.628374)
		(end 279.329134 -392.605514)
		(stroke
			(width 0.635)
			(type default)
		)
		(layer "In7.Cu")
	)
	(gr_line
		(start 279.547066 -394.041884)
		(end 280.477976 -393.110974)
		(stroke
			(width 0.635)
			(type default)
		)
		(layer "In7.Cu")
	)
	(gr_line
		(start 279.616408 -392.513566)
		(end 278.892508 -393.237466)
		(stroke
			(width 0.635)
			(type default)
		)
		(layer "In7.Cu")
	)
	(gr_line
		(start 279.616408 -383.780538)
		(end 279.616408 -392.513566)
		(stroke
			(width 0.635)
			(type default)
		)
		(layer "In7.Cu")
	)
	(gr_line
		(start 279.834086 -383.56286)
		(end 279.616408 -383.780538)
		(stroke
			(width 0.635)
			(type default)
		)
		(layer "In7.Cu")
	)
	(gr_arc
		(start 279.875996 -394.318998)
		(mid 279.756473 -394.238916)
		(end 279.615392 -394.210794)
		(stroke
			(width 0.635)
			(type default)
		)
		(layer "In7.Cu")
	)
	(gr_line
		(start 279.983946 -392.846814)
		(end 279.983946 -383.781046)
		(stroke
			(width 0.635)
			(type default)
		)
		(layer "In7.Cu")
	)
	(gr_line
		(start 279.983946 -383.781046)
		(end 280.202132 -383.56286)
		(stroke
			(width 0.635)
			(type default)
		)
		(layer "In7.Cu")
	)
	(gr_line
		(start 280.202132 -383.56286)
		(end 274.87372 -383.56286)
		(stroke
			(width 0.635)
			(type default)
		)
		(layer "In7.Cu")
	)
	(gr_line
		(start 280.202132 -383.56286)
		(end 279.834086 -383.56286)
		(stroke
			(width 0.635)
			(type default)
		)
		(layer "In7.Cu")
	)
	(gr_line
		(start 280.259536 -394.702538)
		(end 279.875996 -394.318998)
		(stroke
			(width 0.635)
			(type default)
		)
		(layer "In7.Cu")
	)
	(gr_line
		(start 280.36774 -409.10256)
		(end 272.19021 -417.28009)
		(stroke
			(width 0.635)
			(type default)
		)
		(layer "In7.Cu")
	)
	(gr_line
		(start 280.36774 -407.473404)
		(end 280.36774 -394.963142)
		(stroke
			(width 0.635)
			(type default)
		)
		(layer "In7.Cu")
	)
	(gr_arc
		(start 280.36774 -394.963142)
		(mid 280.339553 -394.822088)
		(end 280.259536 -394.702538)
		(stroke
			(width 0.635)
			(type default)
		)
		(layer "In7.Cu")
	)
	(gr_line
		(start 280.36774 -394.963142)
		(end 280.36774 -409.10256)
		(stroke
			(width 0.635)
			(type default)
		)
		(layer "In7.Cu")
	)
	(gr_line
		(start 280.477976 -393.110974)
		(end 280.477976 -383.838704)
		(stroke
			(width 0.635)
			(type default)
		)
		(layer "In7.Cu")
	)
	(gr_line
		(start 280.477976 -383.838704)
		(end 280.202132 -383.56286)
		(stroke
			(width 0.635)
			(type default)
		)
		(layer "In7.Cu")
	)
	(gr_line
		(start 280.537412 -392.55446)
		(end 274.67052 -392.55446)
		(stroke
			(width 0.635)
			(type default)
		)
		(layer "In7.Cu")
	)
	(gr_line
		(start 280.537412 -392.55446)
		(end 280.9113 -392.180572)
		(stroke
			(width 0.635)
			(type default)
		)
		(layer "In7.Cu")
	)
	(gr_line
		(start 280.9113 -392.180572)
		(end 280.9113 -384.272028)
		(stroke
			(width 0.635)
			(type default)
		)
		(layer "In7.Cu")
	)
	(gr_line
		(start 280.9113 -384.272028)
		(end 280.202132 -383.56286)
		(stroke
			(width 0.635)
			(type default)
		)
		(layer "In7.Cu")
	)
	(gr_circle
		(center 284.393386 -348.704662)
		(end 285.273496 -348.704662)
		(stroke
			(width 0.2)
			(type default)
		)
		(fill no)
		(layer "In7.Cu")
	)
	(gr_circle
		(center 285.010606 -348.704662)
		(end 285.890716 -348.704662)
		(stroke
			(width 0.2)
			(type default)
		)
		(fill no)
		(layer "In7.Cu")
	)
	(gr_circle
		(center 285.627826 -348.704662)
		(end 286.507936 -348.704662)
		(stroke
			(width 0.2)
			(type default)
		)
		(fill no)
		(layer "In7.Cu")
	)
	(gr_circle
		(center 285.869126 -347.982032)
		(end 286.758126 -347.982032)
		(stroke
			(width 0.2)
			(type default)
		)
		(fill no)
		(layer "In7.Cu")
	)
	(gr_circle
		(center 285.869126 -347.245432)
		(end 286.758126 -347.245432)
		(stroke
			(width 0.2)
			(type default)
		)
		(fill no)
		(layer "In7.Cu")
	)
	(gr_circle
		(center 286.329882 -350.313752)
		(end 287.218882 -350.313752)
		(stroke
			(width 0.2)
			(type default)
		)
		(fill no)
		(layer "In7.Cu")
	)
	(gr_circle
		(center 286.329882 -349.577152)
		(end 287.218882 -349.577152)
		(stroke
			(width 0.2)
			(type default)
		)
		(fill no)
		(layer "In7.Cu")
	)
	(gr_circle
		(center 286.36595 -355.279198)
		(end 287.25495 -355.279198)
		(stroke
			(width 0.2)
			(type default)
		)
		(fill no)
		(layer "In7.Cu")
	)
	(gr_circle
		(center 286.37611 -356.584758)
		(end 287.26511 -356.584758)
		(stroke
			(width 0.2)
			(type default)
		)
		(fill no)
		(layer "In7.Cu")
	)
	(gr_circle
		(center 286.37611 -355.949758)
		(end 287.26511 -355.949758)
		(stroke
			(width 0.2)
			(type default)
		)
		(fill no)
		(layer "In7.Cu")
	)
	(gr_circle
		(center 286.854646 -349.137732)
		(end 287.743646 -349.137732)
		(stroke
			(width 0.2)
			(type default)
		)
		(fill no)
		(layer "In7.Cu")
	)
	(gr_circle
		(center 286.880046 -349.899732)
		(end 287.769046 -349.899732)
		(stroke
			(width 0.2)
			(type default)
		)
		(fill no)
		(layer "In7.Cu")
	)
	(gr_circle
		(center 287.00095 -355.279198)
		(end 287.88995 -355.279198)
		(stroke
			(width 0.2)
			(type default)
		)
		(fill no)
		(layer "In7.Cu")
	)
	(gr_circle
		(center 287.01111 -356.584758)
		(end 287.90011 -356.584758)
		(stroke
			(width 0.2)
			(type default)
		)
		(fill no)
		(layer "In7.Cu")
	)
	(gr_circle
		(center 287.01111 -355.949758)
		(end 287.90011 -355.949758)
		(stroke
			(width 0.2)
			(type default)
		)
		(fill no)
		(layer "In7.Cu")
	)
	(gr_circle
		(center 287.413446 -350.255332)
		(end 288.302446 -350.255332)
		(stroke
			(width 0.2)
			(type default)
		)
		(fill no)
		(layer "In7.Cu")
	)
	(gr_circle
		(center 287.413446 -349.518732)
		(end 288.302446 -349.518732)
		(stroke
			(width 0.2)
			(type default)
		)
		(fill no)
		(layer "In7.Cu")
	)
	(gr_circle
		(center 287.413446 -348.782132)
		(end 288.302446 -348.782132)
		(stroke
			(width 0.2)
			(type default)
		)
		(fill no)
		(layer "In7.Cu")
	)
	(gr_circle
		(center 287.63595 -355.279198)
		(end 288.52495 -355.279198)
		(stroke
			(width 0.2)
			(type default)
		)
		(fill no)
		(layer "In7.Cu")
	)
	(gr_circle
		(center 287.64611 -356.584758)
		(end 288.53511 -356.584758)
		(stroke
			(width 0.2)
			(type default)
		)
		(fill no)
		(layer "In7.Cu")
	)
	(gr_circle
		(center 287.64611 -355.949758)
		(end 288.53511 -355.949758)
		(stroke
			(width 0.2)
			(type default)
		)
		(fill no)
		(layer "In7.Cu")
	)
	(gr_circle
		(center 288.27095 -355.279198)
		(end 289.15995 -355.279198)
		(stroke
			(width 0.2)
			(type default)
		)
		(fill no)
		(layer "In7.Cu")
	)
	(gr_circle
		(center 288.28111 -356.584758)
		(end 289.17011 -356.584758)
		(stroke
			(width 0.2)
			(type default)
		)
		(fill no)
		(layer "In7.Cu")
	)
	(gr_circle
		(center 288.28111 -355.949758)
		(end 289.17011 -355.949758)
		(stroke
			(width 0.2)
			(type default)
		)
		(fill no)
		(layer "In7.Cu")
	)
	(gr_circle
		(center 288.90595 -355.279198)
		(end 289.79495 -355.279198)
		(stroke
			(width 0.2)
			(type default)
		)
		(fill no)
		(layer "In7.Cu")
	)
	(gr_circle
		(center 288.91611 -356.584758)
		(end 289.80511 -356.584758)
		(stroke
			(width 0.2)
			(type default)
		)
		(fill no)
		(layer "In7.Cu")
	)
	(gr_circle
		(center 288.91611 -355.949758)
		(end 289.80511 -355.949758)
		(stroke
			(width 0.2)
			(type default)
		)
		(fill no)
		(layer "In7.Cu")
	)
	(gr_circle
		(center 292.699186 -348.704662)
		(end 293.579296 -348.704662)
		(stroke
			(width 0.2)
			(type default)
		)
		(fill no)
		(layer "In7.Cu")
	)
	(gr_circle
		(center 293.316406 -348.704662)
		(end 294.196516 -348.704662)
		(stroke
			(width 0.2)
			(type default)
		)
		(fill no)
		(layer "In7.Cu")
	)
	(gr_circle
		(center 293.933626 -348.704662)
		(end 294.813736 -348.704662)
		(stroke
			(width 0.2)
			(type default)
		)
		(fill no)
		(layer "In7.Cu")
	)
	(gr_circle
		(center 294.146986 -347.959172)
		(end 295.035986 -347.959172)
		(stroke
			(width 0.2)
			(type default)
		)
		(fill no)
		(layer "In7.Cu")
	)
	(gr_circle
		(center 294.146986 -347.222572)
		(end 295.035986 -347.222572)
		(stroke
			(width 0.2)
			(type default)
		)
		(fill no)
		(layer "In7.Cu")
	)
	(gr_circle
		(center 294.635682 -350.313752)
		(end 295.524682 -350.313752)
		(stroke
			(width 0.2)
			(type default)
		)
		(fill no)
		(layer "In7.Cu")
	)
	(gr_circle
		(center 294.635682 -349.577152)
		(end 295.524682 -349.577152)
		(stroke
			(width 0.2)
			(type default)
		)
		(fill no)
		(layer "In7.Cu")
	)
	(gr_circle
		(center 295.160446 -349.137732)
		(end 296.049446 -349.137732)
		(stroke
			(width 0.2)
			(type default)
		)
		(fill no)
		(layer "In7.Cu")
	)
	(gr_circle
		(center 295.185846 -349.899732)
		(end 296.074846 -349.899732)
		(stroke
			(width 0.2)
			(type default)
		)
		(fill no)
		(layer "In7.Cu")
	)
	(gr_circle
		(center 295.719246 -350.255332)
		(end 296.608246 -350.255332)
		(stroke
			(width 0.2)
			(type default)
		)
		(fill no)
		(layer "In7.Cu")
	)
	(gr_circle
		(center 295.719246 -349.518732)
		(end 296.608246 -349.518732)
		(stroke
			(width 0.2)
			(type default)
		)
		(fill no)
		(layer "In7.Cu")
	)
	(gr_circle
		(center 295.719246 -348.782132)
		(end 296.608246 -348.782132)
		(stroke
			(width 0.2)
			(type default)
		)
		(fill no)
		(layer "In7.Cu")
	)
	(gr_circle
		(center 296.29989 -358.769666)
		(end 297.69689 -358.769666)
		(stroke
			(width 0.2)
			(type default)
		)
		(fill no)
		(layer "In7.Cu")
	)
	(gr_circle
		(center 301.055786 -348.704662)
		(end 301.935896 -348.704662)
		(stroke
			(width 0.2)
			(type default)
		)
		(fill no)
		(layer "In7.Cu")
	)
	(gr_circle
		(center 301.673006 -348.704662)
		(end 302.553116 -348.704662)
		(stroke
			(width 0.2)
			(type default)
		)
		(fill no)
		(layer "In7.Cu")
	)
	(gr_circle
		(center 302.290226 -348.704662)
		(end 303.170336 -348.704662)
		(stroke
			(width 0.2)
			(type default)
		)
		(fill no)
		(layer "In7.Cu")
	)
	(gr_circle
		(center 302.526446 -348.002352)
		(end 303.415446 -348.002352)
		(stroke
			(width 0.2)
			(type default)
		)
		(fill no)
		(layer "In7.Cu")
	)
	(gr_circle
		(center 302.526446 -347.265752)
		(end 303.415446 -347.265752)
		(stroke
			(width 0.2)
			(type default)
		)
		(fill no)
		(layer "In7.Cu")
	)
	(gr_circle
		(center 302.992282 -350.313752)
		(end 303.881282 -350.313752)
		(stroke
			(width 0.2)
			(type default)
		)
		(fill no)
		(layer "In7.Cu")
	)
	(gr_circle
		(center 302.992282 -349.577152)
		(end 303.881282 -349.577152)
		(stroke
			(width 0.2)
			(type default)
		)
		(fill no)
		(layer "In7.Cu")
	)
	(gr_circle
		(center 303.517046 -349.137732)
		(end 304.406046 -349.137732)
		(stroke
			(width 0.2)
			(type default)
		)
		(fill no)
		(layer "In7.Cu")
	)
	(gr_circle
		(center 303.542446 -349.899732)
		(end 304.431446 -349.899732)
		(stroke
			(width 0.2)
			(type default)
		)
		(fill no)
		(layer "In7.Cu")
	)
	(gr_circle
		(center 304.075846 -350.255332)
		(end 304.964846 -350.255332)
		(stroke
			(width 0.2)
			(type default)
		)
		(fill no)
		(layer "In7.Cu")
	)
	(gr_circle
		(center 304.075846 -349.518732)
		(end 304.964846 -349.518732)
		(stroke
			(width 0.2)
			(type default)
		)
		(fill no)
		(layer "In7.Cu")
	)
	(gr_circle
		(center 304.075846 -348.782132)
		(end 304.964846 -348.782132)
		(stroke
			(width 0.2)
			(type default)
		)
		(fill no)
		(layer "In7.Cu")
	)
	(gr_circle
		(center 309.386986 -348.704662)
		(end 310.267096 -348.704662)
		(stroke
			(width 0.2)
			(type default)
		)
		(fill no)
		(layer "In7.Cu")
	)
	(gr_circle
		(center 310.004206 -348.704662)
		(end 310.884316 -348.704662)
		(stroke
			(width 0.2)
			(type default)
		)
		(fill no)
		(layer "In7.Cu")
	)
	(gr_circle
		(center 310.621426 -348.704662)
		(end 311.501536 -348.704662)
		(stroke
			(width 0.2)
			(type default)
		)
		(fill no)
		(layer "In7.Cu")
	)
	(gr_circle
		(center 310.867806 -348.002352)
		(end 311.756806 -348.002352)
		(stroke
			(width 0.2)
			(type default)
		)
		(fill no)
		(layer "In7.Cu")
	)
	(gr_circle
		(center 310.867806 -347.265752)
		(end 311.756806 -347.265752)
		(stroke
			(width 0.2)
			(type default)
		)
		(fill no)
		(layer "In7.Cu")
	)
	(gr_circle
		(center 311.323482 -350.313752)
		(end 312.212482 -350.313752)
		(stroke
			(width 0.2)
			(type default)
		)
		(fill no)
		(layer "In7.Cu")
	)
	(gr_circle
		(center 311.323482 -349.577152)
		(end 312.212482 -349.577152)
		(stroke
			(width 0.2)
			(type default)
		)
		(fill no)
		(layer "In7.Cu")
	)
	(gr_circle
		(center 311.848246 -349.137732)
		(end 312.737246 -349.137732)
		(stroke
			(width 0.2)
			(type default)
		)
		(fill no)
		(layer "In7.Cu")
	)
	(gr_circle
		(center 311.873646 -349.899732)
		(end 312.762646 -349.899732)
		(stroke
			(width 0.2)
			(type default)
		)
		(fill no)
		(layer "In7.Cu")
	)
	(gr_circle
		(center 312.407046 -350.255332)
		(end 313.296046 -350.255332)
		(stroke
			(width 0.2)
			(type default)
		)
		(fill no)
		(layer "In7.Cu")
	)
	(gr_circle
		(center 312.407046 -349.518732)
		(end 313.296046 -349.518732)
		(stroke
			(width 0.2)
			(type default)
		)
		(fill no)
		(layer "In7.Cu")
	)
	(gr_circle
		(center 312.407046 -348.782132)
		(end 313.296046 -348.782132)
		(stroke
			(width 0.2)
			(type default)
		)
		(fill no)
		(layer "In7.Cu")
	)
	(gr_circle
		(center 319.0367 -336.983578)
		(end 319.91681 -336.983578)
		(stroke
			(width 0.2)
			(type default)
		)
		(fill no)
		(layer "In7.Cu")
	)
	(gr_circle
		(center 319.65392 -336.983578)
		(end 320.53403 -336.983578)
		(stroke
			(width 0.2)
			(type default)
		)
		(fill no)
		(layer "In7.Cu")
	)
	(gr_circle
		(center 320.27114 -336.983578)
		(end 321.15125 -336.983578)
		(stroke
			(width 0.2)
			(type default)
		)
		(fill no)
		(layer "In7.Cu")
	)
	(gr_circle
		(center 320.5607 -336.239612)
		(end 321.4497 -336.239612)
		(stroke
			(width 0.2)
			(type default)
		)
		(fill no)
		(layer "In7.Cu")
	)
	(gr_circle
		(center 320.5607 -335.503012)
		(end 321.4497 -335.503012)
		(stroke
			(width 0.2)
			(type default)
		)
		(fill no)
		(layer "In7.Cu")
	)
	(gr_circle
		(center 320.973196 -338.592668)
		(end 321.862196 -338.592668)
		(stroke
			(width 0.2)
			(type default)
		)
		(fill no)
		(layer "In7.Cu")
	)
	(gr_circle
		(center 320.973196 -337.856068)
		(end 321.862196 -337.856068)
		(stroke
			(width 0.2)
			(type default)
		)
		(fill no)
		(layer "In7.Cu")
	)
	(gr_circle
		(center 321.49796 -337.416648)
		(end 322.38696 -337.416648)
		(stroke
			(width 0.2)
			(type default)
		)
		(fill no)
		(layer "In7.Cu")
	)
	(gr_circle
		(center 321.52336 -338.178648)
		(end 322.41236 -338.178648)
		(stroke
			(width 0.2)
			(type default)
		)
		(fill no)
		(layer "In7.Cu")
	)
	(gr_circle
		(center 322.05676 -338.534248)
		(end 322.94576 -338.534248)
		(stroke
			(width 0.2)
			(type default)
		)
		(fill no)
		(layer "In7.Cu")
	)
	(gr_circle
		(center 322.05676 -337.797648)
		(end 322.94576 -337.797648)
		(stroke
			(width 0.2)
			(type default)
		)
		(fill no)
		(layer "In7.Cu")
	)
	(gr_circle
		(center 322.05676 -337.061048)
		(end 322.94576 -337.061048)
		(stroke
			(width 0.2)
			(type default)
		)
		(fill no)
		(layer "In7.Cu")
	)
	(gr_circle
		(center 327.392284 -336.976466)
		(end 328.272394 -336.976466)
		(stroke
			(width 0.2)
			(type default)
		)
		(fill no)
		(layer "In7.Cu")
	)
	(gr_circle
		(center 327.692258 -104.30129)
		(end 328.581258 -104.30129)
		(stroke
			(width 0.2)
			(type default)
		)
		(fill no)
		(layer "In7.Cu")
	)
	(gr_circle
		(center 327.951084 -349.43161)
		(end 329.348084 -349.43161)
		(stroke
			(width 0.2)
			(type default)
		)
		(fill no)
		(layer "In7.Cu")
	)
	(gr_circle
		(center 328.009504 -336.976466)
		(end 328.889614 -336.976466)
		(stroke
			(width 0.2)
			(type default)
		)
		(fill no)
		(layer "In7.Cu")
	)
	(gr_circle
		(center 328.626724 -336.976466)
		(end 329.506834 -336.976466)
		(stroke
			(width 0.2)
			(type default)
		)
		(fill no)
		(layer "In7.Cu")
	)
	(gr_circle
		(center 328.918824 -336.253836)
		(end 329.807824 -336.253836)
		(stroke
			(width 0.2)
			(type default)
		)
		(fill no)
		(layer "In7.Cu")
	)
	(gr_circle
		(center 328.918824 -335.517236)
		(end 329.807824 -335.517236)
		(stroke
			(width 0.2)
			(type default)
		)
		(fill no)
		(layer "In7.Cu")
	)
	(gr_circle
		(center 329.32878 -338.585556)
		(end 330.21778 -338.585556)
		(stroke
			(width 0.2)
			(type default)
		)
		(fill no)
		(layer "In7.Cu")
	)
	(gr_circle
		(center 329.32878 -337.848956)
		(end 330.21778 -337.848956)
		(stroke
			(width 0.2)
			(type default)
		)
		(fill no)
		(layer "In7.Cu")
	)
	(gr_circle
		(center 329.853544 -337.409536)
		(end 330.742544 -337.409536)
		(stroke
			(width 0.2)
			(type default)
		)
		(fill no)
		(layer "In7.Cu")
	)
	(gr_circle
		(center 329.878944 -338.171536)
		(end 330.767944 -338.171536)
		(stroke
			(width 0.2)
			(type default)
		)
		(fill no)
		(layer "In7.Cu")
	)
	(gr_circle
		(center 330.412344 -338.527136)
		(end 331.301344 -338.527136)
		(stroke
			(width 0.2)
			(type default)
		)
		(fill no)
		(layer "In7.Cu")
	)
	(gr_circle
		(center 330.412344 -337.790536)
		(end 331.301344 -337.790536)
		(stroke
			(width 0.2)
			(type default)
		)
		(fill no)
		(layer "In7.Cu")
	)
	(gr_circle
		(center 330.412344 -337.053936)
		(end 331.301344 -337.053936)
		(stroke
			(width 0.2)
			(type default)
		)
		(fill no)
		(layer "In7.Cu")
	)
	(gr_circle
		(center 335.411064 -349.43161)
		(end 336.808064 -349.43161)
		(stroke
			(width 0.2)
			(type default)
		)
		(fill no)
		(layer "In7.Cu")
	)
	(gr_circle
		(center 335.7499 -336.961988)
		(end 336.63001 -336.961988)
		(stroke
			(width 0.2)
			(type default)
		)
		(fill no)
		(layer "In7.Cu")
	)
	(gr_circle
		(center 336.36712 -336.961988)
		(end 337.24723 -336.961988)
		(stroke
			(width 0.2)
			(type default)
		)
		(fill no)
		(layer "In7.Cu")
	)
	(gr_circle
		(center 336.98434 -336.961988)
		(end 337.86445 -336.961988)
		(stroke
			(width 0.2)
			(type default)
		)
		(fill no)
		(layer "In7.Cu")
	)
	(gr_circle
		(center 337.280504 -336.253836)
		(end 338.169504 -336.253836)
		(stroke
			(width 0.2)
			(type default)
		)
		(fill no)
		(layer "In7.Cu")
	)
	(gr_circle
		(center 337.280504 -335.517236)
		(end 338.169504 -335.517236)
		(stroke
			(width 0.2)
			(type default)
		)
		(fill no)
		(layer "In7.Cu")
	)
	(gr_circle
		(center 337.686396 -338.571078)
		(end 338.575396 -338.571078)
		(stroke
			(width 0.2)
			(type default)
		)
		(fill no)
		(layer "In7.Cu")
	)
	(gr_circle
		(center 337.686396 -337.834478)
		(end 338.575396 -337.834478)
		(stroke
			(width 0.2)
			(type default)
		)
		(fill no)
		(layer "In7.Cu")
	)
	(gr_circle
		(center 338.21116 -337.395058)
		(end 339.10016 -337.395058)
		(stroke
			(width 0.2)
			(type default)
		)
		(fill no)
		(layer "In7.Cu")
	)
	(gr_circle
		(center 338.23656 -338.157058)
		(end 339.12556 -338.157058)
		(stroke
			(width 0.2)
			(type default)
		)
		(fill no)
		(layer "In7.Cu")
	)
	(gr_circle
		(center 338.76996 -338.512658)
		(end 339.65896 -338.512658)
		(stroke
			(width 0.2)
			(type default)
		)
		(fill no)
		(layer "In7.Cu")
	)
	(gr_circle
		(center 338.76996 -337.776058)
		(end 339.65896 -337.776058)
		(stroke
			(width 0.2)
			(type default)
		)
		(fill no)
		(layer "In7.Cu")
	)
	(gr_circle
		(center 338.76996 -337.039458)
		(end 339.65896 -337.039458)
		(stroke
			(width 0.2)
			(type default)
		)
		(fill no)
		(layer "In7.Cu")
	)
	(gr_circle
		(center 339.73897 -352.973132)
		(end 340.62797 -352.973132)
		(stroke
			(width 0.2)
			(type default)
		)
		(fill no)
		(layer "In7.Cu")
	)
	(gr_circle
		(center 339.739224 -352.215196)
		(end 340.628224 -352.215196)
		(stroke
			(width 0.2)
			(type default)
		)
		(fill no)
		(layer "In7.Cu")
	)
	(gr_circle
		(center 339.739224 -351.453196)
		(end 340.628224 -351.453196)
		(stroke
			(width 0.2)
			(type default)
		)
		(fill no)
		(layer "In7.Cu")
	)
	(gr_circle
		(center 340.501224 -352.215196)
		(end 341.390224 -352.215196)
		(stroke
			(width 0.2)
			(type default)
		)
		(fill no)
		(layer "In7.Cu")
	)
	(gr_circle
		(center 340.501224 -351.453196)
		(end 341.390224 -351.453196)
		(stroke
			(width 0.2)
			(type default)
		)
		(fill no)
		(layer "In7.Cu")
	)
	(gr_circle
		(center 340.667848 -353.010216)
		(end 341.556848 -353.010216)
		(stroke
			(width 0.2)
			(type default)
		)
		(fill no)
		(layer "In7.Cu")
	)
	(gr_circle
		(center 341.263224 -352.215196)
		(end 342.152224 -352.215196)
		(stroke
			(width 0.2)
			(type default)
		)
		(fill no)
		(layer "In7.Cu")
	)
	(gr_circle
		(center 341.263224 -351.453196)
		(end 342.152224 -351.453196)
		(stroke
			(width 0.2)
			(type default)
		)
		(fill no)
		(layer "In7.Cu")
	)
	(gr_circle
		(center 341.302848 -353.010216)
		(end 342.191848 -353.010216)
		(stroke
			(width 0.2)
			(type default)
		)
		(fill no)
		(layer "In7.Cu")
	)
	(gr_circle
		(center 341.937848 -353.010216)
		(end 342.826848 -353.010216)
		(stroke
			(width 0.2)
			(type default)
		)
		(fill no)
		(layer "In7.Cu")
	)
	(gr_circle
		(center 342.025224 -352.215196)
		(end 342.914224 -352.215196)
		(stroke
			(width 0.2)
			(type default)
		)
		(fill no)
		(layer "In7.Cu")
	)
	(gr_circle
		(center 342.025224 -351.453196)
		(end 342.914224 -351.453196)
		(stroke
			(width 0.2)
			(type default)
		)
		(fill no)
		(layer "In7.Cu")
	)
	(gr_circle
		(center 342.572848 -353.010216)
		(end 343.461848 -353.010216)
		(stroke
			(width 0.2)
			(type default)
		)
		(fill no)
		(layer "In7.Cu")
	)
	(gr_circle
		(center 342.787224 -352.215196)
		(end 343.676224 -352.215196)
		(stroke
			(width 0.2)
			(type default)
		)
		(fill no)
		(layer "In7.Cu")
	)
	(gr_circle
		(center 342.787224 -351.453196)
		(end 343.676224 -351.453196)
		(stroke
			(width 0.2)
			(type default)
		)
		(fill no)
		(layer "In7.Cu")
	)
	(gr_circle
		(center 343.46515 -353.006152)
		(end 344.35415 -353.006152)
		(stroke
			(width 0.2)
			(type default)
		)
		(fill no)
		(layer "In7.Cu")
	)
	(gr_circle
		(center 343.465404 -352.248216)
		(end 344.354404 -352.248216)
		(stroke
			(width 0.2)
			(type default)
		)
		(fill no)
		(layer "In7.Cu")
	)
	(gr_circle
		(center 343.465404 -351.486216)
		(end 344.354404 -351.486216)
		(stroke
			(width 0.2)
			(type default)
		)
		(fill no)
		(layer "In7.Cu")
	)
	(gr_circle
		(center 344.016838 -159.073596)
		(end 344.905838 -159.073596)
		(stroke
			(width 0.2)
			(type default)
		)
		(fill no)
		(layer "In7.Cu")
	)
	(gr_circle
		(center 344.016838 -158.336996)
		(end 344.905838 -158.336996)
		(stroke
			(width 0.2)
			(type default)
		)
		(fill no)
		(layer "In7.Cu")
	)
	(gr_circle
		(center 344.016838 -157.600396)
		(end 344.905838 -157.600396)
		(stroke
			(width 0.2)
			(type default)
		)
		(fill no)
		(layer "In7.Cu")
	)
	(gr_circle
		(center 344.0811 -337.012788)
		(end 344.96121 -337.012788)
		(stroke
			(width 0.2)
			(type default)
		)
		(fill no)
		(layer "In7.Cu")
	)
	(gr_circle
		(center 344.550238 -157.955996)
		(end 345.439238 -157.955996)
		(stroke
			(width 0.2)
			(type default)
		)
		(fill no)
		(layer "In7.Cu")
	)
	(gr_circle
		(center 344.575638 -158.717996)
		(end 345.464638 -158.717996)
		(stroke
			(width 0.2)
			(type default)
		)
		(fill no)
		(layer "In7.Cu")
	)
	(gr_circle
		(center 344.69832 -337.012788)
		(end 345.57843 -337.012788)
		(stroke
			(width 0.2)
			(type default)
		)
		(fill no)
		(layer "In7.Cu")
	)
	(gr_circle
		(center 345.100402 -158.278576)
		(end 345.989402 -158.278576)
		(stroke
			(width 0.2)
			(type default)
		)
		(fill no)
		(layer "In7.Cu")
	)
	(gr_circle
		(center 345.100402 -157.541976)
		(end 345.989402 -157.541976)
		(stroke
			(width 0.2)
			(type default)
		)
		(fill no)
		(layer "In7.Cu")
	)
	(gr_circle
		(center 345.31554 -337.012788)
		(end 346.19565 -337.012788)
		(stroke
			(width 0.2)
			(type default)
		)
		(fill no)
		(layer "In7.Cu")
	)
	(gr_circle
		(center 345.623896 -336.317336)
		(end 346.512896 -336.317336)
		(stroke
			(width 0.2)
			(type default)
		)
		(fill no)
		(layer "In7.Cu")
	)
	(gr_circle
		(center 345.623896 -335.580736)
		(end 346.512896 -335.580736)
		(stroke
			(width 0.2)
			(type default)
		)
		(fill no)
		(layer "In7.Cu")
	)
	(gr_circle
		(center 345.684856 -160.633156)
		(end 346.573856 -160.633156)
		(stroke
			(width 0.2)
			(type default)
		)
		(fill no)
		(layer "In7.Cu")
	)
	(gr_circle
		(center 345.684856 -159.896556)
		(end 346.573856 -159.896556)
		(stroke
			(width 0.2)
			(type default)
		)
		(fill no)
		(layer "In7.Cu")
	)
	(gr_circle
		(center 345.802458 -159.151066)
		(end 346.682568 -159.151066)
		(stroke
			(width 0.2)
			(type default)
		)
		(fill no)
		(layer "In7.Cu")
	)
	(gr_circle
		(center 345.921076 -278.136096)
		(end 346.175076 -278.136096)
		(stroke
			(width 0.1016)
			(type default)
		)
		(fill no)
		(layer "In7.Cu")
	)
	(gr_circle
		(center 345.921076 -276.516084)
		(end 346.175076 -276.516084)
		(stroke
			(width 0.1016)
			(type default)
		)
		(fill no)
		(layer "In7.Cu")
	)
	(gr_circle
		(center 345.921076 -274.896072)
		(end 346.175076 -274.896072)
		(stroke
			(width 0.1016)
			(type default)
		)
		(fill no)
		(layer "In7.Cu")
	)
	(gr_circle
		(center 345.921076 -273.27606)
		(end 346.175076 -273.27606)
		(stroke
			(width 0.1016)
			(type default)
		)
		(fill no)
		(layer "In7.Cu")
	)
	(gr_circle
		(center 345.921076 -271.656048)
		(end 346.175076 -271.656048)
		(stroke
			(width 0.1016)
			(type default)
		)
		(fill no)
		(layer "In7.Cu")
	)
	(gr_circle
		(center 345.921076 -270.036036)
		(end 346.175076 -270.036036)
		(stroke
			(width 0.1016)
			(type default)
		)
		(fill no)
		(layer "In7.Cu")
	)
	(gr_circle
		(center 346.017596 -339.358478)
		(end 346.906596 -339.358478)
		(stroke
			(width 0.2)
			(type default)
		)
		(fill no)
		(layer "In7.Cu")
	)
	(gr_circle
		(center 346.017596 -338.621878)
		(end 346.906596 -338.621878)
		(stroke
			(width 0.2)
			(type default)
		)
		(fill no)
		(layer "In7.Cu")
	)
	(gr_circle
		(center 346.017596 -337.885278)
		(end 346.906596 -337.885278)
		(stroke
			(width 0.2)
			(type default)
		)
		(fill no)
		(layer "In7.Cu")
	)
	(gr_circle
		(center 346.419678 -159.151066)
		(end 347.299788 -159.151066)
		(stroke
			(width 0.2)
			(type default)
		)
		(fill no)
		(layer "In7.Cu")
	)
	(gr_circle
		(center 346.54236 -337.445858)
		(end 347.43136 -337.445858)
		(stroke
			(width 0.2)
			(type default)
		)
		(fill no)
		(layer "In7.Cu")
	)
	(gr_circle
		(center 346.56776 -339.731858)
		(end 347.45676 -339.731858)
		(stroke
			(width 0.2)
			(type default)
		)
		(fill no)
		(layer "In7.Cu")
	)
	(gr_circle
		(center 346.56776 -338.969858)
		(end 347.45676 -338.969858)
		(stroke
			(width 0.2)
			(type default)
		)
		(fill no)
		(layer "In7.Cu")
	)
	(gr_circle
		(center 346.56776 -338.207858)
		(end 347.45676 -338.207858)
		(stroke
			(width 0.2)
			(type default)
		)
		(fill no)
		(layer "In7.Cu")
	)
	(gr_circle
		(center 346.86113 -278.136096)
		(end 347.11513 -278.136096)
		(stroke
			(width 0.1016)
			(type default)
		)
		(fill no)
		(layer "In7.Cu")
	)
	(gr_circle
		(center 346.86113 -276.516084)
		(end 347.11513 -276.516084)
		(stroke
			(width 0.1016)
			(type default)
		)
		(fill no)
		(layer "In7.Cu")
	)
	(gr_circle
		(center 346.86113 -274.896072)
		(end 347.11513 -274.896072)
		(stroke
			(width 0.1016)
			(type default)
		)
		(fill no)
		(layer "In7.Cu")
	)
	(gr_circle
		(center 346.86113 -273.27606)
		(end 347.11513 -273.27606)
		(stroke
			(width 0.1016)
			(type default)
		)
		(fill no)
		(layer "In7.Cu")
	)
	(gr_circle
		(center 346.86113 -271.656048)
		(end 347.11513 -271.656048)
		(stroke
			(width 0.1016)
			(type default)
		)
		(fill no)
		(layer "In7.Cu")
	)
	(gr_circle
		(center 346.86113 -270.036036)
		(end 347.11513 -270.036036)
		(stroke
			(width 0.1016)
			(type default)
		)
		(fill no)
		(layer "In7.Cu")
	)
	(gr_circle
		(center 347.036898 -159.151066)
		(end 347.917008 -159.151066)
		(stroke
			(width 0.2)
			(type default)
		)
		(fill no)
		(layer "In7.Cu")
	)
	(gr_circle
		(center 348.740984 -278.136096)
		(end 348.994984 -278.136096)
		(stroke
			(width 0.1016)
			(type default)
		)
		(fill no)
		(layer "In7.Cu")
	)
	(gr_circle
		(center 348.740984 -276.516084)
		(end 348.994984 -276.516084)
		(stroke
			(width 0.1016)
			(type default)
		)
		(fill no)
		(layer "In7.Cu")
	)
	(gr_circle
		(center 348.740984 -274.896072)
		(end 348.994984 -274.896072)
		(stroke
			(width 0.1016)
			(type default)
		)
		(fill no)
		(layer "In7.Cu")
	)
	(gr_circle
		(center 348.740984 -273.27606)
		(end 348.994984 -273.27606)
		(stroke
			(width 0.1016)
			(type default)
		)
		(fill no)
		(layer "In7.Cu")
	)
	(gr_circle
		(center 348.740984 -271.656048)
		(end 348.994984 -271.656048)
		(stroke
			(width 0.1016)
			(type default)
		)
		(fill no)
		(layer "In7.Cu")
	)
	(gr_circle
		(center 348.740984 -270.036036)
		(end 348.994984 -270.036036)
		(stroke
			(width 0.1016)
			(type default)
		)
		(fill no)
		(layer "In7.Cu")
	)
	(gr_circle
		(center 349.681038 -278.136096)
		(end 349.935038 -278.136096)
		(stroke
			(width 0.1016)
			(type default)
		)
		(fill no)
		(layer "In7.Cu")
	)
	(gr_circle
		(center 349.681038 -276.516084)
		(end 349.935038 -276.516084)
		(stroke
			(width 0.1016)
			(type default)
		)
		(fill no)
		(layer "In7.Cu")
	)
	(gr_circle
		(center 349.681038 -274.896072)
		(end 349.935038 -274.896072)
		(stroke
			(width 0.1016)
			(type default)
		)
		(fill no)
		(layer "In7.Cu")
	)
	(gr_circle
		(center 349.681038 -273.27606)
		(end 349.935038 -273.27606)
		(stroke
			(width 0.1016)
			(type default)
		)
		(fill no)
		(layer "In7.Cu")
	)
	(gr_circle
		(center 349.681038 -271.656048)
		(end 349.935038 -271.656048)
		(stroke
			(width 0.1016)
			(type default)
		)
		(fill no)
		(layer "In7.Cu")
	)
	(gr_circle
		(center 349.681038 -270.036036)
		(end 349.935038 -270.036036)
		(stroke
			(width 0.1016)
			(type default)
		)
		(fill no)
		(layer "In7.Cu")
	)
	(gr_circle
		(center 351.561146 -278.136096)
		(end 351.815146 -278.136096)
		(stroke
			(width 0.1016)
			(type default)
		)
		(fill no)
		(layer "In7.Cu")
	)
	(gr_circle
		(center 351.561146 -276.516084)
		(end 351.815146 -276.516084)
		(stroke
			(width 0.1016)
			(type default)
		)
		(fill no)
		(layer "In7.Cu")
	)
	(gr_circle
		(center 351.561146 -274.896072)
		(end 351.815146 -274.896072)
		(stroke
			(width 0.1016)
			(type default)
		)
		(fill no)
		(layer "In7.Cu")
	)
	(gr_circle
		(center 351.561146 -273.27606)
		(end 351.815146 -273.27606)
		(stroke
			(width 0.1016)
			(type default)
		)
		(fill no)
		(layer "In7.Cu")
	)
	(gr_circle
		(center 351.561146 -271.656048)
		(end 351.815146 -271.656048)
		(stroke
			(width 0.1016)
			(type default)
		)
		(fill no)
		(layer "In7.Cu")
	)
	(gr_circle
		(center 351.561146 -270.036036)
		(end 351.815146 -270.036036)
		(stroke
			(width 0.1016)
			(type default)
		)
		(fill no)
		(layer "In7.Cu")
	)
	(gr_circle
		(center 352.322638 -167.430196)
		(end 353.211638 -167.430196)
		(stroke
			(width 0.2)
			(type default)
		)
		(fill no)
		(layer "In7.Cu")
	)
	(gr_circle
		(center 352.322638 -166.693596)
		(end 353.211638 -166.693596)
		(stroke
			(width 0.2)
			(type default)
		)
		(fill no)
		(layer "In7.Cu")
	)
	(gr_circle
		(center 352.322638 -165.956996)
		(end 353.211638 -165.956996)
		(stroke
			(width 0.2)
			(type default)
		)
		(fill no)
		(layer "In7.Cu")
	)
	(gr_circle
		(center 352.356928 -341.922862)
		(end 353.237038 -341.922862)
		(stroke
			(width 0.2)
			(type default)
		)
		(fill no)
		(layer "In7.Cu")
	)
	(gr_circle
		(center 352.5012 -278.136096)
		(end 352.7552 -278.136096)
		(stroke
			(width 0.1016)
			(type default)
		)
		(fill no)
		(layer "In7.Cu")
	)
	(gr_circle
		(center 352.5012 -276.516084)
		(end 352.7552 -276.516084)
		(stroke
			(width 0.1016)
			(type default)
		)
		(fill no)
		(layer "In7.Cu")
	)
	(gr_circle
		(center 352.5012 -274.896072)
		(end 352.7552 -274.896072)
		(stroke
			(width 0.1016)
			(type default)
		)
		(fill no)
		(layer "In7.Cu")
	)
	(gr_circle
		(center 352.5012 -273.27606)
		(end 352.7552 -273.27606)
		(stroke
			(width 0.1016)
			(type default)
		)
		(fill no)
		(layer "In7.Cu")
	)
	(gr_circle
		(center 352.5012 -271.656048)
		(end 352.7552 -271.656048)
		(stroke
			(width 0.1016)
			(type default)
		)
		(fill no)
		(layer "In7.Cu")
	)
	(gr_circle
		(center 352.5012 -270.036036)
		(end 352.7552 -270.036036)
		(stroke
			(width 0.1016)
			(type default)
		)
		(fill no)
		(layer "In7.Cu")
	)
	(gr_circle
		(center 352.856038 -166.312596)
		(end 353.745038 -166.312596)
		(stroke
			(width 0.2)
			(type default)
		)
		(fill no)
		(layer "In7.Cu")
	)
	(gr_circle
		(center 352.881438 -167.074596)
		(end 353.770438 -167.074596)
		(stroke
			(width 0.2)
			(type default)
		)
		(fill no)
		(layer "In7.Cu")
	)
	(gr_circle
		(center 352.974148 -341.922862)
		(end 353.854258 -341.922862)
		(stroke
			(width 0.2)
			(type default)
		)
		(fill no)
		(layer "In7.Cu")
	)
	(gr_circle
		(center 353.406202 -166.635176)
		(end 354.295202 -166.635176)
		(stroke
			(width 0.2)
			(type default)
		)
		(fill no)
		(layer "In7.Cu")
	)
	(gr_circle
		(center 353.406202 -165.898576)
		(end 354.295202 -165.898576)
		(stroke
			(width 0.2)
			(type default)
		)
		(fill no)
		(layer "In7.Cu")
	)
	(gr_circle
		(center 353.591368 -341.922862)
		(end 354.471478 -341.922862)
		(stroke
			(width 0.2)
			(type default)
		)
		(fill no)
		(layer "In7.Cu")
	)
	(gr_circle
		(center 353.899724 -341.22741)
		(end 354.788724 -341.22741)
		(stroke
			(width 0.2)
			(type default)
		)
		(fill no)
		(layer "In7.Cu")
	)
	(gr_circle
		(center 353.899724 -340.49081)
		(end 354.788724 -340.49081)
		(stroke
			(width 0.2)
			(type default)
		)
		(fill no)
		(layer "In7.Cu")
	)
	(gr_circle
		(center 353.990656 -168.982136)
		(end 354.879656 -168.982136)
		(stroke
			(width 0.2)
			(type default)
		)
		(fill no)
		(layer "In7.Cu")
	)
	(gr_circle
		(center 353.990656 -168.245536)
		(end 354.879656 -168.245536)
		(stroke
			(width 0.2)
			(type default)
		)
		(fill no)
		(layer "In7.Cu")
	)
	(gr_circle
		(center 354.108258 -167.507666)
		(end 354.988368 -167.507666)
		(stroke
			(width 0.2)
			(type default)
		)
		(fill no)
		(layer "In7.Cu")
	)
	(gr_circle
		(center 354.293424 -343.531952)
		(end 355.182424 -343.531952)
		(stroke
			(width 0.2)
			(type default)
		)
		(fill no)
		(layer "In7.Cu")
	)
	(gr_circle
		(center 354.293424 -342.795352)
		(end 355.182424 -342.795352)
		(stroke
			(width 0.2)
			(type default)
		)
		(fill no)
		(layer "In7.Cu")
	)
	(gr_circle
		(center 354.381054 -279.756108)
		(end 354.635054 -279.756108)
		(stroke
			(width 0.1016)
			(type default)
		)
		(fill no)
		(layer "In7.Cu")
	)
	(gr_circle
		(center 354.381054 -278.136096)
		(end 354.635054 -278.136096)
		(stroke
			(width 0.1016)
			(type default)
		)
		(fill no)
		(layer "In7.Cu")
	)
	(gr_circle
		(center 354.381054 -276.516084)
		(end 354.635054 -276.516084)
		(stroke
			(width 0.1016)
			(type default)
		)
		(fill no)
		(layer "In7.Cu")
	)
	(gr_circle
		(center 354.381054 -274.896072)
		(end 354.635054 -274.896072)
		(stroke
			(width 0.1016)
			(type default)
		)
		(fill no)
		(layer "In7.Cu")
	)
	(gr_circle
		(center 354.381054 -273.27606)
		(end 354.635054 -273.27606)
		(stroke
			(width 0.1016)
			(type default)
		)
		(fill no)
		(layer "In7.Cu")
	)
	(gr_circle
		(center 354.381054 -271.656048)
		(end 354.635054 -271.656048)
		(stroke
			(width 0.1016)
			(type default)
		)
		(fill no)
		(layer "In7.Cu")
	)
	(gr_circle
		(center 354.381054 -270.036036)
		(end 354.635054 -270.036036)
		(stroke
			(width 0.1016)
			(type default)
		)
		(fill no)
		(layer "In7.Cu")
	)
	(gr_circle
		(center 354.725478 -167.507666)
		(end 355.605588 -167.507666)
		(stroke
			(width 0.2)
			(type default)
		)
		(fill no)
		(layer "In7.Cu")
	)
	(gr_circle
		(center 354.818188 -342.355932)
		(end 355.707188 -342.355932)
		(stroke
			(width 0.2)
			(type default)
		)
		(fill no)
		(layer "In7.Cu")
	)
	(gr_circle
		(center 354.843588 -343.117932)
		(end 355.732588 -343.117932)
		(stroke
			(width 0.2)
			(type default)
		)
		(fill no)
		(layer "In7.Cu")
	)
	(gr_circle
		(center 355.321108 -279.756108)
		(end 355.575108 -279.756108)
		(stroke
			(width 0.1016)
			(type default)
		)
		(fill no)
		(layer "In7.Cu")
	)
	(gr_circle
		(center 355.321108 -278.136096)
		(end 355.575108 -278.136096)
		(stroke
			(width 0.1016)
			(type default)
		)
		(fill no)
		(layer "In7.Cu")
	)
	(gr_circle
		(center 355.321108 -276.516084)
		(end 355.575108 -276.516084)
		(stroke
			(width 0.1016)
			(type default)
		)
		(fill no)
		(layer "In7.Cu")
	)
	(gr_circle
		(center 355.321108 -274.896072)
		(end 355.575108 -274.896072)
		(stroke
			(width 0.1016)
			(type default)
		)
		(fill no)
		(layer "In7.Cu")
	)
	(gr_circle
		(center 355.321108 -273.27606)
		(end 355.575108 -273.27606)
		(stroke
			(width 0.1016)
			(type default)
		)
		(fill no)
		(layer "In7.Cu")
	)
	(gr_circle
		(center 355.321108 -271.656048)
		(end 355.575108 -271.656048)
		(stroke
			(width 0.1016)
			(type default)
		)
		(fill no)
		(layer "In7.Cu")
	)
	(gr_circle
		(center 355.321108 -270.036036)
		(end 355.575108 -270.036036)
		(stroke
			(width 0.1016)
			(type default)
		)
		(fill no)
		(layer "In7.Cu")
	)
	(gr_circle
		(center 355.342698 -167.507666)
		(end 356.222808 -167.507666)
		(stroke
			(width 0.2)
			(type default)
		)
		(fill no)
		(layer "In7.Cu")
	)
	(gr_circle
		(center 355.376988 -343.473532)
		(end 356.265988 -343.473532)
		(stroke
			(width 0.2)
			(type default)
		)
		(fill no)
		(layer "In7.Cu")
	)
	(gr_circle
		(center 355.376988 -342.736932)
		(end 356.265988 -342.736932)
		(stroke
			(width 0.2)
			(type default)
		)
		(fill no)
		(layer "In7.Cu")
	)
	(gr_circle
		(center 355.376988 -342.000332)
		(end 356.265988 -342.000332)
		(stroke
			(width 0.2)
			(type default)
		)
		(fill no)
		(layer "In7.Cu")
	)
	(gr_circle
		(center 356.731062 -278.946102)
		(end 356.985062 -278.946102)
		(stroke
			(width 0.1016)
			(type default)
		)
		(fill no)
		(layer "In7.Cu")
	)
	(gr_circle
		(center 356.731062 -277.32609)
		(end 356.985062 -277.32609)
		(stroke
			(width 0.1016)
			(type default)
		)
		(fill no)
		(layer "In7.Cu")
	)
	(gr_circle
		(center 356.731062 -275.706078)
		(end 356.985062 -275.706078)
		(stroke
			(width 0.1016)
			(type default)
		)
		(fill no)
		(layer "In7.Cu")
	)
	(gr_circle
		(center 356.731062 -274.086066)
		(end 356.985062 -274.086066)
		(stroke
			(width 0.1016)
			(type default)
		)
		(fill no)
		(layer "In7.Cu")
	)
	(gr_circle
		(center 356.731062 -272.466054)
		(end 356.985062 -272.466054)
		(stroke
			(width 0.1016)
			(type default)
		)
		(fill no)
		(layer "In7.Cu")
	)
	(gr_circle
		(center 356.731062 -270.846042)
		(end 356.985062 -270.846042)
		(stroke
			(width 0.1016)
			(type default)
		)
		(fill no)
		(layer "In7.Cu")
	)
	(gr_circle
		(center 356.731062 -269.22603)
		(end 356.985062 -269.22603)
		(stroke
			(width 0.1016)
			(type default)
		)
		(fill no)
		(layer "In7.Cu")
	)
	(gr_circle
		(center 357.671116 -278.946102)
		(end 357.925116 -278.946102)
		(stroke
			(width 0.1016)
			(type default)
		)
		(fill no)
		(layer "In7.Cu")
	)
	(gr_circle
		(center 357.671116 -277.32609)
		(end 357.925116 -277.32609)
		(stroke
			(width 0.1016)
			(type default)
		)
		(fill no)
		(layer "In7.Cu")
	)
	(gr_circle
		(center 357.671116 -275.706078)
		(end 357.925116 -275.706078)
		(stroke
			(width 0.1016)
			(type default)
		)
		(fill no)
		(layer "In7.Cu")
	)
	(gr_circle
		(center 357.671116 -274.086066)
		(end 357.925116 -274.086066)
		(stroke
			(width 0.1016)
			(type default)
		)
		(fill no)
		(layer "In7.Cu")
	)
	(gr_circle
		(center 357.671116 -272.466054)
		(end 357.925116 -272.466054)
		(stroke
			(width 0.1016)
			(type default)
		)
		(fill no)
		(layer "In7.Cu")
	)
	(gr_circle
		(center 357.671116 -270.846042)
		(end 357.925116 -270.846042)
		(stroke
			(width 0.1016)
			(type default)
		)
		(fill no)
		(layer "In7.Cu")
	)
	(gr_circle
		(center 357.671116 -269.22603)
		(end 357.925116 -269.22603)
		(stroke
			(width 0.1016)
			(type default)
		)
		(fill no)
		(layer "In7.Cu")
	)
	(gr_circle
		(center 359.58526 -152.71242)
		(end 360.98226 -152.71242)
		(stroke
			(width 0.2)
			(type default)
		)
		(fill no)
		(layer "In7.Cu")
	)
	(gr_circle
		(center 360.603038 -175.705516)
		(end 361.492038 -175.705516)
		(stroke
			(width 0.2)
			(type default)
		)
		(fill no)
		(layer "In7.Cu")
	)
	(gr_circle
		(center 360.603038 -174.968916)
		(end 361.492038 -174.968916)
		(stroke
			(width 0.2)
			(type default)
		)
		(fill no)
		(layer "In7.Cu")
	)
	(gr_circle
		(center 360.603038 -174.232316)
		(end 361.492038 -174.232316)
		(stroke
			(width 0.2)
			(type default)
		)
		(fill no)
		(layer "In7.Cu")
	)
	(gr_circle
		(center 361.136438 -174.587916)
		(end 362.025438 -174.587916)
		(stroke
			(width 0.2)
			(type default)
		)
		(fill no)
		(layer "In7.Cu")
	)
	(gr_circle
		(center 361.161838 -175.349916)
		(end 362.050838 -175.349916)
		(stroke
			(width 0.2)
			(type default)
		)
		(fill no)
		(layer "In7.Cu")
	)
	(gr_circle
		(center 361.686602 -174.910496)
		(end 362.575602 -174.910496)
		(stroke
			(width 0.2)
			(type default)
		)
		(fill no)
		(layer "In7.Cu")
	)
	(gr_circle
		(center 361.686602 -174.173896)
		(end 362.575602 -174.173896)
		(stroke
			(width 0.2)
			(type default)
		)
		(fill no)
		(layer "In7.Cu")
	)
	(gr_circle
		(center 362.271056 -177.254916)
		(end 363.160056 -177.254916)
		(stroke
			(width 0.2)
			(type default)
		)
		(fill no)
		(layer "In7.Cu")
	)
	(gr_circle
		(center 362.271056 -176.518316)
		(end 363.160056 -176.518316)
		(stroke
			(width 0.2)
			(type default)
		)
		(fill no)
		(layer "In7.Cu")
	)
	(gr_circle
		(center 362.364782 -278.946102)
		(end 362.618782 -278.946102)
		(stroke
			(width 0.1016)
			(type default)
		)
		(fill no)
		(layer "In7.Cu")
	)
	(gr_circle
		(center 362.364782 -277.32609)
		(end 362.618782 -277.32609)
		(stroke
			(width 0.1016)
			(type default)
		)
		(fill no)
		(layer "In7.Cu")
	)
	(gr_circle
		(center 362.364782 -275.706078)
		(end 362.618782 -275.706078)
		(stroke
			(width 0.1016)
			(type default)
		)
		(fill no)
		(layer "In7.Cu")
	)
	(gr_circle
		(center 362.364782 -274.086066)
		(end 362.618782 -274.086066)
		(stroke
			(width 0.1016)
			(type default)
		)
		(fill no)
		(layer "In7.Cu")
	)
	(gr_circle
		(center 362.364782 -272.466054)
		(end 362.618782 -272.466054)
		(stroke
			(width 0.1016)
			(type default)
		)
		(fill no)
		(layer "In7.Cu")
	)
	(gr_circle
		(center 362.364782 -270.846042)
		(end 362.618782 -270.846042)
		(stroke
			(width 0.1016)
			(type default)
		)
		(fill no)
		(layer "In7.Cu")
	)
	(gr_circle
		(center 362.364782 -269.22603)
		(end 362.618782 -269.22603)
		(stroke
			(width 0.1016)
			(type default)
		)
		(fill no)
		(layer "In7.Cu")
	)
	(gr_circle
		(center 362.396278 -175.859186)
		(end 363.276388 -175.859186)
		(stroke
			(width 0.2)
			(type default)
		)
		(fill no)
		(layer "In7.Cu")
	)
	(gr_circle
		(center 363.013498 -175.859186)
		(end 363.893608 -175.859186)
		(stroke
			(width 0.2)
			(type default)
		)
		(fill no)
		(layer "In7.Cu")
	)
	(gr_circle
		(center 363.304836 -278.946102)
		(end 363.558836 -278.946102)
		(stroke
			(width 0.1016)
			(type default)
		)
		(fill no)
		(layer "In7.Cu")
	)
	(gr_circle
		(center 363.304836 -277.32609)
		(end 363.558836 -277.32609)
		(stroke
			(width 0.1016)
			(type default)
		)
		(fill no)
		(layer "In7.Cu")
	)
	(gr_circle
		(center 363.304836 -275.706078)
		(end 363.558836 -275.706078)
		(stroke
			(width 0.1016)
			(type default)
		)
		(fill no)
		(layer "In7.Cu")
	)
	(gr_circle
		(center 363.304836 -274.086066)
		(end 363.558836 -274.086066)
		(stroke
			(width 0.1016)
			(type default)
		)
		(fill no)
		(layer "In7.Cu")
	)
	(gr_circle
		(center 363.304836 -272.466054)
		(end 363.558836 -272.466054)
		(stroke
			(width 0.1016)
			(type default)
		)
		(fill no)
		(layer "In7.Cu")
	)
	(gr_circle
		(center 363.304836 -270.846042)
		(end 363.558836 -270.846042)
		(stroke
			(width 0.1016)
			(type default)
		)
		(fill no)
		(layer "In7.Cu")
	)
	(gr_circle
		(center 363.304836 -269.22603)
		(end 363.558836 -269.22603)
		(stroke
			(width 0.1016)
			(type default)
		)
		(fill no)
		(layer "In7.Cu")
	)
	(gr_circle
		(center 363.630718 -175.859186)
		(end 364.510828 -175.859186)
		(stroke
			(width 0.2)
			(type default)
		)
		(fill no)
		(layer "In7.Cu")
	)
	(gr_circle
		(center 364.71479 -279.756108)
		(end 364.96879 -279.756108)
		(stroke
			(width 0.1016)
			(type default)
		)
		(fill no)
		(layer "In7.Cu")
	)
	(gr_circle
		(center 364.71479 -278.136096)
		(end 364.96879 -278.136096)
		(stroke
			(width 0.1016)
			(type default)
		)
		(fill no)
		(layer "In7.Cu")
	)
	(gr_circle
		(center 364.71479 -276.516084)
		(end 364.96879 -276.516084)
		(stroke
			(width 0.1016)
			(type default)
		)
		(fill no)
		(layer "In7.Cu")
	)
	(gr_circle
		(center 364.71479 -274.896072)
		(end 364.96879 -274.896072)
		(stroke
			(width 0.1016)
			(type default)
		)
		(fill no)
		(layer "In7.Cu")
	)
	(gr_circle
		(center 364.71479 -273.27606)
		(end 364.96879 -273.27606)
		(stroke
			(width 0.1016)
			(type default)
		)
		(fill no)
		(layer "In7.Cu")
	)
	(gr_circle
		(center 364.71479 -271.656048)
		(end 364.96879 -271.656048)
		(stroke
			(width 0.1016)
			(type default)
		)
		(fill no)
		(layer "In7.Cu")
	)
	(gr_circle
		(center 364.71479 -270.036036)
		(end 364.96879 -270.036036)
		(stroke
			(width 0.1016)
			(type default)
		)
		(fill no)
		(layer "In7.Cu")
	)
	(gr_circle
		(center 365.654844 -279.756108)
		(end 365.908844 -279.756108)
		(stroke
			(width 0.1016)
			(type default)
		)
		(fill no)
		(layer "In7.Cu")
	)
	(gr_circle
		(center 365.654844 -278.136096)
		(end 365.908844 -278.136096)
		(stroke
			(width 0.1016)
			(type default)
		)
		(fill no)
		(layer "In7.Cu")
	)
	(gr_circle
		(center 365.654844 -276.516084)
		(end 365.908844 -276.516084)
		(stroke
			(width 0.1016)
			(type default)
		)
		(fill no)
		(layer "In7.Cu")
	)
	(gr_circle
		(center 365.654844 -274.896072)
		(end 365.908844 -274.896072)
		(stroke
			(width 0.1016)
			(type default)
		)
		(fill no)
		(layer "In7.Cu")
	)
	(gr_circle
		(center 365.654844 -273.27606)
		(end 365.908844 -273.27606)
		(stroke
			(width 0.1016)
			(type default)
		)
		(fill no)
		(layer "In7.Cu")
	)
	(gr_circle
		(center 365.654844 -271.656048)
		(end 365.908844 -271.656048)
		(stroke
			(width 0.1016)
			(type default)
		)
		(fill no)
		(layer "In7.Cu")
	)
	(gr_circle
		(center 365.654844 -270.036036)
		(end 365.908844 -270.036036)
		(stroke
			(width 0.1016)
			(type default)
		)
		(fill no)
		(layer "In7.Cu")
	)
	(gr_circle
		(center 366.744504 -164.53358)
		(end 367.633504 -164.53358)
		(stroke
			(width 0.2)
			(type default)
		)
		(fill no)
		(layer "In7.Cu")
	)
	(gr_circle
		(center 366.744504 -163.89858)
		(end 367.633504 -163.89858)
		(stroke
			(width 0.2)
			(type default)
		)
		(fill no)
		(layer "In7.Cu")
	)
	(gr_circle
		(center 366.757204 -165.19398)
		(end 367.646204 -165.19398)
		(stroke
			(width 0.2)
			(type default)
		)
		(fill no)
		(layer "In7.Cu")
	)
	(gr_circle
		(center 367.379504 -164.53358)
		(end 368.268504 -164.53358)
		(stroke
			(width 0.2)
			(type default)
		)
		(fill no)
		(layer "In7.Cu")
	)
	(gr_circle
		(center 367.379504 -163.89858)
		(end 368.268504 -163.89858)
		(stroke
			(width 0.2)
			(type default)
		)
		(fill no)
		(layer "In7.Cu")
	)
	(gr_circle
		(center 367.392204 -165.19398)
		(end 368.281204 -165.19398)
		(stroke
			(width 0.2)
			(type default)
		)
		(fill no)
		(layer "In7.Cu")
	)
	(gr_circle
		(center 367.534698 -278.136096)
		(end 367.788698 -278.136096)
		(stroke
			(width 0.1016)
			(type default)
		)
		(fill no)
		(layer "In7.Cu")
	)
	(gr_circle
		(center 367.534698 -276.516084)
		(end 367.788698 -276.516084)
		(stroke
			(width 0.1016)
			(type default)
		)
		(fill no)
		(layer "In7.Cu")
	)
	(gr_circle
		(center 367.534698 -274.896072)
		(end 367.788698 -274.896072)
		(stroke
			(width 0.1016)
			(type default)
		)
		(fill no)
		(layer "In7.Cu")
	)
	(gr_circle
		(center 367.534698 -273.27606)
		(end 367.788698 -273.27606)
		(stroke
			(width 0.1016)
			(type default)
		)
		(fill no)
		(layer "In7.Cu")
	)
	(gr_circle
		(center 367.534698 -271.656048)
		(end 367.788698 -271.656048)
		(stroke
			(width 0.1016)
			(type default)
		)
		(fill no)
		(layer "In7.Cu")
	)
	(gr_circle
		(center 367.534698 -270.036036)
		(end 367.788698 -270.036036)
		(stroke
			(width 0.1016)
			(type default)
		)
		(fill no)
		(layer "In7.Cu")
	)
	(gr_circle
		(center 368.044984 -164.53358)
		(end 368.933984 -164.53358)
		(stroke
			(width 0.2)
			(type default)
		)
		(fill no)
		(layer "In7.Cu")
	)
	(gr_circle
		(center 368.044984 -163.89858)
		(end 368.933984 -163.89858)
		(stroke
			(width 0.2)
			(type default)
		)
		(fill no)
		(layer "In7.Cu")
	)
	(gr_circle
		(center 368.057684 -165.19398)
		(end 368.946684 -165.19398)
		(stroke
			(width 0.2)
			(type default)
		)
		(fill no)
		(layer "In7.Cu")
	)
	(gr_circle
		(center 368.474752 -278.136096)
		(end 368.728752 -278.136096)
		(stroke
			(width 0.1016)
			(type default)
		)
		(fill no)
		(layer "In7.Cu")
	)
	(gr_circle
		(center 368.474752 -276.516084)
		(end 368.728752 -276.516084)
		(stroke
			(width 0.1016)
			(type default)
		)
		(fill no)
		(layer "In7.Cu")
	)
	(gr_circle
		(center 368.474752 -274.896072)
		(end 368.728752 -274.896072)
		(stroke
			(width 0.1016)
			(type default)
		)
		(fill no)
		(layer "In7.Cu")
	)
	(gr_circle
		(center 368.474752 -273.27606)
		(end 368.728752 -273.27606)
		(stroke
			(width 0.1016)
			(type default)
		)
		(fill no)
		(layer "In7.Cu")
	)
	(gr_circle
		(center 368.474752 -271.656048)
		(end 368.728752 -271.656048)
		(stroke
			(width 0.1016)
			(type default)
		)
		(fill no)
		(layer "In7.Cu")
	)
	(gr_circle
		(center 368.474752 -270.036036)
		(end 368.728752 -270.036036)
		(stroke
			(width 0.1016)
			(type default)
		)
		(fill no)
		(layer "In7.Cu")
	)
	(gr_circle
		(center 368.679984 -164.53358)
		(end 369.568984 -164.53358)
		(stroke
			(width 0.2)
			(type default)
		)
		(fill no)
		(layer "In7.Cu")
	)
	(gr_circle
		(center 368.679984 -163.89858)
		(end 369.568984 -163.89858)
		(stroke
			(width 0.2)
			(type default)
		)
		(fill no)
		(layer "In7.Cu")
	)
	(gr_circle
		(center 368.692684 -165.19398)
		(end 369.581684 -165.19398)
		(stroke
			(width 0.2)
			(type default)
		)
		(fill no)
		(layer "In7.Cu")
	)
	(gr_circle
		(center 368.96421 -179.204874)
		(end 369.85321 -179.204874)
		(stroke
			(width 0.2)
			(type default)
		)
		(fill no)
		(layer "In7.Cu")
	)
	(gr_circle
		(center 369.314984 -164.53358)
		(end 370.203984 -164.53358)
		(stroke
			(width 0.2)
			(type default)
		)
		(fill no)
		(layer "In7.Cu")
	)
	(gr_circle
		(center 369.314984 -163.89858)
		(end 370.203984 -163.89858)
		(stroke
			(width 0.2)
			(type default)
		)
		(fill no)
		(layer "In7.Cu")
	)
	(gr_circle
		(center 369.327684 -165.19398)
		(end 370.216684 -165.19398)
		(stroke
			(width 0.2)
			(type default)
		)
		(fill no)
		(layer "In7.Cu")
	)
	(gr_circle
		(center 369.49761 -179.560474)
		(end 370.38661 -179.560474)
		(stroke
			(width 0.2)
			(type default)
		)
		(fill no)
		(layer "In7.Cu")
	)
	(gr_circle
		(center 369.49761 -178.798474)
		(end 370.38661 -178.798474)
		(stroke
			(width 0.2)
			(type default)
		)
		(fill no)
		(layer "In7.Cu")
	)
	(gr_circle
		(center 369.49761 -178.036474)
		(end 370.38661 -178.036474)
		(stroke
			(width 0.2)
			(type default)
		)
		(fill no)
		(layer "In7.Cu")
	)
	(gr_circle
		(center 369.52301 -180.322474)
		(end 370.41201 -180.322474)
		(stroke
			(width 0.2)
			(type default)
		)
		(fill no)
		(layer "In7.Cu")
	)
	(gr_circle
		(center 369.949984 -164.53358)
		(end 370.838984 -164.53358)
		(stroke
			(width 0.2)
			(type default)
		)
		(fill no)
		(layer "In7.Cu")
	)
	(gr_circle
		(center 369.949984 -163.89858)
		(end 370.838984 -163.89858)
		(stroke
			(width 0.2)
			(type default)
		)
		(fill no)
		(layer "In7.Cu")
	)
	(gr_circle
		(center 369.962684 -165.19398)
		(end 370.851684 -165.19398)
		(stroke
			(width 0.2)
			(type default)
		)
		(fill no)
		(layer "In7.Cu")
	)
	(gr_circle
		(center 370.047774 -179.883054)
		(end 370.936774 -179.883054)
		(stroke
			(width 0.2)
			(type default)
		)
		(fill no)
		(layer "In7.Cu")
	)
	(gr_circle
		(center 370.047774 -179.146454)
		(end 370.936774 -179.146454)
		(stroke
			(width 0.2)
			(type default)
		)
		(fill no)
		(layer "In7.Cu")
	)
	(gr_circle
		(center 370.35486 -278.136096)
		(end 370.60886 -278.136096)
		(stroke
			(width 0.1016)
			(type default)
		)
		(fill no)
		(layer "In7.Cu")
	)
	(gr_circle
		(center 370.35486 -276.516084)
		(end 370.60886 -276.516084)
		(stroke
			(width 0.1016)
			(type default)
		)
		(fill no)
		(layer "In7.Cu")
	)
	(gr_circle
		(center 370.35486 -274.896072)
		(end 370.60886 -274.896072)
		(stroke
			(width 0.1016)
			(type default)
		)
		(fill no)
		(layer "In7.Cu")
	)
	(gr_circle
		(center 370.35486 -273.27606)
		(end 370.60886 -273.27606)
		(stroke
			(width 0.1016)
			(type default)
		)
		(fill no)
		(layer "In7.Cu")
	)
	(gr_circle
		(center 370.35486 -271.656048)
		(end 370.60886 -271.656048)
		(stroke
			(width 0.1016)
			(type default)
		)
		(fill no)
		(layer "In7.Cu")
	)
	(gr_circle
		(center 370.35486 -270.036036)
		(end 370.60886 -270.036036)
		(stroke
			(width 0.1016)
			(type default)
		)
		(fill no)
		(layer "In7.Cu")
	)
	(gr_circle
		(center 370.529358 -182.141876)
		(end 371.418358 -182.141876)
		(stroke
			(width 0.2)
			(type default)
		)
		(fill no)
		(layer "In7.Cu")
	)
	(gr_circle
		(center 370.529358 -181.405276)
		(end 371.418358 -181.405276)
		(stroke
			(width 0.2)
			(type default)
		)
		(fill no)
		(layer "In7.Cu")
	)
	(gr_circle
		(center 370.686584 -164.53358)
		(end 371.575584 -164.53358)
		(stroke
			(width 0.2)
			(type default)
		)
		(fill no)
		(layer "In7.Cu")
	)
	(gr_circle
		(center 370.686584 -163.89858)
		(end 371.575584 -163.89858)
		(stroke
			(width 0.2)
			(type default)
		)
		(fill no)
		(layer "In7.Cu")
	)
	(gr_circle
		(center 370.699284 -165.19398)
		(end 371.588284 -165.19398)
		(stroke
			(width 0.2)
			(type default)
		)
		(fill no)
		(layer "In7.Cu")
	)
	(gr_circle
		(center 370.74221 -180.803804)
		(end 371.62232 -180.803804)
		(stroke
			(width 0.2)
			(type default)
		)
		(fill no)
		(layer "In7.Cu")
	)
	(gr_circle
		(center 371.294914 -278.136096)
		(end 371.548914 -278.136096)
		(stroke
			(width 0.1016)
			(type default)
		)
		(fill no)
		(layer "In7.Cu")
	)
	(gr_circle
		(center 371.294914 -276.516084)
		(end 371.548914 -276.516084)
		(stroke
			(width 0.1016)
			(type default)
		)
		(fill no)
		(layer "In7.Cu")
	)
	(gr_circle
		(center 371.294914 -274.896072)
		(end 371.548914 -274.896072)
		(stroke
			(width 0.1016)
			(type default)
		)
		(fill no)
		(layer "In7.Cu")
	)
	(gr_circle
		(center 371.294914 -273.27606)
		(end 371.548914 -273.27606)
		(stroke
			(width 0.1016)
			(type default)
		)
		(fill no)
		(layer "In7.Cu")
	)
	(gr_circle
		(center 371.294914 -271.656048)
		(end 371.548914 -271.656048)
		(stroke
			(width 0.1016)
			(type default)
		)
		(fill no)
		(layer "In7.Cu")
	)
	(gr_circle
		(center 371.294914 -270.036036)
		(end 371.548914 -270.036036)
		(stroke
			(width 0.1016)
			(type default)
		)
		(fill no)
		(layer "In7.Cu")
	)
	(gr_circle
		(center 371.35943 -180.803804)
		(end 372.23954 -180.803804)
		(stroke
			(width 0.2)
			(type default)
		)
		(fill no)
		(layer "In7.Cu")
	)
	(gr_circle
		(center 371.97665 -180.803804)
		(end 372.85676 -180.803804)
		(stroke
			(width 0.2)
			(type default)
		)
		(fill no)
		(layer "In7.Cu")
	)
	(gr_circle
		(center 373.174768 -278.136096)
		(end 373.428768 -278.136096)
		(stroke
			(width 0.1016)
			(type default)
		)
		(fill no)
		(layer "In7.Cu")
	)
	(gr_circle
		(center 373.174768 -276.516084)
		(end 373.428768 -276.516084)
		(stroke
			(width 0.1016)
			(type default)
		)
		(fill no)
		(layer "In7.Cu")
	)
	(gr_circle
		(center 373.174768 -274.896072)
		(end 373.428768 -274.896072)
		(stroke
			(width 0.1016)
			(type default)
		)
		(fill no)
		(layer "In7.Cu")
	)
	(gr_circle
		(center 373.174768 -273.27606)
		(end 373.428768 -273.27606)
		(stroke
			(width 0.1016)
			(type default)
		)
		(fill no)
		(layer "In7.Cu")
	)
	(gr_circle
		(center 373.174768 -271.656048)
		(end 373.428768 -271.656048)
		(stroke
			(width 0.1016)
			(type default)
		)
		(fill no)
		(layer "In7.Cu")
	)
	(gr_circle
		(center 373.174768 -270.036036)
		(end 373.428768 -270.036036)
		(stroke
			(width 0.1016)
			(type default)
		)
		(fill no)
		(layer "In7.Cu")
	)
	(gr_circle
		(center 374.114822 -278.136096)
		(end 374.368822 -278.136096)
		(stroke
			(width 0.1016)
			(type default)
		)
		(fill no)
		(layer "In7.Cu")
	)
	(gr_circle
		(center 374.114822 -276.516084)
		(end 374.368822 -276.516084)
		(stroke
			(width 0.1016)
			(type default)
		)
		(fill no)
		(layer "In7.Cu")
	)
	(gr_circle
		(center 374.114822 -274.896072)
		(end 374.368822 -274.896072)
		(stroke
			(width 0.1016)
			(type default)
		)
		(fill no)
		(layer "In7.Cu")
	)
	(gr_circle
		(center 374.114822 -273.27606)
		(end 374.368822 -273.27606)
		(stroke
			(width 0.1016)
			(type default)
		)
		(fill no)
		(layer "In7.Cu")
	)
	(gr_circle
		(center 374.114822 -271.656048)
		(end 374.368822 -271.656048)
		(stroke
			(width 0.1016)
			(type default)
		)
		(fill no)
		(layer "In7.Cu")
	)
	(gr_circle
		(center 374.114822 -270.036036)
		(end 374.368822 -270.036036)
		(stroke
			(width 0.1016)
			(type default)
		)
		(fill no)
		(layer "In7.Cu")
	)
	(gr_circle
		(center 377.367038 -180.678074)
		(end 378.256038 -180.678074)
		(stroke
			(width 0.2)
			(type default)
		)
		(fill no)
		(layer "In7.Cu")
	)
	(gr_circle
		(center 377.367038 -179.941474)
		(end 378.256038 -179.941474)
		(stroke
			(width 0.2)
			(type default)
		)
		(fill no)
		(layer "In7.Cu")
	)
	(gr_circle
		(center 377.367038 -179.204874)
		(end 378.256038 -179.204874)
		(stroke
			(width 0.2)
			(type default)
		)
		(fill no)
		(layer "In7.Cu")
	)
	(gr_circle
		(center 377.869958 -162.59683)
		(end 379.266958 -162.59683)
		(stroke
			(width 0.2)
			(type default)
		)
		(fill no)
		(layer "In7.Cu")
	)
	(gr_circle
		(center 377.900438 -179.560474)
		(end 378.789438 -179.560474)
		(stroke
			(width 0.2)
			(type default)
		)
		(fill no)
		(layer "In7.Cu")
	)
	(gr_circle
		(center 377.925838 -180.322474)
		(end 378.814838 -180.322474)
		(stroke
			(width 0.2)
			(type default)
		)
		(fill no)
		(layer "In7.Cu")
	)
	(gr_circle
		(center 378.450602 -179.883054)
		(end 379.339602 -179.883054)
		(stroke
			(width 0.2)
			(type default)
		)
		(fill no)
		(layer "In7.Cu")
	)
	(gr_circle
		(center 378.450602 -179.146454)
		(end 379.339602 -179.146454)
		(stroke
			(width 0.2)
			(type default)
		)
		(fill no)
		(layer "In7.Cu")
	)
	(gr_circle
		(center 379.035056 -182.230776)
		(end 379.924056 -182.230776)
		(stroke
			(width 0.2)
			(type default)
		)
		(fill no)
		(layer "In7.Cu")
	)
	(gr_circle
		(center 379.035056 -181.494176)
		(end 379.924056 -181.494176)
		(stroke
			(width 0.2)
			(type default)
		)
		(fill no)
		(layer "In7.Cu")
	)
	(gr_circle
		(center 379.152658 -180.755544)
		(end 380.032768 -180.755544)
		(stroke
			(width 0.2)
			(type default)
		)
		(fill no)
		(layer "In7.Cu")
	)
	(gr_circle
		(center 379.769878 -180.755544)
		(end 380.649988 -180.755544)
		(stroke
			(width 0.2)
			(type default)
		)
		(fill no)
		(layer "In7.Cu")
	)
	(gr_circle
		(center 380.387098 -180.755544)
		(end 381.267208 -180.755544)
		(stroke
			(width 0.2)
			(type default)
		)
		(fill no)
		(layer "In7.Cu")
	)
	(gr_arc
		(start 385.601972 -11.780012)
		(mid 387.016183 -11.194227)
		(end 387.601968 -9.780016)
		(stroke
			(width 1.016)
			(type default)
		)
		(layer "In7.Cu")
	)
	(gr_circle
		(center 385.698238 -180.678074)
		(end 386.587238 -180.678074)
		(stroke
			(width 0.2)
			(type default)
		)
		(fill no)
		(layer "In7.Cu")
	)
	(gr_circle
		(center 385.698238 -179.941474)
		(end 386.587238 -179.941474)
		(stroke
			(width 0.2)
			(type default)
		)
		(fill no)
		(layer "In7.Cu")
	)
	(gr_circle
		(center 385.698238 -179.204874)
		(end 386.587238 -179.204874)
		(stroke
			(width 0.2)
			(type default)
		)
		(fill no)
		(layer "In7.Cu")
	)
	(gr_circle
		(center 386.231638 -179.560474)
		(end 387.120638 -179.560474)
		(stroke
			(width 0.2)
			(type default)
		)
		(fill no)
		(layer "In7.Cu")
	)
	(gr_circle
		(center 386.257038 -180.322474)
		(end 387.146038 -180.322474)
		(stroke
			(width 0.2)
			(type default)
		)
		(fill no)
		(layer "In7.Cu")
	)
	(gr_circle
		(center 386.781802 -179.883054)
		(end 387.670802 -179.883054)
		(stroke
			(width 0.2)
			(type default)
		)
		(fill no)
		(layer "In7.Cu")
	)
	(gr_circle
		(center 386.781802 -179.146454)
		(end 387.670802 -179.146454)
		(stroke
			(width 0.2)
			(type default)
		)
		(fill no)
		(layer "In7.Cu")
	)
	(gr_circle
		(center 387.206998 -162.65271)
		(end 388.603998 -162.65271)
		(stroke
			(width 0.2)
			(type default)
		)
		(fill no)
		(layer "In7.Cu")
	)
	(gr_circle
		(center 387.293358 -157.001972)
		(end 388.182358 -157.001972)
		(stroke
			(width 0.2)
			(type default)
		)
		(fill no)
		(layer "In7.Cu")
	)
	(gr_circle
		(center 387.293358 -156.366972)
		(end 388.182358 -156.366972)
		(stroke
			(width 0.2)
			(type default)
		)
		(fill no)
		(layer "In7.Cu")
	)
	(gr_circle
		(center 387.293358 -155.724352)
		(end 388.182358 -155.724352)
		(stroke
			(width 0.2)
			(type default)
		)
		(fill no)
		(layer "In7.Cu")
	)
	(gr_circle
		(center 387.293358 -155.089352)
		(end 388.182358 -155.089352)
		(stroke
			(width 0.2)
			(type default)
		)
		(fill no)
		(layer "In7.Cu")
	)
	(gr_circle
		(center 387.293358 -154.428952)
		(end 388.182358 -154.428952)
		(stroke
			(width 0.2)
			(type default)
		)
		(fill no)
		(layer "In7.Cu")
	)
	(gr_circle
		(center 387.293358 -153.793952)
		(end 388.182358 -153.793952)
		(stroke
			(width 0.2)
			(type default)
		)
		(fill no)
		(layer "In7.Cu")
	)
	(gr_circle
		(center 387.366256 -182.230776)
		(end 388.255256 -182.230776)
		(stroke
			(width 0.2)
			(type default)
		)
		(fill no)
		(layer "In7.Cu")
	)
	(gr_circle
		(center 387.366256 -181.494176)
		(end 388.255256 -181.494176)
		(stroke
			(width 0.2)
			(type default)
		)
		(fill no)
		(layer "In7.Cu")
	)
	(gr_circle
		(center 387.483858 -180.755544)
		(end 388.363968 -180.755544)
		(stroke
			(width 0.2)
			(type default)
		)
		(fill no)
		(layer "In7.Cu")
	)
	(gr_line
		(start 387.601968 -9.780016)
		(end 387.601968 -0.500126)
		(stroke
			(width 1.016)
			(type default)
		)
		(layer "In7.Cu")
	)
	(gr_circle
		(center 387.928358 -157.001972)
		(end 388.817358 -157.001972)
		(stroke
			(width 0.2)
			(type default)
		)
		(fill no)
		(layer "In7.Cu")
	)
	(gr_circle
		(center 387.928358 -156.366972)
		(end 388.817358 -156.366972)
		(stroke
			(width 0.2)
			(type default)
		)
		(fill no)
		(layer "In7.Cu")
	)
	(gr_circle
		(center 387.928358 -155.724352)
		(end 388.817358 -155.724352)
		(stroke
			(width 0.2)
			(type default)
		)
		(fill no)
		(layer "In7.Cu")
	)
	(gr_circle
		(center 387.928358 -155.089352)
		(end 388.817358 -155.089352)
		(stroke
			(width 0.2)
			(type default)
		)
		(fill no)
		(layer "In7.Cu")
	)
	(gr_circle
		(center 387.928358 -154.428952)
		(end 388.817358 -154.428952)
		(stroke
			(width 0.2)
			(type default)
		)
		(fill no)
		(layer "In7.Cu")
	)
	(gr_circle
		(center 387.928358 -153.793952)
		(end 388.817358 -153.793952)
		(stroke
			(width 0.2)
			(type default)
		)
		(fill no)
		(layer "In7.Cu")
	)
	(gr_circle
		(center 388.101078 -180.755544)
		(end 388.981188 -180.755544)
		(stroke
			(width 0.2)
			(type default)
		)
		(fill no)
		(layer "In7.Cu")
	)
	(gr_arc
		(start 388.102094 0)
		(mid 387.748465 -0.146487)
		(end 387.601968 -0.500126)
		(stroke
			(width 1.016)
			(type default)
		)
		(layer "In7.Cu")
	)
	(gr_line
		(start 388.102094 0)
		(end 455.701908 0)
		(stroke
			(width 1.016)
			(type default)
		)
		(layer "In7.Cu")
	)
	(gr_circle
		(center 388.718298 -180.755544)
		(end 389.598408 -180.755544)
		(stroke
			(width 0.2)
			(type default)
		)
		(fill no)
		(layer "In7.Cu")
	)
	(gr_circle
		(center 394.628878 -173.21911)
		(end 395.517878 -173.21911)
		(stroke
			(width 0.2)
			(type default)
		)
		(fill no)
		(layer "In7.Cu")
	)
	(gr_circle
		(center 394.628878 -172.45711)
		(end 395.517878 -172.45711)
		(stroke
			(width 0.2)
			(type default)
		)
		(fill no)
		(layer "In7.Cu")
	)
	(gr_circle
		(center 394.646658 -173.987714)
		(end 395.535658 -173.987714)
		(stroke
			(width 0.2)
			(type default)
		)
		(fill no)
		(layer "In7.Cu")
	)
	(gr_circle
		(center 394.672058 -174.749714)
		(end 395.561058 -174.749714)
		(stroke
			(width 0.2)
			(type default)
		)
		(fill no)
		(layer "In7.Cu")
	)
	(gr_circle
		(center 395.196822 -174.310294)
		(end 396.085822 -174.310294)
		(stroke
			(width 0.2)
			(type default)
		)
		(fill no)
		(layer "In7.Cu")
	)
	(gr_circle
		(center 395.196822 -173.573694)
		(end 396.085822 -173.573694)
		(stroke
			(width 0.2)
			(type default)
		)
		(fill no)
		(layer "In7.Cu")
	)
	(gr_circle
		(center 395.230858 -172.819314)
		(end 396.119858 -172.819314)
		(stroke
			(width 0.2)
			(type default)
		)
		(fill no)
		(layer "In7.Cu")
	)
	(gr_circle
		(center 395.781276 -176.657254)
		(end 396.670276 -176.657254)
		(stroke
			(width 0.2)
			(type default)
		)
		(fill no)
		(layer "In7.Cu")
	)
	(gr_circle
		(center 395.781276 -175.895254)
		(end 396.670276 -175.895254)
		(stroke
			(width 0.2)
			(type default)
		)
		(fill no)
		(layer "In7.Cu")
	)
	(gr_circle
		(center 395.898878 -175.182784)
		(end 396.778988 -175.182784)
		(stroke
			(width 0.2)
			(type default)
		)
		(fill no)
		(layer "In7.Cu")
	)
	(gr_circle
		(center 396.516098 -175.182784)
		(end 397.396208 -175.182784)
		(stroke
			(width 0.2)
			(type default)
		)
		(fill no)
		(layer "In7.Cu")
	)
	(gr_circle
		(center 397.133318 -175.182784)
		(end 398.013428 -175.182784)
		(stroke
			(width 0.2)
			(type default)
		)
		(fill no)
		(layer "In7.Cu")
	)
	(gr_circle
		(center 399.165064 -81.051146)
		(end 400.054064 -81.051146)
		(stroke
			(width 0.2)
			(type default)
		)
		(fill no)
		(layer "In7.Cu")
	)
	(gr_circle
		(center 402.436838 -166.527988)
		(end 403.325838 -166.527988)
		(stroke
			(width 0.2)
			(type default)
		)
		(fill no)
		(layer "In7.Cu")
	)
	(gr_circle
		(center 402.436838 -165.791388)
		(end 403.325838 -165.791388)
		(stroke
			(width 0.2)
			(type default)
		)
		(fill no)
		(layer "In7.Cu")
	)
	(gr_circle
		(center 402.436838 -165.054788)
		(end 403.325838 -165.054788)
		(stroke
			(width 0.2)
			(type default)
		)
		(fill no)
		(layer "In7.Cu")
	)
	(gr_circle
		(center 402.970238 -165.410388)
		(end 403.859238 -165.410388)
		(stroke
			(width 0.2)
			(type default)
		)
		(fill no)
		(layer "In7.Cu")
	)
	(gr_circle
		(center 402.995638 -166.172388)
		(end 403.884638 -166.172388)
		(stroke
			(width 0.2)
			(type default)
		)
		(fill no)
		(layer "In7.Cu")
	)
	(gr_circle
		(center 403.520402 -165.732968)
		(end 404.409402 -165.732968)
		(stroke
			(width 0.2)
			(type default)
		)
		(fill no)
		(layer "In7.Cu")
	)
	(gr_circle
		(center 403.520402 -164.996368)
		(end 404.409402 -164.996368)
		(stroke
			(width 0.2)
			(type default)
		)
		(fill no)
		(layer "In7.Cu")
	)
	(gr_circle
		(center 404.104856 -168.082214)
		(end 404.993856 -168.082214)
		(stroke
			(width 0.2)
			(type default)
		)
		(fill no)
		(layer "In7.Cu")
	)
	(gr_circle
		(center 404.104856 -167.320214)
		(end 404.993856 -167.320214)
		(stroke
			(width 0.2)
			(type default)
		)
		(fill no)
		(layer "In7.Cu")
	)
	(gr_circle
		(center 404.222458 -166.605458)
		(end 405.102568 -166.605458)
		(stroke
			(width 0.2)
			(type default)
		)
		(fill no)
		(layer "In7.Cu")
	)
	(gr_circle
		(center 404.839678 -166.605458)
		(end 405.719788 -166.605458)
		(stroke
			(width 0.2)
			(type default)
		)
		(fill no)
		(layer "In7.Cu")
	)
	(gr_circle
		(center 405.456898 -166.605458)
		(end 406.337008 -166.605458)
		(stroke
			(width 0.2)
			(type default)
		)
		(fill no)
		(layer "In7.Cu")
	)
	(gr_circle
		(center 410.818838 -161.701988)
		(end 411.707838 -161.701988)
		(stroke
			(width 0.2)
			(type default)
		)
		(fill no)
		(layer "In7.Cu")
	)
	(gr_circle
		(center 410.818838 -160.965388)
		(end 411.707838 -160.965388)
		(stroke
			(width 0.2)
			(type default)
		)
		(fill no)
		(layer "In7.Cu")
	)
	(gr_circle
		(center 410.818838 -160.228788)
		(end 411.707838 -160.228788)
		(stroke
			(width 0.2)
			(type default)
		)
		(fill no)
		(layer "In7.Cu")
	)
	(gr_circle
		(center 411.352238 -160.584388)
		(end 412.241238 -160.584388)
		(stroke
			(width 0.2)
			(type default)
		)
		(fill no)
		(layer "In7.Cu")
	)
	(gr_circle
		(center 411.377638 -161.346388)
		(end 412.266638 -161.346388)
		(stroke
			(width 0.2)
			(type default)
		)
		(fill no)
		(layer "In7.Cu")
	)
	(gr_circle
		(center 411.902402 -160.906968)
		(end 412.791402 -160.906968)
		(stroke
			(width 0.2)
			(type default)
		)
		(fill no)
		(layer "In7.Cu")
	)
	(gr_circle
		(center 411.902402 -160.170368)
		(end 412.791402 -160.170368)
		(stroke
			(width 0.2)
			(type default)
		)
		(fill no)
		(layer "In7.Cu")
	)
	(gr_circle
		(center 412.486856 -163.256214)
		(end 413.375856 -163.256214)
		(stroke
			(width 0.2)
			(type default)
		)
		(fill no)
		(layer "In7.Cu")
	)
	(gr_circle
		(center 412.486856 -162.494214)
		(end 413.375856 -162.494214)
		(stroke
			(width 0.2)
			(type default)
		)
		(fill no)
		(layer "In7.Cu")
	)
	(gr_circle
		(center 412.604458 -161.779458)
		(end 413.484568 -161.779458)
		(stroke
			(width 0.2)
			(type default)
		)
		(fill no)
		(layer "In7.Cu")
	)
	(gr_circle
		(center 413.221678 -161.779458)
		(end 414.101788 -161.779458)
		(stroke
			(width 0.2)
			(type default)
		)
		(fill no)
		(layer "In7.Cu")
	)
	(gr_circle
		(center 413.838898 -161.779458)
		(end 414.719008 -161.779458)
		(stroke
			(width 0.2)
			(type default)
		)
		(fill no)
		(layer "In7.Cu")
	)
	(gr_circle
		(center 424.33494 -353.10318)
		(end 425.21505 -353.10318)
		(stroke
			(width 0.2)
			(type default)
		)
		(fill no)
		(layer "In7.Cu")
	)
	(gr_circle
		(center 424.95216 -353.10318)
		(end 425.83227 -353.10318)
		(stroke
			(width 0.2)
			(type default)
		)
		(fill no)
		(layer "In7.Cu")
	)
	(gr_circle
		(center 425.56938 -353.10318)
		(end 426.44949 -353.10318)
		(stroke
			(width 0.2)
			(type default)
		)
		(fill no)
		(layer "In7.Cu")
	)
	(gr_circle
		(center 425.686474 -352.35769)
		(end 426.575474 -352.35769)
		(stroke
			(width 0.2)
			(type default)
		)
		(fill no)
		(layer "In7.Cu")
	)
	(gr_circle
		(center 425.686474 -351.62109)
		(end 426.575474 -351.62109)
		(stroke
			(width 0.2)
			(type default)
		)
		(fill no)
		(layer "In7.Cu")
	)
	(gr_circle
		(center 426.271436 -354.71227)
		(end 427.160436 -354.71227)
		(stroke
			(width 0.2)
			(type default)
		)
		(fill no)
		(layer "In7.Cu")
	)
	(gr_circle
		(center 426.271436 -353.97567)
		(end 427.160436 -353.97567)
		(stroke
			(width 0.2)
			(type default)
		)
		(fill no)
		(layer "In7.Cu")
	)
	(gr_circle
		(center 426.7962 -353.53625)
		(end 427.6852 -353.53625)
		(stroke
			(width 0.2)
			(type default)
		)
		(fill no)
		(layer "In7.Cu")
	)
	(gr_circle
		(center 426.8216 -354.29825)
		(end 427.7106 -354.29825)
		(stroke
			(width 0.2)
			(type default)
		)
		(fill no)
		(layer "In7.Cu")
	)
	(gr_circle
		(center 427.355 -354.65385)
		(end 428.244 -354.65385)
		(stroke
			(width 0.2)
			(type default)
		)
		(fill no)
		(layer "In7.Cu")
	)
	(gr_circle
		(center 427.355 -353.91725)
		(end 428.244 -353.91725)
		(stroke
			(width 0.2)
			(type default)
		)
		(fill no)
		(layer "In7.Cu")
	)
	(gr_circle
		(center 427.355 -353.18065)
		(end 428.244 -353.18065)
		(stroke
			(width 0.2)
			(type default)
		)
		(fill no)
		(layer "In7.Cu")
	)
	(gr_circle
		(center 432.01336 -361.827826)
		(end 433.41036 -361.827826)
		(stroke
			(width 0.2)
			(type default)
		)
		(fill no)
		(layer "In7.Cu")
	)
	(gr_circle
		(center 432.661568 -353.12858)
		(end 433.541678 -353.12858)
		(stroke
			(width 0.2)
			(type default)
		)
		(fill no)
		(layer "In7.Cu")
	)
	(gr_circle
		(center 433.278788 -353.12858)
		(end 434.158898 -353.12858)
		(stroke
			(width 0.2)
			(type default)
		)
		(fill no)
		(layer "In7.Cu")
	)
	(gr_circle
		(center 433.896008 -353.12858)
		(end 434.776118 -353.12858)
		(stroke
			(width 0.2)
			(type default)
		)
		(fill no)
		(layer "In7.Cu")
	)
	(gr_circle
		(center 434.013102 -352.38309)
		(end 434.902102 -352.38309)
		(stroke
			(width 0.2)
			(type default)
		)
		(fill no)
		(layer "In7.Cu")
	)
	(gr_circle
		(center 434.013102 -351.64649)
		(end 434.902102 -351.64649)
		(stroke
			(width 0.2)
			(type default)
		)
		(fill no)
		(layer "In7.Cu")
	)
	(gr_circle
		(center 434.598064 -354.73767)
		(end 435.487064 -354.73767)
		(stroke
			(width 0.2)
			(type default)
		)
		(fill no)
		(layer "In7.Cu")
	)
	(gr_circle
		(center 434.598064 -354.00107)
		(end 435.487064 -354.00107)
		(stroke
			(width 0.2)
			(type default)
		)
		(fill no)
		(layer "In7.Cu")
	)
	(gr_circle
		(center 435.122828 -353.56165)
		(end 436.011828 -353.56165)
		(stroke
			(width 0.2)
			(type default)
		)
		(fill no)
		(layer "In7.Cu")
	)
	(gr_circle
		(center 435.148228 -354.32365)
		(end 436.037228 -354.32365)
		(stroke
			(width 0.2)
			(type default)
		)
		(fill no)
		(layer "In7.Cu")
	)
	(gr_circle
		(center 435.469538 -361.496102)
		(end 436.358538 -361.496102)
		(stroke
			(width 0.2)
			(type default)
		)
		(fill no)
		(layer "In7.Cu")
	)
	(gr_circle
		(center 435.469538 -360.734102)
		(end 436.358538 -360.734102)
		(stroke
			(width 0.2)
			(type default)
		)
		(fill no)
		(layer "In7.Cu")
	)
	(gr_circle
		(center 435.469538 -359.972102)
		(end 436.358538 -359.972102)
		(stroke
			(width 0.2)
			(type default)
		)
		(fill no)
		(layer "In7.Cu")
	)
	(gr_circle
		(center 435.681628 -354.67925)
		(end 436.570628 -354.67925)
		(stroke
			(width 0.2)
			(type default)
		)
		(fill no)
		(layer "In7.Cu")
	)
	(gr_circle
		(center 435.681628 -353.94265)
		(end 436.570628 -353.94265)
		(stroke
			(width 0.2)
			(type default)
		)
		(fill no)
		(layer "In7.Cu")
	)
	(gr_circle
		(center 435.681628 -353.20605)
		(end 436.570628 -353.20605)
		(stroke
			(width 0.2)
			(type default)
		)
		(fill no)
		(layer "In7.Cu")
	)
	(gr_circle
		(center 436.231538 -361.496102)
		(end 437.120538 -361.496102)
		(stroke
			(width 0.2)
			(type default)
		)
		(fill no)
		(layer "In7.Cu")
	)
	(gr_circle
		(center 436.231538 -360.734102)
		(end 437.120538 -360.734102)
		(stroke
			(width 0.2)
			(type default)
		)
		(fill no)
		(layer "In7.Cu")
	)
	(gr_circle
		(center 436.231538 -359.972102)
		(end 437.120538 -359.972102)
		(stroke
			(width 0.2)
			(type default)
		)
		(fill no)
		(layer "In7.Cu")
	)
	(gr_circle
		(center 437.703214 -12.400788)
		(end 438.592214 -12.400788)
		(stroke
			(width 0.2)
			(type default)
		)
		(fill no)
		(layer "In7.Cu")
	)
	(gr_circle
		(center 438.06999 -13.069316)
		(end 438.95899 -13.069316)
		(stroke
			(width 0.2)
			(type default)
		)
		(fill no)
		(layer "In7.Cu")
	)
	(gr_circle
		(center 438.592214 -12.400788)
		(end 439.481214 -12.400788)
		(stroke
			(width 0.2)
			(type default)
		)
		(fill no)
		(layer "In7.Cu")
	)
	(gr_circle
		(center 438.71515 -13.061696)
		(end 439.60415 -13.061696)
		(stroke
			(width 0.2)
			(type default)
		)
		(fill no)
		(layer "In7.Cu")
	)
	(gr_circle
		(center 439.39333 -13.043916)
		(end 440.28233 -13.043916)
		(stroke
			(width 0.2)
			(type default)
		)
		(fill no)
		(layer "In7.Cu")
	)
	(gr_circle
		(center 439.481214 -12.400788)
		(end 440.370214 -12.400788)
		(stroke
			(width 0.2)
			(type default)
		)
		(fill no)
		(layer "In7.Cu")
	)
	(gr_circle
		(center 440.945524 -11.261852)
		(end 441.834524 -11.261852)
		(stroke
			(width 0.2)
			(type default)
		)
		(fill no)
		(layer "In7.Cu")
	)
	(gr_circle
		(center 440.945524 -10.626852)
		(end 441.834524 -10.626852)
		(stroke
			(width 0.2)
			(type default)
		)
		(fill no)
		(layer "In7.Cu")
	)
	(gr_circle
		(center 441.129674 -25.982422)
		(end 442.018674 -25.982422)
		(stroke
			(width 0.2)
			(type default)
		)
		(fill no)
		(layer "In7.Cu")
	)
	(gr_circle
		(center 441.354718 -20.73656)
		(end 442.243718 -20.73656)
		(stroke
			(width 0.2)
			(type default)
		)
		(fill no)
		(layer "In7.Cu")
	)
	(gr_circle
		(center 441.354718 -20.10156)
		(end 442.243718 -20.10156)
		(stroke
			(width 0.2)
			(type default)
		)
		(fill no)
		(layer "In7.Cu")
	)
	(gr_circle
		(center 441.354718 -19.21256)
		(end 442.243718 -19.21256)
		(stroke
			(width 0.2)
			(type default)
		)
		(fill no)
		(layer "In7.Cu")
	)
	(gr_circle
		(center 441.354718 -18.57756)
		(end 442.243718 -18.57756)
		(stroke
			(width 0.2)
			(type default)
		)
		(fill no)
		(layer "In7.Cu")
	)
	(gr_circle
		(center 441.475622 -14.123162)
		(end 442.364622 -14.123162)
		(stroke
			(width 0.2)
			(type default)
		)
		(fill no)
		(layer "In7.Cu")
	)
	(gr_circle
		(center 441.475622 -13.488162)
		(end 442.364622 -13.488162)
		(stroke
			(width 0.2)
			(type default)
		)
		(fill no)
		(layer "In7.Cu")
	)
	(gr_circle
		(center 441.56249 -25.461976)
		(end 442.45149 -25.461976)
		(stroke
			(width 0.2)
			(type default)
		)
		(fill no)
		(layer "In7.Cu")
	)
	(gr_circle
		(center 442.018674 -25.982422)
		(end 442.907674 -25.982422)
		(stroke
			(width 0.2)
			(type default)
		)
		(fill no)
		(layer "In7.Cu")
	)
	(gr_circle
		(center 442.371734 -20.983702)
		(end 443.260734 -20.983702)
		(stroke
			(width 0.2)
			(type default)
		)
		(fill no)
		(layer "In7.Cu")
	)
	(gr_circle
		(center 442.371734 -20.348702)
		(end 443.260734 -20.348702)
		(stroke
			(width 0.2)
			(type default)
		)
		(fill no)
		(layer "In7.Cu")
	)
	(gr_circle
		(center 442.371734 -19.459702)
		(end 443.260734 -19.459702)
		(stroke
			(width 0.2)
			(type default)
		)
		(fill no)
		(layer "In7.Cu")
	)
	(gr_circle
		(center 442.371734 -18.824702)
		(end 443.260734 -18.824702)
		(stroke
			(width 0.2)
			(type default)
		)
		(fill no)
		(layer "In7.Cu")
	)
	(gr_circle
		(center 442.45149 -25.461976)
		(end 443.34049 -25.461976)
		(stroke
			(width 0.2)
			(type default)
		)
		(fill no)
		(layer "In7.Cu")
	)
	(gr_circle
		(center 442.907674 -25.982422)
		(end 443.796674 -25.982422)
		(stroke
			(width 0.2)
			(type default)
		)
		(fill no)
		(layer "In7.Cu")
	)
	(gr_circle
		(center 443.34049 -25.461976)
		(end 444.22949 -25.461976)
		(stroke
			(width 0.2)
			(type default)
		)
		(fill no)
		(layer "In7.Cu")
	)
	(gr_circle
		(center 444.166244 -24.741632)
		(end 445.055244 -24.741632)
		(stroke
			(width 0.2)
			(type default)
		)
		(fill no)
		(layer "In7.Cu")
	)
	(gr_circle
		(center 450.669914 -14.526514)
		(end 451.558914 -14.526514)
		(stroke
			(width 0.2)
			(type default)
		)
		(fill no)
		(layer "In7.Cu")
	)
	(gr_circle
		(center 450.670676 -16.010382)
		(end 451.559676 -16.010382)
		(stroke
			(width 0.2)
			(type default)
		)
		(fill no)
		(layer "In7.Cu")
	)
	(gr_circle
		(center 450.670676 -15.273782)
		(end 451.559676 -15.273782)
		(stroke
			(width 0.2)
			(type default)
		)
		(fill no)
		(layer "In7.Cu")
	)
	(gr_circle
		(center 452.054976 -18.535142)
		(end 452.943976 -18.535142)
		(stroke
			(width 0.2)
			(type default)
		)
		(fill no)
		(layer "In7.Cu")
	)
	(gr_circle
		(center 452.054976 -17.798542)
		(end 452.943976 -17.798542)
		(stroke
			(width 0.2)
			(type default)
		)
		(fill no)
		(layer "In7.Cu")
	)
	(gr_arc
		(start 456.202034 -9.780016)
		(mid 456.787819 -11.194227)
		(end 458.20203 -11.780012)
		(stroke
			(width 1.016)
			(type default)
		)
		(layer "In7.Cu")
	)
	(gr_arc
		(start 456.202034 -0.500126)
		(mid 456.05556 -0.146464)
		(end 455.701908 0)
		(stroke
			(width 1.016)
			(type default)
		)
		(layer "In7.Cu")
	)
	(gr_line
		(start 456.202034 -0.500126)
		(end 456.202034 -9.780016)
		(stroke
			(width 1.016)
			(type default)
		)
		(layer "In7.Cu")
	)
	(gr_line
		(start 458.20203 -11.780012)
		(end 469.799924 -11.780012)
		(stroke
			(width 1.016)
			(type default)
		)
		(layer "In7.Cu")
	)
	(gr_line
		(start 463.300064 -441.989972)
		(end 277.314914 -441.989972)
		(stroke
			(width 1.016)
			(type default)
		)
		(layer "In7.Cu")
	)
	(gr_arc
		(start 463.300064 -441.989972)
		(mid 464.71429 -441.404198)
		(end 465.30006 -439.989976)
		(stroke
			(width 1.016)
			(type default)
		)
		(layer "In7.Cu")
	)
	(gr_line
		(start 465.30006 -409.528518)
		(end 465.30006 -439.989976)
		(stroke
			(width 1.016)
			(type default)
		)
		(layer "In7.Cu")
	)
	(gr_arc
		(start 465.885784 -408.114246)
		(mid 465.452221 -408.76312)
		(end 465.30006 -409.528518)
		(stroke
			(width 1.016)
			(type default)
		)
		(layer "In7.Cu")
	)
	(gr_line
		(start 467.71433 -406.2857)
		(end 465.885784 -408.114246)
		(stroke
			(width 1.016)
			(type default)
		)
		(layer "In7.Cu")
	)
	(gr_arc
		(start 467.71433 -406.2857)
		(mid 468.147828 -405.636947)
		(end 468.300054 -404.871682)
		(stroke
			(width 1.016)
			(type default)
		)
		(layer "In7.Cu")
	)
	(gr_line
		(start 468.300054 -82.828384)
		(end 468.300054 -404.871682)
		(stroke
			(width 1.016)
			(type default)
		)
		(layer "In7.Cu")
	)
	(gr_arc
		(start 468.885778 -81.414112)
		(mid 468.452215 -82.062986)
		(end 468.300054 -82.828384)
		(stroke
			(width 1.016)
			(type default)
		)
		(layer "In7.Cu")
	)
	(gr_line
		(start 471.214196 -79.085694)
		(end 468.885778 -81.414112)
		(stroke
			(width 1.016)
			(type default)
		)
		(layer "In7.Cu")
	)
	(gr_arc
		(start 471.214196 -79.085694)
		(mid 471.6477 -78.436942)
		(end 471.79992 -77.671676)
		(stroke
			(width 1.016)
			(type default)
		)
		(layer "In7.Cu")
	)
	(gr_arc
		(start 471.79992 -13.780008)
		(mid 471.214139 -12.365784)
		(end 469.799924 -11.780012)
		(stroke
			(width 1.016)
			(type default)
		)
		(layer "In7.Cu")
	)
	(gr_line
		(start 471.79992 -13.780008)
		(end 471.79992 -77.671676)
		(stroke
			(width 1.016)
			(type default)
		)
		(layer "In7.Cu")
	)
	(gr_line
		(start 0 -77.671676)
		(end 0 -13.780008)
		(stroke
			(width 3.048)
			(type default)
		)
		(layer "In8.Cu")
	)
	(gr_arc
		(start 0 -77.671676)
		(mid 0.152237 -78.436936)
		(end 0.585724 -79.085694)
		(stroke
			(width 3.048)
			(type default)
		)
		(layer "In8.Cu")
	)
	(gr_poly
		(pts
			(arc
				(start 279.248108 -392.288014)
				(mid 279.284029 -392.273135)
				(end 279.298908 -392.237214)
			)
			(arc
				(start 279.298908 -383.93116)
				(mid 279.284029 -383.895239)
				(end 279.248108 -383.88036)
			)
			(arc
				(start 275.026374 -383.88036)
				(mid 275.006851 -383.884261)
				(end 274.990306 -383.895346)
			)
			(arc
				(start 274.766278 -384.119374)
				(mid 274.755167 -384.135908)
				(end 274.751292 -384.155442)
			)
			(arc
				(start 274.751292 -392.107928)
				(mid 274.755193 -392.127451)
				(end 274.766278 -392.143996)
			)
			(arc
				(start 274.89531 -392.273028)
				(mid 274.911844 -392.284139)
				(end 274.931378 -392.288014)
			)
		)
		(stroke
			(width 0)
			(type solid)
		)
		(fill yes)
		(layer "In8.Cu")
		(net "P12V_MAIN_R_0")
	)
	(gr_poly
		(pts
			(arc
				(start 273.15541 -393.27836)
				(mid 273.174933 -393.274459)
				(end 273.191478 -393.263374)
			)
			(xy 273.191732 -393.26312) (xy 273.669252 -392.7856)
			(arc
				(start 273.669506 -392.785346)
				(mid 273.680617 -392.768812)
				(end 273.684492 -392.749278)
			)
			(arc
				(start 273.684492 -384.155442)
				(mid 273.680591 -384.135919)
				(end 273.669506 -384.119374)
			)
			(xy 273.669252 -384.11912) (xy 273.447764 -383.897632) (xy 273.447256 -383.897124)
			(arc
				(start 273.445478 -383.895346)
				(mid 273.428944 -383.884235)
				(end 273.40941 -383.88036)
			)
			(arc
				(start 239.542574 -383.88036)
				(mid 239.523051 -383.884261)
				(end 239.506506 -383.895346)
			)
			(xy 239.506252 -383.8956) (xy 239.03051 -384.371342) (xy 239.030256 -384.371596)
			(arc
				(start 239.028478 -384.373374)
				(mid 239.017367 -384.389908)
				(end 239.013492 -384.409442)
			)
			(arc
				(start 239.013492 -393.003278)
				(mid 239.017393 -393.022801)
				(end 239.028478 -393.039346)
			)
			(xy 239.028732 -393.0396) (xy 239.252252 -393.26312)
			(arc
				(start 239.252506 -393.263374)
				(mid 239.26904 -393.274485)
				(end 239.288574 -393.27836)
			)
		)
		(stroke
			(width 0)
			(type solid)
		)
		(fill yes)
		(layer "In8.Cu")
		(net "P12V_MAIN_R")
	)
	(gr_poly
		(pts
			(arc
				(start 206.398622 -326.59066)
				(mid 206.418145 -326.586759)
				(end 206.43469 -326.575674)
			)
			(arc
				(start 206.868014 -326.14235)
				(mid 206.879125 -326.125816)
				(end 206.883 -326.106282)
			)
			(arc
				(start 206.883 -195.214748)
				(mid 206.868121 -195.178827)
				(end 206.8322 -195.163948)
			)
			(arc
				(start 205.382368 -195.163948)
				(mid 205.364098 -195.167347)
				(end 205.348332 -195.177156)
			)
			(arc
				(start 205.348332 -195.177156)
				(mid 205.229568 -195.250032)
				(end 205.092554 -195.275454)
			)
			(arc
				(start 205.092554 -195.275454)
				(mid 204.955518 -195.250091)
				(end 204.836776 -195.177156)
			)
			(arc
				(start 204.836776 -195.177156)
				(mid 204.820978 -195.16743)
				(end 204.80274 -195.163948)
			)
			(arc
				(start 203.563728 -195.163948)
				(mid 203.547063 -195.166759)
				(end 203.532232 -195.17487)
			)
			(arc
				(start 203.532232 -195.17487)
				(mid 203.424633 -195.233867)
				(end 203.303632 -195.254372)
			)
			(arc
				(start 203.303632 -195.254372)
				(mid 203.182603 -195.233948)
				(end 203.075032 -195.17487)
			)
			(arc
				(start 203.075032 -195.17487)
				(mid 203.060207 -195.166744)
				(end 203.043536 -195.163948)
			)
			(xy 201.03846 -195.163948)
			(arc
				(start 201.035412 -195.164202)
				(mid 201.013858 -195.166084)
				(end 200.992232 -195.166742)
			)
			(arc
				(start 200.992232 -195.166742)
				(mid 200.970606 -195.166085)
				(end 200.949052 -195.164202)
			)
			(xy 200.946004 -195.163948)
			(arc
				(start 197.838568 -195.163948)
				(mid 197.820298 -195.167347)
				(end 197.804532 -195.177156)
			)
			(arc
				(start 197.804532 -195.177156)
				(mid 197.5485 -195.275732)
				(end 197.292468 -195.177156)
			)
			(arc
				(start 197.292468 -195.177156)
				(mid 197.27667 -195.16743)
				(end 197.258432 -195.163948)
			)
			(arc
				(start 196.019928 -195.163948)
				(mid 196.003263 -195.166759)
				(end 195.988432 -195.17487)
			)
			(arc
				(start 195.988432 -195.17487)
				(mid 195.880833 -195.233867)
				(end 195.759832 -195.254372)
			)
			(arc
				(start 195.759832 -195.254372)
				(mid 195.638803 -195.233948)
				(end 195.531232 -195.17487)
			)
			(arc
				(start 195.531232 -195.17487)
				(mid 195.516407 -195.166744)
				(end 195.499736 -195.163948)
			)
			(xy 193.49466 -195.163948)
			(arc
				(start 193.491612 -195.164202)
				(mid 193.470058 -195.166084)
				(end 193.448432 -195.166742)
			)
			(arc
				(start 193.448432 -195.166742)
				(mid 193.426806 -195.166085)
				(end 193.405252 -195.164202)
			)
			(xy 193.402204 -195.163948)
			(arc
				(start 190.294514 -195.163948)
				(mid 190.276244 -195.167347)
				(end 190.260478 -195.177156)
			)
			(arc
				(start 190.260478 -195.177156)
				(mid 190.004446 -195.275732)
				(end 189.748414 -195.177156)
			)
			(arc
				(start 189.748414 -195.177156)
				(mid 189.732616 -195.16743)
				(end 189.714378 -195.163948)
			)
			(arc
				(start 188.475874 -195.163948)
				(mid 188.459209 -195.166759)
				(end 188.444378 -195.17487)
			)
			(arc
				(start 188.444378 -195.17487)
				(mid 188.336779 -195.233867)
				(end 188.215778 -195.254372)
			)
			(arc
				(start 188.215778 -195.254372)
				(mid 188.094749 -195.233948)
				(end 187.987178 -195.17487)
			)
			(arc
				(start 187.987178 -195.17487)
				(mid 187.972353 -195.166744)
				(end 187.955682 -195.163948)
			)
			(xy 184.81802 -195.163948)
			(arc
				(start 184.814972 -195.164202)
				(mid 184.793418 -195.166084)
				(end 184.771792 -195.166742)
			)
			(arc
				(start 184.771792 -195.166742)
				(mid 184.750166 -195.166085)
				(end 184.728612 -195.164202)
			)
			(xy 184.725564 -195.163948)
			(arc
				(start 182.750714 -195.163948)
				(mid 182.732444 -195.167347)
				(end 182.716678 -195.177156)
			)
			(arc
				(start 182.716678 -195.177156)
				(mid 182.460646 -195.275732)
				(end 182.204614 -195.177156)
			)
			(arc
				(start 182.204614 -195.177156)
				(mid 182.188816 -195.16743)
				(end 182.170578 -195.163948)
			)
			(arc
				(start 180.93182 -195.163948)
				(mid 180.915155 -195.166759)
				(end 180.900324 -195.17487)
			)
			(arc
				(start 180.900324 -195.17487)
				(mid 180.792725 -195.233867)
				(end 180.671724 -195.254372)
			)
			(arc
				(start 180.671724 -195.254372)
				(mid 180.550695 -195.233948)
				(end 180.443124 -195.17487)
			)
			(arc
				(start 180.443124 -195.17487)
				(mid 180.428299 -195.166744)
				(end 180.411628 -195.163948)
			)
			(xy 178.406552 -195.163948)
			(arc
				(start 178.403504 -195.164202)
				(mid 178.38195 -195.166084)
				(end 178.360324 -195.166742)
			)
			(arc
				(start 178.360324 -195.166742)
				(mid 178.338698 -195.166085)
				(end 178.317144 -195.164202)
			)
			(xy 178.314096 -195.163948)
			(arc
				(start 175.20666 -195.163948)
				(mid 175.18839 -195.167347)
				(end 175.172624 -195.177156)
			)
			(arc
				(start 175.172624 -195.177156)
				(mid 174.916592 -195.275732)
				(end 174.66056 -195.177156)
			)
			(arc
				(start 174.66056 -195.177156)
				(mid 174.644762 -195.16743)
				(end 174.626524 -195.163948)
			)
			(arc
				(start 173.387766 -195.163948)
				(mid 173.371101 -195.166759)
				(end 173.35627 -195.17487)
			)
			(arc
				(start 173.35627 -195.17487)
				(mid 173.248671 -195.233867)
				(end 173.12767 -195.254372)
			)
			(arc
				(start 173.12767 -195.254372)
				(mid 173.006641 -195.233948)
				(end 172.89907 -195.17487)
			)
			(arc
				(start 172.89907 -195.17487)
				(mid 172.884245 -195.166744)
				(end 172.867574 -195.163948)
			)
			(xy 170.862498 -195.163948)
			(arc
				(start 170.85945 -195.164202)
				(mid 170.837896 -195.166084)
				(end 170.81627 -195.166742)
			)
			(arc
				(start 170.81627 -195.166742)
				(mid 170.794644 -195.166085)
				(end 170.77309 -195.164202)
			)
			(xy 170.770042 -195.163948)
			(arc
				(start 167.662606 -195.163948)
				(mid 167.644336 -195.167347)
				(end 167.62857 -195.177156)
			)
			(arc
				(start 167.62857 -195.177156)
				(mid 167.372538 -195.275732)
				(end 167.116506 -195.177156)
			)
			(arc
				(start 167.116506 -195.177156)
				(mid 167.100708 -195.16743)
				(end 167.08247 -195.163948)
			)
			(arc
				(start 165.843712 -195.163948)
				(mid 165.827047 -195.166759)
				(end 165.812216 -195.17487)
			)
			(arc
				(start 165.812216 -195.17487)
				(mid 165.704617 -195.233867)
				(end 165.583616 -195.254372)
			)
			(arc
				(start 165.583616 -195.254372)
				(mid 165.462587 -195.233948)
				(end 165.355016 -195.17487)
			)
			(arc
				(start 165.355016 -195.17487)
				(mid 165.340191 -195.166744)
				(end 165.32352 -195.163948)
			)
			(arc
				(start 164.972238 -195.163948)
				(mid 164.952715 -195.167849)
				(end 164.93617 -195.178934)
			)
			(arc
				(start 164.799772 -195.315332)
				(mid 164.788661 -195.331866)
				(end 164.784786 -195.3514)
			)
			(xy 164.784786 -197.242176)
			(arc
				(start 164.78631 -197.248018)
				(mid 164.794144 -197.291394)
				(end 164.796724 -197.335394)
			)
			(arc
				(start 164.796724 -197.335394)
				(mid 164.794121 -197.379392)
				(end 164.78631 -197.42277)
			)
			(xy 164.784786 -197.428612) (xy 164.784786 -198.942198)
			(arc
				(start 164.78631 -198.94804)
				(mid 164.794144 -198.991416)
				(end 164.796724 -199.035416)
			)
			(arc
				(start 164.796724 -199.035416)
				(mid 164.794121 -199.079414)
				(end 164.78631 -199.122792)
			)
			(xy 164.784786 -199.128634) (xy 164.784786 -204.892148)
			(arc
				(start 164.78631 -204.89799)
				(mid 164.794144 -204.941366)
				(end 164.796724 -204.985366)
			)
			(arc
				(start 164.796724 -204.985366)
				(mid 164.794121 -205.029364)
				(end 164.78631 -205.072742)
			)
			(xy 164.784786 -205.078584) (xy 164.784786 -206.59217)
			(arc
				(start 164.78631 -206.598012)
				(mid 164.794144 -206.641388)
				(end 164.796724 -206.685388)
			)
			(arc
				(start 164.796724 -206.685388)
				(mid 164.794121 -206.729386)
				(end 164.78631 -206.772764)
			)
			(xy 164.784786 -206.778606) (xy 164.784786 -208.292192)
			(arc
				(start 164.78631 -208.298034)
				(mid 164.794144 -208.34141)
				(end 164.796724 -208.38541)
			)
			(arc
				(start 164.796724 -208.38541)
				(mid 164.794121 -208.429408)
				(end 164.78631 -208.472786)
			)
			(xy 164.784786 -208.478628) (xy 164.784786 -214.242142)
			(arc
				(start 164.78631 -214.247984)
				(mid 164.794144 -214.29136)
				(end 164.796724 -214.33536)
			)
			(arc
				(start 164.796724 -214.33536)
				(mid 164.794121 -214.379358)
				(end 164.78631 -214.422736)
			)
			(xy 164.784786 -214.428578) (xy 164.784786 -215.942164)
			(arc
				(start 164.78631 -215.948006)
				(mid 164.794144 -215.991382)
				(end 164.796724 -216.035382)
			)
			(arc
				(start 164.796724 -216.035382)
				(mid 164.794121 -216.07938)
				(end 164.78631 -216.122758)
			)
			(xy 164.784786 -216.1286) (xy 164.784786 -217.642186)
			(arc
				(start 164.78631 -217.648028)
				(mid 164.794144 -217.691404)
				(end 164.796724 -217.735404)
			)
			(arc
				(start 164.796724 -217.735404)
				(mid 164.794121 -217.779402)
				(end 164.78631 -217.82278)
			)
			(xy 164.784786 -217.828622) (xy 164.784786 -223.592136)
			(arc
				(start 164.78631 -223.597978)
				(mid 164.794144 -223.641354)
				(end 164.796724 -223.685354)
			)
			(arc
				(start 164.796724 -223.685354)
				(mid 164.794121 -223.729352)
				(end 164.78631 -223.77273)
			)
			(xy 164.784786 -223.778572) (xy 164.784786 -225.292158)
			(arc
				(start 164.78631 -225.298)
				(mid 164.794144 -225.341376)
				(end 164.796724 -225.385376)
			)
			(arc
				(start 164.796724 -225.385376)
				(mid 164.794121 -225.429374)
				(end 164.78631 -225.472752)
			)
			(xy 164.784786 -225.478594) (xy 164.784786 -226.99218)
			(arc
				(start 164.78631 -226.998022)
				(mid 164.794144 -227.041398)
				(end 164.796724 -227.085398)
			)
			(arc
				(start 164.796724 -227.085398)
				(mid 164.794121 -227.129396)
				(end 164.78631 -227.172774)
			)
			(xy 164.784786 -227.178616) (xy 164.784786 -232.94213)
			(arc
				(start 164.78631 -232.947972)
				(mid 164.794144 -232.991348)
				(end 164.796724 -233.035348)
			)
			(arc
				(start 164.796724 -233.035348)
				(mid 164.794121 -233.079346)
				(end 164.78631 -233.122724)
			)
			(xy 164.784786 -233.128566) (xy 164.784786 -234.642152)
			(arc
				(start 164.78631 -234.647994)
				(mid 164.794144 -234.69137)
				(end 164.796724 -234.73537)
			)
			(arc
				(start 164.796724 -234.73537)
				(mid 164.794121 -234.779368)
				(end 164.78631 -234.822746)
			)
			(xy 164.784786 -234.828588) (xy 164.784786 -236.342174)
			(arc
				(start 164.78631 -236.348016)
				(mid 164.794144 -236.391392)
				(end 164.796724 -236.435392)
			)
			(arc
				(start 164.796724 -236.435392)
				(mid 164.794121 -236.47939)
				(end 164.78631 -236.522768)
			)
			(xy 164.784786 -236.52861) (xy 164.784786 -242.292124)
			(arc
				(start 164.78631 -242.297966)
				(mid 164.794144 -242.341342)
				(end 164.796724 -242.385342)
			)
			(arc
				(start 164.796724 -242.385342)
				(mid 164.794121 -242.42934)
				(end 164.78631 -242.472718)
			)
			(xy 164.784786 -242.47856) (xy 164.784786 -243.992146)
			(arc
				(start 164.78631 -243.997988)
				(mid 164.794144 -244.041364)
				(end 164.796724 -244.085364)
			)
			(arc
				(start 164.796724 -244.085364)
				(mid 164.794121 -244.129362)
				(end 164.78631 -244.17274)
			)
			(xy 164.784786 -244.178582) (xy 164.784786 -245.692168)
			(arc
				(start 164.78631 -245.69801)
				(mid 164.794144 -245.741386)
				(end 164.796724 -245.785386)
			)
			(arc
				(start 164.796724 -245.785386)
				(mid 164.794121 -245.829384)
				(end 164.78631 -245.872762)
			)
			(xy 164.784786 -245.878604) (xy 164.784786 -247.39219)
			(arc
				(start 164.78631 -247.398032)
				(mid 164.794144 -247.441408)
				(end 164.796724 -247.485408)
			)
			(arc
				(start 164.796724 -247.485408)
				(mid 164.794121 -247.529406)
				(end 164.78631 -247.572784)
			)
			(xy 164.784786 -247.578626) (xy 164.784786 -249.092212)
			(arc
				(start 164.78631 -249.098054)
				(mid 164.794144 -249.14143)
				(end 164.796724 -249.18543)
			)
			(arc
				(start 164.796724 -249.18543)
				(mid 164.794121 -249.229428)
				(end 164.78631 -249.272806)
			)
			(xy 164.784786 -249.278648) (xy 164.784786 -250.79198)
			(arc
				(start 164.78631 -250.797822)
				(mid 164.794144 -250.841198)
				(end 164.796724 -250.885198)
			)
			(arc
				(start 164.796724 -250.885198)
				(mid 164.794121 -250.929196)
				(end 164.78631 -250.972574)
			)
			(xy 164.784786 -250.978416) (xy 164.784786 -252.492002)
			(arc
				(start 164.78631 -252.497844)
				(mid 164.794144 -252.54122)
				(end 164.796724 -252.58522)
			)
			(arc
				(start 164.796724 -252.58522)
				(mid 164.794121 -252.629218)
				(end 164.78631 -252.672596)
			)
			(xy 164.784786 -252.678438) (xy 164.784786 -255.042162)
			(arc
				(start 164.78631 -255.048004)
				(mid 164.794144 -255.09138)
				(end 164.796724 -255.13538)
			)
			(arc
				(start 164.796724 -255.13538)
				(mid 164.794121 -255.179378)
				(end 164.78631 -255.222756)
			)
			(xy 164.784786 -255.228598) (xy 164.784786 -262.692134)
			(arc
				(start 164.78631 -262.697976)
				(mid 164.794144 -262.741352)
				(end 164.796724 -262.785352)
			)
			(arc
				(start 164.796724 -262.785352)
				(mid 164.794121 -262.82935)
				(end 164.78631 -262.872728)
			)
			(xy 164.784786 -262.87857) (xy 164.784786 -264.392156)
			(arc
				(start 164.78631 -264.397998)
				(mid 164.794144 -264.441374)
				(end 164.796724 -264.485374)
			)
			(arc
				(start 164.796724 -264.485374)
				(mid 164.794121 -264.529372)
				(end 164.78631 -264.57275)
			)
			(xy 164.784786 -264.578592) (xy 164.784786 -266.092178)
			(arc
				(start 164.78631 -266.09802)
				(mid 164.794144 -266.141396)
				(end 164.796724 -266.185396)
			)
			(arc
				(start 164.796724 -266.185396)
				(mid 164.795076 -266.220477)
				(end 164.79012 -266.255246)
			)
			(xy 164.78758 -266.267692) (xy 164.794946 -266.291568)
			(arc
				(start 165.03269 -266.529312)
				(mid 165.049224 -266.540423)
				(end 165.068758 -266.544298)
			)
			(arc
				(start 191.409066 -266.544298)
				(mid 191.506253 -266.563648)
				(end 191.588644 -266.61872)
			)
			(arc
				(start 196.473572 -271.503648)
				(mid 196.528678 -271.586025)
				(end 196.547994 -271.683226)
			)
			(arc
				(start 196.547994 -321.89039)
				(mid 196.528644 -321.987577)
				(end 196.473572 -322.069968)
			)
			(arc
				(start 194.912488 -323.631052)
				(mid 194.901377 -323.647586)
				(end 194.897502 -323.66712)
			)
			(arc
				(start 194.897502 -325.064374)
				(mid 194.901403 -325.083897)
				(end 194.912488 -325.100442)
			)
			(arc
				(start 196.38772 -326.575674)
				(mid 196.404254 -326.586785)
				(end 196.423788 -326.59066)
			)
		)
		(stroke
			(width 0)
			(type solid)
		)
		(fill yes)
		(layer "In8.Cu")
		(net "GND")
	)
	(gr_poly
		(pts
			(arc
				(start 270.790162 -335.233518)
				(mid 270.826083 -335.218639)
				(end 270.840962 -335.182718)
			)
			(arc
				(start 270.840962 -244.368828)
				(mid 270.836564 -244.348152)
				(end 270.824198 -244.330982)
			)
			(arc
				(start 270.824198 -244.330982)
				(mid 270.74315 -244.219724)
				(end 270.71447 -244.08511)
			)
			(arc
				(start 270.71447 -244.08511)
				(mid 270.743209 -243.950522)
				(end 270.824198 -243.839238)
			)
			(arc
				(start 270.824198 -243.839238)
				(mid 270.836655 -243.822109)
				(end 270.840962 -243.801392)
			)
			(arc
				(start 270.840962 -227.143818)
				(mid 270.885666 -226.999983)
				(end 271.00403 -226.906836)
			)
			(arc
				(start 271.00403 -226.906836)
				(mid 271.021922 -226.895264)
				(end 271.033494 -226.877372)
			)
			(arc
				(start 271.033494 -226.877372)
				(mid 271.126645 -226.759015)
				(end 271.270476 -226.714304)
			)
			(arc
				(start 311.935622 -226.714304)
				(mid 311.955145 -226.710403)
				(end 311.97169 -226.699318)
			)
			(arc
				(start 312.322972 -226.348036)
				(mid 312.334083 -226.331502)
				(end 312.337958 -226.311968)
			)
			(arc
				(start 312.337958 -194.378326)
				(mid 312.334057 -194.358803)
				(end 312.322972 -194.342258)
			)
			(arc
				(start 312.201052 -194.220338)
				(mid 312.184518 -194.209227)
				(end 312.164984 -194.205352)
			)
			(arc
				(start 308.78145 -194.205352)
				(mid 308.764019 -194.208436)
				(end 308.748684 -194.21729)
			)
			(arc
				(start 308.748684 -194.21729)
				(mid 308.511194 -194.303925)
				(end 308.273704 -194.21729)
			)
			(arc
				(start 308.273704 -194.21729)
				(mid 308.25838 -194.208406)
				(end 308.240938 -194.205352)
			)
			(arc
				(start 306.541932 -194.205352)
				(mid 306.519783 -194.210435)
				(end 306.502054 -194.224656)
			)
			(arc
				(start 306.502054 -194.224656)
				(mid 306.212494 -194.365074)
				(end 305.922934 -194.224656)
			)
			(arc
				(start 305.922934 -194.224656)
				(mid 305.905212 -194.21042)
				(end 305.883056 -194.205352)
			)
			(arc
				(start 304.753264 -194.205352)
				(mid 304.731115 -194.210435)
				(end 304.713386 -194.224656)
			)
			(arc
				(start 304.713386 -194.224656)
				(mid 304.423826 -194.365074)
				(end 304.134266 -194.224656)
			)
			(arc
				(start 304.134266 -194.224656)
				(mid 304.116544 -194.21042)
				(end 304.094388 -194.205352)
			)
			(arc
				(start 302.382682 -194.205352)
				(mid 302.365251 -194.208436)
				(end 302.349916 -194.21729)
			)
			(arc
				(start 302.349916 -194.21729)
				(mid 302.112426 -194.303925)
				(end 301.874936 -194.21729)
			)
			(arc
				(start 301.874936 -194.21729)
				(mid 301.859612 -194.208406)
				(end 301.84217 -194.205352)
			)
			(arc
				(start 301.237396 -194.205352)
				(mid 301.219965 -194.208436)
				(end 301.20463 -194.21729)
			)
			(arc
				(start 301.20463 -194.21729)
				(mid 300.96714 -194.303925)
				(end 300.72965 -194.21729)
			)
			(arc
				(start 300.72965 -194.21729)
				(mid 300.714326 -194.208406)
				(end 300.696884 -194.205352)
			)
			(arc
				(start 298.997878 -194.205352)
				(mid 298.975729 -194.210435)
				(end 298.958 -194.224656)
			)
			(arc
				(start 298.958 -194.224656)
				(mid 298.66844 -194.365074)
				(end 298.37888 -194.224656)
			)
			(arc
				(start 298.37888 -194.224656)
				(mid 298.361158 -194.21042)
				(end 298.339002 -194.205352)
			)
			(arc
				(start 297.20921 -194.205352)
				(mid 297.187061 -194.210435)
				(end 297.169332 -194.224656)
			)
			(arc
				(start 297.169332 -194.224656)
				(mid 296.879772 -194.365074)
				(end 296.590212 -194.224656)
			)
			(arc
				(start 296.590212 -194.224656)
				(mid 296.57249 -194.21042)
				(end 296.550334 -194.205352)
			)
			(arc
				(start 294.838628 -194.205352)
				(mid 294.821197 -194.208436)
				(end 294.805862 -194.21729)
			)
			(arc
				(start 294.805862 -194.21729)
				(mid 294.568372 -194.303925)
				(end 294.330882 -194.21729)
			)
			(arc
				(start 294.330882 -194.21729)
				(mid 294.315558 -194.208406)
				(end 294.298116 -194.205352)
			)
			(arc
				(start 293.693342 -194.205352)
				(mid 293.675911 -194.208436)
				(end 293.660576 -194.21729)
			)
			(arc
				(start 293.660576 -194.21729)
				(mid 293.423086 -194.303925)
				(end 293.185596 -194.21729)
			)
			(arc
				(start 293.185596 -194.21729)
				(mid 293.170272 -194.208406)
				(end 293.15283 -194.205352)
			)
			(arc
				(start 291.454078 -194.205352)
				(mid 291.431929 -194.210435)
				(end 291.4142 -194.224656)
			)
			(arc
				(start 291.4142 -194.224656)
				(mid 291.12464 -194.365074)
				(end 290.83508 -194.224656)
			)
			(arc
				(start 290.83508 -194.224656)
				(mid 290.817358 -194.21042)
				(end 290.795202 -194.205352)
			)
			(arc
				(start 289.665156 -194.205352)
				(mid 289.643007 -194.210435)
				(end 289.625278 -194.224656)
			)
			(arc
				(start 289.625278 -194.224656)
				(mid 289.335718 -194.365074)
				(end 289.046158 -194.224656)
			)
			(arc
				(start 289.046158 -194.224656)
				(mid 289.028436 -194.21042)
				(end 289.00628 -194.205352)
			)
			(arc
				(start 287.294574 -194.205352)
				(mid 287.277143 -194.208436)
				(end 287.261808 -194.21729)
			)
			(arc
				(start 287.261808 -194.21729)
				(mid 287.024318 -194.303925)
				(end 286.786828 -194.21729)
			)
			(arc
				(start 286.786828 -194.21729)
				(mid 286.771504 -194.208406)
				(end 286.754062 -194.205352)
			)
			(arc
				(start 286.149288 -194.205352)
				(mid 286.131857 -194.208436)
				(end 286.116522 -194.21729)
			)
			(arc
				(start 286.116522 -194.21729)
				(mid 285.879032 -194.303925)
				(end 285.641542 -194.21729)
			)
			(arc
				(start 285.641542 -194.21729)
				(mid 285.626218 -194.208406)
				(end 285.608776 -194.205352)
			)
			(arc
				(start 283.910024 -194.205352)
				(mid 283.887875 -194.210435)
				(end 283.870146 -194.224656)
			)
			(arc
				(start 283.870146 -194.224656)
				(mid 283.580586 -194.365074)
				(end 283.291026 -194.224656)
			)
			(arc
				(start 283.291026 -194.224656)
				(mid 283.273304 -194.21042)
				(end 283.251148 -194.205352)
			)
			(arc
				(start 282.121102 -194.205352)
				(mid 282.098953 -194.210435)
				(end 282.081224 -194.224656)
			)
			(arc
				(start 282.081224 -194.224656)
				(mid 281.791664 -194.365074)
				(end 281.502104 -194.224656)
			)
			(arc
				(start 281.502104 -194.224656)
				(mid 281.484382 -194.21042)
				(end 281.462226 -194.205352)
			)
			(arc
				(start 279.75052 -194.205352)
				(mid 279.733089 -194.208436)
				(end 279.717754 -194.21729)
			)
			(arc
				(start 279.717754 -194.21729)
				(mid 279.480264 -194.303925)
				(end 279.242774 -194.21729)
			)
			(arc
				(start 279.242774 -194.21729)
				(mid 279.22745 -194.208406)
				(end 279.210008 -194.205352)
			)
			(arc
				(start 278.605488 -194.205352)
				(mid 278.588057 -194.208436)
				(end 278.572722 -194.21729)
			)
			(arc
				(start 278.572722 -194.21729)
				(mid 278.335232 -194.303925)
				(end 278.097742 -194.21729)
			)
			(arc
				(start 278.097742 -194.21729)
				(mid 278.082418 -194.208406)
				(end 278.064976 -194.205352)
			)
			(arc
				(start 276.36597 -194.205352)
				(mid 276.343821 -194.210435)
				(end 276.326092 -194.224656)
			)
			(arc
				(start 276.326092 -194.224656)
				(mid 276.036532 -194.365074)
				(end 275.746972 -194.224656)
			)
			(arc
				(start 275.746972 -194.224656)
				(mid 275.72925 -194.21042)
				(end 275.707094 -194.205352)
			)
			(arc
				(start 274.577302 -194.205352)
				(mid 274.555153 -194.210435)
				(end 274.537424 -194.224656)
			)
			(arc
				(start 274.537424 -194.224656)
				(mid 274.247864 -194.365074)
				(end 273.958304 -194.224656)
			)
			(arc
				(start 273.958304 -194.224656)
				(mid 273.940582 -194.21042)
				(end 273.918426 -194.205352)
			)
			(arc
				(start 272.20672 -194.205352)
				(mid 272.189289 -194.208436)
				(end 272.173954 -194.21729)
			)
			(arc
				(start 272.173954 -194.21729)
				(mid 271.936464 -194.303925)
				(end 271.698974 -194.21729)
			)
			(arc
				(start 271.698974 -194.21729)
				(mid 271.68365 -194.208406)
				(end 271.666208 -194.205352)
			)
			(arc
				(start 271.061434 -194.205352)
				(mid 271.044003 -194.208436)
				(end 271.028668 -194.21729)
			)
			(arc
				(start 271.028668 -194.21729)
				(mid 270.791178 -194.303925)
				(end 270.553688 -194.21729)
			)
			(arc
				(start 270.553688 -194.21729)
				(mid 270.538364 -194.208406)
				(end 270.520922 -194.205352)
			)
			(arc
				(start 268.821916 -194.205352)
				(mid 268.799767 -194.210435)
				(end 268.782038 -194.224656)
			)
			(arc
				(start 268.782038 -194.224656)
				(mid 268.492478 -194.365074)
				(end 268.202918 -194.224656)
			)
			(arc
				(start 268.202918 -194.224656)
				(mid 268.185196 -194.21042)
				(end 268.16304 -194.205352)
			)
			(arc
				(start 267.033248 -194.205352)
				(mid 267.011099 -194.210435)
				(end 266.99337 -194.224656)
			)
			(arc
				(start 266.99337 -194.224656)
				(mid 266.70381 -194.365074)
				(end 266.41425 -194.224656)
			)
			(arc
				(start 266.41425 -194.224656)
				(mid 266.396528 -194.21042)
				(end 266.374372 -194.205352)
			)
			(arc
				(start 264.662666 -194.205352)
				(mid 264.645235 -194.208436)
				(end 264.6299 -194.21729)
			)
			(arc
				(start 264.6299 -194.21729)
				(mid 264.54161 -194.272401)
				(end 264.441432 -194.300602)
			)
			(xy 264.43305 -194.301872) (xy 264.418318 -194.308984)
			(arc
				(start 264.099802 -194.6275)
				(mid 264.088691 -194.644034)
				(end 264.084816 -194.663568)
			)
			(arc
				(start 264.084816 -196.49694)
				(mid 264.089964 -196.519479)
				(end 264.104628 -196.537326)
			)
			(arc
				(start 264.104628 -196.537326)
				(mid 264.253701 -196.83984)
				(end 264.104628 -197.142354)
			)
			(arc
				(start 264.104628 -197.142354)
				(mid 264.090052 -197.160243)
				(end 264.084816 -197.18274)
			)
			(xy 264.084816 -323.566028) (xy 264.107168 -323.593714)
			(arc
				(start 264.124948 -323.597524)
				(mid 264.341407 -323.730748)
				(end 264.426192 -323.970396)
			)
			(arc
				(start 264.426192 -323.970396)
				(mid 264.376683 -324.158346)
				(end 264.241026 -324.297548)
			)
			(xy 264.229342 -324.30466) (xy 264.216388 -324.328028) (xy 264.218166 -324.443344) (xy 264.231882 -324.466458)
			(arc
				(start 264.24382 -324.473316)
				(mid 264.386894 -324.613217)
				(end 264.4394 -324.80631)
			)
			(arc
				(start 264.4394 -324.80631)
				(mid 264.350918 -325.050705)
				(end 264.126472 -325.181722)
			)
			(xy 264.108184 -325.185024) (xy 264.084816 -325.213218)
			(arc
				(start 264.084816 -335.091786)
				(mid 264.088717 -335.111309)
				(end 264.099802 -335.127854)
			)
			(arc
				(start 264.19048 -335.218532)
				(mid 264.207014 -335.229643)
				(end 264.226548 -335.233518)
			)
		)
		(stroke
			(width 0)
			(type solid)
		)
		(fill yes)
		(layer "In8.Cu")
		(net "GND")
	)
	(gr_poly
		(pts
			(arc
				(start 228.921818 -436.47868)
				(mid 228.941341 -436.474779)
				(end 228.957886 -436.463694)
			)
			(arc
				(start 229.664514 -435.757066)
				(mid 229.675625 -435.740532)
				(end 229.6795 -435.720998)
			)
			(arc
				(start 229.6795 -422.180766)
				(mid 229.703653 -422.05925)
				(end 229.772464 -421.95623)
			)
			(arc
				(start 234.67314 -417.055554)
				(mid 234.776172 -416.986773)
				(end 234.897676 -416.96259)
			)
			(arc
				(start 272.037556 -416.96259)
				(mid 272.057079 -416.958689)
				(end 272.073624 -416.947604)
			)
			(arc
				(start 280.035254 -408.985974)
				(mid 280.046365 -408.96944)
				(end 280.05024 -408.949906)
			)
			(arc
				(start 280.05024 -394.963396)
				(mid 280.046339 -394.943873)
				(end 280.035254 -394.927328)
			)
			(xy 280.035 -394.927074) (xy 279.65146 -394.543534)
			(arc
				(start 279.651206 -394.54328)
				(mid 279.634672 -394.532169)
				(end 279.615138 -394.528294)
			)
			(arc
				(start 278.051514 -394.528294)
				(mid 278.036928 -394.530433)
				(end 278.023574 -394.536676)
			)
			(arc
				(start 278.023574 -394.536676)
				(mid 277.823537 -394.629726)
				(end 277.605236 -394.661644)
			)
			(arc
				(start 277.605236 -394.661644)
				(mid 277.421236 -394.639047)
				(end 277.248112 -394.572744)
			)
			(arc
				(start 277.248112 -394.572744)
				(mid 277.224236 -394.566797)
				(end 277.20036 -394.572744)
			)
			(arc
				(start 277.20036 -394.572744)
				(mid 277.027244 -394.639078)
				(end 276.843236 -394.661644)
			)
			(arc
				(start 276.843236 -394.661644)
				(mid 276.624932 -394.629737)
				(end 276.424898 -394.536676)
			)
			(arc
				(start 276.424898 -394.536676)
				(mid 276.411542 -394.53044)
				(end 276.396958 -394.528294)
			)
			(arc
				(start 269.04569 -394.528294)
				(mid 269.030398 -394.53065)
				(end 269.01648 -394.537438)
			)
			(arc
				(start 269.01648 -394.537438)
				(mid 268.808203 -394.640414)
				(end 268.578584 -394.675868)
			)
			(arc
				(start 268.578584 -394.675868)
				(mid 268.394584 -394.653271)
				(end 268.22146 -394.586968)
			)
			(arc
				(start 268.22146 -394.586968)
				(mid 268.197584 -394.581021)
				(end 268.173708 -394.586968)
			)
			(arc
				(start 268.173708 -394.586968)
				(mid 268.000592 -394.653302)
				(end 267.816584 -394.675868)
			)
			(arc
				(start 267.816584 -394.675868)
				(mid 267.586971 -394.640395)
				(end 267.378688 -394.537438)
			)
			(arc
				(start 267.378688 -394.537438)
				(mid 267.364793 -394.530577)
				(end 267.349478 -394.528294)
			)
			(arc
				(start 261.01929 -394.528294)
				(mid 261.003998 -394.53065)
				(end 260.99008 -394.537438)
			)
			(arc
				(start 260.99008 -394.537438)
				(mid 260.781803 -394.640414)
				(end 260.552184 -394.675868)
			)
			(arc
				(start 260.552184 -394.675868)
				(mid 260.368184 -394.653271)
				(end 260.19506 -394.586968)
			)
			(arc
				(start 260.19506 -394.586968)
				(mid 260.171184 -394.581021)
				(end 260.147308 -394.586968)
			)
			(arc
				(start 260.147308 -394.586968)
				(mid 259.974192 -394.653302)
				(end 259.790184 -394.675868)
			)
			(arc
				(start 259.790184 -394.675868)
				(mid 259.560571 -394.640395)
				(end 259.352288 -394.537438)
			)
			(arc
				(start 259.352288 -394.537438)
				(mid 259.338393 -394.530577)
				(end 259.323078 -394.528294)
			)
			(arc
				(start 252.99289 -394.528294)
				(mid 252.977598 -394.53065)
				(end 252.96368 -394.537438)
			)
			(arc
				(start 252.96368 -394.537438)
				(mid 252.755403 -394.640414)
				(end 252.525784 -394.675868)
			)
			(arc
				(start 252.525784 -394.675868)
				(mid 252.341784 -394.653271)
				(end 252.16866 -394.586968)
			)
			(arc
				(start 252.16866 -394.586968)
				(mid 252.144784 -394.581021)
				(end 252.120908 -394.586968)
			)
			(arc
				(start 252.120908 -394.586968)
				(mid 251.947792 -394.653302)
				(end 251.763784 -394.675868)
			)
			(arc
				(start 251.763784 -394.675868)
				(mid 251.534171 -394.640395)
				(end 251.325888 -394.537438)
			)
			(arc
				(start 251.325888 -394.537438)
				(mid 251.311993 -394.530577)
				(end 251.296678 -394.528294)
			)
			(arc
				(start 244.9576 -394.528294)
				(mid 244.942576 -394.530567)
				(end 244.928898 -394.537184)
			)
			(arc
				(start 244.928898 -394.537184)
				(mid 244.722849 -394.637373)
				(end 244.496336 -394.671804)
			)
			(arc
				(start 244.496336 -394.671804)
				(mid 244.312336 -394.649207)
				(end 244.139212 -394.582904)
			)
			(arc
				(start 244.139212 -394.582904)
				(mid 244.115336 -394.576957)
				(end 244.09146 -394.582904)
			)
			(arc
				(start 244.09146 -394.582904)
				(mid 243.918344 -394.649238)
				(end 243.734336 -394.671804)
			)
			(arc
				(start 243.734336 -394.671804)
				(mid 243.507823 -394.637371)
				(end 243.301774 -394.537184)
			)
			(arc
				(start 243.301774 -394.537184)
				(mid 243.288095 -394.53057)
				(end 243.273072 -394.528294)
			)
			(arc
				(start 239.250982 -394.528294)
				(mid 239.215061 -394.543173)
				(end 239.200182 -394.579094)
			)
			(arc
				(start 239.200182 -405.390096)
				(mid 239.176029 -405.511612)
				(end 239.107218 -405.614632)
			)
			(arc
				(start 238.94034 -405.78151)
				(mid 238.837308 -405.850291)
				(end 238.715804 -405.874474)
			)
			(arc
				(start 234.522264 -405.874474)
				(mid 234.400748 -405.850321)
				(end 234.297728 -405.78151)
			)
			(arc
				(start 233.595926 -405.079708)
				(mid 233.527145 -404.976676)
				(end 233.502962 -404.855172)
			)
			(arc
				(start 233.502962 -404.072344)
				(mid 233.499061 -404.052821)
				(end 233.487976 -404.036276)
			)
			(arc
				(start 233.3498 -403.8981)
				(mid 233.281019 -403.795068)
				(end 233.256836 -403.673564)
			)
			(arc
				(start 233.256836 -400.256502)
				(mid 233.252935 -400.236979)
				(end 233.24185 -400.220434)
			)
			(arc
				(start 233.236008 -400.214592)
				(mid 233.219474 -400.203481)
				(end 233.19994 -400.199606)
			)
			(arc
				(start 229.898956 -400.199606)
				(mid 229.879433 -400.203507)
				(end 229.862888 -400.214592)
			)
			(arc
				(start 229.848664 -400.228816)
				(mid 229.837553 -400.24535)
				(end 229.833678 -400.264884)
			)
			(arc
				(start 229.833678 -403.583648)
				(mid 229.809525 -403.705164)
				(end 229.740714 -403.808184)
			)
			(arc
				(start 229.66426 -403.884638)
				(mid 229.653149 -403.901172)
				(end 229.649274 -403.920706)
			)
			(arc
				(start 229.649274 -406.19299)
				(mid 229.625121 -406.314506)
				(end 229.55631 -406.417526)
			)
			(arc
				(start 227.443284 -408.530552)
				(mid 227.340252 -408.599333)
				(end 227.218748 -408.623516)
			)
			(arc
				(start 225.642424 -408.623516)
				(mid 225.623565 -408.627146)
				(end 225.607372 -408.637486)
			)
			(arc
				(start 225.607372 -408.637486)
				(mid 225.364908 -408.792887)
				(end 225.0821 -408.84729)
			)
			(arc
				(start 225.0821 -408.84729)
				(mid 224.549885 -408.630828)
				(end 224.319846 -408.10434)
			)
			(xy 224.319592 -408.094434) (xy 224.311972 -408.076654)
			(arc
				(start 222.874586 -406.639268)
				(mid 222.805805 -406.536236)
				(end 222.781622 -406.414732)
			)
			(arc
				(start 222.781622 -403.953472)
				(mid 222.777721 -403.933949)
				(end 222.766636 -403.917404)
			)
			(arc
				(start 222.681546 -403.832314)
				(mid 222.612765 -403.729282)
				(end 222.588582 -403.607778)
			)
			(xy 222.588582 -400.229832) (xy 222.580962 -400.21129) (xy 222.57766 -400.207988)
			(arc
				(start 219.197936 -400.207988)
				(mid 219.178413 -400.211889)
				(end 219.161868 -400.222974)
			)
			(xy 219.157296 -400.227546)
			(arc
				(start 219.157296 -403.583394)
				(mid 219.133143 -403.70491)
				(end 219.064332 -403.80793)
			)
			(arc
				(start 219.00007 -403.872192)
				(mid 218.988959 -403.888726)
				(end 218.985084 -403.90826)
			)
			(arc
				(start 218.985084 -406.217374)
				(mid 218.960931 -406.33889)
				(end 218.89212 -406.44191)
			)
			(arc
				(start 216.76614 -408.56789)
				(mid 216.663108 -408.636671)
				(end 216.541604 -408.660854)
			)
			(arc
				(start 214.93226 -408.660854)
				(mid 214.915131 -408.66392)
				(end 214.900002 -408.672538)
			)
			(arc
				(start 214.900002 -408.672538)
				(mid 214.672289 -408.802264)
				(end 214.4141 -408.84729)
			)
			(arc
				(start 214.4141 -408.84729)
				(mid 213.886272 -408.635069)
				(end 213.652354 -408.116532)
			)
			(xy 213.651846 -408.10688) (xy 213.644226 -408.089608)
			(arc
				(start 212.189822 -406.635204)
				(mid 212.121041 -406.532172)
				(end 212.096858 -406.410668)
			)
			(arc
				(start 212.096858 -403.916642)
				(mid 212.092957 -403.897119)
				(end 212.081872 -403.880574)
			)
			(arc
				(start 212.058504 -403.857206)
				(mid 211.989723 -403.754174)
				(end 211.96554 -403.63267)
			)
			(arc
				(start 211.96554 -400.29765)
				(mid 211.961639 -400.278127)
				(end 211.950554 -400.261582)
			)
			(arc
				(start 211.854542 -400.16557)
				(mid 211.838008 -400.154459)
				(end 211.818474 -400.150584)
			)
			(arc
				(start 208.578704 -400.150584)
				(mid 208.559181 -400.154485)
				(end 208.542636 -400.16557)
			)
			(arc
				(start 208.512156 -400.19605)
				(mid 208.501045 -400.212584)
				(end 208.49717 -400.232118)
			)
			(arc
				(start 208.49717 -403.534118)
				(mid 208.473017 -403.655634)
				(end 208.404206 -403.758654)
			)
			(arc
				(start 208.323688 -403.839172)
				(mid 208.312577 -403.855706)
				(end 208.308702 -403.87524)
			)
			(arc
				(start 208.308702 -406.275032)
				(mid 208.284549 -406.396548)
				(end 208.215738 -406.499568)
			)
			(arc
				(start 206.172562 -408.542744)
				(mid 206.06953 -408.611525)
				(end 205.948026 -408.635708)
			)
			(arc
				(start 204.293216 -408.635708)
				(mid 204.274946 -408.639107)
				(end 204.25918 -408.648916)
			)
			(arc
				(start 204.25918 -408.648916)
				(mid 204.021144 -408.79596)
				(end 203.7461 -408.84729)
			)
			(arc
				(start 203.7461 -408.84729)
				(mid 203.306844 -408.708001)
				(end 203.028042 -408.341068)
			)
			(xy 203.023978 -408.330146)
			(arc
				(start 201.5871 -406.893268)
				(mid 201.518319 -406.790236)
				(end 201.494136 -406.668732)
			)
			(arc
				(start 201.494136 -403.941026)
				(mid 201.490235 -403.921503)
				(end 201.47915 -403.904958)
			)
			(arc
				(start 201.373994 -403.799802)
				(mid 201.305213 -403.69677)
				(end 201.28103 -403.575266)
			)
			(arc
				(start 201.28103 -400.264884)
				(mid 201.277129 -400.245361)
				(end 201.266044 -400.228816)
			)
			(arc
				(start 201.221594 -400.184366)
				(mid 201.20506 -400.173255)
				(end 201.185526 -400.16938)
			)
			(arc
				(start 197.9168 -400.16938)
				(mid 197.897277 -400.173281)
				(end 197.880732 -400.184366)
			)
			(arc
				(start 197.844156 -400.220942)
				(mid 197.833045 -400.237476)
				(end 197.82917 -400.25701)
			)
			(arc
				(start 197.82917 -403.58314)
				(mid 197.805017 -403.704656)
				(end 197.736206 -403.807676)
			)
			(arc
				(start 195.6435 -405.900382)
				(mid 195.540468 -405.969163)
				(end 195.418964 -405.993346)
			)
			(arc
				(start 191.073786 -405.993346)
				(mid 190.95227 -405.969193)
				(end 190.84925 -405.900382)
			)
			(arc
				(start 188.07938 -403.130512)
				(mid 188.010599 -403.02748)
				(end 187.986416 -402.905976)
			)
			(arc
				(start 187.986416 -400.258534)
				(mid 187.971537 -400.222613)
				(end 187.935616 -400.207734)
			)
			(arc
				(start 184.616598 -400.207734)
				(mid 184.597075 -400.211635)
				(end 184.58053 -400.22272)
			)
			(xy 184.575958 -400.227292) (xy 184.575958 -405.83104) (xy 184.598818 -405.85898)
			(arc
				(start 184.617106 -405.862536)
				(mid 184.925224 -406.236932)
				(end 184.617106 -406.611328)
			)
			(xy 184.598818 -406.614884) (xy 184.575958 -406.642824)
			(arc
				(start 184.575958 -410.555694)
				(mid 184.579859 -410.575217)
				(end 184.590944 -410.591762)
			)
			(arc
				(start 184.926986 -410.927804)
				(mid 184.94352 -410.938915)
				(end 184.963054 -410.94279)
			)
			(arc
				(start 187.965334 -410.94279)
				(mid 188.08685 -410.966943)
				(end 188.18987 -411.035754)
			)
			(arc
				(start 188.836808 -411.682692)
				(mid 188.853342 -411.693803)
				(end 188.872876 -411.697678)
			)
			(arc
				(start 195.270882 -411.697678)
				(mid 195.392398 -411.721831)
				(end 195.495418 -411.790642)
			)
			(arc
				(start 196.65696 -412.952184)
				(mid 196.725741 -413.055216)
				(end 196.749924 -413.17672)
			)
			(arc
				(start 196.749924 -421.558466)
				(mid 196.753825 -421.577989)
				(end 196.76491 -421.594534)
			)
			(arc
				(start 205.961996 -430.79162)
				(mid 206.030777 -430.894652)
				(end 206.05496 -431.016156)
			)
			(arc
				(start 206.05496 -435.078378)
				(mid 206.058861 -435.097901)
				(end 206.069946 -435.114446)
			)
			(arc
				(start 207.419194 -436.463694)
				(mid 207.435728 -436.474805)
				(end 207.455262 -436.47868)
			)
		)
		(stroke
			(width 0)
			(type solid)
		)
		(fill yes)
		(layer "In8.Cu")
		(net "P12V_PSU")
	)
	(gr_poly
		(pts
			(xy 380.355094 -396.399004) (xy 380.365165 -396.398582) (xy 380.383771 -396.39087) (xy 380.391162 -396.384018)
			(xy 381.94488 -394.8303) (xy 381.95885 -394.817346) (xy 381.968248 -394.809218) (xy 381.977392 -394.786358)
			(xy 381.96647 -394.678662) (xy 381.953008 -394.657834) (xy 381.942086 -394.651738) (xy 381.923282 -394.640765)
			(xy 381.888705 -394.614311) (xy 381.858242 -394.583209) (xy 381.83251 -394.548091) (xy 381.821944 -394.529056)
			(xy 381.821436 -394.528294) (xy 381.423672 -393.839954) (xy 381.411735 -393.817294) (xy 381.394778 -393.76897)
			(xy 381.386128 -393.718493) (xy 381.385572 -393.692888) (xy 381.385572 -393.69238) (xy 381.386021 -393.668375)
			(xy 381.393538 -393.620956) (xy 381.408383 -393.575298) (xy 381.430191 -393.532526) (xy 381.458425 -393.493694)
			(xy 381.492388 -393.45976) (xy 381.531243 -393.431559) (xy 381.574033 -393.409786) (xy 381.619703 -393.394978)
			(xy 381.667128 -393.387501) (xy 381.691134 -393.387072) (xy 381.715067 -393.387539) (xy 381.762348 -393.395007)
			(xy 381.807886 -393.409754) (xy 381.850568 -393.43142) (xy 381.889351 -393.459475) (xy 381.923286 -393.493233)
			(xy 381.951544 -393.531869) (xy 381.962914 -393.552934) (xy 381.963422 -393.55395) (xy 382.043728 -393.692888)
			(xy 382.585976 -393.692888) (xy 382.585976 -393.69238) (xy 382.586444 -393.668389) (xy 382.593953 -393.620998)
			(xy 382.608782 -393.575365) (xy 382.630567 -393.532614) (xy 382.65877 -393.493796) (xy 382.692699 -393.459868)
			(xy 382.731517 -393.431664) (xy 382.774269 -393.40988) (xy 382.819902 -393.395052) (xy 382.867293 -393.387544)
			(xy 382.891284 -393.387072) (xy 382.91522 -393.387511) (xy 382.962506 -393.394974) (xy 383.008049 -393.40972)
			(xy 383.050736 -393.431388) (xy 383.089521 -393.459448) (xy 383.123456 -393.493214) (xy 383.15171 -393.531858)
			(xy 383.163064 -393.552934) (xy 383.163572 -393.55395) (xy 383.243878 -393.692888) (xy 383.785872 -393.692888)
			(xy 383.785872 -393.69238) (xy 383.786344 -393.668389) (xy 383.793853 -393.620999) (xy 383.808681 -393.575366)
			(xy 383.830466 -393.532615) (xy 383.858669 -393.493797) (xy 383.892597 -393.459869) (xy 383.931415 -393.431666)
			(xy 383.974166 -393.409881) (xy 384.019799 -393.395053) (xy 384.067189 -393.387544) (xy 384.09118 -393.387072)
			(xy 384.115116 -393.387515) (xy 384.162401 -393.394977) (xy 384.207945 -393.409722) (xy 384.250631 -393.43139)
			(xy 384.289417 -393.459449) (xy 384.323352 -393.493214) (xy 384.351606 -393.531858) (xy 384.36296 -393.552934)
			(xy 384.363468 -393.55395) (xy 384.443774 -393.692888) (xy 384.985768 -393.692888) (xy 384.985768 -393.69238)
			(xy 384.986244 -393.668389) (xy 384.993752 -393.620999) (xy 385.008581 -393.575367) (xy 385.030365 -393.532616)
			(xy 385.058568 -393.493799) (xy 385.092496 -393.459871) (xy 385.131313 -393.431667) (xy 385.174063 -393.409883)
			(xy 385.219695 -393.395053) (xy 385.267085 -393.387544) (xy 385.291076 -393.387072) (xy 385.315011 -393.387518)
			(xy 385.362297 -393.39498) (xy 385.40784 -393.409724) (xy 385.450527 -393.431391) (xy 385.489312 -393.45945)
			(xy 385.523247 -393.493215) (xy 385.551501 -393.531858) (xy 385.562856 -393.552934) (xy 385.563364 -393.55395)
			(xy 385.64367 -393.692888) (xy 386.185664 -393.692888) (xy 386.185664 -393.69238) (xy 386.186121 -393.668375)
			(xy 386.193637 -393.620957) (xy 386.208482 -393.5753) (xy 386.23029 -393.532528) (xy 386.258522 -393.493697)
			(xy 386.292484 -393.459762) (xy 386.331339 -393.431561) (xy 386.374127 -393.409788) (xy 386.419797 -393.39498)
			(xy 386.467221 -393.387501) (xy 386.491226 -393.387072) (xy 386.51516 -393.387558) (xy 386.562444 -393.395013)
			(xy 386.607986 -393.40975) (xy 386.650673 -393.43141) (xy 386.689459 -393.459463) (xy 386.723395 -393.493222)
			(xy 386.751651 -393.53186) (xy 386.763006 -393.552934) (xy 386.763514 -393.55395) (xy 386.84382 -393.692888)
			(xy 387.38556 -393.692888) (xy 387.38556 -393.69238) (xy 387.386021 -393.668375) (xy 387.393537 -393.620958)
			(xy 387.408382 -393.575301) (xy 387.430189 -393.53253) (xy 387.458421 -393.493698) (xy 387.492383 -393.459764)
			(xy 387.531236 -393.431563) (xy 387.574025 -393.409789) (xy 387.619693 -393.394981) (xy 387.667117 -393.387502)
			(xy 387.691122 -393.387072) (xy 387.715056 -393.387562) (xy 387.762339 -393.395015) (xy 387.807882 -393.409752)
			(xy 387.850568 -393.431412) (xy 387.889354 -393.459464) (xy 387.923291 -393.493222) (xy 387.951547 -393.531861)
			(xy 387.962902 -393.552934) (xy 387.96341 -393.55395) (xy 388.043716 -393.692888) (xy 388.585964 -393.692888)
			(xy 388.585964 -393.69238) (xy 388.586444 -393.66839) (xy 388.593952 -393.621) (xy 388.608781 -393.575368)
			(xy 388.630564 -393.532617) (xy 388.658767 -393.4938) (xy 388.692694 -393.459872) (xy 388.73151 -393.431668)
			(xy 388.774261 -393.409884) (xy 388.819892 -393.395054) (xy 388.867282 -393.387545) (xy 388.891272 -393.387072)
			(xy 388.915207 -393.387521) (xy 388.962493 -393.394982) (xy 389.008036 -393.409727) (xy 389.050723 -393.431393)
			(xy 389.089508 -393.459451) (xy 389.123443 -393.493215) (xy 389.151697 -393.531858) (xy 389.163052 -393.552934)
			(xy 389.16356 -393.55395) (xy 389.55599 -394.232892) (xy 389.568819 -394.256222) (xy 389.587037 -394.306246)
			(xy 389.596295 -394.358673) (xy 389.596884 -394.385292) (xy 389.596453 -394.409299) (xy 389.588939 -394.456721)
			(xy 389.574095 -394.502382) (xy 389.552286 -394.545157) (xy 389.524051 -394.583991) (xy 389.490085 -394.617927)
			(xy 389.451226 -394.646128) (xy 389.408432 -394.667898) (xy 389.362758 -394.682702) (xy 389.315329 -394.690175)
			(xy 389.291322 -394.6906) (xy 389.267749 -394.690188) (xy 389.221161 -394.68295) (xy 389.176243 -394.668628)
			(xy 389.134065 -394.647562) (xy 389.095631 -394.620255) (xy 389.061859 -394.587358) (xy 389.033553 -394.549655)
			(xy 389.022082 -394.529056) (xy 389.021574 -394.528294) (xy 388.62381 -393.839954) (xy 388.611948 -393.81727)
			(xy 388.595093 -393.76894) (xy 388.586513 -393.71848) (xy 388.585964 -393.692888) (xy 388.043716 -393.692888)
			(xy 388.35584 -394.232892) (xy 388.368594 -394.256247) (xy 388.386701 -394.30628) (xy 388.395902 -394.358688)
			(xy 388.39648 -394.385292) (xy 388.396054 -394.409286) (xy 388.388548 -394.456684) (xy 388.373719 -394.502324)
			(xy 388.351932 -394.545082) (xy 388.323724 -394.583905) (xy 388.28979 -394.617837) (xy 388.250965 -394.646042)
			(xy 388.208206 -394.667826) (xy 388.162565 -394.682653) (xy 388.115166 -394.690156) (xy 388.091172 -394.6906)
			(xy 388.067597 -394.690229) (xy 388.021008 -394.682983) (xy 387.976089 -394.668653) (xy 387.93391 -394.647581)
			(xy 387.895478 -394.620268) (xy 387.861707 -394.587365) (xy 387.833402 -394.549657) (xy 387.821932 -394.529056)
			(xy 387.821424 -394.528294) (xy 387.42366 -393.839954) (xy 387.41173 -393.817293) (xy 387.394797 -393.768964)
			(xy 387.386143 -393.718491) (xy 387.38556 -393.692888) (xy 386.84382 -393.692888) (xy 387.155944 -394.232892)
			(xy 387.168698 -394.256247) (xy 387.186805 -394.30628) (xy 387.196006 -394.358688) (xy 387.196584 -394.385292)
			(xy 387.196154 -394.409286) (xy 387.188648 -394.456684) (xy 387.173819 -394.502323) (xy 387.152033 -394.545081)
			(xy 387.123825 -394.583904) (xy 387.089892 -394.617836) (xy 387.051067 -394.646041) (xy 387.008308 -394.667825)
			(xy 386.962668 -394.682652) (xy 386.91527 -394.690156) (xy 386.891276 -394.6906) (xy 386.867701 -394.690226)
			(xy 386.821112 -394.68298) (xy 386.776193 -394.668651) (xy 386.734015 -394.647579) (xy 386.695582 -394.620267)
			(xy 386.661811 -394.587365) (xy 386.633506 -394.549657) (xy 386.622036 -394.529056) (xy 386.621528 -394.528294)
			(xy 386.223764 -393.839954) (xy 386.211835 -393.817292) (xy 386.194901 -393.768964) (xy 386.186248 -393.718491)
			(xy 386.185664 -393.692888) (xy 385.64367 -393.692888) (xy 385.955794 -394.232892) (xy 385.968623 -394.256222)
			(xy 385.986841 -394.306246) (xy 385.996099 -394.358673) (xy 385.996688 -394.385292) (xy 385.996253 -394.409299)
			(xy 385.988739 -394.45672) (xy 385.973895 -394.502381) (xy 385.952087 -394.545156) (xy 385.923852 -394.58399)
			(xy 385.889887 -394.617925) (xy 385.851029 -394.646126) (xy 385.808235 -394.667897) (xy 385.762561 -394.682702)
			(xy 385.715133 -394.690174) (xy 385.691126 -394.6906) (xy 385.667553 -394.690185) (xy 385.620965 -394.682948)
			(xy 385.576047 -394.668626) (xy 385.533869 -394.64756) (xy 385.495436 -394.620254) (xy 385.461663 -394.587357)
			(xy 385.433357 -394.549655) (xy 385.421886 -394.529056) (xy 385.421378 -394.528294) (xy 385.023614 -393.839954)
			(xy 385.011752 -393.81727) (xy 384.994897 -393.76894) (xy 384.986317 -393.71848) (xy 384.985768 -393.692888)
			(xy 384.443774 -393.692888) (xy 384.755898 -394.232892) (xy 384.768719 -394.256226) (xy 384.786942 -394.306248)
			(xy 384.796203 -394.358674) (xy 384.796792 -394.385292) (xy 384.796353 -394.409298) (xy 384.78884 -394.45672)
			(xy 384.773996 -394.50238) (xy 384.752188 -394.545155) (xy 384.723953 -394.583988) (xy 384.689989 -394.617924)
			(xy 384.651131 -394.646125) (xy 384.608338 -394.667896) (xy 384.562664 -394.682701) (xy 384.515237 -394.690174)
			(xy 384.49123 -394.6906) (xy 384.467657 -394.690182) (xy 384.42107 -394.682945) (xy 384.376152 -394.668624)
			(xy 384.333973 -394.647559) (xy 384.29554 -394.620253) (xy 384.261768 -394.587357) (xy 384.233461 -394.549654)
			(xy 384.22199 -394.529056) (xy 384.221482 -394.528294) (xy 383.823718 -393.839954) (xy 383.811856 -393.81727)
			(xy 383.795001 -393.76894) (xy 383.786421 -393.71848) (xy 383.785872 -393.692888) (xy 383.243878 -393.692888)
			(xy 383.556002 -394.232892) (xy 383.568824 -394.256226) (xy 383.587046 -394.306248) (xy 383.596307 -394.358674)
			(xy 383.596896 -394.385292) (xy 383.596453 -394.409298) (xy 383.58894 -394.456719) (xy 383.574096 -394.502379)
			(xy 383.552288 -394.545153) (xy 383.524055 -394.583987) (xy 383.49009 -394.617922) (xy 383.451233 -394.646123)
			(xy 383.408441 -394.667895) (xy 383.362768 -394.6827) (xy 383.315341 -394.690174) (xy 383.291334 -394.6906)
			(xy 383.267761 -394.690179) (xy 383.221174 -394.682942) (xy 383.176256 -394.668622) (xy 383.134078 -394.647557)
			(xy 383.095644 -394.620252) (xy 383.061872 -394.587356) (xy 383.033565 -394.549654) (xy 383.022094 -394.529056)
			(xy 383.021586 -394.528294) (xy 382.623822 -393.839954) (xy 382.611961 -393.81727) (xy 382.595105 -393.76894)
			(xy 382.586526 -393.71848) (xy 382.585976 -393.692888) (xy 382.043728 -393.692888) (xy 382.355852 -394.232892)
			(xy 382.368658 -394.256225) (xy 382.386803 -394.306257) (xy 382.395981 -394.358681) (xy 382.396492 -394.385292)
			(xy 382.396492 -394.395706) (xy 382.395984 -394.405866) (xy 382.402842 -394.424408) (xy 382.465326 -394.491972)
			(xy 382.483106 -394.500354) (xy 382.49352 -394.500608) (xy 382.518066 -394.502168) (xy 382.566329 -394.511642)
			(xy 382.612655 -394.52816) (xy 382.656023 -394.551359) (xy 382.695477 -394.580727) (xy 382.730144 -394.615615)
			(xy 382.759261 -394.655253) (xy 382.782184 -394.698768) (xy 382.7907 -394.721842) (xy 382.796034 -394.737082)
			(xy 382.82245 -394.755878) (xy 382.94056 -394.755878) (xy 382.965514 -394.756495) (xy 383.014463 -394.766242)
			(xy 383.06057 -394.785349) (xy 383.102064 -394.813083) (xy 383.120138 -394.8303) (xy 383.47015 -395.180312)
			(xy 383.503424 -395.184884) (xy 383.51841 -395.176756) (xy 383.54306 -395.163759) (xy 383.59564 -395.145315)
			(xy 383.65057 -395.135954) (xy 383.67843 -395.135354) (xy 383.704417 -395.135866) (xy 383.75575 -395.144)
			(xy 383.805179 -395.160063) (xy 383.851487 -395.18366) (xy 383.893534 -395.214209) (xy 383.930285 -395.25096)
			(xy 383.960836 -395.293006) (xy 383.984434 -395.339314) (xy 384.000498 -395.388742) (xy 384.008634 -395.440075)
			(xy 384.009138 -395.466062) (xy 384.008542 -395.493923) (xy 383.999172 -395.548851) (xy 383.980741 -395.601436)
			(xy 383.967736 -395.626082) (xy 383.959608 -395.641068) (xy 383.96418 -395.674342) (xy 384.4163 -396.126462)
			(xy 384.423697 -396.133313) (xy 384.442295 -396.141053) (xy 384.452368 -396.141448) (xy 392.429746 -396.141448)
			(xy 392.439811 -396.141015) (xy 392.458399 -396.133283) (xy 392.465814 -396.126462) (xy 392.611102 -395.981174)
			(xy 392.617944 -395.973774) (xy 392.625669 -395.955176) (xy 392.626088 -395.945106) (xy 392.626088 -395.12621)
			(xy 392.626654 -395.102112) (xy 392.635742 -395.05478) (xy 392.653594 -395.010011) (xy 392.67957 -394.969414)
			(xy 392.712737 -394.934444) (xy 392.732006 -394.919962) (xy 392.741424 -394.912298) (xy 392.752415 -394.890685)
			(xy 392.753088 -394.87856) (xy 392.753088 -394.756894) (xy 392.75365 -394.740317) (xy 392.762253 -394.708298)
			(xy 392.778823 -394.679581) (xy 392.790172 -394.667486) (xy 392.915902 -394.54201) (xy 392.92275 -394.534612)
			(xy 392.930488 -394.516014) (xy 392.930888 -394.505942) (xy 392.930888 -393.305284) (xy 392.93026 -393.29315)
			(xy 392.919243 -393.271536) (xy 392.909806 -393.263882) (xy 392.890552 -393.249382) (xy 392.857384 -393.214419)
			(xy 392.83141 -393.173825) (xy 392.813561 -393.12906) (xy 392.80448 -393.08173) (xy 392.803888 -393.057634)
			(xy 392.803888 -392.385042) (xy 392.803454 -392.374977) (xy 392.795723 -392.356389) (xy 392.788902 -392.348974)
			(xy 392.623294 -392.183366) (xy 392.615898 -392.176513) (xy 392.5973 -392.16877) (xy 392.587226 -392.16838)
			(xy 377.946666 -392.16838) (xy 377.936598 -392.168809) (xy 377.918001 -392.17653) (xy 377.910598 -392.183366)
			(xy 377.452636 -392.641328) (xy 377.44579 -392.648726) (xy 377.43806 -392.667325) (xy 377.43765 -392.677396)
			(xy 377.43765 -393.692888) (xy 377.785884 -393.692888) (xy 377.785884 -393.69238) (xy 377.786344 -393.668389)
			(xy 377.793853 -393.620997) (xy 377.808683 -393.575363) (xy 377.830468 -393.532611) (xy 377.858673 -393.493793)
			(xy 377.892602 -393.459865) (xy 377.931421 -393.431662) (xy 377.974174 -393.409878) (xy 378.019809 -393.39505)
			(xy 378.067201 -393.387543) (xy 378.091192 -393.387072) (xy 378.115128 -393.387505) (xy 378.162414 -393.394969)
			(xy 378.207958 -393.409716) (xy 378.250644 -393.431385) (xy 378.28943 -393.459446) (xy 378.323364 -393.493212)
			(xy 378.351618 -393.531857) (xy 378.362972 -393.552934) (xy 378.36348 -393.55395) (xy 378.443786 -393.692888)
			(xy 378.98578 -393.692888) (xy 378.98578 -393.69238) (xy 378.986244 -393.668389) (xy 378.993753 -393.620998)
			(xy 379.008582 -393.575364) (xy 379.030367 -393.532612) (xy 379.058571 -393.493795) (xy 379.092501 -393.459866)
			(xy 379.131319 -393.431663) (xy 379.174072 -393.409879) (xy 379.219705 -393.395051) (xy 379.267097 -393.387543)
			(xy 379.291088 -393.387072) (xy 379.315024 -393.387508) (xy 379.36231 -393.394972) (xy 379.407853 -393.409718)
			(xy 379.45054 -393.431387) (xy 379.489325 -393.459447) (xy 379.52326 -393.493213) (xy 379.551514 -393.531858)
			(xy 379.562868 -393.552934) (xy 379.563376 -393.55395) (xy 379.643682 -393.692888) (xy 380.185676 -393.692888)
			(xy 380.185676 -393.69238) (xy 380.186121 -393.668374) (xy 380.193638 -393.620955) (xy 380.208483 -393.575297)
			(xy 380.230292 -393.532525) (xy 380.258526 -393.493693) (xy 380.292489 -393.459758) (xy 380.331345 -393.431557)
			(xy 380.374136 -393.409785) (xy 380.419807 -393.394977) (xy 380.467232 -393.3875) (xy 380.491238 -393.387072)
			(xy 380.515172 -393.387549) (xy 380.562456 -393.395005) (xy 380.607999 -393.409744) (xy 380.650686 -393.431406)
			(xy 380.689472 -393.45946) (xy 380.723407 -393.49322) (xy 380.751663 -393.53186) (xy 380.763018 -393.552934)
			(xy 380.763526 -393.55395) (xy 381.155956 -394.232892) (xy 381.168711 -394.256246) (xy 381.186817 -394.30628)
			(xy 381.196018 -394.358688) (xy 381.196596 -394.385292) (xy 381.196154 -394.409286) (xy 381.188648 -394.456682)
			(xy 381.17382 -394.50232) (xy 381.152035 -394.545077) (xy 381.123829 -394.5839) (xy 381.089897 -394.617831)
			(xy 381.051074 -394.646037) (xy 381.008317 -394.667822) (xy 380.962678 -394.682649) (xy 380.915282 -394.690155)
			(xy 380.891288 -394.6906) (xy 380.867714 -394.690216) (xy 380.821125 -394.682973) (xy 380.776206 -394.668645)
			(xy 380.734028 -394.647575) (xy 380.695595 -394.620264) (xy 380.661823 -394.587363) (xy 380.633518 -394.549656)
			(xy 380.622048 -394.529056) (xy 380.62154 -394.528294) (xy 380.223776 -393.839954) (xy 380.21184 -393.817296)
			(xy 380.19491 -393.768965) (xy 380.186259 -393.718492) (xy 380.185676 -393.692888) (xy 379.643682 -393.692888)
			(xy 379.955806 -394.232892) (xy 379.968628 -394.256226) (xy 379.98685 -394.306248) (xy 379.996111 -394.358674)
			(xy 379.9967 -394.385292) (xy 379.996254 -394.409298) (xy 379.98874 -394.456718) (xy 379.973896 -394.502378)
			(xy 379.952089 -394.545152) (xy 379.923856 -394.583985) (xy 379.889892 -394.617921) (xy 379.851035 -394.646122)
			(xy 379.808243 -394.667894) (xy 379.762571 -394.682699) (xy 379.715144 -394.690173) (xy 379.691138 -394.6906)
			(xy 379.667565 -394.690176) (xy 379.620978 -394.68294) (xy 379.57606 -394.66862) (xy 379.533882 -394.647556)
			(xy 379.495448 -394.620251) (xy 379.461676 -394.587356) (xy 379.433369 -394.549654) (xy 379.421898 -394.529056)
			(xy 379.42139 -394.528294) (xy 379.023626 -393.839954) (xy 379.011765 -393.81727) (xy 378.994909 -393.76894)
			(xy 378.98633 -393.71848) (xy 378.98578 -393.692888) (xy 378.443786 -393.692888) (xy 378.75591 -394.232892)
			(xy 378.768732 -394.256226) (xy 378.786954 -394.306248) (xy 378.796215 -394.358673) (xy 378.796804 -394.385292)
			(xy 378.796354 -394.409298) (xy 378.78884 -394.456718) (xy 378.773997 -394.502377) (xy 378.75219 -394.545151)
			(xy 378.723957 -394.583984) (xy 378.689994 -394.61792) (xy 378.651137 -394.646121) (xy 378.608346 -394.667893)
			(xy 378.562674 -394.682698) (xy 378.515248 -394.690173) (xy 378.491242 -394.6906) (xy 378.467669 -394.690172)
			(xy 378.421083 -394.682937) (xy 378.376165 -394.668617) (xy 378.333986 -394.647554) (xy 378.295553 -394.62025)
			(xy 378.26178 -394.587355) (xy 378.233473 -394.549654) (xy 378.222002 -394.529056) (xy 378.221494 -394.528294)
			(xy 377.82373 -393.839954) (xy 377.811869 -393.81727) (xy 377.795013 -393.76894) (xy 377.786434 -393.71848)
			(xy 377.785884 -393.692888) (xy 377.43765 -393.692888) (xy 377.43765 -394.014452) (xy 377.437851 -394.021118)
			(xy 377.441335 -394.033986) (xy 377.444508 -394.039852) (xy 377.556014 -394.232892) (xy 377.568802 -394.256241)
			(xy 377.587003 -394.306264) (xy 377.596296 -394.358678) (xy 377.596908 -394.385292) (xy 377.596401 -394.410382)
			(xy 377.588196 -394.459887) (xy 377.572007 -394.507384) (xy 377.548269 -394.551594) (xy 377.517621 -394.591327)
			(xy 377.480888 -394.625514) (xy 377.460256 -394.6398) (xy 377.450194 -394.647316) (xy 377.438338 -394.669424)
			(xy 377.43765 -394.681964) (xy 377.43765 -396.043912) (xy 377.438077 -396.05398) (xy 377.4458 -396.072577)
			(xy 377.452636 -396.07998) (xy 377.756674 -396.384018) (xy 377.764073 -396.390862) (xy 377.782672 -396.398582)
			(xy 377.792742 -396.399004)
		)
		(stroke
			(width 0)
			(type solid)
		)
		(fill yes)
		(layer "In8.Cu")
		(net "P1V8_CPU0_RT3_1A")
	)
	(gr_poly
		(pts
			(xy 124.330968 -387.96214) (xy 124.341031 -387.961703) (xy 124.359612 -387.953964) (xy 124.367036 -387.947154)
			(xy 125.003814 -387.310376) (xy 125.007878 -387.27507) (xy 124.99848 -387.260084) (xy 124.986448 -387.240227)
			(xy 124.967461 -387.197857) (xy 124.954589 -387.153248) (xy 124.948084 -387.107277) (xy 124.94768 -387.084062)
			(xy 124.948192 -387.058076) (xy 124.956328 -387.006746) (xy 124.972392 -386.95732) (xy 124.995989 -386.911015)
			(xy 125.02654 -386.868971) (xy 125.06329 -386.832223) (xy 125.105337 -386.801676) (xy 125.151644 -386.778082)
			(xy 125.201071 -386.762022) (xy 125.252402 -386.75389) (xy 125.278388 -386.753354) (xy 125.301603 -386.753747)
			(xy 125.347576 -386.760249) (xy 125.392185 -386.773126) (xy 125.434551 -386.792124) (xy 125.45441 -386.804154)
			(xy 125.469396 -386.813552) (xy 125.504702 -386.809488) (xy 125.920754 -386.393436) (xy 125.929371 -386.384995)
			(xy 125.947942 -386.369599) (xy 125.957838 -386.362702) (xy 125.966325 -386.356341) (xy 125.977624 -386.338421)
			(xy 125.980722 -386.317463) (xy 125.97509 -386.297041) (xy 125.961689 -386.280633) (xy 125.952504 -386.275326)
			(xy 125.931995 -386.26437) (xy 125.894268 -386.237196) (xy 125.861103 -386.204609) (xy 125.833269 -386.167366)
			(xy 125.821948 -386.147056) (xy 125.82144 -386.146294) (xy 125.423676 -385.457954) (xy 125.411739 -385.435294)
			(xy 125.394782 -385.38697) (xy 125.386132 -385.336493) (xy 125.385576 -385.310888) (xy 125.385576 -385.31038)
			(xy 125.386025 -385.286375) (xy 125.393542 -385.238956) (xy 125.408387 -385.193299) (xy 125.430196 -385.150527)
			(xy 125.458429 -385.111696) (xy 125.492392 -385.077761) (xy 125.531247 -385.049561) (xy 125.574037 -385.027788)
			(xy 125.619708 -385.012981) (xy 125.667132 -385.005504) (xy 125.691138 -385.005072) (xy 125.715071 -385.00554)
			(xy 125.762351 -385.013008) (xy 125.807889 -385.027755) (xy 125.850571 -385.049421) (xy 125.889353 -385.077476)
			(xy 125.923288 -385.111235) (xy 125.951545 -385.14987) (xy 125.962918 -385.170934) (xy 125.963426 -385.17195)
			(xy 126.043732 -385.310888) (xy 126.58598 -385.310888) (xy 126.58598 -385.31038) (xy 126.586444 -385.286389)
			(xy 126.593953 -385.238998) (xy 126.608782 -385.193364) (xy 126.630567 -385.150612) (xy 126.658771 -385.111795)
			(xy 126.692701 -385.077866) (xy 126.731519 -385.049663) (xy 126.774272 -385.027879) (xy 126.819905 -385.013051)
			(xy 126.867297 -385.005543) (xy 126.891288 -385.005072) (xy 126.915224 -385.005508) (xy 126.96251 -385.012972)
			(xy 127.008053 -385.027718) (xy 127.05074 -385.049387) (xy 127.089525 -385.077447) (xy 127.12346 -385.111213)
			(xy 127.151714 -385.149858) (xy 127.163068 -385.170934) (xy 127.163576 -385.17195) (xy 127.243882 -385.310888)
			(xy 127.785876 -385.310888) (xy 127.785876 -385.31038) (xy 127.786344 -385.286389) (xy 127.793853 -385.238998)
			(xy 127.808682 -385.193365) (xy 127.830467 -385.150614) (xy 127.85867 -385.111796) (xy 127.892599 -385.077868)
			(xy 127.931417 -385.049664) (xy 127.974169 -385.02788) (xy 128.019802 -385.013052) (xy 128.067193 -385.005544)
			(xy 128.091184 -385.005072) (xy 128.11512 -385.005511) (xy 128.162406 -385.012974) (xy 128.207949 -385.02772)
			(xy 128.250636 -385.049388) (xy 128.289421 -385.077448) (xy 128.323356 -385.111214) (xy 128.35161 -385.149858)
			(xy 128.362964 -385.170934) (xy 128.363472 -385.17195) (xy 128.443778 -385.310888) (xy 128.985772 -385.310888)
			(xy 128.985772 -385.31038) (xy 128.986244 -385.286389) (xy 128.993753 -385.238999) (xy 129.008581 -385.193366)
			(xy 129.030366 -385.150615) (xy 129.058569 -385.111797) (xy 129.092497 -385.077869) (xy 129.131315 -385.049666)
			(xy 129.174066 -385.027881) (xy 129.219699 -385.013053) (xy 129.267089 -385.005544) (xy 129.29108 -385.005072)
			(xy 129.315016 -385.005515) (xy 129.362301 -385.012977) (xy 129.407845 -385.027722) (xy 129.450531 -385.04939)
			(xy 129.489317 -385.077449) (xy 129.523252 -385.111214) (xy 129.551506 -385.149858) (xy 129.56286 -385.170934)
			(xy 129.563368 -385.17195) (xy 129.643674 -385.310888) (xy 130.185668 -385.310888) (xy 130.185668 -385.31038)
			(xy 130.186121 -385.286375) (xy 130.193637 -385.238957) (xy 130.208483 -385.193299) (xy 130.230291 -385.150527)
			(xy 130.258524 -385.111696) (xy 130.292486 -385.077761) (xy 130.331341 -385.04956) (xy 130.37413 -385.027787)
			(xy 130.4198 -385.012979) (xy 130.467224 -385.005501) (xy 130.49123 -385.005072) (xy 130.515164 -385.005555)
			(xy 130.562448 -385.01301) (xy 130.60799 -385.027748) (xy 130.650677 -385.049409) (xy 130.689463 -385.077462)
			(xy 130.723399 -385.111221) (xy 130.751655 -385.14986) (xy 130.76301 -385.170934) (xy 130.763518 -385.17195)
			(xy 130.843824 -385.310888) (xy 131.385564 -385.310888) (xy 131.385564 -385.31038) (xy 131.386021 -385.286375)
			(xy 131.393537 -385.238957) (xy 131.408382 -385.1933) (xy 131.43019 -385.150528) (xy 131.458422 -385.111697)
			(xy 131.492384 -385.077762) (xy 131.531239 -385.049561) (xy 131.574027 -385.027788) (xy 131.619697 -385.01298)
			(xy 131.667121 -385.005501) (xy 131.691126 -385.005072) (xy 131.71506 -385.005558) (xy 131.762344 -385.013013)
			(xy 131.807886 -385.02775) (xy 131.850573 -385.04941) (xy 131.889359 -385.077463) (xy 131.923295 -385.111222)
			(xy 131.951551 -385.14986) (xy 131.962906 -385.170934) (xy 131.963414 -385.17195) (xy 132.04372 -385.310888)
			(xy 132.585968 -385.310888) (xy 132.585968 -385.31038) (xy 132.586444 -385.286389) (xy 132.593952 -385.238999)
			(xy 132.608781 -385.193367) (xy 132.630565 -385.150616) (xy 132.658768 -385.111799) (xy 132.692696 -385.077871)
			(xy 132.731513 -385.049667) (xy 132.774263 -385.027883) (xy 132.819895 -385.013053) (xy 132.867285 -385.005544)
			(xy 132.891276 -385.005072) (xy 132.915211 -385.005518) (xy 132.962497 -385.01298) (xy 133.00804 -385.027724)
			(xy 133.050727 -385.049391) (xy 133.089512 -385.07745) (xy 133.123447 -385.111215) (xy 133.151701 -385.149858)
			(xy 133.163056 -385.170934) (xy 133.163564 -385.17195) (xy 133.555994 -385.850892) (xy 133.568823 -385.874222)
			(xy 133.587041 -385.924246) (xy 133.596299 -385.976673) (xy 133.596888 -386.003292) (xy 133.596453 -386.027299)
			(xy 133.588939 -386.07472) (xy 133.574095 -386.120381) (xy 133.552287 -386.163156) (xy 133.524052 -386.20199)
			(xy 133.490087 -386.235925) (xy 133.451229 -386.264126) (xy 133.408435 -386.285897) (xy 133.362761 -386.300702)
			(xy 133.315333 -386.308174) (xy 133.291326 -386.3086) (xy 133.267753 -386.308185) (xy 133.221165 -386.300948)
			(xy 133.176247 -386.286626) (xy 133.134069 -386.26556) (xy 133.095636 -386.238254) (xy 133.061863 -386.205357)
			(xy 133.033557 -386.167655) (xy 133.022086 -386.147056) (xy 133.021578 -386.146294) (xy 132.623814 -385.457954)
			(xy 132.611952 -385.43527) (xy 132.595097 -385.38694) (xy 132.586517 -385.33648) (xy 132.585968 -385.310888)
			(xy 132.04372 -385.310888) (xy 132.355844 -385.850892) (xy 132.368598 -385.874247) (xy 132.386705 -385.92428)
			(xy 132.395906 -385.976688) (xy 132.396484 -386.003292) (xy 132.396054 -386.027286) (xy 132.388548 -386.074684)
			(xy 132.373719 -386.120323) (xy 132.351933 -386.163081) (xy 132.323725 -386.201904) (xy 132.289792 -386.235836)
			(xy 132.250967 -386.264041) (xy 132.208208 -386.285825) (xy 132.162568 -386.300652) (xy 132.11517 -386.308156)
			(xy 132.091176 -386.3086) (xy 132.067601 -386.308226) (xy 132.021012 -386.30098) (xy 131.976093 -386.286651)
			(xy 131.933915 -386.265579) (xy 131.895482 -386.238267) (xy 131.861711 -386.205365) (xy 131.833406 -386.167657)
			(xy 131.821936 -386.147056) (xy 131.821428 -386.146294) (xy 131.423664 -385.457954) (xy 131.411735 -385.435292)
			(xy 131.394801 -385.386964) (xy 131.386148 -385.336491) (xy 131.385564 -385.310888) (xy 130.843824 -385.310888)
			(xy 131.155948 -385.850892) (xy 131.168702 -385.874247) (xy 131.186809 -385.92428) (xy 131.19601 -385.976688)
			(xy 131.196588 -386.003292) (xy 131.196154 -386.027286) (xy 131.188648 -386.074683) (xy 131.17382 -386.120322)
			(xy 131.152033 -386.16308) (xy 131.123826 -386.201902) (xy 131.089893 -386.235834) (xy 131.05107 -386.26404)
			(xy 131.008311 -386.285824) (xy 130.962671 -386.300651) (xy 130.915274 -386.308155) (xy 130.89128 -386.3086)
			(xy 130.867705 -386.308222) (xy 130.821116 -386.300978) (xy 130.776197 -386.286649) (xy 130.734019 -386.265578)
			(xy 130.695586 -386.238266) (xy 130.661815 -386.205364) (xy 130.63351 -386.167657) (xy 130.62204 -386.147056)
			(xy 130.621532 -386.146294) (xy 130.223768 -385.457954) (xy 130.211839 -385.435292) (xy 130.194906 -385.386964)
			(xy 130.186252 -385.336491) (xy 130.185668 -385.310888) (xy 129.643674 -385.310888) (xy 129.955798 -385.850892)
			(xy 129.968619 -385.874226) (xy 129.986842 -385.924248) (xy 129.996103 -385.976674) (xy 129.996692 -386.003292)
			(xy 129.996253 -386.027298) (xy 129.98874 -386.07472) (xy 129.973896 -386.12038) (xy 129.952088 -386.163155)
			(xy 129.923853 -386.201988) (xy 129.889889 -386.235924) (xy 129.851031 -386.264125) (xy 129.808238 -386.285896)
			(xy 129.762564 -386.300701) (xy 129.715137 -386.308174) (xy 129.69113 -386.3086) (xy 129.667557 -386.308182)
			(xy 129.62097 -386.300945) (xy 129.576052 -386.286624) (xy 129.533873 -386.265559) (xy 129.49544 -386.238253)
			(xy 129.461668 -386.205357) (xy 129.433361 -386.167654) (xy 129.42189 -386.147056) (xy 129.421382 -386.146294)
			(xy 129.023618 -385.457954) (xy 129.011756 -385.43527) (xy 128.994901 -385.38694) (xy 128.986321 -385.33648)
			(xy 128.985772 -385.310888) (xy 128.443778 -385.310888) (xy 128.755902 -385.850892) (xy 128.768724 -385.874226)
			(xy 128.786946 -385.924248) (xy 128.796207 -385.976674) (xy 128.796796 -386.003292) (xy 128.796353 -386.027298)
			(xy 128.78884 -386.074719) (xy 128.773996 -386.120379) (xy 128.752188 -386.163153) (xy 128.723955 -386.201987)
			(xy 128.68999 -386.235922) (xy 128.651133 -386.264123) (xy 128.608341 -386.285895) (xy 128.562668 -386.3007)
			(xy 128.515241 -386.308174) (xy 128.491234 -386.3086) (xy 128.467661 -386.308179) (xy 128.421074 -386.300942)
			(xy 128.376156 -386.286622) (xy 128.333978 -386.265557) (xy 128.295544 -386.238252) (xy 128.261772 -386.205356)
			(xy 128.233465 -386.167654) (xy 128.221994 -386.147056) (xy 128.221486 -386.146294) (xy 127.823722 -385.457954)
			(xy 127.811861 -385.43527) (xy 127.795005 -385.38694) (xy 127.786426 -385.33648) (xy 127.785876 -385.310888)
			(xy 127.243882 -385.310888) (xy 127.556006 -385.850892) (xy 127.568828 -385.874226) (xy 127.58705 -385.924248)
			(xy 127.596311 -385.976674) (xy 127.5969 -386.003292) (xy 127.596454 -386.027298) (xy 127.58894 -386.074718)
			(xy 127.574096 -386.120378) (xy 127.552289 -386.163152) (xy 127.524056 -386.201985) (xy 127.490092 -386.235921)
			(xy 127.451235 -386.264122) (xy 127.408443 -386.285894) (xy 127.362771 -386.300699) (xy 127.315344 -386.308173)
			(xy 127.291338 -386.3086) (xy 127.267765 -386.308176) (xy 127.221178 -386.30094) (xy 127.17626 -386.28662)
			(xy 127.134082 -386.265556) (xy 127.095648 -386.238251) (xy 127.061876 -386.205356) (xy 127.033569 -386.167654)
			(xy 127.022098 -386.147056) (xy 127.02159 -386.146294) (xy 126.623826 -385.457954) (xy 126.611965 -385.43527)
			(xy 126.595109 -385.38694) (xy 126.58653 -385.33648) (xy 126.58598 -385.310888) (xy 126.043732 -385.310888)
			(xy 126.355856 -385.850892) (xy 126.368662 -385.874225) (xy 126.386807 -385.924257) (xy 126.395984 -385.976681)
			(xy 126.396496 -386.003292) (xy 126.396496 -386.013706) (xy 126.395988 -386.023866) (xy 126.402846 -386.042408)
			(xy 126.46533 -386.109972) (xy 126.48311 -386.118354) (xy 126.493524 -386.118608) (xy 126.517857 -386.120164)
			(xy 126.565707 -386.129532) (xy 126.611663 -386.145821) (xy 126.654731 -386.168679) (xy 126.693978 -386.197611)
			(xy 126.728554 -386.231989) (xy 126.757709 -386.27107) (xy 126.769622 -386.292344) (xy 126.77648 -386.30479)
			(xy 126.800356 -386.319014) (xy 126.916434 -386.319014) (xy 126.941389 -386.319629) (xy 126.990339 -386.329372)
			(xy 127.036448 -386.348478) (xy 127.077943 -386.376213) (xy 127.096012 -386.393436) (xy 127.489712 -386.787136)
			(xy 127.521208 -386.792724) (xy 127.53594 -386.785612) (xy 127.558303 -386.77544) (xy 127.605283 -386.761074)
			(xy 127.65387 -386.753806) (xy 127.678434 -386.753354) (xy 127.704421 -386.753866) (xy 127.755753 -386.762001)
			(xy 127.805182 -386.778064) (xy 127.851489 -386.801661) (xy 127.893536 -386.832211) (xy 127.930287 -386.868961)
			(xy 127.960837 -386.911007) (xy 127.984434 -386.957315) (xy 128.000498 -387.006743) (xy 128.008634 -387.058075)
			(xy 128.009142 -387.084062) (xy 128.008696 -387.108627) (xy 128.001434 -387.157216) (xy 127.987065 -387.204196)
			(xy 127.976884 -387.226556) (xy 127.969772 -387.241288) (xy 127.97536 -387.272784) (xy 128.392174 -387.689598)
			(xy 128.399577 -387.696433) (xy 128.418175 -387.704141) (xy 128.428242 -387.704584) (xy 136.40562 -387.704584)
			(xy 136.415688 -387.704157) (xy 136.434286 -387.696436) (xy 136.441688 -387.689598) (xy 136.586976 -387.54431)
			(xy 136.593826 -387.536913) (xy 136.601568 -387.518315) (xy 136.601962 -387.508242) (xy 136.601962 -386.689346)
			(xy 136.602534 -386.665252) (xy 136.611634 -386.617929) (xy 136.629498 -386.573173) (xy 136.655483 -386.532591)
			(xy 136.688657 -386.497638) (xy 136.70788 -386.483098) (xy 136.717308 -386.475439) (xy 136.72832 -386.453826)
			(xy 136.728962 -386.441696) (xy 136.728962 -386.32003) (xy 136.729533 -386.303458) (xy 136.738153 -386.271451)
			(xy 136.754739 -386.242753) (xy 136.766046 -386.230622) (xy 136.891776 -386.105146) (xy 136.898616 -386.097746)
			(xy 136.906335 -386.079147) (xy 136.906762 -386.069078) (xy 136.906762 -384.86842) (xy 136.906141 -384.856283)
			(xy 136.895129 -384.83466) (xy 136.88568 -384.827018) (xy 136.866425 -384.812518) (xy 136.833256 -384.777555)
			(xy 136.807278 -384.736962) (xy 136.789426 -384.692196) (xy 136.780339 -384.644867) (xy 136.779762 -384.62077)
			(xy 136.779762 -383.948178) (xy 136.779334 -383.93811) (xy 136.77161 -383.919515) (xy 136.764776 -383.91211)
			(xy 136.599168 -383.746502) (xy 136.591768 -383.73966) (xy 136.57317 -383.731937) (xy 136.5631 -383.731516)
			(xy 121.92254 -383.731516) (xy 121.912475 -383.731951) (xy 121.893888 -383.739682) (xy 121.886472 -383.746502)
			(xy 121.42851 -384.204464) (xy 121.421673 -384.211866) (xy 121.41396 -384.230464) (xy 121.413524 -384.240532)
			(xy 121.413524 -385.310888) (xy 121.785888 -385.310888) (xy 121.785888 -385.31038) (xy 121.786344 -385.286388)
			(xy 121.793853 -385.238996) (xy 121.808683 -385.193362) (xy 121.830469 -385.15061) (xy 121.858674 -385.111792)
			(xy 121.892604 -385.077863) (xy 121.931424 -385.04966) (xy 121.974177 -385.027877) (xy 122.019812 -385.013049)
			(xy 122.067204 -385.005543) (xy 122.091196 -385.005072) (xy 122.115132 -385.005502) (xy 122.162418 -385.012966)
			(xy 122.207962 -385.027714) (xy 122.250649 -385.049384) (xy 122.289434 -385.077445) (xy 122.323368 -385.111212)
			(xy 122.351622 -385.149857) (xy 122.362976 -385.170934) (xy 122.363484 -385.17195) (xy 122.44379 -385.310888)
			(xy 122.985784 -385.310888) (xy 122.985784 -385.31038) (xy 122.986244 -385.286389) (xy 122.993753 -385.238997)
			(xy 123.008583 -385.193363) (xy 123.030368 -385.150611) (xy 123.058573 -385.111793) (xy 123.092502 -385.077865)
			(xy 123.131321 -385.049662) (xy 123.174074 -385.027878) (xy 123.219709 -385.01305) (xy 123.267101 -385.005543)
			(xy 123.291092 -385.005072) (xy 123.315028 -385.005505) (xy 123.362314 -385.012969) (xy 123.407858 -385.027716)
			(xy 123.450544 -385.049385) (xy 123.48933 -385.077446) (xy 123.523264 -385.111212) (xy 123.551518 -385.149857)
			(xy 123.562872 -385.170934) (xy 123.56338 -385.17195) (xy 123.643686 -385.310888) (xy 124.18568 -385.310888)
			(xy 124.18568 -385.31038) (xy 124.186121 -385.286374) (xy 124.193638 -385.238955) (xy 124.208484 -385.193296)
			(xy 124.230293 -385.150524) (xy 124.258527 -385.111692) (xy 124.292491 -385.077757) (xy 124.331347 -385.049556)
			(xy 124.374139 -385.027783) (xy 124.41981 -385.012977) (xy 124.467236 -385.0055) (xy 124.491242 -385.005072)
			(xy 124.515176 -385.005545) (xy 124.562461 -385.013002) (xy 124.608003 -385.027742) (xy 124.65069 -385.049404)
			(xy 124.689476 -385.077459) (xy 124.723412 -385.11122) (xy 124.751667 -385.14986) (xy 124.763022 -385.170934)
			(xy 124.76353 -385.17195) (xy 125.15596 -385.850892) (xy 125.168715 -385.874246) (xy 125.186821 -385.92428)
			(xy 125.196022 -385.976688) (xy 125.1966 -386.003292) (xy 125.196154 -386.027285) (xy 125.188649 -386.074681)
			(xy 125.173821 -386.12032) (xy 125.152036 -386.163076) (xy 125.12383 -386.201898) (xy 125.089898 -386.23583)
			(xy 125.051076 -386.264036) (xy 125.00832 -386.285821) (xy 124.962681 -386.300649) (xy 124.915285 -386.308154)
			(xy 124.891292 -386.3086) (xy 124.867718 -386.308213) (xy 124.821129 -386.30097) (xy 124.77621 -386.286643)
			(xy 124.734032 -386.265573) (xy 124.695599 -386.238263) (xy 124.661828 -386.205362) (xy 124.633522 -386.167656)
			(xy 124.622052 -386.147056) (xy 124.621544 -386.146294) (xy 124.22378 -385.457954) (xy 124.211844 -385.435296)
			(xy 124.194915 -385.386965) (xy 124.186263 -385.336492) (xy 124.18568 -385.310888) (xy 123.643686 -385.310888)
			(xy 123.95581 -385.850892) (xy 123.968632 -385.874226) (xy 123.986854 -385.924248) (xy 123.996115 -385.976673)
			(xy 123.996704 -386.003292) (xy 123.996254 -386.027298) (xy 123.98874 -386.074718) (xy 123.973897 -386.120377)
			(xy 123.95209 -386.163151) (xy 123.923857 -386.201984) (xy 123.889894 -386.23592) (xy 123.851037 -386.264121)
			(xy 123.808246 -386.285893) (xy 123.762574 -386.300698) (xy 123.715148 -386.308173) (xy 123.691142 -386.3086)
			(xy 123.667569 -386.308172) (xy 123.620983 -386.300937) (xy 123.576065 -386.286617) (xy 123.533886 -386.265554)
			(xy 123.495453 -386.23825) (xy 123.46168 -386.205355) (xy 123.433373 -386.167654) (xy 123.421902 -386.147056)
			(xy 123.421394 -386.146294) (xy 123.02363 -385.457954) (xy 123.011769 -385.43527) (xy 122.994913 -385.38694)
			(xy 122.986334 -385.33648) (xy 122.985784 -385.310888) (xy 122.44379 -385.310888) (xy 122.755914 -385.850892)
			(xy 122.768737 -385.874226) (xy 122.786958 -385.924248) (xy 122.796219 -385.976673) (xy 122.796808 -386.003292)
			(xy 122.796354 -386.027298) (xy 122.78884 -386.074717) (xy 122.773997 -386.120377) (xy 122.752191 -386.16315)
			(xy 122.723958 -386.201983) (xy 122.689995 -386.235918) (xy 122.65114 -386.264119) (xy 122.608349 -386.285891)
			(xy 122.562678 -386.300698) (xy 122.515252 -386.308173) (xy 122.491246 -386.3086) (xy 122.467673 -386.308169)
			(xy 122.421087 -386.300935) (xy 122.376169 -386.286615) (xy 122.333991 -386.265553) (xy 122.295557 -386.238249)
			(xy 122.261784 -386.205355) (xy 122.233477 -386.167654) (xy 122.222006 -386.147056) (xy 122.221498 -386.146294)
			(xy 121.823734 -385.457954) (xy 121.811874 -385.43527) (xy 121.795018 -385.38694) (xy 121.786438 -385.33648)
			(xy 121.785888 -385.310888) (xy 121.413524 -385.310888) (xy 121.413524 -385.590542) (xy 121.413723 -385.597208)
			(xy 121.417203 -385.610079) (xy 121.420382 -385.615942) (xy 121.556018 -385.850892) (xy 121.568806 -385.874241)
			(xy 121.587007 -385.924264) (xy 121.5963 -385.976678) (xy 121.596912 -386.003292) (xy 121.596478 -386.026514)
			(xy 121.589443 -386.072421) (xy 121.575534 -386.116733) (xy 121.555072 -386.158425) (xy 121.528529 -386.196537)
			(xy 121.496519 -386.230187) (xy 121.459781 -386.258599) (xy 121.439686 -386.270246) (xy 121.427494 -386.277104)
			(xy 121.413524 -386.300726) (xy 121.413524 -387.607048) (xy 121.413956 -387.617114) (xy 121.421686 -387.635703)
			(xy 121.42851 -387.643116) (xy 121.732548 -387.947154) (xy 121.739947 -387.953998) (xy 121.758546 -387.961722)
			(xy 121.768616 -387.96214)
		)
		(stroke
			(width 0)
			(type solid)
		)
		(fill yes)
		(layer "In8.Cu")
		(net "P1V8_CPU1_RT3_1A")
	)
	(gr_poly
		(pts
			(xy 344.367612 -396.415514) (xy 344.386879 -396.410732) (xy 344.426248 -396.405633) (xy 344.446098 -396.405354)
			(xy 344.465946 -396.405659) (xy 344.505312 -396.410758) (xy 344.524584 -396.415514) (xy 344.530934 -396.417292)
			(xy 345.561158 -396.417292) (xy 345.567508 -396.415514) (xy 345.586775 -396.410732) (xy 345.626144 -396.405632)
			(xy 345.645994 -396.405354) (xy 345.665842 -396.405659) (xy 345.705208 -396.410757) (xy 345.72448 -396.415514)
			(xy 345.73083 -396.417292) (xy 345.928442 -396.417292) (xy 345.938509 -396.416861) (xy 345.957101 -396.409135)
			(xy 345.96451 -396.402306) (xy 347.571822 -394.794994) (xy 347.579188 -394.781278) (xy 347.580458 -394.773404)
			(xy 347.584776 -394.753084) (xy 347.53296 -394.690346) (xy 347.518736 -394.6906) (xy 347.495167 -394.690157)
			(xy 347.448591 -394.6829) (xy 347.403685 -394.668568) (xy 347.361516 -394.647501) (xy 347.323087 -394.620202)
			(xy 347.289313 -394.587319) (xy 347.260997 -394.549634) (xy 347.249496 -394.529056) (xy 347.248988 -394.528294)
			(xy 346.851224 -393.839954) (xy 346.839289 -393.817294) (xy 346.822334 -393.76897) (xy 346.813686 -393.718493)
			(xy 346.813124 -393.692888) (xy 346.813124 -393.69238) (xy 346.813573 -393.668376) (xy 346.82109 -393.62096)
			(xy 346.835936 -393.575306) (xy 346.857745 -393.532538) (xy 346.88598 -393.49371) (xy 346.919943 -393.459781)
			(xy 346.958799 -393.431585) (xy 347.001589 -393.409819) (xy 347.047258 -393.395019) (xy 347.094682 -393.387549)
			(xy 347.118686 -393.387072) (xy 347.142621 -393.387536) (xy 347.189906 -393.394997) (xy 347.23545 -393.409739)
			(xy 347.278138 -393.431401) (xy 347.316927 -393.459455) (xy 347.350868 -393.493212) (xy 347.379131 -393.531849)
			(xy 347.390466 -393.552934) (xy 347.390974 -393.55395) (xy 347.783404 -394.232892) (xy 347.796208 -394.256225)
			(xy 347.81435 -394.306258) (xy 347.823526 -394.358681) (xy 347.824044 -394.385292) (xy 347.824044 -394.395706)
			(xy 347.823536 -394.405866) (xy 347.830394 -394.424408) (xy 347.892878 -394.491972) (xy 347.910658 -394.500354)
			(xy 347.921072 -394.500608) (xy 347.946518 -394.502227) (xy 347.996495 -394.512315) (xy 348.044331 -394.529958)
			(xy 348.08889 -394.554738) (xy 348.129115 -394.586066) (xy 348.164053 -394.6232) (xy 348.192874 -394.665258)
			(xy 348.204282 -394.68806) (xy 348.210632 -394.701268) (xy 348.23527 -394.716762) (xy 348.44482 -394.716762)
			(xy 348.458192 -394.716942) (xy 348.484789 -394.719743) (xy 348.497906 -394.72235) (xy 348.50771 -394.723998)
			(xy 348.527265 -394.720531) (xy 348.544038 -394.709898) (xy 348.555517 -394.693691) (xy 348.559981 -394.674339)
			(xy 348.556762 -394.654742) (xy 348.546342 -394.637835) (xy 348.538546 -394.631672) (xy 348.520364 -394.617854)
			(xy 348.48796 -394.585679) (xy 348.460721 -394.549027) (xy 348.449646 -394.529056) (xy 348.449138 -394.528294)
			(xy 348.051374 -393.839954) (xy 348.039479 -393.817285) (xy 348.022611 -393.768954) (xy 348.014058 -393.718483)
			(xy 348.013528 -393.692888) (xy 348.013528 -393.69238) (xy 348.013976 -393.668389) (xy 348.021485 -393.620998)
			(xy 348.036316 -393.575365) (xy 348.058103 -393.532615) (xy 348.08631 -393.493799) (xy 348.120241 -393.459873)
			(xy 348.159062 -393.431674) (xy 348.201817 -393.409894) (xy 348.247452 -393.395072) (xy 348.294845 -393.387571)
			(xy 348.318836 -393.387072) (xy 348.342769 -393.387539) (xy 348.390049 -393.395007) (xy 348.435587 -393.409754)
			(xy 348.478269 -393.43142) (xy 348.517052 -393.459476) (xy 348.550987 -393.493234) (xy 348.579244 -393.53187)
			(xy 348.590616 -393.552934) (xy 348.591124 -393.55395) (xy 348.67143 -393.692888) (xy 349.213424 -393.692888)
			(xy 349.213424 -393.69238) (xy 349.21382 -393.668385) (xy 349.221331 -393.620985) (xy 349.236164 -393.575345)
			(xy 349.257954 -393.532586) (xy 349.286166 -393.493764) (xy 349.320103 -393.459832) (xy 349.358931 -393.431627)
			(xy 349.401693 -393.409844) (xy 349.447336 -393.395018) (xy 349.494737 -393.387516) (xy 349.518732 -393.387072)
			(xy 349.542666 -393.387554) (xy 349.58995 -393.395009) (xy 349.635493 -393.409747) (xy 349.678179 -393.431408)
			(xy 349.716965 -393.459462) (xy 349.750901 -393.493221) (xy 349.779157 -393.53186) (xy 349.790512 -393.552934)
			(xy 349.79102 -393.55395) (xy 349.871326 -393.692888) (xy 350.41332 -393.692888) (xy 350.41332 -393.69238)
			(xy 350.41372 -393.668385) (xy 350.42123 -393.620986) (xy 350.436063 -393.575346) (xy 350.457854 -393.532588)
			(xy 350.486065 -393.493765) (xy 350.520001 -393.459833) (xy 350.558829 -393.431629) (xy 350.60159 -393.409845)
			(xy 350.647233 -393.395019) (xy 350.694633 -393.387516) (xy 350.718628 -393.387072) (xy 350.718882 -393.387072)
			(xy 350.742818 -393.387513) (xy 350.790103 -393.394976) (xy 350.835647 -393.409721) (xy 350.878334 -393.431389)
			(xy 350.917119 -393.459449) (xy 350.951054 -393.493214) (xy 350.979308 -393.531858) (xy 350.990662 -393.552934)
			(xy 350.99117 -393.55395) (xy 351.071476 -393.692888) (xy 351.613216 -393.692888) (xy 351.613216 -393.69238)
			(xy 351.613621 -393.668372) (xy 351.621139 -393.620949) (xy 351.635987 -393.575288) (xy 351.657799 -393.532513)
			(xy 351.686038 -393.493679) (xy 351.720006 -393.459744) (xy 351.758867 -393.431543) (xy 351.801664 -393.409773)
			(xy 351.84734 -393.394969) (xy 351.89477 -393.387497) (xy 351.918778 -393.387072) (xy 351.942713 -393.387516)
			(xy 351.989999 -393.394978) (xy 352.035543 -393.409723) (xy 352.078229 -393.431391) (xy 352.117015 -393.45945)
			(xy 352.150949 -393.493214) (xy 352.179204 -393.531858) (xy 352.190558 -393.552934) (xy 352.191066 -393.55395)
			(xy 352.271372 -393.692888) (xy 352.813112 -393.692888) (xy 352.813112 -393.69238) (xy 352.813521 -393.668373)
			(xy 352.821039 -393.62095) (xy 352.835887 -393.575289) (xy 352.857699 -393.532514) (xy 352.885937 -393.493681)
			(xy 352.919904 -393.459745) (xy 352.958765 -393.431545) (xy 353.001561 -393.409774) (xy 353.047236 -393.39497)
			(xy 353.094666 -393.387498) (xy 353.118674 -393.387072) (xy 353.118928 -393.387072) (xy 353.142862 -393.387557)
			(xy 353.190146 -393.395011) (xy 353.235688 -393.409749) (xy 353.278375 -393.43141) (xy 353.317161 -393.459463)
			(xy 353.351097 -393.493222) (xy 353.379353 -393.53186) (xy 353.390708 -393.552934) (xy 353.391216 -393.55395)
			(xy 353.471522 -393.692888) (xy 354.013516 -393.692888) (xy 354.013516 -393.69238) (xy 354.01392 -393.668385)
			(xy 354.02143 -393.620987) (xy 354.036263 -393.575347) (xy 354.058053 -393.532589) (xy 354.086263 -393.493766)
			(xy 354.1202 -393.459835) (xy 354.159026 -393.43163) (xy 354.201787 -393.409846) (xy 354.247429 -393.39502)
			(xy 354.294829 -393.387516) (xy 354.318824 -393.387072) (xy 354.342758 -393.38756) (xy 354.390042 -393.395014)
			(xy 354.435584 -393.409751) (xy 354.478271 -393.431411) (xy 354.517057 -393.459464) (xy 354.550993 -393.493222)
			(xy 354.579249 -393.53186) (xy 354.590604 -393.552934) (xy 354.591112 -393.55395) (xy 354.983542 -394.232892)
			(xy 354.996367 -394.256224) (xy 355.014587 -394.306247) (xy 355.023847 -394.358673) (xy 355.024436 -394.385292)
			(xy 355.023954 -394.409296) (xy 355.016441 -394.456713) (xy 355.0016 -394.50237) (xy 354.979796 -394.545141)
			(xy 354.951566 -394.583973) (xy 354.917607 -394.617908) (xy 354.878755 -394.64611) (xy 354.835968 -394.667883)
			(xy 354.790301 -394.682692) (xy 354.742879 -394.690171) (xy 354.718874 -394.6906) (xy 354.695299 -394.690227)
			(xy 354.64871 -394.682982) (xy 354.603791 -394.668652) (xy 354.561613 -394.64758) (xy 354.52318 -394.620267)
			(xy 354.489409 -394.587365) (xy 354.461104 -394.549657) (xy 354.449634 -394.529056) (xy 354.449126 -394.528294)
			(xy 354.051362 -393.839954) (xy 354.039504 -393.817268) (xy 354.022646 -393.76894) (xy 354.014066 -393.71848)
			(xy 354.013516 -393.692888) (xy 353.471522 -393.692888) (xy 353.783646 -394.232892) (xy 353.796471 -394.256224)
			(xy 353.814691 -394.306247) (xy 353.823951 -394.358673) (xy 353.82454 -394.385292) (xy 353.824054 -394.409296)
			(xy 353.816541 -394.456713) (xy 353.8017 -394.502369) (xy 353.779896 -394.54514) (xy 353.751667 -394.583972)
			(xy 353.717709 -394.617907) (xy 353.678857 -394.646108) (xy 353.636071 -394.667882) (xy 353.590404 -394.682691)
			(xy 353.542982 -394.69017) (xy 353.518978 -394.6906) (xy 353.518724 -394.6906) (xy 353.495151 -394.690187)
			(xy 353.448563 -394.682949) (xy 353.403645 -394.668627) (xy 353.361467 -394.647561) (xy 353.323033 -394.620255)
			(xy 353.289261 -394.587358) (xy 353.260955 -394.549655) (xy 353.249484 -394.529056) (xy 353.248976 -394.528294)
			(xy 352.851212 -393.839954) (xy 352.839279 -393.817295) (xy 352.822347 -393.768965) (xy 352.813695 -393.718491)
			(xy 352.813112 -393.692888) (xy 352.271372 -393.692888) (xy 352.583496 -394.232892) (xy 352.596246 -394.256249)
			(xy 352.614355 -394.306281) (xy 352.623558 -394.358688) (xy 352.624136 -394.385292) (xy 352.62363 -394.409282)
			(xy 352.616126 -394.45667) (xy 352.601301 -394.502302) (xy 352.579521 -394.545053) (xy 352.551322 -394.58387)
			(xy 352.517397 -394.617798) (xy 352.478583 -394.646002) (xy 352.435835 -394.667788) (xy 352.390205 -394.682618)
			(xy 352.342818 -394.690127) (xy 352.318828 -394.6906) (xy 352.295255 -394.690184) (xy 352.248668 -394.682946)
			(xy 352.20375 -394.668625) (xy 352.161571 -394.64756) (xy 352.123138 -394.620254) (xy 352.089365 -394.587357)
			(xy 352.061059 -394.549654) (xy 352.049588 -394.529056) (xy 352.04908 -394.528294) (xy 351.651316 -393.839954)
			(xy 351.639383 -393.817294) (xy 351.622452 -393.768965) (xy 351.613799 -393.718491) (xy 351.613216 -393.692888)
			(xy 351.071476 -393.692888) (xy 351.3836 -394.232892) (xy 351.39635 -394.256249) (xy 351.41446 -394.306281)
			(xy 351.423662 -394.358688) (xy 351.42424 -394.385292) (xy 351.42373 -394.409281) (xy 351.416226 -394.45667)
			(xy 351.401402 -394.502301) (xy 351.379622 -394.545051) (xy 351.351423 -394.583869) (xy 351.317499 -394.617797)
			(xy 351.278686 -394.646001) (xy 351.235938 -394.667787) (xy 351.190309 -394.682617) (xy 351.142921 -394.690127)
			(xy 351.118932 -394.6906) (xy 351.118678 -394.6906) (xy 351.095103 -394.690224) (xy 351.048514 -394.682979)
			(xy 351.003595 -394.66865) (xy 350.961417 -394.647579) (xy 350.922984 -394.620266) (xy 350.889213 -394.587364)
			(xy 350.860908 -394.549657) (xy 350.849438 -394.529056) (xy 350.84893 -394.528294) (xy 350.451166 -393.839954)
			(xy 350.439308 -393.817268) (xy 350.42245 -393.76894) (xy 350.41387 -393.71848) (xy 350.41332 -393.692888)
			(xy 349.871326 -393.692888) (xy 350.18345 -394.232892) (xy 350.196276 -394.256224) (xy 350.214495 -394.306247)
			(xy 350.223755 -394.358673) (xy 350.224344 -394.385292) (xy 350.223854 -394.409296) (xy 350.216341 -394.456712)
			(xy 350.201501 -394.502368) (xy 350.179697 -394.545139) (xy 350.151469 -394.58397) (xy 350.11751 -394.617905)
			(xy 350.07866 -394.646107) (xy 350.035874 -394.667881) (xy 349.990207 -394.68269) (xy 349.942786 -394.69017)
			(xy 349.918782 -394.6906) (xy 349.895207 -394.690221) (xy 349.848619 -394.682977) (xy 349.8037 -394.668648)
			(xy 349.761521 -394.647577) (xy 349.723088 -394.620265) (xy 349.689317 -394.587364) (xy 349.661012 -394.549657)
			(xy 349.649542 -394.529056) (xy 349.649034 -394.528294) (xy 349.25127 -393.839954) (xy 349.239412 -393.817268)
			(xy 349.222555 -393.768939) (xy 349.213974 -393.71848) (xy 349.213424 -393.692888) (xy 348.67143 -393.692888)
			(xy 348.983554 -394.232892) (xy 348.99634 -394.256242) (xy 349.014539 -394.306265) (xy 349.023831 -394.358678)
			(xy 349.024448 -394.385292) (xy 349.024001 -394.409299) (xy 349.016488 -394.456723) (xy 349.001645 -394.502386)
			(xy 348.979839 -394.545163) (xy 348.951606 -394.584) (xy 348.917643 -394.61794) (xy 348.878787 -394.646147)
			(xy 348.835995 -394.667924) (xy 348.790322 -394.682736) (xy 348.742894 -394.690218) (xy 348.718886 -394.6906)
			(xy 348.700285 -394.690354) (xy 348.663351 -394.685898) (xy 348.645226 -394.68171) (xy 348.63553 -394.679801)
			(xy 348.615999 -394.68268) (xy 348.599004 -394.692728) (xy 348.587068 -394.708454) (xy 348.581961 -394.727524)
			(xy 348.584441 -394.74711) (xy 348.594139 -394.764306) (xy 348.601538 -394.770864) (xy 348.624398 -394.791184)
			(xy 348.977458 -395.144244) (xy 349.003874 -395.151102) (xy 349.017336 -395.147546) (xy 349.039059 -395.141876)
			(xy 349.083535 -395.135763) (xy 349.105982 -395.135354) (xy 349.131971 -395.135862) (xy 349.18331 -395.14399)
			(xy 349.232745 -395.160049) (xy 349.27906 -395.183643) (xy 349.321114 -395.214192) (xy 349.357871 -395.250943)
			(xy 349.388427 -395.292992) (xy 349.412029 -395.339303) (xy 349.428097 -395.388735) (xy 349.436233 -395.440073)
			(xy 349.43669 -395.466062) (xy 349.4363 -395.48851) (xy 349.430185 -395.532989) (xy 349.424498 -395.554708)
			(xy 349.420942 -395.56817) (xy 349.4278 -395.594586) (xy 349.919544 -396.08633) (xy 349.926941 -396.093177)
			(xy 349.94554 -396.100907) (xy 349.955612 -396.101316) (xy 357.958644 -396.101316) (xy 357.968711 -396.100885)
			(xy 357.987305 -396.093162) (xy 357.994712 -396.08633) (xy 358.113584 -395.967458) (xy 358.116378 -395.929866)
			(xy 358.104694 -395.914372) (xy 358.092758 -395.897772) (xy 358.073788 -395.861556) (xy 358.060864 -395.82277)
			(xy 358.054319 -395.782414) (xy 358.053894 -395.761972) (xy 358.053894 -395.12621) (xy 358.05446 -395.102112)
			(xy 358.063549 -395.05478) (xy 358.081401 -395.010012) (xy 358.107377 -394.969415) (xy 358.140544 -394.934446)
			(xy 358.159812 -394.919962) (xy 358.169229 -394.912298) (xy 358.180218 -394.890685) (xy 358.180894 -394.87856)
			(xy 358.180894 -394.756894) (xy 358.181456 -394.740317) (xy 358.190059 -394.708298) (xy 358.20663 -394.679581)
			(xy 358.217978 -394.667486) (xy 358.343708 -394.54201) (xy 358.350555 -394.534612) (xy 358.358292 -394.516014)
			(xy 358.358694 -394.505942) (xy 358.358694 -393.305284) (xy 358.358066 -393.29315) (xy 358.34705 -393.271535)
			(xy 358.337612 -393.263882) (xy 358.318358 -393.249383) (xy 358.285189 -393.21442) (xy 358.259214 -393.173826)
			(xy 358.241365 -393.12906) (xy 358.232284 -393.081731) (xy 358.231694 -393.057634) (xy 358.231694 -392.378184)
			(xy 358.231268 -392.368115) (xy 358.223549 -392.349516) (xy 358.216708 -392.342116) (xy 358.115362 -392.24077)
			(xy 358.107965 -392.233922) (xy 358.089366 -392.22619) (xy 358.079294 -392.225784) (xy 343.21623 -392.225784)
			(xy 343.206165 -392.226219) (xy 343.187578 -392.23395) (xy 343.180162 -392.24077) (xy 342.899238 -392.521694)
			(xy 342.892387 -392.52909) (xy 342.884644 -392.547689) (xy 342.884252 -392.557762) (xy 342.884252 -393.692888)
			(xy 343.213436 -393.692888) (xy 343.213436 -393.69238) (xy 343.21382 -393.668384) (xy 343.221331 -393.620984)
			(xy 343.236165 -393.575342) (xy 343.257957 -393.532583) (xy 343.286169 -393.493759) (xy 343.320108 -393.459828)
			(xy 343.358938 -393.431623) (xy 343.401701 -393.40984) (xy 343.447346 -393.395016) (xy 343.494748 -393.387515)
			(xy 343.518744 -393.387072) (xy 343.542678 -393.387544) (xy 343.589963 -393.395001) (xy 343.635506 -393.409741)
			(xy 343.678192 -393.431404) (xy 343.716978 -393.459459) (xy 343.750914 -393.493219) (xy 343.779169 -393.53186)
			(xy 343.790524 -393.552934) (xy 343.791032 -393.55395) (xy 343.871338 -393.692888) (xy 344.413332 -393.692888)
			(xy 344.413332 -393.69238) (xy 344.41372 -393.668384) (xy 344.421231 -393.620984) (xy 344.436065 -393.575343)
			(xy 344.457856 -393.532584) (xy 344.486068 -393.493761) (xy 344.520006 -393.459829) (xy 344.558835 -393.431624)
			(xy 344.601598 -393.409842) (xy 344.647243 -393.395017) (xy 344.694644 -393.387515) (xy 344.71864 -393.387072)
			(xy 344.718894 -393.387072) (xy 344.74283 -393.387503) (xy 344.790116 -393.394968) (xy 344.83566 -393.409715)
			(xy 344.878347 -393.431385) (xy 344.917132 -393.459446) (xy 344.951066 -393.493212) (xy 344.97932 -393.531857)
			(xy 344.990674 -393.552934) (xy 344.991182 -393.55395) (xy 345.071488 -393.692888) (xy 345.613228 -393.692888)
			(xy 345.613228 -393.69238) (xy 345.613621 -393.668372) (xy 345.621139 -393.620948) (xy 345.635988 -393.575285)
			(xy 345.657802 -393.532509) (xy 345.686041 -393.493675) (xy 345.720011 -393.45974) (xy 345.758874 -393.431539)
			(xy 345.801672 -393.40977) (xy 345.84735 -393.394967) (xy 345.894781 -393.387497) (xy 345.91879 -393.387072)
			(xy 345.942726 -393.387506) (xy 345.990012 -393.39497) (xy 346.035556 -393.409717) (xy 346.078242 -393.431386)
			(xy 346.117027 -393.459447) (xy 346.150962 -393.493213) (xy 346.179216 -393.531857) (xy 346.19057 -393.552934)
			(xy 346.191078 -393.55395) (xy 346.583508 -394.232892) (xy 346.596259 -394.256248) (xy 346.614368 -394.306281)
			(xy 346.62357 -394.358688) (xy 346.624148 -394.385292) (xy 346.62363 -394.409281) (xy 346.616126 -394.456669)
			(xy 346.601303 -394.502299) (xy 346.579524 -394.545049) (xy 346.551325 -394.583866) (xy 346.517403 -394.617794)
			(xy 346.47859 -394.645998) (xy 346.435843 -394.667784) (xy 346.390215 -394.682615) (xy 346.342829 -394.690126)
			(xy 346.31884 -394.6906) (xy 346.295267 -394.690174) (xy 346.24868 -394.682939) (xy 346.203763 -394.668618)
			(xy 346.161584 -394.647555) (xy 346.123151 -394.620251) (xy 346.089378 -394.587355) (xy 346.061071 -394.549654)
			(xy 346.0496 -394.529056) (xy 346.049092 -394.528294) (xy 345.651328 -393.839954) (xy 345.639396 -393.817294)
			(xy 345.622464 -393.768965) (xy 345.613811 -393.718491) (xy 345.613228 -393.692888) (xy 345.071488 -393.692888)
			(xy 345.383612 -394.232892) (xy 345.396363 -394.256248) (xy 345.414472 -394.306281) (xy 345.423674 -394.358688)
			(xy 345.424252 -394.385292) (xy 345.42373 -394.409281) (xy 345.416227 -394.456668) (xy 345.401403 -394.502298)
			(xy 345.379624 -394.545048) (xy 345.351427 -394.583865) (xy 345.317504 -394.617793) (xy 345.278692 -394.645997)
			(xy 345.235946 -394.667783) (xy 345.190319 -394.682614) (xy 345.142933 -394.690126) (xy 345.118944 -394.6906)
			(xy 345.11869 -394.6906) (xy 345.095116 -394.690214) (xy 345.048527 -394.682971) (xy 345.003608 -394.668644)
			(xy 344.96143 -394.647574) (xy 344.922997 -394.620263) (xy 344.889226 -394.587363) (xy 344.86092 -394.549656)
			(xy 344.84945 -394.529056) (xy 344.848942 -394.528294) (xy 344.451178 -393.839954) (xy 344.439321 -393.817268)
			(xy 344.422463 -393.768939) (xy 344.413882 -393.718479) (xy 344.413332 -393.692888) (xy 343.871338 -393.692888)
			(xy 344.183462 -394.232892) (xy 344.196289 -394.256224) (xy 344.214508 -394.306247) (xy 344.223767 -394.358673)
			(xy 344.224356 -394.385292) (xy 344.223854 -394.409295) (xy 344.216342 -394.45671) (xy 344.201502 -394.502365)
			(xy 344.179699 -394.545135) (xy 344.151472 -394.583966) (xy 344.117515 -394.617901) (xy 344.078666 -394.646103)
			(xy 344.035882 -394.667878) (xy 343.990217 -394.682688) (xy 343.942798 -394.690169) (xy 343.918794 -394.6906)
			(xy 343.89522 -394.690211) (xy 343.848631 -394.682969) (xy 343.803713 -394.668642) (xy 343.761534 -394.647573)
			(xy 343.723101 -394.620262) (xy 343.68933 -394.587362) (xy 343.661024 -394.549656) (xy 343.649554 -394.529056)
			(xy 343.649046 -394.528294) (xy 343.251282 -393.839954) (xy 343.239425 -393.817268) (xy 343.222567 -393.768939)
			(xy 343.213986 -393.718479) (xy 343.213436 -393.692888) (xy 342.884252 -393.692888) (xy 342.884252 -394.047218)
			(xy 342.884449 -394.053885) (xy 342.887925 -394.066757) (xy 342.89111 -394.072618) (xy 342.983566 -394.232892)
			(xy 342.996352 -394.256242) (xy 343.01455 -394.306265) (xy 343.023842 -394.358678) (xy 343.02446 -394.385292)
			(xy 343.024013 -394.408694) (xy 343.016872 -394.454949) (xy 343.002757 -394.499573) (xy 342.981996 -394.541521)
			(xy 342.955078 -394.579809) (xy 342.922633 -394.613541) (xy 342.904318 -394.628116) (xy 342.89532 -394.635704)
			(xy 342.884838 -394.656749) (xy 342.884252 -394.668502) (xy 342.884252 -396.108428) (xy 342.884682 -396.118495)
			(xy 342.892409 -396.137087) (xy 342.899238 -396.144496) (xy 343.15908 -396.404338) (xy 343.182448 -396.411704)
			(xy 343.19464 -396.409672) (xy 343.207371 -396.407656) (xy 343.233059 -396.405497) (xy 343.245948 -396.405354)
			(xy 343.265796 -396.405656) (xy 343.305164 -396.410749) (xy 343.324434 -396.415514) (xy 343.330784 -396.417292)
			(xy 344.361262 -396.417292)
		)
		(stroke
			(width 0)
			(type solid)
		)
		(fill yes)
		(layer "In8.Cu")
		(net "P1V8_CPU0_RT1_1A")
	)
	(gr_poly
		(pts
			(xy 424.662346 -397.467328) (xy 424.672413 -397.466897) (xy 424.691008 -397.459174) (xy 424.698414 -397.452342)
			(xy 424.777916 -397.37284) (xy 424.782996 -397.340074) (xy 424.775376 -397.325088) (xy 424.761649 -397.297614)
			(xy 424.742185 -397.239368) (xy 424.732306 -397.178756) (xy 424.731688 -397.14805) (xy 424.732148 -397.120795)
			(xy 424.739899 -397.066838) (xy 424.755251 -397.014534) (xy 424.77789 -396.964947) (xy 424.807357 -396.919088)
			(xy 424.843051 -396.877889) (xy 424.884244 -396.842189) (xy 424.9301 -396.812716) (xy 424.979683 -396.79007)
			(xy 425.031985 -396.774711) (xy 425.085941 -396.766952) (xy 425.113196 -396.766542) (xy 425.133287 -396.766785)
			(xy 425.173249 -396.770984) (xy 425.192952 -396.774924) (xy 425.204382 -396.777464) (xy 425.226734 -396.77213)
			(xy 425.297092 -396.715234) (xy 425.305518 -396.707562) (xy 425.315255 -396.686991) (xy 425.315888 -396.67561)
			(xy 425.315888 -392.39698) (xy 425.315461 -392.386912) (xy 425.30774 -392.368314) (xy 425.300902 -392.360912)
			(xy 424.985434 -392.045444) (xy 424.978034 -392.038603) (xy 424.959435 -392.030886) (xy 424.949366 -392.030458)
			(xy 410.052266 -392.030458) (xy 410.04226 -392.030951) (xy 410.023772 -392.038615) (xy 410.00962 -392.052766)
			(xy 410.001953 -392.071252) (xy 410.001466 -392.081258) (xy 410.001466 -393.692888) (xy 410.313632 -393.692888)
			(xy 410.313632 -393.69238) (xy 410.31402 -393.668384) (xy 410.321531 -393.620984) (xy 410.336365 -393.575343)
			(xy 410.358156 -393.532584) (xy 410.386368 -393.493761) (xy 410.420306 -393.459829) (xy 410.459135 -393.431624)
			(xy 410.501898 -393.409842) (xy 410.547543 -393.395017) (xy 410.594944 -393.387515) (xy 410.61894 -393.387072)
			(xy 410.642874 -393.387547) (xy 410.690159 -393.395003) (xy 410.735701 -393.409743) (xy 410.778388 -393.431405)
			(xy 410.817174 -393.45946) (xy 410.85111 -393.49322) (xy 410.879365 -393.53186) (xy 410.89072 -393.552934)
			(xy 410.891228 -393.55395) (xy 410.971534 -393.692888) (xy 411.513528 -393.692888) (xy 411.513528 -393.69238)
			(xy 411.51392 -393.668385) (xy 411.521431 -393.620985) (xy 411.536264 -393.575344) (xy 411.558055 -393.532585)
			(xy 411.586267 -393.493762) (xy 411.620205 -393.45983) (xy 411.659033 -393.431626) (xy 411.701796 -393.409843)
			(xy 411.747439 -393.395018) (xy 411.79484 -393.387515) (xy 411.818836 -393.387072) (xy 411.84277 -393.38755)
			(xy 411.890054 -393.395006) (xy 411.935597 -393.409745) (xy 411.978284 -393.431407) (xy 412.017069 -393.459461)
			(xy 412.051005 -393.49322) (xy 412.079261 -393.53186) (xy 412.090616 -393.552934) (xy 412.091124 -393.55395)
			(xy 412.17143 -393.692888) (xy 412.713424 -393.692888) (xy 412.713424 -393.69238) (xy 412.713821 -393.668372)
			(xy 412.721339 -393.620948) (xy 412.736188 -393.575286) (xy 412.758001 -393.53251) (xy 412.78624 -393.493676)
			(xy 412.820209 -393.459741) (xy 412.859072 -393.431541) (xy 412.901869 -393.409771) (xy 412.947546 -393.394968)
			(xy 412.994978 -393.387497) (xy 413.018986 -393.387072) (xy 413.042922 -393.38751) (xy 413.090208 -393.394973)
			(xy 413.135751 -393.409719) (xy 413.178438 -393.431388) (xy 413.217223 -393.459448) (xy 413.251158 -393.493213)
			(xy 413.279412 -393.531858) (xy 413.290766 -393.552934) (xy 413.291274 -393.55395) (xy 413.683704 -394.232892)
			(xy 413.696455 -394.256249) (xy 413.714564 -394.306281) (xy 413.723766 -394.358688) (xy 413.724344 -394.385292)
			(xy 413.72383 -394.409281) (xy 413.716326 -394.456669) (xy 413.701502 -394.5023) (xy 413.679723 -394.54505)
			(xy 413.651524 -394.583867) (xy 413.617601 -394.617796) (xy 413.578788 -394.646) (xy 413.536041 -394.667785)
			(xy 413.490412 -394.682616) (xy 413.443025 -394.690127) (xy 413.419036 -394.6906) (xy 413.395463 -394.690177)
			(xy 413.348876 -394.682941) (xy 413.303958 -394.668621) (xy 413.26178 -394.647557) (xy 413.223346 -394.620252)
			(xy 413.189574 -394.587356) (xy 413.161267 -394.549654) (xy 413.149796 -394.529056) (xy 413.149288 -394.528294)
			(xy 412.751524 -393.839954) (xy 412.739592 -393.817294) (xy 412.72266 -393.768965) (xy 412.714007 -393.718491)
			(xy 412.713424 -393.692888) (xy 412.17143 -393.692888) (xy 412.483554 -394.232892) (xy 412.49638 -394.256224)
			(xy 412.514599 -394.306247) (xy 412.523859 -394.358673) (xy 412.524448 -394.385292) (xy 412.523954 -394.409296)
			(xy 412.516441 -394.456711) (xy 412.501601 -394.502367) (xy 412.479798 -394.545138) (xy 412.45157 -394.583969)
			(xy 412.417612 -394.617904) (xy 412.378762 -394.646106) (xy 412.335977 -394.66788) (xy 412.290311 -394.68269)
			(xy 412.24289 -394.69017) (xy 412.218886 -394.6906) (xy 412.195312 -394.690217) (xy 412.148723 -394.682974)
			(xy 412.103804 -394.668646) (xy 412.061626 -394.647576) (xy 412.023193 -394.620264) (xy 411.989421 -394.587363)
			(xy 411.961116 -394.549656) (xy 411.949646 -394.529056) (xy 411.949138 -394.528294) (xy 411.551374 -393.839954)
			(xy 411.539517 -393.817268) (xy 411.522659 -393.768939) (xy 411.514078 -393.718479) (xy 411.513528 -393.692888)
			(xy 410.971534 -393.692888) (xy 411.283658 -394.232892) (xy 411.296484 -394.256224) (xy 411.314704 -394.306247)
			(xy 411.323963 -394.358673) (xy 411.324552 -394.385292) (xy 411.324054 -394.409295) (xy 411.316542 -394.456711)
			(xy 411.301701 -394.502366) (xy 411.279899 -394.545137) (xy 411.251671 -394.583968) (xy 411.217714 -394.617902)
			(xy 411.178864 -394.646104) (xy 411.136079 -394.667879) (xy 411.090414 -394.682689) (xy 411.042994 -394.690169)
			(xy 411.01899 -394.6906) (xy 410.995416 -394.690214) (xy 410.948827 -394.682971) (xy 410.903908 -394.668644)
			(xy 410.86173 -394.647574) (xy 410.823297 -394.620263) (xy 410.789526 -394.587363) (xy 410.76122 -394.549656)
			(xy 410.74975 -394.529056) (xy 410.749242 -394.528294) (xy 410.351478 -393.839954) (xy 410.339621 -393.817268)
			(xy 410.322763 -393.768939) (xy 410.314182 -393.718479) (xy 410.313632 -393.692888) (xy 410.001466 -393.692888)
			(xy 410.001466 -394.076682) (xy 410.001658 -394.08335) (xy 410.005128 -394.096227) (xy 410.008324 -394.102082)
			(xy 410.083762 -394.232892) (xy 410.096548 -394.256242) (xy 410.114747 -394.306265) (xy 410.124038 -394.358678)
			(xy 410.124656 -394.385292) (xy 410.124092 -394.411494) (xy 410.115111 -394.463125) (xy 410.097461 -394.512469)
			(xy 410.071658 -394.558082) (xy 410.038459 -394.598631) (xy 410.018992 -394.616178) (xy 410.011087 -394.623735)
			(xy 410.002015 -394.643609) (xy 410.001466 -394.654532) (xy 410.001466 -396.055596) (xy 410.00189 -396.065665)
			(xy 410.009611 -396.084264) (xy 410.016452 -396.091664) (xy 410.322268 -396.39748) (xy 410.340556 -396.405354)
			(xy 410.350462 -396.405354) (xy 410.373097 -396.406083) (xy 410.417787 -396.413405) (xy 410.460903 -396.427255)
			(xy 410.501497 -396.447329) (xy 410.538677 -396.473184) (xy 410.55544 -396.488412) (xy 410.56273 -396.494695)
			(xy 410.580621 -396.501743) (xy 410.590238 -396.502128) (xy 411.3022 -396.502128) (xy 411.311808 -396.501711)
			(xy 411.329687 -396.49466) (xy 411.336998 -396.488412) (xy 411.356023 -396.471216) (xy 411.398704 -396.442792)
			(xy 411.445533 -396.421898) (xy 411.495195 -396.409122) (xy 411.546294 -396.404823) (xy 411.597393 -396.409122)
			(xy 411.647055 -396.421898) (xy 411.693884 -396.442792) (xy 411.736565 -396.471216) (xy 411.75559 -396.488412)
			(xy 411.762878 -396.494702) (xy 411.780769 -396.501768) (xy 411.790388 -396.502128) (xy 412.502096 -396.502128)
			(xy 412.511705 -396.501712) (xy 412.529584 -396.494662) (xy 412.536894 -396.488412) (xy 412.553982 -396.472901)
			(xy 412.591956 -396.446679) (xy 412.633442 -396.426467) (xy 412.677496 -396.412726) (xy 412.723116 -396.405768)
			(xy 412.74619 -396.405354) (xy 412.771358 -396.405869) (xy 412.821011 -396.414134) (xy 412.868632 -396.430441)
			(xy 412.912929 -396.454346) (xy 412.933134 -396.469362) (xy 412.948374 -396.481046) (xy 412.986474 -396.47876)
			(xy 414.672526 -394.792708) (xy 414.679638 -394.779246) (xy 414.680908 -394.771626) (xy 414.684972 -394.753084)
			(xy 414.633156 -394.690346) (xy 414.618932 -394.6906) (xy 414.595363 -394.690157) (xy 414.548788 -394.682899)
			(xy 414.503882 -394.668566) (xy 414.461713 -394.6475) (xy 414.423285 -394.6202) (xy 414.389512 -394.587317)
			(xy 414.361195 -394.549632) (xy 414.349692 -394.529056) (xy 414.349184 -394.528294) (xy 413.95142 -393.839954)
			(xy 413.939485 -393.817293) (xy 413.922531 -393.768969) (xy 413.913883 -393.718493) (xy 413.91332 -393.692888)
			(xy 413.91332 -393.69238) (xy 413.913769 -393.668376) (xy 413.921286 -393.62096) (xy 413.936132 -393.575305)
			(xy 413.957941 -393.532537) (xy 413.986175 -393.493709) (xy 414.020139 -393.459779) (xy 414.058995 -393.431583)
			(xy 414.101785 -393.409816) (xy 414.147454 -393.395015) (xy 414.194878 -393.387545) (xy 414.218882 -393.387072)
			(xy 414.242817 -393.387535) (xy 414.290103 -393.394996) (xy 414.335647 -393.409738) (xy 414.378336 -393.4314)
			(xy 414.417125 -393.459453) (xy 414.451067 -393.49321) (xy 414.47933 -393.531847) (xy 414.490662 -393.552934)
			(xy 414.49117 -393.55395) (xy 414.8836 -394.232892) (xy 414.896404 -394.256225) (xy 414.914546 -394.306258)
			(xy 414.923722 -394.358681) (xy 414.92424 -394.385292) (xy 414.92424 -394.395706) (xy 414.923732 -394.405866)
			(xy 414.93059 -394.424408) (xy 414.993074 -394.491972) (xy 415.010854 -394.500354) (xy 415.021268 -394.500608)
			(xy 415.046493 -394.502231) (xy 415.09605 -394.512178) (xy 415.143515 -394.529552) (xy 415.187783 -394.553947)
			(xy 415.227822 -394.584797) (xy 415.262699 -394.62138) (xy 415.277554 -394.641832) (xy 415.285171 -394.651492)
			(xy 415.306931 -394.662886) (xy 415.31921 -394.663676) (xy 415.458402 -394.663676) (xy 415.480174 -394.664126)
			(xy 415.523083 -394.671534) (xy 415.543746 -394.678408) (xy 415.553069 -394.681308) (xy 415.572563 -394.680605)
			(xy 415.590387 -394.672678) (xy 415.603966 -394.658674) (xy 415.611338 -394.640614) (xy 415.611439 -394.621107)
			(xy 415.604253 -394.602972) (xy 415.597848 -394.595604) (xy 415.58392 -394.580443) (xy 415.559833 -394.547056)
			(xy 415.549842 -394.529056) (xy 415.549334 -394.528294) (xy 415.15157 -393.839954) (xy 415.139675 -393.817285)
			(xy 415.122807 -393.768954) (xy 415.114254 -393.718483) (xy 415.113724 -393.692888) (xy 415.113724 -393.69238)
			(xy 415.114172 -393.668389) (xy 415.121681 -393.620998) (xy 415.136512 -393.575365) (xy 415.158299 -393.532614)
			(xy 415.186505 -393.493797) (xy 415.220437 -393.459871) (xy 415.259258 -393.431672) (xy 415.302013 -393.409892)
			(xy 415.347648 -393.395069) (xy 415.395041 -393.387568) (xy 415.419032 -393.387072) (xy 415.442965 -393.387539)
			(xy 415.490246 -393.395006) (xy 415.535784 -393.409753) (xy 415.578467 -393.431419) (xy 415.61725 -393.459474)
			(xy 415.651185 -393.493232) (xy 415.679443 -393.531868) (xy 415.690812 -393.552934) (xy 415.69132 -393.55395)
			(xy 415.771626 -393.692888) (xy 416.31362 -393.692888) (xy 416.31362 -393.69238) (xy 416.31402 -393.668385)
			(xy 416.32153 -393.620986) (xy 416.336363 -393.575346) (xy 416.358154 -393.532588) (xy 416.386365 -393.493765)
			(xy 416.420301 -393.459833) (xy 416.459129 -393.431629) (xy 416.50189 -393.409845) (xy 416.547533 -393.395019)
			(xy 416.594933 -393.387516) (xy 416.618928 -393.387072) (xy 416.642862 -393.387557) (xy 416.690146 -393.395011)
			(xy 416.735688 -393.409749) (xy 416.778375 -393.43141) (xy 416.817161 -393.459463) (xy 416.851097 -393.493222)
			(xy 416.879353 -393.53186) (xy 416.890708 -393.552934) (xy 416.891216 -393.55395) (xy 416.971522 -393.692888)
			(xy 417.513516 -393.692888) (xy 417.513516 -393.69238) (xy 417.51392 -393.668385) (xy 417.52143 -393.620987)
			(xy 417.536263 -393.575347) (xy 417.558053 -393.532589) (xy 417.586263 -393.493766) (xy 417.6202 -393.459835)
			(xy 417.659026 -393.43163) (xy 417.701787 -393.409846) (xy 417.747429 -393.39502) (xy 417.794829 -393.387516)
			(xy 417.818824 -393.387072) (xy 417.842758 -393.38756) (xy 417.890042 -393.395014) (xy 417.935584 -393.409751)
			(xy 417.978271 -393.431411) (xy 418.017057 -393.459464) (xy 418.050993 -393.493222) (xy 418.079249 -393.53186)
			(xy 418.090604 -393.552934) (xy 418.091112 -393.55395) (xy 418.171418 -393.692888) (xy 418.713412 -393.692888)
			(xy 418.713412 -393.69238) (xy 418.713821 -393.668373) (xy 418.721339 -393.62095) (xy 418.736187 -393.575289)
			(xy 418.757999 -393.532514) (xy 418.786237 -393.493681) (xy 418.820204 -393.459745) (xy 418.859065 -393.431545)
			(xy 418.901861 -393.409774) (xy 418.947536 -393.39497) (xy 418.994966 -393.387498) (xy 419.018974 -393.387072)
			(xy 419.042909 -393.387519) (xy 419.090195 -393.394981) (xy 419.135738 -393.409726) (xy 419.178425 -393.431392)
			(xy 419.21721 -393.459451) (xy 419.251145 -393.493215) (xy 419.279399 -393.531858) (xy 419.290754 -393.552934)
			(xy 419.291262 -393.55395) (xy 419.371568 -393.692888) (xy 419.913308 -393.692888) (xy 419.913308 -393.69238)
			(xy 419.913721 -393.668373) (xy 419.921239 -393.620951) (xy 419.936087 -393.57529) (xy 419.957898 -393.532515)
			(xy 419.986135 -393.493682) (xy 420.020103 -393.459747) (xy 420.058963 -393.431546) (xy 420.101758 -393.409775)
			(xy 420.147433 -393.394971) (xy 420.194862 -393.387498) (xy 420.21887 -393.387072) (xy 420.242805 -393.387523)
			(xy 420.290091 -393.394984) (xy 420.335634 -393.409728) (xy 420.378321 -393.431394) (xy 420.417106 -393.459452)
			(xy 420.451041 -393.493216) (xy 420.479295 -393.531858) (xy 420.49065 -393.552934) (xy 420.491158 -393.55395)
			(xy 420.571464 -393.692888) (xy 421.113712 -393.692888) (xy 421.113712 -393.69238) (xy 421.114144 -393.668387)
			(xy 421.121654 -393.620993) (xy 421.136485 -393.575357) (xy 421.158273 -393.532603) (xy 421.186481 -393.493784)
			(xy 421.220414 -393.459855) (xy 421.259237 -393.431652) (xy 421.301994 -393.40987) (xy 421.347632 -393.395045)
			(xy 421.395027 -393.387541) (xy 421.41902 -393.387072) (xy 421.442954 -393.387563) (xy 421.490237 -393.395017)
			(xy 421.53578 -393.409753) (xy 421.578466 -393.431413) (xy 421.617252 -393.459465) (xy 421.651189 -393.493223)
			(xy 421.679444 -393.531861) (xy 421.6908 -393.552934) (xy 421.691308 -393.55395) (xy 422.083738 -394.232892)
			(xy 422.096563 -394.256225) (xy 422.114783 -394.306247) (xy 422.124043 -394.358673) (xy 422.124632 -394.385292)
			(xy 422.124154 -394.409296) (xy 422.116641 -394.456714) (xy 422.101799 -394.502371) (xy 422.079995 -394.545143)
			(xy 422.051765 -394.583974) (xy 422.017805 -394.617909) (xy 421.978953 -394.646111) (xy 421.936165 -394.667885)
			(xy 421.890498 -394.682693) (xy 421.843075 -394.690171) (xy 421.81907 -394.6906) (xy 421.795495 -394.69023)
			(xy 421.748906 -394.682984) (xy 421.703987 -394.668654) (xy 421.661808 -394.647582) (xy 421.623376 -394.620268)
			(xy 421.589605 -394.587365) (xy 421.5613 -394.549657) (xy 421.54983 -394.529056) (xy 421.549322 -394.528294)
			(xy 421.151558 -393.839954) (xy 421.139699 -393.817269) (xy 421.122842 -393.76894) (xy 421.114262 -393.71848)
			(xy 421.113712 -393.692888) (xy 420.571464 -393.692888) (xy 420.883588 -394.232892) (xy 420.896337 -394.256249)
			(xy 420.914447 -394.306281) (xy 420.92365 -394.358688) (xy 420.924228 -394.385292) (xy 420.92373 -394.409282)
			(xy 420.916226 -394.456672) (xy 420.901401 -394.502304) (xy 420.87962 -394.545055) (xy 420.85142 -394.583873)
			(xy 420.817494 -394.617801) (xy 420.778679 -394.646005) (xy 420.73593 -394.66779) (xy 420.690299 -394.682619)
			(xy 420.64291 -394.690128) (xy 420.61892 -394.6906) (xy 420.595347 -394.69019) (xy 420.548759 -394.682952)
			(xy 420.503841 -394.668629) (xy 420.461662 -394.647563) (xy 420.423229 -394.620256) (xy 420.389457 -394.587358)
			(xy 420.361151 -394.549655) (xy 420.34968 -394.529056) (xy 420.349172 -394.528294) (xy 419.951408 -393.839954)
			(xy 419.939474 -393.817295) (xy 419.922543 -393.768965) (xy 419.913891 -393.718491) (xy 419.913308 -393.692888)
			(xy 419.371568 -393.692888) (xy 419.683692 -394.232892) (xy 419.696442 -394.256249) (xy 419.714551 -394.306281)
			(xy 419.723754 -394.358688) (xy 419.724332 -394.385292) (xy 419.72383 -394.409282) (xy 419.716326 -394.456671)
			(xy 419.701501 -394.502303) (xy 419.679721 -394.545054) (xy 419.651521 -394.583871) (xy 419.617596 -394.6178)
			(xy 419.578781 -394.646004) (xy 419.536032 -394.667789) (xy 419.490402 -394.682618) (xy 419.443014 -394.690128)
			(xy 419.419024 -394.6906) (xy 419.395451 -394.690187) (xy 419.348863 -394.682949) (xy 419.303945 -394.668627)
			(xy 419.261767 -394.647561) (xy 419.223333 -394.620255) (xy 419.189561 -394.587358) (xy 419.161255 -394.549655)
			(xy 419.149784 -394.529056) (xy 419.149276 -394.528294) (xy 418.751512 -393.839954) (xy 418.739579 -393.817295)
			(xy 418.722647 -393.768965) (xy 418.713995 -393.718491) (xy 418.713412 -393.692888) (xy 418.171418 -393.692888)
			(xy 418.483542 -394.232892) (xy 418.496367 -394.256224) (xy 418.514587 -394.306247) (xy 418.523847 -394.358673)
			(xy 418.524436 -394.385292) (xy 418.523954 -394.409296) (xy 418.516441 -394.456713) (xy 418.5016 -394.50237)
			(xy 418.479796 -394.545141) (xy 418.451566 -394.583973) (xy 418.417607 -394.617908) (xy 418.378755 -394.64611)
			(xy 418.335968 -394.667883) (xy 418.290301 -394.682692) (xy 418.242879 -394.690171) (xy 418.218874 -394.6906)
			(xy 418.195299 -394.690227) (xy 418.14871 -394.682982) (xy 418.103791 -394.668652) (xy 418.061613 -394.64758)
			(xy 418.02318 -394.620267) (xy 417.989409 -394.587365) (xy 417.961104 -394.549657) (xy 417.949634 -394.529056)
			(xy 417.949126 -394.528294) (xy 417.551362 -393.839954) (xy 417.539504 -393.817268) (xy 417.522646 -393.76894)
			(xy 417.514066 -393.71848) (xy 417.513516 -393.692888) (xy 416.971522 -393.692888) (xy 417.283646 -394.232892)
			(xy 417.296471 -394.256224) (xy 417.314691 -394.306247) (xy 417.323951 -394.358673) (xy 417.32454 -394.385292)
			(xy 417.324054 -394.409296) (xy 417.316541 -394.456713) (xy 417.3017 -394.502369) (xy 417.279896 -394.54514)
			(xy 417.251667 -394.583972) (xy 417.217709 -394.617907) (xy 417.178857 -394.646108) (xy 417.136071 -394.667882)
			(xy 417.090404 -394.682691) (xy 417.042982 -394.69017) (xy 417.018978 -394.6906) (xy 416.995403 -394.690224)
			(xy 416.948814 -394.682979) (xy 416.903895 -394.66865) (xy 416.861717 -394.647579) (xy 416.823284 -394.620266)
			(xy 416.789513 -394.587364) (xy 416.761208 -394.549657) (xy 416.749738 -394.529056) (xy 416.74923 -394.528294)
			(xy 416.351466 -393.839954) (xy 416.339608 -393.817268) (xy 416.32275 -393.76894) (xy 416.31417 -393.71848)
			(xy 416.31362 -393.692888) (xy 415.771626 -393.692888) (xy 416.08375 -394.232892) (xy 416.096537 -394.256242)
			(xy 416.114736 -394.306264) (xy 416.124028 -394.358678) (xy 416.124644 -394.385292) (xy 416.124197 -394.409299)
			(xy 416.116684 -394.456722) (xy 416.101841 -394.502385) (xy 416.080035 -394.545162) (xy 416.051802 -394.583999)
			(xy 416.017839 -394.617939) (xy 415.978983 -394.646145) (xy 415.936191 -394.667922) (xy 415.890518 -394.682733)
			(xy 415.84309 -394.690214) (xy 415.819082 -394.6906) (xy 415.790394 -394.689995) (xy 415.734009 -394.679392)
			(xy 415.707068 -394.669518) (xy 415.692844 -394.663676) (xy 415.66338 -394.670026) (xy 415.652458 -394.680694)
			(xy 415.645628 -394.688061) (xy 415.637904 -394.706588) (xy 415.637914 -394.726661) (xy 415.645656 -394.74518)
			(xy 415.652458 -394.752576) (xy 416.053016 -395.153134) (xy 416.081464 -395.159484) (xy 416.095434 -395.154404)
			(xy 416.122245 -395.145486) (xy 416.177928 -395.135911) (xy 416.206178 -395.135354) (xy 416.232167 -395.135862)
			(xy 416.283507 -395.143989) (xy 416.332943 -395.160048) (xy 416.379258 -395.183642) (xy 416.421312 -395.214191)
			(xy 416.45807 -395.250942) (xy 416.488626 -395.292991) (xy 416.512229 -395.339302) (xy 416.528297 -395.388735)
			(xy 416.536433 -395.440073) (xy 416.536886 -395.466062) (xy 416.536305 -395.494309) (xy 416.52672 -395.549985)
			(xy 416.517836 -395.576806) (xy 416.512756 -395.590776) (xy 416.519106 -395.619224) (xy 416.953954 -396.054072)
			(xy 416.966144 -396.06672) (xy 416.987302 -396.094759) (xy 416.996118 -396.109952) (xy 417.002976 -396.122144)
			(xy 417.026344 -396.13586) (xy 420.975028 -396.13586) (xy 420.999987 -396.136434) (xy 421.048944 -396.14618)
			(xy 421.095059 -396.165291) (xy 421.136558 -396.193032) (xy 421.154606 -396.210282) (xy 422.396666 -397.452342)
			(xy 422.404065 -397.459184) (xy 422.422664 -397.466904) (xy 422.432734 -397.467328)
		)
		(stroke
			(width 0)
			(type solid)
		)
		(fill yes)
		(layer "In8.Cu")
		(net "P1V8_CPU0_RT2_1A")
	)
	(gr_poly
		(pts
			(xy 167.146986 -389.005572) (xy 167.149526 -388.986522) (xy 167.153585 -388.960437) (xy 167.168901 -388.909921)
			(xy 167.192049 -388.86248) (xy 167.22244 -388.819319) (xy 167.259302 -388.781534) (xy 167.301699 -388.750086)
			(xy 167.348553 -388.725773) (xy 167.398676 -388.709213) (xy 167.450792 -388.700826) (xy 167.50358 -388.700826)
			(xy 167.555696 -388.709213) (xy 167.605819 -388.725773) (xy 167.652673 -388.750086) (xy 167.69507 -388.781534)
			(xy 167.731932 -388.819319) (xy 167.762323 -388.86248) (xy 167.785471 -388.909921) (xy 167.800787 -388.960437)
			(xy 167.804846 -388.986522) (xy 167.807386 -389.005572) (xy 167.836088 -389.030464) (xy 168.63822 -389.030464)
			(xy 168.648288 -389.030036) (xy 168.666884 -389.022313) (xy 168.674288 -389.015478) (xy 168.75252 -388.937246)
			(xy 168.759124 -388.908544) (xy 168.754044 -388.894574) (xy 168.74361 -388.863473) (xy 168.732365 -388.798848)
			(xy 168.731692 -388.76605) (xy 168.732152 -388.738795) (xy 168.739903 -388.684838) (xy 168.755255 -388.632535)
			(xy 168.777894 -388.582948) (xy 168.807361 -388.537089) (xy 168.843055 -388.49589) (xy 168.884249 -388.460191)
			(xy 168.930104 -388.430718) (xy 168.979688 -388.408072) (xy 169.03199 -388.392714) (xy 169.085945 -388.384955)
			(xy 169.1132 -388.384542) (xy 169.128443 -388.384681) (xy 169.158833 -388.387095) (xy 169.173906 -388.389368)
			(xy 169.185082 -388.391146) (xy 169.206418 -388.385304) (xy 169.273982 -388.3279) (xy 169.282047 -388.320278)
			(xy 169.291273 -388.300124) (xy 169.291762 -388.289038) (xy 169.291762 -383.960116) (xy 169.291323 -383.950053)
			(xy 169.283583 -383.931475) (xy 169.276776 -383.924048) (xy 168.961308 -383.60858) (xy 168.953914 -383.601723)
			(xy 168.935315 -383.593973) (xy 168.92524 -383.593594) (xy 154.02814 -383.593594) (xy 154.018113 -383.594007)
			(xy 153.999581 -383.601669) (xy 153.985395 -383.615843) (xy 153.977716 -383.634367) (xy 153.97734 -383.644394)
			(xy 153.97734 -385.310888) (xy 154.313636 -385.310888) (xy 154.313636 -385.31038) (xy 154.31402 -385.286384)
			(xy 154.321531 -385.238984) (xy 154.336365 -385.193342) (xy 154.358157 -385.150583) (xy 154.386369 -385.111759)
			(xy 154.420308 -385.077828) (xy 154.459138 -385.049623) (xy 154.501901 -385.02784) (xy 154.547546 -385.013016)
			(xy 154.594948 -385.005515) (xy 154.618944 -385.005072) (xy 154.642878 -385.005544) (xy 154.690163 -385.013001)
			(xy 154.735706 -385.027741) (xy 154.778392 -385.049404) (xy 154.817178 -385.077459) (xy 154.851114 -385.111219)
			(xy 154.879369 -385.14986) (xy 154.890724 -385.170934) (xy 154.891232 -385.17195) (xy 154.971538 -385.310888)
			(xy 155.513532 -385.310888) (xy 155.513532 -385.31038) (xy 155.51392 -385.286384) (xy 155.521431 -385.238984)
			(xy 155.536265 -385.193343) (xy 155.558056 -385.150584) (xy 155.586268 -385.111761) (xy 155.620206 -385.077829)
			(xy 155.659035 -385.049624) (xy 155.701798 -385.027842) (xy 155.747443 -385.013017) (xy 155.794844 -385.005515)
			(xy 155.81884 -385.005072) (xy 155.842774 -385.005547) (xy 155.890059 -385.013003) (xy 155.935601 -385.027743)
			(xy 155.978288 -385.049405) (xy 156.017074 -385.07746) (xy 156.05101 -385.11122) (xy 156.079265 -385.14986)
			(xy 156.09062 -385.170934) (xy 156.091128 -385.17195) (xy 156.171434 -385.310888) (xy 156.713428 -385.310888)
			(xy 156.713428 -385.31038) (xy 156.713821 -385.286372) (xy 156.721339 -385.238948) (xy 156.736188 -385.193285)
			(xy 156.758002 -385.150509) (xy 156.786241 -385.111675) (xy 156.820211 -385.07774) (xy 156.859074 -385.049539)
			(xy 156.901872 -385.02777) (xy 156.94755 -385.012967) (xy 156.994981 -385.005497) (xy 157.01899 -385.005072)
			(xy 157.042926 -385.005506) (xy 157.090212 -385.01297) (xy 157.135756 -385.027717) (xy 157.178442 -385.049386)
			(xy 157.217227 -385.077447) (xy 157.251162 -385.111213) (xy 157.279416 -385.149857) (xy 157.29077 -385.170934)
			(xy 157.291278 -385.17195) (xy 157.683708 -385.850892) (xy 157.696459 -385.874248) (xy 157.714568 -385.924281)
			(xy 157.72377 -385.976688) (xy 157.724348 -386.003292) (xy 157.72383 -386.027281) (xy 157.716326 -386.074669)
			(xy 157.701503 -386.120299) (xy 157.679724 -386.163049) (xy 157.651525 -386.201866) (xy 157.617603 -386.235794)
			(xy 157.57879 -386.263998) (xy 157.536043 -386.285784) (xy 157.490415 -386.300615) (xy 157.443029 -386.308126)
			(xy 157.41904 -386.3086) (xy 157.395467 -386.308174) (xy 157.34888 -386.300939) (xy 157.303963 -386.286618)
			(xy 157.261784 -386.265555) (xy 157.223351 -386.238251) (xy 157.189578 -386.205355) (xy 157.161271 -386.167654)
			(xy 157.1498 -386.147056) (xy 157.149292 -386.146294) (xy 156.751528 -385.457954) (xy 156.739596 -385.435294)
			(xy 156.722664 -385.386965) (xy 156.714011 -385.336491) (xy 156.713428 -385.310888) (xy 156.171434 -385.310888)
			(xy 156.483558 -385.850892) (xy 156.496384 -385.874224) (xy 156.514604 -385.924247) (xy 156.523863 -385.976673)
			(xy 156.524452 -386.003292) (xy 156.523954 -386.027295) (xy 156.516442 -386.074711) (xy 156.501601 -386.120366)
			(xy 156.479799 -386.163137) (xy 156.451571 -386.201968) (xy 156.417614 -386.235902) (xy 156.378764 -386.264104)
			(xy 156.335979 -386.285879) (xy 156.290314 -386.300689) (xy 156.242894 -386.308169) (xy 156.21889 -386.3086)
			(xy 156.195316 -386.308214) (xy 156.148727 -386.300971) (xy 156.103808 -386.286644) (xy 156.06163 -386.265574)
			(xy 156.023197 -386.238263) (xy 155.989426 -386.205363) (xy 155.96112 -386.167656) (xy 155.94965 -386.147056)
			(xy 155.949142 -386.146294) (xy 155.551378 -385.457954) (xy 155.539521 -385.435268) (xy 155.522663 -385.386939)
			(xy 155.514082 -385.336479) (xy 155.513532 -385.310888) (xy 154.971538 -385.310888) (xy 155.283662 -385.850892)
			(xy 155.296489 -385.874224) (xy 155.314708 -385.924247) (xy 155.323967 -385.976673) (xy 155.324556 -386.003292)
			(xy 155.324054 -386.027295) (xy 155.316542 -386.07471) (xy 155.301702 -386.120365) (xy 155.279899 -386.163135)
			(xy 155.251672 -386.201966) (xy 155.217715 -386.235901) (xy 155.178866 -386.264103) (xy 155.136082 -386.285878)
			(xy 155.090417 -386.300688) (xy 155.042998 -386.308169) (xy 155.018994 -386.3086) (xy 154.99542 -386.308211)
			(xy 154.948831 -386.300969) (xy 154.903913 -386.286642) (xy 154.861734 -386.265573) (xy 154.823301 -386.238262)
			(xy 154.78953 -386.205362) (xy 154.761224 -386.167656) (xy 154.749754 -386.147056) (xy 154.749246 -386.146294)
			(xy 154.351482 -385.457954) (xy 154.339625 -385.435268) (xy 154.322767 -385.386939) (xy 154.314186 -385.336479)
			(xy 154.313636 -385.310888) (xy 153.97734 -385.310888) (xy 153.97734 -385.653026) (xy 153.977537 -385.659693)
			(xy 153.981015 -385.672565) (xy 153.984198 -385.678426) (xy 154.083766 -385.850892) (xy 154.096552 -385.874242)
			(xy 154.11475 -385.924265) (xy 154.124042 -385.976678) (xy 154.12466 -386.003292) (xy 154.124212 -386.027334)
			(xy 154.116682 -386.074824) (xy 154.101808 -386.120548) (xy 154.079955 -386.163379) (xy 154.051665 -386.202259)
			(xy 154.017634 -386.236228) (xy 153.998422 -386.250688) (xy 153.989033 -386.258297) (xy 153.978019 -386.279771)
			(xy 153.97734 -386.291836) (xy 153.97734 -387.618732) (xy 153.97777 -387.628799) (xy 153.985497 -387.647391)
			(xy 153.992326 -387.6548) (xy 154.354276 -388.01675) (xy 154.36977 -388.024116) (xy 154.37866 -388.025132)
			(xy 154.407722 -388.028857) (xy 154.463744 -388.045989) (xy 154.489912 -388.059168) (xy 154.4955 -388.062216)
			(xy 154.507438 -388.065264) (xy 155.385008 -388.065264) (xy 155.396946 -388.062216) (xy 155.402534 -388.059168)
			(xy 155.424794 -388.04787) (xy 155.472081 -388.031881) (xy 155.521339 -388.023803) (xy 155.546298 -388.023354)
			(xy 155.571254 -388.023833) (xy 155.620508 -388.031913) (xy 155.667794 -388.04789) (xy 155.690062 -388.059168)
			(xy 155.69565 -388.062216) (xy 155.707588 -388.065264) (xy 156.584904 -388.065264) (xy 156.596842 -388.062216)
			(xy 156.60243 -388.059168) (xy 156.62469 -388.04787) (xy 156.671977 -388.03188) (xy 156.721235 -388.023801)
			(xy 156.746194 -388.023354) (xy 156.77115 -388.023833) (xy 156.820404 -388.031912) (xy 156.86769 -388.047889)
			(xy 156.889958 -388.059168) (xy 156.895546 -388.062216) (xy 156.907484 -388.065264) (xy 156.917898 -388.065264)
			(xy 156.927968 -388.064841) (xy 156.946569 -388.057123) (xy 156.953966 -388.050278) (xy 158.54807 -386.456174)
			(xy 158.556531 -386.446663) (xy 158.563717 -386.422276) (xy 158.561786 -386.409692) (xy 158.540958 -386.313426)
			(xy 158.52394 -386.293868) (xy 158.511748 -386.289296) (xy 158.486141 -386.279062) (xy 158.438834 -386.250733)
			(xy 158.397398 -386.214353) (xy 158.363186 -386.171108) (xy 158.349696 -386.147056) (xy 158.349188 -386.146294)
			(xy 157.951424 -385.457954) (xy 157.939489 -385.435294) (xy 157.922534 -385.38697) (xy 157.913886 -385.336493)
			(xy 157.913324 -385.310888) (xy 157.913324 -385.31038) (xy 157.913773 -385.286376) (xy 157.92129 -385.23896)
			(xy 157.936136 -385.193306) (xy 157.957945 -385.150538) (xy 157.98618 -385.11171) (xy 158.020143 -385.077781)
			(xy 158.058999 -385.049585) (xy 158.101789 -385.027819) (xy 158.147458 -385.013019) (xy 158.194882 -385.005549)
			(xy 158.218886 -385.005072) (xy 158.242821 -385.005536) (xy 158.290106 -385.012997) (xy 158.33565 -385.027739)
			(xy 158.378338 -385.049401) (xy 158.417127 -385.077455) (xy 158.451068 -385.111212) (xy 158.479331 -385.149849)
			(xy 158.490666 -385.170934) (xy 158.491174 -385.17195) (xy 158.883604 -385.850892) (xy 158.896408 -385.874225)
			(xy 158.91455 -385.924258) (xy 158.923726 -385.976681) (xy 158.924244 -386.003292) (xy 158.924244 -386.013706)
			(xy 158.923736 -386.023866) (xy 158.930594 -386.042408) (xy 158.993078 -386.109972) (xy 159.010858 -386.118354)
			(xy 159.021272 -386.118608) (xy 159.045298 -386.120157) (xy 159.092559 -386.129332) (xy 159.137994 -386.145255)
			(xy 159.180644 -386.167589) (xy 159.219611 -386.195863) (xy 159.237172 -386.212334) (xy 159.244553 -386.218915)
			(xy 159.262853 -386.226362) (xy 159.272732 -386.226812) (xy 159.434276 -386.226812) (xy 159.451054 -386.227096)
			(xy 159.484312 -386.23155) (xy 159.50057 -386.235702) (xy 159.510435 -386.237913) (xy 159.53046 -386.235244)
			(xy 159.547903 -386.225054) (xy 159.560063 -386.208922) (xy 159.565055 -386.189347) (xy 159.562106 -386.169362)
			(xy 159.557212 -386.160518) (xy 159.549846 -386.147056) (xy 159.549338 -386.146294) (xy 159.151574 -385.457954)
			(xy 159.139679 -385.435285) (xy 159.122811 -385.386954) (xy 159.114258 -385.336483) (xy 159.113728 -385.310888)
			(xy 159.113728 -385.31038) (xy 159.114176 -385.286389) (xy 159.121685 -385.238998) (xy 159.136516 -385.193365)
			(xy 159.158303 -385.150615) (xy 159.18651 -385.111799) (xy 159.220441 -385.077873) (xy 159.259262 -385.049674)
			(xy 159.302017 -385.027894) (xy 159.347652 -385.013072) (xy 159.395045 -385.005571) (xy 159.419036 -385.005072)
			(xy 159.442969 -385.005539) (xy 159.490249 -385.013007) (xy 159.535787 -385.027754) (xy 159.578469 -385.04942)
			(xy 159.617252 -385.077476) (xy 159.651187 -385.111234) (xy 159.679444 -385.14987) (xy 159.690816 -385.170934)
			(xy 159.691324 -385.17195) (xy 159.77163 -385.310888) (xy 160.313624 -385.310888) (xy 160.313624 -385.31038)
			(xy 160.31402 -385.286385) (xy 160.321531 -385.238985) (xy 160.336364 -385.193345) (xy 160.358154 -385.150586)
			(xy 160.386366 -385.111764) (xy 160.420303 -385.077832) (xy 160.459131 -385.049627) (xy 160.501893 -385.027844)
			(xy 160.547536 -385.013018) (xy 160.594937 -385.005516) (xy 160.618932 -385.005072) (xy 160.642866 -385.005554)
			(xy 160.69015 -385.013009) (xy 160.735693 -385.027747) (xy 160.778379 -385.049408) (xy 160.817165 -385.077462)
			(xy 160.851101 -385.111221) (xy 160.879357 -385.14986) (xy 160.890712 -385.170934) (xy 160.89122 -385.17195)
			(xy 160.971526 -385.310888) (xy 161.51352 -385.310888) (xy 161.51352 -385.31038) (xy 161.51392 -385.286385)
			(xy 161.52143 -385.238986) (xy 161.536263 -385.193346) (xy 161.558054 -385.150588) (xy 161.586265 -385.111765)
			(xy 161.620201 -385.077833) (xy 161.659029 -385.049629) (xy 161.70179 -385.027845) (xy 161.747433 -385.013019)
			(xy 161.794833 -385.005516) (xy 161.818828 -385.005072) (xy 161.842762 -385.005557) (xy 161.890046 -385.013011)
			(xy 161.935588 -385.027749) (xy 161.978275 -385.04941) (xy 162.017061 -385.077463) (xy 162.050997 -385.111222)
			(xy 162.079253 -385.14986) (xy 162.090608 -385.170934) (xy 162.091116 -385.17195) (xy 162.171422 -385.310888)
			(xy 162.713416 -385.310888) (xy 162.713416 -385.31038) (xy 162.713821 -385.286372) (xy 162.721339 -385.238949)
			(xy 162.736187 -385.193288) (xy 162.757999 -385.150513) (xy 162.786238 -385.111679) (xy 162.820206 -385.077744)
			(xy 162.859067 -385.049543) (xy 162.901864 -385.027773) (xy 162.94754 -385.012969) (xy 162.99497 -385.005497)
			(xy 163.018978 -385.005072) (xy 163.042913 -385.005516) (xy 163.090199 -385.012978) (xy 163.135743 -385.027723)
			(xy 163.178429 -385.049391) (xy 163.217215 -385.07745) (xy 163.251149 -385.111214) (xy 163.279404 -385.149858)
			(xy 163.290758 -385.170934) (xy 163.291266 -385.17195) (xy 163.371572 -385.310888) (xy 163.913312 -385.310888)
			(xy 163.913312 -385.31038) (xy 163.913721 -385.286373) (xy 163.921239 -385.23895) (xy 163.936087 -385.193289)
			(xy 163.957899 -385.150514) (xy 163.986137 -385.111681) (xy 164.020104 -385.077745) (xy 164.058965 -385.049545)
			(xy 164.101761 -385.027774) (xy 164.147436 -385.01297) (xy 164.194866 -385.005498) (xy 164.218874 -385.005072)
			(xy 164.242809 -385.005519) (xy 164.290095 -385.012981) (xy 164.335638 -385.027726) (xy 164.378325 -385.049392)
			(xy 164.41711 -385.077451) (xy 164.451045 -385.111215) (xy 164.479299 -385.149858) (xy 164.490654 -385.170934)
			(xy 164.491162 -385.17195) (xy 164.571468 -385.310888) (xy 165.113716 -385.310888) (xy 165.113716 -385.31038)
			(xy 165.11412 -385.286385) (xy 165.12163 -385.238987) (xy 165.136463 -385.193347) (xy 165.158253 -385.150589)
			(xy 165.186463 -385.111766) (xy 165.2204 -385.077835) (xy 165.259226 -385.04963) (xy 165.301987 -385.027846)
			(xy 165.347629 -385.01302) (xy 165.395029 -385.005516) (xy 165.419024 -385.005072) (xy 165.442958 -385.00556)
			(xy 165.490242 -385.013014) (xy 165.535784 -385.027751) (xy 165.578471 -385.049411) (xy 165.617257 -385.077464)
			(xy 165.651193 -385.111222) (xy 165.679449 -385.14986) (xy 165.690804 -385.170934) (xy 165.691312 -385.17195)
			(xy 166.083742 -385.850892) (xy 166.096567 -385.874224) (xy 166.114787 -385.924247) (xy 166.124047 -385.976673)
			(xy 166.124636 -386.003292) (xy 166.124154 -386.027296) (xy 166.116641 -386.074713) (xy 166.1018 -386.12037)
			(xy 166.079996 -386.163141) (xy 166.051766 -386.201973) (xy 166.017807 -386.235908) (xy 165.978955 -386.26411)
			(xy 165.936168 -386.285883) (xy 165.890501 -386.300692) (xy 165.843079 -386.308171) (xy 165.819074 -386.3086)
			(xy 165.795499 -386.308227) (xy 165.74891 -386.300982) (xy 165.703991 -386.286652) (xy 165.661813 -386.26558)
			(xy 165.62338 -386.238267) (xy 165.589609 -386.205365) (xy 165.561304 -386.167657) (xy 165.549834 -386.147056)
			(xy 165.549326 -386.146294) (xy 165.151562 -385.457954) (xy 165.139704 -385.435268) (xy 165.122846 -385.38694)
			(xy 165.114266 -385.33648) (xy 165.113716 -385.310888) (xy 164.571468 -385.310888) (xy 164.883592 -385.850892)
			(xy 164.896342 -385.874249) (xy 164.914451 -385.924281) (xy 164.923654 -385.976688) (xy 164.924232 -386.003292)
			(xy 164.92373 -386.027282) (xy 164.916226 -386.074671) (xy 164.901401 -386.120303) (xy 164.879621 -386.163054)
			(xy 164.851421 -386.201871) (xy 164.817496 -386.2358) (xy 164.778681 -386.264004) (xy 164.735932 -386.285789)
			(xy 164.690302 -386.300618) (xy 164.642914 -386.308128) (xy 164.618924 -386.3086) (xy 164.595351 -386.308187)
			(xy 164.548763 -386.300949) (xy 164.503845 -386.286627) (xy 164.461667 -386.265561) (xy 164.423233 -386.238255)
			(xy 164.389461 -386.205358) (xy 164.361155 -386.167655) (xy 164.349684 -386.147056) (xy 164.349176 -386.146294)
			(xy 163.951412 -385.457954) (xy 163.939479 -385.435295) (xy 163.922547 -385.386965) (xy 163.913895 -385.336491)
			(xy 163.913312 -385.310888) (xy 163.371572 -385.310888) (xy 163.683696 -385.850892) (xy 163.696446 -385.874249)
			(xy 163.714555 -385.924281) (xy 163.723758 -385.976688) (xy 163.724336 -386.003292) (xy 163.72383 -386.027282)
			(xy 163.716326 -386.07467) (xy 163.701501 -386.120302) (xy 163.679721 -386.163053) (xy 163.651522 -386.20187)
			(xy 163.617597 -386.235798) (xy 163.578783 -386.264002) (xy 163.536035 -386.285788) (xy 163.490405 -386.300618)
			(xy 163.443018 -386.308127) (xy 163.419028 -386.3086) (xy 163.395455 -386.308184) (xy 163.348868 -386.300946)
			(xy 163.30395 -386.286625) (xy 163.261771 -386.26556) (xy 163.223338 -386.238254) (xy 163.189565 -386.205357)
			(xy 163.161259 -386.167654) (xy 163.149788 -386.147056) (xy 163.14928 -386.146294) (xy 162.751516 -385.457954)
			(xy 162.739583 -385.435294) (xy 162.722652 -385.386965) (xy 162.713999 -385.336491) (xy 162.713416 -385.310888)
			(xy 162.171422 -385.310888) (xy 162.483546 -385.850892) (xy 162.496371 -385.874224) (xy 162.514591 -385.924247)
			(xy 162.523851 -385.976673) (xy 162.52444 -386.003292) (xy 162.523954 -386.027296) (xy 162.516441 -386.074713)
			(xy 162.5016 -386.120369) (xy 162.479796 -386.16314) (xy 162.451567 -386.201972) (xy 162.417609 -386.235907)
			(xy 162.378757 -386.264108) (xy 162.335971 -386.285882) (xy 162.290304 -386.300691) (xy 162.242882 -386.30817)
			(xy 162.218878 -386.3086) (xy 162.195303 -386.308224) (xy 162.148714 -386.300979) (xy 162.103795 -386.28665)
			(xy 162.061617 -386.265579) (xy 162.023184 -386.238266) (xy 161.989413 -386.205364) (xy 161.961108 -386.167657)
			(xy 161.949638 -386.147056) (xy 161.94913 -386.146294) (xy 161.551366 -385.457954) (xy 161.539508 -385.435268)
			(xy 161.52265 -385.38694) (xy 161.51407 -385.33648) (xy 161.51352 -385.310888) (xy 160.971526 -385.310888)
			(xy 161.28365 -385.850892) (xy 161.296476 -385.874224) (xy 161.314695 -385.924247) (xy 161.323955 -385.976673)
			(xy 161.324544 -386.003292) (xy 161.324054 -386.027296) (xy 161.316541 -386.074712) (xy 161.301701 -386.120368)
			(xy 161.279897 -386.163139) (xy 161.251669 -386.20197) (xy 161.21771 -386.235905) (xy 161.17886 -386.264107)
			(xy 161.136074 -386.285881) (xy 161.090407 -386.30069) (xy 161.042986 -386.30817) (xy 161.018982 -386.3086)
			(xy 160.995407 -386.308221) (xy 160.948819 -386.300977) (xy 160.9039 -386.286648) (xy 160.861721 -386.265577)
			(xy 160.823288 -386.238265) (xy 160.789517 -386.205364) (xy 160.761212 -386.167657) (xy 160.749742 -386.147056)
			(xy 160.749234 -386.146294) (xy 160.35147 -385.457954) (xy 160.339612 -385.435268) (xy 160.322755 -385.386939)
			(xy 160.314174 -385.33648) (xy 160.313624 -385.310888) (xy 159.77163 -385.310888) (xy 160.083754 -385.850892)
			(xy 160.09654 -385.874242) (xy 160.114739 -385.924265) (xy 160.124031 -385.976678) (xy 160.124648 -386.003292)
			(xy 160.124201 -386.027299) (xy 160.116688 -386.074723) (xy 160.101845 -386.120386) (xy 160.080039 -386.163163)
			(xy 160.051806 -386.202) (xy 160.017843 -386.23594) (xy 159.978987 -386.264147) (xy 159.936195 -386.285924)
			(xy 159.890522 -386.300736) (xy 159.843094 -386.308218) (xy 159.819086 -386.3086) (xy 159.800549 -386.30834)
			(xy 159.763744 -386.30388) (xy 159.74568 -386.29971) (xy 159.732726 -386.296662) (xy 159.707072 -386.303774)
			(xy 159.697674 -386.313172) (xy 159.690838 -386.320538) (xy 159.683103 -386.339069) (xy 159.683107 -386.359149)
			(xy 159.690849 -386.377677) (xy 159.697674 -386.385054) (xy 160.075626 -386.763006) (xy 160.102296 -386.769864)
			(xy 160.115504 -386.766054) (xy 160.137705 -386.760131) (xy 160.183208 -386.75375) (xy 160.206182 -386.753354)
			(xy 160.232171 -386.753862) (xy 160.28351 -386.76199) (xy 160.332945 -386.778049) (xy 160.37926 -386.801643)
			(xy 160.421314 -386.832192) (xy 160.458071 -386.868943) (xy 160.488627 -386.910992) (xy 160.512229 -386.957303)
			(xy 160.528297 -387.006735) (xy 160.536433 -387.058073) (xy 160.53689 -387.084062) (xy 160.5365 -387.107037)
			(xy 160.530133 -387.152544) (xy 160.52419 -387.17474) (xy 160.52038 -387.187948) (xy 160.527238 -387.214618)
			(xy 160.929828 -387.617208) (xy 160.942014 -387.629859) (xy 160.963163 -387.657903) (xy 160.971992 -387.673088)
			(xy 160.97885 -387.68528) (xy 161.002218 -387.698996) (xy 164.950902 -387.698996) (xy 164.975859 -387.699608)
			(xy 165.024813 -387.709345) (xy 165.070926 -387.728446) (xy 165.112428 -387.756177) (xy 165.13048 -387.773418)
			(xy 166.37254 -389.015478) (xy 166.37994 -389.022321) (xy 166.398538 -389.030044) (xy 166.408608 -389.030464)
			(xy 167.118284 -389.030464)
		)
		(stroke
			(width 0)
			(type solid)
		)
		(fill yes)
		(layer "In8.Cu")
		(net "P1V8_CPU1_RT2_1A")
	)
	(gr_poly
		(pts
			(xy 531.7998 -462.519268) (xy 531.855569 -462.518759) (xy 531.966796 -462.510424) (xy 532.077089 -462.4938)
			(xy 532.185831 -462.46898) (xy 532.292414 -462.436103) (xy 532.396243 -462.395354) (xy 532.496736 -462.346959)
			(xy 532.593331 -462.291189) (xy 532.685488 -462.228357) (xy 532.772692 -462.158813) (xy 532.854456 -462.082947)
			(xy 532.930321 -462.001183) (xy 532.999864 -461.913979) (xy 533.062695 -461.821821) (xy 533.118464 -461.725225)
			(xy 533.166858 -461.624732) (xy 533.207607 -461.520903) (xy 533.240483 -461.41432) (xy 533.265302 -461.305577)
			(xy 533.281925 -461.195284) (xy 533.29026 -461.084057) (xy 533.29078 -461.028288) (xy 533.29078 -455.0283)
			(xy 533.290259 -454.972531) (xy 533.281923 -454.861305) (xy 533.265299 -454.751013) (xy 533.24048 -454.642271)
			(xy 533.207603 -454.535688) (xy 533.166854 -454.43186) (xy 533.118459 -454.331368) (xy 533.06269 -454.234773)
			(xy 532.999859 -454.142616) (xy 532.930316 -454.055412) (xy 532.854451 -453.973649) (xy 532.772688 -453.897784)
			(xy 532.685484 -453.828241) (xy 532.593327 -453.76541) (xy 532.496732 -453.709641) (xy 532.39624 -453.661246)
			(xy 532.292412 -453.620497) (xy 532.185829 -453.58762) (xy 532.077087 -453.562801) (xy 531.966795 -453.546177)
			(xy 531.855569 -453.537841) (xy 531.7998 -453.53732) (xy 516.019796 -453.53732) (xy 515.949414 -453.536826)
			(xy 515.808871 -453.528933) (xy 515.668991 -453.513172) (xy 515.530216 -453.489593) (xy 515.392981 -453.45827)
			(xy 515.257718 -453.419302) (xy 515.124852 -453.37281) (xy 514.994803 -453.318942) (xy 514.867978 -453.257866)
			(xy 514.744778 -453.189776) (xy 514.625589 -453.114884) (xy 514.510787 -453.033428) (xy 514.400733 -452.945663)
			(xy 514.295773 -452.851865) (xy 514.196238 -452.75233) (xy 514.10244 -452.64737) (xy 514.014674 -452.537316)
			(xy 513.933218 -452.422514) (xy 513.858326 -452.303325) (xy 513.790236 -452.180125) (xy 513.72916 -452.053301)
			(xy 513.675292 -451.923251) (xy 513.6288 -451.790386) (xy 513.589831 -451.655123) (xy 513.558507 -451.517888)
			(xy 513.534928 -451.379113) (xy 513.519167 -451.239233) (xy 513.511274 -451.09869) (xy 513.510784 -451.028308)
			(xy 513.510784 -312.408316) (xy 513.511268 -312.337933) (xy 513.51916 -312.197389) (xy 513.53492 -312.057508)
			(xy 513.558498 -311.918731) (xy 513.589821 -311.781495) (xy 513.628789 -311.646231) (xy 513.67528 -311.513364)
			(xy 513.729148 -311.383313) (xy 513.790224 -311.256488) (xy 513.858314 -311.133286) (xy 513.933205 -311.014096)
			(xy 514.014662 -310.899292) (xy 514.102427 -310.789237) (xy 514.196225 -310.684276) (xy 514.295761 -310.584739)
			(xy 514.400722 -310.49094) (xy 514.510776 -310.403174) (xy 514.625579 -310.321716) (xy 514.744769 -310.246824)
			(xy 514.86797 -310.178733) (xy 514.994795 -310.117656) (xy 515.124845 -310.063787) (xy 515.257712 -310.017295)
			(xy 515.392976 -309.978326) (xy 515.530212 -309.947002) (xy 515.668989 -309.923423) (xy 515.808869 -309.907662)
			(xy 515.949413 -309.899769) (xy 516.019796 -309.899304) (xy 531.7998 -309.899304) (xy 531.855569 -309.898783)
			(xy 531.966796 -309.890447) (xy 532.077089 -309.873823) (xy 532.185831 -309.849004) (xy 532.292415 -309.816128)
			(xy 532.396243 -309.775378) (xy 532.496737 -309.726984) (xy 532.593332 -309.671215) (xy 532.68549 -309.608384)
			(xy 532.772695 -309.538841) (xy 532.854459 -309.462976) (xy 532.930326 -309.381213) (xy 532.99987 -309.294009)
			(xy 533.062703 -309.201852) (xy 533.118473 -309.105258) (xy 533.166869 -309.004765) (xy 533.20762 -308.900937)
			(xy 533.240498 -308.794355) (xy 533.265319 -308.685613) (xy 533.281945 -308.57532) (xy 533.290282 -308.464093)
			(xy 533.29078 -308.408324) (xy 533.29078 10.40003) (xy 533.290257 10.455798) (xy 533.28192 10.567023)
			(xy 533.265294 10.677313) (xy 533.240473 10.786053) (xy 533.207596 10.892634) (xy 533.166845 10.99646)
			(xy 533.11845 11.09695) (xy 533.06268 11.193543) (xy 532.999848 11.285698) (xy 532.930305 11.3729)
			(xy 532.85444 11.454661) (xy 532.772677 11.530525) (xy 532.685474 11.600066) (xy 532.593318 11.662896)
			(xy 532.496724 11.718664) (xy 532.396232 11.767057) (xy 532.292406 11.807806) (xy 532.185824 11.840681)
			(xy 532.077084 11.8655) (xy 531.966793 11.882123) (xy 531.855568 11.890459) (xy 531.7998 11.89101)
			(xy 475.799912 11.89101) (xy 475.744142 11.890489) (xy 475.632915 11.882155) (xy 475.522621 11.865531)
			(xy 475.413878 11.840713) (xy 475.307293 11.807837) (xy 475.203464 11.767088) (xy 475.10297 11.718694)
			(xy 475.006373 11.662926) (xy 474.914214 11.600094) (xy 474.827008 11.530552) (xy 474.745243 11.454687)
			(xy 474.669376 11.372924) (xy 474.599831 11.28572) (xy 474.536997 11.193563) (xy 474.481225 11.096967)
			(xy 474.432829 10.996475) (xy 474.392077 10.892646) (xy 474.359198 10.786063) (xy 474.334376 10.67732)
			(xy 474.31775 10.567027) (xy 474.309413 10.4558) (xy 474.308932 10.40003) (xy 474.308932 7.335466)
			(xy 526.704041 7.335466) (xy 526.704041 7.464606) (xy 526.711991 7.593501) (xy 526.727861 7.721661)
			(xy 526.75159 7.848602) (xy 526.783089 7.973841) (xy 526.822238 8.096904) (xy 526.868889 8.217323)
			(xy 526.922864 8.334642) (xy 526.983959 8.448416) (xy 527.051942 8.558213) (xy 527.126556 8.663616)
			(xy 527.207517 8.764226) (xy 527.294517 8.859661) (xy 527.387228 8.94956) (xy 527.485298 9.033581)
			(xy 527.588353 9.111405) (xy 527.696004 9.182737) (xy 527.807843 9.247307) (xy 527.923444 9.304869)
			(xy 528.042369 9.355206) (xy 528.164168 9.398126) (xy 528.288378 9.433467) (xy 528.414527 9.461094)
			(xy 528.542139 9.480903) (xy 528.670728 9.492819) (xy 528.799806 9.496796) (xy 528.928884 9.492819)
			(xy 529.057473 9.480903) (xy 529.185085 9.461094) (xy 529.311234 9.433467) (xy 529.435444 9.398126)
			(xy 529.557243 9.355206) (xy 529.676168 9.304869) (xy 529.791769 9.247307) (xy 529.903608 9.182737)
			(xy 530.011259 9.111405) (xy 530.114314 9.033581) (xy 530.212384 8.94956) (xy 530.305095 8.859661)
			(xy 530.392095 8.764226) (xy 530.473056 8.663616) (xy 530.54767 8.558213) (xy 530.615653 8.448416)
			(xy 530.676748 8.334642) (xy 530.730723 8.217323) (xy 530.777374 8.096904) (xy 530.816523 7.973841)
			(xy 530.848022 7.848602) (xy 530.871751 7.721661) (xy 530.887621 7.593501) (xy 530.895571 7.464606)
			(xy 530.896068 7.400036) (xy 530.895571 7.335466) (xy 530.887621 7.206571) (xy 530.871751 7.078411)
			(xy 530.848022 6.95147) (xy 530.816523 6.826231) (xy 530.777374 6.703168) (xy 530.730723 6.582749)
			(xy 530.676748 6.46543) (xy 530.615653 6.351656) (xy 530.54767 6.241859) (xy 530.473056 6.136456)
			(xy 530.392095 6.035846) (xy 530.305095 5.940411) (xy 530.212384 5.850512) (xy 530.114314 5.766491)
			(xy 530.011259 5.688667) (xy 529.903608 5.617335) (xy 529.791769 5.552765) (xy 529.676168 5.495203)
			(xy 529.557243 5.444866) (xy 529.435444 5.401946) (xy 529.311234 5.366605) (xy 529.185085 5.338978)
			(xy 529.057473 5.319169) (xy 528.928884 5.307253) (xy 528.799806 5.303277) (xy 528.670728 5.307253)
			(xy 528.542139 5.319169) (xy 528.414527 5.338978) (xy 528.288378 5.366605) (xy 528.164168 5.401946)
			(xy 528.042369 5.444866) (xy 527.923444 5.495203) (xy 527.807843 5.552765) (xy 527.696004 5.617335)
			(xy 527.588353 5.688667) (xy 527.485298 5.766491) (xy 527.387228 5.850512) (xy 527.294517 5.940411)
			(xy 527.207517 6.035846) (xy 527.126556 6.136456) (xy 527.051942 6.241859) (xy 526.983959 6.351656)
			(xy 526.922864 6.46543) (xy 526.868889 6.582749) (xy 526.822238 6.703168) (xy 526.783089 6.826231)
			(xy 526.75159 6.95147) (xy 526.727861 7.078411) (xy 526.711991 7.206571) (xy 526.704041 7.335466)
			(xy 474.308932 7.335466) (xy 474.308932 -12.515904) (xy 476.704141 -12.515904) (xy 476.704141 -12.386764)
			(xy 476.712091 -12.257869) (xy 476.727961 -12.129709) (xy 476.75169 -12.002768) (xy 476.783189 -11.877529)
			(xy 476.822338 -11.754466) (xy 476.868989 -11.634047) (xy 476.922964 -11.516728) (xy 476.984059 -11.402954)
			(xy 477.052042 -11.293157) (xy 477.126656 -11.187754) (xy 477.207617 -11.087144) (xy 477.294617 -10.991709)
			(xy 477.387328 -10.90181) (xy 477.485398 -10.817789) (xy 477.588453 -10.739965) (xy 477.696104 -10.668633)
			(xy 477.807943 -10.604063) (xy 477.923544 -10.546501) (xy 478.042469 -10.496164) (xy 478.164268 -10.453244)
			(xy 478.288478 -10.417903) (xy 478.414627 -10.390276) (xy 478.542239 -10.370467) (xy 478.670828 -10.358551)
			(xy 478.799906 -10.354575) (xy 478.928984 -10.358551) (xy 479.057573 -10.370467) (xy 479.185185 -10.390276)
			(xy 479.311334 -10.417903) (xy 479.435544 -10.453244) (xy 479.557343 -10.496164) (xy 479.676268 -10.546501)
			(xy 479.791869 -10.604063) (xy 479.903708 -10.668633) (xy 480.011359 -10.739965) (xy 480.114414 -10.817789)
			(xy 480.212484 -10.90181) (xy 480.305195 -10.991709) (xy 480.392195 -11.087144) (xy 480.473156 -11.187754)
			(xy 480.54777 -11.293157) (xy 480.615753 -11.402954) (xy 480.676848 -11.516728) (xy 480.730823 -11.634047)
			(xy 480.777474 -11.754466) (xy 480.816623 -11.877529) (xy 480.848122 -12.002768) (xy 480.871851 -12.129709)
			(xy 480.887721 -12.257869) (xy 480.895671 -12.386764) (xy 480.896168 -12.451334) (xy 480.895671 -12.515904)
			(xy 480.887721 -12.644799) (xy 480.871851 -12.772959) (xy 480.848122 -12.8999) (xy 480.816623 -13.025139)
			(xy 480.777474 -13.148202) (xy 480.730823 -13.268621) (xy 480.676848 -13.38594) (xy 480.615753 -13.499714)
			(xy 480.54777 -13.609511) (xy 480.473156 -13.714914) (xy 480.392195 -13.815524) (xy 480.305195 -13.910959)
			(xy 480.212484 -14.000858) (xy 480.114414 -14.084879) (xy 480.011359 -14.162703) (xy 479.903708 -14.234035)
			(xy 479.791869 -14.298605) (xy 479.676268 -14.356167) (xy 479.557343 -14.406504) (xy 479.435544 -14.449424)
			(xy 479.311334 -14.484765) (xy 479.185185 -14.512392) (xy 479.057573 -14.532201) (xy 478.928984 -14.544117)
			(xy 478.799906 -14.548094) (xy 478.670828 -14.544117) (xy 478.542239 -14.532201) (xy 478.414627 -14.512392)
			(xy 478.288478 -14.484765) (xy 478.164268 -14.449424) (xy 478.042469 -14.406504) (xy 477.923544 -14.356167)
			(xy 477.807943 -14.298605) (xy 477.696104 -14.234035) (xy 477.588453 -14.162703) (xy 477.485398 -14.084879)
			(xy 477.387328 -14.000858) (xy 477.294617 -13.910959) (xy 477.207617 -13.815524) (xy 477.126656 -13.714914)
			(xy 477.052042 -13.609511) (xy 476.984059 -13.499714) (xy 476.922964 -13.38594) (xy 476.868989 -13.268621)
			(xy 476.822338 -13.148202) (xy 476.783189 -13.025139) (xy 476.75169 -12.8999) (xy 476.727961 -12.772959)
			(xy 476.712091 -12.644799) (xy 476.704141 -12.515904) (xy 474.308932 -12.515904) (xy 474.308932 -77.67193)
			(xy 474.308458 -77.765117) (xy 474.300759 -77.951331) (xy 474.28537 -78.137067) (xy 474.262318 -78.32201)
			(xy 474.231642 -78.505841) (xy 474.193396 -78.688247) (xy 474.147643 -78.868917) (xy 474.094463 -79.047542)
			(xy 474.033945 -79.223817) (xy 473.966195 -79.397439) (xy 473.891327 -79.568113) (xy 473.809469 -79.735548)
			(xy 473.720761 -79.899456) (xy 473.625355 -80.059558) (xy 473.523414 -80.21558) (xy 473.415112 -80.367256)
			(xy 473.300633 -80.514327) (xy 473.180175 -80.65654) (xy 473.053942 -80.793654) (xy 472.988386 -80.859884)
			(xy 471.245946 -82.602324) (xy 471.208633 -82.640304) (xy 471.138899 -82.72077) (xy 471.07508 -82.806006)
			(xy 471.017504 -82.895576) (xy 470.966464 -82.989025) (xy 470.922218 -83.085876) (xy 470.884993 -83.185636)
			(xy 470.854978 -83.287798) (xy 470.832326 -83.391839) (xy 470.817153 -83.497232) (xy 470.809535 -83.603438)
			(xy 470.809066 -83.656678) (xy 470.809066 -328.137828) (xy 473.204275 -328.137828) (xy 473.204275 -328.008688)
			(xy 473.212225 -327.879793) (xy 473.228095 -327.751633) (xy 473.251824 -327.624692) (xy 473.283323 -327.499453)
			(xy 473.322472 -327.37639) (xy 473.369123 -327.255971) (xy 473.423098 -327.138652) (xy 473.484193 -327.024878)
			(xy 473.552176 -326.915081) (xy 473.62679 -326.809678) (xy 473.707751 -326.709068) (xy 473.794751 -326.613633)
			(xy 473.887462 -326.523734) (xy 473.985532 -326.439713) (xy 474.088587 -326.361889) (xy 474.196238 -326.290557)
			(xy 474.308077 -326.225987) (xy 474.423678 -326.168425) (xy 474.542603 -326.118088) (xy 474.664402 -326.075168)
			(xy 474.788612 -326.039827) (xy 474.914761 -326.0122) (xy 475.042373 -325.992391) (xy 475.170962 -325.980475)
			(xy 475.30004 -325.976499) (xy 475.429118 -325.980475) (xy 475.557707 -325.992391) (xy 475.685319 -326.0122)
			(xy 475.811468 -326.039827) (xy 475.935678 -326.075168) (xy 476.057477 -326.118088) (xy 476.176402 -326.168425)
			(xy 476.292003 -326.225987) (xy 476.403842 -326.290557) (xy 476.511493 -326.361889) (xy 476.614548 -326.439713)
			(xy 476.712618 -326.523734) (xy 476.805329 -326.613633) (xy 476.892329 -326.709068) (xy 476.97329 -326.809678)
			(xy 477.047904 -326.915081) (xy 477.115887 -327.024878) (xy 477.176982 -327.138652) (xy 477.230957 -327.255971)
			(xy 477.277608 -327.37639) (xy 477.316757 -327.499453) (xy 477.348256 -327.624692) (xy 477.371985 -327.751633)
			(xy 477.387855 -327.879793) (xy 477.395805 -328.008688) (xy 477.396302 -328.073258) (xy 477.395805 -328.137828)
			(xy 477.387855 -328.266723) (xy 477.371985 -328.394883) (xy 477.348256 -328.521824) (xy 477.316757 -328.647063)
			(xy 477.277608 -328.770126) (xy 477.230957 -328.890545) (xy 477.176982 -329.007864) (xy 477.115887 -329.121638)
			(xy 477.047904 -329.231435) (xy 476.97329 -329.336838) (xy 476.892329 -329.437448) (xy 476.805329 -329.532883)
			(xy 476.712618 -329.622782) (xy 476.614548 -329.706803) (xy 476.511493 -329.784627) (xy 476.403842 -329.855959)
			(xy 476.292003 -329.920529) (xy 476.176402 -329.978091) (xy 476.057477 -330.028428) (xy 475.935678 -330.071348)
			(xy 475.811468 -330.106689) (xy 475.685319 -330.134316) (xy 475.557707 -330.154125) (xy 475.429118 -330.166041)
			(xy 475.30004 -330.170018) (xy 475.170962 -330.166041) (xy 475.042373 -330.154125) (xy 474.914761 -330.134316)
			(xy 474.788612 -330.106689) (xy 474.664402 -330.071348) (xy 474.542603 -330.028428) (xy 474.423678 -329.978091)
			(xy 474.308077 -329.920529) (xy 474.196238 -329.855959) (xy 474.088587 -329.784627) (xy 473.985532 -329.706803)
			(xy 473.887462 -329.622782) (xy 473.794751 -329.532883) (xy 473.707751 -329.437448) (xy 473.62679 -329.336838)
			(xy 473.552176 -329.231435) (xy 473.484193 -329.121638) (xy 473.423098 -329.007864) (xy 473.369123 -328.890545)
			(xy 473.322472 -328.770126) (xy 473.283323 -328.647063) (xy 473.251824 -328.521824) (xy 473.228095 -328.394883)
			(xy 473.212225 -328.266723) (xy 473.204275 -328.137828) (xy 470.809066 -328.137828) (xy 470.809066 -404.871936)
			(xy 470.808592 -404.965123) (xy 470.800892 -405.151337) (xy 470.785503 -405.337074) (xy 470.762451 -405.522016)
			(xy 470.731776 -405.705847) (xy 470.693529 -405.888254) (xy 470.647776 -406.068924) (xy 470.594596 -406.247549)
			(xy 470.534079 -406.423823) (xy 470.466329 -406.597446) (xy 470.391461 -406.76812) (xy 470.309603 -406.935555)
			(xy 470.220896 -407.099463) (xy 470.12549 -407.259566) (xy 470.02355 -407.415588) (xy 469.915248 -407.567265)
			(xy 469.80077 -407.714335) (xy 469.680312 -407.856549) (xy 469.554079 -407.993664) (xy 469.48852 -408.05989)
			(xy 468.245698 -409.302712) (xy 468.208406 -409.340689) (xy 468.138712 -409.421147) (xy 468.074932 -409.506369)
			(xy 468.017391 -409.595922) (xy 467.966382 -409.68935) (xy 467.922165 -409.786178) (xy 467.884964 -409.885911)
			(xy 467.85497 -409.988044) (xy 467.832334 -410.092055) (xy 467.817172 -410.197416) (xy 467.809562 -410.303589)
			(xy 467.809072 -410.356812) (xy 467.809072 -439.989976) (xy 467.809593 -440.045746) (xy 467.817926 -440.156975)
			(xy 467.834548 -440.26727) (xy 467.859367 -440.376014) (xy 467.892242 -440.4826) (xy 467.93299 -440.586431)
			(xy 467.981383 -440.686926) (xy 468.037152 -440.783525) (xy 468.099983 -440.875685) (xy 468.169525 -440.962893)
			(xy 468.24539 -441.044659) (xy 468.327153 -441.120528) (xy 468.414357 -441.190075) (xy 468.506514 -441.25291)
			(xy 468.60311 -441.308683) (xy 468.703603 -441.357081) (xy 468.807432 -441.397835) (xy 468.914016 -441.430715)
			(xy 469.022759 -441.455538) (xy 469.133053 -441.472166) (xy 469.244282 -441.480505) (xy 469.300052 -441.480956)
			(xy 471.79992 -441.480956) (xy 471.870302 -441.48145) (xy 472.010845 -441.489344) (xy 472.150724 -441.505105)
			(xy 472.2895 -441.528685) (xy 472.426735 -441.560009) (xy 472.561998 -441.598978) (xy 472.694863 -441.64547)
			(xy 472.824912 -441.699339) (xy 472.951736 -441.760414) (xy 473.074936 -441.828505) (xy 473.194125 -441.903396)
			(xy 473.308927 -441.984852) (xy 473.418981 -442.072617) (xy 473.523941 -442.166415) (xy 473.623477 -442.26595)
			(xy 473.717275 -442.37091) (xy 473.80504 -442.480964) (xy 473.886497 -442.595765) (xy 473.961389 -442.714953)
			(xy 474.02948 -442.838153) (xy 474.090556 -442.964977) (xy 474.144426 -443.095026) (xy 474.190918 -443.227891)
			(xy 474.229888 -443.363154) (xy 474.261212 -443.500389) (xy 474.284793 -443.639164) (xy 474.300555 -443.779043)
			(xy 474.308449 -443.919586) (xy 474.308932 -443.989968) (xy 474.308932 -458.092864) (xy 526.704041 -458.092864)
			(xy 526.704041 -457.963724) (xy 526.711991 -457.834829) (xy 526.727861 -457.706669) (xy 526.75159 -457.579728)
			(xy 526.783089 -457.454489) (xy 526.822238 -457.331426) (xy 526.868889 -457.211007) (xy 526.922864 -457.093688)
			(xy 526.983959 -456.979914) (xy 527.051942 -456.870117) (xy 527.126556 -456.764714) (xy 527.207517 -456.664104)
			(xy 527.294517 -456.568669) (xy 527.387228 -456.47877) (xy 527.485298 -456.394749) (xy 527.588353 -456.316925)
			(xy 527.696004 -456.245593) (xy 527.807843 -456.181023) (xy 527.923444 -456.123461) (xy 528.042369 -456.073124)
			(xy 528.164168 -456.030204) (xy 528.288378 -455.994863) (xy 528.414527 -455.967236) (xy 528.542139 -455.947427)
			(xy 528.670728 -455.935511) (xy 528.799806 -455.931535) (xy 528.928884 -455.935511) (xy 529.057473 -455.947427)
			(xy 529.185085 -455.967236) (xy 529.311234 -455.994863) (xy 529.435444 -456.030204) (xy 529.557243 -456.073124)
			(xy 529.676168 -456.123461) (xy 529.791769 -456.181023) (xy 529.903608 -456.245593) (xy 530.011259 -456.316925)
			(xy 530.114314 -456.394749) (xy 530.212384 -456.47877) (xy 530.305095 -456.568669) (xy 530.392095 -456.664104)
			(xy 530.473056 -456.764714) (xy 530.54767 -456.870117) (xy 530.615653 -456.979914) (xy 530.676748 -457.093688)
			(xy 530.730723 -457.211007) (xy 530.777374 -457.331426) (xy 530.816523 -457.454489) (xy 530.848022 -457.579728)
			(xy 530.871751 -457.706669) (xy 530.887621 -457.834829) (xy 530.895571 -457.963724) (xy 530.896068 -458.028294)
			(xy 530.895571 -458.092864) (xy 530.887621 -458.221759) (xy 530.871751 -458.349919) (xy 530.848022 -458.47686)
			(xy 530.816523 -458.602099) (xy 530.777374 -458.725162) (xy 530.730723 -458.845581) (xy 530.676748 -458.9629)
			(xy 530.615653 -459.076674) (xy 530.54767 -459.186471) (xy 530.473056 -459.291874) (xy 530.392095 -459.392484)
			(xy 530.305095 -459.487919) (xy 530.212384 -459.577818) (xy 530.114314 -459.661839) (xy 530.011259 -459.739663)
			(xy 529.903608 -459.810995) (xy 529.791769 -459.875565) (xy 529.676168 -459.933127) (xy 529.557243 -459.983464)
			(xy 529.435444 -460.026384) (xy 529.311234 -460.061725) (xy 529.185085 -460.089352) (xy 529.057473 -460.109161)
			(xy 528.928884 -460.121077) (xy 528.799806 -460.125054) (xy 528.670728 -460.121077) (xy 528.542139 -460.109161)
			(xy 528.414527 -460.089352) (xy 528.288378 -460.061725) (xy 528.164168 -460.026384) (xy 528.042369 -459.983464)
			(xy 527.923444 -459.933127) (xy 527.807843 -459.875565) (xy 527.696004 -459.810995) (xy 527.588353 -459.739663)
			(xy 527.485298 -459.661839) (xy 527.387228 -459.577818) (xy 527.294517 -459.487919) (xy 527.207517 -459.392484)
			(xy 527.126556 -459.291874) (xy 527.051942 -459.186471) (xy 526.983959 -459.076674) (xy 526.922864 -458.9629)
			(xy 526.868889 -458.845581) (xy 526.822238 -458.725162) (xy 526.783089 -458.602099) (xy 526.75159 -458.47686)
			(xy 526.727861 -458.349919) (xy 526.711991 -458.221759) (xy 526.704041 -458.092864) (xy 474.308932 -458.092864)
			(xy 474.308932 -461.028288) (xy 474.30944 -461.084058) (xy 474.317775 -461.195285) (xy 474.334398 -461.305579)
			(xy 474.359217 -461.414322) (xy 474.392093 -461.520906) (xy 474.432843 -461.624735) (xy 474.481238 -461.725228)
			(xy 474.537007 -461.821824) (xy 474.599839 -461.913982) (xy 474.669383 -462.001187) (xy 474.745248 -462.082952)
			(xy 474.827013 -462.158817) (xy 474.914218 -462.228361) (xy 475.006376 -462.291193) (xy 475.102972 -462.346962)
			(xy 475.203465 -462.395357) (xy 475.307294 -462.436107) (xy 475.413878 -462.468983) (xy 475.522621 -462.493802)
			(xy 475.632915 -462.510425) (xy 475.744142 -462.51876) (xy 475.799912 -462.519268)
		)
		(stroke
			(width 0)
			(type solid)
		)
		(fill yes)
		(layer "In8.Cu")
		(net "T1_GND")
	)
	(gr_poly
		(pts
			(xy 89.904316 -387.980428) (xy 89.914386 -387.980003) (xy 89.932988 -387.972287) (xy 89.940384 -387.965442)
			(xy 91.449144 -386.456682) (xy 91.454921 -386.45045) (xy 91.462341 -386.435172) (xy 91.464367 -386.418309)
			(xy 91.46286 -386.409946) (xy 91.441778 -386.31368) (xy 91.425014 -386.294122) (xy 91.412568 -386.28955)
			(xy 91.386842 -386.279344) (xy 91.339301 -386.251016) (xy 91.297655 -386.214571) (xy 91.263273 -386.171206)
			(xy 91.249754 -386.147056) (xy 91.249246 -386.146294) (xy 90.851482 -385.457954) (xy 90.839587 -385.435285)
			(xy 90.822718 -385.386954) (xy 90.814165 -385.336483) (xy 90.813636 -385.310888) (xy 90.813636 -385.31038)
			(xy 90.814084 -385.286389) (xy 90.821593 -385.238999) (xy 90.836424 -385.193366) (xy 90.858211 -385.150616)
			(xy 90.886418 -385.111801) (xy 90.92035 -385.077876) (xy 90.959171 -385.049678) (xy 91.001926 -385.0279)
			(xy 91.047561 -385.013078) (xy 91.094953 -385.005579) (xy 91.118944 -385.005072) (xy 91.142877 -385.00554)
			(xy 91.190156 -385.013009) (xy 91.235693 -385.027757) (xy 91.278374 -385.049424) (xy 91.317156 -385.077479)
			(xy 91.35109 -385.111237) (xy 91.379346 -385.149873) (xy 91.390724 -385.170934) (xy 91.391232 -385.17195)
			(xy 91.783662 -385.850892) (xy 91.796448 -385.874242) (xy 91.814647 -385.924265) (xy 91.823938 -385.976678)
			(xy 91.824556 -386.003292) (xy 91.824302 -386.013706) (xy 91.823794 -386.023866) (xy 91.830652 -386.042408)
			(xy 91.893136 -386.109972) (xy 91.910916 -386.118354) (xy 91.92133 -386.118608) (xy 91.946403 -386.120215)
			(xy 91.99567 -386.13006) (xy 92.042882 -386.147241) (xy 92.086954 -386.171364) (xy 92.126871 -386.201872)
			(xy 92.161717 -386.238065) (xy 92.1766 -386.258308) (xy 92.184172 -386.267899) (xy 92.205804 -386.279177)
			(xy 92.218002 -386.279898) (xy 92.420694 -386.279898) (xy 92.440506 -386.28066) (xy 92.450457 -386.280968)
			(xy 92.46939 -386.274875) (xy 92.484583 -386.26204) (xy 92.493756 -386.244392) (xy 92.495528 -386.224582)
			(xy 92.489636 -386.205586) (xy 92.483686 -386.197602) (xy 92.474143 -386.185734) (xy 92.457222 -386.160411)
			(xy 92.449904 -386.147056) (xy 92.449396 -386.146294) (xy 92.051632 -385.457954) (xy 92.039697 -385.435294)
			(xy 92.022742 -385.38697) (xy 92.014093 -385.336493) (xy 92.013532 -385.310888) (xy 92.013532 -385.31038)
			(xy 92.013981 -385.286376) (xy 92.021498 -385.238961) (xy 92.036344 -385.193307) (xy 92.058154 -385.15054)
			(xy 92.086388 -385.111713) (xy 92.120352 -385.077784) (xy 92.159208 -385.049589) (xy 92.201998 -385.027824)
			(xy 92.247667 -385.013025) (xy 92.29509 -385.005556) (xy 92.319094 -385.005072) (xy 92.343029 -385.005536)
			(xy 92.390313 -385.012998) (xy 92.435856 -385.027741) (xy 92.478543 -385.049404) (xy 92.517331 -385.077458)
			(xy 92.551271 -385.111216) (xy 92.579533 -385.149852) (xy 92.590874 -385.170934) (xy 92.591382 -385.17195)
			(xy 92.671688 -385.310888) (xy 93.213428 -385.310888) (xy 93.213428 -385.31038) (xy 93.213821 -385.286372)
			(xy 93.221339 -385.238948) (xy 93.236188 -385.193285) (xy 93.258002 -385.150509) (xy 93.286241 -385.111675)
			(xy 93.320211 -385.07774) (xy 93.359074 -385.049539) (xy 93.401872 -385.02777) (xy 93.44755 -385.012967)
			(xy 93.494981 -385.005497) (xy 93.51899 -385.005072) (xy 93.542926 -385.005506) (xy 93.590212 -385.01297)
			(xy 93.635756 -385.027717) (xy 93.678442 -385.049386) (xy 93.717227 -385.077447) (xy 93.751162 -385.111213)
			(xy 93.779416 -385.149857) (xy 93.79077 -385.170934) (xy 93.791278 -385.17195) (xy 93.871584 -385.310888)
			(xy 94.413324 -385.310888) (xy 94.413324 -385.31038) (xy 94.413721 -385.286372) (xy 94.421239 -385.238948)
			(xy 94.436088 -385.193286) (xy 94.457901 -385.15051) (xy 94.48614 -385.111676) (xy 94.520109 -385.077741)
			(xy 94.558972 -385.049541) (xy 94.601769 -385.027771) (xy 94.647446 -385.012968) (xy 94.694878 -385.005497)
			(xy 94.718886 -385.005072) (xy 94.742822 -385.00551) (xy 94.790108 -385.012973) (xy 94.835651 -385.027719)
			(xy 94.878338 -385.049388) (xy 94.917123 -385.077448) (xy 94.951058 -385.111213) (xy 94.979312 -385.149858)
			(xy 94.990666 -385.170934) (xy 94.991174 -385.17195) (xy 95.07148 -385.310888) (xy 95.613728 -385.310888)
			(xy 95.613728 -385.31038) (xy 95.61412 -385.286385) (xy 95.621631 -385.238985) (xy 95.636464 -385.193344)
			(xy 95.658255 -385.150585) (xy 95.686467 -385.111762) (xy 95.720405 -385.07783) (xy 95.759233 -385.049626)
			(xy 95.801996 -385.027843) (xy 95.847639 -385.013018) (xy 95.89504 -385.005515) (xy 95.919036 -385.005072)
			(xy 95.94297 -385.00555) (xy 95.990254 -385.013006) (xy 96.035797 -385.027745) (xy 96.078484 -385.049407)
			(xy 96.117269 -385.077461) (xy 96.151205 -385.11122) (xy 96.179461 -385.14986) (xy 96.190816 -385.170934)
			(xy 96.191324 -385.17195) (xy 96.27163 -385.310888) (xy 96.813624 -385.310888) (xy 96.813624 -385.31038)
			(xy 96.81402 -385.286385) (xy 96.821531 -385.238985) (xy 96.836364 -385.193345) (xy 96.858154 -385.150586)
			(xy 96.886366 -385.111764) (xy 96.920303 -385.077832) (xy 96.959131 -385.049627) (xy 97.001893 -385.027844)
			(xy 97.047536 -385.013018) (xy 97.094937 -385.005516) (xy 97.118932 -385.005072) (xy 97.142866 -385.005554)
			(xy 97.19015 -385.013009) (xy 97.235693 -385.027747) (xy 97.278379 -385.049408) (xy 97.317165 -385.077462)
			(xy 97.351101 -385.111221) (xy 97.379357 -385.14986) (xy 97.390712 -385.170934) (xy 97.39122 -385.17195)
			(xy 97.471526 -385.310888) (xy 98.01352 -385.310888) (xy 98.01352 -385.31038) (xy 98.013921 -385.286372)
			(xy 98.021439 -385.238949) (xy 98.036288 -385.193287) (xy 98.0581 -385.150512) (xy 98.086339 -385.111678)
			(xy 98.120308 -385.077742) (xy 98.15917 -385.049542) (xy 98.201966 -385.027772) (xy 98.247643 -385.012969)
			(xy 98.295074 -385.005497) (xy 98.319082 -385.005072) (xy 98.343018 -385.005513) (xy 98.390303 -385.012976)
			(xy 98.435847 -385.027721) (xy 98.478534 -385.049389) (xy 98.517319 -385.077449) (xy 98.551254 -385.111214)
			(xy 98.579508 -385.149858) (xy 98.590862 -385.170934) (xy 98.59137 -385.17195) (xy 98.9838 -385.850892)
			(xy 98.99655 -385.874249) (xy 99.01466 -385.924281) (xy 99.023862 -385.976688) (xy 99.02444 -386.003292)
			(xy 99.02393 -386.027281) (xy 99.016426 -386.07467) (xy 99.001602 -386.120301) (xy 98.979822 -386.163051)
			(xy 98.951623 -386.201869) (xy 98.917699 -386.235797) (xy 98.878886 -386.264001) (xy 98.836138 -386.285787)
			(xy 98.790509 -386.300617) (xy 98.743121 -386.308127) (xy 98.719132 -386.3086) (xy 98.695559 -386.30818)
			(xy 98.648972 -386.300944) (xy 98.604054 -386.286623) (xy 98.561875 -386.265558) (xy 98.523442 -386.238253)
			(xy 98.48967 -386.205357) (xy 98.461363 -386.167654) (xy 98.449892 -386.147056) (xy 98.449384 -386.146294)
			(xy 98.05162 -385.457954) (xy 98.039687 -385.435294) (xy 98.022756 -385.386965) (xy 98.014103 -385.336491)
			(xy 98.01352 -385.310888) (xy 97.471526 -385.310888) (xy 97.78365 -385.850892) (xy 97.796476 -385.874224)
			(xy 97.814695 -385.924247) (xy 97.823955 -385.976673) (xy 97.824544 -386.003292) (xy 97.824054 -386.027296)
			(xy 97.816541 -386.074712) (xy 97.801701 -386.120368) (xy 97.779897 -386.163139) (xy 97.751669 -386.20197)
			(xy 97.71771 -386.235905) (xy 97.67886 -386.264107) (xy 97.636074 -386.285881) (xy 97.590407 -386.30069)
			(xy 97.542986 -386.30817) (xy 97.518982 -386.3086) (xy 97.495407 -386.308221) (xy 97.448819 -386.300977)
			(xy 97.4039 -386.286648) (xy 97.361721 -386.265577) (xy 97.323288 -386.238265) (xy 97.289517 -386.205364)
			(xy 97.261212 -386.167657) (xy 97.249742 -386.147056) (xy 97.249234 -386.146294) (xy 96.85147 -385.457954)
			(xy 96.839612 -385.435268) (xy 96.822755 -385.386939) (xy 96.814174 -385.33648) (xy 96.813624 -385.310888)
			(xy 96.27163 -385.310888) (xy 96.583754 -385.850892) (xy 96.59658 -385.874224) (xy 96.614799 -385.924247)
			(xy 96.624059 -385.976673) (xy 96.624648 -386.003292) (xy 96.624154 -386.027296) (xy 96.616641 -386.074711)
			(xy 96.601801 -386.120367) (xy 96.579998 -386.163138) (xy 96.55177 -386.201969) (xy 96.517812 -386.235904)
			(xy 96.478962 -386.264106) (xy 96.436177 -386.28588) (xy 96.390511 -386.30069) (xy 96.34309 -386.30817)
			(xy 96.319086 -386.3086) (xy 96.295512 -386.308217) (xy 96.248923 -386.300974) (xy 96.204004 -386.286646)
			(xy 96.161826 -386.265576) (xy 96.123393 -386.238264) (xy 96.089621 -386.205363) (xy 96.061316 -386.167656)
			(xy 96.049846 -386.147056) (xy 96.049338 -386.146294) (xy 95.651574 -385.457954) (xy 95.639717 -385.435268)
			(xy 95.622859 -385.386939) (xy 95.614278 -385.336479) (xy 95.613728 -385.310888) (xy 95.07148 -385.310888)
			(xy 95.383604 -385.850892) (xy 95.396355 -385.874249) (xy 95.414464 -385.924281) (xy 95.423666 -385.976688)
			(xy 95.424244 -386.003292) (xy 95.42373 -386.027281) (xy 95.416226 -386.074669) (xy 95.401402 -386.1203)
			(xy 95.379623 -386.16305) (xy 95.351424 -386.201867) (xy 95.317501 -386.235796) (xy 95.278688 -386.264)
			(xy 95.235941 -386.285785) (xy 95.190312 -386.300616) (xy 95.142925 -386.308127) (xy 95.118936 -386.3086)
			(xy 95.095363 -386.308177) (xy 95.048776 -386.300941) (xy 95.003858 -386.286621) (xy 94.96168 -386.265557)
			(xy 94.923246 -386.238252) (xy 94.889474 -386.205356) (xy 94.861167 -386.167654) (xy 94.849696 -386.147056)
			(xy 94.849188 -386.146294) (xy 94.451424 -385.457954) (xy 94.439492 -385.435294) (xy 94.42256 -385.386965)
			(xy 94.413907 -385.336491) (xy 94.413324 -385.310888) (xy 93.871584 -385.310888) (xy 94.183708 -385.850892)
			(xy 94.196459 -385.874248) (xy 94.214568 -385.924281) (xy 94.22377 -385.976688) (xy 94.224348 -386.003292)
			(xy 94.22383 -386.027281) (xy 94.216326 -386.074669) (xy 94.201503 -386.120299) (xy 94.179724 -386.163049)
			(xy 94.151525 -386.201866) (xy 94.117603 -386.235794) (xy 94.07879 -386.263998) (xy 94.036043 -386.285784)
			(xy 93.990415 -386.300615) (xy 93.943029 -386.308126) (xy 93.91904 -386.3086) (xy 93.895467 -386.308174)
			(xy 93.84888 -386.300939) (xy 93.803963 -386.286618) (xy 93.761784 -386.265555) (xy 93.723351 -386.238251)
			(xy 93.689578 -386.205355) (xy 93.661271 -386.167654) (xy 93.6498 -386.147056) (xy 93.649292 -386.146294)
			(xy 93.251528 -385.457954) (xy 93.239596 -385.435294) (xy 93.222664 -385.386965) (xy 93.214011 -385.336491)
			(xy 93.213428 -385.310888) (xy 92.671688 -385.310888) (xy 92.983812 -385.850892) (xy 92.996616 -385.874226)
			(xy 93.014757 -385.924258) (xy 93.023933 -385.976681) (xy 93.024452 -386.003292) (xy 93.023982 -386.027285)
			(xy 93.016477 -386.07468) (xy 93.001651 -386.120318) (xy 92.979869 -386.163075) (xy 92.951666 -386.201898)
			(xy 92.917738 -386.235832) (xy 92.878919 -386.264041) (xy 92.836166 -386.285831) (xy 92.790531 -386.300665)
			(xy 92.743137 -386.308178) (xy 92.719144 -386.3086) (xy 92.709531 -386.308554) (xy 92.69034 -386.30741)
			(xy 92.68079 -386.306314) (xy 92.669106 -386.30479) (xy 92.647008 -386.31241) (xy 92.638626 -386.320792)
			(xy 92.631789 -386.328156) (xy 92.624053 -386.346684) (xy 92.624062 -386.366762) (xy 92.631815 -386.385283)
			(xy 92.638626 -386.392674) (xy 93.001592 -386.75564) (xy 93.025976 -386.763006) (xy 93.038676 -386.760212)
			(xy 93.055377 -386.756967) (xy 93.089227 -386.753529) (xy 93.10624 -386.753354) (xy 93.132226 -386.753866)
			(xy 93.183558 -386.762002) (xy 93.232986 -386.778066) (xy 93.279292 -386.801663) (xy 93.321338 -386.832213)
			(xy 93.358088 -386.868963) (xy 93.388638 -386.911009) (xy 93.412235 -386.957316) (xy 93.428299 -387.006744)
			(xy 93.436434 -387.058076) (xy 93.436948 -387.084062) (xy 93.436755 -387.101074) (xy 93.433318 -387.134922)
			(xy 93.43009 -387.151626) (xy 93.427296 -387.164326) (xy 93.434662 -387.18871) (xy 93.895418 -387.649466)
			(xy 93.902816 -387.656313) (xy 93.921414 -387.664047) (xy 93.931486 -387.664452) (xy 94.091506 -387.664452)
			(xy 94.119192 -387.6421) (xy 94.123002 -387.62432) (xy 94.12906 -387.598556) (xy 94.148257 -387.549238)
			(xy 94.175063 -387.503606) (xy 94.208795 -387.462827) (xy 94.248591 -387.42794) (xy 94.293436 -387.399836)
			(xy 94.342183 -387.379234) (xy 94.39359 -387.366658) (xy 94.446344 -387.36243) (xy 94.499098 -387.366658)
			(xy 94.550505 -387.379234) (xy 94.599252 -387.399836) (xy 94.644097 -387.42794) (xy 94.683893 -387.462827)
			(xy 94.717625 -387.503606) (xy 94.744431 -387.549238) (xy 94.763628 -387.598556) (xy 94.769686 -387.62432)
			(xy 94.773496 -387.6421) (xy 94.801182 -387.664452) (xy 95.291402 -387.664452) (xy 95.319088 -387.6421)
			(xy 95.322898 -387.62432) (xy 95.328956 -387.598556) (xy 95.348153 -387.549238) (xy 95.374959 -387.503606)
			(xy 95.408691 -387.462827) (xy 95.448487 -387.42794) (xy 95.493332 -387.399836) (xy 95.542079 -387.379234)
			(xy 95.593486 -387.366658) (xy 95.64624 -387.36243) (xy 95.698994 -387.366658) (xy 95.750401 -387.379234)
			(xy 95.799148 -387.399836) (xy 95.843993 -387.42794) (xy 95.883789 -387.462827) (xy 95.917521 -387.503606)
			(xy 95.944327 -387.549238) (xy 95.963524 -387.598556) (xy 95.969582 -387.62432) (xy 95.973392 -387.6421)
			(xy 96.001078 -387.664452) (xy 96.491552 -387.664452) (xy 96.519238 -387.6421) (xy 96.523048 -387.62432)
			(xy 96.529106 -387.598556) (xy 96.548303 -387.549238) (xy 96.575109 -387.503606) (xy 96.608841 -387.462827)
			(xy 96.648637 -387.42794) (xy 96.693482 -387.399836) (xy 96.742229 -387.379234) (xy 96.793636 -387.366658)
			(xy 96.84639 -387.36243) (xy 96.899144 -387.366658) (xy 96.950551 -387.379234) (xy 96.999298 -387.399836)
			(xy 97.044143 -387.42794) (xy 97.083939 -387.462827) (xy 97.117671 -387.503606) (xy 97.144477 -387.549238)
			(xy 97.163674 -387.598556) (xy 97.169732 -387.62432) (xy 97.173542 -387.6421) (xy 97.201228 -387.664452)
			(xy 97.691448 -387.664452) (xy 97.719134 -387.6421) (xy 97.722944 -387.62432) (xy 97.729002 -387.598556)
			(xy 97.748199 -387.549238) (xy 97.775005 -387.503606) (xy 97.808737 -387.462827) (xy 97.848533 -387.42794)
			(xy 97.893378 -387.399836) (xy 97.942125 -387.379234) (xy 97.993532 -387.366658) (xy 98.046286 -387.36243)
			(xy 98.09904 -387.366658) (xy 98.150447 -387.379234) (xy 98.199194 -387.399836) (xy 98.244039 -387.42794)
			(xy 98.283835 -387.462827) (xy 98.317567 -387.503606) (xy 98.344373 -387.549238) (xy 98.36357 -387.598556)
			(xy 98.369628 -387.62432) (xy 98.373438 -387.6421) (xy 98.401124 -387.664452) (xy 101.934518 -387.664452)
			(xy 101.944586 -387.664024) (xy 101.963181 -387.6563) (xy 101.970586 -387.649466) (xy 102.089458 -387.530594)
			(xy 102.092252 -387.493002) (xy 102.080568 -387.477508) (xy 102.068631 -387.460908) (xy 102.049658 -387.424693)
			(xy 102.036729 -387.385906) (xy 102.03018 -387.34555) (xy 102.029768 -387.325108) (xy 102.029768 -386.689346)
			(xy 102.030339 -386.66525) (xy 102.039437 -386.617925) (xy 102.057296 -386.573164) (xy 102.083275 -386.532574)
			(xy 102.116443 -386.497612) (xy 102.135686 -386.483098) (xy 102.145113 -386.475438) (xy 102.156124 -386.453825)
			(xy 102.156768 -386.441696) (xy 102.156768 -386.32003) (xy 102.157339 -386.303458) (xy 102.165959 -386.271452)
			(xy 102.182546 -386.242753) (xy 102.193852 -386.230622) (xy 102.319582 -386.105146) (xy 102.326422 -386.097746)
			(xy 102.33414 -386.079147) (xy 102.334568 -386.069078) (xy 102.334568 -384.86842) (xy 102.333947 -384.856283)
			(xy 102.322936 -384.834659) (xy 102.313486 -384.827018) (xy 102.294231 -384.812518) (xy 102.261061 -384.777555)
			(xy 102.235083 -384.736962) (xy 102.217229 -384.692197) (xy 102.208142 -384.644867) (xy 102.207568 -384.62077)
			(xy 102.207568 -383.94132) (xy 102.20713 -383.931257) (xy 102.199391 -383.912677) (xy 102.192582 -383.905252)
			(xy 102.091236 -383.803906) (xy 102.083834 -383.797069) (xy 102.065236 -383.789357) (xy 102.055168 -383.78892)
			(xy 87.192104 -383.78892) (xy 87.182034 -383.789343) (xy 87.16343 -383.797058) (xy 87.156036 -383.803906)
			(xy 86.875112 -384.08483) (xy 86.868269 -384.09223) (xy 86.860544 -384.110828) (xy 86.860126 -384.120898)
			(xy 86.860126 -385.310888) (xy 87.21344 -385.310888) (xy 87.21344 -385.31038) (xy 87.213821 -385.286371)
			(xy 87.22134 -385.238946) (xy 87.23619 -385.193282) (xy 87.258004 -385.150506) (xy 87.286245 -385.111671)
			(xy 87.320216 -385.077735) (xy 87.359081 -385.049535) (xy 87.40188 -385.027766) (xy 87.44756 -385.012965)
			(xy 87.494993 -385.005496) (xy 87.519002 -385.005072) (xy 87.542935 -385.005578) (xy 87.590218 -385.013028)
			(xy 87.63576 -385.027763) (xy 87.678447 -385.04942) (xy 87.717233 -385.077469) (xy 87.75117 -385.111225)
			(xy 87.779426 -385.149861) (xy 87.790782 -385.170934) (xy 87.79129 -385.17195) (xy 87.871596 -385.310888)
			(xy 88.413336 -385.310888) (xy 88.413336 -385.31038) (xy 88.413721 -385.286371) (xy 88.42124 -385.238947)
			(xy 88.436089 -385.193283) (xy 88.457903 -385.150507) (xy 88.486144 -385.111672) (xy 88.520115 -385.077737)
			(xy 88.558979 -385.049537) (xy 88.601777 -385.027767) (xy 88.647456 -385.012965) (xy 88.694889 -385.005496)
			(xy 88.718898 -385.005072) (xy 88.742834 -385.0055) (xy 88.790121 -385.012965) (xy 88.835664 -385.027713)
			(xy 88.878351 -385.049383) (xy 88.917136 -385.077445) (xy 88.95107 -385.111212) (xy 88.979324 -385.149857)
			(xy 88.990678 -385.170934) (xy 88.991186 -385.17195) (xy 89.071492 -385.310888) (xy 89.61374 -385.310888)
			(xy 89.61374 -385.31038) (xy 89.61412 -385.286384) (xy 89.621631 -385.238983) (xy 89.636465 -385.193341)
			(xy 89.658257 -385.150582) (xy 89.68647 -385.111758) (xy 89.72041 -385.077826) (xy 89.75924 -385.049622)
			(xy 89.802004 -385.027839) (xy 89.847649 -385.013015) (xy 89.895052 -385.005515) (xy 89.919048 -385.005072)
			(xy 89.942983 -385.005541) (xy 89.990267 -385.012998) (xy 90.03581 -385.027739) (xy 90.078497 -385.049402)
			(xy 90.117282 -385.077458) (xy 90.151218 -385.111219) (xy 90.179473 -385.149859) (xy 90.190828 -385.170934)
			(xy 90.191336 -385.17195) (xy 90.583766 -385.850892) (xy 90.596593 -385.874223) (xy 90.614812 -385.924247)
			(xy 90.624071 -385.976673) (xy 90.62466 -386.003292) (xy 90.624253 -386.0273) (xy 90.616738 -386.074724)
			(xy 90.601893 -386.120388) (xy 90.580082 -386.163164) (xy 90.551844 -386.201999) (xy 90.517875 -386.235935)
			(xy 90.479013 -386.264136) (xy 90.436216 -386.285905) (xy 90.390538 -386.300707) (xy 90.343106 -386.308176)
			(xy 90.319098 -386.3086) (xy 90.295524 -386.308208) (xy 90.248936 -386.300966) (xy 90.204017 -386.28664)
			(xy 90.161839 -386.265571) (xy 90.123406 -386.238261) (xy 90.089634 -386.205361) (xy 90.061328 -386.167656)
			(xy 90.049858 -386.147056) (xy 90.04935 -386.146294) (xy 89.651586 -385.457954) (xy 89.63973 -385.435267)
			(xy 89.622871 -385.386939) (xy 89.61429 -385.336479) (xy 89.61374 -385.310888) (xy 89.071492 -385.310888)
			(xy 89.383616 -385.850892) (xy 89.396368 -385.874248) (xy 89.414476 -385.924281) (xy 89.423678 -385.976688)
			(xy 89.424256 -386.003292) (xy 89.42373 -386.027281) (xy 89.416227 -386.074667) (xy 89.401403 -386.120297)
			(xy 89.379625 -386.163047) (xy 89.351428 -386.201863) (xy 89.317506 -386.235791) (xy 89.278694 -386.263996)
			(xy 89.235949 -386.285782) (xy 89.190322 -386.300614) (xy 89.142937 -386.308126) (xy 89.118948 -386.3086)
			(xy 89.095375 -386.308168) (xy 89.048789 -386.300933) (xy 89.003871 -386.286614) (xy 88.961693 -386.265552)
			(xy 88.923259 -386.238248) (xy 88.889486 -386.205354) (xy 88.861179 -386.167654) (xy 88.849708 -386.147056)
			(xy 88.8492 -386.146294) (xy 88.451436 -385.457954) (xy 88.439505 -385.435294) (xy 88.422572 -385.386964)
			(xy 88.413919 -385.336491) (xy 88.413336 -385.310888) (xy 87.871596 -385.310888) (xy 88.18372 -385.850892)
			(xy 88.196472 -385.874248) (xy 88.21458 -385.924281) (xy 88.223782 -385.976688) (xy 88.22436 -386.003292)
			(xy 88.223954 -386.027287) (xy 88.216447 -386.074687) (xy 88.201617 -386.120329) (xy 88.179828 -386.163088)
			(xy 88.151618 -386.201912) (xy 88.117682 -386.235844) (xy 88.078854 -386.264049) (xy 88.036092 -386.285832)
			(xy 87.990448 -386.300657) (xy 87.943047 -386.308157) (xy 87.919052 -386.3086) (xy 87.895479 -386.308164)
			(xy 87.848893 -386.300931) (xy 87.803976 -386.286612) (xy 87.761797 -386.265551) (xy 87.723364 -386.238247)
			(xy 87.689591 -386.205354) (xy 87.661283 -386.167653) (xy 87.649812 -386.147056) (xy 87.649304 -386.146294)
			(xy 87.25154 -385.457954) (xy 87.239609 -385.435293) (xy 87.222676 -385.386964) (xy 87.214023 -385.336491)
			(xy 87.21344 -385.310888) (xy 86.860126 -385.310888) (xy 86.860126 -385.623054) (xy 86.860327 -385.62972)
			(xy 86.863809 -385.642588) (xy 86.866984 -385.648454) (xy 86.983824 -385.850892) (xy 86.996627 -385.874226)
			(xy 87.014768 -385.924258) (xy 87.023943 -385.976681) (xy 87.024464 -386.003292) (xy 87.02395 -386.028812)
			(xy 87.015463 -386.079141) (xy 86.998723 -386.127357) (xy 86.974198 -386.172118) (xy 86.94257 -386.212176)
			(xy 86.90472 -386.246417) (xy 86.883494 -386.260594) (xy 86.876497 -386.265474) (xy 86.865964 -386.278881)
			(xy 86.860395 -386.294995) (xy 86.860126 -386.30352) (xy 86.860126 -387.671564) (xy 86.860561 -387.681628)
			(xy 86.868295 -387.700214) (xy 86.875112 -387.707632) (xy 87.132922 -387.965442) (xy 87.140319 -387.972291)
			(xy 87.158918 -387.980027) (xy 87.16899 -387.980428)
		)
		(stroke
			(width 0)
			(type solid)
		)
		(fill yes)
		(layer "In8.Cu")
		(net "P1V8_CPU1_RT1_1A")
	)
	(gr_poly
		(pts
			(xy 311.646062 -396.5321) (xy 311.657169 -396.531534) (xy 311.677318 -396.52218) (xy 311.684924 -396.514066)
			(xy 311.700842 -396.49586) (xy 311.73742 -396.464227) (xy 311.77853 -396.438763) (xy 311.823144 -396.420104)
			(xy 311.870143 -396.408718) (xy 311.91835 -396.404891) (xy 311.966557 -396.408718) (xy 312.013556 -396.420104)
			(xy 312.05817 -396.438763) (xy 312.09928 -396.464227) (xy 312.135858 -396.49586) (xy 312.151776 -396.514066)
			(xy 312.15937 -396.522192) (xy 312.179529 -396.531527) (xy 312.190638 -396.5321) (xy 312.845958 -396.5321)
			(xy 312.857065 -396.531535) (xy 312.877215 -396.522182) (xy 312.88482 -396.514066) (xy 312.902383 -396.494078)
			(xy 312.943166 -396.459911) (xy 312.989253 -396.43333) (xy 313.039251 -396.41514) (xy 313.091644 -396.405892)
			(xy 313.118246 -396.405354) (xy 313.144973 -396.405902) (xy 313.197607 -396.415224) (xy 313.222894 -396.423896)
			(xy 313.236864 -396.428976) (xy 313.265566 -396.422626) (xy 314.908692 -394.7795) (xy 314.923678 -394.765784)
			(xy 314.931675 -394.758248) (xy 314.940891 -394.738325) (xy 314.940957 -394.716374) (xy 314.931859 -394.696396)
			(xy 314.915258 -394.682035) (xy 314.904882 -394.678408) (xy 314.881726 -394.671093) (xy 314.83791 -394.650162)
			(xy 314.797961 -394.622558) (xy 314.762885 -394.588979) (xy 314.733567 -394.550269) (xy 314.721748 -394.529056)
			(xy 314.72124 -394.528294) (xy 314.323476 -393.839954) (xy 314.311539 -393.817294) (xy 314.294582 -393.76897)
			(xy 314.285932 -393.718493) (xy 314.285376 -393.692888) (xy 314.285376 -393.69238) (xy 314.285881 -393.667453)
			(xy 314.294032 -393.618269) (xy 314.31011 -393.571078) (xy 314.321444 -393.54887) (xy 314.321444 -393.548616)
			(xy 314.333087 -393.52771) (xy 314.361866 -393.489481) (xy 314.396256 -393.456209) (xy 314.435413 -393.428707)
			(xy 314.47838 -393.407648) (xy 314.524106 -393.393548) (xy 314.571472 -393.386752) (xy 314.619317 -393.387425)
			(xy 314.666473 -393.395553) (xy 314.711783 -393.410935) (xy 314.75414 -393.433196) (xy 314.792508 -393.46179)
			(xy 314.825946 -393.496017) (xy 314.853637 -393.535041) (xy 314.86475 -393.556236) (xy 314.865512 -393.55776)
			(xy 314.929947 -393.669225) (xy 315.485986 -393.669225) (xy 315.493312 -393.621681) (xy 315.507999 -393.575872)
			(xy 315.529685 -393.532932) (xy 315.557833 -393.493922) (xy 315.591748 -393.459806) (xy 315.630591 -393.431428)
			(xy 315.673402 -393.409489) (xy 315.719123 -393.394531) (xy 315.766623 -393.386925) (xy 315.814729 -393.386858)
			(xy 315.86225 -393.394332) (xy 315.908012 -393.409163) (xy 315.950884 -393.430983) (xy 315.989806 -393.459253)
			(xy 316.023816 -393.493274) (xy 316.052072 -393.532206) (xy 316.063376 -393.553442) (xy 316.063884 -393.554712)
			(xy 316.143736 -393.692888) (xy 316.685676 -393.692888) (xy 316.685676 -393.69238) (xy 316.686166 -393.667466)
			(xy 316.694263 -393.6183) (xy 316.710223 -393.571096) (xy 316.72149 -393.54887) (xy 316.72149 -393.548616)
			(xy 316.733168 -393.527733) (xy 316.761958 -393.489523) (xy 316.796353 -393.456267) (xy 316.83551 -393.428779)
			(xy 316.878474 -393.407731) (xy 316.924194 -393.393637) (xy 316.971551 -393.386841) (xy 317.019389 -393.387511)
			(xy 317.066538 -393.395629) (xy 317.111845 -393.410998) (xy 317.154203 -393.43324) (xy 317.192576 -393.461814)
			(xy 317.226025 -393.496019) (xy 317.253735 -393.535021) (xy 317.264796 -393.556236) (xy 317.265558 -393.55776)
			(xy 317.329994 -393.669227) (xy 317.885945 -393.669227) (xy 317.893271 -393.621675) (xy 317.90796 -393.575859)
			(xy 317.929649 -393.532911) (xy 317.957803 -393.493895) (xy 317.991723 -393.459773) (xy 318.030573 -393.431391)
			(xy 318.073392 -393.409449) (xy 318.119121 -393.39449) (xy 318.166629 -393.386884) (xy 318.214742 -393.386818)
			(xy 318.262271 -393.394295) (xy 318.30804 -393.40913) (xy 318.350919 -393.430956) (xy 318.389845 -393.459233)
			(xy 318.423859 -393.493262) (xy 318.452118 -393.532202) (xy 318.463422 -393.553442) (xy 318.46393 -393.554712)
			(xy 318.543782 -393.692888) (xy 319.085468 -393.692888) (xy 319.085468 -393.69238) (xy 319.085963 -393.667452)
			(xy 319.094114 -393.618266) (xy 319.110192 -393.571073) (xy 319.121536 -393.54887) (xy 319.121536 -393.548616)
			(xy 319.133145 -393.527693) (xy 319.161942 -393.489479) (xy 319.196343 -393.456222) (xy 319.235508 -393.428733)
			(xy 319.278479 -393.407685) (xy 319.324205 -393.393592) (xy 319.37157 -393.386799) (xy 319.419414 -393.387472)
			(xy 319.466568 -393.395595) (xy 319.51188 -393.410968) (xy 319.554242 -393.433217) (xy 319.592618 -393.461796)
			(xy 319.62607 -393.496009) (xy 319.653781 -393.535017) (xy 319.664842 -393.556236) (xy 319.665604 -393.55776)
			(xy 319.730039 -393.669225) (xy 320.286093 -393.669225) (xy 320.293419 -393.621682) (xy 320.308106 -393.575875)
			(xy 320.329791 -393.532936) (xy 320.357938 -393.493927) (xy 320.391852 -393.459812) (xy 320.430694 -393.431435)
			(xy 320.473504 -393.409496) (xy 320.519224 -393.394539) (xy 320.566722 -393.386932) (xy 320.614826 -393.386865)
			(xy 320.662346 -393.394339) (xy 320.708107 -393.409169) (xy 320.750978 -393.430987) (xy 320.789899 -393.459256)
			(xy 320.823908 -393.493277) (xy 320.852164 -393.532207) (xy 320.863468 -393.553442) (xy 320.863976 -393.554712)
			(xy 320.930153 -393.669224) (xy 321.485997 -393.669224) (xy 321.493322 -393.621682) (xy 321.508009 -393.575876)
			(xy 321.529694 -393.532938) (xy 321.557841 -393.493929) (xy 321.591754 -393.459815) (xy 321.630596 -393.431438)
			(xy 321.673405 -393.409499) (xy 321.719124 -393.394542) (xy 321.766622 -393.386936) (xy 321.814725 -393.386869)
			(xy 321.862244 -393.394342) (xy 321.908005 -393.409171) (xy 321.950875 -393.43099) (xy 321.989796 -393.459258)
			(xy 322.023804 -393.493278) (xy 322.052061 -393.532207) (xy 322.063364 -393.553442) (xy 322.063872 -393.554712)
			(xy 322.455794 -394.232892) (xy 322.456048 -394.2334) (xy 322.456302 -394.2334) (xy 322.457572 -394.23594)
			(xy 322.469822 -394.258867) (xy 322.487237 -394.307839) (xy 322.49612 -394.359051) (xy 322.496688 -394.385038)
			(xy 322.496688 -394.385292) (xy 322.496253 -394.409299) (xy 322.488739 -394.45672) (xy 322.473895 -394.502381)
			(xy 322.452087 -394.545156) (xy 322.423852 -394.58399) (xy 322.389887 -394.617925) (xy 322.351029 -394.646126)
			(xy 322.308235 -394.667897) (xy 322.262561 -394.682702) (xy 322.215133 -394.690174) (xy 322.191126 -394.6906)
			(xy 322.167461 -394.690167) (xy 322.120698 -394.682859) (xy 322.075621 -394.668429) (xy 322.033308 -394.647222)
			(xy 321.99477 -394.619746) (xy 321.960928 -394.586656) (xy 321.932592 -394.548745) (xy 321.921124 -394.52804)
			(xy 321.92087 -394.527278) (xy 321.523614 -393.839954) (xy 321.511421 -393.816744) (xy 321.494316 -393.767188)
			(xy 321.489578 -393.741402) (xy 321.489578 -393.741148) (xy 321.486214 -393.717327) (xy 321.485997 -393.669224)
			(xy 320.930153 -393.669224) (xy 321.255898 -394.232892) (xy 321.256152 -394.2334) (xy 321.256406 -394.2334)
			(xy 321.257676 -394.23594) (xy 321.269926 -394.258866) (xy 321.287341 -394.307839) (xy 321.296224 -394.359051)
			(xy 321.296792 -394.385038) (xy 321.296792 -394.385292) (xy 321.296353 -394.409298) (xy 321.28884 -394.45672)
			(xy 321.273996 -394.50238) (xy 321.252188 -394.545155) (xy 321.223953 -394.583988) (xy 321.189989 -394.617924)
			(xy 321.151131 -394.646125) (xy 321.108338 -394.667896) (xy 321.062664 -394.682701) (xy 321.015237 -394.690174)
			(xy 320.99123 -394.6906) (xy 320.967565 -394.690164) (xy 320.920803 -394.682856) (xy 320.875726 -394.668427)
			(xy 320.833412 -394.647221) (xy 320.794874 -394.619745) (xy 320.761032 -394.586656) (xy 320.732696 -394.548745)
			(xy 320.721228 -394.52804) (xy 320.720974 -394.527278) (xy 320.323718 -393.839954) (xy 320.311526 -393.816744)
			(xy 320.29442 -393.767188) (xy 320.289682 -393.741402) (xy 320.289682 -393.741148) (xy 320.28631 -393.717328)
			(xy 320.286093 -393.669225) (xy 319.730039 -393.669225) (xy 320.037968 -394.201904) (xy 320.038222 -394.202412)
			(xy 320.05778 -394.23594) (xy 320.07003 -394.258866) (xy 320.087445 -394.307839) (xy 320.096328 -394.359051)
			(xy 320.096896 -394.385038) (xy 320.096896 -394.385292) (xy 320.096453 -394.409298) (xy 320.08894 -394.456719)
			(xy 320.074096 -394.502379) (xy 320.052288 -394.545153) (xy 320.024055 -394.583987) (xy 319.99009 -394.617922)
			(xy 319.951233 -394.646123) (xy 319.908441 -394.667895) (xy 319.862768 -394.6827) (xy 319.815341 -394.690174)
			(xy 319.791334 -394.6906) (xy 319.79108 -394.6906) (xy 319.767505 -394.690222) (xy 319.720916 -394.682978)
			(xy 319.675997 -394.668649) (xy 319.633819 -394.647578) (xy 319.595386 -394.620266) (xy 319.561615 -394.587364)
			(xy 319.53331 -394.549657) (xy 319.52184 -394.529056) (xy 319.521332 -394.528294) (xy 319.123568 -393.839954)
			(xy 319.111639 -393.817292) (xy 319.094706 -393.768964) (xy 319.086052 -393.718491) (xy 319.085468 -393.692888)
			(xy 318.543782 -393.692888) (xy 318.855852 -394.232892) (xy 318.856106 -394.2334) (xy 318.85636 -394.2334)
			(xy 318.85763 -394.23594) (xy 318.869845 -394.258873) (xy 318.887171 -394.307855) (xy 318.895966 -394.35906)
			(xy 318.896492 -394.385038) (xy 318.896492 -394.385292) (xy 318.896054 -394.409286) (xy 318.888548 -394.456682)
			(xy 318.87372 -394.502321) (xy 318.851934 -394.545079) (xy 318.823728 -394.583901) (xy 318.789795 -394.617833)
			(xy 318.750972 -394.646038) (xy 318.708214 -394.667823) (xy 318.662575 -394.68265) (xy 318.615178 -394.690155)
			(xy 318.591184 -394.6906) (xy 318.567518 -394.690201) (xy 318.520753 -394.682887) (xy 318.475676 -394.668451)
			(xy 318.433362 -394.647238) (xy 318.394825 -394.619757) (xy 318.360984 -394.586662) (xy 318.33265 -394.548747)
			(xy 318.321182 -394.52804) (xy 318.320928 -394.527278) (xy 317.923672 -393.839954) (xy 317.911483 -393.816742)
			(xy 317.894374 -393.767188) (xy 317.889636 -393.741402) (xy 317.889636 -393.741148) (xy 317.886163 -393.71734)
			(xy 317.885945 -393.669227) (xy 317.329994 -393.669227) (xy 317.637922 -394.201904) (xy 317.638176 -394.202412)
			(xy 317.657734 -394.23594) (xy 317.669949 -394.258873) (xy 317.687275 -394.307854) (xy 317.69607 -394.35906)
			(xy 317.696596 -394.385038) (xy 317.696596 -394.385292) (xy 317.696154 -394.409286) (xy 317.688648 -394.456682)
			(xy 317.67382 -394.50232) (xy 317.652035 -394.545077) (xy 317.623829 -394.5839) (xy 317.589897 -394.617831)
			(xy 317.551074 -394.646037) (xy 317.508317 -394.667822) (xy 317.462678 -394.682649) (xy 317.415282 -394.690155)
			(xy 317.391288 -394.6906) (xy 317.391034 -394.6906) (xy 317.367461 -394.690179) (xy 317.320874 -394.682942)
			(xy 317.275956 -394.668622) (xy 317.233778 -394.647557) (xy 317.195344 -394.620252) (xy 317.161572 -394.587356)
			(xy 317.133265 -394.549654) (xy 317.121794 -394.529056) (xy 317.121286 -394.528294) (xy 316.723522 -393.839954)
			(xy 316.711661 -393.81727) (xy 316.694805 -393.76894) (xy 316.686226 -393.71848) (xy 316.685676 -393.692888)
			(xy 316.143736 -393.692888) (xy 316.455806 -394.232892) (xy 316.45606 -394.2334) (xy 316.456314 -394.2334)
			(xy 316.457584 -394.23594) (xy 316.469835 -394.258866) (xy 316.487249 -394.307839) (xy 316.496132 -394.359051)
			(xy 316.4967 -394.385038) (xy 316.4967 -394.385292) (xy 316.496254 -394.409298) (xy 316.48874 -394.456718)
			(xy 316.473896 -394.502378) (xy 316.452089 -394.545152) (xy 316.423856 -394.583985) (xy 316.389892 -394.617921)
			(xy 316.351035 -394.646122) (xy 316.308243 -394.667894) (xy 316.262571 -394.682699) (xy 316.215144 -394.690173)
			(xy 316.191138 -394.6906) (xy 316.167473 -394.690157) (xy 316.120711 -394.682851) (xy 316.075634 -394.668423)
			(xy 316.033321 -394.647218) (xy 315.994782 -394.619743) (xy 315.960941 -394.586655) (xy 315.932604 -394.548745)
			(xy 315.921136 -394.52804) (xy 315.920882 -394.527278) (xy 315.523626 -393.839954) (xy 315.511434 -393.816744)
			(xy 315.494328 -393.767188) (xy 315.48959 -393.741402) (xy 315.48959 -393.741148) (xy 315.486203 -393.71733)
			(xy 315.485986 -393.669225) (xy 314.929947 -393.669225) (xy 315.237876 -394.201904) (xy 315.23813 -394.202412)
			(xy 315.257688 -394.23594) (xy 315.26996 -394.258856) (xy 315.287376 -394.307832) (xy 315.296252 -394.359049)
			(xy 315.296804 -394.385038) (xy 315.296804 -394.385292) (xy 315.29655 -394.395706) (xy 315.296042 -394.405866)
			(xy 315.3029 -394.424408) (xy 315.365384 -394.491972) (xy 315.383164 -394.500354) (xy 315.393324 -394.500608)
			(xy 315.417955 -394.502179) (xy 315.46638 -394.511714) (xy 315.512848 -394.528344) (xy 315.556327 -394.551698)
			(xy 315.59585 -394.581257) (xy 315.630538 -394.616365) (xy 315.65962 -394.65624) (xy 315.671454 -394.6779)
			(xy 315.678058 -394.690346) (xy 315.702188 -394.705078) (xy 315.789056 -394.705078) (xy 315.814011 -394.705695)
			(xy 315.862959 -394.715441) (xy 315.909067 -394.734548) (xy 315.950561 -394.762281) (xy 315.968634 -394.7795)
			(xy 316.369446 -395.180312) (xy 316.402974 -395.185138) (xy 316.41796 -395.176756) (xy 316.442652 -395.163747)
			(xy 316.495317 -395.145288) (xy 316.550331 -395.13592) (xy 316.578234 -395.135354) (xy 316.604221 -395.135866)
			(xy 316.655553 -395.144001) (xy 316.704982 -395.160064) (xy 316.751289 -395.183661) (xy 316.793336 -395.214211)
			(xy 316.830087 -395.250961) (xy 316.860637 -395.293007) (xy 316.884234 -395.339315) (xy 316.900298 -395.388743)
			(xy 316.908434 -395.440075) (xy 316.908942 -395.466062) (xy 316.908367 -395.493966) (xy 316.899013 -395.548983)
			(xy 316.880564 -395.601652) (xy 316.86754 -395.626336) (xy 316.859158 -395.641322) (xy 316.863984 -395.67485)
			(xy 317.235586 -396.046452) (xy 317.242987 -396.05329) (xy 317.261586 -396.061001) (xy 317.271654 -396.061438)
			(xy 317.56096 -396.061438) (xy 317.589408 -396.037562) (xy 317.592456 -396.019274) (xy 317.597324 -395.994007)
			(xy 317.613843 -395.945277) (xy 317.63771 -395.899693) (xy 317.668348 -395.858356) (xy 317.705018 -395.822262)
			(xy 317.746836 -395.792282) (xy 317.792792 -395.769141) (xy 317.841778 -395.753396) (xy 317.892611 -395.745427)
			(xy 317.944065 -395.745427) (xy 317.994898 -395.753396) (xy 318.043884 -395.769141) (xy 318.08984 -395.792282)
			(xy 318.131658 -395.822262) (xy 318.168328 -395.858356) (xy 318.198966 -395.899693) (xy 318.222833 -395.945277)
			(xy 318.239352 -395.994007) (xy 318.24422 -396.019274) (xy 318.247268 -396.037562) (xy 318.275716 -396.061438)
			(xy 318.760856 -396.061438) (xy 318.789304 -396.037562) (xy 318.792352 -396.019274) (xy 318.79722 -395.994007)
			(xy 318.813739 -395.945277) (xy 318.837606 -395.899693) (xy 318.868244 -395.858356) (xy 318.904914 -395.822262)
			(xy 318.946732 -395.792282) (xy 318.992688 -395.769141) (xy 319.041674 -395.753396) (xy 319.092507 -395.745427)
			(xy 319.143961 -395.745427) (xy 319.194794 -395.753396) (xy 319.24378 -395.769141) (xy 319.289736 -395.792282)
			(xy 319.331554 -395.822262) (xy 319.368224 -395.858356) (xy 319.398862 -395.899693) (xy 319.422729 -395.945277)
			(xy 319.439248 -395.994007) (xy 319.444116 -396.019274) (xy 319.447164 -396.037562) (xy 319.475612 -396.061438)
			(xy 319.961006 -396.061438) (xy 319.989454 -396.037562) (xy 319.992502 -396.019274) (xy 319.99737 -395.994007)
			(xy 320.013889 -395.945277) (xy 320.037756 -395.899693) (xy 320.068394 -395.858356) (xy 320.105064 -395.822262)
			(xy 320.146882 -395.792282) (xy 320.192838 -395.769141) (xy 320.241824 -395.753396) (xy 320.292657 -395.745427)
			(xy 320.344111 -395.745427) (xy 320.394944 -395.753396) (xy 320.44393 -395.769141) (xy 320.489886 -395.792282)
			(xy 320.531704 -395.822262) (xy 320.568374 -395.858356) (xy 320.599012 -395.899693) (xy 320.622879 -395.945277)
			(xy 320.639398 -395.994007) (xy 320.644266 -396.019274) (xy 320.647314 -396.037562) (xy 320.675762 -396.061438)
			(xy 321.160902 -396.061438) (xy 321.18935 -396.037562) (xy 321.192398 -396.019274) (xy 321.197266 -395.994007)
			(xy 321.213785 -395.945277) (xy 321.237652 -395.899693) (xy 321.26829 -395.858356) (xy 321.30496 -395.822262)
			(xy 321.346778 -395.792282) (xy 321.392734 -395.769141) (xy 321.44172 -395.753396) (xy 321.492553 -395.745427)
			(xy 321.544007 -395.745427) (xy 321.59484 -395.753396) (xy 321.643826 -395.769141) (xy 321.689782 -395.792282)
			(xy 321.7316 -395.822262) (xy 321.76827 -395.858356) (xy 321.798908 -395.899693) (xy 321.822775 -395.945277)
			(xy 321.839294 -395.994007) (xy 321.844162 -396.019274) (xy 321.84721 -396.037562) (xy 321.875658 -396.061438)
			(xy 325.056246 -396.061438) (xy 325.066311 -396.061005) (xy 325.084898 -396.053272) (xy 325.092314 -396.046452)
			(xy 325.51116 -395.627606) (xy 325.518012 -395.62021) (xy 325.525755 -395.601611) (xy 325.526146 -395.591538)
			(xy 325.526146 -395.12621) (xy 325.526712 -395.102112) (xy 325.535802 -395.054782) (xy 325.553657 -395.010017)
			(xy 325.579637 -394.969424) (xy 325.612807 -394.93446) (xy 325.632064 -394.919962) (xy 325.641488 -394.912301)
			(xy 325.652488 -394.890688) (xy 325.653146 -394.87856) (xy 325.653146 -394.756894) (xy 325.653708 -394.740318)
			(xy 325.662315 -394.708301) (xy 325.67889 -394.679589) (xy 325.69023 -394.667486) (xy 325.81596 -394.54201)
			(xy 325.822812 -394.534614) (xy 325.830557 -394.516016) (xy 325.830946 -394.505942) (xy 325.830946 -393.305284)
			(xy 325.83032 -393.293148) (xy 325.819311 -393.271525) (xy 325.809864 -393.263882) (xy 325.790613 -393.249381)
			(xy 325.75745 -393.214415) (xy 325.73148 -393.173821) (xy 325.713635 -393.129057) (xy 325.704555 -393.081729)
			(xy 325.703946 -393.057634) (xy 325.703946 -392.385042) (xy 325.703511 -392.374978) (xy 325.695776 -392.356394)
			(xy 325.68896 -392.348974) (xy 325.523352 -392.183366) (xy 325.515954 -392.17652) (xy 325.497355 -392.168792)
			(xy 325.487284 -392.16838) (xy 310.8706 -392.16838) (xy 310.860529 -392.168802) (xy 310.841923 -392.176515)
			(xy 310.834532 -392.183366) (xy 310.751728 -392.26617) (xy 310.734983 -392.282211) (xy 310.69681 -392.308529)
			(xy 310.654494 -392.327481) (xy 310.632094 -392.33348) (xy 310.625236 -392.335004) (xy 310.613298 -392.341862)
			(xy 310.39435 -392.56081) (xy 310.3875 -392.568207) (xy 310.379761 -392.586805) (xy 310.379364 -392.596878)
			(xy 310.379364 -393.692888) (xy 310.685688 -393.692888) (xy 310.685688 -393.69238) (xy 310.686144 -393.668388)
			(xy 310.693653 -393.620996) (xy 310.708483 -393.575362) (xy 310.730269 -393.53261) (xy 310.758474 -393.493792)
			(xy 310.792404 -393.459863) (xy 310.831224 -393.43166) (xy 310.873977 -393.409877) (xy 310.919612 -393.395049)
			(xy 310.967004 -393.387543) (xy 310.990996 -393.387072) (xy 311.014932 -393.387502) (xy 311.062218 -393.394966)
			(xy 311.107762 -393.409714) (xy 311.150449 -393.431384) (xy 311.189234 -393.459445) (xy 311.223168 -393.493212)
			(xy 311.251422 -393.531857) (xy 311.262776 -393.552934) (xy 311.263284 -393.55395) (xy 311.34359 -393.692888)
			(xy 311.885584 -393.692888) (xy 311.885584 -393.69238) (xy 311.886044 -393.668389) (xy 311.893553 -393.620997)
			(xy 311.908383 -393.575363) (xy 311.930168 -393.532611) (xy 311.958373 -393.493793) (xy 311.992302 -393.459865)
			(xy 312.031121 -393.431662) (xy 312.073874 -393.409878) (xy 312.119509 -393.39505) (xy 312.166901 -393.387543)
			(xy 312.190892 -393.387072) (xy 312.191146 -393.387072) (xy 312.215081 -393.387542) (xy 312.262365 -393.394999)
			(xy 312.307908 -393.40974) (xy 312.350594 -393.431403) (xy 312.38938 -393.459458) (xy 312.423316 -393.493219)
			(xy 312.451571 -393.531859) (xy 312.462926 -393.552934) (xy 312.463434 -393.55395) (xy 312.54374 -393.692888)
			(xy 313.08548 -393.692888) (xy 313.08548 -393.69238) (xy 313.085974 -393.667452) (xy 313.094125 -393.618266)
			(xy 313.110204 -393.571073) (xy 313.121548 -393.54887) (xy 313.121548 -393.548616) (xy 313.133139 -393.527682)
			(xy 313.161937 -393.489468) (xy 313.19634 -393.45621) (xy 313.235507 -393.428721) (xy 313.27848 -393.407673)
			(xy 313.324208 -393.39358) (xy 313.371574 -393.386788) (xy 313.41942 -393.387462) (xy 313.466576 -393.395586)
			(xy 313.51189 -393.41096) (xy 313.554252 -393.43321) (xy 313.592629 -393.461792) (xy 313.626082 -393.496006)
			(xy 313.653793 -393.535016) (xy 313.664854 -393.556236) (xy 313.665616 -393.55776) (xy 314.03798 -394.201904)
			(xy 314.038234 -394.202412) (xy 314.057792 -394.23594) (xy 314.070043 -394.258866) (xy 314.087457 -394.307839)
			(xy 314.09634 -394.359051) (xy 314.096908 -394.385038) (xy 314.096908 -394.385292) (xy 314.096454 -394.409298)
			(xy 314.08894 -394.456717) (xy 314.074097 -394.502377) (xy 314.052291 -394.54515) (xy 314.024058 -394.583983)
			(xy 313.990095 -394.617918) (xy 313.95124 -394.646119) (xy 313.908449 -394.667891) (xy 313.862778 -394.682698)
			(xy 313.815352 -394.690173) (xy 313.791346 -394.6906) (xy 313.791092 -394.6906) (xy 313.767518 -394.690213)
			(xy 313.720929 -394.68297) (xy 313.67601 -394.668643) (xy 313.633832 -394.647573) (xy 313.595399 -394.620263)
			(xy 313.561628 -394.587362) (xy 313.533322 -394.549656) (xy 313.521852 -394.529056) (xy 313.521344 -394.528294)
			(xy 313.12358 -393.839954) (xy 313.111644 -393.817296) (xy 313.094715 -393.768965) (xy 313.086063 -393.718492)
			(xy 313.08548 -393.692888) (xy 312.54374 -393.692888) (xy 312.855864 -394.232892) (xy 312.86862 -394.256246)
			(xy 312.886726 -394.30628) (xy 312.895926 -394.358688) (xy 312.896504 -394.385292) (xy 312.896054 -394.409285)
			(xy 312.888549 -394.456681) (xy 312.873721 -394.502319) (xy 312.851936 -394.545075) (xy 312.823731 -394.583897)
			(xy 312.7898 -394.617829) (xy 312.750978 -394.646034) (xy 312.708222 -394.66782) (xy 312.662585 -394.682648)
			(xy 312.615189 -394.690154) (xy 312.591196 -394.6906) (xy 312.590942 -394.6906) (xy 312.567369 -394.690172)
			(xy 312.520783 -394.682937) (xy 312.475865 -394.668617) (xy 312.433686 -394.647554) (xy 312.395253 -394.62025)
			(xy 312.36148 -394.587355) (xy 312.333173 -394.549654) (xy 312.321702 -394.529056) (xy 312.321194 -394.528294)
			(xy 311.92343 -393.839954) (xy 311.911569 -393.81727) (xy 311.894713 -393.76894) (xy 311.886134 -393.71848)
			(xy 311.885584 -393.692888) (xy 311.34359 -393.692888) (xy 311.655714 -394.232892) (xy 311.668537 -394.256226)
			(xy 311.686758 -394.306248) (xy 311.696019 -394.358673) (xy 311.696608 -394.385292) (xy 311.696154 -394.409298)
			(xy 311.68864 -394.456717) (xy 311.673797 -394.502377) (xy 311.651991 -394.54515) (xy 311.623758 -394.583983)
			(xy 311.589795 -394.617918) (xy 311.55094 -394.646119) (xy 311.508149 -394.667891) (xy 311.462478 -394.682698)
			(xy 311.415052 -394.690173) (xy 311.391046 -394.6906) (xy 311.367473 -394.690169) (xy 311.320887 -394.682935)
			(xy 311.275969 -394.668615) (xy 311.233791 -394.647553) (xy 311.195357 -394.620249) (xy 311.161584 -394.587355)
			(xy 311.133277 -394.549654) (xy 311.121806 -394.529056) (xy 311.121298 -394.528294) (xy 310.723534 -393.839954)
			(xy 310.711674 -393.81727) (xy 310.694818 -393.76894) (xy 310.686238 -393.71848) (xy 310.685688 -393.692888)
			(xy 310.379364 -393.692888) (xy 310.379364 -394.086842) (xy 310.379564 -394.093508) (xy 310.383046 -394.106377)
			(xy 310.386222 -394.112242) (xy 310.455818 -394.232892) (xy 310.468606 -394.256241) (xy 310.486807 -394.306264)
			(xy 310.4961 -394.358678) (xy 310.496712 -394.385292) (xy 310.496197 -394.410833) (xy 310.487699 -394.461205)
			(xy 310.47094 -394.50946) (xy 310.446385 -394.554254) (xy 310.41472 -394.594339) (xy 310.396128 -394.61186)
			(xy 310.388614 -394.619403) (xy 310.379942 -394.638822) (xy 310.379364 -394.649452) (xy 310.379364 -396.212822)
			(xy 310.379793 -396.222889) (xy 310.38752 -396.241482) (xy 310.39435 -396.24889) (xy 310.568848 -396.423388)
			(xy 310.597804 -396.429738) (xy 310.611774 -396.424404) (xy 310.637475 -396.415505) (xy 310.691008 -396.405923)
			(xy 310.7182 -396.405354) (xy 310.744799 -396.405932) (xy 310.797191 -396.415163) (xy 310.847187 -396.433345)
			(xy 310.893269 -396.459926) (xy 310.93404 -396.4941) (xy 310.951626 -396.514066) (xy 310.959217 -396.5222)
			(xy 310.979375 -396.531555) (xy 310.990488 -396.5321)
		)
		(stroke
			(width 0)
			(type solid)
		)
		(fill yes)
		(layer "In8.Cu")
		(net "P1V8_CPU0_RT0_1A")
	)
	(gr_poly
		(pts
			(xy 55.703978 -388.095236) (xy 55.712235 -388.094953) (xy 55.72791 -388.089766) (xy 55.734712 -388.085076)
			(xy 55.754693 -388.070562) (xy 55.798364 -388.047511) (xy 55.845181 -388.031801) (xy 55.893917 -388.023842)
			(xy 55.918608 -388.023354) (xy 55.943297 -388.023851) (xy 55.992027 -388.031833) (xy 56.038842 -388.04754)
			(xy 56.082525 -388.070563) (xy 56.102504 -388.085076) (xy 56.109301 -388.089774) (xy 56.12498 -388.094958)
			(xy 56.133238 -388.095236) (xy 56.903874 -388.095236) (xy 56.912131 -388.094954) (xy 56.927807 -388.089767)
			(xy 56.934608 -388.085076) (xy 56.954588 -388.070562) (xy 56.99826 -388.04751) (xy 57.045076 -388.031799)
			(xy 57.093813 -388.02384) (xy 57.118504 -388.023354) (xy 57.131267 -388.023491) (xy 57.156701 -388.025651)
			(xy 57.169304 -388.027672) (xy 57.18175 -388.029704) (xy 57.204864 -388.022338) (xy 57.909206 -387.317996)
			(xy 57.912762 -387.281928) (xy 57.902856 -387.266688) (xy 57.889822 -387.246291) (xy 57.869219 -387.202489)
			(xy 57.855231 -387.15615) (xy 57.848157 -387.108264) (xy 57.847738 -387.084062) (xy 57.848224 -387.058076)
			(xy 57.85636 -387.006745) (xy 57.872426 -386.957318) (xy 57.896027 -386.911014) (xy 57.926581 -386.868971)
			(xy 57.963335 -386.832226) (xy 58.005385 -386.801683) (xy 58.051696 -386.778094) (xy 58.101127 -386.762041)
			(xy 58.15246 -386.753917) (xy 58.178446 -386.753354) (xy 58.202644 -386.75382) (xy 58.250518 -386.760913)
			(xy 58.296851 -386.774897) (xy 58.340655 -386.795475) (xy 58.361072 -386.808472) (xy 58.371116 -386.814468)
			(xy 58.394285 -386.817498) (xy 58.416405 -386.80997) (xy 58.42508 -386.802122) (xy 58.823352 -386.40385)
			(xy 58.830769 -386.39568) (xy 58.838401 -386.375002) (xy 58.838084 -386.363972) (xy 58.831226 -386.276088)
			(xy 58.820304 -386.25653) (xy 58.811414 -386.249926) (xy 58.793133 -386.236092) (xy 58.760543 -386.20385)
			(xy 58.733147 -386.167092) (xy 58.722006 -386.147056) (xy 58.721498 -386.146294) (xy 58.323734 -385.457954)
			(xy 58.31184 -385.435284) (xy 58.294975 -385.386953) (xy 58.286423 -385.336483) (xy 58.285888 -385.310888)
			(xy 58.285888 -385.31038) (xy 58.286375 -385.285464) (xy 58.294454 -385.236293) (xy 58.310412 -385.189086)
			(xy 58.321702 -385.16687) (xy 58.321702 -385.166616) (xy 58.333345 -385.145707) (xy 58.362126 -385.107471)
			(xy 58.396517 -385.074193) (xy 58.435677 -385.046685) (xy 58.478649 -385.025621) (xy 58.524379 -385.011516)
			(xy 58.57175 -385.004716) (xy 58.619602 -385.005387) (xy 58.666763 -385.013512) (xy 58.71208 -385.028894)
			(xy 58.754444 -385.051154) (xy 58.792818 -385.079749) (xy 58.826263 -385.113979) (xy 58.85396 -385.153006)
			(xy 58.865008 -385.174236) (xy 58.86577 -385.17576) (xy 58.943884 -385.310888) (xy 59.485784 -385.310888)
			(xy 59.485784 -385.31038) (xy 59.486277 -385.285452) (xy 59.494428 -385.236266) (xy 59.510508 -385.189073)
			(xy 59.521852 -385.16687) (xy 59.521852 -385.166616) (xy 59.533437 -385.145679) (xy 59.562236 -385.107464)
			(xy 59.59664 -385.074206) (xy 59.635807 -385.046717) (xy 59.67878 -385.025669) (xy 59.724509 -385.011576)
			(xy 59.771876 -385.004784) (xy 59.819722 -385.005458) (xy 59.866879 -385.013583) (xy 59.912193 -385.028958)
			(xy 59.954556 -385.051208) (xy 59.992933 -385.07979) (xy 60.026386 -385.114005) (xy 60.054097 -385.153016)
			(xy 60.065158 -385.174236) (xy 60.06592 -385.17576) (xy 60.144034 -385.310888) (xy 60.68568 -385.310888)
			(xy 60.68568 -385.31038) (xy 60.686174 -385.285452) (xy 60.694325 -385.236266) (xy 60.710404 -385.189073)
			(xy 60.721748 -385.16687) (xy 60.721748 -385.166616) (xy 60.733339 -385.145682) (xy 60.762137 -385.107468)
			(xy 60.79654 -385.07421) (xy 60.835707 -385.046721) (xy 60.87868 -385.025673) (xy 60.924408 -385.01158)
			(xy 60.971774 -385.004788) (xy 61.01962 -385.005462) (xy 61.066776 -385.013586) (xy 61.11209 -385.02896)
			(xy 61.154452 -385.05121) (xy 61.192829 -385.079792) (xy 61.226282 -385.114006) (xy 61.253993 -385.153016)
			(xy 61.265054 -385.174236) (xy 61.265816 -385.17576) (xy 61.34393 -385.310888) (xy 61.885576 -385.310888)
			(xy 61.885576 -385.31038) (xy 61.88607 -385.285452) (xy 61.894221 -385.236266) (xy 61.9103 -385.189073)
			(xy 61.921644 -385.16687) (xy 61.921644 -385.166616) (xy 61.933241 -385.145686) (xy 61.962039 -385.107472)
			(xy 61.996441 -385.074214) (xy 62.035607 -385.046725) (xy 62.078579 -385.025677) (xy 62.124307 -385.011584)
			(xy 62.171673 -385.004792) (xy 62.219518 -385.005465) (xy 62.266674 -385.013589) (xy 62.311986 -385.028963)
			(xy 62.354349 -385.051212) (xy 62.392726 -385.079793) (xy 62.426178 -385.114007) (xy 62.453889 -385.153016)
			(xy 62.46495 -385.174236) (xy 62.465712 -385.17576) (xy 62.543826 -385.310888) (xy 63.08598 -385.310888)
			(xy 63.08598 -385.31038) (xy 63.086469 -385.285466) (xy 63.094566 -385.2363) (xy 63.110527 -385.189096)
			(xy 63.121794 -385.16687) (xy 63.121794 -385.166616) (xy 63.133466 -385.14573) (xy 63.162257 -385.107519)
			(xy 63.196652 -385.074263) (xy 63.23581 -385.046775) (xy 63.278774 -385.025727) (xy 63.324495 -385.011633)
			(xy 63.371853 -385.004838) (xy 63.419691 -385.005508) (xy 63.46684 -385.013626) (xy 63.512148 -385.028995)
			(xy 63.554506 -385.051238) (xy 63.592879 -385.079812) (xy 63.626329 -385.114018) (xy 63.654039 -385.15302)
			(xy 63.6651 -385.174236) (xy 63.665862 -385.17576) (xy 63.743976 -385.310888) (xy 64.285876 -385.310888)
			(xy 64.285876 -385.31038) (xy 64.286366 -385.285466) (xy 64.294463 -385.2363) (xy 64.310423 -385.189096)
			(xy 64.32169 -385.16687) (xy 64.32169 -385.166616) (xy 64.333368 -385.145733) (xy 64.362158 -385.107523)
			(xy 64.396553 -385.074267) (xy 64.43571 -385.046779) (xy 64.478674 -385.025731) (xy 64.524394 -385.011637)
			(xy 64.571751 -385.004841) (xy 64.619589 -385.005511) (xy 64.666738 -385.013629) (xy 64.712045 -385.028998)
			(xy 64.754403 -385.05124) (xy 64.792776 -385.079814) (xy 64.826225 -385.114019) (xy 64.853935 -385.153021)
			(xy 64.864996 -385.174236) (xy 64.865758 -385.17576) (xy 64.943872 -385.310888) (xy 65.485772 -385.310888)
			(xy 65.485772 -385.31038) (xy 65.486267 -385.285452) (xy 65.494417 -385.236266) (xy 65.510496 -385.189073)
			(xy 65.52184 -385.16687) (xy 65.52184 -385.166616) (xy 65.533443 -385.145689) (xy 65.56224 -385.107475)
			(xy 65.596642 -385.074218) (xy 65.635808 -385.046729) (xy 65.678779 -385.025681) (xy 65.724506 -385.011588)
			(xy 65.771871 -385.004795) (xy 65.819716 -385.005469) (xy 65.866871 -385.013592) (xy 65.912183 -385.028966)
			(xy 65.954546 -385.051215) (xy 65.992922 -385.079795) (xy 66.026374 -385.114008) (xy 66.054085 -385.153017)
			(xy 66.065146 -385.174236) (xy 66.065908 -385.17576) (xy 66.438272 -385.819904) (xy 66.438526 -385.820412)
			(xy 66.458084 -385.85394) (xy 66.470335 -385.876866) (xy 66.487749 -385.925839) (xy 66.496632 -385.977051)
			(xy 66.4972 -386.003038) (xy 66.4972 -386.003292) (xy 66.496754 -386.027298) (xy 66.48924 -386.074718)
			(xy 66.474396 -386.120378) (xy 66.452589 -386.163152) (xy 66.424356 -386.201985) (xy 66.390392 -386.235921)
			(xy 66.351535 -386.264122) (xy 66.308743 -386.285894) (xy 66.263071 -386.300699) (xy 66.215644 -386.308173)
			(xy 66.191638 -386.3086) (xy 66.191384 -386.3086) (xy 66.16781 -386.308219) (xy 66.121221 -386.300975)
			(xy 66.076302 -386.286647) (xy 66.034123 -386.265576) (xy 65.995691 -386.238265) (xy 65.961919 -386.205363)
			(xy 65.933614 -386.167656) (xy 65.922144 -386.147056) (xy 65.921636 -386.146294) (xy 65.523872 -385.457954)
			(xy 65.511936 -385.435296) (xy 65.495006 -385.386965) (xy 65.486355 -385.336492) (xy 65.485772 -385.310888)
			(xy 64.943872 -385.310888) (xy 65.238122 -385.819904) (xy 65.238376 -385.820412) (xy 65.257934 -385.85394)
			(xy 65.270149 -385.876873) (xy 65.287475 -385.925854) (xy 65.29627 -385.97706) (xy 65.296796 -386.003038)
			(xy 65.296796 -386.003292) (xy 65.296354 -386.027286) (xy 65.288848 -386.074682) (xy 65.27402 -386.12032)
			(xy 65.252235 -386.163077) (xy 65.224029 -386.2019) (xy 65.190097 -386.235831) (xy 65.151274 -386.264037)
			(xy 65.108517 -386.285822) (xy 65.062878 -386.300649) (xy 65.015482 -386.308155) (xy 64.991488 -386.3086)
			(xy 64.991234 -386.3086) (xy 64.967661 -386.308179) (xy 64.921074 -386.300942) (xy 64.876156 -386.286622)
			(xy 64.833978 -386.265557) (xy 64.795544 -386.238252) (xy 64.761772 -386.205356) (xy 64.733465 -386.167654)
			(xy 64.721994 -386.147056) (xy 64.721486 -386.146294) (xy 64.323722 -385.457954) (xy 64.311861 -385.43527)
			(xy 64.295005 -385.38694) (xy 64.286426 -385.33648) (xy 64.285876 -385.310888) (xy 63.743976 -385.310888)
			(xy 64.038226 -385.819904) (xy 64.03848 -385.820412) (xy 64.058038 -385.85394) (xy 64.070253 -385.876873)
			(xy 64.087579 -385.925854) (xy 64.096374 -385.97706) (xy 64.0969 -386.003038) (xy 64.0969 -386.003292)
			(xy 64.096454 -386.027285) (xy 64.088949 -386.074681) (xy 64.074121 -386.12032) (xy 64.052336 -386.163076)
			(xy 64.02413 -386.201898) (xy 63.990198 -386.23583) (xy 63.951376 -386.264036) (xy 63.90862 -386.285821)
			(xy 63.862981 -386.300649) (xy 63.815585 -386.308154) (xy 63.791592 -386.3086) (xy 63.791338 -386.3086)
			(xy 63.767765 -386.308176) (xy 63.721178 -386.30094) (xy 63.67626 -386.28662) (xy 63.634082 -386.265556)
			(xy 63.595648 -386.238251) (xy 63.561876 -386.205356) (xy 63.533569 -386.167654) (xy 63.522098 -386.147056)
			(xy 63.52159 -386.146294) (xy 63.123826 -385.457954) (xy 63.111965 -385.43527) (xy 63.095109 -385.38694)
			(xy 63.08653 -385.33648) (xy 63.08598 -385.310888) (xy 62.543826 -385.310888) (xy 62.838076 -385.819904)
			(xy 62.83833 -385.820412) (xy 62.857888 -385.85394) (xy 62.870139 -385.876866) (xy 62.887553 -385.925839)
			(xy 62.896436 -385.977051) (xy 62.897004 -386.003038) (xy 62.897004 -386.003292) (xy 62.896554 -386.027298)
			(xy 62.88904 -386.074718) (xy 62.874197 -386.120377) (xy 62.85239 -386.163151) (xy 62.824157 -386.201984)
			(xy 62.790194 -386.23592) (xy 62.751337 -386.264121) (xy 62.708546 -386.285893) (xy 62.662874 -386.300698)
			(xy 62.615448 -386.308173) (xy 62.591442 -386.3086) (xy 62.591188 -386.3086) (xy 62.567614 -386.308216)
			(xy 62.521025 -386.300973) (xy 62.476106 -386.286645) (xy 62.433928 -386.265575) (xy 62.395495 -386.238264)
			(xy 62.361723 -386.205363) (xy 62.333418 -386.167656) (xy 62.321948 -386.147056) (xy 62.32144 -386.146294)
			(xy 61.923676 -385.457954) (xy 61.91174 -385.435296) (xy 61.89481 -385.386965) (xy 61.886159 -385.336492)
			(xy 61.885576 -385.310888) (xy 61.34393 -385.310888) (xy 61.63818 -385.819904) (xy 61.638434 -385.820412)
			(xy 61.657992 -385.85394) (xy 61.670243 -385.876866) (xy 61.687657 -385.925839) (xy 61.69654 -385.977051)
			(xy 61.697108 -386.003038) (xy 61.697108 -386.003292) (xy 61.696654 -386.027298) (xy 61.68914 -386.074717)
			(xy 61.674297 -386.120377) (xy 61.652491 -386.16315) (xy 61.624258 -386.201983) (xy 61.590295 -386.235918)
			(xy 61.55144 -386.264119) (xy 61.508649 -386.285891) (xy 61.462978 -386.300698) (xy 61.415552 -386.308173)
			(xy 61.391546 -386.3086) (xy 61.391292 -386.3086) (xy 61.367718 -386.308213) (xy 61.321129 -386.30097)
			(xy 61.27621 -386.286643) (xy 61.234032 -386.265573) (xy 61.195599 -386.238263) (xy 61.161828 -386.205362)
			(xy 61.133522 -386.167656) (xy 61.122052 -386.147056) (xy 61.121544 -386.146294) (xy 60.72378 -385.457954)
			(xy 60.711844 -385.435296) (xy 60.694915 -385.386965) (xy 60.686263 -385.336492) (xy 60.68568 -385.310888)
			(xy 60.144034 -385.310888) (xy 60.438284 -385.819904) (xy 60.438538 -385.820412) (xy 60.458096 -385.85394)
			(xy 60.470348 -385.876866) (xy 60.487761 -385.925839) (xy 60.496644 -385.977051) (xy 60.497212 -386.003038)
			(xy 60.497212 -386.003292) (xy 60.496754 -386.027297) (xy 60.48924 -386.074717) (xy 60.474398 -386.120376)
			(xy 60.452591 -386.163149) (xy 60.424359 -386.201981) (xy 60.390397 -386.235917) (xy 60.351542 -386.264118)
			(xy 60.308752 -386.28589) (xy 60.263081 -386.300697) (xy 60.215656 -386.308172) (xy 60.19165 -386.3086)
			(xy 60.191396 -386.3086) (xy 60.167822 -386.308209) (xy 60.121233 -386.300967) (xy 60.076315 -386.286641)
			(xy 60.034136 -386.265572) (xy 59.995703 -386.238262) (xy 59.961932 -386.205362) (xy 59.933626 -386.167656)
			(xy 59.922156 -386.147056) (xy 59.921648 -386.146294) (xy 59.523884 -385.457954) (xy 59.511948 -385.435296)
			(xy 59.495019 -385.386965) (xy 59.486367 -385.336492) (xy 59.485784 -385.310888) (xy 58.943884 -385.310888)
			(xy 59.238134 -385.819904) (xy 59.238388 -385.820412) (xy 59.257946 -385.85394) (xy 59.270177 -385.876865)
			(xy 59.287505 -385.925848) (xy 59.296284 -385.977059) (xy 59.296808 -386.003038) (xy 59.296808 -386.003292)
			(xy 59.296808 -386.013706) (xy 59.2963 -386.023866) (xy 59.303158 -386.042408) (xy 59.365642 -386.109972)
			(xy 59.383422 -386.118354) (xy 59.393582 -386.118608) (xy 59.417613 -386.120136) (xy 59.46489 -386.12927)
			(xy 59.510346 -386.145153) (xy 59.553024 -386.16745) (xy 59.592023 -386.195692) (xy 59.626522 -386.229283)
			(xy 59.641486 -386.248148) (xy 59.649034 -386.257084) (xy 59.66994 -386.26752) (xy 59.681618 -386.268214)
			(xy 59.76493 -386.268214) (xy 59.789889 -386.268788) (xy 59.838848 -386.278533) (xy 59.884964 -386.297641)
			(xy 59.926467 -386.32538) (xy 59.944508 -386.342636) (xy 60.389262 -386.78739) (xy 60.420758 -386.792978)
			(xy 60.435744 -386.785866) (xy 60.458136 -386.775631) (xy 60.505194 -386.761163) (xy 60.553876 -386.753832)
			(xy 60.578492 -386.753354) (xy 60.604481 -386.753863) (xy 60.655818 -386.761992) (xy 60.705252 -386.778052)
			(xy 60.751566 -386.801647) (xy 60.793618 -386.832196) (xy 60.830374 -386.868947) (xy 60.860929 -386.910995)
			(xy 60.88453 -386.957305) (xy 60.900597 -387.006737) (xy 60.908733 -387.058073) (xy 60.9092 -387.084062)
			(xy 60.908729 -387.108678) (xy 60.901393 -387.157361) (xy 60.886924 -387.204418) (xy 60.876688 -387.22681)
			(xy 60.869576 -387.241796) (xy 60.875164 -387.273292) (xy 61.21146 -387.609588) (xy 61.218861 -387.616426)
			(xy 61.237459 -387.624141) (xy 61.247528 -387.624574) (xy 61.573156 -387.624574) (xy 61.599318 -387.605524)
			(xy 61.604652 -387.589776) (xy 61.613256 -387.565369) (xy 61.636967 -387.519373) (xy 61.667553 -387.477632)
			(xy 61.704267 -387.441165) (xy 61.746214 -387.410861) (xy 61.792369 -387.387462) (xy 61.841606 -387.371537)
			(xy 61.892722 -387.363477) (xy 61.94447 -387.363477) (xy 61.995586 -387.371537) (xy 62.044823 -387.387462)
			(xy 62.090978 -387.410861) (xy 62.132925 -387.441165) (xy 62.169639 -387.477632) (xy 62.200225 -387.519373)
			(xy 62.223936 -387.565369) (xy 62.23254 -387.589776) (xy 62.237874 -387.605524) (xy 62.264036 -387.624574)
			(xy 62.773052 -387.624574) (xy 62.799214 -387.605524) (xy 62.804548 -387.589776) (xy 62.813152 -387.565369)
			(xy 62.836863 -387.519373) (xy 62.867449 -387.477632) (xy 62.904163 -387.441165) (xy 62.94611 -387.410861)
			(xy 62.992265 -387.387462) (xy 63.041502 -387.371537) (xy 63.092618 -387.363477) (xy 63.144366 -387.363477)
			(xy 63.195482 -387.371537) (xy 63.244719 -387.387462) (xy 63.290874 -387.410861) (xy 63.332821 -387.441165)
			(xy 63.369535 -387.477632) (xy 63.400121 -387.519373) (xy 63.423832 -387.565369) (xy 63.432436 -387.589776)
			(xy 63.43777 -387.605524) (xy 63.463932 -387.624574) (xy 63.973202 -387.624574) (xy 63.999364 -387.605524)
			(xy 64.004698 -387.589776) (xy 64.013302 -387.565369) (xy 64.037013 -387.519373) (xy 64.067599 -387.477632)
			(xy 64.104313 -387.441165) (xy 64.14626 -387.410861) (xy 64.192415 -387.387462) (xy 64.241652 -387.371537)
			(xy 64.292768 -387.363477) (xy 64.344516 -387.363477) (xy 64.395632 -387.371537) (xy 64.444869 -387.387462)
			(xy 64.491024 -387.410861) (xy 64.532971 -387.441165) (xy 64.569685 -387.477632) (xy 64.600271 -387.519373)
			(xy 64.623982 -387.565369) (xy 64.632586 -387.589776) (xy 64.63792 -387.605524) (xy 64.664082 -387.624574)
			(xy 65.173098 -387.624574) (xy 65.19926 -387.605524) (xy 65.204594 -387.589776) (xy 65.213198 -387.565369)
			(xy 65.236909 -387.519373) (xy 65.267495 -387.477632) (xy 65.304209 -387.441165) (xy 65.346156 -387.410861)
			(xy 65.392311 -387.387462) (xy 65.441548 -387.371537) (xy 65.492664 -387.363477) (xy 65.544412 -387.363477)
			(xy 65.595528 -387.371537) (xy 65.644765 -387.387462) (xy 65.69092 -387.410861) (xy 65.732867 -387.441165)
			(xy 65.769581 -387.477632) (xy 65.800167 -387.519373) (xy 65.823878 -387.565369) (xy 65.832482 -387.589776)
			(xy 65.837816 -387.605524) (xy 65.863978 -387.624574) (xy 69.03212 -387.624574) (xy 69.042188 -387.624147)
			(xy 69.060785 -387.616424) (xy 69.068188 -387.609588) (xy 69.487034 -387.190742) (xy 69.493879 -387.183344)
			(xy 69.501602 -387.164745) (xy 69.50202 -387.154674) (xy 69.50202 -386.689346) (xy 69.502592 -386.665251)
			(xy 69.511691 -386.617927) (xy 69.529552 -386.573169) (xy 69.555535 -386.532583) (xy 69.588706 -386.497626)
			(xy 69.607938 -386.483098) (xy 69.617372 -386.475442) (xy 69.628393 -386.453828) (xy 69.62902 -386.441696)
			(xy 69.62902 -386.32003) (xy 69.62959 -386.303457) (xy 69.638208 -386.271449) (xy 69.65479 -386.242746)
			(xy 69.666104 -386.230622) (xy 69.791834 -386.105146) (xy 69.798679 -386.097748) (xy 69.806404 -386.079149)
			(xy 69.80682 -386.069078) (xy 69.80682 -384.86842) (xy 69.806201 -384.856281) (xy 69.795197 -384.834649)
			(xy 69.785738 -384.827018) (xy 69.76648 -384.812521) (xy 69.733303 -384.77756) (xy 69.707319 -384.736967)
			(xy 69.689462 -384.692201) (xy 69.680373 -384.644868) (xy 69.67982 -384.62077) (xy 69.67982 -383.948178)
			(xy 69.679394 -383.938109) (xy 69.671676 -383.919509) (xy 69.664834 -383.91211) (xy 69.499226 -383.746502)
			(xy 69.491823 -383.739667) (xy 69.473225 -383.731959) (xy 69.463158 -383.731516) (xy 54.846474 -383.731516)
			(xy 54.836406 -383.731944) (xy 54.81781 -383.739667) (xy 54.810406 -383.746502) (xy 54.727602 -383.829306)
			(xy 54.710861 -383.845355) (xy 54.672694 -383.87169) (xy 54.63038 -383.890659) (xy 54.607968 -383.896616)
			(xy 54.60111 -383.89814) (xy 54.589172 -383.904998) (xy 54.370224 -384.123946) (xy 54.363382 -384.131346)
			(xy 54.355661 -384.149944) (xy 54.355238 -384.160014) (xy 54.355238 -385.310888) (xy 54.685692 -385.310888)
			(xy 54.685692 -385.31038) (xy 54.686121 -385.286374) (xy 54.693638 -385.238953) (xy 54.708485 -385.193293)
			(xy 54.730295 -385.15052) (xy 54.758531 -385.111687) (xy 54.792496 -385.077752) (xy 54.831354 -385.049552)
			(xy 54.874147 -385.02778) (xy 54.91982 -385.012974) (xy 54.967247 -385.005499) (xy 54.991254 -385.005072)
			(xy 55.015189 -385.005536) (xy 55.062474 -385.012994) (xy 55.108017 -385.027736) (xy 55.150703 -385.0494)
			(xy 55.189489 -385.077456) (xy 55.223424 -385.111218) (xy 55.251679 -385.149859) (xy 55.263034 -385.170934)
			(xy 55.263542 -385.17195) (xy 55.343848 -385.310888) (xy 55.885588 -385.310888) (xy 55.885588 -385.31038)
			(xy 55.886021 -385.286374) (xy 55.893538 -385.238954) (xy 55.908385 -385.193294) (xy 55.930194 -385.150521)
			(xy 55.95843 -385.111689) (xy 55.992394 -385.077754) (xy 56.031252 -385.049553) (xy 56.074044 -385.027781)
			(xy 56.119717 -385.012975) (xy 56.167143 -385.0055) (xy 56.19115 -385.005072) (xy 56.215085 -385.005539)
			(xy 56.262369 -385.012997) (xy 56.307912 -385.027738) (xy 56.350599 -385.049401) (xy 56.389384 -385.077457)
			(xy 56.42332 -385.111218) (xy 56.451575 -385.149859) (xy 56.46293 -385.170934) (xy 56.463438 -385.17195)
			(xy 56.543744 -385.310888) (xy 57.085992 -385.310888) (xy 57.085992 -385.31038) (xy 57.08648 -385.285466)
			(xy 57.094577 -385.236299) (xy 57.110538 -385.189096) (xy 57.121806 -385.16687) (xy 57.121806 -385.166616)
			(xy 57.13346 -385.145719) (xy 57.162252 -385.107508) (xy 57.196649 -385.074251) (xy 57.235809 -385.046763)
			(xy 57.278776 -385.025715) (xy 57.324498 -385.011621) (xy 57.371858 -385.004827) (xy 57.419698 -385.005498)
			(xy 57.466848 -385.013617) (xy 57.512157 -385.028987) (xy 57.554516 -385.051232) (xy 57.59289 -385.079808)
			(xy 57.626341 -385.114016) (xy 57.654051 -385.153019) (xy 57.665112 -385.174236) (xy 57.665874 -385.17576)
			(xy 58.038238 -385.819904) (xy 58.038492 -385.820412) (xy 58.05805 -385.85394) (xy 58.070266 -385.876872)
			(xy 58.087592 -385.925854) (xy 58.096386 -385.97706) (xy 58.096912 -386.003038) (xy 58.096912 -386.003292)
			(xy 58.096454 -386.027285) (xy 58.088949 -386.07468) (xy 58.074122 -386.120317) (xy 58.052338 -386.163073)
			(xy 58.024134 -386.201894) (xy 57.990203 -386.235826) (xy 57.951383 -386.264032) (xy 57.908628 -386.285817)
			(xy 57.862991 -386.300646) (xy 57.815597 -386.308154) (xy 57.791604 -386.3086) (xy 57.79135 -386.3086)
			(xy 57.767777 -386.308166) (xy 57.721191 -386.300932) (xy 57.676273 -386.286613) (xy 57.634095 -386.265551)
			(xy 57.595661 -386.238248) (xy 57.561888 -386.205354) (xy 57.533581 -386.167653) (xy 57.52211 -386.147056)
			(xy 57.521602 -386.146294) (xy 57.123838 -385.457954) (xy 57.111978 -385.435269) (xy 57.095122 -385.38694)
			(xy 57.086542 -385.33648) (xy 57.085992 -385.310888) (xy 56.543744 -385.310888) (xy 56.855868 -385.850892)
			(xy 56.868624 -385.874246) (xy 56.88673 -385.92428) (xy 56.89593 -385.976688) (xy 56.896508 -386.003292)
			(xy 56.896054 -386.027285) (xy 56.888549 -386.07468) (xy 56.873721 -386.120318) (xy 56.851937 -386.163074)
			(xy 56.823732 -386.201896) (xy 56.789802 -386.235827) (xy 56.750981 -386.264033) (xy 56.708225 -386.285818)
			(xy 56.662588 -386.300647) (xy 56.615193 -386.308154) (xy 56.5912 -386.3086) (xy 56.567626 -386.308206)
			(xy 56.521038 -386.300965) (xy 56.476119 -386.286639) (xy 56.433941 -386.26557) (xy 56.395508 -386.238261)
			(xy 56.361736 -386.205361) (xy 56.33343 -386.167656) (xy 56.32196 -386.147056) (xy 56.321452 -386.146294)
			(xy 55.923688 -385.457954) (xy 55.911753 -385.435296) (xy 55.894823 -385.386965) (xy 55.886171 -385.336491)
			(xy 55.885588 -385.310888) (xy 55.343848 -385.310888) (xy 55.655972 -385.850892) (xy 55.668728 -385.874246)
			(xy 55.686834 -385.92428) (xy 55.696034 -385.976688) (xy 55.696612 -386.003292) (xy 55.696154 -386.027285)
			(xy 55.688649 -386.07468) (xy 55.673822 -386.120317) (xy 55.652038 -386.163073) (xy 55.623834 -386.201894)
			(xy 55.589903 -386.235826) (xy 55.551083 -386.264032) (xy 55.508328 -386.285817) (xy 55.462691 -386.300646)
			(xy 55.415297 -386.308154) (xy 55.391304 -386.3086) (xy 55.36773 -386.308203) (xy 55.321142 -386.300962)
			(xy 55.276223 -386.286637) (xy 55.234045 -386.265569) (xy 55.195612 -386.23826) (xy 55.16184 -386.205361)
			(xy 55.133535 -386.167656) (xy 55.122064 -386.147056) (xy 55.121556 -386.146294) (xy 54.723792 -385.457954)
			(xy 54.711857 -385.435295) (xy 54.694927 -385.386965) (xy 54.686275 -385.336491) (xy 54.685692 -385.310888)
			(xy 54.355238 -385.310888) (xy 54.355238 -385.662678) (xy 54.355429 -385.669347) (xy 54.358896 -385.682225)
			(xy 54.362096 -385.688078) (xy 54.456076 -385.850892) (xy 54.468881 -385.874225) (xy 54.487025 -385.924258)
			(xy 54.496201 -385.976681) (xy 54.496716 -386.003292) (xy 54.496305 -386.026824) (xy 54.48913 -386.073336)
			(xy 54.474903 -386.118197) (xy 54.45396 -386.160343) (xy 54.426799 -386.198777) (xy 54.394061 -386.232587)
			(xy 54.375558 -386.247132) (xy 54.366484 -386.254681) (xy 54.355872 -386.275733) (xy 54.355238 -386.287518)
			(xy 54.355238 -387.775958) (xy 54.355672 -387.786023) (xy 54.363406 -387.804608) (xy 54.370224 -387.812026)
			(xy 54.591204 -388.033006) (xy 54.618382 -388.039864) (xy 54.63159 -388.036054) (xy 54.652818 -388.030135)
			(xy 54.696424 -388.023755) (xy 54.718458 -388.023354) (xy 54.743146 -388.023855) (xy 54.791872 -388.031844)
			(xy 54.838682 -388.047557) (xy 54.88236 -388.070586) (xy 54.902354 -388.085076) (xy 54.909153 -388.089767)
			(xy 54.924832 -388.094936) (xy 54.933088 -388.095236)
		)
		(stroke
			(width 0)
			(type solid)
		)
		(fill yes)
		(layer "In8.Cu")
		(net "P1V8_CPU1_RT0_1A")
	)
	(gr_poly
		(pts
			(xy 346.84208 -256.362454) (xy 346.854018 -256.354834) (xy 346.873964 -256.342667) (xy 346.916558 -256.323466)
			(xy 346.961434 -256.310465) (xy 347.007695 -256.303924) (xy 347.031056 -256.303526) (xy 347.044772 -256.30378)
			(xy 347.058742 -256.304288) (xy 347.083634 -256.290826) (xy 347.229176 -256.040382) (xy 347.228668 -256.011934)
			(xy 347.221048 -255.999996) (xy 347.209073 -255.980154) (xy 347.190182 -255.937834) (xy 347.177378 -255.893292)
			(xy 347.17091 -255.847401) (xy 347.170502 -255.824228) (xy 347.170983 -255.798238) (xy 347.179111 -255.746896)
			(xy 347.195171 -255.697459) (xy 347.218767 -255.651142) (xy 347.249319 -255.609088) (xy 347.286074 -255.572331)
			(xy 347.328127 -255.541777) (xy 347.374442 -255.518178) (xy 347.423879 -255.502115) (xy 347.47522 -255.493984)
			(xy 347.50121 -255.49352) (xy 347.526889 -255.494006) (xy 347.57763 -255.501948) (xy 347.626533 -255.517639)
			(xy 347.672421 -255.540702) (xy 347.714193 -255.570582) (xy 347.750842 -255.606562) (xy 347.781489 -255.647774)
			(xy 347.793818 -255.670304) (xy 347.800422 -255.68275) (xy 347.824806 -255.697482) (xy 348.117414 -255.697482)
			(xy 348.141798 -255.68275) (xy 348.148402 -255.670304) (xy 348.160086 -255.64973) (xy 348.167452 -255.637792)
			(xy 348.16796 -255.609852) (xy 348.021656 -255.35763) (xy 347.997272 -255.344168) (xy 347.983048 -255.344676)
			(xy 347.97111 -255.34493) (xy 347.945118 -255.344448) (xy 347.893775 -255.336317) (xy 347.844336 -255.320255)
			(xy 347.798018 -255.296656) (xy 347.755963 -255.266102) (xy 347.719205 -255.229345) (xy 347.688649 -255.18729)
			(xy 347.665049 -255.140973) (xy 347.648985 -255.091534) (xy 347.640853 -255.040191) (xy 347.640853 -254.988209)
			(xy 347.648985 -254.936866) (xy 347.665049 -254.887427) (xy 347.688649 -254.84111) (xy 347.719205 -254.799055)
			(xy 347.755963 -254.762298) (xy 347.798018 -254.731744) (xy 347.844336 -254.708145) (xy 347.893775 -254.692083)
			(xy 347.945118 -254.683952) (xy 347.97111 -254.683514) (xy 347.994066 -254.683921) (xy 348.039532 -254.690301)
			(xy 348.083678 -254.70291) (xy 348.125656 -254.721504) (xy 348.145354 -254.733298) (xy 348.157292 -254.740664)
			(xy 348.185232 -254.741172) (xy 349.037148 -254.251714) (xy 349.050864 -254.22733) (xy 349.050356 -254.21336)
			(xy 349.050356 -254.204216) (xy 349.05061 -254.192024) (xy 349.051118 -254.178054) (xy 349.037402 -254.153162)
			(xy 348.18828 -253.665482) (xy 348.159832 -253.66599) (xy 348.147894 -253.67361) (xy 348.127975 -253.685761)
			(xy 348.085443 -253.704943) (xy 348.040633 -253.717944) (xy 347.994439 -253.724503) (xy 347.97111 -253.724918)
			(xy 347.945119 -253.724436) (xy 347.893778 -253.716305) (xy 347.844341 -253.700244) (xy 347.798025 -253.676646)
			(xy 347.755971 -253.646093) (xy 347.719214 -253.609337) (xy 347.68866 -253.567284) (xy 347.66506 -253.520968)
			(xy 347.648997 -253.471532) (xy 347.640865 -253.420191) (xy 347.640865 -253.368209) (xy 347.648997 -253.316868)
			(xy 347.66506 -253.267432) (xy 347.68866 -253.221116) (xy 347.719214 -253.179063) (xy 347.755971 -253.142307)
			(xy 347.798025 -253.111754) (xy 347.844341 -253.088156) (xy 347.893778 -253.072095) (xy 347.945119 -253.063964)
			(xy 347.97111 -253.063502) (xy 347.994066 -253.063909) (xy 348.039532 -253.070289) (xy 348.083679 -253.082897)
			(xy 348.125657 -253.10149) (xy 348.145354 -253.113286) (xy 348.157292 -253.120652) (xy 348.185232 -253.12116)
			(xy 349.037148 -252.631702) (xy 349.050864 -252.607318) (xy 349.050356 -252.593348) (xy 349.050356 -252.584204)
			(xy 349.050865 -252.558216) (xy 349.058995 -252.506879) (xy 349.075055 -252.457445) (xy 349.09865 -252.411132)
			(xy 349.129199 -252.369081) (xy 349.16595 -252.332325) (xy 349.207998 -252.301771) (xy 349.254308 -252.278171)
			(xy 349.30374 -252.262104) (xy 349.355076 -252.253968) (xy 349.381064 -252.253496) (xy 349.391224 -252.25375)
			(xy 349.405194 -252.254004) (xy 349.429578 -252.240542) (xy 349.576898 -251.986796) (xy 349.57639 -251.958856)
			(xy 349.569024 -251.946918) (xy 349.557493 -251.927337) (xy 349.539322 -251.885686) (xy 349.527029 -251.841938)
			(xy 349.520844 -251.796919) (xy 349.52051 -251.774198) (xy 349.520897 -251.751325) (xy 349.527199 -251.706015)
			(xy 349.539682 -251.662005) (xy 349.558109 -251.620134) (xy 349.569786 -251.600462) (xy 349.577406 -251.58827)
			(xy 349.57766 -251.56033) (xy 349.431102 -251.3076) (xy 349.406718 -251.294138) (xy 349.392494 -251.294646)
			(xy 349.381064 -251.2949) (xy 349.355079 -251.294388) (xy 349.303749 -251.286253) (xy 349.254324 -251.270188)
			(xy 349.20802 -251.246591) (xy 349.165978 -251.21604) (xy 349.129231 -251.179289) (xy 349.098686 -251.137242)
			(xy 349.075095 -251.090935) (xy 349.059037 -251.041508) (xy 349.050909 -250.990177) (xy 349.050356 -250.964192)
			(xy 349.05061 -250.952254) (xy 349.051118 -250.93803) (xy 349.037656 -250.913646) (xy 348.187772 -250.425458)
			(xy 348.159832 -250.425966) (xy 348.147894 -250.43384) (xy 348.127961 -250.445948) (xy 348.085416 -250.465051)
			(xy 348.040609 -250.477988) (xy 347.994429 -250.4845) (xy 347.97111 -250.484894) (xy 347.945121 -250.484412)
			(xy 347.893782 -250.476282) (xy 347.844347 -250.46022) (xy 347.798033 -250.436623) (xy 347.755981 -250.40607)
			(xy 347.719227 -250.369316) (xy 347.688675 -250.327263) (xy 347.665078 -250.28095) (xy 347.649018 -250.231514)
			(xy 347.640888 -250.180175) (xy 347.640402 -250.154186) (xy 347.640794 -250.131272) (xy 347.647132 -250.085883)
			(xy 347.659684 -250.041806) (xy 347.678208 -249.999888) (xy 347.689932 -249.980196) (xy 347.697298 -249.968258)
			(xy 347.697552 -249.940318) (xy 347.550994 -249.687588) (xy 347.52661 -249.674126) (xy 347.51264 -249.674634)
			(xy 347.50121 -249.674888) (xy 347.475221 -249.674406) (xy 347.423882 -249.666275) (xy 347.374448 -249.650214)
			(xy 347.328134 -249.626616) (xy 347.286083 -249.596064) (xy 347.24933 -249.559309) (xy 347.218778 -249.517257)
			(xy 347.195182 -249.470943) (xy 347.179122 -249.421508) (xy 347.170994 -249.370169) (xy 347.170502 -249.34418)
			(xy 347.17089 -249.321307) (xy 347.177194 -249.275998) (xy 347.189679 -249.231989) (xy 347.208108 -249.19012)
			(xy 347.219778 -249.170444) (xy 347.227398 -249.158252) (xy 347.227652 -249.130566) (xy 347.081094 -248.877582)
			(xy 347.05671 -248.86412) (xy 347.042486 -248.864628) (xy 347.031056 -248.864882) (xy 347.007355 -248.864472)
			(xy 346.960438 -248.857699) (xy 346.914968 -248.844298) (xy 346.871877 -248.824544) (xy 346.851732 -248.81205)
			(xy 346.839794 -248.804176) (xy 346.8116 -248.803668) (xy 345.96451 -249.290332) (xy 345.950794 -249.31497)
			(xy 345.951556 -249.329448) (xy 345.95181 -249.34418) (xy 345.9513 -249.370167) (xy 345.94317 -249.421502)
			(xy 345.927109 -249.470932) (xy 345.903513 -249.517242) (xy 345.872963 -249.55929) (xy 345.836212 -249.596041)
			(xy 345.794164 -249.626591) (xy 345.747854 -249.650187) (xy 345.698424 -249.666248) (xy 345.647089 -249.674378)
			(xy 345.595115 -249.674378) (xy 345.54378 -249.666248) (xy 345.49435 -249.650187) (xy 345.44804 -249.626591)
			(xy 345.405992 -249.596041) (xy 345.369241 -249.55929) (xy 345.338691 -249.517242) (xy 345.315095 -249.470932)
			(xy 345.299034 -249.421502) (xy 345.290904 -249.370167) (xy 345.290394 -249.34418) (xy 345.290648 -249.332496)
			(xy 345.291156 -249.318018) (xy 345.277694 -249.293634) (xy 344.427556 -248.8057) (xy 344.39987 -248.806208)
			(xy 344.387678 -248.813828) (xy 344.367773 -248.82592) (xy 344.32529 -248.845005) (xy 344.280548 -248.857939)
			(xy 344.234435 -248.864467) (xy 344.211148 -248.864882) (xy 344.185158 -248.864403) (xy 344.133818 -248.856278)
			(xy 344.084381 -248.840221) (xy 344.038065 -248.816628) (xy 343.99601 -248.786079) (xy 343.959252 -248.749327)
			(xy 343.928697 -248.707276) (xy 343.905097 -248.660964) (xy 343.889033 -248.611529) (xy 343.880901 -248.56019)
			(xy 343.880901 -248.50821) (xy 343.889033 -248.456871) (xy 343.905097 -248.407436) (xy 343.928697 -248.361124)
			(xy 343.959252 -248.319073) (xy 343.99601 -248.282321) (xy 344.038065 -248.251772) (xy 344.084381 -248.228179)
			(xy 344.133818 -248.212122) (xy 344.185158 -248.203997) (xy 344.211148 -248.203466) (xy 344.2208 -248.20372)
			(xy 344.23477 -248.203974) (xy 344.259154 -248.190512) (xy 344.406474 -247.936512) (xy 344.40622 -247.908572)
			(xy 344.398854 -247.896634) (xy 344.387345 -247.877079) (xy 344.369206 -247.835488) (xy 344.356927 -247.791806)
			(xy 344.350738 -247.746855) (xy 344.35034 -247.724168) (xy 344.350826 -247.698182) (xy 344.358961 -247.64685)
			(xy 344.375027 -247.597423) (xy 344.398627 -247.551117) (xy 344.429181 -247.509074) (xy 344.465935 -247.472329)
			(xy 344.507986 -247.441785) (xy 344.554297 -247.418196) (xy 344.603728 -247.402142) (xy 344.655062 -247.394019)
			(xy 344.681048 -247.39346) (xy 344.6907 -247.393714) (xy 344.70467 -247.393968) (xy 344.729054 -247.380506)
			(xy 344.876628 -247.125998) (xy 344.876374 -247.098566) (xy 344.869008 -247.086374) (xy 344.85751 -247.066848)
			(xy 344.83938 -247.02532) (xy 344.827094 -246.981704) (xy 344.820881 -246.936818) (xy 344.820494 -246.914162)
			(xy 344.820883 -246.89129) (xy 344.827189 -246.845981) (xy 344.839676 -246.801974) (xy 344.858106 -246.760105)
			(xy 344.86977 -246.740426) (xy 344.877136 -246.728488) (xy 344.877644 -246.700548) (xy 344.730832 -246.447818)
			(xy 344.706448 -246.434102) (xy 344.692224 -246.43461) (xy 344.681048 -246.434864) (xy 344.655058 -246.434384)
			(xy 344.603716 -246.426259) (xy 344.554278 -246.4102) (xy 344.507961 -246.386604) (xy 344.465907 -246.356052)
			(xy 344.42915 -246.319297) (xy 344.398598 -246.277242) (xy 344.375001 -246.230926) (xy 344.358942 -246.181488)
			(xy 344.350816 -246.130146) (xy 344.35034 -246.104156) (xy 344.350723 -246.081282) (xy 344.357018 -246.035969)
			(xy 344.369496 -245.991955) (xy 344.387919 -245.95008) (xy 344.399616 -245.93042) (xy 344.407236 -245.918228)
			(xy 344.40749 -245.890288) (xy 344.260932 -245.637812) (xy 344.236548 -245.624096) (xy 344.222324 -245.624604)
			(xy 344.211148 -245.624858) (xy 344.185152 -245.624378) (xy 344.1338 -245.616252) (xy 344.084352 -245.600191)
			(xy 344.038025 -245.576593) (xy 343.995961 -245.546037) (xy 343.959195 -245.509276) (xy 343.928633 -245.467216)
			(xy 343.905027 -245.420893) (xy 343.888959 -245.371447) (xy 343.880825 -245.320096) (xy 343.880825 -245.268104)
			(xy 343.888959 -245.216753) (xy 343.905027 -245.167307) (xy 343.928633 -245.120984) (xy 343.959195 -245.078924)
			(xy 343.995961 -245.042163) (xy 344.038025 -245.011607) (xy 344.084352 -244.988009) (xy 344.1338 -244.971948)
			(xy 344.185152 -244.963822) (xy 344.211148 -244.963442) (xy 344.220546 -244.963696) (xy 344.234516 -244.96395)
			(xy 344.2589 -244.950488) (xy 344.406474 -244.696234) (xy 344.405966 -244.668294) (xy 344.398854 -244.656356)
			(xy 344.387355 -244.636831) (xy 344.369225 -244.595302) (xy 344.35694 -244.551686) (xy 344.350729 -244.506801)
			(xy 344.35034 -244.484144) (xy 344.35082 -244.458154) (xy 344.358946 -244.406813) (xy 344.375005 -244.357375)
			(xy 344.398601 -244.31106) (xy 344.429153 -244.269006) (xy 344.465909 -244.232251) (xy 344.507963 -244.201699)
			(xy 344.554279 -244.178103) (xy 344.603717 -244.162045) (xy 344.655058 -244.15392) (xy 344.681048 -244.153436)
			(xy 344.6907 -244.15369) (xy 344.70467 -244.153944) (xy 344.729054 -244.140482) (xy 344.876628 -243.885974)
			(xy 344.876374 -243.858542) (xy 344.868754 -243.84635) (xy 344.857296 -243.826812) (xy 344.83924 -243.785272)
			(xy 344.827016 -243.741658) (xy 344.82085 -243.696785) (xy 344.820494 -243.674138) (xy 344.820878 -243.651264)
			(xy 344.827175 -243.605952) (xy 344.839653 -243.561939) (xy 344.858076 -243.520064) (xy 344.86977 -243.500402)
			(xy 344.877136 -243.488464) (xy 344.877644 -243.460524) (xy 344.730832 -243.207794) (xy 344.706448 -243.194078)
			(xy 344.692224 -243.194586) (xy 344.681048 -243.19484) (xy 344.655055 -243.19436) (xy 344.603709 -243.186235)
			(xy 344.554266 -243.170178) (xy 344.507944 -243.146583) (xy 344.465883 -243.116032) (xy 344.42912 -243.079278)
			(xy 344.398559 -243.037224) (xy 344.374953 -242.990908) (xy 344.358883 -242.941469) (xy 344.350746 -242.890125)
			(xy 344.35034 -242.864132) (xy 344.350724 -242.841258) (xy 344.357023 -242.795947) (xy 344.369503 -242.751935)
			(xy 344.387929 -242.710062) (xy 344.399616 -242.690396) (xy 344.407236 -242.678204) (xy 344.40749 -242.650264)
			(xy 344.260932 -242.397788) (xy 344.236548 -242.384072) (xy 344.222324 -242.38458) (xy 344.211148 -242.384834)
			(xy 344.185154 -242.384354) (xy 344.133806 -242.376228) (xy 344.084361 -242.360169) (xy 344.038037 -242.336572)
			(xy 343.995976 -242.306018) (xy 343.959213 -242.26926) (xy 343.928653 -242.227203) (xy 343.905049 -242.180883)
			(xy 343.888983 -242.131441) (xy 343.880849 -242.080094) (xy 343.880849 -242.028106) (xy 343.888983 -241.976759)
			(xy 343.905049 -241.927317) (xy 343.928653 -241.880997) (xy 343.959213 -241.83894) (xy 343.995976 -241.802182)
			(xy 344.038038 -241.771628) (xy 344.084361 -241.748031) (xy 344.133806 -241.731972) (xy 344.185154 -241.723846)
			(xy 344.211148 -241.723418) (xy 344.220546 -241.723672) (xy 344.234516 -241.723926) (xy 344.2589 -241.710464)
			(xy 344.406474 -241.45621) (xy 344.405966 -241.42827) (xy 344.398854 -241.416332) (xy 344.387357 -241.396806)
			(xy 344.36923 -241.355277) (xy 344.356947 -241.311661) (xy 344.350739 -241.266776) (xy 344.35034 -241.24412)
			(xy 344.350822 -241.218131) (xy 344.358951 -241.166793) (xy 344.375012 -241.117359) (xy 344.398609 -241.071046)
			(xy 344.429162 -241.028996) (xy 344.465917 -240.992244) (xy 344.50797 -240.961695) (xy 344.554285 -240.938101)
			(xy 344.60372 -240.922044) (xy 344.655059 -240.913919) (xy 344.681048 -240.913412) (xy 344.6907 -240.913666)
			(xy 344.70467 -240.91392) (xy 344.729054 -240.900458) (xy 344.876628 -240.64595) (xy 344.876374 -240.618518)
			(xy 344.868754 -240.606326) (xy 344.857297 -240.586788) (xy 344.839245 -240.545247) (xy 344.827023 -240.501633)
			(xy 344.820861 -240.456761) (xy 344.820494 -240.434114) (xy 344.82088 -240.411241) (xy 344.827179 -240.365929)
			(xy 344.839661 -240.321918) (xy 344.858085 -240.280045) (xy 344.86977 -240.260378) (xy 344.877136 -240.24844)
			(xy 344.877644 -240.2205) (xy 344.731086 -239.967516) (xy 344.706448 -239.954054) (xy 344.692478 -239.954562)
			(xy 344.681048 -239.954816) (xy 344.655056 -239.954336) (xy 344.603711 -239.946211) (xy 344.55427 -239.930153)
			(xy 344.507949 -239.906558) (xy 344.465891 -239.876007) (xy 344.429129 -239.839252) (xy 344.398571 -239.797199)
			(xy 344.374968 -239.750882) (xy 344.358902 -239.701443) (xy 344.350768 -239.6501) (xy 344.35034 -239.624108)
			(xy 344.350731 -239.601193) (xy 344.357067 -239.555804) (xy 344.369617 -239.511727) (xy 344.388142 -239.469808)
			(xy 344.39987 -239.450118) (xy 344.407236 -239.43818) (xy 344.407744 -239.41024) (xy 344.261186 -239.15751)
			(xy 344.236802 -239.144048) (xy 344.222578 -239.144556) (xy 344.211148 -239.14481) (xy 344.185156 -239.14433)
			(xy 344.133811 -239.136205) (xy 344.08437 -239.120147) (xy 344.03805 -239.096552) (xy 343.995992 -239.066)
			(xy 343.959231 -239.029245) (xy 343.928673 -238.987191) (xy 343.905071 -238.940874) (xy 343.889006 -238.891435)
			(xy 343.880873 -238.840092) (xy 343.880873 -238.788108) (xy 343.889006 -238.736765) (xy 343.905071 -238.687326)
			(xy 343.928673 -238.641009) (xy 343.959231 -238.598955) (xy 343.995992 -238.5622) (xy 344.03805 -238.531648)
			(xy 344.08437 -238.508053) (xy 344.133811 -238.491995) (xy 344.185156 -238.48387) (xy 344.211148 -238.483394)
			(xy 344.234064 -238.483782) (xy 344.279456 -238.490111) (xy 344.323537 -238.502655) (xy 344.365461 -238.521173)
			(xy 344.385138 -238.532924) (xy 344.397076 -238.54029) (xy 344.425016 -238.540798) (xy 345.277186 -238.05134)
			(xy 345.290902 -238.026956) (xy 345.290394 -238.012986) (xy 345.290394 -238.004096) (xy 345.290786 -237.981181)
			(xy 345.297122 -237.935792) (xy 345.309672 -237.891715) (xy 345.328195 -237.849796) (xy 345.339924 -237.830106)
			(xy 345.34729 -237.818168) (xy 345.347544 -237.790228) (xy 345.200986 -237.537752) (xy 345.176602 -237.524036)
			(xy 345.162378 -237.524544) (xy 345.151202 -237.524798) (xy 345.125213 -237.524315) (xy 345.073875 -237.516184)
			(xy 345.024441 -237.500122) (xy 344.978128 -237.476524) (xy 344.936077 -237.445972) (xy 344.899323 -237.409217)
			(xy 344.868772 -237.367165) (xy 344.845175 -237.320852) (xy 344.829114 -237.271418) (xy 344.820984 -237.220079)
			(xy 344.820494 -237.19409) (xy 344.820881 -237.171217) (xy 344.827184 -237.125907) (xy 344.839668 -237.081897)
			(xy 344.858095 -237.040027) (xy 344.86977 -237.020354) (xy 344.87739 -237.008162) (xy 344.877644 -236.980222)
			(xy 344.731086 -236.727492) (xy 344.706702 -236.71403) (xy 344.692478 -236.714538) (xy 344.681048 -236.714792)
			(xy 344.655058 -236.714313) (xy 344.603716 -236.706188) (xy 344.554277 -236.69013) (xy 344.507959 -236.666536)
			(xy 344.465903 -236.635986) (xy 344.429145 -236.599233) (xy 344.398589 -236.557182) (xy 344.374988 -236.510867)
			(xy 344.358924 -236.461431) (xy 344.350791 -236.41009) (xy 344.350791 -236.35811) (xy 344.358924 -236.306769)
			(xy 344.374988 -236.257333) (xy 344.398589 -236.211018) (xy 344.429145 -236.168967) (xy 344.465903 -236.132214)
			(xy 344.507959 -236.101664) (xy 344.554277 -236.07807) (xy 344.603716 -236.062012) (xy 344.655058 -236.053887)
			(xy 344.681048 -236.053376) (xy 344.6907 -236.05363) (xy 344.70467 -236.053884) (xy 344.729054 -236.040422)
			(xy 344.876628 -235.785914) (xy 344.876374 -235.758482) (xy 344.869008 -235.74629) (xy 344.857509 -235.726765)
			(xy 344.839377 -235.685236) (xy 344.827089 -235.64162) (xy 344.820874 -235.596735) (xy 344.820494 -235.574078)
			(xy 344.820882 -235.551205) (xy 344.827186 -235.505896) (xy 344.839672 -235.461887) (xy 344.8581 -235.420018)
			(xy 344.86977 -235.400342) (xy 344.877136 -235.388404) (xy 344.877644 -235.360464) (xy 344.730832 -235.107734)
			(xy 344.706448 -235.094018) (xy 344.692224 -235.094526) (xy 344.681048 -235.09478) (xy 344.655057 -235.0943)
			(xy 344.603714 -235.086175) (xy 344.554275 -235.070117) (xy 344.507957 -235.046521) (xy 344.465902 -235.015969)
			(xy 344.429144 -234.979214) (xy 344.398589 -234.93716) (xy 344.374991 -234.890843) (xy 344.35893 -234.841405)
			(xy 344.350801 -234.790063) (xy 344.35034 -234.764072) (xy 344.350729 -234.741199) (xy 344.357034 -234.695891)
			(xy 344.369522 -234.651883) (xy 344.387953 -234.610016) (xy 344.399616 -234.590336) (xy 344.407236 -234.578144)
			(xy 344.40749 -234.550204) (xy 344.260932 -234.297728) (xy 344.236548 -234.284012) (xy 344.222324 -234.28452)
			(xy 344.211148 -234.284774) (xy 344.185159 -234.284295) (xy 344.13382 -234.27617) (xy 344.084384 -234.260114)
			(xy 344.038069 -234.236521) (xy 343.996015 -234.205973) (xy 343.959258 -234.169221) (xy 343.928704 -234.127172)
			(xy 343.905105 -234.08086) (xy 343.889041 -234.031427) (xy 343.880909 -233.980089) (xy 343.880909 -233.928111)
			(xy 343.889041 -233.876773) (xy 343.905105 -233.82734) (xy 343.928704 -233.781028) (xy 343.959258 -233.738979)
			(xy 343.996015 -233.702227) (xy 344.038069 -233.671679) (xy 344.084384 -233.648086) (xy 344.13382 -233.63203)
			(xy 344.185159 -233.623905) (xy 344.211148 -233.623358) (xy 344.220546 -233.623612) (xy 344.234516 -233.623866)
			(xy 344.2589 -233.610404) (xy 344.406474 -233.35615) (xy 344.405966 -233.32821) (xy 344.398854 -233.316272)
			(xy 344.387354 -233.296747) (xy 344.369222 -233.255219) (xy 344.356935 -233.211603) (xy 344.350721 -233.166717)
			(xy 344.35034 -233.14406) (xy 344.350826 -233.118074) (xy 344.358963 -233.066743) (xy 344.375029 -233.017317)
			(xy 344.39863 -232.971013) (xy 344.429183 -232.928971) (xy 344.465938 -232.892226) (xy 344.507988 -232.861684)
			(xy 344.554299 -232.838095) (xy 344.603729 -232.822042) (xy 344.655062 -232.813919) (xy 344.681048 -232.813352)
			(xy 344.6907 -232.813606) (xy 344.70467 -232.81386) (xy 344.729054 -232.800398) (xy 344.876628 -232.54589)
			(xy 344.876374 -232.518458) (xy 344.868754 -232.506266) (xy 344.857295 -232.486728) (xy 344.839237 -232.445188)
			(xy 344.827011 -232.401575) (xy 344.820843 -232.356702) (xy 344.820494 -232.334054) (xy 344.820877 -232.31118)
			(xy 344.827171 -232.265866) (xy 344.839648 -232.221852) (xy 344.858069 -232.179976) (xy 344.86977 -232.160318)
			(xy 344.877136 -232.14838) (xy 344.877644 -232.12044) (xy 344.731086 -231.867456) (xy 344.706702 -231.853994)
			(xy 344.692478 -231.854502) (xy 344.681048 -231.854756) (xy 344.655053 -231.854276) (xy 344.603701 -231.84615)
			(xy 344.554253 -231.83009) (xy 344.507926 -231.806491) (xy 344.465862 -231.775935) (xy 344.429096 -231.739175)
			(xy 344.398534 -231.697115) (xy 344.374929 -231.650792) (xy 344.358861 -231.601346) (xy 344.350727 -231.549995)
			(xy 344.350727 -231.498005) (xy 344.358861 -231.446654) (xy 344.374929 -231.397208) (xy 344.398534 -231.350885)
			(xy 344.429096 -231.308825) (xy 344.465862 -231.272065) (xy 344.507926 -231.241509) (xy 344.554253 -231.21791)
			(xy 344.603701 -231.20185) (xy 344.655053 -231.193724) (xy 344.681048 -231.19334) (xy 344.6907 -231.193594)
			(xy 344.70467 -231.193848) (xy 344.729054 -231.180386) (xy 344.890852 -230.90124) (xy 344.891106 -230.874824)
			(xy 344.884502 -230.862886) (xy 344.872378 -230.840013) (xy 344.855162 -230.791197) (xy 344.846421 -230.740177)
			(xy 344.845894 -230.714296) (xy 344.846438 -230.688072) (xy 344.855401 -230.636396) (xy 344.873063 -230.587012)
			(xy 344.885518 -230.563928) (xy 344.892122 -230.55199) (xy 344.892122 -230.52532) (xy 344.731086 -230.247444)
			(xy 344.706702 -230.233982) (xy 344.692478 -230.23449) (xy 344.681048 -230.234744) (xy 344.655053 -230.234264)
			(xy 344.603703 -230.226138) (xy 344.554257 -230.210078) (xy 344.507932 -230.186481) (xy 344.46587 -230.155926)
			(xy 344.429105 -230.119167) (xy 344.398544 -230.077109) (xy 344.37494 -230.030787) (xy 344.358873 -229.981343)
			(xy 344.350739 -229.929994) (xy 344.350739 -229.878006) (xy 344.358873 -229.826657) (xy 344.37494 -229.777213)
			(xy 344.398544 -229.730891) (xy 344.429105 -229.688833) (xy 344.46587 -229.652074) (xy 344.507932 -229.621519)
			(xy 344.554257 -229.597922) (xy 344.603703 -229.581862) (xy 344.655053 -229.573736) (xy 344.681048 -229.573328)
			(xy 344.6907 -229.573582) (xy 344.70467 -229.573836) (xy 344.729054 -229.560374) (xy 344.876628 -229.30612)
			(xy 344.87612 -229.278434) (xy 344.868754 -229.266496) (xy 344.857299 -229.246957) (xy 344.839251 -229.205416)
			(xy 344.827033 -229.161802) (xy 344.820875 -229.11693) (xy 344.820494 -229.094284) (xy 344.820882 -229.071411)
			(xy 344.827185 -229.026102) (xy 344.83967 -228.982092) (xy 344.858097 -228.940222) (xy 344.86977 -228.920548)
			(xy 344.87739 -228.908356) (xy 344.877644 -228.880416) (xy 344.731086 -228.627686) (xy 344.706702 -228.614224)
			(xy 344.692478 -228.614732) (xy 344.681048 -228.614986) (xy 344.655265 -228.614488) (xy 344.604325 -228.606476)
			(xy 344.555246 -228.590654) (xy 344.509218 -228.567405) (xy 344.467357 -228.537293) (xy 344.430677 -228.501049)
			(xy 344.400068 -228.45955) (xy 344.387678 -228.436932) (xy 344.381074 -228.424232) (xy 344.356944 -228.4095)
			(xy 344.065098 -228.4095) (xy 344.040968 -228.424232) (xy 344.034364 -228.436932) (xy 344.022024 -228.459579)
			(xy 343.991408 -228.50108) (xy 343.95472 -228.537324) (xy 343.91285 -228.567434) (xy 343.866814 -228.59068)
			(xy 343.817727 -228.606496) (xy 343.76678 -228.614501) (xy 343.740994 -228.614986) (xy 343.715006 -228.614502)
			(xy 343.663669 -228.60637) (xy 343.614237 -228.590307) (xy 343.567926 -228.566709) (xy 343.525877 -228.536156)
			(xy 343.489126 -228.499402) (xy 343.458577 -228.45735) (xy 343.434982 -228.411037) (xy 343.418923 -228.361604)
			(xy 343.410795 -228.310266) (xy 343.410286 -228.284278) (xy 343.410679 -228.261364) (xy 343.417017 -228.215975)
			(xy 343.429569 -228.171899) (xy 343.448094 -228.129981) (xy 343.459816 -228.110288) (xy 343.467182 -228.098096)
			(xy 343.46769 -228.070156) (xy 343.321132 -227.81768) (xy 343.296748 -227.804218) (xy 343.282524 -227.804726)
			(xy 343.271094 -227.80498) (xy 343.245106 -227.804496) (xy 343.19377 -227.796364) (xy 343.144338 -227.780301)
			(xy 343.098027 -227.756703) (xy 343.055979 -227.72615) (xy 343.019228 -227.689395) (xy 342.98868 -227.647344)
			(xy 342.965086 -227.601031) (xy 342.949028 -227.551597) (xy 342.940901 -227.50026) (xy 342.940386 -227.474272)
			(xy 342.940779 -227.451358) (xy 342.947118 -227.40597) (xy 342.959671 -227.361894) (xy 342.978196 -227.319977)
			(xy 342.989916 -227.300282) (xy 342.997282 -227.288344) (xy 342.99779 -227.260404) (xy 342.851232 -227.007674)
			(xy 342.826594 -226.994212) (xy 342.812624 -226.99472) (xy 342.801194 -226.994974) (xy 342.775206 -226.99449)
			(xy 342.72387 -226.986358) (xy 342.674439 -226.970295) (xy 342.628129 -226.946696) (xy 342.586081 -226.916143)
			(xy 342.549331 -226.879389) (xy 342.518783 -226.837337) (xy 342.49519 -226.791024) (xy 342.479132 -226.741591)
			(xy 342.471006 -226.690254) (xy 342.470486 -226.664266) (xy 342.470875 -226.641393) (xy 342.47718 -226.596085)
			(xy 342.489667 -226.552077) (xy 342.508096 -226.510208) (xy 342.519762 -226.49053) (xy 342.527382 -226.478338)
			(xy 342.527636 -226.450398) (xy 342.381078 -226.197668) (xy 342.356694 -226.184206) (xy 342.34247 -226.184714)
			(xy 342.33104 -226.184968) (xy 342.30505 -226.184488) (xy 342.253709 -226.176361) (xy 342.204271 -226.160302)
			(xy 342.157956 -226.136706) (xy 342.115902 -226.106154) (xy 342.079146 -226.069398) (xy 342.048594 -226.027344)
			(xy 342.024998 -225.981029) (xy 342.008939 -225.931591) (xy 342.000812 -225.88025) (xy 342.000332 -225.85426)
			(xy 342.00072 -225.831344) (xy 342.007049 -225.785952) (xy 342.019593 -225.741871) (xy 342.038112 -225.699947)
			(xy 342.049862 -225.68027) (xy 342.057228 -225.668332) (xy 342.057482 -225.640392) (xy 341.910924 -225.387916)
			(xy 341.88654 -225.3742) (xy 341.872316 -225.374708) (xy 341.86114 -225.374962) (xy 341.83515 -225.374482)
			(xy 341.783809 -225.366355) (xy 341.734372 -225.350296) (xy 341.688057 -225.3267) (xy 341.646004 -225.296147)
			(xy 341.609249 -225.259392) (xy 341.578697 -225.217338) (xy 341.555102 -225.171022) (xy 341.539043 -225.121585)
			(xy 341.530918 -225.070244) (xy 341.530432 -225.044254) (xy 341.530815 -225.02138) (xy 341.53711 -224.976067)
			(xy 341.549588 -224.932053) (xy 341.568011 -224.890178) (xy 341.579708 -224.870518) (xy 341.587328 -224.858326)
			(xy 341.587582 -224.83064) (xy 341.441024 -224.577656) (xy 341.41664 -224.564194) (xy 341.402416 -224.564702)
			(xy 341.390986 -224.564956) (xy 341.364998 -224.564445) (xy 341.313663 -224.556313) (xy 341.264231 -224.540252)
			(xy 341.21792 -224.516656) (xy 341.17587 -224.486107) (xy 341.139115 -224.449356) (xy 341.108562 -224.407309)
			(xy 341.084961 -224.361001) (xy 341.068894 -224.311571) (xy 341.060757 -224.260236) (xy 341.060278 -224.234248)
			(xy 341.060666 -224.211332) (xy 341.066995 -224.16594) (xy 341.079539 -224.121859) (xy 341.098057 -224.079935)
			(xy 341.109808 -224.060258) (xy 341.117174 -224.04832) (xy 341.117428 -224.02038) (xy 340.50097 -222.957898)
			(xy 340.476586 -222.944182) (xy 340.462362 -222.94469) (xy 340.451186 -222.944944) (xy 340.425199 -222.944433)
			(xy 340.373864 -222.936301) (xy 340.324433 -222.92024) (xy 340.278122 -222.896644) (xy 340.236073 -222.866094)
			(xy 340.19932 -222.829344) (xy 340.168768 -222.787296) (xy 340.145169 -222.740988) (xy 340.129104 -222.691558)
			(xy 340.120968 -222.640223) (xy 340.120478 -222.614236) (xy 340.120862 -222.591362) (xy 340.127159 -222.54605)
			(xy 340.139637 -222.502036) (xy 340.158059 -222.460161) (xy 340.169754 -222.4405) (xy 340.177374 -222.428308)
			(xy 340.177628 -222.400368) (xy 339.985858 -222.06966) (xy 339.965284 -222.056452) (xy 339.953092 -222.055182)
			(xy 339.931412 -222.05259) (xy 339.889333 -222.040945) (xy 339.849864 -222.022279) (xy 339.814167 -221.997142)
			(xy 339.798406 -221.98203) (xy 332.98638 -215.170004) (xy 332.969123 -215.151962) (xy 332.941372 -215.110467)
			(xy 332.922266 -215.064349) (xy 332.912543 -215.015386) (xy 332.911958 -214.990426) (xy 332.911958 -172.717206)
			(xy 332.912538 -172.69225) (xy 332.922295 -172.643299) (xy 332.941414 -172.597193) (xy 332.969161 -172.555703)
			(xy 332.98638 -172.537628) (xy 333.49438 -172.029628) (xy 333.51242 -172.012367) (xy 333.553913 -171.984608)
			(xy 333.600032 -171.965496) (xy 333.648997 -171.955767) (xy 333.673958 -171.955206) (xy 337.35772 -171.955206)
			(xy 337.367789 -171.95478) (xy 337.386389 -171.947061) (xy 337.393788 -171.94022) (xy 337.63077 -171.703238)
			(xy 337.63761 -171.695838) (xy 337.645326 -171.677239) (xy 337.645756 -171.66717) (xy 337.645756 -156.185108)
			(xy 337.645248 -156.1846) (xy 337.645248 -156.17825) (xy 337.638136 -156.166058) (xy 337.626808 -156.146186)
			(xy 337.610716 -156.103372) (xy 337.602538 -156.058371) (xy 337.602538 -156.012633) (xy 337.610715 -155.967631)
			(xy 337.626806 -155.924817) (xy 337.638136 -155.904946) (xy 337.641692 -155.899104) (xy 337.645248 -155.885642)
			(xy 337.645248 -150.087584) (xy 337.644797 -150.077558) (xy 337.637201 -150.059004) (xy 337.630516 -150.051516)
			(xy 337.292188 -149.713188) (xy 337.284762 -149.706414) (xy 337.266166 -149.698826) (xy 337.25612 -149.698456)
			(xy 314.004706 -149.698456) (xy 313.994678 -149.698903) (xy 313.976119 -149.706494) (xy 313.968638 -149.713188)
			(xy 312.861198 -150.820628) (xy 312.854356 -150.828028) (xy 312.846632 -150.846626) (xy 312.846212 -150.856696)
			(xy 312.846212 -193.491104) (xy 312.849514 -193.49974) (xy 312.857217 -193.521416) (xy 312.865532 -193.566657)
			(xy 312.866024 -193.589656) (xy 312.865501 -193.612652) (xy 312.857191 -193.657889) (xy 312.849514 -193.679572)
			(xy 312.846212 -193.688208) (xy 312.846212 -193.715132) (xy 312.845958 -193.71564) (xy 312.845958 -195.123816)
			(xy 312.865516 -195.15074) (xy 312.881518 -195.155566) (xy 312.906691 -195.163999) (xy 312.954405 -195.187269)
			(xy 312.998139 -195.217362) (xy 313.036922 -195.253611) (xy 313.069897 -195.295214) (xy 313.096334 -195.34125)
			(xy 313.115646 -195.390699) (xy 313.127407 -195.442466) (xy 313.131356 -195.495405) (xy 313.127405 -195.548345)
			(xy 313.115643 -195.600112) (xy 313.096329 -195.64956) (xy 313.069891 -195.695595) (xy 313.036915 -195.737197)
			(xy 312.99813 -195.773445) (xy 312.954396 -195.803537) (xy 312.906681 -195.826805) (xy 312.881518 -195.83527)
			(xy 312.865516 -195.840096) (xy 312.845958 -195.86702) (xy 312.845958 -212.980016) (xy 326.752462 -212.980016)
			(xy 326.756491 -212.837695) (xy 326.768566 -212.69583) (xy 326.788647 -212.554876) (xy 326.81667 -212.415283)
			(xy 326.852546 -212.277499) (xy 326.89616 -212.141966) (xy 326.947372 -212.009117) (xy 327.006018 -211.879378)
			(xy 327.071909 -211.753165) (xy 327.144836 -211.630882) (xy 327.224564 -211.51292) (xy 327.310838 -211.399658)
			(xy 327.403382 -211.291459) (xy 327.501898 -211.188668) (xy 327.606073 -211.091616) (xy 327.715571 -211.000612)
			(xy 327.830042 -210.91595) (xy 327.94912 -210.837899) (xy 328.072423 -210.76671) (xy 328.199556 -210.702611)
			(xy 328.330112 -210.645807) (xy 328.463672 -210.596481) (xy 328.599809 -210.554789) (xy 328.738087 -210.520866)
			(xy 328.878062 -210.494821) (xy 329.019287 -210.476736) (xy 329.161308 -210.466671) (xy 329.303672 -210.464656)
			(xy 329.445922 -210.470699) (xy 329.587602 -210.484779) (xy 329.728258 -210.506853) (xy 329.86744 -210.536849)
			(xy 330.004702 -210.574671) (xy 330.139605 -210.620199) (xy 330.271716 -210.673285) (xy 330.400612 -210.733761)
			(xy 330.52588 -210.801432) (xy 330.647119 -210.876082) (xy 330.76394 -210.957471) (xy 330.87597 -211.045339)
			(xy 330.982849 -211.139405) (xy 331.084235 -211.239366) (xy 331.179804 -211.344904) (xy 331.269249 -211.455679)
			(xy 331.352283 -211.571337) (xy 331.428641 -211.691507) (xy 331.498078 -211.815805) (xy 331.560371 -211.943832)
			(xy 331.615322 -212.075179) (xy 331.662754 -212.209424) (xy 331.702515 -212.346137) (xy 331.734477 -212.484881)
			(xy 331.758539 -212.625211) (xy 331.774623 -212.766677) (xy 331.782679 -212.908827) (xy 331.783182 -212.980016)
			(xy 331.782679 -213.051205) (xy 331.774623 -213.193355) (xy 331.758539 -213.334821) (xy 331.734477 -213.475151)
			(xy 331.702515 -213.613895) (xy 331.662754 -213.750608) (xy 331.615322 -213.884853) (xy 331.560371 -214.0162)
			(xy 331.498078 -214.144227) (xy 331.428641 -214.268525) (xy 331.352283 -214.388695) (xy 331.269249 -214.504353)
			(xy 331.179804 -214.615128) (xy 331.084235 -214.720666) (xy 330.982849 -214.820627) (xy 330.87597 -214.914693)
			(xy 330.76394 -215.002561) (xy 330.647119 -215.08395) (xy 330.52588 -215.1586) (xy 330.400612 -215.226271)
			(xy 330.271716 -215.286747) (xy 330.139605 -215.339833) (xy 330.004702 -215.385361) (xy 329.86744 -215.423183)
			(xy 329.728258 -215.453179) (xy 329.587602 -215.475253) (xy 329.445922 -215.489333) (xy 329.303672 -215.495376)
			(xy 329.161308 -215.493361) (xy 329.019287 -215.483296) (xy 328.878062 -215.465211) (xy 328.738087 -215.439166)
			(xy 328.599809 -215.405243) (xy 328.463672 -215.363551) (xy 328.330112 -215.314225) (xy 328.199556 -215.257421)
			(xy 328.072423 -215.193322) (xy 327.94912 -215.122133) (xy 327.830042 -215.044082) (xy 327.715571 -214.95942)
			(xy 327.606073 -214.868416) (xy 327.501898 -214.771364) (xy 327.403382 -214.668573) (xy 327.310838 -214.560374)
			(xy 327.224564 -214.447112) (xy 327.144836 -214.32915) (xy 327.071909 -214.206867) (xy 327.006018 -214.080654)
			(xy 326.947372 -213.950915) (xy 326.89616 -213.818066) (xy 326.852546 -213.682533) (xy 326.81667 -213.544749)
			(xy 326.788647 -213.405156) (xy 326.768566 -213.264202) (xy 326.756491 -213.122337) (xy 326.752462 -212.980016)
			(xy 312.845958 -212.980016) (xy 312.845958 -226.311968) (xy 312.846395 -226.322031) (xy 312.854133 -226.340612)
			(xy 312.860944 -226.348036) (xy 313.190128 -226.67722) (xy 313.197524 -226.684071) (xy 313.216123 -226.691808)
			(xy 313.226196 -226.692206) (xy 313.226958 -226.692206) (xy 313.251325 -226.692786) (xy 313.299155 -226.702128)
			(xy 313.321954 -226.710748) (xy 313.331098 -226.714304) (xy 327.011284 -226.714304) (xy 327.035382 -226.71487)
			(xy 327.082714 -226.723957) (xy 327.127483 -226.74181) (xy 327.16808 -226.767786) (xy 327.203049 -226.800954)
			(xy 327.217532 -226.820222) (xy 327.225197 -226.829639) (xy 327.246809 -226.840629) (xy 327.258934 -226.841304)
			(xy 335.191354 -226.841304) (xy 335.207928 -226.841872) (xy 335.239939 -226.850486) (xy 335.268646 -226.867064)
			(xy 335.280762 -226.878388) (xy 335.562194 -227.15982) (xy 335.573525 -227.171932) (xy 335.590107 -227.200641)
			(xy 335.598738 -227.232652) (xy 335.599278 -227.249228) (xy 335.599278 -228.194108) (xy 335.601056 -228.200458)
			(xy 335.606067 -228.221049) (xy 335.611418 -228.263088) (xy 335.611724 -228.284278) (xy 335.611419 -228.305468)
			(xy 335.60607 -228.347508) (xy 335.601056 -228.368098) (xy 335.599278 -228.374448) (xy 335.599278 -229.813866)
			(xy 335.601056 -229.820216) (xy 335.606069 -229.840807) (xy 335.611426 -229.882846) (xy 335.611724 -229.904036)
			(xy 335.611415 -229.925225) (xy 335.606059 -229.967263) (xy 335.601056 -229.987856) (xy 335.599278 -229.994206)
			(xy 335.599278 -231.433878) (xy 335.601056 -231.440228) (xy 335.606069 -231.460819) (xy 335.611424 -231.502858)
			(xy 335.611724 -231.524048) (xy 335.611421 -231.545238) (xy 335.606076 -231.587279) (xy 335.601056 -231.607868)
			(xy 335.599278 -231.614218) (xy 335.599278 -233.05389) (xy 335.601056 -233.06024) (xy 335.606068 -233.080831)
			(xy 335.611421 -233.12287) (xy 335.611724 -233.14406) (xy 335.61142 -233.16525) (xy 335.606073 -233.20729)
			(xy 335.601056 -233.22788) (xy 335.599278 -233.23423) (xy 335.599278 -234.673902) (xy 335.601056 -234.680252)
			(xy 335.606067 -234.700843) (xy 335.611419 -234.742882) (xy 335.611724 -234.764072) (xy 335.611419 -234.785262)
			(xy 335.606071 -234.827302) (xy 335.601056 -234.847892) (xy 335.599278 -234.854242) (xy 335.599278 -236.293914)
			(xy 335.601056 -236.300264) (xy 335.606066 -236.320855) (xy 335.611417 -236.362894) (xy 335.611724 -236.384084)
			(xy 335.611419 -236.405274) (xy 335.606069 -236.447313) (xy 335.601056 -236.467904) (xy 335.599278 -236.474254)
			(xy 335.599278 -237.913926) (xy 335.601056 -237.920276) (xy 335.606066 -237.940867) (xy 335.611415 -237.982906)
			(xy 335.611724 -238.004096) (xy 335.611418 -238.025286) (xy 335.606067 -238.067325) (xy 335.601056 -238.087916)
			(xy 335.599278 -238.094266) (xy 335.599278 -239.533938) (xy 335.601056 -239.540288) (xy 335.606065 -239.560879)
			(xy 335.611412 -239.602918) (xy 335.611724 -239.624108) (xy 335.611417 -239.645298) (xy 335.606064 -239.687336)
			(xy 335.601056 -239.707928) (xy 335.599278 -239.714278) (xy 335.599278 -241.15395) (xy 335.601056 -241.1603)
			(xy 335.606064 -241.180891) (xy 335.61141 -241.222931) (xy 335.611724 -241.24412) (xy 335.611416 -241.265309)
			(xy 335.606062 -241.307348) (xy 335.601056 -241.32794) (xy 335.599278 -241.33429) (xy 335.599278 -242.773962)
			(xy 335.601056 -242.780312) (xy 335.606063 -242.800903) (xy 335.611408 -242.842943) (xy 335.611724 -242.864132)
			(xy 335.611416 -242.885321) (xy 335.60606 -242.927359) (xy 335.601056 -242.947952) (xy 335.599278 -242.954302)
			(xy 335.599278 -244.393974) (xy 335.601056 -244.400324) (xy 335.606069 -244.420915) (xy 335.611424 -244.462954)
			(xy 335.611724 -244.484144) (xy 335.611421 -244.505334) (xy 335.606076 -244.547375) (xy 335.601056 -244.567964)
			(xy 335.599278 -244.574314) (xy 335.599278 -246.013986) (xy 335.601056 -246.020336) (xy 335.606068 -246.040927)
			(xy 335.611422 -246.082966) (xy 335.611724 -246.104156) (xy 335.61142 -246.125346) (xy 335.606074 -246.167387)
			(xy 335.601056 -246.187976) (xy 335.599278 -246.194326) (xy 335.599278 -247.633998) (xy 335.601056 -247.640348)
			(xy 335.606067 -247.660939) (xy 335.61142 -247.702978) (xy 335.611724 -247.724168) (xy 335.61142 -247.745358)
			(xy 335.606072 -247.787398) (xy 335.601056 -247.807988) (xy 335.599278 -247.814338) (xy 335.599278 -249.25401)
			(xy 335.601056 -249.26036) (xy 335.606067 -249.280951) (xy 335.611418 -249.32299) (xy 335.611724 -249.34418)
			(xy 335.611419 -249.36537) (xy 335.60607 -249.40741) (xy 335.601056 -249.428) (xy 335.599278 -249.43435)
			(xy 335.599278 -251.996448) (xy 335.599709 -252.006515) (xy 335.607433 -252.025109) (xy 335.614264 -252.032516)
			(xy 336.6389 -253.057152) (xy 336.65922 -253.064772) (xy 336.670396 -253.064264) (xy 336.691224 -253.063502)
			(xy 336.71721 -253.064013) (xy 336.768541 -253.072147) (xy 336.817967 -253.08821) (xy 336.864273 -253.111807)
			(xy 336.906317 -253.142358) (xy 336.943064 -253.179109) (xy 336.97361 -253.221156) (xy 336.997203 -253.267464)
			(xy 337.013261 -253.316892) (xy 337.021389 -253.368224) (xy 337.021932 -253.39421) (xy 337.02117 -253.415038)
			(xy 337.020662 -253.426214) (xy 337.028282 -253.446534) (xy 338.331302 -254.749554) (xy 338.367624 -254.752856)
			(xy 338.382864 -254.742188) (xy 338.403726 -254.72834) (xy 338.448741 -254.706415) (xy 338.496543 -254.691513)
			(xy 338.546043 -254.683975) (xy 338.571078 -254.683514) (xy 338.597068 -254.683995) (xy 338.648408 -254.692124)
			(xy 338.697844 -254.708185) (xy 338.744158 -254.731782) (xy 338.786211 -254.762334) (xy 338.822966 -254.799089)
			(xy 338.853518 -254.841142) (xy 338.877115 -254.887456) (xy 338.893176 -254.936892) (xy 338.901305 -254.988232)
			(xy 338.901786 -255.014222) (xy 338.901351 -255.039261) (xy 338.893843 -255.088773) (xy 338.878943 -255.136582)
			(xy 338.856992 -255.181592) (xy 338.843112 -255.202436) (xy 338.832444 -255.217676) (xy 338.835746 -255.253998)
			(xy 339.07095 -255.489202) (xy 339.085174 -255.496314) (xy 339.093048 -255.497584) (xy 339.118246 -255.502112)
			(xy 339.166941 -255.517909) (xy 339.212624 -255.541016) (xy 339.254204 -255.57088) (xy 339.29069 -255.606791)
			(xy 339.321212 -255.647891) (xy 339.333586 -255.670304) (xy 339.34019 -255.68275) (xy 339.364574 -255.697482)
			(xy 339.657436 -255.697482) (xy 339.68182 -255.68275) (xy 339.688424 -255.670304) (xy 339.700795 -255.647795)
			(xy 339.731422 -255.606565) (xy 339.768058 -255.570569) (xy 339.809821 -255.540674) (xy 339.855707 -255.517599)
			(xy 339.904609 -255.5019) (xy 339.955352 -255.493955) (xy 340.006712 -255.493955) (xy 340.057455 -255.5019)
			(xy 340.106357 -255.517599) (xy 340.152243 -255.540674) (xy 340.194006 -255.570569) (xy 340.230642 -255.606565)
			(xy 340.261269 -255.647795) (xy 340.27364 -255.670304) (xy 340.280244 -255.68275) (xy 340.304628 -255.697482)
			(xy 340.59749 -255.697482) (xy 340.621874 -255.68275) (xy 340.628478 -255.670304) (xy 340.640849 -255.647795)
			(xy 340.671476 -255.606565) (xy 340.708112 -255.570569) (xy 340.749875 -255.540674) (xy 340.795761 -255.517599)
			(xy 340.844663 -255.5019) (xy 340.895406 -255.493955) (xy 340.946766 -255.493955) (xy 340.997509 -255.5019)
			(xy 341.046411 -255.517599) (xy 341.092297 -255.540674) (xy 341.13406 -255.570569) (xy 341.170696 -255.606565)
			(xy 341.201323 -255.647795) (xy 341.213694 -255.670304) (xy 341.220298 -255.68275) (xy 341.244682 -255.697482)
			(xy 341.537544 -255.697482) (xy 341.561928 -255.68275) (xy 341.568532 -255.670304) (xy 341.580903 -255.647795)
			(xy 341.61153 -255.606565) (xy 341.648166 -255.570569) (xy 341.689929 -255.540674) (xy 341.735815 -255.517599)
			(xy 341.784717 -255.5019) (xy 341.83546 -255.493955) (xy 341.88682 -255.493955) (xy 341.937563 -255.5019)
			(xy 341.986465 -255.517599) (xy 342.032351 -255.540674) (xy 342.074114 -255.570569) (xy 342.11075 -255.606565)
			(xy 342.141377 -255.647795) (xy 342.153748 -255.670304) (xy 342.160352 -255.68275) (xy 342.184736 -255.697482)
			(xy 342.477598 -255.697482) (xy 342.501982 -255.68275) (xy 342.508586 -255.670304) (xy 342.520957 -255.647795)
			(xy 342.551584 -255.606565) (xy 342.58822 -255.570569) (xy 342.629983 -255.540674) (xy 342.675869 -255.517599)
			(xy 342.724771 -255.5019) (xy 342.775514 -255.493955) (xy 342.826874 -255.493955) (xy 342.877617 -255.5019)
			(xy 342.926519 -255.517599) (xy 342.972405 -255.540674) (xy 343.014168 -255.570569) (xy 343.050804 -255.606565)
			(xy 343.081431 -255.647795) (xy 343.093802 -255.670304) (xy 343.100406 -255.68275) (xy 343.12479 -255.697482)
			(xy 343.417398 -255.697482) (xy 343.441782 -255.68275) (xy 343.448386 -255.670304) (xy 343.460751 -255.647789)
			(xy 343.49137 -255.606549) (xy 343.528003 -255.570545) (xy 343.569768 -255.540645) (xy 343.615657 -255.517569)
			(xy 343.664564 -255.501875) (xy 343.715312 -255.493939) (xy 343.740994 -255.49352) (xy 343.766983 -255.494003)
			(xy 343.81832 -255.502133) (xy 343.867754 -255.518195) (xy 343.914066 -255.541793) (xy 343.956116 -255.572346)
			(xy 343.992868 -255.609101) (xy 344.023418 -255.651153) (xy 344.047013 -255.697466) (xy 344.063072 -255.746901)
			(xy 344.071199 -255.798239) (xy 344.071702 -255.824228) (xy 344.071448 -255.83642) (xy 344.07094 -255.850644)
			(xy 344.084656 -255.875282) (xy 344.933778 -256.363216) (xy 344.962226 -256.362454) (xy 344.974164 -256.354834)
			(xy 344.99411 -256.342664) (xy 345.036702 -256.323456) (xy 345.081578 -256.310447) (xy 345.12784 -256.303899)
			(xy 345.151202 -256.303526) (xy 345.164664 -256.30378) (xy 345.178888 -256.304288) (xy 345.20378 -256.290826)
			(xy 345.349068 -256.040382) (xy 345.34856 -256.012188) (xy 345.34094 -255.999996) (xy 345.328965 -255.980154)
			(xy 345.310074 -255.937833) (xy 345.297271 -255.893292) (xy 345.290804 -255.8474) (xy 345.290394 -255.824228)
			(xy 345.290904 -255.798241) (xy 345.299034 -255.746906) (xy 345.315095 -255.697476) (xy 345.338691 -255.651166)
			(xy 345.369241 -255.609118) (xy 345.405992 -255.572367) (xy 345.44804 -255.541817) (xy 345.49435 -255.518221)
			(xy 345.54378 -255.50216) (xy 345.595115 -255.49403) (xy 345.647089 -255.49403) (xy 345.698424 -255.50216)
			(xy 345.747854 -255.518221) (xy 345.794164 -255.541817) (xy 345.836212 -255.572367) (xy 345.872963 -255.609118)
			(xy 345.903513 -255.651166) (xy 345.927109 -255.697476) (xy 345.94317 -255.746906) (xy 345.9513 -255.798241)
			(xy 345.95181 -255.824228) (xy 345.951556 -255.83642) (xy 345.951048 -255.850644) (xy 345.964764 -255.875282)
			(xy 346.813886 -256.363216)
		)
		(stroke
			(width 0)
			(type solid)
		)
		(fill yes)
		(layer "In8.Cu")
		(net "PVDD18_S5_P0")
	)
	(gr_poly
		(pts
			(xy 89.391744 -256.49301)
			(arc
				(start 89.398348 -256.480564)
				(mid 89.690956 -256.303728)
				(end 89.983564 -256.480564)
			)
			(xy 89.990168 -256.49301) (xy 90.014552 -256.507742) (xy 90.307414 -256.507742) (xy 90.331798 -256.49301)
			(arc
				(start 90.338402 -256.480564)
				(mid 90.63101 -256.303728)
				(end 90.923618 -256.480564)
			)
			(xy 90.930222 -256.49301) (xy 90.954606 -256.507742) (xy 91.247468 -256.507742) (xy 91.271852 -256.49301)
			(arc
				(start 91.278456 -256.480564)
				(mid 91.571064 -256.303728)
				(end 91.863672 -256.480564)
			)
			(xy 91.870276 -256.49301) (xy 91.89466 -256.507742) (xy 92.21597 -256.507742) (xy 92.239592 -256.494026)
			(arc
				(start 92.24645 -256.482342)
				(mid 92.511118 -256.329205)
				(end 92.775786 -256.482342)
			)
			(xy 92.782644 -256.494026) (xy 92.806266 -256.507742) (xy 93.127322 -256.507742) (xy 93.151706 -256.49301)
			(arc
				(start 93.15831 -256.480564)
				(mid 93.450918 -256.303728)
				(end 93.743526 -256.480564)
			)
			(xy 93.75013 -256.49301) (xy 93.774514 -256.507742) (xy 94.067376 -256.507742) (xy 94.09176 -256.49301)
			(arc
				(start 94.098364 -256.480564)
				(mid 94.390972 -256.303728)
				(end 94.68358 -256.480564)
			)
			(xy 94.690184 -256.49301) (xy 94.714568 -256.507742) (xy 95.035878 -256.507742) (xy 95.0595 -256.494026)
			(arc
				(start 95.066358 -256.482342)
				(mid 95.178467 -256.370058)
				(end 95.331788 -256.32918)
			)
			(xy 95.345758 -256.32918) (xy 95.368872 -256.315972) (xy 95.528892 -256.040636) (xy 95.528384 -256.012188)
			(arc
				(start 95.520764 -256.00025)
				(mid 95.483115 -255.915926)
				(end 95.470218 -255.824482)
			)
			(arc
				(start 95.470218 -255.824482)
				(mid 95.800926 -255.493774)
				(end 96.131634 -255.824482)
			)
			(xy 96.13138 -255.83642) (xy 96.130872 -255.850644) (xy 96.144588 -255.875282) (xy 96.993964 -256.363216)
			(xy 97.022158 -256.362708)
			(arc
				(start 97.03435 -256.355088)
				(mid 97.119096 -256.316858)
				(end 97.211134 -256.30378)
			)
			(xy 97.224596 -256.304034) (xy 97.23882 -256.304542) (xy 97.263458 -256.291334) (xy 97.409 -256.040382)
			(xy 97.408492 -256.012188)
			(arc
				(start 97.400872 -256.00025)
				(mid 97.363223 -255.915926)
				(end 97.350326 -255.824482)
			)
			(arc
				(start 97.350326 -255.824482)
				(mid 97.681034 -255.493774)
				(end 98.011742 -255.824482)
			)
			(xy 98.011488 -255.83642) (xy 98.01098 -255.850644) (xy 98.024696 -255.875282) (xy 98.873818 -256.363216)
			(xy 98.902266 -256.362708)
			(arc
				(start 98.914204 -256.355088)
				(mid 98.99895 -256.316858)
				(end 99.090988 -256.30378)
			)
			(xy 99.10445 -256.304034) (xy 99.118928 -256.304542) (xy 99.143312 -256.291334) (xy 99.288854 -256.040382)
			(xy 99.2886 -256.012188)
			(arc
				(start 99.28098 -256.00025)
				(mid 99.243331 -255.915926)
				(end 99.230434 -255.824482)
			)
			(arc
				(start 99.230434 -255.824482)
				(mid 99.327296 -255.590636)
				(end 99.561142 -255.493774)
			)
			(arc
				(start 99.561142 -255.493774)
				(mid 99.732 -255.54133)
				(end 99.85375 -255.670304)
			)
			(xy 99.860354 -255.68275) (xy 99.884484 -255.697482) (xy 100.1776 -255.697482) (xy 100.20173 -255.68275)
			(xy 100.208334 -255.670304) (xy 100.220018 -255.649984) (xy 100.227638 -255.637792) (xy 100.227892 -255.610106)
			(xy 100.081588 -255.357884) (xy 100.057204 -255.344422) (xy 100.04298 -255.34493)
			(arc
				(start 100.031042 -255.345184)
				(mid 99.700334 -255.014476)
				(end 100.031042 -254.683768)
			)
			(arc
				(start 100.031042 -254.683768)
				(mid 100.121632 -254.696345)
				(end 100.205286 -254.733298)
			)
			(xy 100.217224 -254.740664) (xy 100.245164 -254.741172) (xy 101.09708 -254.251714) (xy 101.110796 -254.22733)
			(xy 101.110288 -254.21336) (xy 101.110288 -254.20447) (xy 101.110542 -254.192278) (xy 101.11105 -254.178054)
			(xy 101.097334 -254.153162) (xy 100.248212 -253.665482) (xy 100.220018 -253.666244)
			(arc
				(start 100.20808 -253.673864)
				(mid 100.123212 -253.71213)
				(end 100.031042 -253.725172)
			)
			(arc
				(start 100.031042 -253.725172)
				(mid 99.700334 -253.394464)
				(end 100.031042 -253.063756)
			)
			(arc
				(start 100.031042 -253.063756)
				(mid 100.121632 -253.076333)
				(end 100.205286 -253.113286)
			)
			(xy 100.217224 -253.120652) (xy 100.245164 -253.12116) (xy 101.09708 -252.631702) (xy 101.110796 -252.607318)
			(xy 101.110288 -252.593348)
			(arc
				(start 101.110288 -252.584458)
				(mid 101.20715 -252.350612)
				(end 101.440996 -252.25375)
			)
			(xy 101.450902 -252.254004) (xy 101.464872 -252.254258) (xy 101.489256 -252.240796) (xy 101.636576 -251.986796)
			(xy 101.636322 -251.958856)
			(arc
				(start 101.628956 -251.946918)
				(mid 101.59279 -251.864034)
				(end 101.580442 -251.774452)
			)
			(arc
				(start 101.580442 -251.774452)
				(mid 101.593063 -251.683999)
				(end 101.629972 -251.600462)
			)
			(xy 101.637338 -251.588524) (xy 101.637846 -251.560584) (xy 101.491034 -251.307854) (xy 101.46665 -251.294392)
			(xy 101.452426 -251.2949)
			(arc
				(start 101.440996 -251.295154)
				(mid 101.20715 -251.198292)
				(end 101.110288 -250.964446)
			)
			(xy 101.110542 -250.952508) (xy 101.11105 -250.938284) (xy 101.097334 -250.913646) (xy 100.247958 -250.425712)
			(xy 100.220018 -250.42622)
			(arc
				(start 100.207826 -250.43384)
				(mid 100.12308 -250.47207)
				(end 100.031042 -250.485148)
			)
			(arc
				(start 100.031042 -250.485148)
				(mid 99.797196 -250.388286)
				(end 99.700334 -250.15444)
			)
			(arc
				(start 99.700334 -250.15444)
				(mid 99.712955 -250.063987)
				(end 99.749864 -249.98045)
			)
			(xy 99.75723 -249.968258) (xy 99.757738 -249.940572) (xy 99.61118 -249.687842) (xy 99.586796 -249.67438)
			(xy 99.572572 -249.674888)
			(arc
				(start 99.561142 -249.675142)
				(mid 99.327296 -249.57828)
				(end 99.230434 -249.344434)
			)
			(arc
				(start 99.230434 -249.344434)
				(mid 99.243055 -249.253981)
				(end 99.279964 -249.170444)
			)
			(xy 99.28733 -249.158506) (xy 99.287584 -249.130566) (xy 99.141026 -248.877836) (xy 99.116642 -248.864374)
			(xy 99.102418 -248.864882)
			(arc
				(start 99.090988 -248.865136)
				(mid 98.997517 -248.851652)
				(end 98.911664 -248.812304)
			)
			(xy 98.899472 -248.80443) (xy 98.871278 -248.803668) (xy 98.024188 -249.290332) (xy 98.010726 -249.31497)
			(xy 98.011488 -249.329448)
			(arc
				(start 98.011742 -249.344434)
				(mid 97.681034 -249.675142)
				(end 97.350326 -249.344434)
			)
			(xy 97.35058 -249.332496) (xy 97.351088 -249.318272) (xy 97.337372 -249.293634) (xy 96.487742 -248.8057)
			(xy 96.460056 -248.806208)
			(arc
				(start 96.447864 -248.814082)
				(mid 96.363094 -248.852153)
				(end 96.27108 -248.865136)
			)
			(arc
				(start 96.27108 -248.865136)
				(mid 95.940372 -248.534428)
				(end 96.27108 -248.20372)
			)
			(xy 96.280478 -248.203974) (xy 96.294448 -248.204228) (xy 96.318832 -248.190766) (xy 96.466406 -247.936512)
			(xy 96.465898 -247.908572)
			(arc
				(start 96.458786 -247.896634)
				(mid 96.422654 -247.813872)
				(end 96.410272 -247.724422)
			)
			(arc
				(start 96.410272 -247.724422)
				(mid 96.507134 -247.490576)
				(end 96.74098 -247.393714)
			)
			(xy 96.750378 -247.393968) (xy 96.764348 -247.394222) (xy 96.788732 -247.38076) (xy 96.93656 -247.126252)
			(xy 96.936052 -247.098566)
			(arc
				(start 96.928686 -247.086628)
				(mid 96.892709 -247.003844)
				(end 96.880426 -246.914416)
			)
			(arc
				(start 96.880426 -246.914416)
				(mid 96.892982 -246.824121)
				(end 96.929702 -246.74068)
			)
			(xy 96.937322 -246.728488) (xy 96.937576 -246.700548) (xy 96.791018 -246.447818) (xy 96.766634 -246.434356)
			(xy 96.75241 -246.434864)
			(arc
				(start 96.74098 -246.435118)
				(mid 96.507134 -246.338256)
				(end 96.410272 -246.10441)
			)
			(arc
				(start 96.410272 -246.10441)
				(mid 96.422893 -246.013957)
				(end 96.459802 -245.93042)
			)
			(xy 96.467168 -245.918482) (xy 96.467676 -245.890542) (xy 96.321118 -245.637812) (xy 96.29648 -245.62435)
			(xy 96.28251 -245.624858)
			(arc
				(start 96.27108 -245.625112)
				(mid 95.940372 -245.294404)
				(end 96.27108 -244.963696)
			)
			(xy 96.280478 -244.96395) (xy 96.294702 -244.964204) (xy 96.318578 -244.950742) (xy 96.466152 -244.696488)
			(xy 96.465898 -244.668548)
			(arc
				(start 96.458532 -244.65661)
				(mid 96.422555 -244.573826)
				(end 96.410272 -244.484398)
			)
			(arc
				(start 96.410272 -244.484398)
				(mid 96.507134 -244.250552)
				(end 96.74098 -244.15369)
			)
			(xy 96.750378 -244.153944) (xy 96.764348 -244.154198) (xy 96.788732 -244.140736) (xy 96.936306 -243.886228)
			(xy 96.936052 -243.858542)
			(arc
				(start 96.928686 -243.846604)
				(mid 96.892709 -243.76382)
				(end 96.880426 -243.674392)
			)
			(arc
				(start 96.880426 -243.674392)
				(mid 96.892982 -243.584097)
				(end 96.929702 -243.500656)
			)
			(xy 96.937322 -243.488464) (xy 96.937576 -243.460524) (xy 96.791018 -243.207794) (xy 96.766634 -243.194332)
			(xy 96.75241 -243.19484)
			(arc
				(start 96.74098 -243.195094)
				(mid 96.507134 -243.098232)
				(end 96.410272 -242.864386)
			)
			(arc
				(start 96.410272 -242.864386)
				(mid 96.422893 -242.773933)
				(end 96.459802 -242.690396)
			)
			(xy 96.467168 -242.678458) (xy 96.467676 -242.650518) (xy 96.321118 -242.397788) (xy 96.29648 -242.384326)
			(xy 96.28251 -242.384834)
			(arc
				(start 96.27108 -242.385088)
				(mid 95.940372 -242.05438)
				(end 96.27108 -241.723672)
			)
			(xy 96.280478 -241.723926) (xy 96.294702 -241.72418) (xy 96.318578 -241.710718) (xy 96.466152 -241.456464)
			(xy 96.465898 -241.428524)
			(arc
				(start 96.458532 -241.416586)
				(mid 96.422555 -241.333802)
				(end 96.410272 -241.244374)
			)
			(arc
				(start 96.410272 -241.244374)
				(mid 96.507134 -241.010528)
				(end 96.74098 -240.913666)
			)
			(xy 96.750378 -240.91392) (xy 96.764348 -240.914174) (xy 96.788732 -240.900712) (xy 96.936306 -240.646204)
			(xy 96.936052 -240.618518)
			(arc
				(start 96.928686 -240.60658)
				(mid 96.892709 -240.523796)
				(end 96.880426 -240.434368)
			)
			(arc
				(start 96.880426 -240.434368)
				(mid 96.892982 -240.344073)
				(end 96.929702 -240.260632)
			)
			(xy 96.937322 -240.24844) (xy 96.937576 -240.2205) (xy 96.791018 -239.96777) (xy 96.766634 -239.954308)
			(xy 96.75241 -239.954816)
			(arc
				(start 96.74098 -239.95507)
				(mid 96.507134 -239.858208)
				(end 96.410272 -239.624362)
			)
			(arc
				(start 96.410272 -239.624362)
				(mid 96.422893 -239.533909)
				(end 96.459802 -239.450372)
			)
			(xy 96.467168 -239.43818) (xy 96.467676 -239.410494) (xy 96.321118 -239.157764) (xy 96.296734 -239.144302)
			(xy 96.28251 -239.14481)
			(arc
				(start 96.27108 -239.145064)
				(mid 95.940372 -238.814356)
				(end 96.27108 -238.483648)
			)
			(arc
				(start 96.27108 -238.483648)
				(mid 96.361375 -238.496204)
				(end 96.444816 -238.532924)
			)
			(xy 96.456754 -238.54029) (xy 96.484694 -238.540798) (xy 97.337118 -238.05134) (xy 97.350834 -238.026956)
			(xy 97.350326 -238.012986)
			(arc
				(start 97.350326 -238.00435)
				(mid 97.362947 -237.913897)
				(end 97.399856 -237.83036)
			)
			(xy 97.407222 -237.818422) (xy 97.40773 -237.790482) (xy 97.261172 -237.537752) (xy 97.236788 -237.52429)
			(xy 97.222564 -237.524798)
			(arc
				(start 97.211134 -237.525052)
				(mid 96.977288 -237.42819)
				(end 96.880426 -237.194344)
			)
			(arc
				(start 96.880426 -237.194344)
				(mid 96.893047 -237.103891)
				(end 96.929956 -237.020354)
			)
			(xy 96.937322 -237.008416) (xy 96.93783 -236.980476) (xy 96.791018 -236.727746) (xy 96.766634 -236.714284)
			(xy 96.752664 -236.714792)
			(arc
				(start 96.74098 -236.715046)
				(mid 96.410272 -236.384338)
				(end 96.74098 -236.05363)
			)
			(xy 96.750378 -236.053884) (xy 96.764348 -236.054138) (xy 96.788986 -236.040676) (xy 96.93656 -235.786168)
			(xy 96.936052 -235.758482)
			(arc
				(start 96.928686 -235.746544)
				(mid 96.892709 -235.66376)
				(end 96.880426 -235.574332)
			)
			(arc
				(start 96.880426 -235.574332)
				(mid 96.892982 -235.484037)
				(end 96.929702 -235.400596)
			)
			(xy 96.937322 -235.388404) (xy 96.937576 -235.360464) (xy 96.791018 -235.107734) (xy 96.766634 -235.094272)
			(xy 96.75241 -235.09478)
			(arc
				(start 96.74098 -235.095034)
				(mid 96.507134 -234.998172)
				(end 96.410272 -234.764326)
			)
			(arc
				(start 96.410272 -234.764326)
				(mid 96.422893 -234.673873)
				(end 96.459802 -234.590336)
			)
			(xy 96.467168 -234.578398) (xy 96.467676 -234.550458) (xy 96.321118 -234.297728) (xy 96.29648 -234.284266)
			(xy 96.28251 -234.284774)
			(arc
				(start 96.27108 -234.285028)
				(mid 95.940372 -233.95432)
				(end 96.27108 -233.623612)
			)
			(xy 96.280478 -233.623866) (xy 96.294702 -233.62412) (xy 96.318578 -233.610658) (xy 96.466152 -233.356404)
			(xy 96.465898 -233.328464)
			(arc
				(start 96.458532 -233.316526)
				(mid 96.422555 -233.233742)
				(end 96.410272 -233.144314)
			)
			(arc
				(start 96.410272 -233.144314)
				(mid 96.507134 -232.910468)
				(end 96.74098 -232.813606)
			)
			(xy 96.750378 -232.81386) (xy 96.764348 -232.814114) (xy 96.788732 -232.800652) (xy 96.936306 -232.546144)
			(xy 96.936052 -232.518458)
			(arc
				(start 96.928686 -232.50652)
				(mid 96.892709 -232.423736)
				(end 96.880426 -232.334308)
			)
			(arc
				(start 96.880426 -232.334308)
				(mid 96.892982 -232.244013)
				(end 96.929702 -232.160572)
			)
			(xy 96.937322 -232.14838) (xy 96.937576 -232.12044) (xy 96.791018 -231.86771) (xy 96.766634 -231.854248)
			(xy 96.75241 -231.854756)
			(arc
				(start 96.74098 -231.85501)
				(mid 96.410272 -231.524302)
				(end 96.74098 -231.193594)
			)
			(xy 96.750378 -231.193848) (xy 96.764348 -231.194102) (xy 96.788986 -231.18064) (xy 96.950784 -230.901494)
			(xy 96.951038 -230.874824)
			(arc
				(start 96.944434 -230.86314)
				(mid 96.915642 -230.791311)
				(end 96.905826 -230.71455)
			)
			(arc
				(start 96.905826 -230.71455)
				(mid 96.9159 -230.636801)
				(end 96.94545 -230.564182)
			)
			(xy 96.952308 -230.552244) (xy 96.952054 -230.52532) (xy 96.791018 -230.247698) (xy 96.766634 -230.234236)
			(xy 96.75241 -230.234744)
			(arc
				(start 96.74098 -230.234998)
				(mid 96.410272 -229.90429)
				(end 96.74098 -229.573582)
			)
			(xy 96.750378 -229.573836) (xy 96.764348 -229.57409) (xy 96.788986 -229.560628) (xy 96.936306 -229.30612)
			(xy 96.936052 -229.278688)
			(arc
				(start 96.928686 -229.266496)
				(mid 96.892716 -229.18384)
				(end 96.880426 -229.094538)
			)
			(arc
				(start 96.880426 -229.094538)
				(mid 96.893047 -229.004085)
				(end 96.929956 -228.920548)
			)
			(xy 96.937322 -228.90861) (xy 96.93783 -228.88067) (xy 96.791272 -228.62794) (xy 96.766634 -228.614478)
			(xy 96.752664 -228.614986)
			(arc
				(start 96.74098 -228.61524)
				(mid 96.507134 -228.518378)
				(end 96.410272 -228.284532)
			)
			(arc
				(start 96.410272 -228.284532)
				(mid 96.416779 -228.219507)
				(end 96.435926 -228.157024)
			)
			(xy 96.44126 -228.143816) (xy 96.437196 -228.116384) (xy 96.173544 -227.79482) (xy 96.162876 -227.7872)
			(arc
				(start 96.156272 -227.78466)
				(mid 96.015352 -227.684209)
				(end 95.944436 -227.526342)
			)
			(xy 95.94342 -227.519484) (xy 95.937832 -227.507292) (xy 94.147132 -225.323146) (xy 94.10954 -225.316796)
			(arc
				(start 94.093284 -225.326702)
				(mid 94.010522 -225.362834)
				(end 93.921072 -225.375216)
			)
			(arc
				(start 93.921072 -225.375216)
				(mid 93.687226 -225.278354)
				(end 93.590364 -225.044508)
			)
			(arc
				(start 93.590364 -225.044508)
				(mid 93.613056 -224.924117)
				(end 93.677994 -224.820226)
			)
			(xy 93.690948 -224.806256) (xy 93.691964 -224.76841) (xy 93.529912 -224.570544) (xy 93.505782 -224.560892)
			(arc
				(start 93.492574 -224.56267)
				(mid 93.471786 -224.564596)
				(end 93.450918 -224.56521)
			)
			(arc
				(start 93.450918 -224.56521)
				(mid 93.217072 -224.468348)
				(end 93.12021 -224.234502)
			)
			(arc
				(start 93.12021 -224.234502)
				(mid 93.124572 -224.181221)
				(end 93.137482 -224.129346)
			)
			(xy 93.141546 -224.116646) (xy 93.136974 -224.091246) (xy 93.01734 -223.94545) (xy 93.014038 -223.94164)
			(arc
				(start 92.891864 -223.820228)
				(mid 92.88089 -223.803665)
				(end 92.877132 -223.78416)
			)
			(arc
				(start 92.877132 -222.28556)
				(mid 92.880965 -222.266203)
				(end 92.891864 -222.249746)
			)
			(arc
				(start 92.989146 -222.152718)
				(mid 93.000208 -222.136301)
				(end 93.004132 -222.116904)
			)
			(arc
				(start 93.004132 -219.978224)
				(mid 93.000231 -219.958701)
				(end 92.989146 -219.942156)
			)
			(arc
				(start 92.458794 -219.411804)
				(mid 92.442231 -219.40083)
				(end 92.422726 -219.397072)
			)
			(arc
				(start 84.869782 -219.397072)
				(mid 84.846514 -219.402583)
				(end 84.82838 -219.418154)
			)
			(arc
				(start 84.82838 -219.418154)
				(mid 84.738083 -219.495676)
				(end 84.622386 -219.523564)
			)
			(arc
				(start 76.748386 -219.523564)
				(mid 76.651199 -219.504214)
				(end 76.568808 -219.449142)
			)
			(arc
				(start 59.947302 -202.827636)
				(mid 59.892196 -202.745259)
				(end 59.87288 -202.648058)
			)
			(arc
				(start 59.87288 -192.51803)
				(mid 59.872046 -192.508864)
				(end 59.869578 -192.499996)
			)
			(arc
				(start 59.869578 -192.499996)
				(mid 59.821314 -192.235328)
				(end 59.869578 -191.97066)
			)
			(arc
				(start 59.869578 -191.97066)
				(mid 59.872052 -191.961793)
				(end 59.87288 -191.952626)
			)
			(xy 59.87288 -161.727134) (xy 59.872372 -161.726626)
			(arc
				(start 59.872372 -155.16606)
				(mid 59.868119 -155.145712)
				(end 59.856116 -155.128722)
			)
			(arc
				(start 59.856116 -155.128722)
				(mid 59.765629 -155.001433)
				(end 59.733688 -154.84856)
			)
			(arc
				(start 59.733688 -154.84856)
				(mid 59.746537 -154.75038)
				(end 59.784234 -154.658822)
			)
			(xy 59.79287 -154.643836) (xy 59.788298 -154.6098)
			(arc
				(start 58.85053 -153.672032)
				(mid 58.833967 -153.661058)
				(end 58.814462 -153.6573)
			)
			(xy 58.104786 -153.6573)
			(arc
				(start 58.099452 -153.658316)
				(mid 58.072061 -153.662884)
				(end 58.044334 -153.664412)
			)
			(xy 57.99328 -153.664412) (xy 57.990232 -153.66492)
			(arc
				(start 56.916828 -153.66492)
				(mid 56.901671 -153.667155)
				(end 56.887872 -153.67381)
			)
			(arc
				(start 56.887872 -153.67381)
				(mid 56.784263 -153.724644)
				(end 56.670194 -153.742136)
			)
			(arc
				(start 56.670194 -153.742136)
				(mid 56.556137 -153.724608)
				(end 56.452516 -153.67381)
			)
			(arc
				(start 56.452516 -153.67381)
				(mid 56.438716 -153.667159)
				(end 56.42356 -153.66492)
			)
			(arc
				(start 56.154828 -153.66492)
				(mid 56.139671 -153.667155)
				(end 56.125872 -153.67381)
			)
			(arc
				(start 56.125872 -153.67381)
				(mid 56.022263 -153.724644)
				(end 55.908194 -153.742136)
			)
			(arc
				(start 55.908194 -153.742136)
				(mid 55.794137 -153.724608)
				(end 55.690516 -153.67381)
			)
			(arc
				(start 55.690516 -153.67381)
				(mid 55.676716 -153.667159)
				(end 55.66156 -153.66492)
			)
			(arc
				(start 47.695866 -153.66492)
				(mid 47.676372 -153.668704)
				(end 47.659798 -153.679652)
			)
			(arc
				(start 44.534074 -156.805376)
				(mid 44.522963 -156.82191)
				(end 44.519088 -156.841444)
			)
			(arc
				(start 44.519088 -172.36186)
				(mid 44.522989 -172.381383)
				(end 44.534074 -172.397928)
			)
			(arc
				(start 45.441616 -173.305216)
				(mid 45.45259 -173.321779)
				(end 45.456348 -173.341284)
			)
			(arc
				(start 45.456348 -176.40554)
				(mid 45.452564 -176.425034)
				(end 45.441616 -176.441608)
			)
			(arc
				(start 41.076626 -180.806344)
				(mid 41.065515 -180.822878)
				(end 41.06164 -180.842412)
			)
			(xy 41.06164 -195.8848) (xy 41.061386 -195.8848)
			(arc
				(start 41.061386 -226.357434)
				(mid 41.076265 -226.393355)
				(end 41.112186 -226.408234)
			)
			(arc
				(start 76.774802 -226.408234)
				(mid 76.790565 -226.405644)
				(end 76.804774 -226.398328)
			)
			(arc
				(start 76.804774 -226.398328)
				(mid 77.001116 -226.3338)
				(end 77.197458 -226.398328)
			)
			(arc
				(start 77.197458 -226.398328)
				(mid 77.211651 -226.405692)
				(end 77.22743 -226.408234)
			)
			(arc
				(start 79.59471 -226.408234)
				(mid 79.610473 -226.405644)
				(end 79.624682 -226.398328)
			)
			(arc
				(start 79.624682 -226.398328)
				(mid 79.717687 -226.350346)
				(end 79.821024 -226.333812)
			)
			(arc
				(start 79.821024 -226.333812)
				(mid 79.990944 -226.380761)
				(end 80.112616 -226.50831)
			)
			(xy 80.11922 -226.52101) (xy 80.143096 -226.535234) (xy 80.439006 -226.535234) (xy 80.462882 -226.52101)
			(arc
				(start 80.469486 -226.50831)
				(mid 80.761078 -226.333856)
				(end 81.05267 -226.50831)
			)
			(xy 81.059274 -226.52101) (xy 81.08315 -226.535234) (xy 81.37906 -226.535234) (xy 81.402936 -226.52101)
			(arc
				(start 81.40954 -226.50831)
				(mid 81.701132 -226.333856)
				(end 81.992724 -226.50831)
			)
			(xy 81.999328 -226.52101) (xy 82.023204 -226.535234) (xy 82.31886 -226.535234) (xy 82.342736 -226.52101)
			(arc
				(start 82.34934 -226.50831)
				(mid 82.640932 -226.333856)
				(end 82.932524 -226.50831)
			)
			(xy 82.939128 -226.52101) (xy 82.963004 -226.535234) (xy 83.258914 -226.535234) (xy 83.28279 -226.52101)
			(arc
				(start 83.289394 -226.50831)
				(mid 83.580986 -226.333856)
				(end 83.872578 -226.50831)
			)
			(xy 83.879182 -226.52101) (xy 83.903058 -226.535234) (xy 84.198968 -226.535234) (xy 84.222844 -226.52101)
			(arc
				(start 84.229448 -226.50831)
				(mid 84.52104 -226.333856)
				(end 84.812632 -226.50831)
			)
			(xy 84.819236 -226.52101) (xy 84.843112 -226.535234) (xy 85.139022 -226.535234) (xy 85.162898 -226.52101)
			(arc
				(start 85.169502 -226.50831)
				(mid 85.461094 -226.333856)
				(end 85.752686 -226.50831)
			)
			(xy 85.75929 -226.52101) (xy 85.783166 -226.535234) (xy 86.079076 -226.535234) (xy 86.102952 -226.52101)
			(arc
				(start 86.109556 -226.50831)
				(mid 86.401148 -226.333856)
				(end 86.69274 -226.50831)
			)
			(xy 86.699344 -226.52101) (xy 86.72322 -226.535234)
			(arc
				(start 86.946994 -226.535234)
				(mid 86.995375 -226.544915)
				(end 87.036402 -226.572318)
			)
			(arc
				(start 87.593678 -227.129594)
				(mid 87.621063 -227.170628)
				(end 87.630762 -227.219002)
			)
			(xy 87.630762 -228.11867) (xy 87.633556 -228.1301)
			(arc
				(start 87.636096 -228.135688)
				(mid 87.662585 -228.208027)
				(end 87.671656 -228.284532)
			)
			(arc
				(start 87.671656 -228.284532)
				(mid 87.662623 -228.361046)
				(end 87.636096 -228.433376)
			)
			(xy 87.633556 -228.438964) (xy 87.630762 -228.450394) (xy 87.630762 -229.738428) (xy 87.633556 -229.749858)
			(arc
				(start 87.636096 -229.755446)
				(mid 87.662585 -229.827785)
				(end 87.671656 -229.90429)
			)
			(arc
				(start 87.671656 -229.90429)
				(mid 87.662623 -229.980804)
				(end 87.636096 -230.053134)
			)
			(xy 87.633556 -230.058722) (xy 87.630762 -230.070152) (xy 87.630762 -231.35844) (xy 87.633556 -231.36987)
			(arc
				(start 87.636096 -231.375458)
				(mid 87.662585 -231.447797)
				(end 87.671656 -231.524302)
			)
			(arc
				(start 87.671656 -231.524302)
				(mid 87.662623 -231.600816)
				(end 87.636096 -231.673146)
			)
			(xy 87.633556 -231.678734) (xy 87.630762 -231.690164) (xy 87.630762 -232.978452) (xy 87.633556 -232.989882)
			(arc
				(start 87.636096 -232.99547)
				(mid 87.662585 -233.067809)
				(end 87.671656 -233.144314)
			)
			(arc
				(start 87.671656 -233.144314)
				(mid 87.662623 -233.220828)
				(end 87.636096 -233.293158)
			)
			(xy 87.633556 -233.298746) (xy 87.630762 -233.310176) (xy 87.630762 -234.598464) (xy 87.633556 -234.609894)
			(arc
				(start 87.636096 -234.615482)
				(mid 87.662585 -234.687821)
				(end 87.671656 -234.764326)
			)
			(arc
				(start 87.671656 -234.764326)
				(mid 87.662623 -234.84084)
				(end 87.636096 -234.91317)
			)
			(xy 87.633556 -234.918758) (xy 87.630762 -234.930188) (xy 87.630762 -236.218476) (xy 87.633556 -236.229906)
			(arc
				(start 87.636096 -236.235494)
				(mid 87.662585 -236.307833)
				(end 87.671656 -236.384338)
			)
			(arc
				(start 87.671656 -236.384338)
				(mid 87.662623 -236.460852)
				(end 87.636096 -236.533182)
			)
			(xy 87.633556 -236.53877) (xy 87.630762 -236.5502) (xy 87.630762 -237.838488) (xy 87.633556 -237.849918)
			(arc
				(start 87.636096 -237.855506)
				(mid 87.662585 -237.927845)
				(end 87.671656 -238.00435)
			)
			(arc
				(start 87.671656 -238.00435)
				(mid 87.662623 -238.080864)
				(end 87.636096 -238.153194)
			)
			(xy 87.633556 -238.158782) (xy 87.630762 -238.170212) (xy 87.630762 -239.4585) (xy 87.633556 -239.46993)
			(arc
				(start 87.636096 -239.475518)
				(mid 87.662585 -239.547857)
				(end 87.671656 -239.624362)
			)
			(arc
				(start 87.671656 -239.624362)
				(mid 87.662623 -239.700876)
				(end 87.636096 -239.773206)
			)
			(xy 87.633556 -239.778794) (xy 87.630762 -239.790224) (xy 87.630762 -241.078512) (xy 87.633556 -241.089942)
			(arc
				(start 87.636096 -241.09553)
				(mid 87.662585 -241.167869)
				(end 87.671656 -241.244374)
			)
			(arc
				(start 87.671656 -241.244374)
				(mid 87.662623 -241.320888)
				(end 87.636096 -241.393218)
			)
			(xy 87.633556 -241.398806) (xy 87.630762 -241.410236) (xy 87.630762 -242.698524) (xy 87.633556 -242.709954)
			(arc
				(start 87.636096 -242.715542)
				(mid 87.662585 -242.787881)
				(end 87.671656 -242.864386)
			)
			(arc
				(start 87.671656 -242.864386)
				(mid 87.662623 -242.9409)
				(end 87.636096 -243.01323)
			)
			(xy 87.633556 -243.018818) (xy 87.630762 -243.030248) (xy 87.630762 -244.318536) (xy 87.633556 -244.329966)
			(arc
				(start 87.636096 -244.335554)
				(mid 87.662585 -244.407893)
				(end 87.671656 -244.484398)
			)
			(arc
				(start 87.671656 -244.484398)
				(mid 87.662623 -244.560912)
				(end 87.636096 -244.633242)
			)
			(xy 87.633556 -244.63883) (xy 87.630762 -244.65026) (xy 87.630762 -245.938548) (xy 87.633556 -245.949978)
			(arc
				(start 87.636096 -245.955566)
				(mid 87.662585 -246.027905)
				(end 87.671656 -246.10441)
			)
			(arc
				(start 87.671656 -246.10441)
				(mid 87.662623 -246.180924)
				(end 87.636096 -246.253254)
			)
			(xy 87.633556 -246.258842) (xy 87.630762 -246.270272) (xy 87.630762 -247.55856) (xy 87.633556 -247.56999)
			(arc
				(start 87.636096 -247.575578)
				(mid 87.662585 -247.647917)
				(end 87.671656 -247.724422)
			)
			(arc
				(start 87.671656 -247.724422)
				(mid 87.662623 -247.800936)
				(end 87.636096 -247.873266)
			)
			(xy 87.633556 -247.878854) (xy 87.630762 -247.890284) (xy 87.630762 -249.178572) (xy 87.633556 -249.190002)
			(arc
				(start 87.636096 -249.19559)
				(mid 87.662585 -249.267929)
				(end 87.671656 -249.344434)
			)
			(arc
				(start 87.671656 -249.344434)
				(mid 87.662623 -249.420948)
				(end 87.636096 -249.493278)
			)
			(xy 87.633556 -249.498866) (xy 87.630762 -249.510296) (xy 87.630762 -250.86818)
			(arc
				(start 87.633048 -250.875292)
				(mid 87.64297 -250.919378)
				(end 87.646256 -250.964446)
			)
			(arc
				(start 87.646256 -250.964446)
				(mid 87.64295 -251.009511)
				(end 87.633048 -251.0536)
			)
			(xy 87.630762 -251.060712) (xy 87.630762 -252.418596) (xy 87.633556 -252.430026)
			(arc
				(start 87.636096 -252.435614)
				(mid 87.662585 -252.507953)
				(end 87.671656 -252.584458)
			)
			(arc
				(start 87.671656 -252.584458)
				(mid 87.662623 -252.660972)
				(end 87.636096 -252.733302)
			)
			(xy 87.633556 -252.73889) (xy 87.630762 -252.75032) (xy 87.630762 -254.038608) (xy 87.633556 -254.050038)
			(arc
				(start 87.636096 -254.055626)
				(mid 87.662585 -254.127965)
				(end 87.671656 -254.20447)
			)
			(arc
				(start 87.671656 -254.20447)
				(mid 87.662623 -254.280984)
				(end 87.636096 -254.353314)
			)
			(xy 87.633556 -254.358902) (xy 87.630762 -254.370332)
			(arc
				(start 87.630762 -255.090422)
				(mid 87.634663 -255.109945)
				(end 87.645748 -255.12649)
			)
			(xy 88.063578 -255.54432) (xy 88.097868 -255.548638)
			(arc
				(start 88.112854 -255.539748)
				(mid 88.193842 -255.505472)
				(end 88.281002 -255.493774)
			)
			(arc
				(start 88.281002 -255.493774)
				(mid 88.514848 -255.590636)
				(end 88.61171 -255.824482)
			)
			(arc
				(start 88.61171 -255.824482)
				(mid 88.600008 -255.911641)
				(end 88.565736 -255.99263)
			)
			(arc
				(start 88.565736 -255.99263)
				(mid 88.559182 -256.024801)
				(end 88.57361 -256.054352)
			)
			(xy 88.874092 -256.354834)
			(arc
				(start 88.88222 -256.358644)
				(mid 88.958418 -256.410334)
				(end 89.015824 -256.482342)
			)
			(xy 89.022682 -256.494026) (xy 89.046304 -256.507742) (xy 89.36736 -256.507742)
		)
		(stroke
			(width 0)
			(type solid)
		)
		(fill yes)
		(layer "In8.Cu")
		(net "PVDD18_S5_P1")
	)
	(gr_poly
		(pts
			(xy 303.155604 -335.233518) (xy 303.165674 -335.233095) (xy 303.184279 -335.225381) (xy 303.191672 -335.218532)
			(xy 303.591976 -334.818228) (xy 303.598814 -334.810827) (xy 303.606526 -334.792228) (xy 303.606962 -334.78216)
			(xy 303.606962 -325.083424) (xy 303.606743 -325.076383) (xy 303.602883 -325.062842) (xy 303.599342 -325.056754)
			(xy 303.575673 -325.017544) (xy 303.534828 -324.935561) (xy 303.50172 -324.850159) (xy 303.476634 -324.762067)
			(xy 303.459782 -324.672037) (xy 303.451309 -324.580835) (xy 303.450752 -324.535038) (xy 303.451277 -324.48924)
			(xy 303.459753 -324.398037) (xy 303.476609 -324.308005) (xy 303.5017 -324.219912) (xy 303.534814 -324.13451)
			(xy 303.575666 -324.052529) (xy 303.599342 -324.013322) (xy 303.602844 -324.007216) (xy 303.60671 -323.993686)
			(xy 303.606962 -323.986652) (xy 303.606962 -309.058818) (xy 303.607581 -309.033864) (xy 303.617331 -308.984918)
			(xy 303.63644 -308.938813) (xy 303.664175 -308.897321) (xy 303.681384 -308.87924) (xy 316.781688 -295.778936)
			(xy 316.799731 -295.761681) (xy 316.841226 -295.733933) (xy 316.887344 -295.714829) (xy 316.936307 -295.705106)
			(xy 316.961266 -295.704514) (xy 326.888348 -295.704514) (xy 326.896705 -295.704132) (xy 326.912512 -295.698686)
			(xy 326.919336 -295.693846) (xy 326.941168 -295.677737) (xy 326.988992 -295.652118) (xy 327.040357 -295.634653)
			(xy 327.093885 -295.625811) (xy 327.121012 -295.625266) (xy 327.146851 -295.625766) (xy 327.197899 -295.63381)
			(xy 327.247073 -295.649701) (xy 327.293175 -295.673052) (xy 327.335081 -295.703292) (xy 327.37177 -295.739686)
			(xy 327.402348 -295.781347) (xy 327.414636 -295.804082) (xy 327.421494 -295.816782) (xy 327.44537 -295.831514)
			(xy 330.585064 -295.831514) (xy 330.608686 -295.817798) (xy 330.615544 -295.805606) (xy 330.628186 -295.784255)
			(xy 330.659286 -295.745594) (xy 330.696228 -295.712472) (xy 330.738041 -295.68576) (xy 330.783623 -295.666162)
			(xy 330.831775 -295.654192) (xy 330.881228 -295.650167) (xy 330.930681 -295.654192) (xy 330.978833 -295.666162)
			(xy 331.024415 -295.68576) (xy 331.066228 -295.712472) (xy 331.10317 -295.745594) (xy 331.13427 -295.784255)
			(xy 331.146912 -295.805606) (xy 331.15377 -295.817798) (xy 331.177392 -295.831514) (xy 331.49667 -295.831514)
			(xy 331.520546 -295.816782) (xy 331.527404 -295.804082) (xy 331.539704 -295.781353) (xy 331.570276 -295.739686)
			(xy 331.606961 -295.703287) (xy 331.648865 -295.673042) (xy 331.694966 -295.649688) (xy 331.74414 -295.633796)
			(xy 331.795189 -295.625751) (xy 331.846867 -295.625751) (xy 331.897916 -295.633796) (xy 331.94709 -295.649688)
			(xy 331.993191 -295.673042) (xy 332.035095 -295.703287) (xy 332.07178 -295.739686) (xy 332.102352 -295.781353)
			(xy 332.114652 -295.804082) (xy 332.12151 -295.816782) (xy 332.145386 -295.831514) (xy 332.436724 -295.831514)
			(xy 332.4606 -295.816782) (xy 332.467458 -295.804082) (xy 332.479758 -295.781353) (xy 332.51033 -295.739686)
			(xy 332.547015 -295.703287) (xy 332.588919 -295.673042) (xy 332.63502 -295.649688) (xy 332.684194 -295.633796)
			(xy 332.735243 -295.625751) (xy 332.786921 -295.625751) (xy 332.83797 -295.633796) (xy 332.887144 -295.649688)
			(xy 332.933245 -295.673042) (xy 332.975149 -295.703287) (xy 333.011834 -295.739686) (xy 333.042406 -295.781353)
			(xy 333.054706 -295.804082) (xy 333.061564 -295.816782) (xy 333.08544 -295.831514) (xy 333.376778 -295.831514)
			(xy 333.400654 -295.816782) (xy 333.407512 -295.804082) (xy 333.419812 -295.781353) (xy 333.450384 -295.739686)
			(xy 333.487069 -295.703287) (xy 333.528973 -295.673042) (xy 333.575074 -295.649688) (xy 333.624248 -295.633796)
			(xy 333.675297 -295.625751) (xy 333.726975 -295.625751) (xy 333.778024 -295.633796) (xy 333.827198 -295.649688)
			(xy 333.873299 -295.673042) (xy 333.915203 -295.703287) (xy 333.951888 -295.739686) (xy 333.98246 -295.781353)
			(xy 333.99476 -295.804082) (xy 334.001618 -295.816782) (xy 334.025494 -295.831514) (xy 334.345026 -295.831514)
			(xy 334.368648 -295.817798) (xy 334.375506 -295.805606) (xy 334.388148 -295.784255) (xy 334.419248 -295.745594)
			(xy 334.45619 -295.712472) (xy 334.498003 -295.68576) (xy 334.543585 -295.666162) (xy 334.591737 -295.654192)
			(xy 334.64119 -295.650167) (xy 334.690643 -295.654192) (xy 334.738795 -295.666162) (xy 334.784377 -295.68576)
			(xy 334.82619 -295.712472) (xy 334.863132 -295.745594) (xy 334.894232 -295.784255) (xy 334.906874 -295.805606)
			(xy 334.913732 -295.817798) (xy 334.937354 -295.831514) (xy 336.196686 -295.831514) (xy 336.220562 -295.816782)
			(xy 336.22742 -295.804082) (xy 336.23972 -295.781353) (xy 336.270292 -295.739686) (xy 336.306977 -295.703287)
			(xy 336.348881 -295.673042) (xy 336.394982 -295.649688) (xy 336.444156 -295.633796) (xy 336.495205 -295.625751)
			(xy 336.546883 -295.625751) (xy 336.597932 -295.633796) (xy 336.647106 -295.649688) (xy 336.693207 -295.673042)
			(xy 336.735111 -295.703287) (xy 336.771796 -295.739686) (xy 336.802368 -295.781353) (xy 336.814668 -295.804082)
			(xy 336.821526 -295.816782) (xy 336.845402 -295.831514) (xy 338.076794 -295.831514) (xy 338.10067 -295.816782)
			(xy 338.107528 -295.804082) (xy 338.119828 -295.781353) (xy 338.1504 -295.739686) (xy 338.187085 -295.703287)
			(xy 338.228989 -295.673042) (xy 338.27509 -295.649688) (xy 338.324264 -295.633796) (xy 338.375313 -295.625751)
			(xy 338.426991 -295.625751) (xy 338.47804 -295.633796) (xy 338.527214 -295.649688) (xy 338.573315 -295.673042)
			(xy 338.615219 -295.703287) (xy 338.651904 -295.739686) (xy 338.682476 -295.781353) (xy 338.694776 -295.804082)
			(xy 338.701634 -295.816782) (xy 338.72551 -295.831514) (xy 339.016848 -295.831514) (xy 339.040724 -295.816782)
			(xy 339.047582 -295.804082) (xy 339.059882 -295.781353) (xy 339.090454 -295.739686) (xy 339.127139 -295.703287)
			(xy 339.169043 -295.673042) (xy 339.215144 -295.649688) (xy 339.264318 -295.633796) (xy 339.315367 -295.625751)
			(xy 339.367045 -295.625751) (xy 339.418094 -295.633796) (xy 339.467268 -295.649688) (xy 339.513369 -295.673042)
			(xy 339.555273 -295.703287) (xy 339.591958 -295.739686) (xy 339.62253 -295.781353) (xy 339.63483 -295.804082)
			(xy 339.641688 -295.816782) (xy 339.665564 -295.831514) (xy 339.956648 -295.831514) (xy 339.980524 -295.816782)
			(xy 339.987382 -295.804082) (xy 339.999681 -295.781352) (xy 340.030252 -295.739684) (xy 340.066936 -295.703283)
			(xy 340.10884 -295.673037) (xy 340.154942 -295.649682) (xy 340.204117 -295.633789) (xy 340.255166 -295.625745)
			(xy 340.281006 -295.625266) (xy 340.293706 -295.62552) (xy 340.30793 -295.626028) (xy 340.332314 -295.612566)
			(xy 340.492842 -295.336214) (xy 340.492842 -295.309544) (xy 340.485984 -295.297606) (xy 340.473352 -295.274351)
			(xy 340.455431 -295.224562) (xy 340.446371 -295.172427) (xy 340.445852 -295.145968) (xy 340.446325 -295.121977)
			(xy 340.453835 -295.074587) (xy 340.468665 -295.028955) (xy 340.490449 -294.986204) (xy 340.518652 -294.947386)
			(xy 340.55258 -294.913458) (xy 340.591397 -294.885253) (xy 340.634147 -294.863468) (xy 340.679779 -294.848637)
			(xy 340.727169 -294.841126) (xy 340.75116 -294.84066) (xy 340.760053 -294.840326) (xy 340.776765 -294.834244)
			(xy 340.79038 -294.822803) (xy 340.795102 -294.81526) (xy 340.962742 -294.526462) (xy 340.962996 -294.499538)
			(xy 340.956138 -294.4876) (xy 340.943483 -294.464347) (xy 340.925494 -294.414564) (xy 340.916332 -294.362428)
			(xy 340.915752 -294.335962) (xy 340.916225 -294.311972) (xy 340.923736 -294.264582) (xy 340.938566 -294.218951)
			(xy 340.960351 -294.1762) (xy 340.988555 -294.137384) (xy 341.022482 -294.103456) (xy 341.061299 -294.075252)
			(xy 341.104049 -294.053467) (xy 341.14968 -294.038636) (xy 341.19707 -294.031126) (xy 341.22106 -294.030654)
			(xy 341.229952 -294.03032) (xy 341.246664 -294.024237) (xy 341.260278 -294.012795) (xy 341.265002 -294.005254)
			(xy 341.418418 -293.74084) (xy 341.418164 -293.7129) (xy 341.410544 -293.700962) (xy 341.398687 -293.68118)
			(xy 341.379969 -293.63903) (xy 341.367286 -293.594689) (xy 341.360886 -293.549016) (xy 341.360506 -293.525956)
			(xy 341.361019 -293.499971) (xy 341.369155 -293.448643) (xy 341.38522 -293.399219) (xy 341.408818 -293.352917)
			(xy 341.439369 -293.310876) (xy 341.47612 -293.274131) (xy 341.518167 -293.243588) (xy 341.564473 -293.219998)
			(xy 341.6139 -293.203941) (xy 341.665229 -293.195814) (xy 341.691214 -293.195248) (xy 341.717052 -293.195748)
			(xy 341.768097 -293.203794) (xy 341.817267 -293.219688) (xy 341.863365 -293.243041) (xy 341.905265 -293.273286)
			(xy 341.941946 -293.309684) (xy 341.972515 -293.351348) (xy 341.984838 -293.374064) (xy 341.991696 -293.386764)
			(xy 342.015572 -293.401496) (xy 342.306656 -293.401496) (xy 342.330532 -293.386764) (xy 342.33739 -293.374064)
			(xy 342.34969 -293.351335) (xy 342.380262 -293.30967) (xy 342.416948 -293.273272) (xy 342.458851 -293.243029)
			(xy 342.504952 -293.219677) (xy 342.554127 -293.203786) (xy 342.605175 -293.195743) (xy 342.631014 -293.195248)
			(xy 342.643714 -293.195502) (xy 342.657938 -293.19601) (xy 342.682322 -293.182548) (xy 342.828372 -292.930834)
			(xy 342.828118 -292.902894) (xy 342.820498 -292.890702) (xy 342.808648 -292.870953) (xy 342.789937 -292.828867)
			(xy 342.777261 -292.784589) (xy 342.770864 -292.738979) (xy 342.77046 -292.71595) (xy 342.770939 -292.689957)
			(xy 342.779064 -292.638611) (xy 342.795122 -292.589168) (xy 342.818716 -292.542845) (xy 342.849267 -292.500784)
			(xy 342.886022 -292.46402) (xy 342.928075 -292.433459) (xy 342.974392 -292.409853) (xy 343.023831 -292.393783)
			(xy 343.075175 -292.385646) (xy 343.101168 -292.385242) (xy 343.113614 -292.385496) (xy 343.128092 -292.386004)
			(xy 343.152476 -292.372542) (xy 343.298526 -292.120828) (xy 343.298018 -292.093142) (xy 343.290398 -292.08095)
			(xy 343.278543 -292.061167) (xy 343.259829 -292.019017) (xy 343.24715 -291.974676) (xy 343.240752 -291.929003)
			(xy 343.24036 -291.905944) (xy 343.24084 -291.879952) (xy 343.248965 -291.828606) (xy 343.265023 -291.779163)
			(xy 343.288618 -291.732842) (xy 343.319169 -291.690782) (xy 343.355924 -291.654019) (xy 343.397977 -291.623458)
			(xy 343.444293 -291.599852) (xy 343.493732 -291.583783) (xy 343.545076 -291.575646) (xy 343.571068 -291.575236)
			(xy 343.583768 -291.57549) (xy 343.597992 -291.575998) (xy 343.622376 -291.562536) (xy 343.768426 -291.310822)
			(xy 343.768172 -291.282882) (xy 343.760552 -291.270944) (xy 343.748696 -291.251162) (xy 343.729979 -291.209012)
			(xy 343.717299 -291.16467) (xy 343.710901 -291.118997) (xy 343.710514 -291.095938) (xy 343.710994 -291.069947)
			(xy 343.719121 -291.018606) (xy 343.73518 -290.969167) (xy 343.758776 -290.92285) (xy 343.789328 -290.880796)
			(xy 343.826083 -290.844039) (xy 343.868137 -290.813485) (xy 343.914453 -290.789886) (xy 343.96389 -290.773825)
			(xy 344.015231 -290.765696) (xy 344.041222 -290.76523) (xy 344.053922 -290.765484) (xy 344.068146 -290.765992)
			(xy 344.09253 -290.75253) (xy 344.23858 -290.50107) (xy 344.238072 -290.47313) (xy 344.230452 -290.460938)
			(xy 344.218596 -290.441156) (xy 344.19988 -290.399006) (xy 344.187201 -290.354664) (xy 344.180804 -290.308991)
			(xy 344.180414 -290.285932) (xy 344.180895 -290.259942) (xy 344.189022 -290.208601) (xy 344.205082 -290.159163)
			(xy 344.228678 -290.112847) (xy 344.25923 -290.070793) (xy 344.295985 -290.034037) (xy 344.338039 -290.003483)
			(xy 344.384354 -289.979886) (xy 344.433791 -289.963824) (xy 344.485132 -289.955696) (xy 344.511122 -289.955224)
			(xy 344.523822 -289.955478) (xy 344.5383 -289.955986) (xy 344.562684 -289.942524) (xy 344.70848 -289.691064)
			(xy 344.707972 -289.663124) (xy 344.700606 -289.651186) (xy 344.68868 -289.631397) (xy 344.669871 -289.589194)
			(xy 344.657127 -289.544783) (xy 344.650698 -289.499028) (xy 344.650314 -289.475926) (xy 344.650795 -289.449936)
			(xy 344.658923 -289.398596) (xy 344.674984 -289.349159) (xy 344.69858 -289.302844) (xy 344.729132 -289.260791)
			(xy 344.765888 -289.224035) (xy 344.80794 -289.193482) (xy 344.854255 -289.169885) (xy 344.903692 -289.153824)
			(xy 344.955032 -289.145696) (xy 344.981022 -289.145218) (xy 344.993722 -289.145472) (xy 345.0082 -289.14598)
			(xy 345.032584 -289.132518) (xy 345.178634 -288.880804) (xy 345.178126 -288.852864) (xy 345.170506 -288.840926)
			(xy 345.158653 -288.821143) (xy 345.139941 -288.778992) (xy 345.127265 -288.734651) (xy 345.12087 -288.688979)
			(xy 345.120468 -288.66592) (xy 345.12084 -288.643231) (xy 345.127038 -288.598279) (xy 345.139319 -288.554595)
			(xy 345.157453 -288.512999) (xy 345.168982 -288.493454) (xy 345.176348 -288.481262) (xy 345.176602 -288.453576)
			(xy 345.029536 -288.19983) (xy 345.005152 -288.186368) (xy 344.991182 -288.186622) (xy 344.981022 -288.186876)
			(xy 344.955033 -288.186394) (xy 344.903693 -288.178266) (xy 344.854258 -288.162205) (xy 344.807944 -288.138608)
			(xy 344.765892 -288.108056) (xy 344.729138 -288.0713) (xy 344.698587 -288.029248) (xy 344.674991 -287.982933)
			(xy 344.658932 -287.933497) (xy 344.650805 -287.882157) (xy 344.650314 -287.856168) (xy 344.650699 -287.833409)
			(xy 344.656943 -287.788322) (xy 344.669296 -287.744512) (xy 344.687525 -287.702804) (xy 344.699082 -287.683194)
			(xy 344.706448 -287.671256) (xy 344.706702 -287.643316) (xy 344.559636 -287.38957) (xy 344.535252 -287.376108)
			(xy 344.521282 -287.376362) (xy 344.511122 -287.376616) (xy 344.485131 -287.376134) (xy 344.433789 -287.368006)
			(xy 344.38435 -287.351945) (xy 344.338032 -287.328348) (xy 344.295977 -287.297795) (xy 344.259219 -287.26104)
			(xy 344.228664 -287.218986) (xy 344.205063 -287.172671) (xy 344.188999 -287.123233) (xy 344.180867 -287.071891)
			(xy 344.180867 -287.019909) (xy 344.188999 -286.968567) (xy 344.205063 -286.919129) (xy 344.228664 -286.872814)
			(xy 344.259219 -286.83076) (xy 344.295977 -286.794005) (xy 344.338032 -286.763452) (xy 344.38435 -286.739855)
			(xy 344.433789 -286.723794) (xy 344.485131 -286.715666) (xy 344.511122 -286.7152) (xy 344.523822 -286.715454)
			(xy 344.5383 -286.715962) (xy 344.562684 -286.7025) (xy 344.70848 -286.451294) (xy 344.707972 -286.423354)
			(xy 344.700352 -286.411162) (xy 344.688495 -286.39138) (xy 344.669776 -286.34923) (xy 344.657093 -286.304889)
			(xy 344.650693 -286.259216) (xy 344.650314 -286.236156) (xy 344.650827 -286.210172) (xy 344.658963 -286.158844)
			(xy 344.675028 -286.109421) (xy 344.698627 -286.063119) (xy 344.729178 -286.021078) (xy 344.765929 -285.984335)
			(xy 344.807975 -285.953792) (xy 344.854282 -285.930203) (xy 344.903708 -285.914148) (xy 344.955038 -285.906022)
			(xy 344.981022 -285.905448) (xy 344.993722 -285.905702) (xy 345.007946 -285.90621) (xy 345.03233 -285.892748)
			(xy 345.17838 -285.641034) (xy 345.178126 -285.613094) (xy 345.170506 -285.600902) (xy 345.158655 -285.581153)
			(xy 345.139945 -285.539067) (xy 345.127268 -285.494789) (xy 345.120871 -285.449179) (xy 345.120468 -285.42615)
			(xy 345.120838 -285.403419) (xy 345.127062 -285.358385) (xy 345.139411 -285.314633) (xy 345.157652 -285.272991)
			(xy 345.169236 -285.25343) (xy 345.176348 -285.241492) (xy 345.176856 -285.213552) (xy 345.029536 -284.959806)
			(xy 345.005152 -284.946344) (xy 344.991182 -284.946598) (xy 344.981022 -284.946852) (xy 344.955032 -284.946344)
			(xy 344.903693 -284.938217) (xy 344.854256 -284.922158) (xy 344.807941 -284.898564) (xy 344.765886 -284.868015)
			(xy 344.729127 -284.831264) (xy 344.69857 -284.789216) (xy 344.674967 -284.742905) (xy 344.658899 -284.693472)
			(xy 344.650761 -284.642133) (xy 344.650314 -284.616144) (xy 344.650701 -284.593386) (xy 344.656948 -284.548299)
			(xy 344.669303 -284.504491) (xy 344.687534 -284.462785) (xy 344.699082 -284.44317) (xy 344.706448 -284.431232)
			(xy 344.706702 -284.403292) (xy 344.559636 -284.1498) (xy 344.535252 -284.136338) (xy 344.521282 -284.136592)
			(xy 344.511122 -284.136846) (xy 344.485129 -284.136364) (xy 344.433781 -284.128235) (xy 344.384338 -284.112173)
			(xy 344.338017 -284.088574) (xy 344.295957 -284.058018) (xy 344.259196 -284.021259) (xy 344.228638 -283.979202)
			(xy 344.205036 -283.932882) (xy 344.18897 -283.88344) (xy 344.180837 -283.832093) (xy 344.180837 -283.780107)
			(xy 344.18897 -283.72876) (xy 344.205036 -283.679318) (xy 344.228638 -283.632998) (xy 344.259196 -283.590941)
			(xy 344.295957 -283.554182) (xy 344.338017 -283.523626) (xy 344.384338 -283.500027) (xy 344.433782 -283.483965)
			(xy 344.485129 -283.475836) (xy 344.511122 -283.47543) (xy 344.523822 -283.475684) (xy 344.538046 -283.476192)
			(xy 344.56243 -283.46273) (xy 344.70848 -283.21127) (xy 344.707972 -283.18333) (xy 344.700352 -283.171138)
			(xy 344.688496 -283.151356) (xy 344.66978 -283.109206) (xy 344.657101 -283.064864) (xy 344.650704 -283.019191)
			(xy 344.650314 -282.996132) (xy 344.650795 -282.970142) (xy 344.658922 -282.918801) (xy 344.674982 -282.869363)
			(xy 344.698578 -282.823047) (xy 344.72913 -282.780993) (xy 344.765885 -282.744237) (xy 344.807939 -282.713683)
			(xy 344.854254 -282.690086) (xy 344.903691 -282.674024) (xy 344.955032 -282.665896) (xy 344.981022 -282.665424)
			(xy 344.993722 -282.665678) (xy 345.007946 -282.666186) (xy 345.03233 -282.652724) (xy 345.17838 -282.40101)
			(xy 345.178126 -282.37307) (xy 345.170506 -282.360878) (xy 345.158657 -282.341128) (xy 345.139949 -282.299043)
			(xy 345.127275 -282.254764) (xy 345.120882 -282.209154) (xy 345.120468 -282.186126) (xy 345.12084 -282.163395)
			(xy 345.127066 -282.118363) (xy 345.139418 -282.074612) (xy 345.157661 -282.032972) (xy 345.169236 -282.013406)
			(xy 345.176348 -282.001468) (xy 345.176856 -281.973528) (xy 345.029536 -281.719782) (xy 345.005152 -281.70632)
			(xy 344.991182 -281.706574) (xy 344.981022 -281.706828) (xy 344.95503 -281.706346) (xy 344.903686 -281.698217)
			(xy 344.854245 -281.682156) (xy 344.807926 -281.658558) (xy 344.765869 -281.628005) (xy 344.72911 -281.591248)
			(xy 344.698553 -281.549193) (xy 344.674952 -281.502875) (xy 344.658888 -281.453436) (xy 344.650755 -281.402092)
			(xy 344.650755 -281.350108) (xy 344.658888 -281.298764) (xy 344.674952 -281.249325) (xy 344.698553 -281.203007)
			(xy 344.72911 -281.160952) (xy 344.765869 -281.124195) (xy 344.807926 -281.093642) (xy 344.854245 -281.070044)
			(xy 344.903686 -281.053983) (xy 344.95503 -281.045854) (xy 344.981022 -281.045412) (xy 344.993722 -281.045666)
			(xy 345.007946 -281.046174) (xy 345.03233 -281.032712) (xy 345.17838 -280.780998) (xy 345.178126 -280.753058)
			(xy 345.170506 -280.74112) (xy 345.158653 -280.721337) (xy 345.139942 -280.679186) (xy 345.127267 -280.634845)
			(xy 345.120873 -280.589173) (xy 345.120468 -280.566114) (xy 345.120976 -280.540125) (xy 345.129105 -280.488788)
			(xy 345.145165 -280.439354) (xy 345.168759 -280.393041) (xy 345.199308 -280.350989) (xy 345.23606 -280.314233)
			(xy 345.278108 -280.283679) (xy 345.324419 -280.260079) (xy 345.373851 -280.244014) (xy 345.425187 -280.235879)
			(xy 345.451176 -280.235406) (xy 345.463622 -280.23566) (xy 345.477846 -280.236168) (xy 345.50223 -280.222706)
			(xy 345.64828 -279.970992) (xy 345.648026 -279.943052) (xy 345.640406 -279.93086) (xy 345.628552 -279.911112)
			(xy 345.609834 -279.869027) (xy 345.597149 -279.824749) (xy 345.590744 -279.779138) (xy 345.590368 -279.756108)
			(xy 345.590368 -279.747472) (xy 345.590876 -279.733248) (xy 345.57716 -279.709118) (xy 344.72499 -279.219406)
			(xy 344.69705 -279.219914) (xy 344.685112 -279.22728) (xy 344.665426 -279.239015) (xy 344.623504 -279.257537)
			(xy 344.579427 -279.270092) (xy 344.534037 -279.276438) (xy 344.511122 -279.27681) (xy 344.485131 -279.276329)
			(xy 344.43379 -279.2682) (xy 344.384352 -279.25214) (xy 344.338036 -279.228543) (xy 344.295981 -279.197991)
			(xy 344.259223 -279.161236) (xy 344.228669 -279.119183) (xy 344.205069 -279.072868) (xy 344.189005 -279.023432)
			(xy 344.180873 -278.972091) (xy 344.180873 -278.920109) (xy 344.189005 -278.868768) (xy 344.205069 -278.819332)
			(xy 344.228669 -278.773017) (xy 344.259223 -278.730964) (xy 344.295981 -278.694209) (xy 344.338036 -278.663657)
			(xy 344.384352 -278.64006) (xy 344.43379 -278.624) (xy 344.485131 -278.615871) (xy 344.511122 -278.615394)
			(xy 344.523822 -278.615648) (xy 344.538046 -278.616156) (xy 344.56243 -278.602694) (xy 344.70848 -278.351234)
			(xy 344.707972 -278.323294) (xy 344.700352 -278.311102) (xy 344.688499 -278.291319) (xy 344.669787 -278.249168)
			(xy 344.657112 -278.204827) (xy 344.65072 -278.159155) (xy 344.650314 -278.136096) (xy 344.650797 -278.110108)
			(xy 344.658929 -278.058771) (xy 344.674992 -278.009338) (xy 344.698591 -277.963027) (xy 344.729143 -277.920978)
			(xy 344.765898 -277.884226) (xy 344.807949 -277.853677) (xy 344.854262 -277.830082) (xy 344.903696 -277.814023)
			(xy 344.955034 -277.805895) (xy 344.981022 -277.805388) (xy 344.993722 -277.805642) (xy 345.007946 -277.80615)
			(xy 345.03233 -277.792688) (xy 345.17838 -277.540974) (xy 345.178126 -277.513034) (xy 345.170506 -277.500842)
			(xy 345.158653 -277.481093) (xy 345.139937 -277.439009) (xy 345.127255 -277.394731) (xy 345.120852 -277.349119)
			(xy 345.120468 -277.32609) (xy 345.120842 -277.30336) (xy 345.127073 -277.25833) (xy 345.139429 -277.214581)
			(xy 345.157676 -277.172945) (xy 345.169236 -277.15337) (xy 345.176348 -277.141432) (xy 345.176856 -277.113492)
			(xy 345.029536 -276.859746) (xy 345.005152 -276.846284) (xy 344.991182 -276.846538) (xy 344.981022 -276.846792)
			(xy 344.955032 -276.846311) (xy 344.903692 -276.838182) (xy 344.854255 -276.822121) (xy 344.80794 -276.798525)
			(xy 344.765887 -276.767972) (xy 344.729131 -276.731218) (xy 344.698579 -276.689165) (xy 344.674981 -276.64285)
			(xy 344.65892 -276.593414) (xy 344.65079 -276.542074) (xy 344.650314 -276.516084) (xy 344.650698 -276.493325)
			(xy 344.65694 -276.448236) (xy 344.669291 -276.404426) (xy 344.687518 -276.362716) (xy 344.699082 -276.34311)
			(xy 344.706448 -276.331172) (xy 344.706702 -276.303232) (xy 344.559636 -276.04974) (xy 344.535252 -276.036278)
			(xy 344.521282 -276.036532) (xy 344.511122 -276.036786) (xy 344.485133 -276.036305) (xy 344.433796 -276.028177)
			(xy 344.384361 -276.012117) (xy 344.338048 -275.988522) (xy 344.295996 -275.957973) (xy 344.259242 -275.92122)
			(xy 344.228689 -275.879171) (xy 344.205091 -275.832859) (xy 344.189029 -275.783426) (xy 344.180897 -275.732089)
			(xy 344.180897 -275.680111) (xy 344.189029 -275.628774) (xy 344.205091 -275.579341) (xy 344.228689 -275.533029)
			(xy 344.259242 -275.49098) (xy 344.295996 -275.454227) (xy 344.338048 -275.423678) (xy 344.384361 -275.400083)
			(xy 344.433796 -275.384023) (xy 344.485133 -275.375895) (xy 344.511122 -275.37537) (xy 344.523822 -275.375624)
			(xy 344.538046 -275.376132) (xy 344.56243 -275.36267) (xy 344.70848 -275.11121) (xy 344.707972 -275.08327)
			(xy 344.700352 -275.071078) (xy 344.688494 -275.051296) (xy 344.669773 -275.009147) (xy 344.657088 -274.964806)
			(xy 344.650686 -274.919132) (xy 344.650314 -274.896072) (xy 344.650826 -274.870087) (xy 344.65896 -274.818757)
			(xy 344.675024 -274.769332) (xy 344.698621 -274.723028) (xy 344.729172 -274.680985) (xy 344.765923 -274.644239)
			(xy 344.80797 -274.613695) (xy 344.854278 -274.590104) (xy 344.903706 -274.574048) (xy 344.955037 -274.565922)
			(xy 344.981022 -274.565364) (xy 344.993722 -274.565618) (xy 345.007946 -274.566126) (xy 345.03233 -274.552664)
			(xy 345.17838 -274.30095) (xy 345.178126 -274.27301) (xy 345.170506 -274.260818) (xy 345.158654 -274.241069)
			(xy 345.139942 -274.198984) (xy 345.127263 -274.154706) (xy 345.120863 -274.109095) (xy 345.120468 -274.086066)
			(xy 345.120837 -274.063335) (xy 345.127058 -274.0183) (xy 345.139406 -273.974546) (xy 345.157645 -273.932903)
			(xy 345.169236 -273.913346) (xy 345.176348 -273.901408) (xy 345.176856 -273.873468) (xy 345.029536 -273.619722)
			(xy 345.005152 -273.60626) (xy 344.991182 -273.606514) (xy 344.981022 -273.606768) (xy 344.955033 -273.606286)
			(xy 344.903694 -273.598158) (xy 344.854259 -273.582097) (xy 344.807946 -273.5585) (xy 344.765894 -273.527947)
			(xy 344.729141 -273.491192) (xy 344.698591 -273.449139) (xy 344.674996 -273.402824) (xy 344.658938 -273.353389)
			(xy 344.650812 -273.302049) (xy 344.650314 -273.27606) (xy 344.6507 -273.253301) (xy 344.656945 -273.208214)
			(xy 344.669298 -273.164405) (xy 344.687528 -273.122697) (xy 344.699082 -273.103086) (xy 344.706448 -273.091148)
			(xy 344.706702 -273.063208) (xy 344.559636 -272.809716) (xy 344.535252 -272.796254) (xy 344.521282 -272.796508)
			(xy 344.511122 -272.796762) (xy 344.485135 -272.796281) (xy 344.433801 -272.788153) (xy 344.384371 -272.772095)
			(xy 344.338061 -272.748502) (xy 344.296012 -272.717954) (xy 344.25926 -272.681205) (xy 344.22871 -272.639158)
			(xy 344.205113 -272.59285) (xy 344.189052 -272.54342) (xy 344.180921 -272.492087) (xy 344.180921 -272.440113)
			(xy 344.189052 -272.38878) (xy 344.205113 -272.33935) (xy 344.22871 -272.293042) (xy 344.25926 -272.250995)
			(xy 344.296012 -272.214246) (xy 344.338061 -272.183698) (xy 344.384371 -272.160105) (xy 344.433801 -272.144047)
			(xy 344.485135 -272.135919) (xy 344.511122 -272.135346) (xy 344.523822 -272.1356) (xy 344.538046 -272.136108)
			(xy 344.56243 -272.122646) (xy 344.70848 -271.871186) (xy 344.707972 -271.843246) (xy 344.700352 -271.831054)
			(xy 344.688495 -271.811272) (xy 344.669777 -271.769122) (xy 344.657096 -271.724781) (xy 344.650697 -271.679108)
			(xy 344.650314 -271.656048) (xy 344.650794 -271.630057) (xy 344.658919 -271.578714) (xy 344.674977 -271.529274)
			(xy 344.698573 -271.482956) (xy 344.729125 -271.4409) (xy 344.76588 -271.404141) (xy 344.807934 -271.373586)
			(xy 344.85425 -271.349987) (xy 344.903688 -271.333925) (xy 344.955031 -271.325796) (xy 344.981022 -271.32534)
			(xy 344.993722 -271.325594) (xy 345.007946 -271.326102) (xy 345.03233 -271.31264) (xy 345.17838 -271.060926)
			(xy 345.178126 -271.032986) (xy 345.170506 -271.020794) (xy 345.158656 -271.001045) (xy 345.139946 -270.958959)
			(xy 345.12727 -270.914681) (xy 345.120874 -270.86907) (xy 345.120468 -270.846042) (xy 345.120839 -270.823311)
			(xy 345.127063 -270.778278) (xy 345.139413 -270.734526) (xy 345.157655 -270.692885) (xy 345.169236 -270.673322)
			(xy 345.176348 -270.661384) (xy 345.176856 -270.633444) (xy 345.029536 -270.379698) (xy 345.005152 -270.366236)
			(xy 344.991182 -270.36649) (xy 344.981022 -270.366744) (xy 344.955033 -270.366236) (xy 344.903693 -270.358109)
			(xy 344.854258 -270.34205) (xy 344.807942 -270.318456) (xy 344.765888 -270.287907) (xy 344.729131 -270.251156)
			(xy 344.698575 -270.209107) (xy 344.674972 -270.162796) (xy 344.658905 -270.113363) (xy 344.650768 -270.062025)
			(xy 344.650314 -270.036036) (xy 344.650701 -270.013278) (xy 344.656949 -269.968192) (xy 344.669305 -269.924385)
			(xy 344.687537 -269.882679) (xy 344.699082 -269.863062) (xy 344.706448 -269.851124) (xy 344.706702 -269.823184)
			(xy 344.559636 -269.569692) (xy 344.535252 -269.55623) (xy 344.521282 -269.556484) (xy 344.511122 -269.556738)
			(xy 344.485133 -269.55623) (xy 344.433794 -269.548102) (xy 344.384359 -269.532044) (xy 344.338044 -269.50845)
			(xy 344.29599 -269.477901) (xy 344.259233 -269.441149) (xy 344.228678 -269.399101) (xy 344.205076 -269.35279)
			(xy 344.18901 -269.303357) (xy 344.180874 -269.252019) (xy 344.180414 -269.22603) (xy 344.180871 -269.201313)
			(xy 344.188218 -269.152429) (xy 344.202755 -269.105181) (xy 344.224156 -269.060621) (xy 344.251947 -269.019739)
			(xy 344.28551 -268.983446) (xy 344.324097 -268.952547) (xy 344.34526 -268.939772) (xy 344.354404 -268.934692)
			(xy 344.36685 -268.918182) (xy 344.389202 -268.826742) (xy 344.3859 -268.806422) (xy 344.380312 -268.797532)
			(xy 344.359175 -268.763239) (xy 344.323917 -268.690804) (xy 344.297069 -268.61485) (xy 344.278976 -268.536348)
			(xy 344.26987 -268.456304) (xy 344.269314 -268.416024) (xy 344.269784 -268.378749) (xy 344.277574 -268.304608)
			(xy 344.293072 -268.231687) (xy 344.316108 -268.160786) (xy 344.346429 -268.092681) (xy 344.383702 -268.028119)
			(xy 344.427521 -267.967807) (xy 344.477404 -267.912406) (xy 344.532805 -267.862522) (xy 344.593117 -267.818704)
			(xy 344.657679 -267.781429) (xy 344.725784 -267.751108) (xy 344.796685 -267.728073) (xy 344.869606 -267.712575)
			(xy 344.943747 -267.704784) (xy 344.981022 -267.704316) (xy 344.994878 -267.704354) (xy 345.022572 -267.705369)
			(xy 345.036394 -267.706348) (xy 345.047062 -267.707364) (xy 345.066874 -267.700506) (xy 345.137486 -267.635228)
			(xy 345.145868 -267.616178) (xy 345.145868 -267.60551) (xy 345.146375 -267.581543) (xy 345.153942 -267.534209)
			(xy 345.168812 -267.488639) (xy 345.190621 -267.445953) (xy 345.218833 -267.407199) (xy 345.252754 -267.37333)
			(xy 345.291551 -267.345177) (xy 345.33427 -267.323434) (xy 345.379863 -267.308633) (xy 345.427209 -267.301138)
			(xy 345.451176 -267.30071) (xy 345.474211 -267.301128) (xy 345.519759 -267.30805) (xy 345.56375 -267.321738)
			(xy 345.605183 -267.341884) (xy 345.643117 -267.368028) (xy 345.67669 -267.399577) (xy 345.705141 -267.435814)
			(xy 345.71686 -267.45565) (xy 345.723718 -267.467842) (xy 345.74734 -267.481558) (xy 346.066872 -267.481558)
			(xy 346.090748 -267.466826) (xy 346.097606 -267.454126) (xy 346.109906 -267.431397) (xy 346.140478 -267.38973)
			(xy 346.177163 -267.353331) (xy 346.219067 -267.323086) (xy 346.265168 -267.299732) (xy 346.314342 -267.28384)
			(xy 346.365391 -267.275795) (xy 346.417069 -267.275795) (xy 346.468118 -267.28384) (xy 346.517292 -267.299732)
			(xy 346.563393 -267.323086) (xy 346.605297 -267.353331) (xy 346.641982 -267.38973) (xy 346.672554 -267.431397)
			(xy 346.684854 -267.454126) (xy 346.691712 -267.466826) (xy 346.715588 -267.481558) (xy 347.034866 -267.481558)
			(xy 347.058488 -267.467842) (xy 347.065346 -267.45565) (xy 347.077059 -267.435811) (xy 347.105519 -267.399585)
			(xy 347.139098 -267.368045) (xy 347.177033 -267.341906) (xy 347.218464 -267.321762) (xy 347.262451 -267.308069)
			(xy 347.307996 -267.301139) (xy 347.33103 -267.30071) (xy 347.344746 -267.30071) (xy 347.368114 -267.287248)
			(xy 347.528388 -267.010896) (xy 347.528134 -266.982956) (xy 347.520514 -266.970764) (xy 347.508659 -266.951016)
			(xy 347.48994 -266.908932) (xy 347.477255 -266.864654) (xy 347.470849 -266.819042) (xy 347.470476 -266.796012)
			(xy 347.470985 -266.770024) (xy 347.479114 -266.718687) (xy 347.495173 -266.669254) (xy 347.518768 -266.622941)
			(xy 347.549318 -266.58089) (xy 347.586069 -266.544136) (xy 347.628117 -266.513583) (xy 347.674428 -266.489984)
			(xy 347.72386 -266.47392) (xy 347.775196 -266.465787) (xy 347.801184 -266.465304) (xy 347.81363 -266.465558)
			(xy 347.828108 -266.466066) (xy 347.852492 -266.452604) (xy 347.998542 -266.20089) (xy 347.998034 -266.173204)
			(xy 347.990414 -266.161012) (xy 347.978561 -266.141229) (xy 347.959851 -266.099078) (xy 347.947176 -266.054737)
			(xy 347.940783 -266.009065) (xy 347.940376 -265.986006) (xy 347.940885 -265.960018) (xy 347.949015 -265.908682)
			(xy 347.965075 -265.85925) (xy 347.98867 -265.812938) (xy 348.01922 -265.770888) (xy 348.055971 -265.734134)
			(xy 348.098019 -265.703582) (xy 348.144329 -265.679983) (xy 348.19376 -265.66392) (xy 348.245096 -265.655787)
			(xy 348.271084 -265.655298) (xy 348.294525 -265.655725) (xy 348.340935 -265.662376) (xy 348.385942 -265.675506)
			(xy 348.428648 -265.694851) (xy 348.44863 -265.707114) (xy 348.460822 -265.714734) (xy 348.489016 -265.715242)
			(xy 349.337376 -265.22807) (xy 349.351092 -265.203178) (xy 349.350584 -265.188954) (xy 349.35033 -265.176)
			(xy 349.35033 -265.167364) (xy 349.350838 -265.153394) (xy 349.337122 -265.12901) (xy 348.484952 -264.639298)
			(xy 348.457012 -264.639806) (xy 348.445074 -264.647172) (xy 348.425387 -264.658905) (xy 348.383465 -264.677423)
			(xy 348.339387 -264.689972) (xy 348.293999 -264.696314) (xy 348.271084 -264.696702) (xy 348.245098 -264.696191)
			(xy 348.193766 -264.688059) (xy 348.144339 -264.671997) (xy 348.098033 -264.6484) (xy 348.055987 -264.617851)
			(xy 348.019239 -264.5811) (xy 347.988691 -264.539054) (xy 347.965097 -264.492746) (xy 347.949037 -264.443318)
			(xy 347.940907 -264.391986) (xy 347.940907 -264.340014) (xy 347.949037 -264.288682) (xy 347.965097 -264.239254)
			(xy 347.988691 -264.192946) (xy 348.019239 -264.1509) (xy 348.055987 -264.114149) (xy 348.098033 -264.0836)
			(xy 348.144339 -264.060003) (xy 348.193766 -264.043941) (xy 348.245098 -264.035809) (xy 348.271084 -264.035286)
			(xy 348.294557 -264.035695) (xy 348.341033 -264.042328) (xy 348.386104 -264.055462) (xy 348.428867 -264.074835)
			(xy 348.448884 -264.087102) (xy 348.460822 -264.094722) (xy 348.489016 -264.095484) (xy 349.337376 -263.608058)
			(xy 349.351092 -263.58342) (xy 349.350584 -263.569196) (xy 349.35033 -263.555988) (xy 349.350705 -263.5333)
			(xy 349.356907 -263.48835) (xy 349.369194 -263.444669) (xy 349.387334 -263.403077) (xy 349.398844 -263.383522)
			(xy 349.40621 -263.371584) (xy 349.406464 -263.343644) (xy 349.259144 -263.089644) (xy 349.23476 -263.076182)
			(xy 349.22079 -263.076436) (xy 349.211138 -263.07669) (xy 349.185148 -263.07621) (xy 349.133808 -263.068084)
			(xy 349.084371 -263.052026) (xy 349.038055 -263.028431) (xy 348.996001 -262.997881) (xy 348.959243 -262.961128)
			(xy 348.928689 -262.919078) (xy 348.905089 -262.872764) (xy 348.889025 -262.823329) (xy 348.880893 -262.77199)
			(xy 348.880893 -262.72001) (xy 348.889025 -262.668671) (xy 348.905089 -262.619236) (xy 348.928689 -262.572922)
			(xy 348.959243 -262.530872) (xy 348.996001 -262.494119) (xy 349.038055 -262.463569) (xy 349.084371 -262.439974)
			(xy 349.133808 -262.423916) (xy 349.185148 -262.41579) (xy 349.211138 -262.415274) (xy 349.22333 -262.415528)
			(xy 349.237554 -262.416036) (xy 349.261938 -262.402574) (xy 349.408242 -262.150606) (xy 349.407734 -262.122666)
			(xy 349.400114 -262.110474) (xy 349.388321 -262.090739) (xy 349.369707 -262.048703) (xy 349.357096 -262.004493)
			(xy 349.350731 -261.958963) (xy 349.35033 -261.935976) (xy 349.350705 -261.913288) (xy 349.356909 -261.868339)
			(xy 349.369197 -261.824659) (xy 349.387339 -261.783068) (xy 349.398844 -261.76351) (xy 349.40621 -261.751572)
			(xy 349.406464 -261.723632) (xy 349.259144 -261.469632) (xy 349.23476 -261.45617) (xy 349.22079 -261.456424)
			(xy 349.211138 -261.456678) (xy 349.185149 -261.456198) (xy 349.133811 -261.448072) (xy 349.084375 -261.432015)
			(xy 349.038061 -261.408421) (xy 348.996008 -261.377872) (xy 348.959253 -261.341121) (xy 348.928699 -261.299071)
			(xy 348.9051 -261.25276) (xy 348.889037 -261.203326) (xy 348.880905 -261.151989) (xy 348.880905 -261.100011)
			(xy 348.889037 -261.048674) (xy 348.9051 -260.99924) (xy 348.928699 -260.952929) (xy 348.959252 -260.910879)
			(xy 348.996008 -260.874128) (xy 349.038061 -260.843579) (xy 349.084375 -260.819985) (xy 349.133811 -260.803928)
			(xy 349.185149 -260.795802) (xy 349.211138 -260.795262) (xy 349.241218 -260.79592) (xy 349.30039 -260.806779)
			(xy 349.32874 -260.816852) (xy 349.341948 -260.821932) (xy 349.36938 -260.816852) (xy 350.437196 -259.876544)
			(xy 350.445324 -259.848096) (xy 350.44126 -259.833872) (xy 350.434254 -259.808474) (xy 350.426739 -259.756328)
			(xy 350.426274 -259.729986) (xy 350.426737 -259.703855) (xy 350.434131 -259.652117) (xy 350.448754 -259.601941)
			(xy 350.470314 -259.554332) (xy 350.498379 -259.510244) (xy 350.532387 -259.470558) (xy 350.571656 -259.436071)
			(xy 350.6154 -259.407473) (xy 350.638872 -259.395976) (xy 350.652334 -259.389626) (xy 350.668336 -259.364734)
			(xy 350.668336 -259.195316) (xy 350.652334 -259.170424) (xy 350.638872 -259.164074) (xy 350.613826 -259.151816)
			(xy 350.567432 -259.120885) (xy 350.526225 -259.083319) (xy 350.491148 -259.039975) (xy 350.462999 -258.991842)
			(xy 350.442422 -258.940018) (xy 350.429885 -258.885685) (xy 350.425676 -258.830085) (xy 350.42989 -258.774484)
			(xy 350.442431 -258.720153) (xy 350.463012 -258.668331) (xy 350.491165 -258.6202) (xy 350.526246 -258.576859)
			(xy 350.567456 -258.539296) (xy 350.613853 -258.508369) (xy 350.638872 -258.496054) (xy 350.652334 -258.489704)
			(xy 350.668336 -258.464812) (xy 350.668336 -258.295394) (xy 350.652334 -258.270502) (xy 350.638872 -258.264152)
			(xy 350.615382 -258.252684) (xy 350.571616 -258.224103) (xy 350.53233 -258.189623) (xy 350.498311 -258.149936)
			(xy 350.470243 -258.105839) (xy 350.448689 -258.058218) (xy 350.434083 -258.008028) (xy 350.426717 -257.956278)
			(xy 350.426274 -257.930142) (xy 350.426403 -257.915088) (xy 350.42882 -257.885079) (xy 350.4311 -257.870198)
			(xy 350.43364 -257.855212) (xy 350.42221 -257.828542) (xy 349.104712 -256.922524) (xy 349.077026 -256.920746)
			(xy 349.064326 -256.92735) (xy 349.040546 -256.939183) (xy 348.990149 -256.955943) (xy 348.93772 -256.96443)
			(xy 348.911164 -256.964942) (xy 348.885178 -256.96443) (xy 348.833846 -256.956295) (xy 348.784418 -256.940231)
			(xy 348.738111 -256.916634) (xy 348.696065 -256.886084) (xy 348.659314 -256.849334) (xy 348.628765 -256.807288)
			(xy 348.605168 -256.76098) (xy 348.589105 -256.711552) (xy 348.58097 -256.66022) (xy 348.580456 -256.634234)
			(xy 348.580846 -256.611319) (xy 348.587178 -256.565928) (xy 348.599726 -256.521849) (xy 348.618249 -256.479929)
			(xy 348.629986 -256.460244) (xy 348.637352 -256.448052) (xy 348.63786 -256.420366) (xy 348.491302 -256.167636)
			(xy 348.466918 -256.154174) (xy 348.452694 -256.154682) (xy 348.44101 -256.154936) (xy 348.415388 -256.154448)
			(xy 348.364759 -256.146533) (xy 348.315957 -256.130907) (xy 348.270147 -256.107942) (xy 348.228426 -256.078188)
			(xy 348.191791 -256.042357) (xy 348.16112 -256.001307) (xy 348.148656 -255.978914) (xy 348.142052 -255.966214)
			(xy 348.118176 -255.951736) (xy 347.824044 -255.951736) (xy 347.800168 -255.966214) (xy 347.793564 -255.978914)
			(xy 347.781155 -256.00134) (xy 347.750484 -256.042403) (xy 347.713845 -256.078242) (xy 347.672115 -256.107997)
			(xy 347.626293 -256.130957) (xy 347.577477 -256.146572) (xy 347.526836 -256.154466) (xy 347.50121 -256.154936)
			(xy 347.488002 -256.154682) (xy 347.473778 -256.154174) (xy 347.449394 -256.167636) (xy 347.303344 -256.418842)
			(xy 347.303852 -256.446782) (xy 347.311472 -256.458974) (xy 347.323398 -256.478763) (xy 347.342208 -256.520966)
			(xy 347.354954 -256.565377) (xy 347.361387 -256.611132) (xy 347.361764 -256.634234) (xy 347.361254 -256.660221)
			(xy 347.353124 -256.711556) (xy 347.337063 -256.760986) (xy 347.313467 -256.807296) (xy 347.282917 -256.849344)
			(xy 347.246166 -256.886095) (xy 347.204118 -256.916645) (xy 347.157808 -256.940241) (xy 347.108378 -256.956302)
			(xy 347.057043 -256.964432) (xy 347.005069 -256.964432) (xy 346.953734 -256.956302) (xy 346.904304 -256.940241)
			(xy 346.857994 -256.916645) (xy 346.815946 -256.886095) (xy 346.779195 -256.849344) (xy 346.748645 -256.807296)
			(xy 346.725049 -256.760986) (xy 346.708988 -256.711556) (xy 346.700858 -256.660221) (xy 346.700348 -256.634234)
			(xy 346.700602 -256.62255) (xy 346.70111 -256.608326) (xy 346.687648 -256.583942) (xy 345.83751 -256.095754)
			(xy 345.809824 -256.096262) (xy 345.797632 -256.103882) (xy 345.777729 -256.115979) (xy 345.735246 -256.135073)
			(xy 345.690505 -256.148016) (xy 345.64439 -256.154553) (xy 345.621102 -256.154936) (xy 345.608148 -256.154682)
			(xy 345.59367 -256.154174) (xy 345.569286 -256.167636) (xy 345.42349 -256.418842) (xy 345.423998 -256.446782)
			(xy 345.431618 -256.45872) (xy 345.443548 -256.478542) (xy 345.462358 -256.52081) (xy 345.4751 -256.565285)
			(xy 345.481524 -256.611102) (xy 345.48191 -256.634234) (xy 345.4814 -256.660221) (xy 345.47327 -256.711556)
			(xy 345.457209 -256.760986) (xy 345.433613 -256.807296) (xy 345.403063 -256.849344) (xy 345.366312 -256.886095)
			(xy 345.324264 -256.916645) (xy 345.277954 -256.940241) (xy 345.228524 -256.956302) (xy 345.177189 -256.964432)
			(xy 345.125215 -256.964432) (xy 345.07388 -256.956302) (xy 345.02445 -256.940241) (xy 344.97814 -256.916645)
			(xy 344.936092 -256.886095) (xy 344.899341 -256.849344) (xy 344.868791 -256.807296) (xy 344.845195 -256.760986)
			(xy 344.829134 -256.711556) (xy 344.821004 -256.660221) (xy 344.820494 -256.634234) (xy 344.820748 -256.62255)
			(xy 344.821256 -256.608326) (xy 344.807794 -256.583942) (xy 343.957402 -256.095754) (xy 343.929716 -256.096262)
			(xy 343.917524 -256.103882) (xy 343.89762 -256.115979) (xy 343.855138 -256.135071) (xy 343.810397 -256.148014)
			(xy 343.764282 -256.154549) (xy 343.740994 -256.154936) (xy 343.715369 -256.154455) (xy 343.664732 -256.146551)
			(xy 343.61592 -256.130932) (xy 343.5701 -256.107974) (xy 343.528368 -256.078224) (xy 343.491724 -256.042394)
			(xy 343.461042 -256.001343) (xy 343.44864 -255.978914) (xy 343.442036 -255.966214) (xy 343.41816 -255.951736)
			(xy 343.124028 -255.951736) (xy 343.100152 -255.966214) (xy 343.093548 -255.978914) (xy 343.081138 -256.001341)
			(xy 343.050466 -256.042405) (xy 343.013827 -256.078245) (xy 342.972097 -256.108005) (xy 342.926277 -256.130972)
			(xy 342.877462 -256.146595) (xy 342.826821 -256.154502) (xy 342.775567 -256.154502) (xy 342.724926 -256.146595)
			(xy 342.676111 -256.130972) (xy 342.630291 -256.108005) (xy 342.588561 -256.078245) (xy 342.551922 -256.042405)
			(xy 342.52125 -256.001341) (xy 342.50884 -255.978914) (xy 342.502236 -255.966214) (xy 342.47836 -255.951736)
			(xy 342.183974 -255.951736) (xy 342.160098 -255.966214) (xy 342.153494 -255.978914) (xy 342.141084 -256.001341)
			(xy 342.110412 -256.042405) (xy 342.073773 -256.078245) (xy 342.032043 -256.108005) (xy 341.986223 -256.130972)
			(xy 341.937408 -256.146595) (xy 341.886767 -256.154502) (xy 341.835513 -256.154502) (xy 341.784872 -256.146595)
			(xy 341.736057 -256.130972) (xy 341.690237 -256.108005) (xy 341.648507 -256.078245) (xy 341.611868 -256.042405)
			(xy 341.581196 -256.001341) (xy 341.568786 -255.978914) (xy 341.562182 -255.966214) (xy 341.538306 -255.951736)
			(xy 341.24392 -255.951736) (xy 341.220044 -255.966214) (xy 341.21344 -255.978914) (xy 341.20103 -256.001341)
			(xy 341.170358 -256.042405) (xy 341.133719 -256.078245) (xy 341.091989 -256.108005) (xy 341.046169 -256.130972)
			(xy 340.997354 -256.146595) (xy 340.946713 -256.154502) (xy 340.895459 -256.154502) (xy 340.844818 -256.146595)
			(xy 340.796003 -256.130972) (xy 340.750183 -256.108005) (xy 340.708453 -256.078245) (xy 340.671814 -256.042405)
			(xy 340.641142 -256.001341) (xy 340.628732 -255.978914) (xy 340.622128 -255.966214) (xy 340.598252 -255.951736)
			(xy 340.303866 -255.951736) (xy 340.27999 -255.966214) (xy 340.273386 -255.978914) (xy 340.260976 -256.001341)
			(xy 340.230304 -256.042405) (xy 340.193665 -256.078245) (xy 340.151935 -256.108005) (xy 340.106115 -256.130972)
			(xy 340.0573 -256.146595) (xy 340.006659 -256.154502) (xy 339.955405 -256.154502) (xy 339.904764 -256.146595)
			(xy 339.855949 -256.130972) (xy 339.810129 -256.108005) (xy 339.768399 -256.078245) (xy 339.73176 -256.042405)
			(xy 339.701088 -256.001341) (xy 339.688678 -255.978914) (xy 339.682074 -255.966214) (xy 339.658198 -255.951736)
			(xy 339.194902 -255.951736) (xy 339.184934 -255.951263) (xy 339.166488 -255.943697) (xy 339.159088 -255.937004)
			(xy 338.57438 -255.352296) (xy 338.55787 -255.344676) (xy 338.548472 -255.344168) (xy 338.522207 -255.341853)
			(xy 338.470846 -255.329947) (xy 338.422024 -255.310044) (xy 338.376978 -255.282647) (xy 338.336849 -255.248451)
			(xy 338.302653 -255.208322) (xy 338.275256 -255.163276) (xy 338.255353 -255.114454) (xy 338.243447 -255.063093)
			(xy 338.241132 -255.036828) (xy 338.240624 -255.02743) (xy 338.233004 -255.01092) (xy 336.901282 -253.679198)
			(xy 336.8675 -253.674626) (xy 336.852514 -253.682754) (xy 336.8277 -253.695965) (xy 336.77472 -253.714746)
			(xy 336.719329 -253.72431) (xy 336.691224 -253.724918) (xy 336.665233 -253.724437) (xy 336.613891 -253.716308)
			(xy 336.564453 -253.700248) (xy 336.518136 -253.676652) (xy 336.47608 -253.646101) (xy 336.439322 -253.609346)
			(xy 336.408766 -253.567294) (xy 336.385165 -253.520979) (xy 336.369099 -253.471542) (xy 336.360966 -253.420201)
			(xy 336.360516 -253.39421) (xy 336.361097 -253.366102) (xy 336.370642 -253.3107) (xy 336.389424 -253.257713)
			(xy 336.40268 -253.23292) (xy 336.410808 -253.217934) (xy 336.406236 -253.184152) (xy 336.12201 -252.899926)
			(xy 336.111088 -252.896116) (xy 336.088022 -252.887501) (xy 336.044531 -252.864422) (xy 336.004941 -252.835151)
			(xy 335.970128 -252.800334) (xy 335.94086 -252.760741) (xy 335.917786 -252.717247) (xy 335.909158 -252.694186)
			(xy 335.905348 -252.683264) (xy 335.359756 -252.137672) (xy 335.353081 -252.130259) (xy 335.345516 -252.111823)
			(xy 335.345024 -252.101858) (xy 335.345024 -227.323396) (xy 335.344601 -227.313326) (xy 335.336888 -227.29472)
			(xy 335.330038 -227.287328) (xy 335.153254 -227.110544) (xy 335.14583 -227.103764) (xy 335.127234 -227.096159)
			(xy 335.117186 -227.095812) (xy 327.25868 -227.095812) (xy 327.246547 -227.096441) (xy 327.224934 -227.107459)
			(xy 327.217278 -227.116894) (xy 327.202757 -227.136065) (xy 327.167792 -227.169076) (xy 327.127243 -227.194923)
			(xy 327.082556 -227.212684) (xy 327.035327 -227.221724) (xy 327.011284 -227.222304) (xy 303.628552 -227.222304)
			(xy 303.604422 -227.23729) (xy 303.597818 -227.250244) (xy 303.585208 -227.274372) (xy 303.553964 -227.318955)
			(xy 303.516503 -227.358457) (xy 303.473639 -227.39202) (xy 303.426305 -227.418912) (xy 303.37553 -227.438551)
			(xy 303.322418 -227.450507) (xy 303.268126 -227.454522) (xy 303.213834 -227.450507) (xy 303.160722 -227.438551)
			(xy 303.109947 -227.418912) (xy 303.062613 -227.39202) (xy 303.019749 -227.358457) (xy 302.982288 -227.318955)
			(xy 302.951044 -227.274372) (xy 302.938434 -227.250244) (xy 302.93183 -227.23729) (xy 302.9077 -227.222304)
			(xy 300.184566 -227.222304) (xy 300.160436 -227.23729) (xy 300.153832 -227.250244) (xy 300.141222 -227.274372)
			(xy 300.109978 -227.318955) (xy 300.072517 -227.358457) (xy 300.029653 -227.39202) (xy 299.982319 -227.418912)
			(xy 299.931544 -227.438551) (xy 299.878432 -227.450507) (xy 299.82414 -227.454522) (xy 299.769848 -227.450507)
			(xy 299.716736 -227.438551) (xy 299.665961 -227.418912) (xy 299.618627 -227.39202) (xy 299.575763 -227.358457)
			(xy 299.538302 -227.318955) (xy 299.507058 -227.274372) (xy 299.494448 -227.250244) (xy 299.487844 -227.23729)
			(xy 299.463714 -227.222304) (xy 296.084498 -227.222304) (xy 296.060368 -227.23729) (xy 296.053764 -227.250244)
			(xy 296.041154 -227.274372) (xy 296.00991 -227.318955) (xy 295.972449 -227.358457) (xy 295.929585 -227.39202)
			(xy 295.882251 -227.418912) (xy 295.831476 -227.438551) (xy 295.778364 -227.450507) (xy 295.724072 -227.454522)
			(xy 295.66978 -227.450507) (xy 295.616668 -227.438551) (xy 295.565893 -227.418912) (xy 295.518559 -227.39202)
			(xy 295.475695 -227.358457) (xy 295.438234 -227.318955) (xy 295.40699 -227.274372) (xy 295.39438 -227.250244)
			(xy 295.387776 -227.23729) (xy 295.363646 -227.222304) (xy 292.640512 -227.222304) (xy 292.616382 -227.23729)
			(xy 292.609778 -227.250244) (xy 292.597168 -227.274372) (xy 292.565924 -227.318955) (xy 292.528463 -227.358457)
			(xy 292.485599 -227.39202) (xy 292.438265 -227.418912) (xy 292.38749 -227.438551) (xy 292.334378 -227.450507)
			(xy 292.280086 -227.454522) (xy 292.225794 -227.450507) (xy 292.172682 -227.438551) (xy 292.121907 -227.418912)
			(xy 292.074573 -227.39202) (xy 292.031709 -227.358457) (xy 291.994248 -227.318955) (xy 291.963004 -227.274372)
			(xy 291.950394 -227.250244) (xy 291.94379 -227.23729) (xy 291.91966 -227.222304) (xy 288.540444 -227.222304)
			(xy 288.516314 -227.23729) (xy 288.50971 -227.250244) (xy 288.4971 -227.274372) (xy 288.465856 -227.318955)
			(xy 288.428395 -227.358457) (xy 288.385531 -227.39202) (xy 288.338197 -227.418912) (xy 288.287422 -227.438551)
			(xy 288.23431 -227.450507) (xy 288.180018 -227.454522) (xy 288.125726 -227.450507) (xy 288.072614 -227.438551)
			(xy 288.021839 -227.418912) (xy 287.974505 -227.39202) (xy 287.931641 -227.358457) (xy 287.89418 -227.318955)
			(xy 287.862936 -227.274372) (xy 287.850326 -227.250244) (xy 287.843722 -227.23729) (xy 287.819592 -227.222304)
			(xy 285.096458 -227.222304) (xy 285.072328 -227.23729) (xy 285.065724 -227.250244) (xy 285.053114 -227.274372)
			(xy 285.02187 -227.318955) (xy 284.984409 -227.358457) (xy 284.941545 -227.39202) (xy 284.894211 -227.418912)
			(xy 284.843436 -227.438551) (xy 284.790324 -227.450507) (xy 284.736032 -227.454522) (xy 284.68174 -227.450507)
			(xy 284.628628 -227.438551) (xy 284.577853 -227.418912) (xy 284.530519 -227.39202) (xy 284.487655 -227.358457)
			(xy 284.450194 -227.318955) (xy 284.41895 -227.274372) (xy 284.40634 -227.250244) (xy 284.399736 -227.23729)
			(xy 284.375606 -227.222304) (xy 280.99639 -227.222304) (xy 280.97226 -227.23729) (xy 280.965656 -227.250244)
			(xy 280.953046 -227.274372) (xy 280.921802 -227.318955) (xy 280.884341 -227.358457) (xy 280.841477 -227.39202)
			(xy 280.794143 -227.418912) (xy 280.743368 -227.438551) (xy 280.690256 -227.450507) (xy 280.635964 -227.454522)
			(xy 280.581672 -227.450507) (xy 280.52856 -227.438551) (xy 280.477785 -227.418912) (xy 280.430451 -227.39202)
			(xy 280.387587 -227.358457) (xy 280.350126 -227.318955) (xy 280.318882 -227.274372) (xy 280.306272 -227.250244)
			(xy 280.299668 -227.23729) (xy 280.275538 -227.222304) (xy 277.552658 -227.222304) (xy 277.528528 -227.23729)
			(xy 277.521924 -227.250244) (xy 277.509314 -227.274372) (xy 277.47807 -227.318955) (xy 277.440609 -227.358457)
			(xy 277.397745 -227.39202) (xy 277.350411 -227.418912) (xy 277.299636 -227.438551) (xy 277.246524 -227.450507)
			(xy 277.192232 -227.454522) (xy 277.13794 -227.450507) (xy 277.084828 -227.438551) (xy 277.034053 -227.418912)
			(xy 276.986719 -227.39202) (xy 276.943855 -227.358457) (xy 276.906394 -227.318955) (xy 276.87515 -227.274372)
			(xy 276.86254 -227.250244) (xy 276.855936 -227.23729) (xy 276.831806 -227.222304) (xy 273.45259 -227.222304)
			(xy 273.42846 -227.23729) (xy 273.421856 -227.250244) (xy 273.409246 -227.274372) (xy 273.378002 -227.318955)
			(xy 273.340541 -227.358457) (xy 273.297677 -227.39202) (xy 273.250343 -227.418912) (xy 273.199568 -227.438551)
			(xy 273.146456 -227.450507) (xy 273.092164 -227.454522) (xy 273.037872 -227.450507) (xy 272.98476 -227.438551)
			(xy 272.933985 -227.418912) (xy 272.886651 -227.39202) (xy 272.843787 -227.358457) (xy 272.806326 -227.318955)
			(xy 272.775082 -227.274372) (xy 272.762472 -227.250244) (xy 272.755868 -227.23729) (xy 272.731738 -227.222304)
			(xy 271.399762 -227.222304) (xy 271.38976 -227.222799) (xy 271.371282 -227.230465) (xy 271.357142 -227.244617)
			(xy 271.34949 -227.263101) (xy 271.348962 -227.273104) (xy 271.348962 -243.860828) (xy 271.34921 -243.868009)
			(xy 271.353207 -243.881804) (xy 271.356836 -243.888006) (xy 271.370366 -243.910221) (xy 271.391725 -243.957647)
			(xy 271.406205 -244.007604) (xy 271.413516 -244.059102) (xy 271.413515 -244.111115) (xy 271.406201 -244.162612)
			(xy 271.391719 -244.212569) (xy 271.370358 -244.259994) (xy 271.356836 -244.282214) (xy 271.353197 -244.288412)
			(xy 271.34919 -244.302209) (xy 271.348962 -244.309392) (xy 271.348962 -258.880102) (xy 315.252104 -258.880102)
			(xy 315.256134 -258.737767) (xy 315.268209 -258.595887) (xy 315.288292 -258.454919) (xy 315.316319 -258.315312)
			(xy 315.352199 -258.177514) (xy 315.395817 -258.041967) (xy 315.447034 -257.909105) (xy 315.505685 -257.779353)
			(xy 315.571583 -257.653127) (xy 315.644517 -257.530831) (xy 315.724254 -257.412858) (xy 315.810536 -257.299585)
			(xy 315.903089 -257.191374) (xy 316.001616 -257.088573) (xy 316.105801 -256.991511) (xy 316.21531 -256.900499)
			(xy 316.329793 -256.815827) (xy 316.448883 -256.737769) (xy 316.572198 -256.666573) (xy 316.699344 -256.602467)
			(xy 316.829913 -256.545658) (xy 316.963487 -256.496326) (xy 317.099638 -256.45463) (xy 317.237929 -256.420704)
			(xy 317.377919 -256.394656) (xy 317.519158 -256.37657) (xy 317.661194 -256.366503) (xy 317.803572 -256.364488)
			(xy 317.945836 -256.370531) (xy 318.08753 -256.384613) (xy 318.2282 -256.406689) (xy 318.367397 -256.436689)
			(xy 318.504673 -256.474515) (xy 318.639589 -256.520047) (xy 318.771713 -256.573138) (xy 318.900622 -256.63362)
			(xy 319.025903 -256.701298) (xy 319.147154 -256.775955) (xy 319.263987 -256.857353) (xy 319.376028 -256.94523)
			(xy 319.482918 -257.039305) (xy 319.584315 -257.139277) (xy 319.679893 -257.244825) (xy 319.769347 -257.355611)
			(xy 319.852389 -257.47128) (xy 319.928755 -257.591463) (xy 319.998199 -257.715773) (xy 320.060499 -257.843814)
			(xy 320.115455 -257.975173) (xy 320.162892 -258.109432) (xy 320.202656 -258.246159) (xy 320.234622 -258.384917)
			(xy 320.258687 -258.525261) (xy 320.274773 -258.666742) (xy 320.282828 -258.808906) (xy 320.283332 -258.880102)
			(xy 320.282828 -258.951298) (xy 320.274773 -259.093462) (xy 320.258687 -259.234943) (xy 320.234622 -259.375287)
			(xy 320.202656 -259.514045) (xy 320.162892 -259.650772) (xy 320.115455 -259.785031) (xy 320.060499 -259.91639)
			(xy 319.998199 -260.044431) (xy 319.928755 -260.168741) (xy 319.852389 -260.288924) (xy 319.769347 -260.404593)
			(xy 319.679893 -260.515379) (xy 319.584315 -260.620927) (xy 319.482918 -260.720899) (xy 319.376028 -260.814974)
			(xy 319.263987 -260.902851) (xy 319.147154 -260.984249) (xy 319.025903 -261.058906) (xy 318.900622 -261.126584)
			(xy 318.771713 -261.187066) (xy 318.639589 -261.240157) (xy 318.504673 -261.285689) (xy 318.367397 -261.323515)
			(xy 318.2282 -261.353515) (xy 318.08753 -261.375591) (xy 317.945836 -261.389673) (xy 317.803572 -261.395716)
			(xy 317.661194 -261.393701) (xy 317.519158 -261.383634) (xy 317.377919 -261.365548) (xy 317.237929 -261.3395)
			(xy 317.099638 -261.305574) (xy 316.963487 -261.263878) (xy 316.829913 -261.214546) (xy 316.699344 -261.157737)
			(xy 316.572198 -261.093631) (xy 316.448883 -261.022435) (xy 316.329793 -260.944377) (xy 316.21531 -260.859705)
			(xy 316.105801 -260.768693) (xy 316.001616 -260.671631) (xy 315.903089 -260.56883) (xy 315.810536 -260.460619)
			(xy 315.724254 -260.347346) (xy 315.644517 -260.229373) (xy 315.571583 -260.107077) (xy 315.505685 -259.980851)
			(xy 315.447034 -259.851099) (xy 315.395817 -259.718237) (xy 315.352199 -259.58269) (xy 315.316319 -259.444892)
			(xy 315.288292 -259.305285) (xy 315.268209 -259.164317) (xy 315.256134 -259.022437) (xy 315.252104 -258.880102)
			(xy 271.348962 -258.880102) (xy 271.348962 -334.81518) (xy 271.349401 -334.825242) (xy 271.357143 -334.84382)
			(xy 271.363948 -334.851248) (xy 271.731232 -335.218532) (xy 271.738629 -335.225381) (xy 271.757228 -335.233114)
			(xy 271.7673 -335.233518)
		)
		(stroke
			(width 0)
			(type solid)
		)
		(fill yes)
		(layer "In8.Cu")
		(net "PVDDIO_P0")
	)
	(gr_poly
		(pts
			(xy 56.104028 -335.233264) (xy 56.114095 -335.232835) (xy 56.132689 -335.225109) (xy 56.140096 -335.218278)
			(xy 56.5404 -334.817974) (xy 56.547242 -334.810574) (xy 56.554967 -334.791976) (xy 56.555386 -334.781906)
			(xy 56.555386 -325.5772) (xy 56.554966 -325.56718) (xy 56.547296 -325.548665) (xy 56.533123 -325.534496)
			(xy 56.514606 -325.526831) (xy 56.504586 -325.5264) (xy 56.501792 -325.5264) (xy 56.457304 -325.525901)
			(xy 56.368687 -325.517924) (xy 56.281142 -325.502037) (xy 56.195373 -325.478365) (xy 56.112071 -325.447101)
			(xy 56.031907 -325.408495) (xy 55.955527 -325.36286) (xy 55.883544 -325.310561) (xy 55.81654 -325.25202)
			(xy 55.755052 -325.187709) (xy 55.699577 -325.118145) (xy 55.650561 -325.043888) (xy 55.608399 -324.965537)
			(xy 55.573429 -324.883721) (xy 55.545935 -324.799101) (xy 55.526136 -324.712356) (xy 55.514192 -324.624186)
			(xy 55.5102 -324.5353) (xy 55.514192 -324.446414) (xy 55.526136 -324.358244) (xy 55.545935 -324.271499)
			(xy 55.573429 -324.186879) (xy 55.608399 -324.105063) (xy 55.650561 -324.026712) (xy 55.699577 -323.952455)
			(xy 55.755052 -323.882891) (xy 55.81654 -323.81858) (xy 55.883544 -323.760039) (xy 55.955527 -323.70774)
			(xy 56.031907 -323.662105) (xy 56.112071 -323.623499) (xy 56.195373 -323.592235) (xy 56.281142 -323.568563)
			(xy 56.368687 -323.552676) (xy 56.457304 -323.544699) (xy 56.501792 -323.544184) (xy 56.504586 -323.544184)
			(xy 56.514608 -323.543767) (xy 56.533127 -323.536099) (xy 56.5473 -323.521925) (xy 56.554967 -323.503406)
			(xy 56.555386 -323.493384) (xy 56.555386 -315.849762) (xy 56.554944 -315.840865) (xy 56.54876 -315.824175)
			(xy 56.537253 -315.810595) (xy 56.529732 -315.80582) (xy 56.505874 -315.791632) (xy 56.462326 -315.757215)
			(xy 56.424424 -315.716664) (xy 56.393023 -315.670894) (xy 56.36883 -315.620937) (xy 56.352393 -315.56792)
			(xy 56.344082 -315.513039) (xy 56.344084 -315.457533) (xy 56.3524 -315.402653) (xy 56.368841 -315.349637)
			(xy 56.393037 -315.299682) (xy 56.424441 -315.253914) (xy 56.462347 -315.213366) (xy 56.505897 -315.178952)
			(xy 56.529732 -315.164724) (xy 56.537309 -315.160019) (xy 56.548833 -315.146422) (xy 56.554984 -315.129693)
			(xy 56.555386 -315.120782) (xy 56.555386 -313.299856) (xy 56.554943 -313.29096) (xy 56.548758 -313.274271)
			(xy 56.537251 -313.260693) (xy 56.529732 -313.255914) (xy 56.505875 -313.241726) (xy 56.462327 -313.207309)
			(xy 56.424426 -313.166759) (xy 56.393026 -313.120989) (xy 56.368834 -313.071032) (xy 56.352398 -313.018016)
			(xy 56.344087 -312.963136) (xy 56.34409 -312.90763) (xy 56.352405 -312.852751) (xy 56.368847 -312.799736)
			(xy 56.393043 -312.749782) (xy 56.424447 -312.704015) (xy 56.462352 -312.663468) (xy 56.505903 -312.629055)
			(xy 56.529732 -312.614818) (xy 56.537308 -312.610113) (xy 56.54883 -312.596516) (xy 56.554979 -312.579787)
			(xy 56.555386 -312.570876) (xy 56.555386 -308.169564) (xy 56.556001 -308.144609) (xy 56.565744 -308.095658)
			(xy 56.584849 -308.049548) (xy 56.612581 -308.008051) (xy 56.629808 -307.989986) (xy 68.841112 -295.778682)
			(xy 68.859152 -295.761418) (xy 68.900644 -295.733653) (xy 68.946762 -295.714532) (xy 68.995727 -295.704793)
			(xy 69.02069 -295.70426) (xy 78.948788 -295.70426) (xy 78.957133 -295.703969) (xy 78.972948 -295.698651)
			(xy 78.979776 -295.693846) (xy 79.001575 -295.677821) (xy 79.049295 -295.652333) (xy 79.100522 -295.634936)
			(xy 79.153894 -295.62609) (xy 79.180944 -295.62552) (xy 79.206759 -295.626011) (xy 79.257762 -295.634022)
			(xy 79.306903 -295.649857) (xy 79.352988 -295.673133) (xy 79.394898 -295.703284) (xy 79.431617 -295.739578)
			(xy 79.462252 -295.781136) (xy 79.474568 -295.803828) (xy 79.481172 -295.816528) (xy 79.505302 -295.83126)
			(xy 82.644996 -295.83126) (xy 82.668618 -295.817544) (xy 82.675476 -295.805606) (xy 82.688111 -295.784283)
			(xy 82.71919 -295.745676) (xy 82.756102 -295.712602) (xy 82.797874 -295.685929) (xy 82.843408 -295.666359)
			(xy 82.891507 -295.654407) (xy 82.940906 -295.650388) (xy 82.990305 -295.654407) (xy 83.038404 -295.666359)
			(xy 83.083938 -295.685929) (xy 83.12571 -295.712602) (xy 83.162622 -295.745676) (xy 83.193701 -295.784283)
			(xy 83.206336 -295.805606) (xy 83.213194 -295.817544) (xy 83.236816 -295.83126) (xy 83.556602 -295.83126)
			(xy 83.580732 -295.816528) (xy 83.587336 -295.803828) (xy 83.599682 -295.781155) (xy 83.630318 -295.739605)
			(xy 83.667034 -295.703317) (xy 83.70894 -295.67317) (xy 83.755018 -295.649895) (xy 83.804152 -295.634058)
			(xy 83.855149 -295.626042) (xy 83.906771 -295.626042) (xy 83.957768 -295.634058) (xy 84.006902 -295.649895)
			(xy 84.05298 -295.67317) (xy 84.094886 -295.703317) (xy 84.131602 -295.739605) (xy 84.162238 -295.781155)
			(xy 84.174584 -295.803828) (xy 84.181188 -295.816528) (xy 84.205318 -295.83126) (xy 84.525104 -295.83126)
			(xy 84.548726 -295.817544) (xy 84.555584 -295.805606) (xy 84.568219 -295.784283) (xy 84.599298 -295.745676)
			(xy 84.63621 -295.712602) (xy 84.677982 -295.685929) (xy 84.723516 -295.666359) (xy 84.771615 -295.654407)
			(xy 84.821014 -295.650388) (xy 84.870413 -295.654407) (xy 84.918512 -295.666359) (xy 84.964046 -295.685929)
			(xy 85.005818 -295.712602) (xy 85.04273 -295.745676) (xy 85.073809 -295.784283) (xy 85.086444 -295.805606)
			(xy 85.093302 -295.817544) (xy 85.116924 -295.83126) (xy 85.43671 -295.83126) (xy 85.46084 -295.816528)
			(xy 85.467444 -295.803828) (xy 85.47979 -295.781155) (xy 85.510426 -295.739605) (xy 85.547142 -295.703317)
			(xy 85.589048 -295.67317) (xy 85.635126 -295.649895) (xy 85.68426 -295.634058) (xy 85.735257 -295.626042)
			(xy 85.786879 -295.626042) (xy 85.837876 -295.634058) (xy 85.88701 -295.649895) (xy 85.933088 -295.67317)
			(xy 85.974994 -295.703317) (xy 86.01171 -295.739605) (xy 86.042346 -295.781155) (xy 86.054692 -295.803828)
			(xy 86.061296 -295.816528) (xy 86.085426 -295.83126) (xy 86.405212 -295.83126) (xy 86.428834 -295.817544)
			(xy 86.435692 -295.805606) (xy 86.448327 -295.784283) (xy 86.479406 -295.745676) (xy 86.516318 -295.712602)
			(xy 86.55809 -295.685929) (xy 86.603624 -295.666359) (xy 86.651723 -295.654407) (xy 86.701122 -295.650388)
			(xy 86.750521 -295.654407) (xy 86.79862 -295.666359) (xy 86.844154 -295.685929) (xy 86.885926 -295.712602)
			(xy 86.922838 -295.745676) (xy 86.953917 -295.784283) (xy 86.966552 -295.805606) (xy 86.97341 -295.817544)
			(xy 86.997032 -295.83126) (xy 88.256618 -295.83126) (xy 88.280748 -295.816528) (xy 88.287352 -295.803828)
			(xy 88.299698 -295.781155) (xy 88.330334 -295.739605) (xy 88.36705 -295.703317) (xy 88.408956 -295.67317)
			(xy 88.455034 -295.649895) (xy 88.504168 -295.634058) (xy 88.555165 -295.626042) (xy 88.606787 -295.626042)
			(xy 88.657784 -295.634058) (xy 88.706918 -295.649895) (xy 88.752996 -295.67317) (xy 88.794902 -295.703317)
			(xy 88.831618 -295.739605) (xy 88.862254 -295.781155) (xy 88.8746 -295.803828) (xy 88.881204 -295.816528)
			(xy 88.905334 -295.83126) (xy 89.22512 -295.83126) (xy 89.248742 -295.817544) (xy 89.2556 -295.805606)
			(xy 89.268235 -295.784283) (xy 89.299314 -295.745676) (xy 89.336226 -295.712602) (xy 89.377998 -295.685929)
			(xy 89.423532 -295.666359) (xy 89.471631 -295.654407) (xy 89.52103 -295.650388) (xy 89.570429 -295.654407)
			(xy 89.618528 -295.666359) (xy 89.664062 -295.685929) (xy 89.705834 -295.712602) (xy 89.742746 -295.745676)
			(xy 89.773825 -295.784283) (xy 89.78646 -295.805606) (xy 89.793318 -295.817544) (xy 89.81694 -295.83126)
			(xy 90.136726 -295.83126) (xy 90.160856 -295.816528) (xy 90.16746 -295.803828) (xy 90.179806 -295.781155)
			(xy 90.210442 -295.739605) (xy 90.247158 -295.703317) (xy 90.289064 -295.67317) (xy 90.335142 -295.649895)
			(xy 90.384276 -295.634058) (xy 90.435273 -295.626042) (xy 90.486895 -295.626042) (xy 90.537892 -295.634058)
			(xy 90.587026 -295.649895) (xy 90.633104 -295.67317) (xy 90.67501 -295.703317) (xy 90.711726 -295.739605)
			(xy 90.742362 -295.781155) (xy 90.754708 -295.803828) (xy 90.761312 -295.816528) (xy 90.785442 -295.83126)
			(xy 91.105228 -295.83126) (xy 91.12885 -295.817544) (xy 91.135708 -295.805606) (xy 91.148343 -295.784283)
			(xy 91.179422 -295.745676) (xy 91.216334 -295.712602) (xy 91.258106 -295.685929) (xy 91.30364 -295.666359)
			(xy 91.351739 -295.654407) (xy 91.401138 -295.650388) (xy 91.450537 -295.654407) (xy 91.498636 -295.666359)
			(xy 91.54417 -295.685929) (xy 91.585942 -295.712602) (xy 91.622854 -295.745676) (xy 91.653933 -295.784283)
			(xy 91.666568 -295.805606) (xy 91.673426 -295.817544) (xy 91.697048 -295.83126) (xy 92.01658 -295.83126)
			(xy 92.04071 -295.816528) (xy 92.047314 -295.803828) (xy 92.059659 -295.781153) (xy 92.090294 -295.739599)
			(xy 92.127009 -295.703306) (xy 92.168914 -295.673152) (xy 92.214993 -295.649871) (xy 92.264127 -295.634025)
			(xy 92.315125 -295.626001) (xy 92.340938 -295.62552) (xy 92.352876 -295.625774) (xy 92.3671 -295.626282)
			(xy 92.391484 -295.61282) (xy 92.552266 -295.33596) (xy 92.55252 -295.309036) (xy 92.545662 -295.297098)
			(xy 92.533138 -295.273944) (xy 92.515363 -295.224399) (xy 92.506349 -295.17254) (xy 92.505784 -295.146222)
			(xy 92.506251 -295.122255) (xy 92.513738 -295.074909) (xy 92.528533 -295.029315) (xy 92.550271 -294.986593)
			(xy 92.578418 -294.947793) (xy 92.612283 -294.913868) (xy 92.651033 -294.885653) (xy 92.693717 -294.863839)
			(xy 92.739285 -294.848965) (xy 92.786618 -294.841394) (xy 92.810584 -294.840914) (xy 92.824046 -294.840914)
			(xy 92.847414 -294.827452) (xy 93.02242 -294.525954) (xy 93.02242 -294.49903) (xy 93.015562 -294.487346)
			(xy 93.003016 -294.464154) (xy 92.98522 -294.414526) (xy 92.976212 -294.362578) (xy 92.975684 -294.336216)
			(xy 92.976151 -294.312249) (xy 92.98364 -294.264904) (xy 92.998435 -294.21931) (xy 93.020173 -294.176589)
			(xy 93.04832 -294.13779) (xy 93.082185 -294.103866) (xy 93.120935 -294.075651) (xy 93.163618 -294.053839)
			(xy 93.209186 -294.038964) (xy 93.256518 -294.031394) (xy 93.280484 -294.030908) (xy 93.293946 -294.030908)
			(xy 93.317314 -294.017446) (xy 93.478096 -293.740586) (xy 93.477588 -293.712646) (xy 93.470222 -293.700454)
			(xy 93.458445 -293.680747) (xy 93.439851 -293.638772) (xy 93.427242 -293.594628) (xy 93.420862 -293.549164)
			(xy 93.420438 -293.52621) (xy 93.42092 -293.500222) (xy 93.429051 -293.448884) (xy 93.445113 -293.399452)
			(xy 93.468711 -293.35314) (xy 93.499263 -293.311091) (xy 93.536019 -293.27434) (xy 93.578071 -293.243792)
			(xy 93.624385 -293.220199) (xy 93.67382 -293.204142) (xy 93.725157 -293.196018) (xy 93.751146 -293.195502)
			(xy 93.776961 -293.195993) (xy 93.827965 -293.204004) (xy 93.877106 -293.219839) (xy 93.923192 -293.243114)
			(xy 93.965103 -293.273264) (xy 94.001823 -293.309558) (xy 94.03246 -293.351115) (xy 94.04477 -293.37381)
			(xy 94.051374 -293.38651) (xy 94.075504 -293.401242) (xy 94.366588 -293.401242) (xy 94.390718 -293.38651)
			(xy 94.397322 -293.37381) (xy 94.409668 -293.351136) (xy 94.440304 -293.309585) (xy 94.47702 -293.273295)
			(xy 94.518926 -293.243144) (xy 94.565003 -293.219865) (xy 94.614137 -293.204022) (xy 94.665134 -293.195999)
			(xy 94.690946 -293.195502) (xy 94.702884 -293.195756) (xy 94.717108 -293.196264) (xy 94.741492 -293.182802)
			(xy 94.88805 -292.930326) (xy 94.887542 -292.90264) (xy 94.879922 -292.890448) (xy 94.868186 -292.870728)
			(xy 94.849668 -292.828741) (xy 94.837122 -292.784599) (xy 94.830788 -292.739149) (xy 94.830392 -292.716204)
			(xy 94.830875 -292.690215) (xy 94.839006 -292.638875) (xy 94.855067 -292.58944) (xy 94.878665 -292.543127)
			(xy 94.909217 -292.501075) (xy 94.945972 -292.46432) (xy 94.988023 -292.433767) (xy 95.034337 -292.410169)
			(xy 95.083772 -292.394106) (xy 95.135111 -292.385975) (xy 95.1611 -292.385496) (xy 95.173038 -292.38575)
			(xy 95.187262 -292.386258) (xy 95.211646 -292.372796) (xy 95.35795 -292.120574) (xy 95.357442 -292.092634)
			(xy 95.350076 -292.080696) (xy 95.338283 -292.060961) (xy 95.319668 -292.018925) (xy 95.307055 -291.974715)
			(xy 95.300688 -291.929185) (xy 95.300292 -291.906198) (xy 95.300802 -291.880211) (xy 95.308933 -291.828877)
			(xy 95.324994 -291.779446) (xy 95.34859 -291.733137) (xy 95.379139 -291.691089) (xy 95.415891 -291.654338)
			(xy 95.457939 -291.623789) (xy 95.504248 -291.600193) (xy 95.553679 -291.584132) (xy 95.605013 -291.576002)
			(xy 95.631 -291.57549) (xy 95.642938 -291.575744) (xy 95.657162 -291.576252) (xy 95.681546 -291.56279)
			(xy 95.828104 -291.310568) (xy 95.827596 -291.282628) (xy 95.82023 -291.270436) (xy 95.808448 -291.25073)
			(xy 95.789843 -291.208757) (xy 95.777223 -291.164613) (xy 95.770831 -291.119148) (xy 95.770446 -291.096192)
			(xy 95.770956 -291.070204) (xy 95.779087 -291.018868) (xy 95.795148 -290.969435) (xy 95.818744 -290.923124)
			(xy 95.849293 -290.881073) (xy 95.886044 -290.844318) (xy 95.928091 -290.813764) (xy 95.9744 -290.790163)
			(xy 96.023831 -290.774096) (xy 96.075166 -290.765959) (xy 96.101154 -290.765484) (xy 96.113092 -290.765738)
			(xy 96.127316 -290.766246) (xy 96.1517 -290.752784) (xy 96.298004 -290.500562) (xy 96.29775 -290.472876)
			(xy 96.29013 -290.460684) (xy 96.278336 -290.440949) (xy 96.25972 -290.398913) (xy 96.247107 -290.354704)
			(xy 96.24074 -290.309173) (xy 96.240346 -290.286186) (xy 96.240857 -290.260198) (xy 96.248989 -290.208863)
			(xy 96.26505 -290.159431) (xy 96.288646 -290.11312) (xy 96.319195 -290.07107) (xy 96.355946 -290.034316)
			(xy 96.397993 -290.003763) (xy 96.444301 -289.980162) (xy 96.493732 -289.964096) (xy 96.545066 -289.955959)
			(xy 96.571054 -289.955478) (xy 96.583246 -289.955732) (xy 96.59747 -289.95624) (xy 96.621854 -289.942778)
			(xy 96.767904 -289.69081) (xy 96.76765 -289.66287) (xy 96.76003 -289.650678) (xy 96.748236 -289.630943)
			(xy 96.729621 -289.588907) (xy 96.717009 -289.544697) (xy 96.710642 -289.499167) (xy 96.710246 -289.47618)
			(xy 96.710757 -289.450193) (xy 96.71889 -289.398858) (xy 96.734952 -289.349427) (xy 96.758548 -289.303117)
			(xy 96.789097 -289.261068) (xy 96.825848 -289.224314) (xy 96.867895 -289.193762) (xy 96.914203 -289.170162)
			(xy 96.963632 -289.154096) (xy 97.014967 -289.145959) (xy 97.040954 -289.145472) (xy 97.053146 -289.145726)
			(xy 97.06737 -289.146234) (xy 97.091754 -289.132772) (xy 97.238058 -288.88055) (xy 97.23755 -288.85261)
			(xy 97.230184 -288.840418) (xy 97.218404 -288.820712) (xy 97.199804 -288.778737) (xy 97.187188 -288.734594)
			(xy 97.1808 -288.689129) (xy 97.1804 -288.666174) (xy 97.180776 -288.643486) (xy 97.186979 -288.598537)
			(xy 97.199266 -288.554856) (xy 97.217407 -288.513265) (xy 97.228914 -288.493708) (xy 97.23628 -288.48177)
			(xy 97.236534 -288.45383) (xy 97.089214 -288.200084) (xy 97.06483 -288.186622) (xy 97.05086 -288.186876)
			(xy 97.040954 -288.18713) (xy 97.014969 -288.186617) (xy 96.963638 -288.178481) (xy 96.914213 -288.162416)
			(xy 96.867908 -288.138818) (xy 96.825864 -288.108268) (xy 96.789116 -288.071518) (xy 96.758569 -288.029472)
			(xy 96.734975 -287.983165) (xy 96.718913 -287.933738) (xy 96.710781 -287.882407) (xy 96.710246 -287.856422)
			(xy 96.710618 -287.833692) (xy 96.716846 -287.78866) (xy 96.729201 -287.744911) (xy 96.747449 -287.703274)
			(xy 96.759014 -287.683702) (xy 96.76638 -287.671764) (xy 96.766634 -287.643824) (xy 96.619314 -287.389824)
			(xy 96.59493 -287.376362) (xy 96.58096 -287.376616) (xy 96.571054 -287.37687) (xy 96.545072 -287.376357)
			(xy 96.493749 -287.368221) (xy 96.444331 -287.352158) (xy 96.398033 -287.328563) (xy 96.355996 -287.298016)
			(xy 96.319255 -287.261269) (xy 96.288713 -287.219228) (xy 96.265124 -287.172927) (xy 96.249068 -287.123506)
			(xy 96.24094 -287.072182) (xy 96.24094 -287.020218) (xy 96.249068 -286.968894) (xy 96.265124 -286.919473)
			(xy 96.288713 -286.873172) (xy 96.319255 -286.831131) (xy 96.355996 -286.794384) (xy 96.398033 -286.763837)
			(xy 96.444331 -286.740242) (xy 96.493749 -286.724179) (xy 96.545072 -286.716043) (xy 96.571054 -286.715454)
			(xy 96.583246 -286.715708) (xy 96.59747 -286.716216) (xy 96.621854 -286.702754) (xy 96.767904 -286.450786)
			(xy 96.767396 -286.422846) (xy 96.76003 -286.410908) (xy 96.748235 -286.391174) (xy 96.729615 -286.349138)
			(xy 96.716999 -286.304928) (xy 96.710629 -286.259397) (xy 96.710246 -286.23641) (xy 96.710755 -286.210421)
			(xy 96.718884 -286.159083) (xy 96.734943 -286.109648) (xy 96.758538 -286.063334) (xy 96.789087 -286.02128)
			(xy 96.825838 -285.984523) (xy 96.867886 -285.953967) (xy 96.914196 -285.930365) (xy 96.963628 -285.914297)
			(xy 97.014965 -285.906159) (xy 97.040954 -285.905702) (xy 97.052892 -285.905956) (xy 97.067116 -285.906464)
			(xy 97.0915 -285.893002) (xy 97.237804 -285.640526) (xy 97.23755 -285.61284) (xy 97.22993 -285.600648)
			(xy 97.218194 -285.580928) (xy 97.199675 -285.538941) (xy 97.187129 -285.494799) (xy 97.180795 -285.449349)
			(xy 97.1804 -285.426404) (xy 97.180774 -285.403716) (xy 97.186973 -285.358764) (xy 97.199257 -285.315082)
			(xy 97.217395 -285.273488) (xy 97.228914 -285.253938) (xy 97.23628 -285.242) (xy 97.236534 -285.21406)
			(xy 97.089214 -284.96006) (xy 97.06483 -284.946598) (xy 97.05086 -284.946852) (xy 97.040954 -284.947106)
			(xy 97.014969 -284.946593) (xy 96.96364 -284.938457) (xy 96.914216 -284.922392) (xy 96.867913 -284.898793)
			(xy 96.825871 -284.868243) (xy 96.789126 -284.831492) (xy 96.758582 -284.789446) (xy 96.73499 -284.743139)
			(xy 96.718932 -284.693713) (xy 96.710803 -284.642383) (xy 96.710246 -284.616398) (xy 96.71062 -284.593668)
			(xy 96.716851 -284.548638) (xy 96.729209 -284.50489) (xy 96.747458 -284.463255) (xy 96.759014 -284.443678)
			(xy 96.76638 -284.43174) (xy 96.766634 -284.4038) (xy 96.619568 -284.150054) (xy 96.595184 -284.136592)
			(xy 96.58096 -284.136846) (xy 96.571054 -284.1371) (xy 96.54507 -284.136587) (xy 96.493742 -284.128451)
			(xy 96.444319 -284.112386) (xy 96.398017 -284.088789) (xy 96.355976 -284.058239) (xy 96.319231 -284.021489)
			(xy 96.288687 -283.979444) (xy 96.265096 -283.933139) (xy 96.249038 -283.883713) (xy 96.240909 -283.832384)
			(xy 96.240909 -283.780416) (xy 96.249038 -283.729087) (xy 96.265096 -283.679661) (xy 96.288687 -283.633356)
			(xy 96.319231 -283.591311) (xy 96.355976 -283.554561) (xy 96.398017 -283.524011) (xy 96.444319 -283.500414)
			(xy 96.493742 -283.484349) (xy 96.54507 -283.476213) (xy 96.571054 -283.475684) (xy 96.582992 -283.475938)
			(xy 96.597216 -283.476446) (xy 96.6216 -283.462984) (xy 96.767904 -283.210762) (xy 96.767396 -283.182822)
			(xy 96.76003 -283.170884) (xy 96.748236 -283.151149) (xy 96.72962 -283.109113) (xy 96.717007 -283.064904)
			(xy 96.71064 -283.019373) (xy 96.710246 -282.996386) (xy 96.710757 -282.970398) (xy 96.718889 -282.919063)
			(xy 96.73495 -282.869631) (xy 96.758546 -282.82332) (xy 96.789095 -282.78127) (xy 96.825846 -282.744516)
			(xy 96.867893 -282.713963) (xy 96.914201 -282.690362) (xy 96.963632 -282.674296) (xy 97.014966 -282.666159)
			(xy 97.040954 -282.665678) (xy 97.052892 -282.665932) (xy 97.067116 -282.66644) (xy 97.0915 -282.652978)
			(xy 97.237804 -282.400502) (xy 97.23755 -282.372816) (xy 97.22993 -282.360624) (xy 97.218195 -282.340904)
			(xy 97.19968 -282.298916) (xy 97.187137 -282.254775) (xy 97.180806 -282.209324) (xy 97.1804 -282.18638)
			(xy 97.180775 -282.163692) (xy 97.186978 -282.118742) (xy 97.199265 -282.075062) (xy 97.217405 -282.033469)
			(xy 97.228914 -282.013914) (xy 97.23628 -282.001976) (xy 97.236534 -281.974036) (xy 97.089468 -281.720036)
			(xy 97.065084 -281.706574) (xy 97.05086 -281.706828) (xy 97.040954 -281.707082) (xy 97.014971 -281.706569)
			(xy 96.963646 -281.698433) (xy 96.914226 -281.68237) (xy 96.867926 -281.658773) (xy 96.825888 -281.628225)
			(xy 96.789145 -281.591477) (xy 96.758603 -281.549434) (xy 96.735013 -281.503132) (xy 96.718956 -281.453709)
			(xy 96.710827 -281.402383) (xy 96.710827 -281.350417) (xy 96.718956 -281.299091) (xy 96.735013 -281.249668)
			(xy 96.758603 -281.203366) (xy 96.789145 -281.161323) (xy 96.825888 -281.124575) (xy 96.867926 -281.094027)
			(xy 96.914226 -281.07043) (xy 96.963646 -281.054367) (xy 97.014971 -281.046231) (xy 97.040954 -281.045666)
			(xy 97.052892 -281.04592) (xy 97.067116 -281.046428) (xy 97.0915 -281.032966) (xy 97.238058 -280.780744)
			(xy 97.23755 -280.752804) (xy 97.230184 -280.740612) (xy 97.218404 -280.720906) (xy 97.199805 -280.678931)
			(xy 97.18719 -280.634787) (xy 97.180803 -280.589323) (xy 97.1804 -280.566368) (xy 97.180912 -280.540383)
			(xy 97.189047 -280.489053) (xy 97.20511 -280.439627) (xy 97.228708 -280.393322) (xy 97.259259 -280.351279)
			(xy 97.29601 -280.314533) (xy 97.338056 -280.283987) (xy 97.384364 -280.260395) (xy 97.433792 -280.244337)
			(xy 97.485123 -280.236209) (xy 97.511108 -280.23566) (xy 97.522792 -280.235914) (xy 97.537016 -280.236422)
			(xy 97.5614 -280.22296) (xy 97.707958 -279.970484) (xy 97.70745 -279.942798) (xy 97.69983 -279.930606)
			(xy 97.68809 -279.910887) (xy 97.669564 -279.868901) (xy 97.65701 -279.824759) (xy 97.650668 -279.779308)
			(xy 97.6503 -279.756362) (xy 97.6503 -279.747472) (xy 97.650808 -279.733502) (xy 97.637092 -279.709118)
			(xy 96.785176 -279.21966) (xy 96.757236 -279.220168) (xy 96.745298 -279.227534) (xy 96.725578 -279.239271)
			(xy 96.683591 -279.257792) (xy 96.63945 -279.270343) (xy 96.593999 -279.276683) (xy 96.571054 -279.277064)
			(xy 96.545073 -279.276551) (xy 96.493751 -279.268415) (xy 96.444333 -279.252353) (xy 96.398036 -279.228757)
			(xy 96.356 -279.198211) (xy 96.319259 -279.161465) (xy 96.288718 -279.119425) (xy 96.26513 -279.073125)
			(xy 96.249074 -279.023705) (xy 96.240946 -278.972381) (xy 96.240946 -278.920419) (xy 96.249074 -278.869095)
			(xy 96.26513 -278.819675) (xy 96.288718 -278.773375) (xy 96.319259 -278.731335) (xy 96.356 -278.694589)
			(xy 96.398036 -278.664043) (xy 96.444333 -278.640447) (xy 96.493751 -278.624385) (xy 96.545073 -278.616249)
			(xy 96.571054 -278.615648) (xy 96.582992 -278.615902) (xy 96.597216 -278.61641) (xy 96.6216 -278.602948)
			(xy 96.767904 -278.350726) (xy 96.767396 -278.322786) (xy 96.76003 -278.310848) (xy 96.748238 -278.291113)
			(xy 96.729627 -278.249076) (xy 96.717018 -278.204866) (xy 96.710656 -278.159336) (xy 96.710246 -278.13635)
			(xy 96.710725 -278.110357) (xy 96.71885 -278.05901) (xy 96.734907 -278.009565) (xy 96.758502 -277.963242)
			(xy 96.789052 -277.92118) (xy 96.825807 -277.884415) (xy 96.86786 -277.853852) (xy 96.914177 -277.830244)
			(xy 96.963616 -277.814173) (xy 97.014961 -277.806033) (xy 97.040954 -277.805642) (xy 97.052892 -277.805896)
			(xy 97.067116 -277.806404) (xy 97.0915 -277.792942) (xy 97.237804 -277.540466) (xy 97.23755 -277.51278)
			(xy 97.22993 -277.500588) (xy 97.218191 -277.480869) (xy 97.199668 -277.438882) (xy 97.187116 -277.394741)
			(xy 97.180777 -277.34929) (xy 97.1804 -277.326344) (xy 97.180778 -277.303657) (xy 97.186985 -277.258709)
			(xy 97.199276 -277.215031) (xy 97.217419 -277.173441) (xy 97.228914 -277.153878) (xy 97.23628 -277.14194)
			(xy 97.236534 -277.114) (xy 97.089214 -276.86) (xy 97.06483 -276.846538) (xy 97.05086 -276.846792)
			(xy 97.040954 -276.847046) (xy 97.014968 -276.846533) (xy 96.963637 -276.838397) (xy 96.91421 -276.822332)
			(xy 96.867904 -276.798735) (xy 96.825859 -276.768185) (xy 96.78911 -276.731435) (xy 96.758561 -276.689389)
			(xy 96.734964 -276.643082) (xy 96.718901 -276.593655) (xy 96.710766 -276.542324) (xy 96.710246 -276.516338)
			(xy 96.710617 -276.493607) (xy 96.716843 -276.448575) (xy 96.729196 -276.404825) (xy 96.747442 -276.363186)
			(xy 96.759014 -276.343618) (xy 96.76638 -276.33168) (xy 96.766634 -276.30374) (xy 96.619568 -276.049994)
			(xy 96.595184 -276.036532) (xy 96.58096 -276.036786) (xy 96.571054 -276.03704) (xy 96.545067 -276.036527)
			(xy 96.493733 -276.02839) (xy 96.444304 -276.012323) (xy 96.397996 -275.988723) (xy 96.35595 -275.958169)
			(xy 96.319201 -275.921415) (xy 96.288653 -275.879365) (xy 96.265059 -275.833054) (xy 96.248999 -275.783622)
			(xy 96.240869 -275.732287) (xy 96.240869 -275.680313) (xy 96.248999 -275.628978) (xy 96.265059 -275.579546)
			(xy 96.288653 -275.533235) (xy 96.319201 -275.491185) (xy 96.35595 -275.454431) (xy 96.397996 -275.423877)
			(xy 96.444304 -275.400277) (xy 96.493733 -275.38421) (xy 96.545067 -275.376073) (xy 96.571054 -275.375624)
			(xy 96.582992 -275.375878) (xy 96.597216 -275.376386) (xy 96.6216 -275.362924) (xy 96.767904 -275.110702)
			(xy 96.767396 -275.082762) (xy 96.76003 -275.070824) (xy 96.748234 -275.05109) (xy 96.729612 -275.009055)
			(xy 96.716994 -274.964845) (xy 96.710621 -274.919314) (xy 96.710246 -274.896326) (xy 96.710754 -274.870336)
			(xy 96.718881 -274.818996) (xy 96.734939 -274.769559) (xy 96.758532 -274.723242) (xy 96.789081 -274.681187)
			(xy 96.825832 -274.644428) (xy 96.867881 -274.61387) (xy 96.914192 -274.590266) (xy 96.963626 -274.574197)
			(xy 97.014964 -274.566059) (xy 97.040954 -274.565618) (xy 97.052892 -274.565872) (xy 97.067116 -274.56638)
			(xy 97.0915 -274.552918) (xy 97.237804 -274.300442) (xy 97.23755 -274.272756) (xy 97.22993 -274.260564)
			(xy 97.218193 -274.240844) (xy 97.199672 -274.198857) (xy 97.187124 -274.154716) (xy 97.180788 -274.109265)
			(xy 97.1804 -274.08632) (xy 97.180772 -274.063631) (xy 97.18697 -274.018679) (xy 97.199252 -273.974996)
			(xy 97.217388 -273.9334) (xy 97.228914 -273.913854) (xy 97.23628 -273.901916) (xy 97.236534 -273.873976)
			(xy 97.089214 -273.619976) (xy 97.06483 -273.606514) (xy 97.05086 -273.606768) (xy 97.040954 -273.607022)
			(xy 97.014969 -273.606509) (xy 96.963639 -273.598373) (xy 96.914214 -273.582308) (xy 96.86791 -273.55871)
			(xy 96.825867 -273.52816) (xy 96.78912 -273.491409) (xy 96.758573 -273.449363) (xy 96.73498 -273.403057)
			(xy 96.71892 -273.35363) (xy 96.710788 -273.302299) (xy 96.710246 -273.276314) (xy 96.710619 -273.253584)
			(xy 96.716848 -273.208553) (xy 96.729204 -273.164804) (xy 96.747452 -273.123168) (xy 96.759014 -273.103594)
			(xy 96.76638 -273.091656) (xy 96.766634 -273.063716) (xy 96.619568 -272.80997) (xy 96.595184 -272.796508)
			(xy 96.58096 -272.796762) (xy 96.571054 -272.797016) (xy 96.545069 -272.796503) (xy 96.493738 -272.788367)
			(xy 96.444313 -272.772301) (xy 96.398009 -272.748702) (xy 96.355966 -272.718151) (xy 96.319219 -272.681399)
			(xy 96.288674 -272.639352) (xy 96.265081 -272.593045) (xy 96.249023 -272.543617) (xy 96.240893 -272.492286)
			(xy 96.240893 -272.440314) (xy 96.249023 -272.388983) (xy 96.265081 -272.339555) (xy 96.288674 -272.293248)
			(xy 96.319219 -272.251201) (xy 96.355966 -272.214449) (xy 96.398009 -272.183898) (xy 96.444313 -272.160299)
			(xy 96.493738 -272.144233) (xy 96.545069 -272.136097) (xy 96.571054 -272.1356) (xy 96.582992 -272.135854)
			(xy 96.597216 -272.136362) (xy 96.6216 -272.1229) (xy 96.767904 -271.870678) (xy 96.767396 -271.842738)
			(xy 96.76003 -271.8308) (xy 96.748235 -271.811066) (xy 96.729617 -271.76903) (xy 96.717002 -271.72482)
			(xy 96.710632 -271.679289) (xy 96.710246 -271.656302) (xy 96.710755 -271.630313) (xy 96.718885 -271.578976)
			(xy 96.734946 -271.529542) (xy 96.758541 -271.483229) (xy 96.78909 -271.441177) (xy 96.82584 -271.404421)
			(xy 96.867888 -271.373866) (xy 96.914198 -271.350264) (xy 96.963629 -271.334197) (xy 97.014965 -271.326059)
			(xy 97.040954 -271.325594) (xy 97.052892 -271.325848) (xy 97.067116 -271.326356) (xy 97.0915 -271.312894)
			(xy 97.237804 -271.060418) (xy 97.23755 -271.032732) (xy 97.22993 -271.02054) (xy 97.218194 -271.00082)
			(xy 97.199677 -270.958832) (xy 97.187131 -270.914691) (xy 97.180798 -270.869241) (xy 97.1804 -270.846296)
			(xy 97.180774 -270.823608) (xy 97.186975 -270.778657) (xy 97.19926 -270.734975) (xy 97.217398 -270.693382)
			(xy 97.228914 -270.67383) (xy 97.23628 -270.661892) (xy 97.236534 -270.633952) (xy 97.089214 -270.379952)
			(xy 97.06483 -270.36649) (xy 97.05086 -270.366744) (xy 97.040954 -270.366998) (xy 97.014969 -270.366485)
			(xy 96.963641 -270.358349) (xy 96.914217 -270.342283) (xy 96.867915 -270.318685) (xy 96.825874 -270.288134)
			(xy 96.789129 -270.251383) (xy 96.758586 -270.209337) (xy 96.734995 -270.163031) (xy 96.718938 -270.113604)
			(xy 96.710811 -270.062275) (xy 96.710246 -270.03629) (xy 96.710621 -270.01356) (xy 96.716853 -269.968531)
			(xy 96.729211 -269.924784) (xy 96.747462 -269.883149) (xy 96.759014 -269.86357) (xy 96.76638 -269.851632)
			(xy 96.766634 -269.823692) (xy 96.619568 -269.569946) (xy 96.595184 -269.556484) (xy 96.58096 -269.556738)
			(xy 96.571054 -269.556992) (xy 96.54507 -269.556479) (xy 96.493742 -269.548343) (xy 96.444318 -269.532277)
			(xy 96.398016 -269.508679) (xy 96.355976 -269.478128) (xy 96.319232 -269.441377) (xy 96.288689 -269.399331)
			(xy 96.265099 -269.353024) (xy 96.249043 -269.303598) (xy 96.240916 -269.252268) (xy 96.240346 -269.226284)
			(xy 96.240806 -269.201569) (xy 96.24816 -269.15269) (xy 96.262702 -269.105448) (xy 96.284108 -269.060895)
			(xy 96.311903 -269.020021) (xy 96.345468 -268.983735) (xy 96.384056 -268.952845) (xy 96.405192 -268.940026)
			(xy 96.414336 -268.934946) (xy 96.426782 -268.918436) (xy 96.449134 -268.826996) (xy 96.445832 -268.806676)
			(xy 96.440244 -268.797786) (xy 96.419109 -268.763492) (xy 96.383853 -268.691058) (xy 96.357009 -268.615103)
			(xy 96.338921 -268.536601) (xy 96.329819 -268.456558) (xy 96.329246 -268.416278) (xy 96.329735 -268.379004)
			(xy 96.337529 -268.304866) (xy 96.353029 -268.231948) (xy 96.376067 -268.161049) (xy 96.406388 -268.092947)
			(xy 96.443662 -268.028387) (xy 96.487479 -267.968077) (xy 96.53736 -267.912677) (xy 96.592758 -267.862794)
			(xy 96.653067 -267.818975) (xy 96.717626 -267.781699) (xy 96.785727 -267.751375) (xy 96.856625 -267.728336)
			(xy 96.929542 -267.712833) (xy 97.00368 -267.705036) (xy 97.040954 -267.70457) (xy 97.05481 -267.704609)
			(xy 97.082504 -267.705625) (xy 97.096326 -267.706602) (xy 97.106994 -267.707618) (xy 97.126806 -267.70076)
			(xy 97.197418 -267.635482) (xy 97.2058 -267.616432) (xy 97.2058 -267.605764) (xy 97.206311 -267.581801)
			(xy 97.213883 -267.534474) (xy 97.228758 -267.488912) (xy 97.25057 -267.446235) (xy 97.278783 -267.40749)
			(xy 97.312704 -267.373629) (xy 97.351499 -267.345485) (xy 97.394215 -267.323749) (xy 97.439804 -267.308956)
			(xy 97.487144 -267.301467) (xy 97.511108 -267.300964) (xy 97.534117 -267.301383) (xy 97.579613 -267.308294)
			(xy 97.623555 -267.321959) (xy 97.664947 -267.342067) (xy 97.70285 -267.368163) (xy 97.736405 -267.399654)
			(xy 97.76485 -267.435827) (xy 97.776538 -267.45565) (xy 97.783396 -267.467588) (xy 97.807018 -267.481304)
			(xy 98.126804 -267.481304) (xy 98.150934 -267.466572) (xy 98.157538 -267.453872) (xy 98.169884 -267.431199)
			(xy 98.20052 -267.389649) (xy 98.237236 -267.353361) (xy 98.279142 -267.323214) (xy 98.32522 -267.299939)
			(xy 98.374354 -267.284102) (xy 98.425351 -267.276086) (xy 98.476973 -267.276086) (xy 98.52797 -267.284102)
			(xy 98.577104 -267.299939) (xy 98.623182 -267.323214) (xy 98.665088 -267.353361) (xy 98.701804 -267.389649)
			(xy 98.73244 -267.431199) (xy 98.744786 -267.453872) (xy 98.75139 -267.466572) (xy 98.77552 -267.481304)
			(xy 99.095052 -267.481304) (xy 99.118674 -267.467588) (xy 99.125532 -267.45565) (xy 99.139241 -267.432638)
			(xy 99.173403 -267.391386) (xy 99.214229 -267.356716) (xy 99.260471 -267.329688) (xy 99.310714 -267.31113)
			(xy 99.363422 -267.30161) (xy 99.3902 -267.300964) (xy 99.403916 -267.300964) (xy 99.427284 -267.287502)
			(xy 99.588066 -267.010388) (xy 99.587558 -266.982702) (xy 99.579938 -266.97051) (xy 99.568198 -266.950791)
			(xy 99.549671 -266.908805) (xy 99.537116 -266.864664) (xy 99.530773 -266.819212) (xy 99.530408 -266.796266)
			(xy 99.53092 -266.770281) (xy 99.539055 -266.718952) (xy 99.555119 -266.669527) (xy 99.578717 -266.623223)
			(xy 99.609268 -266.581181) (xy 99.646019 -266.544435) (xy 99.688066 -266.513891) (xy 99.734373 -266.4903)
			(xy 99.7838 -266.474243) (xy 99.835131 -266.466116) (xy 99.861116 -266.465558) (xy 99.873054 -266.465812)
			(xy 99.887278 -266.46632) (xy 99.911662 -266.452858) (xy 100.057966 -266.200636) (xy 100.057458 -266.172696)
			(xy 100.050092 -266.160758) (xy 100.038301 -266.141023) (xy 100.01969 -266.098986) (xy 100.007082 -266.054776)
			(xy 100.000719 -266.009246) (xy 100.000308 -265.98626) (xy 100.000821 -265.960275) (xy 100.008956 -265.908947)
			(xy 100.025021 -265.859522) (xy 100.048619 -265.81322) (xy 100.07917 -265.771178) (xy 100.115921 -265.734433)
			(xy 100.157967 -265.70389) (xy 100.204274 -265.680299) (xy 100.253701 -265.664243) (xy 100.305031 -265.656116)
			(xy 100.331016 -265.655552) (xy 100.354374 -265.65596) (xy 100.400626 -265.662536) (xy 100.445496 -265.675541)
			(xy 100.488095 -265.694719) (xy 100.508054 -265.70686) (xy 100.519992 -265.71448) (xy 100.548186 -265.715242)
			(xy 101.397308 -265.227562) (xy 101.411024 -265.20267) (xy 101.410516 -265.188446) (xy 101.410262 -265.176254)
			(xy 101.410262 -265.167364) (xy 101.41077 -265.153394) (xy 101.397054 -265.12901) (xy 100.545138 -264.639552)
			(xy 100.517198 -264.64006) (xy 100.50526 -264.647426) (xy 100.48554 -264.659161) (xy 100.443552 -264.677678)
			(xy 100.399411 -264.690224) (xy 100.353961 -264.696558) (xy 100.331016 -264.696956) (xy 100.305022 -264.696474)
			(xy 100.253674 -264.688344) (xy 100.20423 -264.67228) (xy 100.157908 -264.64868) (xy 100.115848 -264.618124)
			(xy 100.079087 -264.581364) (xy 100.048528 -264.539305) (xy 100.024926 -264.492984) (xy 100.00886 -264.443541)
			(xy 100.000727 -264.392194) (xy 100.000727 -264.340206) (xy 100.00886 -264.288859) (xy 100.024926 -264.239416)
			(xy 100.048528 -264.193095) (xy 100.079087 -264.151036) (xy 100.115848 -264.114276) (xy 100.157908 -264.08372)
			(xy 100.20423 -264.06012) (xy 100.253674 -264.044056) (xy 100.305022 -264.035926) (xy 100.331016 -264.03554)
			(xy 100.354374 -264.035948) (xy 100.400626 -264.042524) (xy 100.445496 -264.055529) (xy 100.488096 -264.074705)
			(xy 100.508054 -264.086848) (xy 100.519992 -264.094468) (xy 100.54844 -264.09523) (xy 101.397308 -263.60755)
			(xy 101.411024 -263.582912) (xy 101.410516 -263.568688) (xy 101.410262 -263.556242) (xy 101.41064 -263.533555)
			(xy 101.416847 -263.488607) (xy 101.429136 -263.444928) (xy 101.447278 -263.403338) (xy 101.458776 -263.383776)
			(xy 101.466142 -263.371838) (xy 101.466396 -263.343898) (xy 101.319076 -263.089898) (xy 101.294692 -263.076436)
			(xy 101.280722 -263.07669) (xy 101.27107 -263.076944) (xy 101.245082 -263.076432) (xy 101.193745 -263.068297)
			(xy 101.144313 -263.052232) (xy 101.098003 -263.028632) (xy 101.055954 -262.998078) (xy 101.019203 -262.961323)
			(xy 100.988653 -262.919272) (xy 100.965057 -262.872959) (xy 100.948996 -262.823526) (xy 100.940866 -262.772189)
			(xy 100.940866 -262.720211) (xy 100.948996 -262.668874) (xy 100.965057 -262.619441) (xy 100.988653 -262.573128)
			(xy 101.019203 -262.531077) (xy 101.055954 -262.494322) (xy 101.098003 -262.463768) (xy 101.144313 -262.440168)
			(xy 101.193745 -262.424103) (xy 101.245082 -262.415968) (xy 101.27107 -262.415528) (xy 101.2825 -262.415782)
			(xy 101.296724 -262.41629) (xy 101.321108 -262.402828) (xy 101.467666 -262.150098) (xy 101.467158 -262.122412)
			(xy 101.459792 -262.11022) (xy 101.448063 -262.090532) (xy 101.429555 -262.048609) (xy 101.417013 -262.004531)
			(xy 101.41068 -261.959144) (xy 101.410262 -261.93623) (xy 101.410652 -261.913574) (xy 101.416871 -261.86869)
			(xy 101.429155 -261.825074) (xy 101.447276 -261.783542) (xy 101.458776 -261.764018) (xy 101.465888 -261.75208)
			(xy 101.466396 -261.72414) (xy 101.318822 -261.469886) (xy 101.294438 -261.456424) (xy 101.280468 -261.456678)
			(xy 101.27107 -261.456932) (xy 101.245082 -261.45642) (xy 101.193748 -261.448285) (xy 101.144318 -261.43222)
			(xy 101.098009 -261.408621) (xy 101.055962 -261.378069) (xy 101.019212 -261.341315) (xy 100.988663 -261.299265)
			(xy 100.965068 -261.252954) (xy 100.949008 -261.203523) (xy 100.940877 -261.152188) (xy 100.940877 -261.100212)
			(xy 100.949008 -261.048877) (xy 100.965068 -260.999446) (xy 100.988663 -260.953135) (xy 101.019212 -260.911085)
			(xy 101.055962 -260.874331) (xy 101.098009 -260.843779) (xy 101.144318 -260.82018) (xy 101.193748 -260.804115)
			(xy 101.245082 -260.79598) (xy 101.27107 -260.795516) (xy 101.300949 -260.796156) (xy 101.359734 -260.806889)
			(xy 101.38791 -260.816852) (xy 101.401372 -260.821932) (xy 101.428804 -260.816852) (xy 102.497128 -259.875782)
			(xy 102.505256 -259.847842) (xy 102.500938 -259.833364) (xy 102.494065 -259.808138) (xy 102.486667 -259.756381)
			(xy 102.486206 -259.73024) (xy 102.486655 -259.704129) (xy 102.494013 -259.652428) (xy 102.508586 -259.602281)
			(xy 102.530083 -259.554689) (xy 102.558076 -259.510604) (xy 102.592005 -259.470906) (xy 102.631192 -259.436388)
			(xy 102.674855 -259.40774) (xy 102.698296 -259.39623) (xy 102.712012 -259.38988) (xy 102.72776 -259.365242)
			(xy 102.72776 -259.195316) (xy 102.712012 -259.170678) (xy 102.698296 -259.164328) (xy 102.673305 -259.15202)
			(xy 102.627023 -259.121016) (xy 102.585927 -259.083409) (xy 102.550949 -259.040053) (xy 102.522883 -258.991933)
			(xy 102.502368 -258.940142) (xy 102.489869 -258.885856) (xy 102.48567 -258.830308) (xy 102.489867 -258.77476)
			(xy 102.502364 -258.720473) (xy 102.522877 -258.668681) (xy 102.55094 -258.62056) (xy 102.585916 -258.577202)
			(xy 102.627011 -258.539593) (xy 102.673291 -258.508588) (xy 102.698296 -258.496308) (xy 102.712012 -258.489958)
			(xy 102.72776 -258.46532) (xy 102.72776 -258.295394) (xy 102.712012 -258.270756) (xy 102.698296 -258.264406)
			(xy 102.67486 -258.25289) (xy 102.631205 -258.224237) (xy 102.592025 -258.189716) (xy 102.558102 -258.150018)
			(xy 102.530113 -258.105934) (xy 102.508618 -258.058345) (xy 102.494045 -258.008202) (xy 102.486685 -257.956505)
			(xy 102.486206 -257.930396) (xy 102.486326 -257.915279) (xy 102.488742 -257.885141) (xy 102.491032 -257.870198)
			(xy 102.493572 -257.855466) (xy 102.482142 -257.828542) (xy 101.164898 -256.922524) (xy 101.136958 -256.921)
			(xy 101.124258 -256.927604) (xy 101.100478 -256.939433) (xy 101.05008 -256.956186) (xy 100.997651 -256.964663)
			(xy 100.971096 -256.965196) (xy 100.945107 -256.964713) (xy 100.89377 -256.956581) (xy 100.844337 -256.940518)
			(xy 100.798025 -256.91692) (xy 100.755975 -256.886367) (xy 100.719222 -256.849613) (xy 100.688672 -256.807561)
			(xy 100.665076 -256.761249) (xy 100.649015 -256.711815) (xy 100.640886 -256.660477) (xy 100.640388 -256.634488)
			(xy 100.64078 -256.611573) (xy 100.647117 -256.566185) (xy 100.659668 -256.522108) (xy 100.678192 -256.480189)
			(xy 100.689918 -256.460498) (xy 100.697284 -256.44856) (xy 100.697538 -256.42062) (xy 100.55098 -256.16789)
			(xy 100.526596 -256.154428) (xy 100.512626 -256.154936) (xy 100.500942 -256.15519) (xy 100.475305 -256.154703)
			(xy 100.424647 -256.14678) (xy 100.375819 -256.131133) (xy 100.329991 -256.108137) (xy 100.288261 -256.078344)
			(xy 100.25163 -256.042466) (xy 100.220976 -256.001364) (xy 100.208588 -255.978914) (xy 100.20173 -255.966214)
			(xy 100.177854 -255.951736) (xy 99.88423 -255.951736) (xy 99.860354 -255.966214) (xy 99.853496 -255.978914)
			(xy 99.841112 -256.00137) (xy 99.810477 -256.042494) (xy 99.773854 -256.07839) (xy 99.732124 -256.108194)
			(xy 99.686289 -256.131191) (xy 99.637451 -256.146828) (xy 99.586782 -256.154729) (xy 99.561142 -256.15519)
			(xy 99.547934 -256.154936) (xy 99.533456 -256.154428) (xy 99.509072 -256.167636) (xy 99.363276 -256.419096)
			(xy 99.363784 -256.446782) (xy 99.371404 -256.458974) (xy 99.383337 -256.478795) (xy 99.402154 -256.521062)
			(xy 99.414902 -256.565538) (xy 99.421333 -256.611355) (xy 99.421696 -256.634488) (xy 99.421186 -256.660475)
			(xy 99.413056 -256.71181) (xy 99.396995 -256.76124) (xy 99.373399 -256.80755) (xy 99.342849 -256.849598)
			(xy 99.306098 -256.886349) (xy 99.26405 -256.916899) (xy 99.21774 -256.940495) (xy 99.16831 -256.956556)
			(xy 99.116975 -256.964686) (xy 99.065001 -256.964686) (xy 99.013666 -256.956556) (xy 98.964236 -256.940495)
			(xy 98.917926 -256.916899) (xy 98.875878 -256.886349) (xy 98.839127 -256.849598) (xy 98.808577 -256.80755)
			(xy 98.784981 -256.76124) (xy 98.76892 -256.71181) (xy 98.76079 -256.660475) (xy 98.76028 -256.634488)
			(xy 98.760534 -256.622804) (xy 98.761042 -256.608326) (xy 98.74758 -256.583942) (xy 97.897696 -256.095754)
			(xy 97.869756 -256.096262) (xy 97.857818 -256.104136) (xy 97.837886 -256.116245) (xy 97.795341 -256.135352)
			(xy 97.750534 -256.148292) (xy 97.704353 -256.154808) (xy 97.681034 -256.15519) (xy 97.667826 -256.154936)
			(xy 97.653602 -256.154428) (xy 97.629218 -256.16789) (xy 97.483422 -256.418842) (xy 97.48393 -256.446782)
			(xy 97.49155 -256.458974) (xy 97.503482 -256.478796) (xy 97.522296 -256.521063) (xy 97.535042 -256.565538)
			(xy 97.541472 -256.611355) (xy 97.541842 -256.634488) (xy 97.541332 -256.660475) (xy 97.533202 -256.71181)
			(xy 97.517141 -256.76124) (xy 97.493545 -256.80755) (xy 97.462995 -256.849598) (xy 97.426244 -256.886349)
			(xy 97.384196 -256.916899) (xy 97.337886 -256.940495) (xy 97.288456 -256.956556) (xy 97.237121 -256.964686)
			(xy 97.185147 -256.964686) (xy 97.133812 -256.956556) (xy 97.084382 -256.940495) (xy 97.038072 -256.916899)
			(xy 96.996024 -256.886349) (xy 96.959273 -256.849598) (xy 96.928723 -256.80755) (xy 96.905127 -256.76124)
			(xy 96.889066 -256.71181) (xy 96.880936 -256.660475) (xy 96.880426 -256.634488) (xy 96.88068 -256.622804)
			(xy 96.881188 -256.608326) (xy 96.867726 -256.583942) (xy 96.017588 -256.095754) (xy 95.989902 -256.096262)
			(xy 95.97771 -256.104136) (xy 95.957778 -256.116245) (xy 95.915233 -256.135351) (xy 95.870426 -256.148289)
			(xy 95.824245 -256.154804) (xy 95.800926 -256.15519) (xy 95.787718 -256.154936) (xy 95.773494 -256.154428)
			(xy 95.74911 -256.16789) (xy 95.588836 -256.443734) (xy 95.588836 -256.470404) (xy 95.595694 -256.482342)
			(xy 95.608443 -256.505654) (xy 95.626559 -256.555597) (xy 95.635748 -256.607924) (xy 95.636334 -256.634488)
			(xy 95.635864 -256.658481) (xy 95.62836 -256.705875) (xy 95.613534 -256.751513) (xy 95.591751 -256.794269)
			(xy 95.563549 -256.833091) (xy 95.52962 -256.867024) (xy 95.490801 -256.895231) (xy 95.448048 -256.917019)
			(xy 95.402412 -256.931851) (xy 95.355019 -256.939361) (xy 95.331026 -256.939796) (xy 95.304399 -256.939211)
			(xy 95.251955 -256.929959) (xy 95.201912 -256.911748) (xy 95.155787 -256.885132) (xy 95.114979 -256.850916)
			(xy 95.080727 -256.810139) (xy 95.066866 -256.787396) (xy 95.060008 -256.775458) (xy 95.03664 -256.761996)
			(xy 94.713806 -256.761996) (xy 94.68993 -256.776474) (xy 94.683326 -256.789174) (xy 94.670916 -256.811601)
			(xy 94.640244 -256.852665) (xy 94.603605 -256.888505) (xy 94.561875 -256.918265) (xy 94.516055 -256.941232)
			(xy 94.46724 -256.956855) (xy 94.416599 -256.964762) (xy 94.365345 -256.964762) (xy 94.314704 -256.956855)
			(xy 94.265889 -256.941232) (xy 94.220069 -256.918265) (xy 94.178339 -256.888505) (xy 94.1417 -256.852665)
			(xy 94.111028 -256.811601) (xy 94.098618 -256.789174) (xy 94.092014 -256.776474) (xy 94.068138 -256.761996)
			(xy 93.773752 -256.761996) (xy 93.749876 -256.776474) (xy 93.743272 -256.789174) (xy 93.730862 -256.811601)
			(xy 93.70019 -256.852665) (xy 93.663551 -256.888505) (xy 93.621821 -256.918265) (xy 93.576001 -256.941232)
			(xy 93.527186 -256.956855) (xy 93.476545 -256.964762) (xy 93.425291 -256.964762) (xy 93.37465 -256.956855)
			(xy 93.325835 -256.941232) (xy 93.280015 -256.918265) (xy 93.238285 -256.888505) (xy 93.201646 -256.852665)
			(xy 93.170974 -256.811601) (xy 93.158564 -256.789174) (xy 93.15196 -256.776474) (xy 93.128084 -256.761996)
			(xy 92.805504 -256.761996) (xy 92.782136 -256.775458) (xy 92.775278 -256.787396) (xy 92.762552 -256.808431)
			(xy 92.731447 -256.846501) (xy 92.69464 -256.879091) (xy 92.653084 -256.905357) (xy 92.607854 -256.924619)
			(xy 92.56012 -256.93638) (xy 92.511118 -256.940334) (xy 92.462116 -256.93638) (xy 92.414382 -256.924619)
			(xy 92.369152 -256.905357) (xy 92.327596 -256.879091) (xy 92.290789 -256.846501) (xy 92.259684 -256.808431)
			(xy 92.246958 -256.787396) (xy 92.2401 -256.775458) (xy 92.216732 -256.761996) (xy 91.893898 -256.761996)
			(xy 91.870022 -256.776474) (xy 91.863418 -256.789174) (xy 91.851008 -256.811601) (xy 91.820336 -256.852665)
			(xy 91.783697 -256.888505) (xy 91.741967 -256.918265) (xy 91.696147 -256.941232) (xy 91.647332 -256.956855)
			(xy 91.596691 -256.964762) (xy 91.545437 -256.964762) (xy 91.494796 -256.956855) (xy 91.445981 -256.941232)
			(xy 91.400161 -256.918265) (xy 91.358431 -256.888505) (xy 91.321792 -256.852665) (xy 91.29112 -256.811601)
			(xy 91.27871 -256.789174) (xy 91.272106 -256.776474) (xy 91.24823 -256.761996) (xy 90.953844 -256.761996)
			(xy 90.929968 -256.776474) (xy 90.923364 -256.789174) (xy 90.910954 -256.811601) (xy 90.880282 -256.852665)
			(xy 90.843643 -256.888505) (xy 90.801913 -256.918265) (xy 90.756093 -256.941232) (xy 90.707278 -256.956855)
			(xy 90.656637 -256.964762) (xy 90.605383 -256.964762) (xy 90.554742 -256.956855) (xy 90.505927 -256.941232)
			(xy 90.460107 -256.918265) (xy 90.418377 -256.888505) (xy 90.381738 -256.852665) (xy 90.351066 -256.811601)
			(xy 90.338656 -256.789174) (xy 90.332052 -256.776474) (xy 90.308176 -256.761996) (xy 90.01379 -256.761996)
			(xy 89.989914 -256.776474) (xy 89.98331 -256.789174) (xy 89.9709 -256.811601) (xy 89.940228 -256.852665)
			(xy 89.903589 -256.888505) (xy 89.861859 -256.918265) (xy 89.816039 -256.941232) (xy 89.767224 -256.956855)
			(xy 89.716583 -256.964762) (xy 89.665329 -256.964762) (xy 89.614688 -256.956855) (xy 89.565873 -256.941232)
			(xy 89.520053 -256.918265) (xy 89.478323 -256.888505) (xy 89.441684 -256.852665) (xy 89.411012 -256.811601)
			(xy 89.398602 -256.789174) (xy 89.391998 -256.776474) (xy 89.368122 -256.761996) (xy 88.942672 -256.761996)
			(xy 88.932707 -256.761517) (xy 88.914273 -256.753938) (xy 88.906858 -256.747264) (xy 88.321896 -256.162302)
			(xy 88.302338 -256.154682) (xy 88.291924 -256.154936) (xy 88.281002 -256.15519) (xy 88.255013 -256.154707)
			(xy 88.203675 -256.146576) (xy 88.154242 -256.130514) (xy 88.10793 -256.106916) (xy 88.065879 -256.076363)
			(xy 88.029126 -256.039609) (xy 87.998576 -255.997557) (xy 87.97498 -255.951243) (xy 87.95892 -255.901809)
			(xy 87.950792 -255.850471) (xy 87.950294 -255.824482) (xy 87.950548 -255.81356) (xy 87.950802 -255.803146)
			(xy 87.943182 -255.783588) (xy 87.39124 -255.231646) (xy 87.384544 -255.224241) (xy 87.376939 -255.205804)
			(xy 87.376508 -255.195832) (xy 87.376508 -227.29317) (xy 87.37608 -227.283102) (xy 87.368359 -227.264505)
			(xy 87.361522 -227.257102) (xy 86.908894 -226.804474) (xy 86.901499 -226.797621) (xy 86.8829 -226.789877)
			(xy 86.872826 -226.789488) (xy 86.725252 -226.789488) (xy 86.701122 -226.80422) (xy 86.694518 -226.81692)
			(xy 86.6822 -226.839594) (xy 86.651614 -226.881151) (xy 86.614941 -226.917449) (xy 86.573073 -226.947607)
			(xy 86.527026 -226.97089) (xy 86.477919 -226.986734) (xy 86.426947 -226.994754) (xy 86.375349 -226.994754)
			(xy 86.324377 -226.986734) (xy 86.27527 -226.97089) (xy 86.229223 -226.947607) (xy 86.187355 -226.917449)
			(xy 86.150682 -226.881151) (xy 86.120096 -226.839594) (xy 86.107778 -226.81692) (xy 86.101174 -226.80422)
			(xy 86.077044 -226.789488) (xy 85.785198 -226.789488) (xy 85.761068 -226.80422) (xy 85.754464 -226.81692)
			(xy 85.742146 -226.839594) (xy 85.71156 -226.881151) (xy 85.674887 -226.917449) (xy 85.633019 -226.947607)
			(xy 85.586972 -226.97089) (xy 85.537865 -226.986734) (xy 85.486893 -226.994754) (xy 85.435295 -226.994754)
			(xy 85.384323 -226.986734) (xy 85.335216 -226.97089) (xy 85.289169 -226.947607) (xy 85.247301 -226.917449)
			(xy 85.210628 -226.881151) (xy 85.180042 -226.839594) (xy 85.167724 -226.81692) (xy 85.16112 -226.80422)
			(xy 85.13699 -226.789488) (xy 84.845144 -226.789488) (xy 84.821014 -226.80422) (xy 84.81441 -226.81692)
			(xy 84.802092 -226.839594) (xy 84.771506 -226.881151) (xy 84.734833 -226.917449) (xy 84.692965 -226.947607)
			(xy 84.646918 -226.97089) (xy 84.597811 -226.986734) (xy 84.546839 -226.994754) (xy 84.495241 -226.994754)
			(xy 84.444269 -226.986734) (xy 84.395162 -226.97089) (xy 84.349115 -226.947607) (xy 84.307247 -226.917449)
			(xy 84.270574 -226.881151) (xy 84.239988 -226.839594) (xy 84.22767 -226.81692) (xy 84.221066 -226.80422)
			(xy 84.196936 -226.789488) (xy 83.90509 -226.789488) (xy 83.88096 -226.80422) (xy 83.874356 -226.81692)
			(xy 83.862038 -226.839594) (xy 83.831452 -226.881151) (xy 83.794779 -226.917449) (xy 83.752911 -226.947607)
			(xy 83.706864 -226.97089) (xy 83.657757 -226.986734) (xy 83.606785 -226.994754) (xy 83.555187 -226.994754)
			(xy 83.504215 -226.986734) (xy 83.455108 -226.97089) (xy 83.409061 -226.947607) (xy 83.367193 -226.917449)
			(xy 83.33052 -226.881151) (xy 83.299934 -226.839594) (xy 83.287616 -226.81692) (xy 83.281012 -226.80422)
			(xy 83.256882 -226.789488) (xy 82.965036 -226.789488) (xy 82.940906 -226.80422) (xy 82.934302 -226.81692)
			(xy 82.921984 -226.839594) (xy 82.891398 -226.881151) (xy 82.854725 -226.917449) (xy 82.812857 -226.947607)
			(xy 82.76681 -226.97089) (xy 82.717703 -226.986734) (xy 82.666731 -226.994754) (xy 82.615133 -226.994754)
			(xy 82.564161 -226.986734) (xy 82.515054 -226.97089) (xy 82.469007 -226.947607) (xy 82.427139 -226.917449)
			(xy 82.390466 -226.881151) (xy 82.35988 -226.839594) (xy 82.347562 -226.81692) (xy 82.340958 -226.80422)
			(xy 82.316828 -226.789488) (xy 82.025236 -226.789488) (xy 82.001106 -226.80422) (xy 81.994502 -226.81692)
			(xy 81.982184 -226.839594) (xy 81.951598 -226.881151) (xy 81.914925 -226.917449) (xy 81.873057 -226.947607)
			(xy 81.82701 -226.97089) (xy 81.777903 -226.986734) (xy 81.726931 -226.994754) (xy 81.675333 -226.994754)
			(xy 81.624361 -226.986734) (xy 81.575254 -226.97089) (xy 81.529207 -226.947607) (xy 81.487339 -226.917449)
			(xy 81.450666 -226.881151) (xy 81.42008 -226.839594) (xy 81.407762 -226.81692) (xy 81.401158 -226.80422)
			(xy 81.377028 -226.789488) (xy 81.085182 -226.789488) (xy 81.061052 -226.80422) (xy 81.054448 -226.81692)
			(xy 81.04213 -226.839594) (xy 81.011544 -226.881151) (xy 80.974871 -226.917449) (xy 80.933003 -226.947607)
			(xy 80.886956 -226.97089) (xy 80.837849 -226.986734) (xy 80.786877 -226.994754) (xy 80.735279 -226.994754)
			(xy 80.684307 -226.986734) (xy 80.6352 -226.97089) (xy 80.589153 -226.947607) (xy 80.547285 -226.917449)
			(xy 80.510612 -226.881151) (xy 80.480026 -226.839594) (xy 80.467708 -226.81692) (xy 80.461104 -226.80422)
			(xy 80.436974 -226.789488) (xy 80.145128 -226.789488) (xy 80.120998 -226.80422) (xy 80.114394 -226.81692)
			(xy 80.102076 -226.839592) (xy 80.071489 -226.881145) (xy 80.034815 -226.917437) (xy 79.992946 -226.947588)
			(xy 79.946898 -226.970863) (xy 79.897792 -226.986698) (xy 79.846822 -226.994706) (xy 79.821024 -226.995228)
			(xy 79.79393 -226.994663) (xy 79.740473 -226.98579) (xy 79.689175 -226.968326) (xy 79.641408 -226.942738)
			(xy 79.619602 -226.926648) (xy 79.612763 -226.921864) (xy 79.596954 -226.916542) (xy 79.588614 -226.916234)
			(xy 77.233526 -226.916234) (xy 77.225181 -226.916523) (xy 77.209362 -226.921836) (xy 77.202538 -226.926648)
			(xy 77.180732 -226.942739) (xy 77.132969 -226.968334) (xy 77.08167 -226.985794) (xy 77.02821 -226.994653)
			(xy 77.001116 -226.995228) (xy 76.974022 -226.994663) (xy 76.920565 -226.985788) (xy 76.869269 -226.968324)
			(xy 76.821502 -226.942735) (xy 76.799694 -226.926648) (xy 76.792854 -226.921865) (xy 76.777046 -226.916546)
			(xy 76.768706 -226.916234) (xy 23.761954 -226.916234) (xy 23.751888 -226.916666) (xy 23.733299 -226.924396)
			(xy 23.725886 -226.93122) (xy 23.423372 -227.233734) (xy 23.416523 -227.241131) (xy 23.40879 -227.25973)
			(xy 23.408386 -227.269802) (xy 23.408386 -243.86032) (xy 23.408633 -243.867501) (xy 23.41263 -243.881297)
			(xy 23.41626 -243.887498) (xy 23.429886 -243.909785) (xy 23.451412 -243.957382) (xy 23.466021 -244.007535)
			(xy 23.473424 -244.059246) (xy 23.473918 -244.085364) (xy 23.47347 -244.111487) (xy 23.466098 -244.16321)
			(xy 23.451484 -244.21337) (xy 23.42992 -244.260959) (xy 23.41626 -244.28323) (xy 23.412622 -244.289428)
			(xy 23.408617 -244.303225) (xy 23.408386 -244.310408) (xy 23.408386 -258.880356) (xy 67.312036 -258.880356)
			(xy 67.316066 -258.738021) (xy 67.328141 -258.596141) (xy 67.348224 -258.455173) (xy 67.376251 -258.315566)
			(xy 67.412131 -258.177768) (xy 67.455749 -258.042221) (xy 67.506966 -257.909359) (xy 67.565617 -257.779607)
			(xy 67.631515 -257.653381) (xy 67.704449 -257.531085) (xy 67.784186 -257.413112) (xy 67.870468 -257.299839)
			(xy 67.963021 -257.191628) (xy 68.061548 -257.088827) (xy 68.165733 -256.991765) (xy 68.275242 -256.900753)
			(xy 68.389725 -256.816081) (xy 68.508815 -256.738023) (xy 68.63213 -256.666827) (xy 68.759276 -256.602721)
			(xy 68.889845 -256.545912) (xy 69.023419 -256.49658) (xy 69.15957 -256.454884) (xy 69.297861 -256.420958)
			(xy 69.437851 -256.39491) (xy 69.57909 -256.376824) (xy 69.721126 -256.366757) (xy 69.863504 -256.364742)
			(xy 70.005768 -256.370785) (xy 70.147462 -256.384867) (xy 70.288132 -256.406943) (xy 70.427329 -256.436943)
			(xy 70.564605 -256.474769) (xy 70.699521 -256.520301) (xy 70.831645 -256.573392) (xy 70.960554 -256.633874)
			(xy 71.085835 -256.701552) (xy 71.207086 -256.776209) (xy 71.323919 -256.857607) (xy 71.43596 -256.945484)
			(xy 71.54285 -257.039559) (xy 71.644247 -257.139531) (xy 71.739825 -257.245079) (xy 71.829279 -257.355865)
			(xy 71.912321 -257.471534) (xy 71.988687 -257.591717) (xy 72.058131 -257.716027) (xy 72.120431 -257.844068)
			(xy 72.175387 -257.975427) (xy 72.222824 -258.109686) (xy 72.262588 -258.246413) (xy 72.294554 -258.385171)
			(xy 72.318619 -258.525515) (xy 72.334705 -258.666996) (xy 72.34276 -258.80916) (xy 72.343264 -258.880356)
			(xy 72.34276 -258.951552) (xy 72.334705 -259.093716) (xy 72.318619 -259.235197) (xy 72.294554 -259.375541)
			(xy 72.262588 -259.514299) (xy 72.222824 -259.651026) (xy 72.175387 -259.785285) (xy 72.120431 -259.916644)
			(xy 72.058131 -260.044685) (xy 71.988687 -260.168995) (xy 71.912321 -260.289178) (xy 71.829279 -260.404847)
			(xy 71.739825 -260.515633) (xy 71.644247 -260.621181) (xy 71.54285 -260.721153) (xy 71.43596 -260.815228)
			(xy 71.323919 -260.903105) (xy 71.207086 -260.984503) (xy 71.085835 -261.05916) (xy 70.960554 -261.126838)
			(xy 70.831645 -261.18732) (xy 70.699521 -261.240411) (xy 70.564605 -261.285943) (xy 70.427329 -261.323769)
			(xy 70.288132 -261.353769) (xy 70.147462 -261.375845) (xy 70.005768 -261.389927) (xy 69.863504 -261.39597)
			(xy 69.721126 -261.393955) (xy 69.57909 -261.383888) (xy 69.437851 -261.365802) (xy 69.297861 -261.339754)
			(xy 69.15957 -261.305828) (xy 69.023419 -261.264132) (xy 68.889845 -261.2148) (xy 68.759276 -261.157991)
			(xy 68.63213 -261.093885) (xy 68.508815 -261.022689) (xy 68.389725 -260.944631) (xy 68.275242 -260.859959)
			(xy 68.165733 -260.768947) (xy 68.061548 -260.671885) (xy 67.963021 -260.569084) (xy 67.870468 -260.460873)
			(xy 67.784186 -260.3476) (xy 67.704449 -260.229627) (xy 67.631515 -260.107331) (xy 67.565617 -259.981105)
			(xy 67.506966 -259.851353) (xy 67.455749 -259.718491) (xy 67.412131 -259.582944) (xy 67.376251 -259.445146)
			(xy 67.348224 -259.305539) (xy 67.328141 -259.164571) (xy 67.316066 -259.022691) (xy 67.312036 -258.880356)
			(xy 23.408386 -258.880356) (xy 23.408386 -334.814926) (xy 23.408813 -334.824994) (xy 23.416533 -334.843593)
			(xy 23.423372 -334.850994) (xy 23.790656 -335.218278) (xy 23.798057 -335.225118) (xy 23.816655 -335.232835)
			(xy 23.826724 -335.233264)
		)
		(stroke
			(width 0)
			(type solid)
		)
		(fill yes)
		(layer "In8.Cu")
		(net "PVDDIO_P1")
	)
	(gr_poly
		(pts
			(xy 19.971258 -195.376546) (xy 19.980677 -195.3761) (xy 19.998256 -195.369319) (xy 20.005548 -195.363338)
			(xy 20.035661 -195.336615) (xy 20.100566 -195.288972) (xy 20.170128 -195.248431) (xy 20.243574 -195.215442)
			(xy 20.320086 -195.190375) (xy 20.398813 -195.173506) (xy 20.478879 -195.165025) (xy 20.559393 -195.165025)
			(xy 20.639459 -195.173506) (xy 20.718186 -195.190375) (xy 20.794698 -195.215442) (xy 20.868144 -195.248431)
			(xy 20.937706 -195.288972) (xy 21.002611 -195.336615) (xy 21.032724 -195.363338) (xy 21.039948 -195.369431)
			(xy 21.057569 -195.376226) (xy 21.067014 -195.376546) (xy 22.125432 -195.376546) (xy 22.135421 -195.376152)
			(xy 22.153885 -195.368528) (xy 22.167993 -195.354387) (xy 22.172168 -195.345304) (xy 22.187424 -195.310196)
			(xy 22.224088 -195.242995) (xy 22.267407 -195.179877) (xy 22.316929 -195.121501) (xy 22.37214 -195.068472)
			(xy 22.432465 -195.021342) (xy 22.497277 -194.980602) (xy 22.565901 -194.946675) (xy 22.637624 -194.919914)
			(xy 22.711699 -194.900598) (xy 22.787357 -194.888927) (xy 22.86381 -194.885024) (xy 22.940263 -194.888927)
			(xy 23.015921 -194.900598) (xy 23.089996 -194.919914) (xy 23.161719 -194.946675) (xy 23.230343 -194.980602)
			(xy 23.295155 -195.021342) (xy 23.35548 -195.068472) (xy 23.410691 -195.121501) (xy 23.460213 -195.179877)
			(xy 23.503532 -195.242995) (xy 23.540196 -195.310196) (xy 23.555452 -195.345304) (xy 23.559749 -195.354298)
			(xy 23.573854 -195.368353) (xy 23.592235 -195.376014) (xy 23.602188 -195.376546) (xy 27.515312 -195.376546)
			(xy 27.524735 -195.376108) (xy 27.542324 -195.369338) (xy 27.549602 -195.363338) (xy 27.579715 -195.336615)
			(xy 27.64462 -195.288972) (xy 27.714182 -195.248431) (xy 27.787628 -195.215442) (xy 27.86414 -195.190375)
			(xy 27.942867 -195.173506) (xy 28.022933 -195.165025) (xy 28.103447 -195.165025) (xy 28.183513 -195.173506)
			(xy 28.26224 -195.190375) (xy 28.338752 -195.215442) (xy 28.412198 -195.248431) (xy 28.48176 -195.288972)
			(xy 28.546665 -195.336615) (xy 28.576778 -195.363338) (xy 28.584005 -195.369423) (xy 28.601626 -195.376198)
			(xy 28.611068 -195.376546) (xy 29.669486 -195.376546) (xy 29.679469 -195.376143) (xy 29.697916 -195.368507)
			(xy 29.712008 -195.354365) (xy 29.716222 -195.345304) (xy 29.731478 -195.310196) (xy 29.768142 -195.242995)
			(xy 29.811461 -195.179877) (xy 29.860983 -195.121501) (xy 29.916194 -195.068472) (xy 29.976519 -195.021342)
			(xy 30.041331 -194.980602) (xy 30.109955 -194.946675) (xy 30.181678 -194.919914) (xy 30.255753 -194.900598)
			(xy 30.331411 -194.888927) (xy 30.407864 -194.885024) (xy 30.484317 -194.888927) (xy 30.559975 -194.900598)
			(xy 30.63405 -194.919914) (xy 30.705773 -194.946675) (xy 30.774397 -194.980602) (xy 30.839209 -195.021342)
			(xy 30.899534 -195.068472) (xy 30.954745 -195.121501) (xy 31.004267 -195.179877) (xy 31.047586 -195.242995)
			(xy 31.08425 -195.310196) (xy 31.099506 -195.345304) (xy 31.1038 -195.354303) (xy 31.117903 -195.368371)
			(xy 31.136285 -195.376047) (xy 31.146242 -195.376546) (xy 35.049714 -195.376546) (xy 35.060134 -195.376033)
			(xy 35.079265 -195.367764) (xy 35.086798 -195.360544) (xy 35.113781 -195.33274) (xy 35.172485 -195.282167)
			(xy 35.236014 -195.237808) (xy 35.303715 -195.20012) (xy 35.374889 -195.169493) (xy 35.448802 -195.146242)
			(xy 35.524692 -195.130607) (xy 35.601776 -195.122749) (xy 35.67926 -195.122749) (xy 35.756344 -195.130607)
			(xy 35.832234 -195.146242) (xy 35.906147 -195.169493) (xy 35.977321 -195.20012) (xy 36.045022 -195.237808)
			(xy 36.108551 -195.282167) (xy 36.167255 -195.33274) (xy 36.194238 -195.360544) (xy 36.201741 -195.367803)
			(xy 36.220893 -195.376053) (xy 36.231322 -195.376546) (xy 37.213286 -195.376546) (xy 37.223269 -195.376143)
			(xy 37.241716 -195.368507) (xy 37.255808 -195.354365) (xy 37.260022 -195.345304) (xy 37.275278 -195.310196)
			(xy 37.311942 -195.242995) (xy 37.355261 -195.179877) (xy 37.404783 -195.121501) (xy 37.459994 -195.068472)
			(xy 37.520319 -195.021342) (xy 37.585131 -194.980602) (xy 37.653755 -194.946675) (xy 37.725478 -194.919914)
			(xy 37.799553 -194.900598) (xy 37.875211 -194.888927) (xy 37.951664 -194.885024) (xy 38.028117 -194.888927)
			(xy 38.103775 -194.900598) (xy 38.17785 -194.919914) (xy 38.249573 -194.946675) (xy 38.318197 -194.980602)
			(xy 38.383009 -195.021342) (xy 38.443334 -195.068472) (xy 38.498545 -195.121501) (xy 38.548067 -195.179877)
			(xy 38.591386 -195.242995) (xy 38.62805 -195.310196) (xy 38.643306 -195.345304) (xy 38.6476 -195.354303)
			(xy 38.661703 -195.368371) (xy 38.680085 -195.376047) (xy 38.690042 -195.376546) (xy 40.502586 -195.376546)
			(xy 40.512599 -195.376061) (xy 40.531103 -195.368406) (xy 40.545272 -195.354254) (xy 40.552949 -195.335758)
			(xy 40.553386 -195.325746) (xy 40.553386 -187.090304) (xy 40.553185 -187.083865) (xy 40.549985 -187.071392)
			(xy 40.547036 -187.065666) (xy 40.52714 -187.028904) (xy 40.492889 -186.952646) (xy 40.465182 -186.873774)
			(xy 40.444216 -186.792849) (xy 40.430139 -186.710446) (xy 40.423053 -186.62715) (xy 40.422576 -186.585352)
			(xy 40.423029 -186.543553) (xy 40.430111 -186.460254) (xy 40.444184 -186.377848) (xy 40.465151 -186.296921)
			(xy 40.492862 -186.218048) (xy 40.527119 -186.14179) (xy 40.547036 -186.105038) (xy 40.549997 -186.099315)
			(xy 40.553218 -186.086842) (xy 40.553386 -186.0804) (xy 40.553386 -180.71592) (xy 40.554005 -180.690966)
			(xy 40.563755 -180.64202) (xy 40.582866 -180.595917) (xy 40.610602 -180.554426) (xy 40.627808 -180.536342)
			(xy 44.933108 -176.231042) (xy 44.939944 -176.22364) (xy 44.947657 -176.205042) (xy 44.948094 -176.194974)
			(xy 44.948094 -173.55185) (xy 44.947661 -173.541784) (xy 44.939934 -173.523193) (xy 44.933108 -173.515782)
			(xy 44.085256 -172.66793) (xy 44.067998 -172.649888) (xy 44.040245 -172.608394) (xy 44.021137 -172.562276)
			(xy 44.01141 -172.513312) (xy 44.010834 -172.488352) (xy 44.010834 -169.327576) (xy 44.010463 -169.318427)
			(xy 44.004052 -169.301291) (xy 43.992024 -169.287505) (xy 43.975914 -169.278831) (xy 43.966892 -169.277284)
			(xy 43.939781 -169.27316) (xy 43.887039 -169.258146) (xy 43.836991 -169.235733) (xy 43.79067 -169.206383)
			(xy 43.749029 -169.170701) (xy 43.712928 -169.129423) (xy 43.683111 -169.083401) (xy 43.660193 -169.033582)
			(xy 43.644647 -168.980995) (xy 43.636792 -168.926723) (xy 43.636792 -168.871886) (xy 43.644645 -168.817614)
			(xy 43.66019 -168.765026) (xy 43.683107 -168.715207) (xy 43.712923 -168.669183) (xy 43.749023 -168.627905)
			(xy 43.790663 -168.592222) (xy 43.836984 -168.562871) (xy 43.887031 -168.540457) (xy 43.939773 -168.525442)
			(xy 43.966892 -168.52138) (xy 43.975895 -168.519765) (xy 43.991986 -168.511094) (xy 44.004014 -168.497332)
			(xy 44.010453 -168.480226) (xy 44.010834 -168.471088) (xy 44.010834 -156.714952) (xy 44.01141 -156.689994)
			(xy 44.021158 -156.641038) (xy 44.04027 -156.594925) (xy 44.068011 -156.553426) (xy 44.085256 -156.535374)
			(xy 47.389796 -153.230834) (xy 47.407839 -153.21358) (xy 47.449335 -153.185833) (xy 47.495453 -153.166731)
			(xy 47.544415 -153.15701) (xy 47.569374 -153.156412) (xy 50.594768 -153.156412) (xy 50.621692 -153.1366)
			(xy 50.626518 -153.120344) (xy 50.634848 -153.094616) (xy 50.657756 -153.04563) (xy 50.687352 -153.00037)
			(xy 50.723044 -152.959744) (xy 50.764116 -152.924567) (xy 50.809744 -152.895542) (xy 50.859015 -152.873254)
			(xy 50.910939 -152.858147) (xy 50.964477 -152.850526) (xy 50.991516 -152.850088) (xy 51.020432 -152.850623)
			(xy 51.077602 -152.859352) (xy 51.132801 -152.876607) (xy 51.184763 -152.901994) (xy 51.2323 -152.934931)
			(xy 51.274323 -152.974664) (xy 51.292506 -152.997154) (xy 51.300095 -153.005988) (xy 51.321004 -153.01619)
			(xy 51.332638 -153.016712) (xy 51.412394 -153.016712) (xy 51.424015 -153.016137) (xy 51.444907 -153.005949)
			(xy 51.452526 -152.997154) (xy 51.470714 -152.974665) (xy 51.512728 -152.934918) (xy 51.560261 -152.901969)
			(xy 51.612223 -152.876573) (xy 51.667424 -152.859313) (xy 51.724598 -152.850584) (xy 51.753516 -152.850088)
			(xy 51.783855 -152.850675) (xy 51.843767 -152.860285) (xy 51.901402 -152.879259) (xy 51.955306 -152.907119)
			(xy 52.004119 -152.943161) (xy 52.025804 -152.964388) (xy 52.034694 -152.973532) (xy 52.059078 -152.981152)
			(xy 52.167536 -152.96007) (xy 52.187348 -152.943814) (xy 52.192174 -152.93213) (xy 52.208306 -152.89462)
			(xy 52.247466 -152.822966) (xy 52.294058 -152.755907) (xy 52.34755 -152.694211) (xy 52.407329 -152.638584)
			(xy 52.472709 -152.589664) (xy 52.542943 -152.548011) (xy 52.617226 -152.514101) (xy 52.694707 -152.488324)
			(xy 52.774499 -152.470974) (xy 52.855688 -152.462249) (xy 52.896516 -152.461722) (xy 52.933692 -152.462183)
			(xy 53.00769 -152.469445) (xy 53.08063 -152.483871) (xy 53.151821 -152.505322) (xy 53.220588 -152.533596)
			(xy 53.25364 -152.550622) (xy 53.264996 -152.555931) (xy 53.290036 -152.555931) (xy 53.301392 -152.550622)
			(xy 53.334441 -152.533589) (xy 53.403203 -152.505296) (xy 53.474394 -152.483835) (xy 53.547337 -152.469411)
			(xy 53.621338 -152.46216) (xy 53.658516 -152.461722) (xy 53.697315 -152.462204) (xy 53.774511 -152.470086)
			(xy 53.850508 -152.485768) (xy 53.924519 -152.509086) (xy 53.995779 -152.5398) (xy 54.063552 -152.577593)
			(xy 54.127136 -152.622073) (xy 54.185874 -152.67278) (xy 54.239158 -152.729191) (xy 54.286439 -152.790721)
			(xy 54.327225 -152.856735) (xy 54.361097 -152.92655) (xy 54.387703 -152.999444) (xy 54.406769 -153.074663)
			(xy 54.412896 -153.112978) (xy 54.41569 -153.131774) (xy 54.444138 -153.156412) (xy 55.15229 -153.156412)
			(xy 55.17896 -153.137108) (xy 55.18404 -153.121614) (xy 55.196997 -153.08399) (xy 55.22967 -153.011428)
			(xy 55.269724 -152.942665) (xy 55.316723 -152.878448) (xy 55.370156 -152.819477) (xy 55.429441 -152.766392)
			(xy 55.493934 -152.719772) (xy 55.562932 -152.680125) (xy 55.635686 -152.64788) (xy 55.711402 -152.62339)
			(xy 55.789257 -152.60692) (xy 55.868405 -152.598651) (xy 55.908194 -152.59812) (xy 55.945371 -152.59858)
			(xy 56.019369 -152.60584) (xy 56.09231 -152.620264) (xy 56.163502 -152.641713) (xy 56.232271 -152.669986)
			(xy 56.265318 -152.68702) (xy 56.276674 -152.692329) (xy 56.301714 -152.692329) (xy 56.31307 -152.68702)
			(xy 56.346119 -152.669986) (xy 56.414881 -152.641691) (xy 56.486072 -152.620228) (xy 56.559015 -152.605802)
			(xy 56.633016 -152.598549) (xy 56.670194 -152.59812) (xy 56.70998 -152.598639) (xy 56.789119 -152.606934)
			(xy 56.866964 -152.623423) (xy 56.942668 -152.647928) (xy 57.01541 -152.680182) (xy 57.084399 -152.719835)
			(xy 57.148884 -152.766455) (xy 57.208164 -152.819536) (xy 57.261595 -152.878501) (xy 57.308597 -152.942708)
			(xy 57.348658 -153.01146) (xy 57.381343 -153.084009) (xy 57.394348 -153.121614) (xy 57.399428 -153.137108)
			(xy 57.426098 -153.156412) (xy 57.989978 -153.156412) (xy 57.994042 -153.155396) (xy 58.008131 -153.152332)
			(xy 58.036775 -153.14902) (xy 58.051192 -153.148792) (xy 58.940954 -153.148792) (xy 58.965909 -153.149409)
			(xy 59.014857 -153.159155) (xy 59.060964 -153.178262) (xy 59.102458 -153.205997) (xy 59.120532 -153.223214)
			(xy 60.306458 -154.40914) (xy 60.321063 -154.424358) (xy 60.345521 -154.458718) (xy 60.363969 -154.496645)
			(xy 60.375898 -154.537099) (xy 60.378848 -154.557984) (xy 60.380094 -154.565979) (xy 60.386952 -154.580624)
			(xy 60.39231 -154.586686) (xy 60.411768 -154.608044) (xy 60.444678 -154.655531) (xy 60.470059 -154.707433)
			(xy 60.487331 -154.762567) (xy 60.4961 -154.819673) (xy 60.496704 -154.84856) (xy 60.496197 -154.877158)
			(xy 60.487667 -154.933713) (xy 60.470792 -154.988362) (xy 60.445951 -155.03988) (xy 60.413699 -155.087115)
			(xy 60.394596 -155.108402) (xy 60.388316 -155.115694) (xy 60.381269 -155.133584) (xy 60.38088 -155.1432)
			(xy 60.38088 -161.494978) (xy 60.381317 -161.505042) (xy 60.389049 -161.523628) (xy 60.395866 -161.531046)
			(xy 60.791344 -161.926524) (xy 60.798741 -161.933372) (xy 60.81734 -161.941102) (xy 60.827412 -161.94151)
			(xy 86.858094 -161.94151) (xy 86.863174 -161.940494) (xy 86.906775 -161.932248) (xy 86.995079 -161.923465)
			(xy 87.03945 -161.922968) (xy 87.083819 -161.923496) (xy 87.172121 -161.932275) (xy 87.215726 -161.940494)
			(xy 87.220806 -161.94151) (xy 87.493094 -161.94151) (xy 87.498174 -161.940494) (xy 87.541775 -161.932248)
			(xy 87.630079 -161.923465) (xy 87.67445 -161.922968) (xy 87.718819 -161.923496) (xy 87.807121 -161.932275)
			(xy 87.850726 -161.940494) (xy 87.855806 -161.94151) (xy 88.128094 -161.94151) (xy 88.133174 -161.940494)
			(xy 88.176775 -161.932248) (xy 88.265079 -161.923465) (xy 88.30945 -161.922968) (xy 88.353819 -161.923496)
			(xy 88.442121 -161.932275) (xy 88.485726 -161.940494) (xy 88.490806 -161.94151) (xy 88.763094 -161.94151)
			(xy 88.768174 -161.940494) (xy 88.811775 -161.932248) (xy 88.900079 -161.923465) (xy 88.94445 -161.922968)
			(xy 88.988819 -161.923496) (xy 89.077121 -161.932275) (xy 89.120726 -161.940494) (xy 89.125806 -161.94151)
			(xy 89.398094 -161.94151) (xy 89.403174 -161.940494) (xy 89.446775 -161.932248) (xy 89.535079 -161.923465)
			(xy 89.57945 -161.922968) (xy 89.623819 -161.923496) (xy 89.712121 -161.932275) (xy 89.755726 -161.940494)
			(xy 89.760806 -161.94151) (xy 90.117168 -161.94151) (xy 90.12047 -161.941002) (xy 90.150173 -161.937273)
			(xy 90.209914 -161.933329) (xy 90.23985 -161.933128) (xy 90.269786 -161.933336) (xy 90.329526 -161.937277)
			(xy 90.35923 -161.941002) (xy 90.362532 -161.94151) (xy 94.747588 -161.94151) (xy 94.757659 -161.94109)
			(xy 94.776268 -161.933379) (xy 94.783656 -161.926524) (xy 104.053132 -152.657048) (xy 104.071173 -152.639788)
			(xy 104.112667 -152.61203) (xy 104.158785 -152.592915) (xy 104.207749 -152.583181) (xy 104.23271 -152.582626)
			(xy 115.345972 -152.582626) (xy 115.37442 -152.557734) (xy 115.37696 -152.538684) (xy 115.383801 -152.49242)
			(xy 115.405943 -152.401552) (xy 115.421156 -152.357328) (xy 115.423799 -152.348892) (xy 115.423785 -152.331226)
			(xy 115.421156 -152.322784) (xy 115.40859 -152.286613) (xy 115.389 -152.212582) (xy 115.375855 -152.137139)
			(xy 115.369251 -152.060846) (xy 115.368832 -152.022556) (xy 115.369294 -151.981447) (xy 115.376886 -151.899581)
			(xy 115.392 -151.818765) (xy 115.414508 -151.739689) (xy 115.444217 -151.663027) (xy 115.480874 -151.589434)
			(xy 115.524166 -151.519537) (xy 115.573724 -151.453935) (xy 115.629125 -151.393185) (xy 115.689895 -151.337808)
			(xy 115.755516 -151.288275) (xy 115.825429 -151.245009) (xy 115.899036 -151.20838) (xy 115.975709 -151.1787)
			(xy 116.054794 -151.156223) (xy 116.135616 -151.141139) (xy 116.217485 -151.133579) (xy 116.258594 -151.133048)
			(xy 116.296909 -151.133442) (xy 116.373258 -151.139991) (xy 116.448762 -151.153076) (xy 116.522862 -151.172599)
			(xy 116.559076 -151.185118) (xy 116.567392 -151.187704) (xy 116.584796 -151.187704) (xy 116.593112 -151.185118)
			(xy 116.629318 -151.172572) (xy 116.703417 -151.15303) (xy 116.778924 -151.139944) (xy 116.855277 -151.133411)
			(xy 116.893594 -151.133048) (xy 116.933807 -151.133485) (xy 117.013907 -151.140719) (xy 117.093029 -151.155148)
			(xy 117.170526 -151.176653) (xy 117.2083 -151.190452) (xy 117.217087 -151.193359) (xy 117.235581 -151.193359)
			(xy 117.244368 -151.190452) (xy 117.282142 -151.176652) (xy 117.359636 -151.155127) (xy 117.438758 -151.140694)
			(xy 117.51886 -151.133468) (xy 117.559074 -151.133048) (xy 117.597389 -151.133441) (xy 117.673738 -151.139989)
			(xy 117.749243 -151.153072) (xy 117.823344 -151.172593) (xy 117.859556 -151.185118) (xy 117.867872 -151.187704)
			(xy 117.885276 -151.187704) (xy 117.893592 -151.185118) (xy 117.929798 -151.172571) (xy 118.003897 -151.153028)
			(xy 118.079404 -151.13994) (xy 118.155757 -151.133405) (xy 118.194074 -151.133048) (xy 118.232389 -151.133441)
			(xy 118.308738 -151.139989) (xy 118.384243 -151.153072) (xy 118.458344 -151.172593) (xy 118.494556 -151.185118)
			(xy 118.502872 -151.187704) (xy 118.520276 -151.187704) (xy 118.528592 -151.185118) (xy 118.564798 -151.172571)
			(xy 118.638897 -151.153028) (xy 118.714404 -151.13994) (xy 118.790757 -151.133405) (xy 118.829074 -151.133048)
			(xy 118.867389 -151.133441) (xy 118.943738 -151.139989) (xy 119.019243 -151.153072) (xy 119.093344 -151.172593)
			(xy 119.129556 -151.185118) (xy 119.137872 -151.187704) (xy 119.155276 -151.187704) (xy 119.163592 -151.185118)
			(xy 119.19971 -151.17261) (xy 119.27362 -151.1531) (xy 119.348933 -151.140013) (xy 119.425091 -151.133445)
			(xy 119.463312 -151.133048) (xy 119.464074 -151.133048) (xy 119.505181 -151.133521) (xy 119.587046 -151.141104)
			(xy 119.667861 -151.156206) (xy 119.746939 -151.178699) (xy 119.823605 -151.208392) (xy 119.897204 -151.245031)
			(xy 119.967109 -151.288303) (xy 120.032725 -151.33784) (xy 120.09349 -151.393219) (xy 120.148887 -151.453968)
			(xy 120.198444 -151.519568) (xy 120.241738 -151.58946) (xy 120.278399 -151.663048) (xy 120.308115 -151.739705)
			(xy 120.330632 -151.818776) (xy 120.345759 -151.899587) (xy 120.353366 -151.981449) (xy 120.353836 -152.022556)
			(xy 120.353398 -152.060844) (xy 120.34677 -152.137132) (xy 120.333619 -152.212571) (xy 120.314043 -152.286602)
			(xy 120.301512 -152.322784) (xy 120.298855 -152.331221) (xy 120.298841 -152.348897) (xy 120.301512 -152.357328)
			(xy 120.316731 -152.40155) (xy 120.338873 -152.492419) (xy 120.345708 -152.538684) (xy 120.348248 -152.557734)
			(xy 120.376696 -152.582626) (xy 127.893318 -152.582626) (xy 127.902304 -152.58228) (xy 127.919167 -152.57607)
			(xy 127.932827 -152.564392) (xy 127.937514 -152.556718) (xy 127.958914 -152.519592) (xy 128.007818 -152.449217)
			(xy 128.063266 -152.383874) (xy 128.124744 -152.324169) (xy 128.191681 -152.270656) (xy 128.263456 -152.223832)
			(xy 128.339404 -152.184131) (xy 128.418819 -152.151921) (xy 128.500965 -152.127502) (xy 128.585079 -152.1111)
			(xy 128.670381 -152.102867) (xy 128.71323 -152.102312) (xy 128.754841 -152.102792) (xy 128.8377 -152.110557)
			(xy 128.919472 -152.126024) (xy 128.999443 -152.14906) (xy 129.076913 -152.179462) (xy 129.151205 -152.216966)
			(xy 129.186686 -152.23871) (xy 129.195818 -152.243893) (xy 129.216543 -152.247112) (xy 129.236829 -152.24178)
			(xy 129.24536 -152.235662) (xy 129.279008 -152.2097) (xy 129.350412 -152.163595) (xy 129.425884 -152.124505)
			(xy 129.504737 -152.092785) (xy 129.586255 -152.068724) (xy 129.669695 -152.052541) (xy 129.754297 -152.044384)
			(xy 129.796794 -152.043892) (xy 129.838657 -152.044377) (xy 129.922011 -152.052254) (xy 130.004256 -152.06793)
			(xy 130.084664 -152.091266) (xy 130.162523 -152.122055) (xy 130.237144 -152.160026) (xy 130.307866 -152.20484)
			(xy 130.374064 -152.256103) (xy 130.435151 -152.313361) (xy 130.490586 -152.376105) (xy 130.53988 -152.443782)
			(xy 130.582595 -152.515792) (xy 130.600958 -152.553416) (xy 130.605419 -152.56195) (xy 130.619431 -152.575136)
			(xy 130.637312 -152.58224) (xy 130.646932 -152.582626) (xy 132.390388 -152.582626) (xy 132.40011 -152.582145)
			(xy 132.418133 -152.574834) (xy 132.42544 -152.568402) (xy 132.446907 -152.548566) (xy 132.494745 -152.514989)
			(xy 132.54714 -152.489094) (xy 132.602869 -152.471484) (xy 132.660631 -152.462572) (xy 132.689854 -152.461976)
			(xy 132.690108 -152.461976) (xy 132.715308 -152.462405) (xy 132.765265 -152.469079) (xy 132.813912 -152.482257)
			(xy 132.860406 -152.501712) (xy 132.882386 -152.514046) (xy 132.892292 -152.519888) (xy 132.914136 -152.52192)
			(xy 133.008878 -152.488392) (xy 133.024626 -152.472898) (xy 133.02869 -152.462484) (xy 133.03938 -152.435703)
			(xy 133.067661 -152.385451) (xy 133.103188 -152.340032) (xy 133.145149 -152.300481) (xy 133.192587 -152.2677)
			(xy 133.244422 -152.242438) (xy 133.299469 -152.225269) (xy 133.356475 -152.216586) (xy 133.385306 -152.216104)
			(xy 133.412369 -152.216569) (xy 133.465953 -152.224204) (xy 133.517921 -152.239334) (xy 133.567229 -152.261655)
			(xy 133.612889 -152.29072) (xy 133.653984 -152.325945) (xy 133.689688 -152.366623) (xy 133.719287 -152.411939)
			(xy 133.742186 -152.460982) (xy 133.757924 -152.512768) (xy 133.762496 -152.539446) (xy 133.764208 -152.548353)
			(xy 133.772977 -152.564216) (xy 133.786724 -152.57603) (xy 133.803725 -152.582315) (xy 133.812788 -152.582626)
			(xy 134.08025 -152.582626) (xy 134.092091 -152.581997) (xy 134.113269 -152.571393) (xy 134.12089 -152.562306)
			(xy 134.137621 -152.540894) (xy 134.176143 -152.502569) (xy 134.219713 -152.470096) (xy 134.267447 -152.444132)
			(xy 134.318383 -152.425202) (xy 134.371488 -152.413688) (xy 134.42569 -152.409824) (xy 134.479892 -152.413688)
			(xy 134.532997 -152.425202) (xy 134.583933 -152.444132) (xy 134.631667 -152.470096) (xy 134.675237 -152.502569)
			(xy 134.713759 -152.540894) (xy 134.73049 -152.562306) (xy 134.738097 -152.571403) (xy 134.759288 -152.58198)
			(xy 134.77113 -152.582626) (xy 134.961376 -152.582626) (xy 134.988554 -152.561798) (xy 134.993126 -152.545288)
			(xy 135.003786 -152.50867) (xy 135.031444 -152.437592) (xy 135.066058 -152.369629) (xy 135.10728 -152.305459)
			(xy 135.154701 -152.245724) (xy 135.207846 -152.191018) (xy 135.266185 -152.141889) (xy 135.329135 -152.098827)
			(xy 135.396068 -152.062262) (xy 135.466316 -152.032559) (xy 135.539178 -152.010015) (xy 135.613926 -151.994854)
			(xy 135.689813 -151.987227) (xy 135.727948 -151.986742) (xy 135.76788 -151.987249) (xy 135.847307 -151.995602)
			(xy 135.925425 -152.012212) (xy 136.00138 -152.036896) (xy 136.074338 -152.069385) (xy 136.1435 -152.109322)
			(xy 136.208109 -152.156269) (xy 136.267456 -152.209713) (xy 136.320893 -152.269067) (xy 136.367832 -152.333682)
			(xy 136.40776 -152.40285) (xy 136.440239 -152.475812) (xy 136.464913 -152.551769) (xy 136.481513 -152.62989)
			(xy 136.489856 -152.709318) (xy 136.490456 -152.74925) (xy 136.490456 -152.749758) (xy 136.489871 -152.791648)
			(xy 136.480661 -152.87492) (xy 136.462378 -152.956681) (xy 136.435245 -153.035946) (xy 136.399587 -153.111759)
			(xy 136.378188 -153.147776) (xy 136.372825 -153.157749) (xy 136.370481 -153.180242) (xy 136.378004 -153.201568)
			(xy 136.385554 -153.210006) (xy 136.577578 -153.40203) (xy 136.594842 -153.420069) (xy 136.622609 -153.46156)
			(xy 136.64173 -153.507679) (xy 136.651467 -153.556645) (xy 136.652 -153.581608) (xy 136.652 -167.738044)
			(xy 136.652496 -167.748046) (xy 136.660163 -167.766522) (xy 136.674314 -167.780662) (xy 136.692798 -167.788313)
			(xy 136.7028 -167.788844) (xy 138.924538 -167.788844) (xy 138.934947 -167.788357) (xy 138.95406 -167.780111)
			(xy 138.968325 -167.76495) (xy 138.97229 -167.755316) (xy 138.981545 -167.730555) (xy 139.003028 -167.682252)
			(xy 139.015216 -167.658796) (xy 139.020533 -167.64744) (xy 139.020542 -167.622395) (xy 139.015216 -167.611044)
			(xy 138.99815 -167.57795) (xy 138.969798 -167.509092) (xy 138.948286 -167.437801) (xy 138.933821 -167.364754)
			(xy 138.926538 -167.290645) (xy 138.926062 -167.253412) (xy 138.926551 -167.214741) (xy 138.934376 -167.137796)
			(xy 138.949945 -167.062037) (xy 138.973098 -166.988242) (xy 139.003598 -166.917168) (xy 139.041133 -166.849545)
			(xy 139.085316 -166.786065) (xy 139.135694 -166.727381) (xy 139.191751 -166.674095) (xy 139.252911 -166.626754)
			(xy 139.318547 -166.585843) (xy 139.387985 -166.551782) (xy 139.460512 -166.52492) (xy 139.535385 -166.505535)
			(xy 139.611835 -166.493823) (xy 139.689078 -166.489906) (xy 139.766321 -166.493823) (xy 139.842771 -166.505535)
			(xy 139.917644 -166.52492) (xy 139.990171 -166.551782) (xy 140.059609 -166.585843) (xy 140.125245 -166.626754)
			(xy 140.186405 -166.674095) (xy 140.242462 -166.727381) (xy 140.29284 -166.786065) (xy 140.337023 -166.849545)
			(xy 140.374558 -166.917168) (xy 140.405058 -166.988242) (xy 140.428211 -167.062037) (xy 140.44378 -167.137796)
			(xy 140.451605 -167.214741) (xy 140.452094 -167.253412) (xy 140.451635 -167.290646) (xy 140.444357 -167.364757)
			(xy 140.429892 -167.437806) (xy 140.408378 -167.509099) (xy 140.380018 -167.577955) (xy 140.36294 -167.611044)
			(xy 140.357636 -167.6224) (xy 140.357645 -167.647435) (xy 140.36294 -167.658796) (xy 140.375131 -167.682251)
			(xy 140.396617 -167.730553) (xy 140.405866 -167.755316) (xy 140.409872 -167.764929) (xy 140.424125 -167.780087)
			(xy 140.443216 -167.78836) (xy 140.453618 -167.788844) (xy 149.473666 -167.788844) (xy 149.498624 -167.789422)
			(xy 149.547577 -167.799173) (xy 149.593688 -167.818288) (xy 149.635183 -167.846032) (xy 149.653244 -167.863266)
			(xy 152.420578 -170.6306) (xy 160.67149 -170.6306) (xy 160.675402 -170.553457) (xy 160.687099 -170.477106)
			(xy 160.70646 -170.402329) (xy 160.733287 -170.329895) (xy 160.767305 -170.260547) (xy 160.808164 -170.194997)
			(xy 160.855445 -170.133916) (xy 160.908663 -170.077932) (xy 160.967271 -170.027619) (xy 161.03067 -169.983494)
			(xy 161.098207 -169.946009) (xy 161.169189 -169.91555) (xy 161.24289 -169.892428) (xy 161.318551 -169.876881)
			(xy 161.395397 -169.869068) (xy 161.434018 -169.868596) (xy 161.47671 -169.869176) (xy 161.561558 -169.878722)
			(xy 161.644811 -169.89768) (xy 161.725426 -169.925813) (xy 161.802397 -169.962771) (xy 161.838894 -169.984928)
			(xy 161.84715 -169.989642) (xy 161.865818 -169.993169) (xy 161.884486 -169.989642) (xy 161.892742 -169.984928)
			(xy 161.929245 -169.962778) (xy 162.006203 -169.925789) (xy 162.086816 -169.897643) (xy 162.170072 -169.878692)
			(xy 162.254925 -169.869175) (xy 162.297618 -169.868596) (xy 162.336237 -169.869094) (xy 162.413078 -169.87691)
			(xy 162.488734 -169.892459) (xy 162.562428 -169.915582) (xy 162.633406 -169.946043) (xy 162.700937 -169.983527)
			(xy 162.76433 -170.027651) (xy 162.822934 -170.077962) (xy 162.876147 -170.133944) (xy 162.923424 -170.195022)
			(xy 162.964279 -170.260569) (xy 162.998294 -170.329914) (xy 163.025118 -170.402343) (xy 163.044478 -170.477115)
			(xy 163.056174 -170.553462) (xy 163.060086 -170.6306) (xy 163.056174 -170.707738) (xy 163.044478 -170.784085)
			(xy 163.025118 -170.858857) (xy 162.998294 -170.931286) (xy 162.964279 -171.000631) (xy 162.923424 -171.066178)
			(xy 162.876147 -171.127256) (xy 162.822934 -171.183238) (xy 162.76433 -171.233549) (xy 162.700937 -171.277673)
			(xy 162.633406 -171.315157) (xy 162.562428 -171.345618) (xy 162.488734 -171.368741) (xy 162.413078 -171.38429)
			(xy 162.336237 -171.392106) (xy 162.297618 -171.392596) (xy 162.254927 -171.392) (xy 162.170079 -171.382458)
			(xy 162.086826 -171.363504) (xy 162.006211 -171.335374) (xy 161.929239 -171.298419) (xy 161.892742 -171.276264)
			(xy 161.884486 -171.27155) (xy 161.865818 -171.268023) (xy 161.84715 -171.27155) (xy 161.838894 -171.276264)
			(xy 161.802407 -171.29844) (xy 161.725444 -171.335424) (xy 161.644827 -171.363565) (xy 161.561568 -171.38251)
			(xy 161.476712 -171.39202) (xy 161.434018 -171.392596) (xy 161.395397 -171.392132) (xy 161.318551 -171.384319)
			(xy 161.24289 -171.368772) (xy 161.169189 -171.34565) (xy 161.098207 -171.315191) (xy 161.03067 -171.277706)
			(xy 160.967271 -171.233581) (xy 160.908663 -171.183268) (xy 160.855445 -171.127284) (xy 160.808164 -171.066203)
			(xy 160.767305 -171.000653) (xy 160.733287 -170.931305) (xy 160.70646 -170.858871) (xy 160.687099 -170.784094)
			(xy 160.675402 -170.707743) (xy 160.67149 -170.6306) (xy 152.420578 -170.6306) (xy 164.710364 -182.920386)
			(xy 164.727619 -182.938429) (xy 164.755367 -182.979924) (xy 164.774471 -183.026042) (xy 164.784195 -183.075004)
			(xy 164.784786 -183.099964) (xy 164.784786 -194.341496) (xy 164.785208 -194.351567) (xy 164.79292 -194.370174)
			(xy 164.799772 -194.377564) (xy 165.06317 -194.640962) (xy 165.07057 -194.647802) (xy 165.089169 -194.655516)
			(xy 165.099238 -194.655948) (xy 165.27145 -194.655948) (xy 165.282173 -194.655527) (xy 165.30177 -194.646835)
			(xy 165.309296 -194.639184) (xy 165.328486 -194.618593) (xy 165.372006 -194.582902) (xy 165.420447 -194.554243)
			(xy 165.472682 -194.533283) (xy 165.527496 -194.520509) (xy 165.583616 -194.516218) (xy 165.639736 -194.520509)
			(xy 165.69455 -194.533283) (xy 165.746785 -194.554243) (xy 165.795226 -194.582902) (xy 165.838746 -194.618593)
			(xy 165.857936 -194.639184) (xy 165.865536 -194.646722) (xy 165.885092 -194.655366) (xy 165.895782 -194.655948)
			(xy 166.612316 -194.655948) (xy 166.622588 -194.655476) (xy 166.64149 -194.647427) (xy 166.655731 -194.632619)
			(xy 166.659814 -194.623182) (xy 166.673896 -194.587486) (xy 166.708239 -194.51886) (xy 166.749301 -194.45403)
			(xy 166.796668 -194.393653) (xy 166.84986 -194.338339) (xy 166.90834 -194.288648) (xy 166.971515 -194.245082)
			(xy 167.038746 -194.208083) (xy 167.109354 -194.178024) (xy 167.182625 -194.15521) (xy 167.257816 -194.139871)
			(xy 167.334168 -194.132162) (xy 167.410908 -194.132162) (xy 167.48726 -194.139871) (xy 167.562451 -194.15521)
			(xy 167.635722 -194.178024) (xy 167.70633 -194.208083) (xy 167.773561 -194.245082) (xy 167.836736 -194.288648)
			(xy 167.895216 -194.338339) (xy 167.948408 -194.393653) (xy 167.995775 -194.45403) (xy 168.036837 -194.51886)
			(xy 168.07118 -194.587486) (xy 168.085262 -194.623182) (xy 168.089345 -194.63262) (xy 168.103581 -194.647433)
			(xy 168.122487 -194.655471) (xy 168.13276 -194.655948) (xy 168.90365 -194.655948) (xy 168.915076 -194.655307)
			(xy 168.935668 -194.6454) (xy 168.949948 -194.627558) (xy 168.95318 -194.616578) (xy 168.962376 -194.578918)
			(xy 168.987518 -194.50558) (xy 169.020093 -194.435228) (xy 169.059751 -194.368611) (xy 169.106071 -194.306442)
			(xy 169.158558 -194.249383) (xy 169.216651 -194.198044) (xy 169.279731 -194.152972) (xy 169.347124 -194.114649)
			(xy 169.418112 -194.083483) (xy 169.491936 -194.059807) (xy 169.567809 -194.043873) (xy 169.64492 -194.035853)
			(xy 169.683684 -194.035426) (xy 169.683938 -194.035426) (xy 169.723766 -194.035949) (xy 169.802975 -194.044388)
			(xy 169.880842 -194.061179) (xy 169.95649 -194.086131) (xy 170.029066 -194.118963) (xy 170.097751 -194.159305)
			(xy 170.161772 -194.206703) (xy 170.19143 -194.233292) (xy 170.198768 -194.239317) (xy 170.216488 -194.246082)
			(xy 170.225974 -194.2465) (xy 170.256454 -194.2465) (xy 170.266023 -194.246001) (xy 170.283776 -194.238827)
			(xy 170.290998 -194.23253) (xy 170.32138 -194.204399) (xy 170.387224 -194.154188) (xy 170.458122 -194.111409)
			(xy 170.533239 -194.076567) (xy 170.61169 -194.050072) (xy 170.69255 -194.032235) (xy 170.774868 -194.023268)
			(xy 170.81627 -194.022726) (xy 170.855792 -194.023231) (xy 170.934411 -194.031416) (xy 171.011762 -194.047691)
			(xy 171.087014 -194.071881) (xy 171.159359 -194.103727) (xy 171.228022 -194.142886) (xy 171.292264 -194.188939)
			(xy 171.351398 -194.241391) (xy 171.404787 -194.29968) (xy 171.45186 -194.36318) (xy 171.49211 -194.431208)
			(xy 171.525106 -194.503036) (xy 171.550494 -194.577893) (xy 171.559728 -194.616324) (xy 171.559728 -194.616578)
			(xy 171.562911 -194.627581) (xy 171.577199 -194.645444) (xy 171.59782 -194.655341) (xy 171.609258 -194.655948)
			(xy 172.815504 -194.655948) (xy 172.826231 -194.655536) (xy 172.845842 -194.646856) (xy 172.85335 -194.639184)
			(xy 172.87254 -194.618593) (xy 172.91606 -194.582902) (xy 172.964501 -194.554243) (xy 173.016736 -194.533283)
			(xy 173.07155 -194.520509) (xy 173.12767 -194.516218) (xy 173.18379 -194.520509) (xy 173.238604 -194.533283)
			(xy 173.290839 -194.554243) (xy 173.33928 -194.582902) (xy 173.3828 -194.618593) (xy 173.40199 -194.639184)
			(xy 173.409587 -194.646729) (xy 173.429143 -194.655391) (xy 173.439836 -194.655948) (xy 174.15637 -194.655948)
			(xy 174.166647 -194.655484) (xy 174.185564 -194.647445) (xy 174.19982 -194.632638) (xy 174.203868 -194.623182)
			(xy 174.21795 -194.587486) (xy 174.252293 -194.51886) (xy 174.293355 -194.45403) (xy 174.340722 -194.393653)
			(xy 174.393914 -194.338339) (xy 174.452394 -194.288648) (xy 174.515569 -194.245082) (xy 174.5828 -194.208083)
			(xy 174.653408 -194.178024) (xy 174.726679 -194.15521) (xy 174.80187 -194.139871) (xy 174.878222 -194.132162)
			(xy 174.954962 -194.132162) (xy 175.031314 -194.139871) (xy 175.106505 -194.15521) (xy 175.179776 -194.178024)
			(xy 175.250384 -194.208083) (xy 175.317615 -194.245082) (xy 175.38079 -194.288648) (xy 175.43927 -194.338339)
			(xy 175.492462 -194.393653) (xy 175.539829 -194.45403) (xy 175.580891 -194.51886) (xy 175.615234 -194.587486)
			(xy 175.629316 -194.623182) (xy 175.633397 -194.632625) (xy 175.64763 -194.64745) (xy 175.666538 -194.655506)
			(xy 175.676814 -194.655948) (xy 176.447704 -194.655948) (xy 176.459136 -194.655316) (xy 176.479746 -194.645418)
			(xy 176.49404 -194.627573) (xy 176.497234 -194.616578) (xy 176.50643 -194.578919) (xy 176.531573 -194.505584)
			(xy 176.564149 -194.435234) (xy 176.603808 -194.368621) (xy 176.650129 -194.306455) (xy 176.702616 -194.2494)
			(xy 176.76071 -194.198065) (xy 176.82379 -194.152997) (xy 176.891183 -194.114678) (xy 176.96217 -194.083517)
			(xy 177.035994 -194.059846) (xy 177.111865 -194.043918) (xy 177.188975 -194.035902) (xy 177.227738 -194.035426)
			(xy 177.227992 -194.035426) (xy 177.267819 -194.035952) (xy 177.347025 -194.044396) (xy 177.424889 -194.061191)
			(xy 177.500534 -194.086148) (xy 177.573106 -194.118984) (xy 177.641787 -194.159329) (xy 177.705804 -194.206729)
			(xy 177.735484 -194.233292) (xy 177.742819 -194.239324) (xy 177.76054 -194.246105) (xy 177.770028 -194.2465)
			(xy 177.800508 -194.2465) (xy 177.810073 -194.245991) (xy 177.827813 -194.238804) (xy 177.835052 -194.23253)
			(xy 177.865435 -194.204401) (xy 177.93128 -194.154195) (xy 178.002179 -194.111421) (xy 178.077296 -194.076584)
			(xy 178.155747 -194.050094) (xy 178.236607 -194.032264) (xy 178.318923 -194.023302) (xy 178.360324 -194.022726)
			(xy 178.399844 -194.023234) (xy 178.47846 -194.031424) (xy 178.555807 -194.047703) (xy 178.631054 -194.071896)
			(xy 178.703395 -194.103744) (xy 178.772052 -194.142906) (xy 178.83629 -194.18896) (xy 178.895419 -194.241412)
			(xy 178.948804 -194.299701) (xy 178.995873 -194.363199) (xy 179.036119 -194.431226) (xy 179.069112 -194.503052)
			(xy 179.094498 -194.577906) (xy 179.103782 -194.616324) (xy 179.103782 -194.616578) (xy 179.106871 -194.627622)
			(xy 179.121192 -194.645507) (xy 179.141855 -194.655404) (xy 179.153312 -194.655948) (xy 180.359558 -194.655948)
			(xy 180.37028 -194.655525) (xy 180.389875 -194.646831) (xy 180.397404 -194.639184) (xy 180.416594 -194.618593)
			(xy 180.460114 -194.582902) (xy 180.508555 -194.554243) (xy 180.56079 -194.533283) (xy 180.615604 -194.520509)
			(xy 180.671724 -194.516218) (xy 180.727844 -194.520509) (xy 180.782658 -194.533283) (xy 180.834893 -194.554243)
			(xy 180.883334 -194.582902) (xy 180.926854 -194.618593) (xy 180.946044 -194.639184) (xy 180.953645 -194.646721)
			(xy 180.9732 -194.655362) (xy 180.98389 -194.655948) (xy 181.700424 -194.655948) (xy 181.710695 -194.655475)
			(xy 181.729595 -194.647424) (xy 181.743833 -194.632616) (xy 181.747922 -194.623182) (xy 181.762004 -194.587486)
			(xy 181.796347 -194.51886) (xy 181.837409 -194.45403) (xy 181.884776 -194.393653) (xy 181.937968 -194.338339)
			(xy 181.996448 -194.288648) (xy 182.059623 -194.245082) (xy 182.126854 -194.208083) (xy 182.197462 -194.178024)
			(xy 182.270733 -194.15521) (xy 182.345924 -194.139871) (xy 182.422276 -194.132162) (xy 182.499016 -194.132162)
			(xy 182.575368 -194.139871) (xy 182.650559 -194.15521) (xy 182.72383 -194.178024) (xy 182.794438 -194.208083)
			(xy 182.861669 -194.245082) (xy 182.924844 -194.288648) (xy 182.983324 -194.338339) (xy 183.036516 -194.393653)
			(xy 183.083883 -194.45403) (xy 183.124945 -194.51886) (xy 183.159288 -194.587486) (xy 183.17337 -194.623182)
			(xy 183.177448 -194.63263) (xy 183.191679 -194.647468) (xy 183.210588 -194.65554) (xy 183.220868 -194.655948)
			(xy 183.978804 -194.655948) (xy 183.990236 -194.655316) (xy 184.010846 -194.645418) (xy 184.02514 -194.627573)
			(xy 184.028334 -194.616578) (xy 184.028334 -194.616324) (xy 184.037566 -194.57789) (xy 184.062936 -194.503023)
			(xy 184.095919 -194.431185) (xy 184.13616 -194.363147) (xy 184.183228 -194.299639) (xy 184.236617 -194.241344)
			(xy 184.295753 -194.188889) (xy 184.36 -194.142837) (xy 184.42867 -194.103681) (xy 184.501023 -194.071845)
			(xy 184.576284 -194.047668) (xy 184.653642 -194.031411) (xy 184.732268 -194.023249) (xy 184.771792 -194.022726)
			(xy 184.809567 -194.023191) (xy 184.884747 -194.030667) (xy 184.958819 -194.045537) (xy 185.031059 -194.067656)
			(xy 185.100759 -194.096806) (xy 185.167237 -194.132703) (xy 185.229841 -194.174995) (xy 185.259218 -194.198748)
			(xy 185.268539 -194.205687) (xy 185.291119 -194.211078) (xy 185.313775 -194.206021) (xy 185.323226 -194.199256)
			(xy 185.3517 -194.177069) (xy 185.412181 -194.137655) (xy 185.476172 -194.104238) (xy 185.543079 -194.077129)
			(xy 185.612282 -194.05658) (xy 185.683141 -194.04278) (xy 185.754999 -194.035857) (xy 185.791094 -194.035426)
			(xy 185.791348 -194.035426) (xy 185.830112 -194.035911) (xy 185.907226 -194.043908) (xy 185.983103 -194.059822)
			(xy 186.056932 -194.083483) (xy 186.127924 -194.114639) (xy 186.195321 -194.152955) (xy 186.258403 -194.198024)
			(xy 186.316496 -194.249363) (xy 186.36898 -194.306425) (xy 186.415293 -194.368599) (xy 186.454942 -194.435221)
			(xy 186.487502 -194.50558) (xy 186.512625 -194.578925) (xy 186.521852 -194.616578) (xy 186.525036 -194.627579)
			(xy 186.539325 -194.645434) (xy 186.559946 -194.655323) (xy 186.571382 -194.655948) (xy 187.903612 -194.655948)
			(xy 187.914338 -194.655534) (xy 187.933947 -194.646852) (xy 187.941458 -194.639184) (xy 187.960648 -194.618593)
			(xy 188.004168 -194.582902) (xy 188.052609 -194.554243) (xy 188.104844 -194.533283) (xy 188.159658 -194.520509)
			(xy 188.215778 -194.516218) (xy 188.271898 -194.520509) (xy 188.326712 -194.533283) (xy 188.378947 -194.554243)
			(xy 188.427388 -194.582902) (xy 188.470908 -194.618593) (xy 188.490098 -194.639184) (xy 188.497696 -194.646728)
			(xy 188.517251 -194.655387) (xy 188.527944 -194.655948) (xy 189.244224 -194.655948) (xy 189.254495 -194.655475)
			(xy 189.273395 -194.647424) (xy 189.287633 -194.632616) (xy 189.291722 -194.623182) (xy 189.305804 -194.587486)
			(xy 189.340147 -194.51886) (xy 189.381209 -194.45403) (xy 189.428576 -194.393653) (xy 189.481768 -194.338339)
			(xy 189.540248 -194.288648) (xy 189.603423 -194.245082) (xy 189.670654 -194.208083) (xy 189.741262 -194.178024)
			(xy 189.814533 -194.15521) (xy 189.889724 -194.139871) (xy 189.966076 -194.132162) (xy 190.042816 -194.132162)
			(xy 190.119168 -194.139871) (xy 190.194359 -194.15521) (xy 190.26763 -194.178024) (xy 190.338238 -194.208083)
			(xy 190.405469 -194.245082) (xy 190.468644 -194.288648) (xy 190.527124 -194.338339) (xy 190.580316 -194.393653)
			(xy 190.627683 -194.45403) (xy 190.668745 -194.51886) (xy 190.703088 -194.587486) (xy 190.71717 -194.623182)
			(xy 190.721248 -194.63263) (xy 190.735479 -194.647468) (xy 190.754388 -194.65554) (xy 190.764668 -194.655948)
			(xy 191.535812 -194.655948) (xy 191.547243 -194.655315) (xy 191.56785 -194.645414) (xy 191.582142 -194.62757)
			(xy 191.585342 -194.616578) (xy 191.594538 -194.578919) (xy 191.619682 -194.505584) (xy 191.652257 -194.435235)
			(xy 191.691917 -194.368623) (xy 191.738237 -194.306457) (xy 191.790725 -194.249403) (xy 191.848819 -194.198068)
			(xy 191.911899 -194.153001) (xy 191.979292 -194.114682) (xy 192.050279 -194.083522) (xy 192.124102 -194.059852)
			(xy 192.199974 -194.043924) (xy 192.277084 -194.03591) (xy 192.315846 -194.035426) (xy 192.3161 -194.035426)
			(xy 192.355927 -194.035952) (xy 192.435133 -194.044397) (xy 192.512996 -194.061193) (xy 192.58864 -194.08615)
			(xy 192.661212 -194.118987) (xy 192.729892 -194.159333) (xy 192.793908 -194.206733) (xy 192.823592 -194.233292)
			(xy 192.830928 -194.239322) (xy 192.848649 -194.2461) (xy 192.858136 -194.2465) (xy 192.888616 -194.2465)
			(xy 192.89818 -194.24599) (xy 192.915918 -194.2388) (xy 192.92316 -194.23253) (xy 192.953543 -194.204402)
			(xy 193.019388 -194.154196) (xy 193.090287 -194.111423) (xy 193.165405 -194.076587) (xy 193.243855 -194.050098)
			(xy 193.324715 -194.032268) (xy 193.407031 -194.023307) (xy 193.448432 -194.022726) (xy 193.487955 -194.023229)
			(xy 193.566577 -194.031411) (xy 193.643931 -194.047682) (xy 193.719186 -194.07187) (xy 193.791535 -194.103714)
			(xy 193.8602 -194.142872) (xy 193.924446 -194.188925) (xy 193.983583 -194.241377) (xy 194.036975 -194.299666)
			(xy 194.084051 -194.363166) (xy 194.124303 -194.431196) (xy 194.157302 -194.503025) (xy 194.182692 -194.577883)
			(xy 194.19189 -194.616324) (xy 194.19189 -194.616578) (xy 194.195071 -194.627585) (xy 194.209357 -194.645458)
			(xy 194.229979 -194.65537) (xy 194.24142 -194.655948) (xy 195.447666 -194.655948) (xy 195.458387 -194.655524)
			(xy 195.47798 -194.646828) (xy 195.485512 -194.639184) (xy 195.504702 -194.618593) (xy 195.548222 -194.582902)
			(xy 195.596663 -194.554243) (xy 195.648898 -194.533283) (xy 195.703712 -194.520509) (xy 195.759832 -194.516218)
			(xy 195.815952 -194.520509) (xy 195.870766 -194.533283) (xy 195.923001 -194.554243) (xy 195.971442 -194.582902)
			(xy 196.014962 -194.618593) (xy 196.034152 -194.639184) (xy 196.041747 -194.646736) (xy 196.061302 -194.655412)
			(xy 196.071998 -194.655948) (xy 196.788278 -194.655948) (xy 196.798554 -194.655483) (xy 196.817469 -194.647441)
			(xy 196.831722 -194.632634) (xy 196.835776 -194.623182) (xy 196.849858 -194.587486) (xy 196.884201 -194.51886)
			(xy 196.925263 -194.45403) (xy 196.97263 -194.393653) (xy 197.025822 -194.338339) (xy 197.084302 -194.288648)
			(xy 197.147477 -194.245082) (xy 197.214708 -194.208083) (xy 197.285316 -194.178024) (xy 197.358587 -194.15521)
			(xy 197.433778 -194.139871) (xy 197.51013 -194.132162) (xy 197.58687 -194.132162) (xy 197.663222 -194.139871)
			(xy 197.738413 -194.15521) (xy 197.811684 -194.178024) (xy 197.882292 -194.208083) (xy 197.949523 -194.245082)
			(xy 198.012698 -194.288648) (xy 198.071178 -194.338339) (xy 198.12437 -194.393653) (xy 198.171737 -194.45403)
			(xy 198.212799 -194.51886) (xy 198.247142 -194.587486) (xy 198.261224 -194.623182) (xy 198.265305 -194.632624)
			(xy 198.279539 -194.647447) (xy 198.298446 -194.6555) (xy 198.308722 -194.655948) (xy 199.079866 -194.655948)
			(xy 199.091289 -194.655304) (xy 199.111876 -194.645394) (xy 199.12615 -194.627553) (xy 199.129396 -194.616578)
			(xy 199.138592 -194.578918) (xy 199.163735 -194.505581) (xy 199.196309 -194.43523) (xy 199.235968 -194.368614)
			(xy 199.282288 -194.306446) (xy 199.334775 -194.249388) (xy 199.392869 -194.19805) (xy 199.455949 -194.15298)
			(xy 199.523342 -194.114658) (xy 199.594329 -194.083493) (xy 199.668153 -194.059818) (xy 199.744025 -194.043886)
			(xy 199.821137 -194.035867) (xy 199.8599 -194.035426) (xy 199.899727 -194.035952) (xy 199.978933 -194.044397)
			(xy 200.056796 -194.061193) (xy 200.13244 -194.08615) (xy 200.205012 -194.118987) (xy 200.273692 -194.159333)
			(xy 200.337708 -194.206733) (xy 200.367392 -194.233292) (xy 200.374728 -194.239322) (xy 200.392449 -194.2461)
			(xy 200.401936 -194.2465) (xy 200.432416 -194.2465) (xy 200.442049 -194.246033) (xy 200.459932 -194.238852)
			(xy 200.467214 -194.23253) (xy 200.497579 -194.204406) (xy 200.563387 -194.154205) (xy 200.634249 -194.111432)
			(xy 200.709328 -194.076592) (xy 200.787742 -194.050094) (xy 200.868566 -194.03225) (xy 200.950847 -194.023272)
			(xy 200.992232 -194.022726) (xy 201.031755 -194.023229) (xy 201.110377 -194.031411) (xy 201.187731 -194.047682)
			(xy 201.262986 -194.07187) (xy 201.335335 -194.103714) (xy 201.404 -194.142872) (xy 201.468246 -194.188925)
			(xy 201.527383 -194.241377) (xy 201.580775 -194.299666) (xy 201.627851 -194.363166) (xy 201.668103 -194.431196)
			(xy 201.701102 -194.503025) (xy 201.726492 -194.577883) (xy 201.73569 -194.616324) (xy 201.73569 -194.616578)
			(xy 201.738871 -194.627585) (xy 201.753157 -194.645458) (xy 201.773779 -194.65537) (xy 201.78522 -194.655948)
			(xy 202.991466 -194.655948) (xy 203.002187 -194.655524) (xy 203.02178 -194.646828) (xy 203.029312 -194.639184)
			(xy 203.048502 -194.618593) (xy 203.092022 -194.582902) (xy 203.140463 -194.554243) (xy 203.192698 -194.533283)
			(xy 203.247512 -194.520509) (xy 203.303632 -194.516218) (xy 203.359752 -194.520509) (xy 203.414566 -194.533283)
			(xy 203.466801 -194.554243) (xy 203.515242 -194.582902) (xy 203.558762 -194.618593) (xy 203.577952 -194.639184)
			(xy 203.585547 -194.646736) (xy 203.605102 -194.655412) (xy 203.615798 -194.655948) (xy 204.332332 -194.655948)
			(xy 204.342602 -194.655473) (xy 204.361499 -194.64742) (xy 204.375735 -194.632613) (xy 204.37983 -194.623182)
			(xy 204.393903 -194.587477) (xy 204.428231 -194.518831) (xy 204.469282 -194.453982) (xy 204.516642 -194.393585)
			(xy 204.56983 -194.338252) (xy 204.628308 -194.288544) (xy 204.691485 -194.244962) (xy 204.758722 -194.207949)
			(xy 204.829336 -194.177879) (xy 204.902615 -194.155055) (xy 204.977816 -194.13971) (xy 205.054179 -194.131999)
			(xy 205.130929 -194.131999) (xy 205.207292 -194.13971) (xy 205.282493 -194.155055) (xy 205.355772 -194.177879)
			(xy 205.426386 -194.207949) (xy 205.493623 -194.244962) (xy 205.5568 -194.288544) (xy 205.615278 -194.338252)
			(xy 205.668466 -194.393585) (xy 205.715826 -194.453982) (xy 205.756877 -194.518831) (xy 205.791205 -194.587477)
			(xy 205.805278 -194.623182) (xy 205.809357 -194.632629) (xy 205.823588 -194.647465) (xy 205.842497 -194.655534)
			(xy 205.852776 -194.655948) (xy 206.610712 -194.655948) (xy 206.622143 -194.655315) (xy 206.64275 -194.645414)
			(xy 206.657042 -194.62757) (xy 206.660242 -194.616578) (xy 206.660242 -194.616324) (xy 206.670057 -194.575671)
			(xy 206.697406 -194.496634) (xy 206.733258 -194.421073) (xy 206.75473 -194.385184) (xy 206.759375 -194.376943)
			(xy 206.762788 -194.35835) (xy 206.759193 -194.339791) (xy 206.754476 -194.33159) (xy 206.732894 -194.295835)
			(xy 206.696908 -194.220466) (xy 206.669517 -194.141565) (xy 206.651061 -194.060111) (xy 206.641767 -193.97711)
			(xy 206.641192 -193.93535) (xy 206.641647 -193.897931) (xy 206.649109 -193.823466) (xy 206.663955 -193.750116)
			(xy 206.686036 -193.67861) (xy 206.715132 -193.60966) (xy 206.750954 -193.543952) (xy 206.793145 -193.482142)
			(xy 206.841286 -193.424843) (xy 206.86776 -193.398394) (xy 206.875126 -193.391028) (xy 206.883 -193.372486)
			(xy 206.883 -193.348102) (xy 206.883621 -193.323149) (xy 206.893374 -193.274206) (xy 206.912488 -193.228105)
			(xy 206.940227 -193.186618) (xy 206.957422 -193.168524) (xy 207.710786 -192.41516) (xy 207.717628 -192.40776)
			(xy 207.72535 -192.389162) (xy 207.725772 -192.379092) (xy 207.725772 -187.908946) (xy 207.725338 -187.898881)
			(xy 207.717607 -187.880293) (xy 207.710786 -187.872878) (xy 205.538832 -185.700924) (xy 205.531431 -185.694086)
			(xy 205.512832 -185.686372) (xy 205.502764 -185.685938) (xy 182.457598 -185.685938) (xy 182.432641 -185.685326)
			(xy 182.383686 -185.67559) (xy 182.337571 -185.656491) (xy 182.296067 -185.628763) (xy 182.27802 -185.611516)
			(xy 168.733724 -172.06722) (xy 168.725616 -172.059787) (xy 168.705042 -172.052075) (xy 168.683131 -172.053709)
			(xy 168.673272 -172.058584) (xy 168.639606 -172.076426) (xy 168.569413 -172.106072) (xy 168.496613 -172.128573)
			(xy 168.421934 -172.143708) (xy 168.346119 -172.151324) (xy 168.30802 -172.151802) (xy 168.307512 -172.151802)
			(xy 168.267577 -172.151298) (xy 168.188144 -172.14295) (xy 168.110019 -172.126345) (xy 168.034057 -172.101665)
			(xy 167.961092 -172.069179) (xy 167.891922 -172.029245) (xy 167.827305 -171.982298) (xy 167.767949 -171.928855)
			(xy 167.714505 -171.8695) (xy 167.667559 -171.804884) (xy 167.627623 -171.735714) (xy 167.595137 -171.662748)
			(xy 167.570456 -171.586787) (xy 167.553851 -171.508662) (xy 167.545502 -171.429229) (xy 167.545004 -171.389294)
			(xy 167.545004 -171.388024) (xy 167.545188 -171.363828) (xy 167.548237 -171.315531) (xy 167.5511 -171.291504)
			(xy 167.551969 -171.280217) (xy 167.54498 -171.258718) (xy 167.529411 -171.242326) (xy 167.519096 -171.237656)
			(xy 167.492452 -171.226863) (xy 167.442489 -171.198435) (xy 167.397353 -171.162837) (xy 167.358065 -171.120874)
			(xy 167.325512 -171.073495) (xy 167.300431 -171.021771) (xy 167.283389 -170.966871) (xy 167.274771 -170.910036)
			(xy 167.27424 -170.881294) (xy 167.274866 -170.850302) (xy 167.284916 -170.789137) (xy 167.304703 -170.730395)
			(xy 167.31869 -170.702732) (xy 167.326564 -170.688) (xy 167.321738 -170.655234) (xy 138.458956 -141.792452)
			(xy 138.451558 -141.785607) (xy 138.432959 -141.77788) (xy 138.422888 -141.777466) (xy 123.385072 -141.777466)
			(xy 123.375005 -141.777896) (xy 123.356415 -141.785625) (xy 123.349004 -141.792452) (xy 121.924826 -143.21663)
			(xy 121.917981 -143.224029) (xy 121.910254 -143.242627) (xy 121.90984 -143.252698) (xy 121.90984 -146.79422)
			(xy 121.909267 -146.819179) (xy 121.899522 -146.868137) (xy 121.880412 -146.914253) (xy 121.852672 -146.955754)
			(xy 121.835418 -146.973798) (xy 121.352818 -147.456398) (xy 121.334777 -147.473657) (xy 121.293283 -147.501413)
			(xy 121.247165 -147.520523) (xy 121.198201 -147.53025) (xy 121.17324 -147.53082) (xy 115.7732 -147.53082)
			(xy 115.748243 -147.530209) (xy 115.699289 -147.520472) (xy 115.653174 -147.501372) (xy 115.611671 -147.473643)
			(xy 115.593622 -147.456398) (xy 114.996722 -146.859498) (xy 114.979463 -146.841457) (xy 114.951708 -146.799963)
			(xy 114.9326 -146.753845) (xy 114.922877 -146.704881) (xy 114.9223 -146.67992) (xy 114.9223 -144.709134)
			(xy 114.921865 -144.699069) (xy 114.914133 -144.680482) (xy 114.907314 -144.673066) (xy 113.57991 -143.345662)
			(xy 113.572515 -143.338807) (xy 113.553916 -143.331059) (xy 113.543842 -143.330676) (xy 106.98226 -143.330676)
			(xy 106.972192 -143.331106) (xy 106.953596 -143.338828) (xy 106.946192 -143.345662) (xy 104.943402 -145.348452)
			(xy 104.936141 -145.356486) (xy 104.928525 -145.376739) (xy 104.92867 -145.387568) (xy 104.92867 -145.387822)
			(xy 104.930702 -145.442432) (xy 104.930226 -145.481103) (xy 104.922394 -145.558046) (xy 104.906815 -145.633802)
			(xy 104.883647 -145.707591) (xy 104.853129 -145.778657) (xy 104.815575 -145.846268) (xy 104.77137 -145.909731)
			(xy 104.720969 -145.968394) (xy 104.664888 -146.021654) (xy 104.603705 -146.068964) (xy 104.538047 -146.109838)
			(xy 104.468589 -146.143856) (xy 104.396044 -146.170669) (xy 104.321158 -146.190001) (xy 104.283002 -146.196304)
			(xy 104.27081 -146.198082) (xy 104.25176 -146.211798) (xy 104.207564 -146.294348) (xy 104.202556 -146.305036)
			(xy 104.201906 -146.328601) (xy 104.206294 -146.33956) (xy 104.206294 -146.339814) (xy 104.223531 -146.377885)
			(xy 104.250535 -146.456976) (xy 104.268716 -146.538549) (xy 104.277855 -146.621623) (xy 104.27843 -146.66341)
			(xy 104.277907 -146.703344) (xy 104.269557 -146.782775) (xy 104.252951 -146.860897) (xy 104.22827 -146.936856)
			(xy 104.195785 -147.009819) (xy 104.155851 -147.078987) (xy 104.108906 -147.143602) (xy 104.055464 -147.202956)
			(xy 103.996111 -147.256398) (xy 103.931497 -147.303344) (xy 103.86233 -147.34328) (xy 103.789367 -147.375766)
			(xy 103.713409 -147.400448) (xy 103.635286 -147.417056) (xy 103.555856 -147.425406) (xy 103.515922 -147.425918)
			(xy 103.515668 -147.425918) (xy 103.476006 -147.425412) (xy 103.397111 -147.417178) (xy 103.319499 -147.400791)
			(xy 103.24401 -147.376429) (xy 103.17146 -147.344356) (xy 103.102635 -147.304918) (xy 103.070152 -147.282154)
			(xy 103.054912 -147.270978) (xy 103.017828 -147.274026) (xy 99.350068 -150.941786) (xy 108.742233 -150.941786)
			(xy 108.746238 -150.836037) (xy 108.758228 -150.730894) (xy 108.778137 -150.626959) (xy 108.805848 -150.524827)
			(xy 108.841205 -150.425083) (xy 108.884003 -150.328299) (xy 108.933999 -150.235029) (xy 108.990906 -150.145808)
			(xy 109.054397 -150.061145) (xy 109.124109 -149.981527) (xy 109.199643 -149.907409) (xy 109.280566 -149.839216)
			(xy 109.366415 -149.777338) (xy 109.456698 -149.722131) (xy 109.550897 -149.673909) (xy 109.648474 -149.632949)
			(xy 109.748869 -149.599487) (xy 109.851507 -149.573713) (xy 109.9558 -149.555775) (xy 110.061151 -149.545776)
			(xy 110.166957 -149.543773) (xy 110.272611 -149.549778) (xy 110.377508 -149.563757) (xy 110.481048 -149.585628)
			(xy 110.582637 -149.615268) (xy 110.681694 -149.652506) (xy 110.777651 -149.697128) (xy 110.869958 -149.74888)
			(xy 110.958087 -149.807465) (xy 111.041533 -149.872547) (xy 111.119817 -149.943753) (xy 111.192492 -150.020676)
			(xy 111.259142 -150.102876) (xy 111.319384 -150.18988) (xy 111.372873 -150.281191) (xy 111.419304 -150.376286)
			(xy 111.458409 -150.47462) (xy 111.489966 -150.575631) (xy 111.513793 -150.678738) (xy 111.529754 -150.783352)
			(xy 111.537758 -150.888874) (xy 111.538258 -150.941786) (xy 111.537758 -150.994698) (xy 111.529754 -151.10022)
			(xy 111.513793 -151.204834) (xy 111.489966 -151.307941) (xy 111.458409 -151.408952) (xy 111.419304 -151.507286)
			(xy 111.372873 -151.602381) (xy 111.319384 -151.693692) (xy 111.259142 -151.780696) (xy 111.192492 -151.862896)
			(xy 111.119817 -151.939819) (xy 111.041533 -152.011025) (xy 110.958087 -152.076107) (xy 110.869958 -152.134692)
			(xy 110.777651 -152.186444) (xy 110.681694 -152.231066) (xy 110.582637 -152.268304) (xy 110.481048 -152.297944)
			(xy 110.377508 -152.319815) (xy 110.272611 -152.333794) (xy 110.166957 -152.339799) (xy 110.061151 -152.337796)
			(xy 109.9558 -152.327797) (xy 109.851507 -152.309859) (xy 109.748869 -152.284085) (xy 109.648474 -152.250623)
			(xy 109.550897 -152.209663) (xy 109.456698 -152.161441) (xy 109.366415 -152.106234) (xy 109.280566 -152.044356)
			(xy 109.199643 -151.976163) (xy 109.124109 -151.902045) (xy 109.054397 -151.822427) (xy 108.990906 -151.737764)
			(xy 108.933999 -151.648543) (xy 108.884003 -151.555273) (xy 108.841205 -151.458489) (xy 108.805848 -151.358745)
			(xy 108.778137 -151.256613) (xy 108.758228 -151.152678) (xy 108.746238 -151.047535) (xy 108.742233 -150.941786)
			(xy 99.350068 -150.941786) (xy 92.15628 -158.135574) (xy 92.138242 -158.15284) (xy 92.096751 -158.180608)
			(xy 92.050632 -158.199731) (xy 92.001665 -158.209471) (xy 91.976702 -158.209996) (xy 81.438496 -158.209996)
			(xy 81.413536 -158.209424) (xy 81.364574 -158.199684) (xy 81.318454 -158.18058) (xy 81.276947 -158.152844)
			(xy 81.258918 -158.135574) (xy 78.337918 -155.214574) (xy 78.331529 -155.208634) (xy 78.315802 -155.201118)
			(xy 78.298459 -155.199364) (xy 78.289912 -155.201112) (xy 78.289658 -155.201112) (xy 78.26716 -155.206339)
			(xy 78.221312 -155.211947) (xy 78.198218 -155.212288) (xy 78.19771 -155.212288) (xy 78.170457 -155.211825)
			(xy 78.116506 -155.204069) (xy 78.064208 -155.188714) (xy 78.014628 -155.166072) (xy 77.968775 -155.136604)
			(xy 77.927583 -155.10091) (xy 77.89189 -155.059717) (xy 77.862423 -155.013863) (xy 77.839782 -154.964282)
			(xy 77.824428 -154.911984) (xy 77.816674 -154.858033) (xy 77.816202 -154.83078) (xy 77.816202 -154.830272)
			(xy 77.816551 -154.807178) (xy 77.822149 -154.761329) (xy 77.827378 -154.738832) (xy 77.827378 -154.738578)
			(xy 77.82908 -154.730031) (xy 77.827288 -154.712707) (xy 77.819835 -154.696966) (xy 77.813916 -154.690572)
			(xy 76.394818 -153.271474) (xy 76.387419 -153.264632) (xy 76.368819 -153.256916) (xy 76.35875 -153.256488)
			(xy 66.872104 -153.256488) (xy 66.847151 -153.255867) (xy 66.798208 -153.246114) (xy 66.752107 -153.227)
			(xy 66.710621 -153.19926) (xy 66.692526 -153.182066) (xy 59.855862 -146.345402) (xy 59.848461 -146.338561)
			(xy 59.829863 -146.33084) (xy 59.819794 -146.330416) (xy 42.527474 -146.330416) (xy 42.517406 -146.330844)
			(xy 42.49881 -146.338567) (xy 42.491406 -146.345402) (xy 35.553396 -153.283412) (xy 35.546552 -153.290811)
			(xy 35.538822 -153.309409) (xy 35.53841 -153.31948) (xy 35.53841 -173.174406) (xy 35.537798 -173.199362)
			(xy 35.52806 -173.248316) (xy 35.508959 -173.29443) (xy 35.481228 -173.335931) (xy 35.463988 -173.353984)
			(xy 34.944304 -173.873668) (xy 34.939224 -173.905926) (xy 34.94659 -173.920658) (xy 34.962143 -173.952556)
			(xy 34.987944 -174.018671) (xy 35.00749 -174.086898) (xy 35.020612 -174.156645) (xy 35.027198 -174.22731)
			(xy 35.027616 -174.262796) (xy 35.027093 -174.30273) (xy 35.018745 -174.382161) (xy 35.00214 -174.460285)
			(xy 34.97746 -174.536244) (xy 34.944975 -174.609208) (xy 34.905041 -174.678376) (xy 34.858096 -174.742992)
			(xy 34.804654 -174.802346) (xy 34.745301 -174.855789) (xy 34.680686 -174.902735) (xy 34.611519 -174.94267)
			(xy 34.538555 -174.975156) (xy 34.462596 -174.999837) (xy 34.384473 -175.016444) (xy 34.305042 -175.024793)
			(xy 34.265108 -175.025304) (xy 34.229622 -175.024899) (xy 34.158957 -175.018308) (xy 34.089209 -175.005182)
			(xy 34.020982 -174.985635) (xy 33.954866 -174.959836) (xy 33.92297 -174.944278) (xy 33.908238 -174.936912)
			(xy 33.87598 -174.941992) (xy 24.717756 -184.100216) (xy 24.701758 -184.11559) (xy 24.665429 -184.141058)
			(xy 24.625227 -184.159824) (xy 24.582375 -184.171317) (xy 24.538178 -184.175187) (xy 24.493981 -184.171317)
			(xy 24.451129 -184.159824) (xy 24.410927 -184.141058) (xy 24.374598 -184.11559) (xy 24.3586 -184.100216)
			(xy 24.356568 -184.098184) (xy 24.338026 -184.090564) (xy 15.765272 -184.090564) (xy 15.755205 -184.090994)
			(xy 15.736614 -184.098723) (xy 15.729204 -184.10555) (xy 13.80871 -186.026044) (xy 13.801869 -186.033444)
			(xy 13.794149 -186.052043) (xy 13.793724 -186.062112) (xy 13.793724 -194.37096) (xy 13.794159 -194.381025)
			(xy 13.801891 -194.399611) (xy 13.80871 -194.407028) (xy 14.763242 -195.36156) (xy 14.770641 -195.368404)
			(xy 14.789239 -195.376129) (xy 14.79931 -195.376546)
		)
		(stroke
			(width 0)
			(type solid)
		)
		(fill yes)
		(layer "In8.Cu")
		(net "P12V_MEM_CPU1")
	)
	(gr_poly
		(pts
			(xy 429.760634 -195.399406) (xy 429.772191 -195.398791) (xy 429.792949 -195.388608) (xy 429.800512 -195.379848)
			(xy 429.824565 -195.349943) (xy 429.87775 -195.29461) (xy 429.936226 -195.2449) (xy 429.999401 -195.201318)
			(xy 430.066635 -195.164304) (xy 430.137248 -195.134233) (xy 430.210525 -195.11141) (xy 430.285724 -195.096064)
			(xy 430.362085 -195.088353) (xy 430.438835 -195.088353) (xy 430.515196 -195.096064) (xy 430.590395 -195.11141)
			(xy 430.663672 -195.134233) (xy 430.734285 -195.164304) (xy 430.801519 -195.201318) (xy 430.864694 -195.2449)
			(xy 430.92317 -195.29461) (xy 430.976355 -195.349943) (xy 431.000408 -195.379848) (xy 431.007947 -195.388642)
			(xy 431.028717 -195.398841) (xy 431.040286 -195.399406) (xy 431.964338 -195.399406) (xy 431.974581 -195.398944)
			(xy 431.993451 -195.39097) (xy 432.00774 -195.376291) (xy 432.011836 -195.366894) (xy 432.026355 -195.330391)
			(xy 432.061983 -195.260371) (xy 432.104738 -195.194461) (xy 432.154152 -195.133384) (xy 432.209682 -195.077809)
			(xy 432.27072 -195.028347) (xy 432.336596 -194.985539) (xy 432.406587 -194.949856) (xy 432.479927 -194.921688)
			(xy 432.55581 -194.901344) (xy 432.633405 -194.889048) (xy 432.71186 -194.884934) (xy 432.790315 -194.889048)
			(xy 432.86791 -194.901344) (xy 432.943793 -194.921688) (xy 433.017133 -194.949856) (xy 433.087124 -194.985539)
			(xy 433.153 -195.028347) (xy 433.214038 -195.077809) (xy 433.269568 -195.133384) (xy 433.318982 -195.194461)
			(xy 433.361737 -195.260371) (xy 433.397365 -195.330391) (xy 433.411884 -195.366894) (xy 433.415986 -195.376303)
			(xy 433.430236 -195.391048) (xy 433.449127 -195.399024) (xy 433.459382 -195.399406) (xy 437.311292 -195.399406)
			(xy 437.322709 -195.398945) (xy 437.343334 -195.389159) (xy 437.350916 -195.38061) (xy 437.376437 -195.349765)
			(xy 437.43294 -195.293043) (xy 437.495075 -195.242554) (xy 437.562159 -195.198854) (xy 437.633452 -195.162424)
			(xy 437.70817 -195.133665) (xy 437.785491 -195.112894) (xy 437.864562 -195.100338) (xy 437.944514 -195.096138)
			(xy 438.024466 -195.100338) (xy 438.103537 -195.112894) (xy 438.180858 -195.133665) (xy 438.255576 -195.162424)
			(xy 438.326869 -195.198854) (xy 438.393953 -195.242554) (xy 438.456088 -195.293043) (xy 438.512591 -195.349765)
			(xy 438.538112 -195.38061) (xy 438.545782 -195.389043) (xy 438.566353 -195.398797) (xy 438.577736 -195.399406)
			(xy 439.508392 -195.399406) (xy 439.518628 -195.398934) (xy 439.537482 -195.390949) (xy 439.551754 -195.376269)
			(xy 439.55589 -195.366894) (xy 439.570409 -195.330391) (xy 439.606037 -195.260371) (xy 439.648792 -195.194461)
			(xy 439.698206 -195.133384) (xy 439.753736 -195.077809) (xy 439.814774 -195.028347) (xy 439.88065 -194.985539)
			(xy 439.950641 -194.949856) (xy 440.023981 -194.921688) (xy 440.099864 -194.901344) (xy 440.177459 -194.889048)
			(xy 440.255914 -194.884934) (xy 440.334369 -194.889048) (xy 440.411964 -194.901344) (xy 440.487847 -194.921688)
			(xy 440.561187 -194.949856) (xy 440.631178 -194.985539) (xy 440.697054 -195.028347) (xy 440.758092 -195.077809)
			(xy 440.813622 -195.133384) (xy 440.863036 -195.194461) (xy 440.905791 -195.260371) (xy 440.941419 -195.330391)
			(xy 440.955938 -195.366894) (xy 440.960042 -195.376297) (xy 440.974295 -195.391027) (xy 440.993185 -195.398983)
			(xy 441.003436 -195.399406) (xy 444.856616 -195.399406) (xy 444.867947 -195.398804) (xy 444.888401 -195.389049)
			(xy 444.895986 -195.38061) (xy 444.921516 -195.349923) (xy 444.977972 -195.293482) (xy 445.040017 -195.24325)
			(xy 445.106973 -195.199778) (xy 445.178105 -195.163541) (xy 445.252635 -195.134937) (xy 445.329745 -195.114279)
			(xy 445.408593 -195.101793) (xy 445.488314 -195.097616) (xy 445.568035 -195.101793) (xy 445.646883 -195.114279)
			(xy 445.723993 -195.134937) (xy 445.798523 -195.163541) (xy 445.869655 -195.199778) (xy 445.936611 -195.24325)
			(xy 445.998656 -195.293482) (xy 446.055112 -195.349923) (xy 446.080642 -195.38061) (xy 446.088263 -195.388998)
			(xy 446.108697 -195.398738) (xy 446.120012 -195.399406) (xy 447.052446 -195.399406) (xy 447.062688 -195.398943)
			(xy 447.081555 -195.390967) (xy 447.095842 -195.376287) (xy 447.099944 -195.366894) (xy 447.114463 -195.330391)
			(xy 447.150091 -195.260371) (xy 447.192846 -195.194461) (xy 447.24226 -195.133384) (xy 447.29779 -195.077809)
			(xy 447.358828 -195.028347) (xy 447.424704 -194.985539) (xy 447.494695 -194.949856) (xy 447.568035 -194.921688)
			(xy 447.643918 -194.901344) (xy 447.721513 -194.889048) (xy 447.799968 -194.884934) (xy 447.878423 -194.889048)
			(xy 447.956018 -194.901344) (xy 448.031901 -194.921688) (xy 448.105241 -194.949856) (xy 448.175232 -194.985539)
			(xy 448.241108 -195.028347) (xy 448.302146 -195.077809) (xy 448.357676 -195.133384) (xy 448.40709 -195.194461)
			(xy 448.449845 -195.260371) (xy 448.485473 -195.330391) (xy 448.499992 -195.366894) (xy 448.504094 -195.376302)
			(xy 448.518344 -195.391045) (xy 448.537236 -195.399018) (xy 448.54749 -195.399406) (xy 452.46036 -195.399406)
			(xy 452.470323 -195.398921) (xy 452.488749 -195.391336) (xy 452.496174 -195.384674) (xy 452.524719 -195.357139)
			(xy 452.586582 -195.307502) (xy 452.653265 -195.264557) (xy 452.724046 -195.228769) (xy 452.798162 -195.200525)
			(xy 452.874809 -195.180129) (xy 452.95316 -195.167803) (xy 453.032368 -195.163679) (xy 453.111576 -195.167803)
			(xy 453.189927 -195.180129) (xy 453.266574 -195.200525) (xy 453.34069 -195.228769) (xy 453.411471 -195.264557)
			(xy 453.478154 -195.307502) (xy 453.540017 -195.357139) (xy 453.568562 -195.384674) (xy 453.575968 -195.391367)
			(xy 453.594405 -195.398967) (xy 453.604376 -195.399406) (xy 454.596246 -195.399406) (xy 454.606488 -195.398943)
			(xy 454.625355 -195.390967) (xy 454.639642 -195.376287) (xy 454.643744 -195.366894) (xy 454.657638 -195.3319)
			(xy 454.691474 -195.264632) (xy 454.731883 -195.201097) (xy 454.778459 -195.141932) (xy 454.830732 -195.087736)
			(xy 454.888175 -195.039053) (xy 454.95021 -194.996375) (xy 455.016211 -194.960131) (xy 455.085513 -194.930687)
			(xy 455.157418 -194.90834) (xy 455.231201 -194.893314) (xy 455.306119 -194.885762) (xy 455.343768 -194.88531)
			(xy 455.344784 -194.88531) (xy 455.377331 -194.885684) (xy 455.442177 -194.891372) (xy 455.506287 -194.902656)
			(xy 455.537824 -194.91071) (xy 455.549361 -194.913247) (xy 455.572524 -194.908744) (xy 455.582274 -194.902074)
			(xy 455.645774 -194.853052) (xy 455.654641 -194.845469) (xy 455.664961 -194.82457) (xy 455.665586 -194.81292)
			(xy 455.665586 -182.640986) (xy 455.66516 -182.630917) (xy 455.65744 -182.612318) (xy 455.6506 -182.604918)
			(xy 443.527434 -170.481752) (xy 443.503812 -170.474386) (xy 443.491366 -170.476672) (xy 443.457068 -170.482622)
			(xy 443.387744 -170.48898) (xy 443.352936 -170.489372) (xy 443.313001 -170.488869) (xy 443.233567 -170.480524)
			(xy 443.155441 -170.46392) (xy 443.079479 -170.439241) (xy 443.006512 -170.406756) (xy 442.937341 -170.366822)
			(xy 442.872724 -170.319875) (xy 442.813368 -170.266432) (xy 442.759925 -170.207076) (xy 442.712978 -170.142459)
			(xy 442.673044 -170.073288) (xy 442.640559 -170.000321) (xy 442.61588 -169.924359) (xy 442.599276 -169.846233)
			(xy 442.590931 -169.766799) (xy 442.590428 -169.726864) (xy 442.590839 -169.692057) (xy 442.597196 -169.622734)
			(xy 442.603128 -169.588434) (xy 442.605414 -169.575988) (xy 442.598048 -169.552366) (xy 440.622436 -167.576754)
			(xy 440.614283 -167.569395) (xy 440.593695 -167.561809) (xy 440.571818 -167.563486) (xy 440.561984 -167.568372)
			(xy 440.528032 -167.586599) (xy 440.457176 -167.616906) (xy 440.383625 -167.639909) (xy 440.308127 -167.655374)
			(xy 440.231455 -167.663142) (xy 440.192922 -167.663622) (xy 440.152986 -167.663118) (xy 440.073552 -167.654772)
			(xy 439.995425 -167.638168) (xy 439.919461 -167.613488) (xy 439.846494 -167.581003) (xy 439.777322 -167.541069)
			(xy 439.712703 -167.494123) (xy 439.653346 -167.44068) (xy 439.5999 -167.381325) (xy 439.552951 -167.316708)
			(xy 439.513013 -167.247538) (xy 439.480525 -167.174572) (xy 439.455842 -167.09861) (xy 439.439234 -167.020484)
			(xy 439.430883 -166.94105) (xy 439.430414 -166.901114) (xy 439.430897 -166.862581) (xy 439.438666 -166.785909)
			(xy 439.454128 -166.71041) (xy 439.477124 -166.636856) (xy 439.50742 -166.565995) (xy 439.525664 -166.532052)
			(xy 439.53052 -166.522205) (xy 439.532207 -166.500336) (xy 439.52464 -166.479749) (xy 439.517282 -166.4716)
			(xy 424.576748 -151.531066) (xy 424.56935 -151.52422) (xy 424.550751 -151.516495) (xy 424.54068 -151.51608)
			(xy 388.39902 -151.51608) (xy 388.388956 -151.516517) (xy 388.370371 -151.52425) (xy 388.362952 -151.531066)
			(xy 387.161532 -152.73274) (xy 387.154549 -152.740334) (xy 387.146828 -152.759444) (xy 387.147301 -152.780049)
			(xy 387.151118 -152.789636) (xy 387.18998 -152.87625) (xy 387.194653 -152.885367) (xy 387.209737 -152.899204)
			(xy 387.229012 -152.906092) (xy 387.239256 -152.905968) (xy 387.23951 -152.905968) (xy 387.293358 -152.904444)
			(xy 387.293866 -152.904444) (xy 387.332117 -152.904855) (xy 387.408338 -152.911422) (xy 387.483715 -152.924502)
			(xy 387.557692 -152.943999) (xy 387.59384 -152.956514) (xy 387.602156 -152.9591) (xy 387.61956 -152.9591)
			(xy 387.627876 -152.956514) (xy 387.663995 -152.94401) (xy 387.737905 -152.924506) (xy 387.813218 -152.911426)
			(xy 387.889376 -152.904866) (xy 387.927596 -152.904444) (xy 387.928358 -152.904444) (xy 387.969466 -152.904917)
			(xy 388.051331 -152.912498) (xy 388.132148 -152.927599) (xy 388.211228 -152.950091) (xy 388.287895 -152.979783)
			(xy 388.361495 -153.016421) (xy 388.431402 -153.059693) (xy 388.497019 -153.10923) (xy 388.557786 -153.164609)
			(xy 388.613185 -153.225358) (xy 388.662743 -153.290958) (xy 388.706037 -153.360851) (xy 388.7427 -153.43444)
			(xy 388.772417 -153.511097) (xy 388.794935 -153.590169) (xy 388.810062 -153.670981) (xy 388.81767 -153.752844)
			(xy 388.81812 -153.793952) (xy 388.817682 -153.83224) (xy 388.811055 -153.908528) (xy 388.797904 -153.983967)
			(xy 388.778327 -154.057998) (xy 388.765796 -154.09418) (xy 388.763135 -154.102617) (xy 388.763119 -154.120294)
			(xy 388.765796 -154.128724) (xy 388.778362 -154.164895) (xy 388.797952 -154.238926) (xy 388.811098 -154.314369)
			(xy 388.817701 -154.390662) (xy 388.81812 -154.428952) (xy 388.817668 -154.468869) (xy 388.810472 -154.548377)
			(xy 388.796169 -154.626919) (xy 388.774876 -154.70386) (xy 388.761224 -154.741372) (xy 388.758387 -154.750041)
			(xy 388.75837 -154.768269) (xy 388.761224 -154.776932) (xy 388.774842 -154.814455) (xy 388.796115 -154.891398)
			(xy 388.810421 -154.969935) (xy 388.817645 -155.049438) (xy 388.81812 -155.089352) (xy 388.817682 -155.12764)
			(xy 388.811055 -155.203928) (xy 388.797904 -155.279367) (xy 388.778327 -155.353398) (xy 388.765796 -155.38958)
			(xy 388.763135 -155.398017) (xy 388.763119 -155.415694) (xy 388.765796 -155.424124) (xy 388.778362 -155.460295)
			(xy 388.797952 -155.534326) (xy 388.811098 -155.609769) (xy 388.817701 -155.686062) (xy 388.81812 -155.724352)
			(xy 388.817711 -155.763146) (xy 388.81095 -155.840438) (xy 388.797477 -155.916847) (xy 388.777393 -155.99179)
			(xy 388.764526 -156.02839) (xy 388.761869 -156.036827) (xy 388.761857 -156.054502) (xy 388.764526 -156.062934)
			(xy 388.777385 -156.099536) (xy 388.797452 -156.174482) (xy 388.810924 -156.25089) (xy 388.8177 -156.328179)
			(xy 388.81812 -156.366972) (xy 388.817686 -156.40526) (xy 388.811065 -156.481551) (xy 388.79792 -156.556992)
			(xy 388.77835 -156.631026) (xy 388.765796 -156.6672) (xy 388.763138 -156.675637) (xy 388.763129 -156.693311)
			(xy 388.765796 -156.701744) (xy 388.778365 -156.737915) (xy 388.797962 -156.811945) (xy 388.811114 -156.887387)
			(xy 388.817725 -156.963682) (xy 388.81812 -157.001972) (xy 388.817661 -157.043076) (xy 388.810078 -157.124934)
			(xy 388.794975 -157.205743) (xy 388.77248 -157.284814) (xy 388.742785 -157.361472) (xy 388.706143 -157.435063)
			(xy 388.662868 -157.504959) (xy 388.613328 -157.570564) (xy 388.557946 -157.631318) (xy 388.497194 -157.686702)
			(xy 388.431592 -157.736245) (xy 388.361698 -157.779524) (xy 388.288108 -157.816169) (xy 388.211452 -157.845867)
			(xy 388.132382 -157.868366) (xy 388.051574 -157.883473) (xy 387.969716 -157.891059) (xy 387.928612 -157.89148)
			(xy 387.92785 -157.89148) (xy 387.889599 -157.891065) (xy 387.813381 -157.88449) (xy 387.738007 -157.871402)
			(xy 387.664033 -157.851898) (xy 387.627876 -157.83941) (xy 387.61956 -157.836824) (xy 387.602156 -157.836824)
			(xy 387.59384 -157.83941) (xy 387.557721 -157.851915) (xy 387.483811 -157.871419) (xy 387.408498 -157.8845)
			(xy 387.33234 -157.891061) (xy 387.29412 -157.89148) (xy 387.293358 -157.89148) (xy 387.252252 -157.891004)
			(xy 387.170391 -157.883416) (xy 387.08958 -157.868309) (xy 387.010506 -157.845812) (xy 386.933845 -157.816116)
			(xy 386.86025 -157.779476) (xy 386.790349 -157.736202) (xy 386.724738 -157.686665) (xy 386.663976 -157.631287)
			(xy 386.608582 -157.570539) (xy 386.559028 -157.504941) (xy 386.515736 -157.435051) (xy 386.479077 -157.361466)
			(xy 386.449361 -157.284812) (xy 386.426844 -157.205744) (xy 386.411716 -157.124936) (xy 386.404107 -157.043078)
			(xy 386.403596 -157.001972) (xy 386.404033 -156.963684) (xy 386.410659 -156.887395) (xy 386.423808 -156.811956)
			(xy 386.443383 -156.737924) (xy 386.45592 -156.701744) (xy 386.458567 -156.693308) (xy 386.458558 -156.67564)
			(xy 386.45592 -156.6672) (xy 386.443353 -156.631029) (xy 386.42376 -156.556998) (xy 386.410613 -156.481556)
			(xy 386.404007 -156.405262) (xy 386.403596 -156.366972) (xy 386.404004 -156.328178) (xy 386.410763 -156.250885)
			(xy 386.424234 -156.174476) (xy 386.444317 -156.099532) (xy 386.45719 -156.062934) (xy 386.459833 -156.054497)
			(xy 386.459821 -156.036832) (xy 386.45719 -156.02839) (xy 386.444334 -155.991787) (xy 386.424273 -155.916841)
			(xy 386.410807 -155.840433) (xy 386.404038 -155.763144) (xy 386.403596 -155.724352) (xy 386.404033 -155.686064)
			(xy 386.410661 -155.609776) (xy 386.423812 -155.534337) (xy 386.443388 -155.460306) (xy 386.45592 -155.424124)
			(xy 386.458564 -155.415688) (xy 386.458548 -155.398023) (xy 386.45592 -155.38958) (xy 386.443354 -155.353409)
			(xy 386.423763 -155.279378) (xy 386.410617 -155.203936) (xy 386.404013 -155.127642) (xy 386.403596 -155.089352)
			(xy 386.404048 -155.049435) (xy 386.411244 -154.969927) (xy 386.425546 -154.891385) (xy 386.446839 -154.814444)
			(xy 386.460492 -154.776932) (xy 386.463312 -154.768263) (xy 386.463296 -154.750047) (xy 386.460492 -154.741372)
			(xy 386.446873 -154.70385) (xy 386.4256 -154.626906) (xy 386.411294 -154.548369) (xy 386.404069 -154.468866)
			(xy 386.403596 -154.428952) (xy 386.404033 -154.390664) (xy 386.410661 -154.314376) (xy 386.423812 -154.238937)
			(xy 386.443388 -154.164906) (xy 386.45592 -154.128724) (xy 386.458564 -154.120288) (xy 386.458548 -154.102623)
			(xy 386.45592 -154.09418) (xy 386.443354 -154.058009) (xy 386.423763 -153.983978) (xy 386.410617 -153.908536)
			(xy 386.404013 -153.832242) (xy 386.403596 -153.793952) (xy 386.405374 -153.740358) (xy 386.405578 -153.730064)
			(xy 386.398747 -153.71066) (xy 386.384825 -153.695517) (xy 386.375656 -153.690828) (xy 386.289042 -153.651712)
			(xy 386.279459 -153.647936) (xy 386.258883 -153.647541) (xy 386.239788 -153.655217) (xy 386.232146 -153.662126)
			(xy 382.421384 -157.472888) (xy 382.418082 -157.478476) (xy 382.397756 -157.512516) (xy 382.351079 -157.576608)
			(xy 382.298002 -157.63551) (xy 382.2391 -157.688586) (xy 382.175007 -157.735262) (xy 382.140968 -157.75559)
			(xy 382.13538 -157.758892) (xy 380.896114 -158.997904) (xy 380.878073 -159.015163) (xy 380.836579 -159.042917)
			(xy 380.79046 -159.062026) (xy 380.741497 -159.071752) (xy 380.716536 -159.072326) (xy 365.43742 -159.072326)
			(xy 365.412466 -159.071707) (xy 365.36352 -159.061957) (xy 365.317416 -159.042847) (xy 365.275924 -159.015112)
			(xy 365.257842 -158.997904) (xy 360.934 -154.674062) (xy 360.916737 -154.656022) (xy 360.888974 -154.61453)
			(xy 360.869857 -154.568412) (xy 360.860121 -154.519446) (xy 360.859578 -154.494484) (xy 360.859578 -153.646378)
			(xy 360.859061 -153.635874) (xy 360.850671 -153.616615) (xy 360.835294 -153.602302) (xy 360.825542 -153.598372)
			(xy 360.735118 -153.566876) (xy 360.725083 -153.563904) (xy 360.704231 -153.56541) (xy 360.685684 -153.57506)
			(xy 360.67873 -153.582878) (xy 360.678476 -153.583132) (xy 360.645507 -153.623747) (xy 360.57438 -153.700469)
			(xy 360.497716 -153.771659) (xy 360.415944 -153.836918) (xy 360.329522 -153.89588) (xy 360.238933 -153.948216)
			(xy 360.144686 -153.993633) (xy 360.047306 -154.031876) (xy 359.94734 -154.062731) (xy 359.845346 -154.086026)
			(xy 359.741897 -154.101631) (xy 359.63757 -154.109457) (xy 359.58526 -154.109928) (xy 359.532987 -154.109438)
			(xy 359.428735 -154.101622) (xy 359.325358 -154.086038) (xy 359.223434 -154.062772) (xy 359.123535 -154.031955)
			(xy 359.026217 -153.993758) (xy 358.932026 -153.948395) (xy 358.841488 -153.896121) (xy 358.75511 -153.837227)
			(xy 358.673375 -153.772043) (xy 358.596739 -153.700933) (xy 358.525631 -153.624295) (xy 358.460449 -153.542558)
			(xy 358.401558 -153.456178) (xy 358.349286 -153.365639) (xy 358.303926 -153.271446) (xy 358.265732 -153.174128)
			(xy 358.234918 -153.074227) (xy 358.211654 -152.972303) (xy 358.196073 -152.868925) (xy 358.188261 -152.764673)
			(xy 358.188261 -152.660127) (xy 358.196073 -152.555875) (xy 358.211654 -152.452497) (xy 358.234918 -152.350573)
			(xy 358.265732 -152.250672) (xy 358.303926 -152.153354) (xy 358.349286 -152.059161) (xy 358.401558 -151.968622)
			(xy 358.460449 -151.882242) (xy 358.525631 -151.800505) (xy 358.596739 -151.723867) (xy 358.673375 -151.652757)
			(xy 358.75511 -151.587573) (xy 358.841488 -151.528679) (xy 358.932026 -151.476405) (xy 359.026217 -151.431042)
			(xy 359.123535 -151.392845) (xy 359.223434 -151.362028) (xy 359.325358 -151.338762) (xy 359.428735 -151.323178)
			(xy 359.532987 -151.315362) (xy 359.58526 -151.314912) (xy 359.637571 -151.315388) (xy 359.741899 -151.323208)
			(xy 359.84535 -151.338807) (xy 359.947346 -151.362098) (xy 360.047314 -151.39295) (xy 360.144696 -151.431191)
			(xy 360.238946 -151.476607) (xy 360.329536 -151.528942) (xy 360.415959 -151.587905) (xy 360.497731 -151.653165)
			(xy 360.574394 -151.724357) (xy 360.64552 -151.801082) (xy 360.678476 -151.841708) (xy 360.67873 -151.841962)
			(xy 360.685686 -151.849788) (xy 360.704221 -151.859484) (xy 360.725085 -151.860964) (xy 360.735118 -151.857964)
			(xy 360.825542 -151.826468) (xy 360.835294 -151.822524) (xy 360.850704 -151.808239) (xy 360.859084 -151.78897)
			(xy 360.859578 -151.778462) (xy 360.859578 -151.095202) (xy 360.859155 -151.085132) (xy 360.851438 -151.066529)
			(xy 360.844592 -151.059134) (xy 344.771218 -134.98576) (xy 344.763818 -134.97892) (xy 344.745219 -134.971206)
			(xy 344.73515 -134.970774) (xy 331.344016 -134.970774) (xy 331.333594 -134.971282) (xy 331.314456 -134.979546)
			(xy 331.306932 -134.986776) (xy 331.287176 -135.006975) (xy 331.242767 -135.041906) (xy 331.193691 -135.0699)
			(xy 331.14102 -135.090346) (xy 331.085909 -135.102795) (xy 331.029564 -135.106976) (xy 330.973219 -135.102795)
			(xy 330.918108 -135.090346) (xy 330.865437 -135.0699) (xy 330.816361 -135.041906) (xy 330.771952 -135.006975)
			(xy 330.752196 -134.986776) (xy 330.744696 -134.97951) (xy 330.725544 -134.971244) (xy 330.715112 -134.970774)
			(xy 330.12888 -134.970774) (xy 330.118974 -134.975092) (xy 330.094692 -134.985272) (xy 330.044033 -134.999625)
			(xy 329.991884 -135.006895) (xy 329.965558 -135.00735) (xy 329.96505 -135.00735) (xy 329.938721 -135.006914)
			(xy 329.886565 -134.999671) (xy 329.835906 -134.985302) (xy 329.811634 -134.975092) (xy 329.801728 -134.970774)
			(xy 307.89245 -134.970774) (xy 307.882383 -134.971206) (xy 307.86379 -134.97893) (xy 307.856382 -134.98576)
			(xy 296.820844 -146.021298) (xy 296.813992 -146.028694) (xy 296.80625 -146.047293) (xy 296.805858 -146.057366)
			(xy 296.805858 -146.996658) (xy 296.806133 -147.004621) (xy 296.811061 -147.019765) (xy 296.81551 -147.026376)
			(xy 296.838368 -147.058913) (xy 296.877954 -147.12788) (xy 296.910152 -147.200591) (xy 296.93461 -147.276257)
			(xy 296.951065 -147.354057) (xy 296.959336 -147.433146) (xy 296.959336 -147.512667) (xy 296.951063 -147.591756)
			(xy 296.934607 -147.669555) (xy 296.910147 -147.745221) (xy 296.877948 -147.817931) (xy 296.838361 -147.886898)
			(xy 296.81551 -147.91944) (xy 296.811101 -147.92607) (xy 296.806179 -147.941203) (xy 296.805858 -147.949158)
			(xy 296.805858 -169.490898) (xy 296.806103 -169.49808) (xy 296.8101 -169.511876) (xy 296.813732 -169.518076)
			(xy 296.834433 -169.551491) (xy 296.869612 -169.621788) (xy 296.897369 -169.695334) (xy 296.917408 -169.771345)
			(xy 296.929516 -169.849016) (xy 296.933565 -169.92752) (xy 296.929512 -170.006024) (xy 296.9174 -170.083694)
			(xy 296.897357 -170.159705) (xy 296.869596 -170.233249) (xy 296.834413 -170.303544) (xy 296.813732 -170.336972)
			(xy 296.810101 -170.343172) (xy 296.80611 -170.356969) (xy 296.805858 -170.36415) (xy 296.805858 -176.49063)
			(xy 296.805284 -176.515589) (xy 296.795538 -176.564547) (xy 296.776428 -176.610662) (xy 296.748688 -176.652162)
			(xy 296.731436 -176.670208) (xy 291.987986 -181.413658) (xy 291.969945 -181.430919) (xy 291.928452 -181.45868)
			(xy 291.882334 -181.477797) (xy 291.83337 -181.487534) (xy 291.808408 -181.48808) (xy 266.202922 -181.48808)
			(xy 266.192858 -181.488517) (xy 266.174272 -181.496249) (xy 266.166854 -181.503066) (xy 264.099802 -183.570118)
			(xy 264.092958 -183.577518) (xy 264.08523 -183.596115) (xy 264.084816 -183.606186) (xy 264.084816 -193.108834)
			(xy 264.08538 -193.12046) (xy 264.095557 -193.141368) (xy 264.104374 -193.148966) (xy 264.16762 -193.198242)
			(xy 264.177009 -193.204917) (xy 264.199493 -193.209832) (xy 264.2108 -193.20764) (xy 264.211054 -193.20764)
			(xy 264.255667 -193.19721) (xy 264.3466 -193.185998) (xy 264.39241 -193.185288) (xy 264.429979 -193.185743)
			(xy 264.50474 -193.193248) (xy 264.578376 -193.208191) (xy 264.650148 -193.230424) (xy 264.719337 -193.259723)
			(xy 264.785249 -193.295795) (xy 264.847224 -193.338277) (xy 264.904639 -193.386743) (xy 264.95692 -193.440709)
			(xy 265.003542 -193.499632) (xy 265.044037 -193.562923) (xy 265.078 -193.629945) (xy 265.091926 -193.66484)
			(xy 265.096012 -193.674201) (xy 265.110185 -193.688885) (xy 265.128966 -193.696867) (xy 265.13917 -193.697352)
			(xy 265.98372 -193.697352) (xy 265.993241 -193.696953) (xy 266.010966 -193.689994) (xy 266.024927 -193.677044)
			(xy 266.02944 -193.66865) (xy 266.046527 -193.634562) (xy 266.086642 -193.569712) (xy 266.133133 -193.509268)
			(xy 266.185519 -193.453855) (xy 266.24326 -193.404047) (xy 266.305758 -193.360356) (xy 266.372368 -193.323236)
			(xy 266.442403 -193.293069) (xy 266.515137 -193.270166) (xy 266.589821 -193.254765) (xy 266.665682 -193.247025)
			(xy 266.741938 -193.247025) (xy 266.817799 -193.254765) (xy 266.892483 -193.270166) (xy 266.965217 -193.293069)
			(xy 267.035252 -193.323236) (xy 267.101862 -193.360356) (xy 267.16436 -193.404047) (xy 267.222101 -193.453855)
			(xy 267.274487 -193.509268) (xy 267.320978 -193.569712) (xy 267.361093 -193.634562) (xy 267.37818 -193.66865)
			(xy 267.382678 -193.677055) (xy 267.396648 -193.690008) (xy 267.414376 -193.696982) (xy 267.4239 -193.697352)
			(xy 268.26083 -193.697352) (xy 268.268241 -193.697093) (xy 268.282435 -193.692826) (xy 268.28877 -193.68897)
			(xy 268.311525 -193.674442) (xy 268.360387 -193.651481) (xy 268.412075 -193.635896) (xy 268.465484 -193.628019)
			(xy 268.519472 -193.628019) (xy 268.572881 -193.635896) (xy 268.624569 -193.651481) (xy 268.673431 -193.674442)
			(xy 268.696186 -193.68897) (xy 268.702514 -193.692841) (xy 268.716713 -193.697114) (xy 268.724126 -193.697352)
			(xy 270.044418 -193.697352) (xy 270.054611 -193.696842) (xy 270.073362 -193.688829) (xy 270.087548 -193.674179)
			(xy 270.091662 -193.66484) (xy 270.105643 -193.629972) (xy 270.139617 -193.562965) (xy 270.180119 -193.499689)
			(xy 270.226743 -193.440779) (xy 270.279022 -193.386825) (xy 270.336432 -193.338366) (xy 270.398399 -193.295889)
			(xy 270.464301 -193.259818) (xy 270.533479 -193.230516) (xy 270.60524 -193.208276) (xy 270.678864 -193.19332)
			(xy 270.753614 -193.185798) (xy 270.791178 -193.185288) (xy 270.830686 -193.185796) (xy 270.909263 -193.194103)
			(xy 270.986531 -193.210626) (xy 271.061633 -193.235184) (xy 271.133736 -193.267503) (xy 271.202041 -193.307226)
			(xy 271.265789 -193.353911) (xy 271.295368 -193.380106) (xy 271.295622 -193.38036) (xy 271.302866 -193.386268)
			(xy 271.320319 -193.392922) (xy 271.329658 -193.393314) (xy 271.397984 -193.393314) (xy 271.407339 -193.392998)
			(xy 271.424818 -193.386339) (xy 271.43202 -193.38036) (xy 271.432274 -193.380106) (xy 271.461859 -193.35392)
			(xy 271.525608 -193.307239) (xy 271.593912 -193.267521) (xy 271.666015 -193.235206) (xy 271.741116 -193.210653)
			(xy 271.818382 -193.194134) (xy 271.896958 -193.185831) (xy 271.936464 -193.185288) (xy 271.974031 -193.185745)
			(xy 272.048789 -193.193255) (xy 272.122421 -193.208203) (xy 272.194189 -193.230439) (xy 272.263374 -193.259741)
			(xy 272.329282 -193.295815) (xy 272.391252 -193.338298) (xy 272.448663 -193.386765) (xy 272.500939 -193.440731)
			(xy 272.547557 -193.499654) (xy 272.588049 -193.562943) (xy 272.622009 -193.629965) (xy 272.63598 -193.66484)
			(xy 272.640064 -193.674206) (xy 272.654234 -193.688903) (xy 272.673017 -193.696902) (xy 272.683224 -193.697352)
			(xy 273.527774 -193.697352) (xy 273.5373 -193.696961) (xy 273.555038 -193.690012) (xy 273.569012 -193.677064)
			(xy 273.573494 -193.66865) (xy 273.590581 -193.634562) (xy 273.630696 -193.569712) (xy 273.677187 -193.509268)
			(xy 273.729573 -193.453855) (xy 273.787314 -193.404047) (xy 273.849812 -193.360356) (xy 273.916422 -193.323236)
			(xy 273.986457 -193.293069) (xy 274.059191 -193.270166) (xy 274.133875 -193.254765) (xy 274.209736 -193.247025)
			(xy 274.285992 -193.247025) (xy 274.361853 -193.254765) (xy 274.436537 -193.270166) (xy 274.509271 -193.293069)
			(xy 274.579306 -193.323236) (xy 274.645916 -193.360356) (xy 274.708414 -193.404047) (xy 274.766155 -193.453855)
			(xy 274.818541 -193.509268) (xy 274.865032 -193.569712) (xy 274.905147 -193.634562) (xy 274.922234 -193.66865)
			(xy 274.926735 -193.677049) (xy 274.940707 -193.689987) (xy 274.958433 -193.696943) (xy 274.967954 -193.697352)
			(xy 275.804884 -193.697352) (xy 275.812297 -193.6971) (xy 275.826499 -193.692843) (xy 275.832824 -193.68897)
			(xy 275.855579 -193.674442) (xy 275.904441 -193.651481) (xy 275.956129 -193.635896) (xy 276.009538 -193.628019)
			(xy 276.063526 -193.628019) (xy 276.116935 -193.635896) (xy 276.168623 -193.651481) (xy 276.217485 -193.674442)
			(xy 276.24024 -193.68897) (xy 276.24657 -193.692834) (xy 276.260768 -193.697092) (xy 276.26818 -193.697352)
			(xy 277.588472 -193.697352) (xy 277.598659 -193.696833) (xy 277.617393 -193.688808) (xy 277.631562 -193.674158)
			(xy 277.635716 -193.66484) (xy 277.649696 -193.629971) (xy 277.68367 -193.562961) (xy 277.724171 -193.499683)
			(xy 277.770794 -193.44077) (xy 277.823072 -193.386812) (xy 277.880482 -193.33835) (xy 277.942449 -193.295869)
			(xy 278.008351 -193.259795) (xy 278.077529 -193.230489) (xy 278.14929 -193.208244) (xy 278.222916 -193.193284)
			(xy 278.297667 -193.185757) (xy 278.335232 -193.185288) (xy 278.374739 -193.185798) (xy 278.453313 -193.194111)
			(xy 278.530578 -193.210639) (xy 278.605677 -193.235201) (xy 278.677776 -193.267524) (xy 278.746077 -193.307249)
			(xy 278.809821 -193.353937) (xy 278.839422 -193.380106) (xy 278.84628 -193.386456) (xy 278.86406 -193.393314)
			(xy 278.951436 -193.393314) (xy 278.969216 -193.386456) (xy 278.976074 -193.380106) (xy 279.005659 -193.35392)
			(xy 279.069408 -193.307239) (xy 279.137712 -193.267521) (xy 279.209815 -193.235206) (xy 279.284916 -193.210653)
			(xy 279.362182 -193.194134) (xy 279.440758 -193.185831) (xy 279.480264 -193.185288) (xy 279.517831 -193.185745)
			(xy 279.592589 -193.193255) (xy 279.666221 -193.208203) (xy 279.737989 -193.230439) (xy 279.807174 -193.259741)
			(xy 279.873082 -193.295815) (xy 279.935052 -193.338298) (xy 279.992463 -193.386765) (xy 280.044739 -193.440731)
			(xy 280.091357 -193.499654) (xy 280.131849 -193.562943) (xy 280.165809 -193.629965) (xy 280.17978 -193.66484)
			(xy 280.183864 -193.674206) (xy 280.198034 -193.688903) (xy 280.216817 -193.696902) (xy 280.227024 -193.697352)
			(xy 281.071574 -193.697352) (xy 281.0811 -193.696961) (xy 281.098838 -193.690012) (xy 281.112812 -193.677064)
			(xy 281.117294 -193.66865) (xy 281.134381 -193.634562) (xy 281.174496 -193.569712) (xy 281.220987 -193.509268)
			(xy 281.273373 -193.453855) (xy 281.331114 -193.404047) (xy 281.393612 -193.360356) (xy 281.460222 -193.323236)
			(xy 281.530257 -193.293069) (xy 281.602991 -193.270166) (xy 281.677675 -193.254765) (xy 281.753536 -193.247025)
			(xy 281.829792 -193.247025) (xy 281.905653 -193.254765) (xy 281.980337 -193.270166) (xy 282.053071 -193.293069)
			(xy 282.123106 -193.323236) (xy 282.189716 -193.360356) (xy 282.252214 -193.404047) (xy 282.309955 -193.453855)
			(xy 282.362341 -193.509268) (xy 282.408832 -193.569712) (xy 282.448947 -193.634562) (xy 282.466034 -193.66865)
			(xy 282.470535 -193.677049) (xy 282.484507 -193.689987) (xy 282.502233 -193.696943) (xy 282.511754 -193.697352)
			(xy 283.348938 -193.697352) (xy 283.356353 -193.697106) (xy 283.370562 -193.69286) (xy 283.376878 -193.68897)
			(xy 283.399633 -193.674442) (xy 283.448495 -193.651481) (xy 283.500183 -193.635896) (xy 283.553592 -193.628019)
			(xy 283.60758 -193.628019) (xy 283.660989 -193.635896) (xy 283.712677 -193.651481) (xy 283.761539 -193.674442)
			(xy 283.784294 -193.68897) (xy 283.790622 -193.69284) (xy 283.804821 -193.697111) (xy 283.812234 -193.697352)
			(xy 285.132272 -193.697352) (xy 285.142459 -193.696833) (xy 285.161193 -193.688808) (xy 285.175362 -193.674158)
			(xy 285.179516 -193.66484) (xy 285.193496 -193.629971) (xy 285.22747 -193.562961) (xy 285.267971 -193.499683)
			(xy 285.314594 -193.44077) (xy 285.366872 -193.386812) (xy 285.424282 -193.33835) (xy 285.486249 -193.295869)
			(xy 285.552151 -193.259795) (xy 285.621329 -193.230489) (xy 285.69309 -193.208244) (xy 285.766716 -193.193284)
			(xy 285.841467 -193.185757) (xy 285.879032 -193.185288) (xy 285.918539 -193.185798) (xy 285.997113 -193.194111)
			(xy 286.074378 -193.210639) (xy 286.149477 -193.235201) (xy 286.221576 -193.267524) (xy 286.289877 -193.307249)
			(xy 286.353621 -193.353937) (xy 286.383222 -193.380106) (xy 286.383476 -193.38036) (xy 286.390723 -193.38626)
			(xy 286.408176 -193.392895) (xy 286.417512 -193.393314) (xy 286.485838 -193.393314) (xy 286.495196 -193.393006)
			(xy 286.512686 -193.386359) (xy 286.519874 -193.38036) (xy 286.520128 -193.380106) (xy 286.549713 -193.353918)
			(xy 286.613461 -193.307233) (xy 286.681764 -193.267511) (xy 286.753866 -193.235192) (xy 286.828967 -193.210634)
			(xy 286.906235 -193.19411) (xy 286.984811 -193.185803) (xy 287.024318 -193.185288) (xy 287.061886 -193.185743)
			(xy 287.136647 -193.193249) (xy 287.210282 -193.208193) (xy 287.282054 -193.230427) (xy 287.351242 -193.259726)
			(xy 287.417154 -193.295798) (xy 287.479128 -193.33828) (xy 287.536543 -193.386747) (xy 287.588823 -193.440712)
			(xy 287.635444 -193.499635) (xy 287.675939 -193.562926) (xy 287.709902 -193.629948) (xy 287.723834 -193.66484)
			(xy 287.727921 -193.6742) (xy 287.742093 -193.688882) (xy 287.760875 -193.696861) (xy 287.771078 -193.697352)
			(xy 288.615628 -193.697352) (xy 288.625148 -193.696952) (xy 288.642871 -193.689991) (xy 288.656829 -193.67704)
			(xy 288.661348 -193.66865) (xy 288.678435 -193.634562) (xy 288.71855 -193.569712) (xy 288.765041 -193.509268)
			(xy 288.817427 -193.453855) (xy 288.875168 -193.404047) (xy 288.937666 -193.360356) (xy 289.004276 -193.323236)
			(xy 289.074311 -193.293069) (xy 289.147045 -193.270166) (xy 289.221729 -193.254765) (xy 289.29759 -193.247025)
			(xy 289.373846 -193.247025) (xy 289.449707 -193.254765) (xy 289.524391 -193.270166) (xy 289.597125 -193.293069)
			(xy 289.66716 -193.323236) (xy 289.73377 -193.360356) (xy 289.796268 -193.404047) (xy 289.854009 -193.453855)
			(xy 289.906395 -193.509268) (xy 289.952886 -193.569712) (xy 289.993001 -193.634562) (xy 290.010088 -193.66865)
			(xy 290.014587 -193.677054) (xy 290.028556 -193.690005) (xy 290.046284 -193.696977) (xy 290.055808 -193.697352)
			(xy 290.892992 -193.697352) (xy 290.900405 -193.697099) (xy 290.914605 -193.69284) (xy 290.920932 -193.68897)
			(xy 290.943687 -193.674442) (xy 290.992549 -193.651481) (xy 291.044237 -193.635896) (xy 291.097646 -193.628019)
			(xy 291.151634 -193.628019) (xy 291.205043 -193.635896) (xy 291.256731 -193.651481) (xy 291.305593 -193.674442)
			(xy 291.328348 -193.68897) (xy 291.334678 -193.692833) (xy 291.348877 -193.697088) (xy 291.356288 -193.697352)
			(xy 292.676326 -193.697352) (xy 292.686518 -193.696841) (xy 292.705267 -193.688826) (xy 292.71945 -193.674176)
			(xy 292.72357 -193.66484) (xy 292.737551 -193.629972) (xy 292.771525 -193.562965) (xy 292.812027 -193.49969)
			(xy 292.858651 -193.440781) (xy 292.910931 -193.386827) (xy 292.968341 -193.338369) (xy 293.030308 -193.295892)
			(xy 293.09621 -193.259823) (xy 293.165388 -193.230521) (xy 293.237148 -193.208281) (xy 293.310772 -193.193326)
			(xy 293.385522 -193.185805) (xy 293.423086 -193.185288) (xy 293.462593 -193.185796) (xy 293.54117 -193.194104)
			(xy 293.618438 -193.210628) (xy 293.693539 -193.235187) (xy 293.765642 -193.267506) (xy 293.833946 -193.307229)
			(xy 293.897694 -193.353914) (xy 293.927276 -193.380106) (xy 293.92753 -193.38036) (xy 293.934775 -193.386266)
			(xy 293.952228 -193.392917) (xy 293.961566 -193.393314) (xy 294.029892 -193.393314) (xy 294.039246 -193.392996)
			(xy 294.056723 -193.386335) (xy 294.063928 -193.38036) (xy 294.064182 -193.380106) (xy 294.093767 -193.35392)
			(xy 294.157516 -193.30724) (xy 294.225821 -193.267523) (xy 294.297923 -193.235209) (xy 294.373024 -193.210656)
			(xy 294.450291 -193.194138) (xy 294.528866 -193.185836) (xy 294.568372 -193.185288) (xy 294.605939 -193.185746)
			(xy 294.680696 -193.193256) (xy 294.754328 -193.208205) (xy 294.826095 -193.230442) (xy 294.895279 -193.259744)
			(xy 294.961186 -193.295818) (xy 295.023156 -193.338301) (xy 295.080566 -193.386769) (xy 295.132842 -193.440734)
			(xy 295.179459 -193.499657) (xy 295.219951 -193.562946) (xy 295.25391 -193.629967) (xy 295.267888 -193.66484)
			(xy 295.271973 -193.674205) (xy 295.286143 -193.6889) (xy 295.304926 -193.696896) (xy 295.315132 -193.697352)
			(xy 296.159682 -193.697352) (xy 296.169207 -193.69696) (xy 296.186943 -193.690009) (xy 296.200915 -193.67706)
			(xy 296.205402 -193.66865) (xy 296.222489 -193.634562) (xy 296.262604 -193.569712) (xy 296.309095 -193.509268)
			(xy 296.361481 -193.453855) (xy 296.419222 -193.404047) (xy 296.48172 -193.360356) (xy 296.54833 -193.323236)
			(xy 296.618365 -193.293069) (xy 296.691099 -193.270166) (xy 296.765783 -193.254765) (xy 296.841644 -193.247025)
			(xy 296.9179 -193.247025) (xy 296.993761 -193.254765) (xy 297.068445 -193.270166) (xy 297.141179 -193.293069)
			(xy 297.211214 -193.323236) (xy 297.277824 -193.360356) (xy 297.340322 -193.404047) (xy 297.398063 -193.453855)
			(xy 297.450449 -193.509268) (xy 297.49694 -193.569712) (xy 297.537055 -193.634562) (xy 297.554142 -193.66865)
			(xy 297.558643 -193.677048) (xy 297.572616 -193.689984) (xy 297.590342 -193.696937) (xy 297.599862 -193.697352)
			(xy 298.436792 -193.697352) (xy 298.444205 -193.697099) (xy 298.458405 -193.69284) (xy 298.464732 -193.68897)
			(xy 298.487487 -193.674442) (xy 298.536349 -193.651481) (xy 298.588037 -193.635896) (xy 298.641446 -193.628019)
			(xy 298.695434 -193.628019) (xy 298.748843 -193.635896) (xy 298.800531 -193.651481) (xy 298.849393 -193.674442)
			(xy 298.872148 -193.68897) (xy 298.878478 -193.692833) (xy 298.892677 -193.697088) (xy 298.900088 -193.697352)
			(xy 300.22038 -193.697352) (xy 300.230566 -193.696831) (xy 300.249298 -193.688805) (xy 300.263464 -193.674155)
			(xy 300.267624 -193.66484) (xy 300.281604 -193.629971) (xy 300.315578 -193.562962) (xy 300.356079 -193.499684)
			(xy 300.402702 -193.440771) (xy 300.454981 -193.386814) (xy 300.512391 -193.338353) (xy 300.574358 -193.295873)
			(xy 300.64026 -193.259799) (xy 300.709438 -193.230494) (xy 300.781199 -193.20825) (xy 300.854824 -193.19329)
			(xy 300.929575 -193.185764) (xy 300.96714 -193.185288) (xy 301.006646 -193.185799) (xy 301.085221 -193.194112)
			(xy 301.162485 -193.210641) (xy 301.237583 -193.235204) (xy 301.309682 -193.267527) (xy 301.377982 -193.307253)
			(xy 301.441726 -193.35394) (xy 301.47133 -193.380106) (xy 301.471584 -193.38036) (xy 301.478831 -193.386258)
			(xy 301.496284 -193.392891) (xy 301.50562 -193.393314) (xy 301.573946 -193.393314) (xy 301.583303 -193.393004)
			(xy 301.600792 -193.386355) (xy 301.607982 -193.38036) (xy 301.608236 -193.380106) (xy 301.637821 -193.353918)
			(xy 301.701569 -193.307234) (xy 301.769873 -193.267513) (xy 301.841975 -193.235194) (xy 301.917076 -193.210637)
			(xy 301.994343 -193.194114) (xy 302.072919 -193.185808) (xy 302.112426 -193.185288) (xy 302.149994 -193.185743)
			(xy 302.224754 -193.19325) (xy 302.298389 -193.208195) (xy 302.37016 -193.230429) (xy 302.439348 -193.259729)
			(xy 302.505259 -193.2958) (xy 302.567232 -193.338283) (xy 302.624646 -193.38675) (xy 302.676926 -193.440715)
			(xy 302.723546 -193.499639) (xy 302.764041 -193.562929) (xy 302.798003 -193.629951) (xy 302.811942 -193.66484)
			(xy 302.816029 -193.674199) (xy 302.830202 -193.688879) (xy 302.848984 -193.696856) (xy 302.859186 -193.697352)
			(xy 303.703736 -193.697352) (xy 303.713265 -193.696967) (xy 303.731014 -193.690026) (xy 303.745 -193.67708)
			(xy 303.749456 -193.66865) (xy 303.766543 -193.634562) (xy 303.806658 -193.569712) (xy 303.853149 -193.509268)
			(xy 303.905535 -193.453855) (xy 303.963276 -193.404047) (xy 304.025774 -193.360356) (xy 304.092384 -193.323236)
			(xy 304.162419 -193.293069) (xy 304.235153 -193.270166) (xy 304.309837 -193.254765) (xy 304.385698 -193.247025)
			(xy 304.461954 -193.247025) (xy 304.537815 -193.254765) (xy 304.612499 -193.270166) (xy 304.685233 -193.293069)
			(xy 304.755268 -193.323236) (xy 304.821878 -193.360356) (xy 304.884376 -193.404047) (xy 304.942117 -193.453855)
			(xy 304.994503 -193.509268) (xy 305.040994 -193.569712) (xy 305.081109 -193.634562) (xy 305.098196 -193.66865)
			(xy 305.102695 -193.677053) (xy 305.116665 -193.690002) (xy 305.134393 -193.696971) (xy 305.143916 -193.697352)
			(xy 305.980846 -193.697352) (xy 305.988261 -193.697105) (xy 306.002468 -193.692857) (xy 306.008786 -193.68897)
			(xy 306.031541 -193.674442) (xy 306.080403 -193.651481) (xy 306.132091 -193.635896) (xy 306.1855 -193.628019)
			(xy 306.239488 -193.628019) (xy 306.292897 -193.635896) (xy 306.344585 -193.651481) (xy 306.393447 -193.674442)
			(xy 306.416202 -193.68897) (xy 306.42253 -193.692839) (xy 306.436729 -193.697107) (xy 306.444142 -193.697352)
			(xy 307.764434 -193.697352) (xy 307.774625 -193.696839) (xy 307.793372 -193.688823) (xy 307.807552 -193.674173)
			(xy 307.811678 -193.66484) (xy 307.826282 -193.628455) (xy 307.862016 -193.558664) (xy 307.904837 -193.492982)
			(xy 307.954278 -193.432127) (xy 308.009798 -193.376763) (xy 308.070792 -193.327495) (xy 308.136594 -193.284859)
			(xy 308.206486 -193.249322) (xy 308.279704 -193.221272) (xy 308.355449 -193.201014) (xy 308.432894 -193.18877)
			(xy 308.511194 -193.184674) (xy 308.589494 -193.18877) (xy 308.666939 -193.201014) (xy 308.742684 -193.221272)
			(xy 308.815902 -193.249322) (xy 308.885794 -193.284859) (xy 308.951596 -193.327495) (xy 309.01259 -193.376763)
			(xy 309.06811 -193.432127) (xy 309.117551 -193.492982) (xy 309.160372 -193.558664) (xy 309.196106 -193.628455)
			(xy 309.21071 -193.66484) (xy 309.214795 -193.674203) (xy 309.228967 -193.688892) (xy 309.247749 -193.696879)
			(xy 309.257954 -193.697352) (xy 312.12409 -193.697352) (xy 312.13416 -193.696929) (xy 312.152762 -193.689212)
			(xy 312.160158 -193.682366) (xy 312.322972 -193.519552) (xy 312.329814 -193.512152) (xy 312.337535 -193.493554)
			(xy 312.337958 -193.483484) (xy 312.337958 -150.730204) (xy 312.338539 -150.705248) (xy 312.348295 -150.656298)
			(xy 312.367415 -150.610192) (xy 312.395162 -150.568702) (xy 312.41238 -150.550626) (xy 313.698636 -149.26437)
			(xy 313.716677 -149.247109) (xy 313.75817 -149.219349) (xy 313.804288 -149.200233) (xy 313.853252 -149.190499)
			(xy 313.878214 -149.189948) (xy 332.009242 -149.189948) (xy 332.019285 -149.189517) (xy 332.037833 -149.181805)
			(xy 332.052011 -149.167576) (xy 332.056232 -149.158452) (xy 332.056232 -149.158198) (xy 332.067306 -149.132147)
			(xy 332.096025 -149.083367) (xy 332.13164 -149.039369) (xy 332.173368 -149.001121) (xy 332.220293 -148.969461)
			(xy 332.271382 -148.945087) (xy 332.325513 -148.928534) (xy 332.381497 -148.920165) (xy 332.438103 -148.920165)
			(xy 332.494087 -148.928534) (xy 332.548218 -148.945087) (xy 332.599307 -148.969461) (xy 332.646232 -149.001121)
			(xy 332.68796 -149.039369) (xy 332.723575 -149.083367) (xy 332.752294 -149.132147) (xy 332.763368 -149.158198)
			(xy 332.763368 -149.158452) (xy 332.767581 -149.167581) (xy 332.781762 -149.181814) (xy 332.800313 -149.189527)
			(xy 332.810358 -149.189948) (xy 337.382612 -149.189948) (xy 337.407572 -149.190521) (xy 337.456531 -149.200263)
			(xy 337.502648 -149.219371) (xy 337.544151 -149.247111) (xy 337.56219 -149.26437) (xy 338.079334 -149.781514)
			(xy 338.096596 -149.799554) (xy 338.12436 -149.841047) (xy 338.143479 -149.887165) (xy 338.153217 -149.93613)
			(xy 338.153756 -149.961092) (xy 338.153756 -155.952952) (xy 338.15419 -155.963017) (xy 338.161924 -155.981602)
			(xy 338.168742 -155.98902) (xy 338.502498 -156.322776) (xy 338.509895 -156.329625) (xy 338.528493 -156.337364)
			(xy 338.538566 -156.337762) (xy 348.982284 -156.337762) (xy 348.991332 -156.337401) (xy 349.008304 -156.331123)
			(xy 349.022041 -156.319343) (xy 349.026734 -156.3116) (xy 349.045922 -156.278073) (xy 349.090081 -156.214684)
			(xy 349.140423 -156.156085) (xy 349.196434 -156.102878) (xy 349.257537 -156.055608) (xy 349.323108 -156.014759)
			(xy 349.392473 -155.980751) (xy 349.464922 -155.953931) (xy 349.539712 -155.934576) (xy 349.616075 -155.922882)
			(xy 349.69323 -155.918971) (xy 349.770385 -155.922882) (xy 349.846748 -155.934576) (xy 349.921538 -155.953931)
			(xy 349.993987 -155.980751) (xy 350.063352 -156.014759) (xy 350.128923 -156.055608) (xy 350.190026 -156.102878)
			(xy 350.246037 -156.156085) (xy 350.296379 -156.214684) (xy 350.340538 -156.278073) (xy 350.359726 -156.3116)
			(xy 350.364432 -156.319333) (xy 350.37816 -156.331115) (xy 350.39513 -156.337384) (xy 350.404176 -156.337762)
			(xy 351.43567 -156.337762) (xy 351.460624 -156.33838) (xy 351.509572 -156.348128) (xy 351.555678 -156.367236)
			(xy 351.597172 -156.394969) (xy 351.615248 -156.412184) (xy 357.799894 -162.59683) (xy 376.471695 -162.59683)
			(xy 376.4757 -162.491081) (xy 376.48769 -162.385938) (xy 376.507599 -162.282003) (xy 376.53531 -162.179871)
			(xy 376.570667 -162.080127) (xy 376.613465 -161.983343) (xy 376.663461 -161.890073) (xy 376.720368 -161.800852)
			(xy 376.783859 -161.716189) (xy 376.853571 -161.636571) (xy 376.929105 -161.562453) (xy 377.010028 -161.49426)
			(xy 377.095877 -161.432382) (xy 377.18616 -161.377175) (xy 377.280359 -161.328953) (xy 377.377936 -161.287993)
			(xy 377.478331 -161.254531) (xy 377.580969 -161.228757) (xy 377.685262 -161.210819) (xy 377.790613 -161.20082)
			(xy 377.896419 -161.198817) (xy 378.002073 -161.204822) (xy 378.10697 -161.218801) (xy 378.21051 -161.240672)
			(xy 378.312099 -161.270312) (xy 378.411156 -161.30755) (xy 378.507113 -161.352172) (xy 378.59942 -161.403924)
			(xy 378.687549 -161.462509) (xy 378.770995 -161.527591) (xy 378.849279 -161.598797) (xy 378.921954 -161.67572)
			(xy 378.988604 -161.75792) (xy 379.048846 -161.844924) (xy 379.102335 -161.936235) (xy 379.148766 -162.03133)
			(xy 379.187871 -162.129664) (xy 379.219428 -162.230675) (xy 379.243255 -162.333782) (xy 379.259216 -162.438396)
			(xy 379.26722 -162.543918) (xy 379.26772 -162.59683) (xy 379.26722 -162.649742) (xy 379.266995 -162.65271)
			(xy 385.808735 -162.65271) (xy 385.81274 -162.546961) (xy 385.82473 -162.441818) (xy 385.844639 -162.337883)
			(xy 385.87235 -162.235751) (xy 385.907707 -162.136007) (xy 385.950505 -162.039223) (xy 386.000501 -161.945953)
			(xy 386.057408 -161.856732) (xy 386.120899 -161.772069) (xy 386.190611 -161.692451) (xy 386.266145 -161.618333)
			(xy 386.347068 -161.55014) (xy 386.432917 -161.488262) (xy 386.5232 -161.433055) (xy 386.617399 -161.384833)
			(xy 386.714976 -161.343873) (xy 386.815371 -161.310411) (xy 386.918009 -161.284637) (xy 387.022302 -161.266699)
			(xy 387.127653 -161.2567) (xy 387.233459 -161.254697) (xy 387.339113 -161.260702) (xy 387.44401 -161.274681)
			(xy 387.54755 -161.296552) (xy 387.649139 -161.326192) (xy 387.748196 -161.36343) (xy 387.844153 -161.408052)
			(xy 387.93646 -161.459804) (xy 388.024589 -161.518389) (xy 388.108035 -161.583471) (xy 388.186319 -161.654677)
			(xy 388.258994 -161.7316) (xy 388.325644 -161.8138) (xy 388.385886 -161.900804) (xy 388.439375 -161.992115)
			(xy 388.485806 -162.08721) (xy 388.524911 -162.185544) (xy 388.556468 -162.286555) (xy 388.580295 -162.389662)
			(xy 388.596256 -162.494276) (xy 388.60426 -162.599798) (xy 388.60476 -162.65271) (xy 388.60426 -162.705622)
			(xy 388.596256 -162.811144) (xy 388.580295 -162.915758) (xy 388.556468 -163.018865) (xy 388.524911 -163.119876)
			(xy 388.485806 -163.21821) (xy 388.439375 -163.313305) (xy 388.385886 -163.404616) (xy 388.325644 -163.49162)
			(xy 388.258994 -163.57382) (xy 388.186319 -163.650743) (xy 388.108035 -163.721949) (xy 388.024589 -163.787031)
			(xy 387.93646 -163.845616) (xy 387.844153 -163.897368) (xy 387.748196 -163.94199) (xy 387.649139 -163.979228)
			(xy 387.54755 -164.008868) (xy 387.44401 -164.030739) (xy 387.339113 -164.044718) (xy 387.233459 -164.050723)
			(xy 387.127653 -164.04872) (xy 387.022302 -164.038721) (xy 386.918009 -164.020783) (xy 386.815371 -163.995009)
			(xy 386.714976 -163.961547) (xy 386.617399 -163.920587) (xy 386.5232 -163.872365) (xy 386.432917 -163.817158)
			(xy 386.347068 -163.75528) (xy 386.266145 -163.687087) (xy 386.190611 -163.612969) (xy 386.120899 -163.533351)
			(xy 386.057408 -163.448688) (xy 386.000501 -163.359467) (xy 385.950505 -163.266197) (xy 385.907707 -163.169413)
			(xy 385.87235 -163.069669) (xy 385.844639 -162.967537) (xy 385.82473 -162.863602) (xy 385.81274 -162.758459)
			(xy 385.808735 -162.65271) (xy 379.266995 -162.65271) (xy 379.259216 -162.755264) (xy 379.243255 -162.859878)
			(xy 379.219428 -162.962985) (xy 379.187871 -163.063996) (xy 379.148766 -163.16233) (xy 379.102335 -163.257425)
			(xy 379.048846 -163.348736) (xy 378.988604 -163.43574) (xy 378.921954 -163.51794) (xy 378.849279 -163.594863)
			(xy 378.770995 -163.666069) (xy 378.687549 -163.731151) (xy 378.59942 -163.789736) (xy 378.507113 -163.841488)
			(xy 378.411156 -163.88611) (xy 378.312099 -163.923348) (xy 378.21051 -163.952988) (xy 378.10697 -163.974859)
			(xy 378.002073 -163.988838) (xy 377.896419 -163.994843) (xy 377.790613 -163.99284) (xy 377.685262 -163.982841)
			(xy 377.580969 -163.964903) (xy 377.478331 -163.939129) (xy 377.377936 -163.905667) (xy 377.280359 -163.864707)
			(xy 377.18616 -163.816485) (xy 377.095877 -163.761278) (xy 377.010028 -163.6994) (xy 376.929105 -163.631207)
			(xy 376.853571 -163.557089) (xy 376.783859 -163.477471) (xy 376.720368 -163.392808) (xy 376.663461 -163.303587)
			(xy 376.613465 -163.210317) (xy 376.570667 -163.113533) (xy 376.53531 -163.013789) (xy 376.507599 -162.911657)
			(xy 376.48769 -162.807722) (xy 376.4757 -162.702579) (xy 376.471695 -162.59683) (xy 357.799894 -162.59683)
			(xy 358.22382 -163.020756) (xy 358.231217 -163.027604) (xy 358.249816 -163.035338) (xy 358.259888 -163.035742)
			(xy 366.527588 -163.035742) (xy 366.533684 -163.034218) (xy 366.568113 -163.026202) (xy 366.637919 -163.015014)
			(xy 366.708394 -163.009408) (xy 366.743742 -163.009072) (xy 366.745266 -163.009072) (xy 366.780614 -163.009424)
			(xy 366.851086 -163.015035) (xy 366.920892 -163.026218) (xy 366.955324 -163.034218) (xy 366.96142 -163.035742)
			(xy 367.162588 -163.035742) (xy 367.168684 -163.034218) (xy 367.203113 -163.026202) (xy 367.272919 -163.015014)
			(xy 367.343394 -163.009408) (xy 367.378742 -163.009072) (xy 367.380266 -163.009072) (xy 367.415614 -163.009424)
			(xy 367.486086 -163.015035) (xy 367.555892 -163.026218) (xy 367.590324 -163.034218) (xy 367.59642 -163.035742)
			(xy 367.828068 -163.035742) (xy 367.834164 -163.034218) (xy 367.868593 -163.026201) (xy 367.938399 -163.015012)
			(xy 368.008873 -163.009404) (xy 368.044222 -163.009072) (xy 368.045746 -163.009072) (xy 368.081094 -163.009423)
			(xy 368.151567 -163.015033) (xy 368.221373 -163.026214) (xy 368.255804 -163.034218) (xy 368.2619 -163.035742)
			(xy 368.463068 -163.035742) (xy 368.469164 -163.034218) (xy 368.503593 -163.026201) (xy 368.573399 -163.015012)
			(xy 368.643873 -163.009404) (xy 368.679222 -163.009072) (xy 368.680746 -163.009072) (xy 368.716094 -163.009423)
			(xy 368.786567 -163.015033) (xy 368.856373 -163.026214) (xy 368.890804 -163.034218) (xy 368.8969 -163.035742)
			(xy 369.098068 -163.035742) (xy 369.104164 -163.034218) (xy 369.138593 -163.026201) (xy 369.208399 -163.015012)
			(xy 369.278873 -163.009404) (xy 369.314222 -163.009072) (xy 369.315746 -163.009072) (xy 369.351094 -163.009423)
			(xy 369.421567 -163.015033) (xy 369.491373 -163.026214) (xy 369.525804 -163.034218) (xy 369.5319 -163.035742)
			(xy 369.733068 -163.035742) (xy 369.739164 -163.034218) (xy 369.773593 -163.026201) (xy 369.843399 -163.015012)
			(xy 369.913873 -163.009404) (xy 369.949222 -163.009072) (xy 369.950746 -163.009072) (xy 369.986094 -163.009423)
			(xy 370.056567 -163.015033) (xy 370.126373 -163.026214) (xy 370.160804 -163.034218) (xy 370.1669 -163.035742)
			(xy 370.469668 -163.035742) (xy 370.475764 -163.034218) (xy 370.510193 -163.026201) (xy 370.579999 -163.015012)
			(xy 370.650473 -163.009404) (xy 370.685822 -163.009072) (xy 370.687346 -163.009072) (xy 370.722694 -163.009423)
			(xy 370.793167 -163.015033) (xy 370.862973 -163.026214) (xy 370.897404 -163.034218) (xy 370.9035 -163.035742)
			(xy 372.847616 -163.035742) (xy 372.872576 -163.036315) (xy 372.921535 -163.046058) (xy 372.967652 -163.065166)
			(xy 373.009154 -163.092906) (xy 373.027194 -163.110164) (xy 375.85523 -165.9382) (xy 375.86263 -165.945042)
			(xy 375.881228 -165.952765) (xy 375.891298 -165.953186) (xy 388.85749 -165.953186) (xy 388.867561 -165.952764)
			(xy 388.886166 -165.945051) (xy 388.893558 -165.9382) (xy 396.423388 -158.40837) (xy 396.44143 -158.391113)
			(xy 396.482925 -158.363362) (xy 396.529043 -158.344255) (xy 396.578006 -158.334531) (xy 396.602966 -158.333948)
			(xy 414.513268 -158.333948) (xy 414.521546 -158.333621) (xy 414.537222 -158.328297) (xy 414.544002 -158.323534)
			(xy 414.566337 -158.307007) (xy 414.614839 -158.279908) (xy 414.66676 -158.260131) (xy 414.721 -158.248095)
			(xy 414.776412 -158.244055) (xy 414.831824 -158.248095) (xy 414.886064 -158.260131) (xy 414.937985 -158.279908)
			(xy 414.986487 -158.307007) (xy 415.008822 -158.323534) (xy 415.015605 -158.328286) (xy 415.031281 -158.333601)
			(xy 415.039556 -158.333948) (xy 417.576 -158.333948) (xy 417.585144 -158.334202) (xy 417.594373 -158.334077)
			(xy 417.611814 -158.328081) (xy 417.61918 -158.322518) (xy 417.639733 -158.306209) (xy 417.684466 -158.278788)
			(xy 417.732535 -158.257757) (xy 417.783034 -158.243515) (xy 417.835008 -158.236328) (xy 417.861242 -158.235904)
			(xy 417.888491 -158.236393) (xy 417.942433 -158.244155) (xy 417.994722 -158.259513) (xy 418.044293 -158.282157)
			(xy 418.090138 -158.311625) (xy 418.131322 -158.347316) (xy 418.167008 -158.388506) (xy 418.196469 -158.434354)
			(xy 418.219105 -158.483928) (xy 418.234457 -158.536219) (xy 418.242211 -158.590163) (xy 418.24275 -158.617412)
			(xy 418.242105 -158.64888) (xy 418.231775 -158.710963) (xy 418.211396 -158.770509) (xy 418.19703 -158.798514)
			(xy 418.19229 -158.80838) (xy 418.190808 -158.830196) (xy 418.198506 -158.850663) (xy 418.20592 -158.858712)
			(xy 418.390578 -159.04337) (xy 418.407839 -159.06141) (xy 418.435599 -159.102903) (xy 418.454713 -159.149021)
			(xy 418.464443 -159.197986) (xy 418.465 -159.222948) (xy 418.465 -159.543242) (xy 418.465274 -159.550564)
			(xy 418.469407 -159.564615) (xy 418.473128 -159.570928) (xy 418.49441 -159.60469) (xy 418.530617 -159.675818)
			(xy 418.559197 -159.750338) (xy 418.579839 -159.827435) (xy 418.592316 -159.906266) (xy 418.596493 -159.98597)
			(xy 418.592323 -160.065674) (xy 418.579852 -160.144506) (xy 418.559216 -160.221605) (xy 418.530641 -160.296127)
			(xy 418.49444 -160.367258) (xy 418.473128 -160.401) (xy 418.469344 -160.407283) (xy 418.465229 -160.421354)
			(xy 418.465 -160.428686) (xy 418.465 -161.804604) (xy 418.465442 -161.814763) (xy 418.473292 -161.833503)
			(xy 418.48024 -161.840926) (xy 418.499546 -161.860583) (xy 418.532873 -161.904456) (xy 418.559543 -161.952666)
			(xy 418.579001 -162.004212) (xy 418.590841 -162.05802) (xy 418.594818 -162.112972) (xy 418.590849 -162.167924)
			(xy 418.579017 -162.221735) (xy 418.559567 -162.273283) (xy 418.532904 -162.321497) (xy 418.499583 -162.365375)
			(xy 418.48024 -162.384994) (xy 418.473288 -162.392417) (xy 418.465422 -162.411154) (xy 418.465 -162.421316)
			(xy 418.465 -162.450018) (xy 418.465444 -162.460176) (xy 418.473298 -162.478912) (xy 418.48024 -162.48634)
			(xy 418.499545 -162.505997) (xy 418.53287 -162.549869) (xy 418.559538 -162.598079) (xy 418.578994 -162.649624)
			(xy 418.590833 -162.703431) (xy 418.594808 -162.758382) (xy 418.590838 -162.813333) (xy 418.579004 -162.867141)
			(xy 418.559554 -162.918688) (xy 418.53289 -162.9669) (xy 418.499569 -163.010776) (xy 418.48024 -163.030408)
			(xy 418.47329 -163.037832) (xy 418.46543 -163.056569) (xy 418.465 -163.06673) (xy 418.465 -163.716716)
			(xy 431.458116 -163.716716) (xy 431.458593 -163.67699) (xy 431.46684 -163.597967) (xy 431.483247 -163.520228)
			(xy 431.507636 -163.444612) (xy 431.539744 -163.371936) (xy 431.579224 -163.302987) (xy 431.625649 -163.23851)
			(xy 431.678517 -163.1792) (xy 431.707544 -163.152074) (xy 431.714516 -163.145218) (xy 431.723062 -163.127648)
			(xy 431.724388 -163.108156) (xy 431.721768 -163.098734) (xy 431.713062 -163.070112) (xy 431.703616 -163.011041)
			(xy 431.702972 -162.981132) (xy 431.703431 -162.95386) (xy 431.71119 -162.899871) (xy 431.726554 -162.847537)
			(xy 431.74921 -162.797921) (xy 431.778698 -162.752036) (xy 431.814416 -162.710814) (xy 431.855637 -162.675097)
			(xy 431.901523 -162.645609) (xy 431.951138 -162.622953) (xy 432.003473 -162.60759) (xy 432.057462 -162.599831)
			(xy 432.084734 -162.59937) (xy 432.111994 -162.599792) (xy 432.165959 -162.607553) (xy 432.218272 -162.622911)
			(xy 432.267867 -162.645555) (xy 432.313737 -162.675024) (xy 432.354949 -162.710718) (xy 432.390663 -162.751912)
			(xy 432.420155 -162.797767) (xy 432.442823 -162.847352) (xy 432.458207 -162.899657) (xy 432.465994 -162.953618)
			(xy 432.466496 -162.980878) (xy 432.466496 -162.981386) (xy 432.466242 -162.99307) (xy 432.505612 -163.006972)
			(xy 432.581318 -163.042196) (xy 432.652731 -163.085464) (xy 432.686206 -163.110418) (xy 432.695405 -163.116761)
			(xy 432.717194 -163.121592) (xy 432.738983 -163.116761) (xy 432.748182 -163.110418) (xy 432.781656 -163.085462)
			(xy 432.853068 -163.042191) (xy 432.928776 -163.006973) (xy 432.968146 -162.99307) (xy 432.967892 -162.981386)
			(xy 432.967892 -162.980878) (xy 432.968471 -162.953623) (xy 432.976257 -162.899672) (xy 432.991638 -162.847378)
			(xy 433.014301 -162.797803) (xy 433.043787 -162.751956) (xy 433.079494 -162.710769) (xy 433.120697 -162.675081)
			(xy 433.166557 -162.645617) (xy 433.216143 -162.622976) (xy 433.268445 -162.607619) (xy 433.322399 -162.599859)
			(xy 433.349654 -162.59937) (xy 433.376925 -162.599844) (xy 433.430913 -162.607601) (xy 433.483248 -162.622963)
			(xy 433.532863 -162.645618) (xy 433.578749 -162.675103) (xy 433.61997 -162.71082) (xy 433.655688 -162.75204)
			(xy 433.685176 -162.797925) (xy 433.707832 -162.847539) (xy 433.723196 -162.899873) (xy 433.730955 -162.953861)
			(xy 433.731416 -162.981132) (xy 433.730789 -163.011043) (xy 433.721344 -163.070117) (xy 433.71262 -163.098734)
			(xy 433.710031 -163.108155) (xy 433.711383 -163.12763) (xy 433.719907 -163.145193) (xy 433.726844 -163.152074)
			(xy 433.755886 -163.179183) (xy 433.808744 -163.2385) (xy 433.855159 -163.302983) (xy 433.894631 -163.371936)
			(xy 433.926732 -163.444613) (xy 433.951115 -163.520229) (xy 433.967519 -163.597969) (xy 433.975764 -163.676991)
			(xy 433.976272 -163.716716) (xy 433.97577 -163.756717) (xy 433.967406 -163.836281) (xy 433.950771 -163.914534)
			(xy 433.926047 -163.99062) (xy 433.893506 -164.063705) (xy 433.853504 -164.132988) (xy 433.806479 -164.19771)
			(xy 433.752947 -164.257162) (xy 433.693493 -164.310693) (xy 433.628769 -164.357716) (xy 433.559485 -164.397716)
			(xy 433.486399 -164.430255) (xy 433.410313 -164.454976) (xy 433.332059 -164.471609) (xy 433.252495 -164.479971)
			(xy 433.212494 -164.480494) (xy 433.170888 -164.479965) (xy 433.08817 -164.470903) (xy 433.006928 -164.4529)
			(xy 432.928126 -164.426168) (xy 432.852699 -164.391024) (xy 432.781541 -164.347886) (xy 432.748182 -164.323014)
			(xy 432.738983 -164.316671) (xy 432.717194 -164.31184) (xy 432.695405 -164.316671) (xy 432.686206 -164.323014)
			(xy 432.652851 -164.347888) (xy 432.581683 -164.391001) (xy 432.506251 -164.426127) (xy 432.42745 -164.452851)
			(xy 432.346212 -164.470855) (xy 432.263498 -164.479926) (xy 432.221894 -164.480494) (xy 432.181894 -164.47996)
			(xy 432.102332 -164.471598) (xy 432.02408 -164.454964) (xy 431.947996 -164.430243) (xy 431.874912 -164.397704)
			(xy 431.80563 -164.357704) (xy 431.740908 -164.310681) (xy 431.681456 -164.257151) (xy 431.627925 -164.1977)
			(xy 431.580902 -164.132979) (xy 431.540901 -164.063697) (xy 431.508361 -163.990614) (xy 431.483638 -163.914529)
			(xy 431.467004 -163.836278) (xy 431.45864 -163.756716) (xy 431.458116 -163.716716) (xy 418.465 -163.716716)
			(xy 418.465 -174.387764) (xy 418.465413 -174.39779) (xy 418.473077 -174.416319) (xy 418.48725 -174.430503)
			(xy 418.505774 -174.43818) (xy 418.5158 -174.438564) (xy 425.076366 -174.438564) (xy 425.10132 -174.439182)
			(xy 425.150268 -174.448929) (xy 425.196375 -174.468036) (xy 425.237869 -174.49577) (xy 425.255944 -174.512986)
			(xy 425.976796 -175.233838) (xy 425.994059 -175.251878) (xy 426.021822 -175.29337) (xy 426.04094 -175.339488)
			(xy 426.050676 -175.388454) (xy 426.051218 -175.413416) (xy 426.051218 -195.27139) (xy 426.05164 -195.281461)
			(xy 426.059354 -195.300066) (xy 426.066204 -195.307458) (xy 426.143166 -195.38442) (xy 426.150564 -195.391265)
			(xy 426.169163 -195.398988) (xy 426.179234 -195.399406)
		)
		(stroke
			(width 0)
			(type solid)
		)
		(fill yes)
		(layer "In8.Cu")
		(net "P12V_MEM_CPU0")
	)
	(gr_poly
		(pts
			(xy 193.670936 -341.982552) (xy 193.681002 -341.982121) (xy 193.699593 -341.974392) (xy 193.707004 -341.967566)
			(xy 196.025008 -339.649562) (xy 196.031847 -339.642161) (xy 196.039567 -339.623563) (xy 196.039994 -339.613494)
			(xy 196.039994 -326.967342) (xy 196.03956 -326.957277) (xy 196.03183 -326.938688) (xy 196.025008 -326.931274)
			(xy 194.463924 -325.37019) (xy 194.446658 -325.352152) (xy 194.418888 -325.310661) (xy 194.399763 -325.264543)
			(xy 194.390021 -325.215575) (xy 194.389502 -325.190612) (xy 194.389502 -323.540882) (xy 194.390115 -323.515926)
			(xy 194.399856 -323.466974) (xy 194.418959 -323.420863) (xy 194.446691 -323.379364) (xy 194.463924 -323.361304)
			(xy 196.025008 -321.80022) (xy 196.031841 -321.792817) (xy 196.039545 -321.774219) (xy 196.039994 -321.764152)
			(xy 196.039994 -271.809464) (xy 196.039564 -271.799397) (xy 196.03184 -271.780802) (xy 196.025008 -271.773396)
			(xy 191.556132 -267.30452) (xy 191.548851 -267.297847) (xy 191.530684 -267.290153) (xy 191.520826 -267.289534)
			(xy 191.4398 -267.288518) (xy 191.421512 -267.29563) (xy 191.414146 -267.302742) (xy 191.393454 -267.321658)
			(xy 191.347421 -267.353654) (xy 191.297081 -267.378324) (xy 191.243589 -267.3951) (xy 191.188176 -267.403597)
			(xy 191.160146 -267.404088) (xy 191.134166 -267.40364) (xy 191.082722 -267.396342) (xy 191.032811 -267.381896)
			(xy 190.98542 -267.360589) (xy 190.941489 -267.332843) (xy 190.901886 -267.299207) (xy 190.867394 -267.260346)
			(xy 190.838697 -267.21703) (xy 190.816363 -267.170116) (xy 190.800833 -267.120531) (xy 190.796164 -267.09497)
			(xy 190.793116 -267.076428) (xy 190.764922 -267.052298) (xy 187.455302 -267.052298) (xy 187.427108 -267.076428)
			(xy 187.42406 -267.09497) (xy 187.419143 -267.12188) (xy 187.402415 -267.173963) (xy 187.378178 -267.223003)
			(xy 187.346963 -267.267926) (xy 187.309457 -267.307746) (xy 187.26648 -267.34159) (xy 187.218976 -267.368715)
			(xy 187.167987 -267.388527) (xy 187.114631 -267.40059) (xy 187.060078 -267.404641) (xy 187.005525 -267.40059)
			(xy 186.952169 -267.388527) (xy 186.90118 -267.368715) (xy 186.853676 -267.34159) (xy 186.810699 -267.307746)
			(xy 186.773193 -267.267926) (xy 186.741978 -267.223003) (xy 186.717741 -267.173963) (xy 186.701013 -267.12188)
			(xy 186.696096 -267.09497) (xy 186.693048 -267.076428) (xy 186.664854 -267.052298) (xy 184.011316 -267.052298)
			(xy 183.983122 -267.076428) (xy 183.980074 -267.09497) (xy 183.975157 -267.12188) (xy 183.958429 -267.173963)
			(xy 183.934192 -267.223003) (xy 183.902977 -267.267926) (xy 183.865471 -267.307746) (xy 183.822494 -267.34159)
			(xy 183.77499 -267.368715) (xy 183.724001 -267.388527) (xy 183.670645 -267.40059) (xy 183.616092 -267.404641)
			(xy 183.561539 -267.40059) (xy 183.508183 -267.388527) (xy 183.457194 -267.368715) (xy 183.40969 -267.34159)
			(xy 183.366713 -267.307746) (xy 183.329207 -267.267926) (xy 183.297992 -267.223003) (xy 183.273755 -267.173963)
			(xy 183.257027 -267.12188) (xy 183.25211 -267.09497) (xy 183.249062 -267.076428) (xy 183.220868 -267.052298)
			(xy 179.911248 -267.052298) (xy 179.883054 -267.076428) (xy 179.880006 -267.09497) (xy 179.875089 -267.12188)
			(xy 179.858361 -267.173963) (xy 179.834124 -267.223003) (xy 179.802909 -267.267926) (xy 179.765403 -267.307746)
			(xy 179.722426 -267.34159) (xy 179.674922 -267.368715) (xy 179.623933 -267.388527) (xy 179.570577 -267.40059)
			(xy 179.516024 -267.404641) (xy 179.461471 -267.40059) (xy 179.408115 -267.388527) (xy 179.357126 -267.368715)
			(xy 179.309622 -267.34159) (xy 179.266645 -267.307746) (xy 179.229139 -267.267926) (xy 179.197924 -267.223003)
			(xy 179.173687 -267.173963) (xy 179.156959 -267.12188) (xy 179.152042 -267.09497) (xy 179.148994 -267.076428)
			(xy 179.1208 -267.052298) (xy 176.467262 -267.052298) (xy 176.439068 -267.076428) (xy 176.43602 -267.09497)
			(xy 176.431103 -267.12188) (xy 176.414375 -267.173963) (xy 176.390138 -267.223003) (xy 176.358923 -267.267926)
			(xy 176.321417 -267.307746) (xy 176.27844 -267.34159) (xy 176.230936 -267.368715) (xy 176.179947 -267.388527)
			(xy 176.126591 -267.40059) (xy 176.072038 -267.404641) (xy 176.017485 -267.40059) (xy 175.964129 -267.388527)
			(xy 175.91314 -267.368715) (xy 175.865636 -267.34159) (xy 175.822659 -267.307746) (xy 175.785153 -267.267926)
			(xy 175.753938 -267.223003) (xy 175.729701 -267.173963) (xy 175.712973 -267.12188) (xy 175.708056 -267.09497)
			(xy 175.705008 -267.076428) (xy 175.676814 -267.052298) (xy 172.367194 -267.052298) (xy 172.339 -267.076428)
			(xy 172.335952 -267.09497) (xy 172.331035 -267.12188) (xy 172.314307 -267.173963) (xy 172.29007 -267.223003)
			(xy 172.258855 -267.267926) (xy 172.221349 -267.307746) (xy 172.178372 -267.34159) (xy 172.130868 -267.368715)
			(xy 172.079879 -267.388527) (xy 172.026523 -267.40059) (xy 171.97197 -267.404641) (xy 171.917417 -267.40059)
			(xy 171.864061 -267.388527) (xy 171.813072 -267.368715) (xy 171.765568 -267.34159) (xy 171.722591 -267.307746)
			(xy 171.685085 -267.267926) (xy 171.65387 -267.223003) (xy 171.629633 -267.173963) (xy 171.612905 -267.12188)
			(xy 171.607988 -267.09497) (xy 171.60494 -267.076428) (xy 171.576746 -267.052298) (xy 168.923208 -267.052298)
			(xy 168.895014 -267.076428) (xy 168.891966 -267.09497) (xy 168.887049 -267.12188) (xy 168.870321 -267.173963)
			(xy 168.846084 -267.223003) (xy 168.814869 -267.267926) (xy 168.777363 -267.307746) (xy 168.734386 -267.34159)
			(xy 168.686882 -267.368715) (xy 168.635893 -267.388527) (xy 168.582537 -267.40059) (xy 168.527984 -267.404641)
			(xy 168.473431 -267.40059) (xy 168.420075 -267.388527) (xy 168.369086 -267.368715) (xy 168.321582 -267.34159)
			(xy 168.278605 -267.307746) (xy 168.241099 -267.267926) (xy 168.209884 -267.223003) (xy 168.185647 -267.173963)
			(xy 168.168919 -267.12188) (xy 168.164002 -267.09497) (xy 168.160954 -267.076428) (xy 168.13276 -267.052298)
			(xy 145.690844 -267.052298) (xy 145.666798 -267.051741) (xy 145.619562 -267.042705) (xy 145.574868 -267.024946)
			(xy 145.534312 -266.999099) (xy 145.49934 -266.966085) (xy 145.48485 -266.946888) (xy 145.477233 -266.937382)
			(xy 145.45561 -266.926241) (xy 145.443448 -266.925552) (xy 144.356836 -266.925552) (xy 144.33296 -266.94003)
			(xy 144.326356 -266.952476) (xy 144.313883 -266.974725) (xy 144.283157 -267.015435) (xy 144.246548 -267.05095)
			(xy 144.204924 -267.080426) (xy 144.15927 -267.103167) (xy 144.110667 -267.118633) (xy 144.060266 -267.126459)
			(xy 144.009262 -267.126459) (xy 143.958861 -267.118633) (xy 143.910258 -267.103167) (xy 143.864604 -267.080426)
			(xy 143.82298 -267.05095) (xy 143.786371 -267.015435) (xy 143.755645 -266.974725) (xy 143.743172 -266.952476)
			(xy 143.736568 -266.94003) (xy 143.712692 -266.925552) (xy 143.416782 -266.925552) (xy 143.392906 -266.94003)
			(xy 143.386302 -266.952476) (xy 143.373826 -266.974724) (xy 143.343097 -267.015433) (xy 143.306487 -267.050947)
			(xy 143.264864 -267.080427) (xy 143.219212 -267.103174) (xy 143.170612 -267.11865) (xy 143.120212 -267.126489)
			(xy 143.09471 -267.126974) (xy 143.068721 -267.126492) (xy 143.017383 -267.118361) (xy 142.96795 -267.1023)
			(xy 142.921638 -267.078702) (xy 142.879588 -267.048149) (xy 142.842835 -267.011394) (xy 142.812286 -266.969342)
			(xy 142.788691 -266.923028) (xy 142.772633 -266.873593) (xy 142.764507 -266.822255) (xy 142.764002 -266.796266)
			(xy 142.764411 -266.772908) (xy 142.770988 -266.726657) (xy 142.783994 -266.681787) (xy 142.803171 -266.639188)
			(xy 142.81531 -266.619228) (xy 142.82293 -266.60729) (xy 142.823438 -266.579096) (xy 142.664434 -266.30503)
			(xy 142.640812 -266.291568) (xy 142.627096 -266.291568) (xy 142.62481 -266.291568) (xy 142.600817 -266.291123)
			(xy 142.553423 -266.283617) (xy 142.507787 -266.268789) (xy 142.465032 -266.247003) (xy 142.426212 -266.218797)
			(xy 142.392283 -266.184865) (xy 142.364081 -266.146042) (xy 142.3423 -266.103286) (xy 142.327476 -266.057648)
			(xy 142.319975 -266.010253) (xy 142.319502 -265.98626) (xy 142.320061 -265.959447) (xy 142.329436 -265.906648)
			(xy 142.347908 -265.856304) (xy 142.360904 -265.832844) (xy 142.367762 -265.820906) (xy 142.367762 -265.793728)
			(xy 142.208504 -265.519408) (xy 142.183866 -265.505946) (xy 142.169642 -265.506708) (xy 142.154656 -265.506962)
			(xy 142.12867 -265.506476) (xy 142.07734 -265.498339) (xy 142.027914 -265.482272) (xy 141.98161 -265.458671)
			(xy 141.939569 -265.428117) (xy 141.902824 -265.391363) (xy 141.872282 -265.349313) (xy 141.848694 -265.303003)
			(xy 141.83264 -265.253573) (xy 141.824517 -265.20224) (xy 141.823948 -265.176254) (xy 141.82437 -265.152927)
			(xy 141.83096 -265.106741) (xy 141.843962 -265.061935) (xy 141.863119 -265.019395) (xy 141.875256 -264.99947)
			(xy 141.882876 -264.987278) (xy 141.883384 -264.959084) (xy 141.73835 -264.709656) (xy 141.713712 -264.69594)
			(xy 141.699488 -264.696702) (xy 141.684756 -264.696956) (xy 141.659251 -264.696489) (xy 141.608845 -264.688666)
			(xy 141.560237 -264.673197) (xy 141.514581 -264.650449) (xy 141.472958 -264.620962) (xy 141.436356 -264.585434)
			(xy 141.405642 -264.544707) (xy 141.393164 -264.522458) (xy 141.38656 -264.510012) (xy 141.362684 -264.495788)
			(xy 141.066774 -264.495788) (xy 141.042898 -264.510012) (xy 141.036294 -264.522458) (xy 141.023821 -264.544707)
			(xy 140.993095 -264.585417) (xy 140.956486 -264.620932) (xy 140.914862 -264.650408) (xy 140.869208 -264.673149)
			(xy 140.820605 -264.688615) (xy 140.770204 -264.696441) (xy 140.7192 -264.696441) (xy 140.668799 -264.688615)
			(xy 140.620196 -264.673149) (xy 140.574542 -264.650408) (xy 140.532918 -264.620932) (xy 140.496309 -264.585417)
			(xy 140.465583 -264.544707) (xy 140.45311 -264.522458) (xy 140.446506 -264.510012) (xy 140.42263 -264.495788)
			(xy 140.12672 -264.495788) (xy 140.102844 -264.510012) (xy 140.09624 -264.522458) (xy 140.083767 -264.544707)
			(xy 140.053041 -264.585417) (xy 140.016432 -264.620932) (xy 139.974808 -264.650408) (xy 139.929154 -264.673149)
			(xy 139.880551 -264.688615) (xy 139.83015 -264.696441) (xy 139.779146 -264.696441) (xy 139.728745 -264.688615)
			(xy 139.680142 -264.673149) (xy 139.634488 -264.650408) (xy 139.592864 -264.620932) (xy 139.556255 -264.585417)
			(xy 139.525529 -264.544707) (xy 139.513056 -264.522458) (xy 139.506452 -264.510012) (xy 139.482576 -264.495788)
			(xy 139.18692 -264.495788) (xy 139.163044 -264.510012) (xy 139.15644 -264.522458) (xy 139.143967 -264.544707)
			(xy 139.113241 -264.585417) (xy 139.076632 -264.620932) (xy 139.035008 -264.650408) (xy 138.989354 -264.673149)
			(xy 138.940751 -264.688615) (xy 138.89035 -264.696441) (xy 138.839346 -264.696441) (xy 138.788945 -264.688615)
			(xy 138.740342 -264.673149) (xy 138.694688 -264.650408) (xy 138.653064 -264.620932) (xy 138.616455 -264.585417)
			(xy 138.585729 -264.544707) (xy 138.573256 -264.522458) (xy 138.566652 -264.510012) (xy 138.542776 -264.495788)
			(xy 138.246866 -264.495788) (xy 138.22299 -264.510012) (xy 138.216386 -264.522458) (xy 138.203913 -264.544707)
			(xy 138.173187 -264.585417) (xy 138.136578 -264.620932) (xy 138.094954 -264.650408) (xy 138.0493 -264.673149)
			(xy 138.000697 -264.688615) (xy 137.950296 -264.696441) (xy 137.899292 -264.696441) (xy 137.848891 -264.688615)
			(xy 137.800288 -264.673149) (xy 137.754634 -264.650408) (xy 137.71301 -264.620932) (xy 137.676401 -264.585417)
			(xy 137.645675 -264.544707) (xy 137.633202 -264.522458) (xy 137.626598 -264.510012) (xy 137.602722 -264.495788)
			(xy 137.306812 -264.495788) (xy 137.282936 -264.510012) (xy 137.276332 -264.522458) (xy 137.263858 -264.544708)
			(xy 137.23313 -264.585422) (xy 137.196522 -264.620942) (xy 137.154899 -264.650427) (xy 137.109247 -264.673179)
			(xy 137.060645 -264.688661) (xy 137.010244 -264.696505) (xy 136.98474 -264.696956) (xy 136.958749 -264.696449)
			(xy 136.907407 -264.688324) (xy 136.857968 -264.672267) (xy 136.81165 -264.648674) (xy 136.769592 -264.618126)
			(xy 136.732831 -264.581375) (xy 136.702272 -264.539325) (xy 136.678666 -264.493013) (xy 136.662596 -264.443578)
			(xy 136.654457 -264.392238) (xy 136.654032 -264.366248) (xy 136.654454 -264.342921) (xy 136.661045 -264.296735)
			(xy 136.674047 -264.251929) (xy 136.693204 -264.209389) (xy 136.70534 -264.189464) (xy 136.71296 -264.177272)
			(xy 136.713468 -264.149078) (xy 136.568688 -263.89965) (xy 136.543796 -263.885934) (xy 136.529572 -263.886696)
			(xy 136.51484 -263.88695) (xy 136.489334 -263.886482) (xy 136.438927 -263.878658) (xy 136.390318 -263.86319)
			(xy 136.344658 -263.840445) (xy 136.303031 -263.810961) (xy 136.266422 -263.775438) (xy 136.2357 -263.734716)
			(xy 136.223248 -263.712452) (xy 136.216644 -263.700006) (xy 136.192768 -263.685528) (xy 135.896858 -263.685528)
			(xy 135.872982 -263.700006) (xy 135.866378 -263.712452) (xy 135.853905 -263.734701) (xy 135.823179 -263.775411)
			(xy 135.78657 -263.810926) (xy 135.744946 -263.840402) (xy 135.699292 -263.863143) (xy 135.650689 -263.878609)
			(xy 135.600288 -263.886435) (xy 135.549284 -263.886435) (xy 135.498883 -263.878609) (xy 135.45028 -263.863143)
			(xy 135.404626 -263.840402) (xy 135.363002 -263.810926) (xy 135.326393 -263.775411) (xy 135.295667 -263.734701)
			(xy 135.283194 -263.712452) (xy 135.27659 -263.700006) (xy 135.252714 -263.685528) (xy 134.956804 -263.685528)
			(xy 134.932928 -263.700006) (xy 134.926324 -263.712452) (xy 134.913851 -263.734701) (xy 134.883125 -263.775411)
			(xy 134.846516 -263.810926) (xy 134.804892 -263.840402) (xy 134.759238 -263.863143) (xy 134.710635 -263.878609)
			(xy 134.660234 -263.886435) (xy 134.60923 -263.886435) (xy 134.558829 -263.878609) (xy 134.510226 -263.863143)
			(xy 134.464572 -263.840402) (xy 134.422948 -263.810926) (xy 134.386339 -263.775411) (xy 134.355613 -263.734701)
			(xy 134.34314 -263.712452) (xy 134.336536 -263.700006) (xy 134.31266 -263.685528) (xy 134.01675 -263.685528)
			(xy 133.992874 -263.700006) (xy 133.98627 -263.712452) (xy 133.973797 -263.734701) (xy 133.943071 -263.775411)
			(xy 133.906462 -263.810926) (xy 133.864838 -263.840402) (xy 133.819184 -263.863143) (xy 133.770581 -263.878609)
			(xy 133.72018 -263.886435) (xy 133.669176 -263.886435) (xy 133.618775 -263.878609) (xy 133.570172 -263.863143)
			(xy 133.524518 -263.840402) (xy 133.482894 -263.810926) (xy 133.446285 -263.775411) (xy 133.415559 -263.734701)
			(xy 133.403086 -263.712452) (xy 133.396482 -263.700006) (xy 133.372606 -263.685528) (xy 133.07695 -263.685528)
			(xy 133.053074 -263.700006) (xy 133.04647 -263.712452) (xy 133.033997 -263.734701) (xy 133.003271 -263.775411)
			(xy 132.966662 -263.810926) (xy 132.925038 -263.840402) (xy 132.879384 -263.863143) (xy 132.830781 -263.878609)
			(xy 132.78038 -263.886435) (xy 132.729376 -263.886435) (xy 132.678975 -263.878609) (xy 132.630372 -263.863143)
			(xy 132.584718 -263.840402) (xy 132.543094 -263.810926) (xy 132.506485 -263.775411) (xy 132.475759 -263.734701)
			(xy 132.463286 -263.712452) (xy 132.456682 -263.700006) (xy 132.432806 -263.685528) (xy 132.136896 -263.685528)
			(xy 132.11302 -263.700006) (xy 132.106416 -263.712452) (xy 132.093942 -263.734702) (xy 132.063214 -263.775415)
			(xy 132.026606 -263.810933) (xy 131.984983 -263.840417) (xy 131.93933 -263.863168) (xy 131.890728 -263.878647)
			(xy 131.840327 -263.886489) (xy 131.814824 -263.88695) (xy 131.788834 -263.886442) (xy 131.737495 -263.878315)
			(xy 131.688058 -263.862257) (xy 131.641742 -263.838663) (xy 131.599687 -263.808114) (xy 131.562929 -263.771363)
			(xy 131.532372 -263.729314) (xy 131.508769 -263.683003) (xy 131.4927 -263.63357) (xy 131.484563 -263.582232)
			(xy 131.484116 -263.556242) (xy 131.48437 -263.544812) (xy 131.484878 -263.530334) (xy 131.471162 -263.506204)
			(xy 130.621278 -263.017762) (xy 130.593592 -263.01827) (xy 130.5814 -263.02589) (xy 130.561496 -263.037985)
			(xy 130.519013 -263.057074) (xy 130.474272 -263.070013) (xy 130.428157 -263.076545) (xy 130.40487 -263.076944)
			(xy 130.379363 -263.076478) (xy 130.328953 -263.068658) (xy 130.280341 -263.053193) (xy 130.234678 -263.03045)
			(xy 130.193047 -263.000967) (xy 130.156436 -262.965444) (xy 130.125711 -262.924721) (xy 130.113278 -262.902446)
			(xy 130.106674 -262.89) (xy 130.082798 -262.875776) (xy 129.786888 -262.875776) (xy 129.763012 -262.89)
			(xy 129.756408 -262.902446) (xy 129.743935 -262.924695) (xy 129.713209 -262.965405) (xy 129.6766 -263.00092)
			(xy 129.634976 -263.030396) (xy 129.589322 -263.053137) (xy 129.540719 -263.068603) (xy 129.490318 -263.076429)
			(xy 129.439314 -263.076429) (xy 129.388913 -263.068603) (xy 129.34031 -263.053137) (xy 129.294656 -263.030396)
			(xy 129.253032 -263.00092) (xy 129.216423 -262.965405) (xy 129.185697 -262.924695) (xy 129.173224 -262.902446)
			(xy 129.16662 -262.89) (xy 129.142744 -262.875776) (xy 128.846834 -262.875776) (xy 128.822958 -262.89)
			(xy 128.816354 -262.902446) (xy 128.803881 -262.924695) (xy 128.773155 -262.965405) (xy 128.736546 -263.00092)
			(xy 128.694922 -263.030396) (xy 128.649268 -263.053137) (xy 128.600665 -263.068603) (xy 128.550264 -263.076429)
			(xy 128.49926 -263.076429) (xy 128.448859 -263.068603) (xy 128.400256 -263.053137) (xy 128.354602 -263.030396)
			(xy 128.312978 -263.00092) (xy 128.276369 -262.965405) (xy 128.245643 -262.924695) (xy 128.23317 -262.902446)
			(xy 128.226566 -262.89) (xy 128.20269 -262.875776) (xy 127.90678 -262.875776) (xy 127.882904 -262.89)
			(xy 127.8763 -262.902446) (xy 127.863826 -262.924695) (xy 127.833098 -262.965408) (xy 127.796489 -263.000925)
			(xy 127.754866 -263.030407) (xy 127.709213 -263.053156) (xy 127.660612 -263.068634) (xy 127.610211 -263.076474)
			(xy 127.584708 -263.076944) (xy 127.57531 -263.07669) (xy 127.561086 -263.076436) (xy 127.536956 -263.089898)
			(xy 127.389382 -263.343898) (xy 127.389636 -263.371838) (xy 127.397002 -263.383776) (xy 127.408518 -263.403329)
			(xy 127.426671 -263.444919) (xy 127.438963 -263.4886) (xy 127.445165 -263.533553) (xy 127.445516 -263.556242)
			(xy 127.445006 -263.582229) (xy 127.436876 -263.633564) (xy 127.420815 -263.682994) (xy 127.397219 -263.729304)
			(xy 127.366669 -263.771352) (xy 127.329918 -263.808103) (xy 127.28787 -263.838653) (xy 127.24156 -263.862249)
			(xy 127.19213 -263.87831) (xy 127.140795 -263.88644) (xy 127.088821 -263.88644) (xy 127.037486 -263.87831)
			(xy 126.988056 -263.862249) (xy 126.941746 -263.838653) (xy 126.899698 -263.808103) (xy 126.862947 -263.771352)
			(xy 126.832397 -263.729304) (xy 126.808801 -263.682994) (xy 126.79274 -263.633564) (xy 126.78461 -263.582229)
			(xy 126.7841 -263.556242) (xy 126.784354 -263.544558) (xy 126.784862 -263.530334) (xy 126.7714 -263.50595)
			(xy 125.921262 -263.017762) (xy 125.893576 -263.01827) (xy 125.881384 -263.02589) (xy 125.86148 -263.037984)
			(xy 125.818997 -263.057071) (xy 125.774255 -263.070008) (xy 125.728141 -263.076537) (xy 125.704854 -263.076944)
			(xy 125.695202 -263.07669) (xy 125.681232 -263.076436) (xy 125.656848 -263.089898) (xy 125.509528 -263.344152)
			(xy 125.509782 -263.372092) (xy 125.516894 -263.38403) (xy 125.528392 -263.403556) (xy 125.546521 -263.445084)
			(xy 125.558807 -263.4887) (xy 125.565019 -263.533586) (xy 125.565408 -263.556242) (xy 125.564898 -263.582229)
			(xy 125.556768 -263.633564) (xy 125.540707 -263.682994) (xy 125.517111 -263.729304) (xy 125.486561 -263.771352)
			(xy 125.44981 -263.808103) (xy 125.407762 -263.838653) (xy 125.361452 -263.862249) (xy 125.312022 -263.87831)
			(xy 125.260687 -263.88644) (xy 125.208713 -263.88644) (xy 125.157378 -263.87831) (xy 125.107948 -263.862249)
			(xy 125.061638 -263.838653) (xy 125.01959 -263.808103) (xy 124.982839 -263.771352) (xy 124.952289 -263.729304)
			(xy 124.928693 -263.682994) (xy 124.912632 -263.633564) (xy 124.904502 -263.582229) (xy 124.903992 -263.556242)
			(xy 124.904246 -263.544558) (xy 124.904754 -263.530334) (xy 124.891292 -263.50595) (xy 124.041154 -263.017762)
			(xy 124.013468 -263.01827) (xy 124.001276 -263.02589) (xy 123.981372 -263.037983) (xy 123.938888 -263.05707)
			(xy 123.894147 -263.070005) (xy 123.848033 -263.076533) (xy 123.824746 -263.076944) (xy 123.798753 -263.076464)
			(xy 123.747407 -263.068339) (xy 123.697964 -263.052281) (xy 123.651642 -263.028687) (xy 123.609581 -262.998136)
			(xy 123.572818 -262.961381) (xy 123.542256 -262.919328) (xy 123.51865 -262.873012) (xy 123.50258 -262.823573)
			(xy 123.494442 -262.772229) (xy 123.494038 -262.746236) (xy 123.494292 -262.734552) (xy 123.4948 -262.720328)
			(xy 123.481338 -262.695944) (xy 122.6312 -262.207756) (xy 122.603514 -262.208264) (xy 122.591322 -262.215884)
			(xy 122.571418 -262.22798) (xy 122.528936 -262.247073) (xy 122.484195 -262.260015) (xy 122.43808 -262.26655)
			(xy 122.414792 -262.266938) (xy 122.40514 -262.266684) (xy 122.39117 -262.26643) (xy 122.366786 -262.279892)
			(xy 122.219466 -262.534146) (xy 122.21972 -262.562086) (xy 122.226832 -262.574024) (xy 122.238329 -262.59355)
			(xy 122.256457 -262.635079) (xy 122.268742 -262.678695) (xy 122.274954 -262.72358) (xy 122.275346 -262.746236)
			(xy 122.274836 -262.772223) (xy 122.266706 -262.823558) (xy 122.250645 -262.872988) (xy 122.227049 -262.919298)
			(xy 122.196499 -262.961346) (xy 122.159748 -262.998097) (xy 122.1177 -263.028647) (xy 122.07139 -263.052243)
			(xy 122.02196 -263.068304) (xy 121.970625 -263.076434) (xy 121.918651 -263.076434) (xy 121.867316 -263.068304)
			(xy 121.817886 -263.052243) (xy 121.771576 -263.028647) (xy 121.729528 -262.998097) (xy 121.692777 -262.961346)
			(xy 121.662227 -262.919298) (xy 121.638631 -262.872988) (xy 121.62257 -262.823558) (xy 121.61444 -262.772223)
			(xy 121.61393 -262.746236) (xy 121.614184 -262.734552) (xy 121.614692 -262.720328) (xy 121.60123 -262.695944)
			(xy 120.46585 -262.043672) (xy 120.455182 -262.035544) (xy 120.232424 -261.812532) (xy 120.225002 -261.805747)
			(xy 120.206405 -261.79814) (xy 120.196356 -261.7978) (xy 116.513356 -261.7978) (xy 116.503289 -261.797369)
			(xy 116.484697 -261.789643) (xy 116.477288 -261.782814) (xy 116.365782 -261.671054) (xy 116.337334 -261.664704)
			(xy 116.323364 -261.670038) (xy 116.293004 -261.680242) (xy 116.22991 -261.691224) (xy 116.197888 -261.691882)
			(xy 116.171778 -261.691429) (xy 116.120079 -261.684067) (xy 116.069934 -261.669491) (xy 116.022344 -261.647992)
			(xy 115.97826 -261.62) (xy 115.938561 -261.586074) (xy 115.904041 -261.54689) (xy 115.875388 -261.503233)
			(xy 115.863878 -261.479792) (xy 115.857528 -261.466076) (xy 115.83289 -261.450328) (xy 115.612926 -261.450328)
			(xy 115.588288 -261.466076) (xy 115.581938 -261.479792) (xy 115.569632 -261.504784) (xy 115.53863 -261.551066)
			(xy 115.501025 -261.592163) (xy 115.457671 -261.627142) (xy 115.409551 -261.655208) (xy 115.357761 -261.675723)
			(xy 115.303475 -261.688222) (xy 115.247928 -261.69242) (xy 115.192381 -261.688222) (xy 115.138095 -261.675723)
			(xy 115.086305 -261.655208) (xy 115.038185 -261.627142) (xy 114.994831 -261.592163) (xy 114.957226 -261.551066)
			(xy 114.926224 -261.504784) (xy 114.913918 -261.479792) (xy 114.907568 -261.466076) (xy 114.88293 -261.450328)
			(xy 114.662966 -261.450328) (xy 114.638328 -261.466076) (xy 114.631978 -261.479792) (xy 114.619672 -261.504784)
			(xy 114.58867 -261.551066) (xy 114.551065 -261.592163) (xy 114.507711 -261.627142) (xy 114.459591 -261.655208)
			(xy 114.407801 -261.675723) (xy 114.353515 -261.688222) (xy 114.297968 -261.69242) (xy 114.242421 -261.688222)
			(xy 114.188135 -261.675723) (xy 114.136345 -261.655208) (xy 114.088225 -261.627142) (xy 114.044871 -261.592163)
			(xy 114.007266 -261.551066) (xy 113.976264 -261.504784) (xy 113.963958 -261.479792) (xy 113.957608 -261.466076)
			(xy 113.93297 -261.450328) (xy 113.713006 -261.450328) (xy 113.688368 -261.466076) (xy 113.682018 -261.479792)
			(xy 113.669712 -261.504784) (xy 113.63871 -261.551066) (xy 113.601105 -261.592163) (xy 113.557751 -261.627142)
			(xy 113.509631 -261.655208) (xy 113.457841 -261.675723) (xy 113.403555 -261.688222) (xy 113.348008 -261.69242)
			(xy 113.292461 -261.688222) (xy 113.238175 -261.675723) (xy 113.186385 -261.655208) (xy 113.138265 -261.627142)
			(xy 113.094911 -261.592163) (xy 113.057306 -261.551066) (xy 113.026304 -261.504784) (xy 113.013998 -261.479792)
			(xy 113.007648 -261.466076) (xy 112.98301 -261.450328) (xy 112.762792 -261.450328) (xy 112.738154 -261.466076)
			(xy 112.731804 -261.479792) (xy 112.719498 -261.504784) (xy 112.688496 -261.551066) (xy 112.650891 -261.592163)
			(xy 112.607537 -261.627142) (xy 112.559417 -261.655208) (xy 112.507627 -261.675723) (xy 112.453341 -261.688222)
			(xy 112.397794 -261.69242) (xy 112.342247 -261.688222) (xy 112.287961 -261.675723) (xy 112.236171 -261.655208)
			(xy 112.188051 -261.627142) (xy 112.144697 -261.592163) (xy 112.107092 -261.551066) (xy 112.07609 -261.504784)
			(xy 112.063784 -261.479792) (xy 112.057434 -261.466076) (xy 112.032796 -261.450328) (xy 111.812832 -261.450328)
			(xy 111.788194 -261.466076) (xy 111.781844 -261.479792) (xy 111.769538 -261.504784) (xy 111.738536 -261.551066)
			(xy 111.700931 -261.592163) (xy 111.657577 -261.627142) (xy 111.609457 -261.655208) (xy 111.557667 -261.675723)
			(xy 111.503381 -261.688222) (xy 111.447834 -261.69242) (xy 111.392287 -261.688222) (xy 111.338001 -261.675723)
			(xy 111.286211 -261.655208) (xy 111.238091 -261.627142) (xy 111.194737 -261.592163) (xy 111.157132 -261.551066)
			(xy 111.12613 -261.504784) (xy 111.113824 -261.479792) (xy 111.107474 -261.466076) (xy 111.082836 -261.450328)
			(xy 110.862872 -261.450328) (xy 110.838234 -261.466076) (xy 110.831884 -261.479792) (xy 110.819578 -261.504784)
			(xy 110.788576 -261.551066) (xy 110.750971 -261.592163) (xy 110.707617 -261.627142) (xy 110.659497 -261.655208)
			(xy 110.607707 -261.675723) (xy 110.553421 -261.688222) (xy 110.497874 -261.69242) (xy 110.442327 -261.688222)
			(xy 110.388041 -261.675723) (xy 110.336251 -261.655208) (xy 110.288131 -261.627142) (xy 110.244777 -261.592163)
			(xy 110.207172 -261.551066) (xy 110.17617 -261.504784) (xy 110.163864 -261.479792) (xy 110.157514 -261.466076)
			(xy 110.132876 -261.450328) (xy 109.912912 -261.450328) (xy 109.888274 -261.466076) (xy 109.881924 -261.479792)
			(xy 109.869618 -261.504784) (xy 109.838616 -261.551066) (xy 109.801011 -261.592163) (xy 109.757657 -261.627142)
			(xy 109.709537 -261.655208) (xy 109.657747 -261.675723) (xy 109.603461 -261.688222) (xy 109.547914 -261.69242)
			(xy 109.492367 -261.688222) (xy 109.438081 -261.675723) (xy 109.386291 -261.655208) (xy 109.338171 -261.627142)
			(xy 109.294817 -261.592163) (xy 109.257212 -261.551066) (xy 109.22621 -261.504784) (xy 109.213904 -261.479792)
			(xy 109.207554 -261.466076) (xy 109.182916 -261.450328) (xy 108.962952 -261.450328) (xy 108.938314 -261.466076)
			(xy 108.931964 -261.479792) (xy 108.919658 -261.504784) (xy 108.888656 -261.551066) (xy 108.851051 -261.592163)
			(xy 108.807697 -261.627142) (xy 108.759577 -261.655208) (xy 108.707787 -261.675723) (xy 108.653501 -261.688222)
			(xy 108.597954 -261.69242) (xy 108.542407 -261.688222) (xy 108.488121 -261.675723) (xy 108.436331 -261.655208)
			(xy 108.388211 -261.627142) (xy 108.344857 -261.592163) (xy 108.307252 -261.551066) (xy 108.27625 -261.504784)
			(xy 108.263944 -261.479792) (xy 108.257594 -261.466076) (xy 108.232956 -261.450328) (xy 108.012992 -261.450328)
			(xy 107.988354 -261.466076) (xy 107.982004 -261.479792) (xy 107.969698 -261.504784) (xy 107.938696 -261.551066)
			(xy 107.901091 -261.592163) (xy 107.857737 -261.627142) (xy 107.809617 -261.655208) (xy 107.757827 -261.675723)
			(xy 107.703541 -261.688222) (xy 107.647994 -261.69242) (xy 107.592447 -261.688222) (xy 107.538161 -261.675723)
			(xy 107.486371 -261.655208) (xy 107.438251 -261.627142) (xy 107.394897 -261.592163) (xy 107.357292 -261.551066)
			(xy 107.32629 -261.504784) (xy 107.313984 -261.479792) (xy 107.307634 -261.466076) (xy 107.282996 -261.450328)
			(xy 106.72572 -261.450328) (xy 106.714616 -261.450898) (xy 106.694476 -261.460261) (xy 106.686858 -261.468362)
			(xy 106.669245 -261.488471) (xy 106.629215 -261.523896) (xy 106.584492 -261.553174) (xy 106.536012 -261.575693)
			(xy 106.48479 -261.590981) (xy 106.431899 -261.598719) (xy 106.405172 -261.599172) (xy 106.379365 -261.598776)
			(xy 106.328247 -261.591635) (xy 106.303318 -261.584948) (xy 106.289856 -261.580884) (xy 106.263186 -261.587742)
			(xy 105.838752 -262.01243) (xy 105.832402 -262.040878) (xy 105.837482 -262.054848) (xy 105.847754 -262.085197)
			(xy 105.858862 -262.148292) (xy 105.85958 -262.180324) (xy 105.85913 -262.206668) (xy 105.851629 -262.258819)
			(xy 105.836782 -262.309371) (xy 105.814891 -262.357296) (xy 105.786403 -262.401618) (xy 105.751897 -262.441434)
			(xy 105.712076 -262.475934) (xy 105.66775 -262.504416) (xy 105.619822 -262.5263) (xy 105.569268 -262.54114)
			(xy 105.517116 -262.548634) (xy 105.490772 -262.549132) (xy 105.46017 -262.548528) (xy 105.399805 -262.538422)
			(xy 105.341935 -262.518494) (xy 105.31475 -262.504428) (xy 105.301542 -262.497316) (xy 105.272332 -262.499094)
			(xy 103.689912 -263.663684) (xy 103.685086 -263.666732) (xy 102.554532 -264.315956) (xy 102.54107 -264.34034)
			(xy 102.541578 -264.354564) (xy 102.541832 -264.366248) (xy 102.541322 -264.392235) (xy 102.533192 -264.44357)
			(xy 102.517131 -264.493) (xy 102.493535 -264.53931) (xy 102.462985 -264.581358) (xy 102.426234 -264.618109)
			(xy 102.384186 -264.648659) (xy 102.337876 -264.672255) (xy 102.288446 -264.688316) (xy 102.237111 -264.696446)
			(xy 102.185137 -264.696446) (xy 102.133802 -264.688316) (xy 102.084372 -264.672255) (xy 102.038062 -264.648659)
			(xy 101.996014 -264.618109) (xy 101.959263 -264.581358) (xy 101.928713 -264.53931) (xy 101.905117 -264.493)
			(xy 101.889056 -264.44357) (xy 101.880926 -264.392235) (xy 101.880416 -264.366248) (xy 101.880805 -264.343592)
			(xy 101.887022 -264.298707) (xy 101.899307 -264.255091) (xy 101.917428 -264.213559) (xy 101.92893 -264.194036)
			(xy 101.936042 -264.182098) (xy 101.93655 -264.154158) (xy 101.788976 -263.899904) (xy 101.764592 -263.886442)
			(xy 101.750622 -263.886696) (xy 101.74097 -263.88695) (xy 101.717721 -263.886579) (xy 101.671678 -263.880105)
			(xy 101.626999 -263.867233) (xy 101.584569 -263.848217) (xy 101.564694 -263.83615) (xy 101.552502 -263.828276)
			(xy 101.524562 -263.827768) (xy 100.674678 -264.315956) (xy 100.660962 -264.34034) (xy 100.66147 -264.354818)
			(xy 100.661724 -264.366248) (xy 100.66147 -264.381234) (xy 100.660708 -264.395712) (xy 100.67417 -264.42035)
			(xy 101.52126 -264.907014) (xy 101.549454 -264.906252) (xy 101.561646 -264.898378) (xy 101.581783 -264.88587)
			(xy 101.624877 -264.866122) (xy 101.670349 -264.852731) (xy 101.717268 -264.845971) (xy 101.74097 -264.845546)
			(xy 101.766964 -264.846027) (xy 101.818314 -264.854156) (xy 101.867759 -264.870217) (xy 101.914083 -264.893817)
			(xy 101.956144 -264.924373) (xy 101.992908 -264.961133) (xy 102.023467 -265.003191) (xy 102.047071 -265.049513)
			(xy 102.063137 -265.098957) (xy 102.071271 -265.150306) (xy 102.071271 -265.202294) (xy 102.063137 -265.253643)
			(xy 102.047071 -265.303087) (xy 102.023467 -265.349409) (xy 101.992908 -265.391467) (xy 101.956144 -265.428227)
			(xy 101.914083 -265.458783) (xy 101.867759 -265.482383) (xy 101.818314 -265.498444) (xy 101.766964 -265.506573)
			(xy 101.74097 -265.506962) (xy 101.717683 -265.506563) (xy 101.671571 -265.500025) (xy 101.626831 -265.487084)
			(xy 101.584349 -265.467994) (xy 101.56444 -265.455908) (xy 101.552502 -265.448288) (xy 101.524562 -265.44778)
			(xy 100.674424 -265.935968) (xy 100.660962 -265.960352) (xy 100.66147 -265.974576) (xy 100.661724 -265.98626)
			(xy 100.66147 -266.001246) (xy 100.660708 -266.015724) (xy 100.674424 -266.040362) (xy 101.52126 -266.527026)
			(xy 101.549454 -266.526264) (xy 101.561646 -266.51839) (xy 101.581783 -266.505882) (xy 101.624877 -266.486133)
			(xy 101.670349 -266.472741) (xy 101.717268 -266.465981) (xy 101.74097 -266.465558) (xy 101.76696 -266.466065)
			(xy 101.8183 -266.474192) (xy 101.867737 -266.49025) (xy 101.914053 -266.513844) (xy 101.956108 -266.544392)
			(xy 101.992866 -266.581144) (xy 102.023423 -266.623193) (xy 102.047026 -266.669504) (xy 102.063093 -266.718938)
			(xy 102.07123 -266.770276) (xy 102.071678 -266.796266) (xy 102.071199 -266.821898) (xy 102.063296 -266.872549)
			(xy 102.05593 -266.897104) (xy 102.051358 -266.911074) (xy 102.058216 -266.938506) (xy 102.31755 -267.198094)
			(xy 102.324951 -267.204933) (xy 102.343549 -267.21265) (xy 102.353618 -267.21308) (xy 102.630224 -267.21308)
			(xy 102.636891 -267.212883) (xy 102.649764 -267.209407) (xy 102.655624 -267.206222) (xy 103.27767 -266.847574)
			(xy 103.291132 -266.82319) (xy 103.290624 -266.808712) (xy 103.29037 -266.796266) (xy 103.290882 -266.77028)
			(xy 103.299017 -266.718948) (xy 103.31508 -266.669521) (xy 103.338678 -266.623214) (xy 103.369228 -266.581169)
			(xy 103.405978 -266.54442) (xy 103.448025 -266.513871) (xy 103.494332 -266.490276) (xy 103.54376 -266.474214)
			(xy 103.595092 -266.466081) (xy 103.621078 -266.465558) (xy 103.632508 -266.465812) (xy 103.646732 -266.46632)
			(xy 103.671116 -266.452858) (xy 103.817674 -266.200382) (xy 103.81742 -266.172442) (xy 103.8098 -266.160504)
			(xy 103.798061 -266.140785) (xy 103.779537 -266.098798) (xy 103.766985 -266.054657) (xy 103.760644 -266.009206)
			(xy 103.76027 -265.98626) (xy 103.76078 -265.960273) (xy 103.76891 -265.908938) (xy 103.784971 -265.859508)
			(xy 103.808567 -265.813198) (xy 103.839117 -265.77115) (xy 103.875868 -265.734399) (xy 103.917916 -265.703849)
			(xy 103.964226 -265.680253) (xy 104.013656 -265.664192) (xy 104.064991 -265.656062) (xy 104.116965 -265.656062)
			(xy 104.1683 -265.664192) (xy 104.21773 -265.680253) (xy 104.26404 -265.703849) (xy 104.306088 -265.734399)
			(xy 104.342839 -265.77115) (xy 104.373389 -265.813198) (xy 104.396985 -265.859508) (xy 104.413046 -265.908938)
			(xy 104.421176 -265.960273) (xy 104.421686 -265.98626) (xy 104.421432 -266.001246) (xy 104.42067 -266.015724)
			(xy 104.434132 -266.040362) (xy 105.281222 -266.527026) (xy 105.309416 -266.526264) (xy 105.321608 -266.51839)
			(xy 105.341744 -266.50588) (xy 105.384837 -266.486126) (xy 105.43031 -266.472729) (xy 105.477229 -266.465963)
			(xy 105.500932 -266.465558) (xy 105.526919 -266.46607) (xy 105.578251 -266.474204) (xy 105.62768 -266.490268)
			(xy 105.673987 -266.513865) (xy 105.716034 -266.544414) (xy 105.752784 -266.581165) (xy 105.783334 -266.623211)
			(xy 105.806932 -266.669519) (xy 105.822995 -266.718947) (xy 105.83113 -266.770279) (xy 105.83164 -266.796266)
			(xy 105.831205 -266.819821) (xy 105.824487 -266.86645) (xy 105.811224 -266.911655) (xy 105.791684 -266.954523)
			(xy 105.779316 -266.974574) (xy 105.771696 -266.986766) (xy 105.770934 -267.01496) (xy 105.915206 -267.263372)
			(xy 105.939844 -267.276834) (xy 105.954322 -267.276072) (xy 105.971086 -267.275564) (xy 105.994412 -267.275988)
			(xy 106.040596 -267.282584) (xy 106.085399 -267.295592) (xy 106.127935 -267.314753) (xy 106.14787 -267.326872)
			(xy 106.159808 -267.334492) (xy 106.188256 -267.335) (xy 107.037378 -266.847066) (xy 107.051094 -266.822428)
			(xy 107.050586 -266.808458) (xy 107.050332 -266.796266) (xy 107.050818 -266.77028) (xy 107.058953 -266.718948)
			(xy 107.075019 -266.66952) (xy 107.098619 -266.623215) (xy 107.129173 -266.581171) (xy 107.165927 -266.544425)
			(xy 107.207978 -266.513881) (xy 107.254289 -266.490291) (xy 107.30372 -266.474236) (xy 107.355054 -266.466112)
			(xy 107.38104 -266.465558) (xy 107.39247 -266.465812) (xy 107.406694 -266.46632) (xy 107.431078 -266.452858)
			(xy 107.577636 -266.200382) (xy 107.577382 -266.172442) (xy 107.569762 -266.160504) (xy 107.558025 -266.140784)
			(xy 107.539503 -266.098797) (xy 107.526952 -266.054656) (xy 107.520611 -266.009205) (xy 107.520232 -265.98626)
			(xy 107.520742 -265.960273) (xy 107.528872 -265.908938) (xy 107.544933 -265.859508) (xy 107.568529 -265.813198)
			(xy 107.599079 -265.77115) (xy 107.63583 -265.734399) (xy 107.677878 -265.703849) (xy 107.724188 -265.680253)
			(xy 107.773618 -265.664192) (xy 107.824953 -265.656062) (xy 107.876927 -265.656062) (xy 107.928262 -265.664192)
			(xy 107.977692 -265.680253) (xy 108.024002 -265.703849) (xy 108.06605 -265.734399) (xy 108.102801 -265.77115)
			(xy 108.133351 -265.813198) (xy 108.156947 -265.859508) (xy 108.173008 -265.908938) (xy 108.181138 -265.960273)
			(xy 108.181648 -265.98626) (xy 108.181394 -266.001246) (xy 108.180632 -266.015724) (xy 108.194094 -266.040362)
			(xy 109.041438 -266.527026) (xy 109.069632 -266.526264) (xy 109.081824 -266.51839) (xy 109.10196 -266.505881)
			(xy 109.145054 -266.486129) (xy 109.190526 -266.472734) (xy 109.237446 -266.465971) (xy 109.261148 -266.465558)
			(xy 109.287134 -266.466071) (xy 109.338464 -266.474207) (xy 109.387891 -266.490272) (xy 109.434196 -266.51387)
			(xy 109.47624 -266.54442) (xy 109.512989 -266.58117) (xy 109.543537 -266.623216) (xy 109.567133 -266.669522)
			(xy 109.583196 -266.718949) (xy 109.59133 -266.77028) (xy 109.591856 -266.796266) (xy 109.59144 -266.819853)
			(xy 109.584742 -266.86655) (xy 109.571477 -266.911821) (xy 109.551915 -266.954748) (xy 109.539532 -266.974828)
			(xy 109.531658 -266.98702) (xy 109.53115 -267.015214) (xy 109.675168 -267.263372) (xy 109.699806 -267.276834)
			(xy 109.714284 -267.276072) (xy 109.731048 -267.275564) (xy 109.754375 -267.275986) (xy 109.800561 -267.282577)
			(xy 109.845366 -267.29558) (xy 109.887906 -267.314738) (xy 109.907832 -267.326872) (xy 109.91977 -267.334492)
			(xy 109.948218 -267.335) (xy 111.09198 -266.677648) (xy 111.097855 -266.674522) (xy 111.110727 -266.671166)
			(xy 111.11738 -266.671044) (xy 111.803434 -266.671044) (xy 111.809665 -266.670834) (xy 111.821742 -266.667752)
			(xy 111.82731 -266.664948) (xy 111.853608 -266.651446) (xy 111.90879 -266.630237) (xy 111.966149 -266.615931)
			(xy 112.024827 -266.608741) (xy 112.054386 -266.608306) (xy 112.083943 -266.608754) (xy 112.142616 -266.615966)
			(xy 112.199973 -266.630271) (xy 112.25516 -266.651457) (xy 112.281462 -266.664948) (xy 112.287031 -266.667753)
			(xy 112.299107 -266.670841) (xy 112.305338 -266.671044) (xy 113.63071 -266.671044) (xy 113.65484 -266.656312)
			(xy 113.661444 -266.643612) (xy 113.673786 -266.620968) (xy 113.704407 -266.579475) (xy 113.741097 -266.543237)
			(xy 113.782966 -266.513134) (xy 113.829002 -266.489894) (xy 113.878086 -266.474081) (xy 113.92903 -266.466079)
			(xy 113.954814 -266.465558) (xy 113.978516 -266.465966) (xy 114.025434 -266.472735) (xy 114.070905 -266.486134)
			(xy 114.113997 -266.505888) (xy 114.134138 -266.51839) (xy 114.14633 -266.526264) (xy 114.174524 -266.527026)
			(xy 115.021614 -266.040362) (xy 115.035076 -266.015724) (xy 115.034314 -266.001246) (xy 115.03406 -265.98626)
			(xy 115.03457 -265.960273) (xy 115.0427 -265.908938) (xy 115.058761 -265.859508) (xy 115.082357 -265.813198)
			(xy 115.112907 -265.77115) (xy 115.149658 -265.734399) (xy 115.191706 -265.703849) (xy 115.238016 -265.680253)
			(xy 115.287446 -265.664192) (xy 115.338781 -265.656062) (xy 115.390755 -265.656062) (xy 115.44209 -265.664192)
			(xy 115.49152 -265.680253) (xy 115.53783 -265.703849) (xy 115.579878 -265.734399) (xy 115.616629 -265.77115)
			(xy 115.647179 -265.813198) (xy 115.670775 -265.859508) (xy 115.686836 -265.908938) (xy 115.694966 -265.960273)
			(xy 115.695476 -265.98626) (xy 115.695087 -266.009175) (xy 115.688756 -266.054567) (xy 115.67621 -266.098647)
			(xy 115.657689 -266.140569) (xy 115.645946 -266.16025) (xy 115.638326 -266.172442) (xy 115.638072 -266.200382)
			(xy 115.78463 -266.452858) (xy 115.809014 -266.46632) (xy 115.823238 -266.465812) (xy 115.834668 -266.465558)
			(xy 115.860658 -266.466065) (xy 115.911998 -266.474192) (xy 115.961435 -266.490249) (xy 116.007752 -266.513843)
			(xy 116.049807 -266.544391) (xy 116.086566 -266.581143) (xy 116.117123 -266.623192) (xy 116.140725 -266.669504)
			(xy 116.156793 -266.718938) (xy 116.16493 -266.770276) (xy 116.165376 -266.796266) (xy 116.165122 -266.808204)
			(xy 116.164614 -266.822682) (xy 116.178076 -266.846812) (xy 117.02796 -267.335) (xy 117.055646 -267.334492)
			(xy 117.067838 -267.326872) (xy 117.087756 -267.314718) (xy 117.130287 -267.295527) (xy 117.175097 -267.282518)
			(xy 117.221292 -267.27595) (xy 117.244622 -267.275564) (xy 117.261386 -267.276072) (xy 117.275864 -267.276834)
			(xy 117.300756 -267.263372) (xy 117.444774 -267.01496) (xy 117.444012 -266.986766) (xy 117.436392 -266.974574)
			(xy 117.424021 -266.954523) (xy 117.404465 -266.91166) (xy 117.391195 -266.866455) (xy 117.38448 -266.819822)
			(xy 117.384068 -266.796266) (xy 117.38458 -266.77028) (xy 117.392715 -266.718948) (xy 117.408778 -266.669521)
			(xy 117.432376 -266.623214) (xy 117.462926 -266.581169) (xy 117.499676 -266.544419) (xy 117.541723 -266.51387)
			(xy 117.58803 -266.490275) (xy 117.637458 -266.474212) (xy 117.68879 -266.466079) (xy 117.714776 -266.465558)
			(xy 117.738479 -266.465963) (xy 117.785399 -266.472728) (xy 117.830873 -266.486122) (xy 117.873969 -266.505872)
			(xy 117.8941 -266.51839) (xy 117.906292 -266.526264) (xy 117.934486 -266.527026) (xy 118.781576 -266.040362)
			(xy 118.795038 -266.015724) (xy 118.794276 -266.001246) (xy 118.794022 -265.98626) (xy 118.794532 -265.960273)
			(xy 118.802662 -265.908938) (xy 118.818723 -265.859508) (xy 118.842319 -265.813198) (xy 118.872869 -265.77115)
			(xy 118.90962 -265.734399) (xy 118.951668 -265.703849) (xy 118.997978 -265.680253) (xy 119.047408 -265.664192)
			(xy 119.098743 -265.656062) (xy 119.150717 -265.656062) (xy 119.202052 -265.664192) (xy 119.251482 -265.680253)
			(xy 119.297792 -265.703849) (xy 119.33984 -265.734399) (xy 119.376591 -265.77115) (xy 119.407141 -265.813198)
			(xy 119.430737 -265.859508) (xy 119.446798 -265.908938) (xy 119.454928 -265.960273) (xy 119.455438 -265.98626)
			(xy 119.455049 -266.009175) (xy 119.448717 -266.054566) (xy 119.436169 -266.098645) (xy 119.417647 -266.140566)
			(xy 119.405908 -266.16025) (xy 119.398288 -266.172442) (xy 119.398034 -266.200382) (xy 119.544592 -266.452858)
			(xy 119.568976 -266.46632) (xy 119.5832 -266.465812) (xy 119.59463 -266.465558) (xy 119.620617 -266.46607)
			(xy 119.671949 -266.474204) (xy 119.721378 -266.490267) (xy 119.767686 -266.513864) (xy 119.809733 -266.544414)
			(xy 119.846484 -266.581164) (xy 119.877034 -266.623211) (xy 119.900631 -266.669518) (xy 119.916695 -266.718947)
			(xy 119.92483 -266.770279) (xy 119.925338 -266.796266) (xy 119.925084 -266.808204) (xy 119.924576 -266.822682)
			(xy 119.938038 -266.846812) (xy 120.787668 -267.335) (xy 120.816116 -267.334492) (xy 120.828054 -267.326872)
			(xy 120.847972 -267.314719) (xy 120.890503 -267.29553) (xy 120.935313 -267.282523) (xy 120.981508 -267.275957)
			(xy 121.004838 -267.275564) (xy 121.021602 -267.276072) (xy 121.035826 -267.276834) (xy 121.060718 -267.263372)
			(xy 121.204736 -267.01496) (xy 121.203974 -266.986766) (xy 121.196354 -266.974574) (xy 121.183984 -266.954523)
			(xy 121.16443 -266.911659) (xy 121.151162 -266.866454) (xy 121.144448 -266.819822) (xy 121.14403 -266.796266)
			(xy 121.144516 -266.77028) (xy 121.152651 -266.718947) (xy 121.168717 -266.66952) (xy 121.192317 -266.623214)
			(xy 121.222871 -266.58117) (xy 121.259625 -266.544424) (xy 121.301676 -266.51388) (xy 121.347986 -266.49029)
			(xy 121.397417 -266.474235) (xy 121.448751 -266.46611) (xy 121.474738 -266.465558) (xy 121.498439 -266.465967)
			(xy 121.545356 -266.47274) (xy 121.590825 -266.486142) (xy 121.633915 -266.505898) (xy 121.654062 -266.51839)
			(xy 121.666254 -266.526264) (xy 121.694448 -266.527026) (xy 122.541538 -266.040616) (xy 122.555 -266.015724)
			(xy 122.554238 -266.001246) (xy 122.553984 -265.98626) (xy 122.554494 -265.960273) (xy 122.562624 -265.908938)
			(xy 122.578685 -265.859508) (xy 122.602281 -265.813198) (xy 122.632831 -265.77115) (xy 122.669582 -265.734399)
			(xy 122.71163 -265.703849) (xy 122.75794 -265.680253) (xy 122.80737 -265.664192) (xy 122.858705 -265.656062)
			(xy 122.910679 -265.656062) (xy 122.962014 -265.664192) (xy 123.011444 -265.680253) (xy 123.057754 -265.703849)
			(xy 123.099802 -265.734399) (xy 123.136553 -265.77115) (xy 123.167103 -265.813198) (xy 123.190699 -265.859508)
			(xy 123.20676 -265.908938) (xy 123.21489 -265.960273) (xy 123.2154 -265.98626) (xy 123.215011 -266.009176)
			(xy 123.208681 -266.054567) (xy 123.196135 -266.098647) (xy 123.177616 -266.14057) (xy 123.16587 -266.16025)
			(xy 123.158504 -266.172188) (xy 123.157996 -266.200128) (xy 123.304808 -266.452858) (xy 123.329192 -266.46632)
			(xy 123.343416 -266.465812) (xy 123.354846 -266.465558) (xy 123.380832 -266.466071) (xy 123.432163 -266.474207)
			(xy 123.481589 -266.490272) (xy 123.527895 -266.513869) (xy 123.56994 -266.544419) (xy 123.606688 -266.58117)
			(xy 123.637237 -266.623215) (xy 123.660833 -266.669522) (xy 123.676896 -266.718949) (xy 123.68503 -266.77028)
			(xy 123.685554 -266.796266) (xy 123.6853 -266.808458) (xy 123.684792 -266.822428) (xy 123.698508 -266.847066)
			(xy 124.54763 -267.335) (xy 124.576078 -267.334492) (xy 124.588016 -267.326872) (xy 124.607935 -267.314723)
			(xy 124.650468 -267.295542) (xy 124.695277 -267.282544) (xy 124.741471 -267.275986) (xy 124.7648 -267.275564)
			(xy 124.781564 -267.276072) (xy 124.796042 -267.276834) (xy 124.82068 -267.263372) (xy 124.964698 -267.015214)
			(xy 124.96419 -266.98702) (xy 124.956316 -266.974828) (xy 124.943946 -266.954742) (xy 124.924397 -266.911813)
			(xy 124.911138 -266.866544) (xy 124.904435 -266.819851) (xy 124.903992 -266.796266) (xy 124.904504 -266.770281)
			(xy 124.912639 -266.71895) (xy 124.928703 -266.669524) (xy 124.952301 -266.623219) (xy 124.982851 -266.581176)
			(xy 125.019602 -266.544429) (xy 125.061648 -266.513883) (xy 125.107956 -266.49029) (xy 125.157383 -266.474231)
			(xy 125.208715 -266.466101) (xy 125.2347 -266.465558) (xy 125.260486 -266.466052) (xy 125.311433 -266.474056)
			(xy 125.36052 -266.489872) (xy 125.406557 -266.513115) (xy 125.448429 -266.543221) (xy 125.48512 -266.579462)
			(xy 125.515742 -266.620959) (xy 125.52807 -266.643612) (xy 125.534674 -266.656312) (xy 125.558804 -266.671044)
			(xy 125.879098 -266.671044) (xy 125.902466 -266.657328) (xy 125.909324 -266.645136) (xy 125.921071 -266.625378)
			(xy 125.949569 -266.589314) (xy 125.983148 -266.557925) (xy 126.02105 -266.531921) (xy 126.06242 -266.511889)
			(xy 126.106324 -266.49828) (xy 126.151771 -266.491402) (xy 126.174754 -266.490958) (xy 126.19875 -266.491401)
			(xy 126.246154 -266.498902) (xy 126.2918 -266.513726) (xy 126.334564 -266.535508) (xy 126.373395 -266.563712)
			(xy 126.407336 -266.597644) (xy 126.43555 -266.636467) (xy 126.457344 -266.679226) (xy 126.47218 -266.724869)
			(xy 126.479693 -266.77227) (xy 126.480062 -266.796266) (xy 126.479542 -266.822534) (xy 126.4706 -266.874301)
			(xy 126.452922 -266.923771) (xy 126.440438 -266.946888) (xy 126.43358 -266.958826) (xy 126.433834 -266.985496)
			(xy 126.594616 -267.262864) (xy 126.619 -267.276326) (xy 126.633224 -267.275818) (xy 126.644654 -267.275564)
			(xy 126.670646 -267.276044) (xy 126.721992 -267.284169) (xy 126.771435 -267.300227) (xy 126.817756 -267.323822)
			(xy 126.859816 -267.354373) (xy 126.896579 -267.391127) (xy 126.92714 -267.433181) (xy 126.950745 -267.479497)
			(xy 126.966814 -267.528936) (xy 126.974951 -267.58028) (xy 126.975362 -267.606272) (xy 126.974972 -267.629187)
			(xy 126.968639 -267.674578) (xy 126.956091 -267.718656) (xy 126.937569 -267.760577) (xy 126.925832 -267.780262)
			(xy 126.918466 -267.7922) (xy 126.918212 -267.82014) (xy 127.06477 -268.07287) (xy 127.089154 -268.086332)
			(xy 127.103378 -268.085824) (xy 127.114808 -268.08557) (xy 127.140795 -268.08608) (xy 127.19213 -268.094212)
			(xy 127.241561 -268.110273) (xy 127.287871 -268.133869) (xy 127.32992 -268.164418) (xy 127.366672 -268.201169)
			(xy 127.397224 -268.243217) (xy 127.420822 -268.289526) (xy 127.436885 -268.338956) (xy 127.445019 -268.390291)
			(xy 127.445516 -268.416278) (xy 127.445126 -268.439193) (xy 127.438793 -268.484584) (xy 127.426246 -268.528663)
			(xy 127.407726 -268.570585) (xy 127.395986 -268.590268) (xy 127.38862 -268.602206) (xy 127.388112 -268.630146)
			(xy 127.53467 -268.882876) (xy 127.559054 -268.896338) (xy 127.573278 -268.89583) (xy 127.584708 -268.895576)
			(xy 127.610696 -268.896086) (xy 127.662032 -268.904218) (xy 127.711464 -268.920281) (xy 127.757775 -268.943878)
			(xy 127.799824 -268.974429) (xy 127.836576 -269.011182) (xy 127.867126 -269.053232) (xy 127.890722 -269.099544)
			(xy 127.906784 -269.148976) (xy 127.914914 -269.200312) (xy 127.914914 -269.252288) (xy 127.906784 -269.303624)
			(xy 127.890722 -269.353056) (xy 127.867126 -269.399368) (xy 127.836576 -269.441418) (xy 127.799824 -269.478171)
			(xy 127.757775 -269.508722) (xy 127.711464 -269.532319) (xy 127.662032 -269.548382) (xy 127.610696 -269.556514)
			(xy 127.584708 -269.556992) (xy 127.57531 -269.556738) (xy 127.561086 -269.556484) (xy 127.53721 -269.569946)
			(xy 127.389636 -269.8242) (xy 127.38989 -269.85214) (xy 127.397256 -269.864078) (xy 127.408712 -269.883617)
			(xy 127.426764 -269.925157) (xy 127.438984 -269.968771) (xy 127.445146 -270.013643) (xy 127.445516 -270.03629)
			(xy 127.445034 -270.06228) (xy 127.436904 -270.11362) (xy 127.420842 -270.163057) (xy 127.397245 -270.209372)
			(xy 127.366693 -270.251425) (xy 127.329939 -270.288182) (xy 127.287887 -270.318736) (xy 127.241573 -270.342336)
			(xy 127.192138 -270.358399) (xy 127.140798 -270.366532) (xy 127.114808 -270.366998) (xy 127.10541 -270.366744)
			(xy 127.09144 -270.36649) (xy 127.067056 -270.379952) (xy 126.919482 -270.63446) (xy 126.919736 -270.662146)
			(xy 126.927102 -270.674084) (xy 126.938559 -270.693622) (xy 126.956613 -270.735163) (xy 126.968834 -270.778776)
			(xy 126.974996 -270.823649) (xy 126.975362 -270.846296) (xy 126.974976 -270.869169) (xy 126.968674 -270.914479)
			(xy 126.95619 -270.958489) (xy 126.937762 -271.00036) (xy 126.926086 -271.020032) (xy 126.918466 -271.032224)
			(xy 126.918212 -271.060164) (xy 127.06477 -271.312894) (xy 127.089154 -271.326356) (xy 127.103378 -271.325848)
			(xy 127.114808 -271.325594) (xy 127.140795 -271.326104) (xy 127.192128 -271.334236) (xy 127.241557 -271.350297)
			(xy 127.287866 -271.373894) (xy 127.329913 -271.404444) (xy 127.366663 -271.441195) (xy 127.397211 -271.483243)
			(xy 127.420806 -271.529552) (xy 127.436867 -271.578982) (xy 127.444997 -271.630315) (xy 127.445516 -271.656302)
			(xy 127.445125 -271.679217) (xy 127.438789 -271.724606) (xy 127.426239 -271.768684) (xy 127.407716 -271.810603)
			(xy 127.395986 -271.830292) (xy 127.38862 -271.84223) (xy 127.388112 -271.87017) (xy 127.53467 -272.1229)
			(xy 127.559308 -272.136362) (xy 127.573278 -272.135854) (xy 127.584708 -272.1356) (xy 127.610694 -272.13611)
			(xy 127.662026 -272.144241) (xy 127.711455 -272.160303) (xy 127.757762 -272.183898) (xy 127.799808 -272.214448)
			(xy 127.836558 -272.251198) (xy 127.867106 -272.293245) (xy 127.8907 -272.339553) (xy 127.90676 -272.388981)
			(xy 127.914891 -272.440314) (xy 127.914891 -272.492286) (xy 127.90676 -272.543619) (xy 127.8907 -272.593047)
			(xy 127.867106 -272.639355) (xy 127.836558 -272.681402) (xy 127.799808 -272.718152) (xy 127.757762 -272.748702)
			(xy 127.711455 -272.772297) (xy 127.662026 -272.788359) (xy 127.610694 -272.79649) (xy 127.584708 -272.797016)
			(xy 127.57531 -272.796762) (xy 127.561086 -272.796508) (xy 127.53721 -272.80997) (xy 127.389636 -273.064224)
			(xy 127.38989 -273.092164) (xy 127.397256 -273.104102) (xy 127.408711 -273.123641) (xy 127.426759 -273.165182)
			(xy 127.438977 -273.208796) (xy 127.445135 -273.253668) (xy 127.445516 -273.276314) (xy 127.445005 -273.302301)
			(xy 127.436873 -273.353634) (xy 127.420811 -273.403063) (xy 127.397215 -273.449371) (xy 127.366665 -273.491418)
			(xy 127.329914 -273.528169) (xy 127.287866 -273.558718) (xy 127.241558 -273.582313) (xy 127.192128 -273.598375)
			(xy 127.140795 -273.606506) (xy 127.114808 -273.607022) (xy 127.10541 -273.606768) (xy 127.09144 -273.606514)
			(xy 127.067056 -273.619976) (xy 126.919482 -273.874484) (xy 126.919736 -273.90217) (xy 126.927102 -273.914108)
			(xy 126.938558 -273.933647) (xy 126.956608 -273.975187) (xy 126.968827 -274.018801) (xy 126.974985 -274.063673)
			(xy 126.975362 -274.08632) (xy 126.974974 -274.109193) (xy 126.968669 -274.154501) (xy 126.956183 -274.19851)
			(xy 126.937753 -274.240378) (xy 126.926086 -274.260056) (xy 126.918466 -274.272248) (xy 126.918212 -274.300188)
			(xy 127.06477 -274.552918) (xy 127.089154 -274.56638) (xy 127.103378 -274.565872) (xy 127.114808 -274.565618)
			(xy 127.140796 -274.566102) (xy 127.192132 -274.574234) (xy 127.241564 -274.590297) (xy 127.287874 -274.613896)
			(xy 127.329922 -274.644449) (xy 127.366673 -274.681203) (xy 127.397222 -274.723255) (xy 127.420816 -274.769567)
			(xy 127.436874 -274.819001) (xy 127.445001 -274.870338) (xy 127.445516 -274.896326) (xy 127.445123 -274.91924)
			(xy 127.438784 -274.964628) (xy 127.426232 -275.008704) (xy 127.407707 -275.050622) (xy 127.395986 -275.070316)
			(xy 127.38862 -275.082254) (xy 127.388112 -275.110194) (xy 127.53467 -275.362924) (xy 127.559308 -275.376386)
			(xy 127.573278 -275.375878) (xy 127.584708 -275.375624) (xy 127.610692 -275.376134) (xy 127.662021 -275.384265)
			(xy 127.711446 -275.400325) (xy 127.757749 -275.423919) (xy 127.799792 -275.454466) (xy 127.836539 -275.491214)
			(xy 127.867085 -275.533257) (xy 127.890678 -275.579562) (xy 127.906737 -275.628987) (xy 127.914867 -275.680316)
			(xy 127.914867 -275.732284) (xy 127.906737 -275.783613) (xy 127.890678 -275.833038) (xy 127.867085 -275.879343)
			(xy 127.836539 -275.921386) (xy 127.799792 -275.958134) (xy 127.757749 -275.988681) (xy 127.711446 -276.012275)
			(xy 127.662021 -276.028335) (xy 127.610692 -276.036466) (xy 127.584708 -276.03704) (xy 127.57531 -276.036786)
			(xy 127.561086 -276.036532) (xy 127.53721 -276.049994) (xy 127.389636 -276.304248) (xy 127.38989 -276.332188)
			(xy 127.397256 -276.344126) (xy 127.408716 -276.363664) (xy 127.426773 -276.405204) (xy 127.439001 -276.448817)
			(xy 127.445169 -276.49369) (xy 127.445516 -276.516338) (xy 127.445004 -276.542323) (xy 127.436868 -276.593654)
			(xy 127.420804 -276.64308) (xy 127.397206 -276.689385) (xy 127.366656 -276.731428) (xy 127.329905 -276.768176)
			(xy 127.287859 -276.798722) (xy 127.241552 -276.822316) (xy 127.192125 -276.838375) (xy 127.140794 -276.846506)
			(xy 127.114808 -276.847046) (xy 127.10541 -276.846792) (xy 127.09144 -276.846538) (xy 127.067056 -276.86)
			(xy 126.919482 -277.114508) (xy 126.919736 -277.142194) (xy 126.927102 -277.154132) (xy 126.938563 -277.17367)
			(xy 126.956622 -277.215209) (xy 126.968851 -277.258823) (xy 126.97502 -277.303696) (xy 126.975362 -277.326344)
			(xy 126.974979 -277.349218) (xy 126.968684 -277.394531) (xy 126.956206 -277.438545) (xy 126.937783 -277.48042)
			(xy 126.926086 -277.50008) (xy 126.918466 -277.512272) (xy 126.918212 -277.540212) (xy 127.06477 -277.792942)
			(xy 127.089154 -277.806404) (xy 127.103378 -277.805896) (xy 127.114808 -277.805642) (xy 127.140795 -277.806126)
			(xy 127.19213 -277.814258) (xy 127.24156 -277.830322) (xy 127.287869 -277.853921) (xy 127.329915 -277.884474)
			(xy 127.366664 -277.921229) (xy 127.397209 -277.963281) (xy 127.4208 -278.009593) (xy 127.436855 -278.059026)
			(xy 127.444979 -278.110362) (xy 127.445516 -278.13635) (xy 127.445128 -278.159266) (xy 127.438799 -278.204658)
			(xy 127.426255 -278.248739) (xy 127.407738 -278.290663) (xy 127.395986 -278.31034) (xy 127.38862 -278.322532)
			(xy 127.388112 -278.350218) (xy 127.53467 -278.602948) (xy 127.559054 -278.61641) (xy 127.573278 -278.615902)
			(xy 127.584708 -278.615648) (xy 127.610698 -278.616158) (xy 127.662039 -278.624291) (xy 127.711475 -278.640355)
			(xy 127.757789 -278.663954) (xy 127.799842 -278.694508) (xy 127.836597 -278.731264) (xy 127.86715 -278.773318)
			(xy 127.890748 -278.819633) (xy 127.906811 -278.869069) (xy 127.914942 -278.92041) (xy 127.914942 -278.97239)
			(xy 127.906811 -279.023731) (xy 127.890748 -279.073167) (xy 127.86715 -279.119482) (xy 127.836597 -279.161536)
			(xy 127.799842 -279.198292) (xy 127.757789 -279.228846) (xy 127.711475 -279.252445) (xy 127.662039 -279.268509)
			(xy 127.610698 -279.276642) (xy 127.584708 -279.277064) (xy 127.561835 -279.276678) (xy 127.516524 -279.270377)
			(xy 127.472514 -279.257893) (xy 127.430643 -279.239466) (xy 127.410972 -279.227788) (xy 127.399034 -279.220422)
			(xy 127.371094 -279.219914) (xy 126.51867 -279.709372) (xy 126.504954 -279.733756) (xy 126.505462 -279.747726)
			(xy 126.505462 -279.756362) (xy 126.505073 -279.779277) (xy 126.498741 -279.824668) (xy 126.486194 -279.868748)
			(xy 126.467673 -279.910669) (xy 126.455932 -279.930352) (xy 126.448566 -279.94229) (xy 126.448058 -279.97023)
			(xy 126.594616 -280.22296) (xy 126.619 -280.236422) (xy 126.633224 -280.235914) (xy 126.644654 -280.23566)
			(xy 126.670647 -280.23614) (xy 126.721993 -280.244265) (xy 126.771435 -280.260323) (xy 126.817757 -280.283918)
			(xy 126.859818 -280.314468) (xy 126.896581 -280.351223) (xy 126.927142 -280.393276) (xy 126.950747 -280.439593)
			(xy 126.966817 -280.489031) (xy 126.974954 -280.540376) (xy 126.975362 -280.566368) (xy 126.974972 -280.589283)
			(xy 126.96864 -280.634674) (xy 126.956092 -280.678753) (xy 126.93757 -280.720674) (xy 126.925832 -280.740358)
			(xy 126.918466 -280.752296) (xy 126.917958 -280.780236) (xy 127.06477 -281.032966) (xy 127.089154 -281.046428)
			(xy 127.103124 -281.04592) (xy 127.114808 -281.045666) (xy 127.140797 -281.046176) (xy 127.192134 -281.054308)
			(xy 127.241568 -281.070371) (xy 127.28788 -281.09397) (xy 127.32993 -281.124522) (xy 127.366683 -281.161276)
			(xy 127.397235 -281.203327) (xy 127.420832 -281.24964) (xy 127.436893 -281.299073) (xy 127.445024 -281.350411)
			(xy 127.445024 -281.402389) (xy 127.436893 -281.453727) (xy 127.420832 -281.50316) (xy 127.397235 -281.549473)
			(xy 127.366683 -281.591524) (xy 127.32993 -281.628278) (xy 127.28788 -281.65883) (xy 127.241568 -281.682429)
			(xy 127.192134 -281.698492) (xy 127.140797 -281.706624) (xy 127.114808 -281.707082) (xy 127.10541 -281.706828)
			(xy 127.09144 -281.706574) (xy 127.066802 -281.720036) (xy 126.919228 -281.974544) (xy 126.919736 -282.00223)
			(xy 126.927102 -282.014168) (xy 126.93856 -282.033706) (xy 126.956616 -282.075246) (xy 126.96884 -282.11886)
			(xy 126.975003 -282.163733) (xy 126.975362 -282.18638) (xy 126.974977 -282.209253) (xy 126.968677 -282.254564)
			(xy 126.956195 -282.298576) (xy 126.937769 -282.340447) (xy 126.926086 -282.360116) (xy 126.918466 -282.372308)
			(xy 126.918212 -282.400248) (xy 127.06477 -282.652978) (xy 127.089154 -282.66644) (xy 127.103378 -282.665932)
			(xy 127.114808 -282.665678) (xy 127.140795 -282.666188) (xy 127.19213 -282.67432) (xy 127.24156 -282.690381)
			(xy 127.287869 -282.713977) (xy 127.329918 -282.744527) (xy 127.366669 -282.781278) (xy 127.39722 -282.823326)
			(xy 127.420817 -282.869635) (xy 127.436879 -282.919065) (xy 127.445011 -282.970399) (xy 127.445516 -282.996386)
			(xy 127.445126 -283.019301) (xy 127.438792 -283.064691) (xy 127.426244 -283.10877) (xy 127.407723 -283.150691)
			(xy 127.395986 -283.170376) (xy 127.38862 -283.182314) (xy 127.388112 -283.210254) (xy 127.53467 -283.462984)
			(xy 127.559308 -283.476446) (xy 127.573278 -283.475938) (xy 127.584708 -283.475684) (xy 127.610695 -283.476194)
			(xy 127.66203 -283.484326) (xy 127.711461 -283.500388) (xy 127.75777 -283.523985) (xy 127.799818 -283.554535)
			(xy 127.83657 -283.591288) (xy 127.867119 -283.633336) (xy 127.890715 -283.679647) (xy 127.906776 -283.729078)
			(xy 127.914906 -283.780413) (xy 127.914906 -283.832387) (xy 127.906776 -283.883722) (xy 127.890715 -283.933153)
			(xy 127.867119 -283.979464) (xy 127.83657 -284.021512) (xy 127.799818 -284.058265) (xy 127.75777 -284.088815)
			(xy 127.711461 -284.112412) (xy 127.66203 -284.128474) (xy 127.610695 -284.136606) (xy 127.584708 -284.1371)
			(xy 127.57531 -284.136846) (xy 127.561086 -284.136592) (xy 127.53721 -284.150054) (xy 127.389636 -284.404308)
			(xy 127.38989 -284.432248) (xy 127.397256 -284.444186) (xy 127.408712 -284.463725) (xy 127.426762 -284.505266)
			(xy 127.438982 -284.548879) (xy 127.445142 -284.593751) (xy 127.445516 -284.616398) (xy 127.445007 -284.642386)
			(xy 127.436876 -284.693721) (xy 127.420816 -284.743152) (xy 127.39722 -284.789462) (xy 127.36667 -284.831511)
			(xy 127.329919 -284.868264) (xy 127.287871 -284.898815) (xy 127.241561 -284.922412) (xy 127.19213 -284.938474)
			(xy 127.140795 -284.946606) (xy 127.114808 -284.947106) (xy 127.10541 -284.946852) (xy 127.09144 -284.946598)
			(xy 127.067056 -284.96006) (xy 126.919482 -285.214568) (xy 126.919736 -285.242254) (xy 126.927102 -285.254192)
			(xy 126.938559 -285.27373) (xy 126.956611 -285.315271) (xy 126.968832 -285.358885) (xy 126.974993 -285.403757)
			(xy 126.975362 -285.426404) (xy 126.974975 -285.449277) (xy 126.968672 -285.494587) (xy 126.956188 -285.538596)
			(xy 126.937759 -285.580466) (xy 126.926086 -285.60014) (xy 126.918466 -285.612332) (xy 126.918212 -285.640272)
			(xy 127.06477 -285.893002) (xy 127.089154 -285.906464) (xy 127.103378 -285.905956) (xy 127.114808 -285.905702)
			(xy 127.140797 -285.906186) (xy 127.192134 -285.914318) (xy 127.241566 -285.930381) (xy 127.287878 -285.953979)
			(xy 127.329927 -285.984532) (xy 127.36668 -286.021286) (xy 127.39723 -286.063338) (xy 127.420826 -286.10965)
			(xy 127.436886 -286.159084) (xy 127.445016 -286.210421) (xy 127.445516 -286.23641) (xy 127.445124 -286.259325)
			(xy 127.438787 -286.304713) (xy 127.426237 -286.348791) (xy 127.407713 -286.39071) (xy 127.395986 -286.4104)
			(xy 127.38862 -286.422338) (xy 127.388112 -286.450278) (xy 127.53467 -286.702754) (xy 127.559054 -286.716216)
			(xy 127.573278 -286.715708) (xy 127.584708 -286.715454) (xy 127.610698 -286.715964) (xy 127.662037 -286.724097)
			(xy 127.711472 -286.74016) (xy 127.757786 -286.763759) (xy 127.799838 -286.794313) (xy 127.836593 -286.831068)
			(xy 127.867145 -286.873121) (xy 127.890743 -286.919435) (xy 127.906805 -286.968871) (xy 127.914936 -287.02021)
			(xy 127.914936 -287.07219) (xy 127.906805 -287.123529) (xy 127.890743 -287.172965) (xy 127.867145 -287.219279)
			(xy 127.836593 -287.261332) (xy 127.799838 -287.298087) (xy 127.757786 -287.328641) (xy 127.711472 -287.35224)
			(xy 127.662037 -287.368303) (xy 127.610698 -287.376436) (xy 127.584708 -287.37687) (xy 127.575564 -287.376616)
			(xy 127.56134 -287.376362) (xy 127.53721 -287.389824) (xy 127.389636 -287.644332) (xy 127.38989 -287.672272)
			(xy 127.397256 -287.68421) (xy 127.40871 -287.703749) (xy 127.426757 -287.745291) (xy 127.438974 -287.788904)
			(xy 127.445131 -287.833776) (xy 127.445516 -287.856422) (xy 127.445005 -287.882408) (xy 127.436872 -287.933741)
			(xy 127.420809 -287.983169) (xy 127.397212 -288.029476) (xy 127.366662 -288.071522) (xy 127.329911 -288.108271)
			(xy 127.287864 -288.138819) (xy 127.241556 -288.162414) (xy 127.192127 -288.178475) (xy 127.140794 -288.186606)
			(xy 127.114808 -288.18713) (xy 127.10541 -288.186876) (xy 127.09144 -288.186622) (xy 127.067056 -288.200084)
			(xy 126.919482 -288.454592) (xy 126.919736 -288.482024) (xy 126.927102 -288.494216) (xy 126.938553 -288.513722)
			(xy 126.956598 -288.555198) (xy 126.968815 -288.598748) (xy 126.974976 -288.643558) (xy 126.975362 -288.666174)
			(xy 126.974972 -288.689089) (xy 126.968639 -288.734479) (xy 126.95609 -288.778558) (xy 126.937568 -288.820478)
			(xy 126.925832 -288.840164) (xy 126.918466 -288.852102) (xy 126.918212 -288.880042) (xy 127.06477 -289.132772)
			(xy 127.089154 -289.146234) (xy 127.103378 -289.145726) (xy 127.114808 -289.145472) (xy 127.140795 -289.145982)
			(xy 127.19213 -289.154114) (xy 127.241561 -289.170175) (xy 127.287871 -289.193771) (xy 127.329919 -289.224321)
			(xy 127.366672 -289.261072) (xy 127.397223 -289.303119) (xy 127.42082 -289.349428) (xy 127.436884 -289.398858)
			(xy 127.445017 -289.450193) (xy 127.445516 -289.47618) (xy 127.445126 -289.499095) (xy 127.438793 -289.544486)
			(xy 127.426246 -289.588565) (xy 127.407725 -289.630486) (xy 127.395986 -289.65017) (xy 127.38862 -289.662362)
			(xy 127.388112 -289.690048) (xy 127.53467 -289.942778) (xy 127.559054 -289.95624) (xy 127.573278 -289.955732)
			(xy 127.584708 -289.955478) (xy 127.610695 -289.955988) (xy 127.66203 -289.96412) (xy 127.71146 -289.980181)
			(xy 127.757769 -290.003777) (xy 127.799818 -290.034327) (xy 127.836569 -290.071078) (xy 127.86712 -290.113126)
			(xy 127.890717 -290.159435) (xy 127.906779 -290.208865) (xy 127.914911 -290.260199) (xy 127.915416 -290.286186)
			(xy 127.915026 -290.309101) (xy 127.908692 -290.354491) (xy 127.896144 -290.39857) (xy 127.877623 -290.440491)
			(xy 127.865886 -290.460176) (xy 127.85852 -290.472114) (xy 127.858012 -290.500054) (xy 128.004824 -290.752784)
			(xy 128.029208 -290.766246) (xy 128.043432 -290.765738) (xy 128.054862 -290.765484) (xy 128.080853 -290.765964)
			(xy 128.132197 -290.774091) (xy 128.181637 -290.79015) (xy 128.227956 -290.813745) (xy 128.270014 -290.844297)
			(xy 128.306774 -290.881051) (xy 128.337331 -290.923104) (xy 128.360933 -290.96942) (xy 128.376999 -291.018858)
			(xy 128.385132 -291.070201) (xy 128.38557 -291.096192) (xy 128.385179 -291.119107) (xy 128.378843 -291.164496)
			(xy 128.366293 -291.208574) (xy 128.347769 -291.250493) (xy 128.33604 -291.270182) (xy 128.328674 -291.282374)
			(xy 128.328166 -291.31006) (xy 128.474724 -291.56279) (xy 128.499108 -291.576252) (xy 128.513332 -291.575744)
			(xy 128.524762 -291.57549) (xy 128.550753 -291.57597) (xy 128.602097 -291.584097) (xy 128.651536 -291.600156)
			(xy 128.697855 -291.623751) (xy 128.739912 -291.654303) (xy 128.776671 -291.691058) (xy 128.807228 -291.733111)
			(xy 128.830829 -291.779427) (xy 128.846894 -291.828864) (xy 128.855027 -291.880207) (xy 128.85547 -291.906198)
			(xy 128.855078 -291.929113) (xy 128.848742 -291.974502) (xy 128.836191 -292.018579) (xy 128.817667 -292.060497)
			(xy 128.80594 -292.080188) (xy 128.798574 -292.092126) (xy 128.798066 -292.120066) (xy 128.944624 -292.372796)
			(xy 128.969008 -292.386258) (xy 128.983232 -292.38575) (xy 128.994662 -292.385496) (xy 129.020653 -292.385976)
			(xy 129.071996 -292.394103) (xy 129.121435 -292.410162) (xy 129.167754 -292.433758) (xy 129.20981 -292.464309)
			(xy 129.246569 -292.501064) (xy 129.277125 -292.543117) (xy 129.300725 -292.589433) (xy 129.316789 -292.638871)
			(xy 129.324921 -292.690213) (xy 129.32537 -292.716204) (xy 129.324995 -292.739109) (xy 129.318707 -292.784484)
			(xy 129.306222 -292.828559) (xy 129.287781 -292.870491) (xy 129.276094 -292.890194) (xy 129.268474 -292.902132)
			(xy 129.26822 -292.930072) (xy 129.414778 -293.182802) (xy 129.439162 -293.196264) (xy 129.453386 -293.195756)
			(xy 129.464816 -293.195502) (xy 129.490601 -293.195997) (xy 129.541545 -293.204004) (xy 129.590628 -293.219823)
			(xy 129.636661 -293.243068) (xy 129.678528 -293.273178) (xy 129.715213 -293.309421) (xy 129.745828 -293.35092)
			(xy 129.758186 -293.373556) (xy 129.76479 -293.386256) (xy 129.78892 -293.400988) (xy 130.080766 -293.400988)
			(xy 130.104896 -293.386256) (xy 130.1115 -293.373556) (xy 130.12384 -293.350908) (xy 130.154456 -293.309405)
			(xy 130.191143 -293.273158) (xy 130.233012 -293.243045) (xy 130.279049 -293.219795) (xy 130.328135 -293.203974)
			(xy 130.379083 -293.195964) (xy 130.40487 -293.195502) (xy 130.430861 -293.195983) (xy 130.482202 -293.20411)
			(xy 130.53164 -293.22017) (xy 130.577957 -293.243767) (xy 130.620011 -293.274318) (xy 130.656769 -293.311073)
			(xy 130.687323 -293.353126) (xy 130.710922 -293.399441) (xy 130.726985 -293.448878) (xy 130.735116 -293.50022)
			(xy 130.735578 -293.52621) (xy 130.735186 -293.549124) (xy 130.728848 -293.594513) (xy 130.716297 -293.638589)
			(xy 130.697771 -293.680507) (xy 130.686048 -293.7002) (xy 130.678682 -293.712392) (xy 130.678174 -293.740332)
			(xy 130.824732 -293.992808) (xy 130.849116 -294.00627) (xy 130.86334 -294.005762) (xy 130.87477 -294.005508)
			(xy 130.90076 -294.005989) (xy 130.952102 -294.014117) (xy 131.001539 -294.030176) (xy 131.047855 -294.053773)
			(xy 131.08991 -294.084325) (xy 131.126666 -294.12108) (xy 131.15722 -294.163133) (xy 131.180818 -294.209448)
			(xy 131.19688 -294.258885) (xy 131.20501 -294.310226) (xy 131.205478 -294.336216) (xy 131.205086 -294.35913)
			(xy 131.198747 -294.404519) (xy 131.186195 -294.448595) (xy 131.167669 -294.490512) (xy 131.155948 -294.510206)
			(xy 131.148582 -294.522144) (xy 131.148328 -294.550084) (xy 131.294886 -294.802814) (xy 131.31927 -294.816276)
			(xy 131.33324 -294.815768) (xy 131.34467 -294.815514) (xy 131.37066 -294.815995) (xy 131.422001 -294.824123)
			(xy 131.471438 -294.840182) (xy 131.517754 -294.863779) (xy 131.559808 -294.894331) (xy 131.596564 -294.931086)
			(xy 131.627117 -294.973139) (xy 131.650715 -295.019454) (xy 131.666776 -295.068891) (xy 131.674904 -295.120232)
			(xy 131.675378 -295.146222) (xy 131.67499 -295.169095) (xy 131.668685 -295.214404) (xy 131.656199 -295.258412)
			(xy 131.637769 -295.300281) (xy 131.626102 -295.319958) (xy 131.618482 -295.33215) (xy 131.618228 -295.359836)
			(xy 131.780534 -295.63949) (xy 131.803648 -295.652952) (xy 131.817618 -295.652952) (xy 131.843633 -295.653399)
			(xy 131.895032 -295.66147) (xy 131.944534 -295.677489) (xy 131.990917 -295.701061) (xy 132.033038 -295.731604)
			(xy 132.069857 -295.768365) (xy 132.100466 -295.810437) (xy 132.124111 -295.856783) (xy 132.140208 -295.906259)
			(xy 132.14836 -295.957646) (xy 132.148834 -295.98366) (xy 132.148325 -296.010354) (xy 132.139749 -296.063048)
			(xy 132.122812 -296.113678) (xy 132.097956 -296.160926) (xy 132.082286 -296.182542) (xy 132.077618 -296.189283)
			(xy 132.07244 -296.204829) (xy 132.072126 -296.213022) (xy 132.072126 -304.780442) (xy 140.011662 -304.780442)
			(xy 140.015692 -304.638092) (xy 140.027769 -304.496199) (xy 140.047854 -304.355216) (xy 140.075883 -304.215595)
			(xy 140.111767 -304.077783) (xy 140.155389 -303.942222) (xy 140.206611 -303.809347) (xy 140.265269 -303.679582)
			(xy 140.331174 -303.553343) (xy 140.404115 -303.431035) (xy 140.483859 -303.31305) (xy 140.570151 -303.199765)
			(xy 140.662713 -303.091544) (xy 140.76125 -302.988732) (xy 140.865445 -302.89166) (xy 140.974966 -302.800639)
			(xy 141.08946 -302.715959) (xy 141.208562 -302.637893) (xy 141.33189 -302.566689) (xy 141.459048 -302.502577)
			(xy 141.58963 -302.445762) (xy 141.723218 -302.396425) (xy 141.859382 -302.354725) (xy 141.997688 -302.320796)
			(xy 142.137691 -302.294745) (xy 142.278945 -302.276657) (xy 142.420995 -302.266589) (xy 142.563387 -302.264574)
			(xy 142.705666 -302.270618) (xy 142.847374 -302.284701) (xy 142.988059 -302.30678) (xy 143.127269 -302.336782)
			(xy 143.264559 -302.374612) (xy 143.399489 -302.420148) (xy 143.531627 -302.473246) (xy 143.660549 -302.533733)
			(xy 143.785842 -302.601418) (xy 143.907105 -302.676083) (xy 144.02395 -302.757489) (xy 144.136003 -302.845375)
			(xy 144.242903 -302.939459) (xy 144.34431 -303.039441) (xy 144.439898 -303.144999) (xy 144.529361 -303.255797)
			(xy 144.612412 -303.371478) (xy 144.688785 -303.491673) (xy 144.758236 -303.615996) (xy 144.820542 -303.744049)
			(xy 144.875504 -303.875422) (xy 144.922945 -304.009694) (xy 144.962714 -304.146435) (xy 144.994683 -304.285207)
			(xy 145.01875 -304.425565) (xy 145.034838 -304.56706) (xy 145.042894 -304.709239) (xy 145.043398 -304.780442)
			(xy 145.042894 -304.851645) (xy 145.034838 -304.993824) (xy 145.01875 -305.135319) (xy 144.994683 -305.275677)
			(xy 144.962714 -305.414449) (xy 144.922945 -305.55119) (xy 144.875504 -305.685462) (xy 144.820542 -305.816835)
			(xy 144.758236 -305.944888) (xy 144.688785 -306.069211) (xy 144.612412 -306.189406) (xy 144.529361 -306.305087)
			(xy 144.439898 -306.415885) (xy 144.34431 -306.521443) (xy 144.242903 -306.621425) (xy 144.136003 -306.715509)
			(xy 144.02395 -306.803395) (xy 143.907105 -306.884801) (xy 143.785842 -306.959466) (xy 143.660549 -307.027151)
			(xy 143.531627 -307.087638) (xy 143.399489 -307.140736) (xy 143.264559 -307.186272) (xy 143.127269 -307.224102)
			(xy 142.988059 -307.254104) (xy 142.847374 -307.276183) (xy 142.705666 -307.290266) (xy 142.563387 -307.29631)
			(xy 142.420995 -307.294295) (xy 142.278945 -307.284227) (xy 142.137691 -307.266139) (xy 141.997688 -307.240088)
			(xy 141.859382 -307.206159) (xy 141.723218 -307.164459) (xy 141.58963 -307.115122) (xy 141.459048 -307.058307)
			(xy 141.33189 -306.994195) (xy 141.208562 -306.922991) (xy 141.08946 -306.844925) (xy 140.974966 -306.760245)
			(xy 140.865445 -306.669224) (xy 140.76125 -306.572152) (xy 140.662713 -306.46934) (xy 140.570151 -306.361119)
			(xy 140.483859 -306.247834) (xy 140.404115 -306.129849) (xy 140.331174 -306.007541) (xy 140.265269 -305.881302)
			(xy 140.206611 -305.751537) (xy 140.155389 -305.618662) (xy 140.111767 -305.483101) (xy 140.075883 -305.345289)
			(xy 140.047854 -305.205668) (xy 140.027769 -305.064685) (xy 140.015692 -304.922792) (xy 140.011662 -304.780442)
			(xy 132.072126 -304.780442) (xy 132.072126 -341.691976) (xy 132.072564 -341.702039) (xy 132.0803 -341.720621)
			(xy 132.087112 -341.728044) (xy 132.326634 -341.967566) (xy 132.334033 -341.974411) (xy 132.352631 -341.982138)
			(xy 132.362702 -341.982552)
		)
		(stroke
			(width 0)
			(type solid)
		)
		(fill yes)
		(layer "In8.Cu")
		(net "PVDD11_S3_P1")
	)
	(gr_poly
		(pts
			(xy 391.674604 -266.656566) (xy 391.681208 -266.643866) (xy 391.693531 -266.621165) (xy 391.724135 -266.579557)
			(xy 391.760835 -266.543213) (xy 391.80274 -266.513017) (xy 391.84883 -266.489703) (xy 391.897984 -266.473838)
			(xy 391.949007 -266.465808) (xy 392.000657 -266.465808) (xy 392.05168 -266.473838) (xy 392.100834 -266.489703)
			(xy 392.146924 -266.513017) (xy 392.188829 -266.543213) (xy 392.225529 -266.579557) (xy 392.256133 -266.621165)
			(xy 392.268456 -266.643866) (xy 392.27506 -266.656566) (xy 392.29919 -266.671298) (xy 393.383262 -266.671298)
			(xy 393.395402 -266.670682) (xy 393.417037 -266.65968) (xy 393.424664 -266.650216) (xy 393.439162 -266.630958)
			(xy 393.474123 -266.597782) (xy 393.514716 -266.571797) (xy 393.559482 -266.553939) (xy 393.606813 -266.544847)
			(xy 393.630912 -266.544298) (xy 425.444158 -266.544298) (xy 425.454973 -266.543861) (xy 425.474716 -266.535043)
			(xy 425.482258 -266.52728) (xy 425.539916 -266.462256) (xy 425.546266 -266.441428) (xy 425.544996 -266.430506)
			(xy 425.543218 -266.400026) (xy 425.543218 -195.503546) (xy 425.542964 -195.503038) (xy 425.542964 -175.539908)
			(xy 425.542542 -175.529838) (xy 425.534825 -175.511235) (xy 425.527978 -175.50384) (xy 424.985942 -174.961804)
			(xy 424.97852 -174.955019) (xy 424.959923 -174.947409) (xy 424.949874 -174.947072) (xy 417.956492 -174.947072)
			(xy 417.956492 -174.946564) (xy 412.05277 -174.946564) (xy 412.042704 -174.946994) (xy 412.024113 -174.954724)
			(xy 412.016702 -174.96155) (xy 407.28011 -179.698142) (xy 407.262068 -179.715398) (xy 407.220573 -179.743148)
			(xy 407.174455 -179.762253) (xy 407.125492 -179.771977) (xy 407.100532 -179.772564) (xy 403.67077 -179.772564)
			(xy 403.660704 -179.772994) (xy 403.642113 -179.780724) (xy 403.634702 -179.78755) (xy 402.162518 -181.259734)
			(xy 402.155675 -181.267133) (xy 402.14795 -181.285732) (xy 402.147532 -181.295802) (xy 402.147532 -186.249564)
			(xy 402.146915 -186.274518) (xy 402.137167 -186.323466) (xy 402.11806 -186.369573) (xy 402.090327 -186.411068)
			(xy 402.07311 -186.429142) (xy 400.16811 -188.334142) (xy 400.150068 -188.351398) (xy 400.108573 -188.379148)
			(xy 400.062455 -188.398253) (xy 400.013492 -188.407977) (xy 399.988532 -188.408564) (xy 395.628622 -188.408564)
			(xy 395.620271 -188.408814) (xy 395.604442 -188.414135) (xy 395.597634 -188.418978) (xy 395.575289 -188.435555)
			(xy 395.526747 -188.462743) (xy 395.474769 -188.482586) (xy 395.420459 -188.494663) (xy 395.36497 -188.498717)
			(xy 395.309481 -188.494663) (xy 395.255171 -188.482586) (xy 395.203193 -188.462743) (xy 395.154651 -188.435555)
			(xy 395.132306 -188.418978) (xy 395.125448 -188.413898) (xy 395.109954 -188.408564) (xy 394.984986 -188.408564)
			(xy 394.969492 -188.413898) (xy 394.962634 -188.418978) (xy 394.940289 -188.435555) (xy 394.891747 -188.462743)
			(xy 394.839769 -188.482586) (xy 394.785459 -188.494663) (xy 394.72997 -188.498717) (xy 394.674481 -188.494663)
			(xy 394.620171 -188.482586) (xy 394.568193 -188.462743) (xy 394.519651 -188.435555) (xy 394.497306 -188.418978)
			(xy 394.490448 -188.413898) (xy 394.474954 -188.408564) (xy 394.39977 -188.408564) (xy 394.389704 -188.408994)
			(xy 394.371113 -188.416724) (xy 394.363702 -188.42355) (xy 393.907518 -188.879734) (xy 393.900675 -188.887133)
			(xy 393.89295 -188.905732) (xy 393.892532 -188.915802) (xy 393.892532 -207.839564) (xy 393.891915 -207.864518)
			(xy 393.882167 -207.913466) (xy 393.86306 -207.959573) (xy 393.835327 -208.001068) (xy 393.81811 -208.019142)
			(xy 391.361422 -210.47583) (xy 391.352991 -210.485282) (xy 391.345801 -210.509536) (xy 391.347706 -210.522058)
			(xy 391.367264 -210.617816) (xy 391.383774 -210.637374) (xy 391.395712 -210.6422) (xy 391.461617 -210.668886)
			(xy 391.590622 -210.72871) (xy 391.71604 -210.795728) (xy 391.837473 -210.869724) (xy 391.95453 -210.950463)
			(xy 392.066839 -211.037687) (xy 392.17404 -211.131116) (xy 392.275792 -211.230454) (xy 392.371768 -211.335381)
			(xy 392.461663 -211.445563) (xy 392.545189 -211.560648) (xy 392.62208 -211.680269) (xy 392.69209 -211.804042)
			(xy 392.754994 -211.931574) (xy 392.810593 -212.062455) (xy 392.858708 -212.196269) (xy 392.899186 -212.332588)
			(xy 392.931898 -212.470976) (xy 392.956739 -212.610991) (xy 392.973629 -212.752185) (xy 392.982515 -212.894109)
			(xy 392.983368 -213.036307) (xy 392.976186 -213.178327) (xy 392.960992 -213.319715) (xy 392.937833 -213.460018)
			(xy 392.906785 -213.598788) (xy 392.867946 -213.735583) (xy 392.82144 -213.869964) (xy 392.767416 -214.001504)
			(xy 392.706047 -214.129781) (xy 392.637528 -214.254386) (xy 392.562078 -214.374921) (xy 392.479939 -214.491)
			(xy 392.391373 -214.602253) (xy 392.296663 -214.708325) (xy 392.196111 -214.808876) (xy 392.090039 -214.903585)
			(xy 391.978785 -214.992151) (xy 391.862705 -215.074289) (xy 391.742169 -215.149737) (xy 391.617564 -215.218255)
			(xy 391.489286 -215.279624) (xy 391.357746 -215.333647) (xy 391.223364 -215.380151) (xy 391.08657 -215.41899)
			(xy 390.947799 -215.450037) (xy 390.807496 -215.473194) (xy 390.666108 -215.488388) (xy 390.524088 -215.495569)
			(xy 390.38189 -215.494714) (xy 390.239966 -215.485827) (xy 390.098772 -215.468936) (xy 389.958757 -215.444094)
			(xy 389.820369 -215.411381) (xy 389.684051 -215.370902) (xy 389.550238 -215.322786) (xy 389.419356 -215.267186)
			(xy 389.291826 -215.204281) (xy 389.168052 -215.13427) (xy 389.048433 -215.057379) (xy 388.933348 -214.973852)
			(xy 388.823166 -214.883956) (xy 388.71824 -214.787978) (xy 388.618904 -214.686226) (xy 388.525475 -214.579024)
			(xy 388.438252 -214.466715) (xy 388.357514 -214.349657) (xy 388.283518 -214.228224) (xy 388.216502 -214.102805)
			(xy 388.156678 -213.973799) (xy 388.130034 -213.907878) (xy 388.125208 -213.89594) (xy 388.10565 -213.87943)
			(xy 388.009892 -213.859618) (xy 387.997337 -213.857743) (xy 387.973064 -213.86506) (xy 387.963664 -213.873588)
			(xy 380.667006 -221.170246) (xy 380.660166 -221.177647) (xy 380.652447 -221.196245) (xy 380.65202 -221.206314)
			(xy 380.65202 -221.802452) (xy 380.651491 -221.825847) (xy 380.642932 -221.871848) (xy 380.626095 -221.915504)
			(xy 380.60155 -221.95534) (xy 380.570126 -221.990008) (xy 380.532885 -222.018335) (xy 380.491087 -222.039366)
			(xy 380.446145 -222.052387) (xy 380.422912 -222.055182) (xy 380.41072 -222.056452) (xy 380.390146 -222.06966)
			(xy 379.258322 -224.02038) (xy 379.258576 -224.04832) (xy 379.266196 -224.060512) (xy 379.277874 -224.080183)
			(xy 379.296298 -224.122055) (xy 379.308781 -224.166065) (xy 379.315086 -224.211375) (xy 379.315472 -224.234248)
			(xy 379.314959 -224.260232) (xy 379.306822 -224.311558) (xy 379.290756 -224.36098) (xy 379.267157 -224.40728)
			(xy 379.236606 -224.449319) (xy 379.199855 -224.486061) (xy 379.157809 -224.516601) (xy 379.111502 -224.540189)
			(xy 379.062076 -224.556242) (xy 379.010748 -224.564365) (xy 378.984764 -224.564956) (xy 378.973334 -224.564702)
			(xy 378.959364 -224.564194) (xy 378.93498 -224.577656) (xy 378.788422 -224.830386) (xy 378.788676 -224.858326)
			(xy 378.796042 -224.870264) (xy 378.807771 -224.889952) (xy 378.826279 -224.931876) (xy 378.838821 -224.975953)
			(xy 378.845156 -225.02134) (xy 378.845572 -225.044254) (xy 378.845092 -225.070245) (xy 378.836967 -225.121587)
			(xy 378.820908 -225.171025) (xy 378.797312 -225.217342) (xy 378.76676 -225.259397) (xy 378.730004 -225.296153)
			(xy 378.687951 -225.326707) (xy 378.641634 -225.350304) (xy 378.592196 -225.366364) (xy 378.540855 -225.374491)
			(xy 378.514864 -225.374962) (xy 378.503434 -225.374708) (xy 378.48921 -225.3742) (xy 378.464826 -225.387662)
			(xy 378.318268 -225.640392) (xy 378.318522 -225.668332) (xy 378.326142 -225.680524) (xy 378.337821 -225.700195)
			(xy 378.356246 -225.742067) (xy 378.36873 -225.786077) (xy 378.375035 -225.831387) (xy 378.375418 -225.85426)
			(xy 378.374938 -225.880252) (xy 378.366812 -225.931596) (xy 378.350753 -225.981036) (xy 378.327158 -226.027356)
			(xy 378.296606 -226.069413) (xy 378.259851 -226.106174) (xy 378.217798 -226.136731) (xy 378.171482 -226.160334)
			(xy 378.122044 -226.1764) (xy 378.070702 -226.184534) (xy 378.04471 -226.184968) (xy 378.033534 -226.184714)
			(xy 378.01931 -226.184206) (xy 377.994926 -226.197922) (xy 377.848368 -226.450398) (xy 377.848622 -226.478338)
			(xy 377.855988 -226.490276) (xy 377.867718 -226.509964) (xy 377.886228 -226.551887) (xy 377.89877 -226.595965)
			(xy 377.905105 -226.641352) (xy 377.905518 -226.664266) (xy 377.905037 -226.690257) (xy 377.89691 -226.741601)
			(xy 377.880851 -226.79104) (xy 377.857256 -226.837359) (xy 377.826704 -226.879416) (xy 377.789949 -226.916176)
			(xy 377.747897 -226.946733) (xy 377.701581 -226.970335) (xy 377.652143 -226.9864) (xy 377.600801 -226.994534)
			(xy 377.57481 -226.994974) (xy 377.56338 -226.99472) (xy 377.549156 -226.994212) (xy 377.524772 -227.007674)
			(xy 377.378214 -227.260404) (xy 377.378722 -227.288344) (xy 377.386088 -227.300282) (xy 377.397817 -227.31997)
			(xy 377.416327 -227.361893) (xy 377.428868 -227.405971) (xy 377.435202 -227.451358) (xy 377.435618 -227.474272)
			(xy 377.435137 -227.500263) (xy 377.427009 -227.551606) (xy 377.41095 -227.601044) (xy 377.387354 -227.647362)
			(xy 377.356802 -227.689418) (xy 377.320047 -227.726177) (xy 377.277995 -227.756734) (xy 377.23168 -227.780335)
			(xy 377.182243 -227.7964) (xy 377.130901 -227.804534) (xy 377.10491 -227.80498) (xy 377.09348 -227.804726)
			(xy 377.079256 -227.804218) (xy 377.054872 -227.81768) (xy 376.908314 -228.07041) (xy 376.908568 -228.09835)
			(xy 376.915934 -228.110288) (xy 376.927667 -228.129975) (xy 376.946186 -228.171897) (xy 376.958739 -228.215974)
			(xy 376.965084 -228.261363) (xy 376.965464 -228.284278) (xy 376.964982 -228.310267) (xy 376.956854 -228.361606)
			(xy 376.940793 -228.41104) (xy 376.917196 -228.457354) (xy 376.886643 -228.499404) (xy 376.849888 -228.536157)
			(xy 376.807835 -228.566707) (xy 376.76152 -228.590301) (xy 376.712084 -228.606359) (xy 376.660745 -228.614484)
			(xy 376.634756 -228.614986) (xy 376.608973 -228.614489) (xy 376.558032 -228.606478) (xy 376.508952 -228.590656)
			(xy 376.462923 -228.567408) (xy 376.421061 -228.537297) (xy 376.38438 -228.501052) (xy 376.35377 -228.459553)
			(xy 376.341386 -228.436932) (xy 376.334782 -228.424232) (xy 376.310652 -228.4095) (xy 376.018806 -228.4095)
			(xy 375.994676 -228.424232) (xy 375.988072 -228.436932) (xy 375.975732 -228.459578) (xy 375.945114 -228.501077)
			(xy 375.908425 -228.53732) (xy 375.866556 -228.567428) (xy 375.82052 -228.590673) (xy 375.771434 -228.606489)
			(xy 375.720488 -228.614494) (xy 375.668916 -228.614494) (xy 375.61797 -228.606489) (xy 375.568884 -228.590673)
			(xy 375.522848 -228.567428) (xy 375.480979 -228.53732) (xy 375.44429 -228.501077) (xy 375.413672 -228.459578)
			(xy 375.401332 -228.436932) (xy 375.394728 -228.424232) (xy 375.370598 -228.4095) (xy 375.079006 -228.4095)
			(xy 375.054876 -228.424232) (xy 375.048272 -228.436932) (xy 375.035933 -228.45958) (xy 375.005316 -228.501081)
			(xy 374.968628 -228.537327) (xy 374.926759 -228.567437) (xy 374.880722 -228.590684) (xy 374.831636 -228.606502)
			(xy 374.780688 -228.614508) (xy 374.754902 -228.614986) (xy 374.743472 -228.614732) (xy 374.729248 -228.614224)
			(xy 374.704864 -228.627686) (xy 374.558306 -228.880416) (xy 374.55856 -228.908356) (xy 374.56618 -228.920548)
			(xy 374.577856 -228.94022) (xy 374.596276 -228.982092) (xy 374.608755 -229.026102) (xy 374.615056 -229.071411)
			(xy 374.615456 -229.094284) (xy 374.615104 -229.116933) (xy 374.608957 -229.16181) (xy 374.596733 -229.205426)
			(xy 374.578664 -229.246962) (xy 374.567196 -229.266496) (xy 374.55983 -229.278434) (xy 374.559322 -229.30612)
			(xy 374.706896 -229.560374) (xy 374.73128 -229.573836) (xy 374.74525 -229.573582) (xy 374.754902 -229.573328)
			(xy 374.780886 -229.573838) (xy 374.832215 -229.581968) (xy 374.88164 -229.598027) (xy 374.927944 -229.62162)
			(xy 374.969987 -229.652167) (xy 375.006734 -229.688914) (xy 375.037281 -229.730958) (xy 375.060874 -229.777262)
			(xy 375.076933 -229.826687) (xy 375.085063 -229.878016) (xy 375.085063 -229.929984) (xy 375.076933 -229.981313)
			(xy 375.060874 -230.030738) (xy 375.037281 -230.077042) (xy 375.006734 -230.119086) (xy 374.969987 -230.155833)
			(xy 374.927944 -230.18638) (xy 374.88164 -230.209973) (xy 374.832215 -230.226032) (xy 374.780886 -230.234162)
			(xy 374.754902 -230.234744) (xy 374.743472 -230.23449) (xy 374.729248 -230.233982) (xy 374.704864 -230.247444)
			(xy 374.543828 -230.52532) (xy 374.543828 -230.55199) (xy 374.550432 -230.563928) (xy 374.562881 -230.587014)
			(xy 374.58054 -230.636397) (xy 374.589494 -230.688073) (xy 374.590056 -230.714296) (xy 374.58951 -230.740176)
			(xy 374.580779 -230.791196) (xy 374.563565 -230.84001) (xy 374.551448 -230.862886) (xy 374.544844 -230.874824)
			(xy 374.545098 -230.90124) (xy 374.706896 -231.180386) (xy 374.73128 -231.193848) (xy 374.74525 -231.193594)
			(xy 374.754902 -231.19334) (xy 374.780885 -231.19385) (xy 374.832212 -231.20198) (xy 374.881635 -231.218038)
			(xy 374.927937 -231.241631) (xy 374.969979 -231.272176) (xy 375.006725 -231.308922) (xy 375.03727 -231.350964)
			(xy 375.060862 -231.397267) (xy 375.076921 -231.44669) (xy 375.08505 -231.498017) (xy 375.08505 -231.549983)
			(xy 375.076921 -231.60131) (xy 375.060862 -231.650733) (xy 375.03727 -231.697036) (xy 375.006725 -231.739078)
			(xy 374.969979 -231.775824) (xy 374.927937 -231.806369) (xy 374.881635 -231.829962) (xy 374.832212 -231.84602)
			(xy 374.780885 -231.85415) (xy 374.754902 -231.854756) (xy 374.743472 -231.854502) (xy 374.729248 -231.853994)
			(xy 374.704864 -231.867456) (xy 374.558306 -232.12044) (xy 374.558814 -232.14838) (xy 374.56618 -232.160318)
			(xy 374.577858 -232.179989) (xy 374.596282 -232.221861) (xy 374.608765 -232.265871) (xy 374.61507 -232.311181)
			(xy 374.615456 -232.334054) (xy 374.615067 -232.35671) (xy 374.608851 -232.401596) (xy 374.596568 -232.445213)
			(xy 374.57845 -232.486747) (xy 374.566942 -232.506266) (xy 374.559576 -232.518458) (xy 374.559322 -232.54589)
			(xy 374.706896 -232.800398) (xy 374.73128 -232.81386) (xy 374.74525 -232.813606) (xy 374.754902 -232.813352)
			(xy 374.78089 -232.813862) (xy 374.832227 -232.821992) (xy 374.88166 -232.838053) (xy 374.927972 -232.861648)
			(xy 374.970023 -232.892197) (xy 375.006778 -232.928948) (xy 375.037332 -232.970996) (xy 375.060933 -233.017305)
			(xy 375.076999 -233.066736) (xy 375.085135 -233.118072) (xy 375.08561 -233.14406) (xy 375.085232 -233.166747)
			(xy 375.079024 -233.211695) (xy 375.066734 -233.255373) (xy 375.04859 -233.296962) (xy 375.037096 -233.316526)
			(xy 375.02973 -233.328464) (xy 375.029476 -233.356404) (xy 375.176796 -233.610404) (xy 375.20118 -233.623866)
			(xy 375.21515 -233.623612) (xy 375.224802 -233.623358) (xy 375.250792 -233.623868) (xy 375.302131 -233.631999)
			(xy 375.351567 -233.648062) (xy 375.397881 -233.671661) (xy 375.439933 -233.702214) (xy 375.476688 -233.738969)
			(xy 375.50724 -233.781021) (xy 375.530839 -233.827335) (xy 375.546901 -233.876771) (xy 375.555032 -233.92811)
			(xy 375.555032 -233.98009) (xy 375.546901 -234.031429) (xy 375.530839 -234.080865) (xy 375.50724 -234.127179)
			(xy 375.476688 -234.169231) (xy 375.439933 -234.205986) (xy 375.397881 -234.236539) (xy 375.351567 -234.260138)
			(xy 375.302131 -234.276201) (xy 375.250792 -234.284332) (xy 375.224802 -234.284774) (xy 375.213372 -234.28452)
			(xy 375.199148 -234.284012) (xy 375.174764 -234.297474) (xy 375.028206 -234.550204) (xy 375.028714 -234.578144)
			(xy 375.03608 -234.590082) (xy 375.047809 -234.60977) (xy 375.066319 -234.651693) (xy 375.078862 -234.695771)
			(xy 375.085195 -234.741158) (xy 375.08561 -234.764072) (xy 375.085129 -234.790063) (xy 375.077001 -234.841405)
			(xy 375.060941 -234.890843) (xy 375.037345 -234.93716) (xy 375.006794 -234.979216) (xy 374.970039 -235.015974)
			(xy 374.927986 -235.04653) (xy 374.881671 -235.07013) (xy 374.832234 -235.086194) (xy 374.780893 -235.094327)
			(xy 374.754902 -235.09478) (xy 374.743472 -235.094526) (xy 374.729248 -235.094018) (xy 374.704864 -235.10748)
			(xy 374.558306 -235.360464) (xy 374.558814 -235.388404) (xy 374.56618 -235.400342) (xy 374.577857 -235.420013)
			(xy 374.596277 -235.461886) (xy 374.608757 -235.505896) (xy 374.615059 -235.551205) (xy 374.615456 -235.574078)
			(xy 374.615066 -235.596734) (xy 374.608846 -235.641618) (xy 374.596561 -235.685233) (xy 374.578441 -235.726765)
			(xy 374.566942 -235.74629) (xy 374.559576 -235.758482) (xy 374.559322 -235.785914) (xy 374.706896 -236.040422)
			(xy 374.73128 -236.053884) (xy 374.74525 -236.05363) (xy 374.754902 -236.053376) (xy 374.78089 -236.053886)
			(xy 374.832227 -236.062017) (xy 374.88166 -236.078079) (xy 374.927971 -236.101676) (xy 374.970021 -236.132227)
			(xy 375.006774 -236.16898) (xy 375.037325 -236.211031) (xy 375.060922 -236.257342) (xy 375.076984 -236.306775)
			(xy 375.085114 -236.358112) (xy 375.085114 -236.410088) (xy 375.076984 -236.461425) (xy 375.060922 -236.510858)
			(xy 375.037325 -236.557169) (xy 375.006774 -236.59922) (xy 374.970021 -236.635973) (xy 374.927971 -236.666524)
			(xy 374.88166 -236.690121) (xy 374.832227 -236.706183) (xy 374.78089 -236.714314) (xy 374.754902 -236.714792)
			(xy 374.743472 -236.714538) (xy 374.729248 -236.71403) (xy 374.704864 -236.727492) (xy 374.558306 -236.980222)
			(xy 374.55856 -237.008162) (xy 374.56618 -237.020354) (xy 374.577856 -237.040026) (xy 374.596275 -237.081898)
			(xy 374.608754 -237.125908) (xy 374.615053 -237.171218) (xy 374.615456 -237.19409) (xy 374.614947 -237.220079)
			(xy 374.606818 -237.271418) (xy 374.590759 -237.320853) (xy 374.567164 -237.367167) (xy 374.536615 -237.40922)
			(xy 374.499865 -237.445978) (xy 374.457816 -237.476534) (xy 374.411506 -237.500137) (xy 374.362074 -237.516205)
			(xy 374.310737 -237.524343) (xy 374.284748 -237.524798) (xy 374.273572 -237.524544) (xy 374.259348 -237.524036)
			(xy 374.234964 -237.537752) (xy 374.088406 -237.790228) (xy 374.08866 -237.818168) (xy 374.096026 -237.830106)
			(xy 374.107759 -237.849793) (xy 374.126276 -237.891715) (xy 374.138826 -237.935793) (xy 374.145169 -237.981181)
			(xy 374.145556 -238.004096) (xy 374.145556 -238.012986) (xy 374.145048 -238.026956) (xy 374.158764 -238.05134)
			(xy 375.010934 -238.540798) (xy 375.038874 -238.54029) (xy 375.050812 -238.532924) (xy 375.070499 -238.52119)
			(xy 375.11242 -238.502671) (xy 375.156498 -238.49012) (xy 375.201887 -238.483776) (xy 375.224802 -238.483394)
			(xy 375.250789 -238.483904) (xy 375.302123 -238.492034) (xy 375.351553 -238.508096) (xy 375.397862 -238.531691)
			(xy 375.439909 -238.562241) (xy 375.47666 -238.598992) (xy 375.50721 -238.64104) (xy 375.530805 -238.687349)
			(xy 375.546866 -238.736779) (xy 375.554996 -238.788113) (xy 375.554996 -238.840087) (xy 375.546866 -238.891421)
			(xy 375.530805 -238.940851) (xy 375.50721 -238.98716) (xy 375.47666 -239.029208) (xy 375.439909 -239.065959)
			(xy 375.397862 -239.096509) (xy 375.351553 -239.120104) (xy 375.302123 -239.136166) (xy 375.250789 -239.144296)
			(xy 375.224802 -239.14481) (xy 375.213372 -239.144556) (xy 375.199148 -239.144048) (xy 375.174764 -239.15751)
			(xy 375.028206 -239.41024) (xy 375.028714 -239.43818) (xy 375.03608 -239.450118) (xy 375.047813 -239.469805)
			(xy 375.066331 -239.511727) (xy 375.078882 -239.555805) (xy 375.085224 -239.601193) (xy 375.08561 -239.624108)
			(xy 375.0851 -239.650095) (xy 375.076968 -239.701428) (xy 375.060907 -239.750858) (xy 375.03731 -239.797167)
			(xy 375.006761 -239.839214) (xy 374.970009 -239.875964) (xy 374.927961 -239.906514) (xy 374.881653 -239.930109)
			(xy 374.832223 -239.94617) (xy 374.780889 -239.9543) (xy 374.754902 -239.954816) (xy 374.743472 -239.954562)
			(xy 374.729502 -239.954054) (xy 374.704864 -239.967516) (xy 374.558306 -240.2205) (xy 374.558814 -240.24844)
			(xy 374.56618 -240.260378) (xy 374.577854 -240.28005) (xy 374.596271 -240.321923) (xy 374.608746 -240.365933)
			(xy 374.615042 -240.411242) (xy 374.615456 -240.434114) (xy 374.615063 -240.456769) (xy 374.608839 -240.501651)
			(xy 374.59655 -240.545264) (xy 374.578426 -240.586793) (xy 374.566942 -240.606326) (xy 374.559576 -240.618518)
			(xy 374.559322 -240.64595) (xy 374.706896 -240.900458) (xy 374.73128 -240.91392) (xy 374.74525 -240.913666)
			(xy 374.754902 -240.913412) (xy 374.780891 -240.913895) (xy 374.832228 -240.922027) (xy 374.881661 -240.93809)
			(xy 374.927972 -240.961688) (xy 374.970022 -240.99224) (xy 375.006774 -241.028995) (xy 375.037324 -241.071047)
			(xy 375.060919 -241.11736) (xy 375.076978 -241.166794) (xy 375.085106 -241.218131) (xy 375.08561 -241.24412)
			(xy 375.085235 -241.266808) (xy 375.079032 -241.311758) (xy 375.066746 -241.355439) (xy 375.048606 -241.397031)
			(xy 375.037096 -241.416586) (xy 375.02973 -241.428524) (xy 375.029476 -241.456464) (xy 375.176796 -241.710464)
			(xy 375.20118 -241.723926) (xy 375.21515 -241.723672) (xy 375.224802 -241.723418) (xy 375.250787 -241.723928)
			(xy 375.302117 -241.732058) (xy 375.351544 -241.748118) (xy 375.397849 -241.771712) (xy 375.439894 -241.802259)
			(xy 375.476642 -241.839008) (xy 375.507189 -241.881052) (xy 375.530783 -241.927358) (xy 375.546843 -241.976785)
			(xy 375.554973 -242.028115) (xy 375.554973 -242.080085) (xy 375.546843 -242.131415) (xy 375.530783 -242.180842)
			(xy 375.507189 -242.227148) (xy 375.476642 -242.269192) (xy 375.439894 -242.305941) (xy 375.397849 -242.336488)
			(xy 375.351544 -242.360082) (xy 375.302117 -242.376142) (xy 375.250787 -242.384272) (xy 375.224802 -242.384834)
			(xy 375.213372 -242.38458) (xy 375.199148 -242.384072) (xy 375.174764 -242.397534) (xy 375.028206 -242.650264)
			(xy 375.028714 -242.678204) (xy 375.03608 -242.690142) (xy 375.047812 -242.709829) (xy 375.066327 -242.751752)
			(xy 375.078874 -242.795829) (xy 375.085213 -242.841218) (xy 375.08561 -242.864132) (xy 375.085098 -242.890118)
			(xy 375.076964 -242.941448) (xy 375.0609 -242.990875) (xy 375.037302 -243.03718) (xy 375.006752 -243.079224)
			(xy 374.970001 -243.115971) (xy 374.927954 -243.146518) (xy 374.881647 -243.170111) (xy 374.832219 -243.186171)
			(xy 374.780888 -243.1943) (xy 374.754902 -243.19484) (xy 374.743472 -243.194586) (xy 374.729248 -243.194078)
			(xy 374.704864 -243.20754) (xy 374.558306 -243.460524) (xy 374.558814 -243.488464) (xy 374.56618 -243.500402)
			(xy 374.577859 -243.520073) (xy 374.596285 -243.561945) (xy 374.60877 -243.605955) (xy 374.615077 -243.651265)
			(xy 374.615456 -243.674138) (xy 374.615068 -243.696795) (xy 374.608854 -243.741681) (xy 374.596573 -243.785299)
			(xy 374.578457 -243.826834) (xy 374.566942 -243.84635) (xy 374.559576 -243.858542) (xy 374.559322 -243.885974)
			(xy 374.706896 -244.140482) (xy 374.73128 -244.153944) (xy 374.74525 -244.15369) (xy 374.754902 -244.153436)
			(xy 374.78089 -244.153919) (xy 374.832226 -244.162051) (xy 374.881657 -244.178114) (xy 374.927967 -244.201713)
			(xy 374.970014 -244.232266) (xy 375.006764 -244.269021) (xy 375.037311 -244.311072) (xy 375.060904 -244.357385)
			(xy 375.07696 -244.406819) (xy 375.085084 -244.458156) (xy 375.08561 -244.484144) (xy 375.085233 -244.506831)
			(xy 375.079028 -244.55178) (xy 375.066739 -244.595459) (xy 375.048597 -244.63705) (xy 375.037096 -244.65661)
			(xy 375.02973 -244.668548) (xy 375.029476 -244.696488) (xy 375.176796 -244.950488) (xy 375.20118 -244.96395)
			(xy 375.21515 -244.963696) (xy 375.224802 -244.963442) (xy 375.250785 -244.963952) (xy 375.302112 -244.972082)
			(xy 375.351534 -244.98814) (xy 375.397836 -245.011733) (xy 375.439878 -245.042278) (xy 375.476623 -245.079024)
			(xy 375.507168 -245.121065) (xy 375.53076 -245.167368) (xy 375.546819 -245.21679) (xy 375.554948 -245.268117)
			(xy 375.554948 -245.320083) (xy 375.546819 -245.37141) (xy 375.53076 -245.420832) (xy 375.507168 -245.467135)
			(xy 375.476623 -245.509176) (xy 375.439878 -245.545922) (xy 375.397836 -245.576467) (xy 375.351534 -245.60006)
			(xy 375.302112 -245.616118) (xy 375.250785 -245.624248) (xy 375.224802 -245.624858) (xy 375.213372 -245.624604)
			(xy 375.199148 -245.624096) (xy 375.174764 -245.637558) (xy 375.028206 -245.890288) (xy 375.028714 -245.918228)
			(xy 375.03608 -245.930166) (xy 375.04781 -245.949854) (xy 375.066322 -245.991776) (xy 375.078867 -246.035854)
			(xy 375.085202 -246.081242) (xy 375.08561 -246.104156) (xy 375.08513 -246.130148) (xy 375.077004 -246.181492)
			(xy 375.060946 -246.230932) (xy 375.037351 -246.277252) (xy 375.006799 -246.319309) (xy 374.970044 -246.356069)
			(xy 374.927991 -246.386627) (xy 374.881675 -246.410228) (xy 374.832236 -246.426294) (xy 374.780894 -246.434427)
			(xy 374.754902 -246.434864) (xy 374.743472 -246.43461) (xy 374.729248 -246.434102) (xy 374.704864 -246.447564)
			(xy 374.558306 -246.700548) (xy 374.558814 -246.728488) (xy 374.56618 -246.740426) (xy 374.577858 -246.760097)
			(xy 374.59628 -246.80197) (xy 374.608762 -246.84598) (xy 374.615066 -246.891289) (xy 374.615456 -246.914162)
			(xy 374.615067 -246.936818) (xy 374.608849 -246.981703) (xy 374.596566 -247.02532) (xy 374.578447 -247.066853)
			(xy 374.566942 -247.086374) (xy 374.559576 -247.098566) (xy 374.559322 -247.125998) (xy 374.706896 -247.380506)
			(xy 374.73128 -247.393968) (xy 374.74525 -247.393714) (xy 374.754902 -247.39346) (xy 374.78089 -247.39397)
			(xy 374.832226 -247.4021) (xy 374.881658 -247.418161) (xy 374.92797 -247.441756) (xy 374.970021 -247.472306)
			(xy 375.006775 -247.509057) (xy 375.037328 -247.551104) (xy 375.060927 -247.597414) (xy 375.076993 -247.646845)
			(xy 375.085128 -247.69818) (xy 375.08561 -247.724168) (xy 375.085232 -247.746855) (xy 375.079023 -247.791802)
			(xy 375.066731 -247.83548) (xy 375.048587 -247.877068) (xy 375.037096 -247.896634) (xy 375.02973 -247.908572)
			(xy 375.029476 -247.936512) (xy 375.176796 -248.190512) (xy 375.20118 -248.203974) (xy 375.21515 -248.20372)
			(xy 375.224802 -248.203466) (xy 375.250791 -248.203976) (xy 375.302129 -248.212107) (xy 375.351564 -248.22817)
			(xy 375.397876 -248.251767) (xy 375.439928 -248.28232) (xy 375.476682 -248.319074) (xy 375.507234 -248.361125)
			(xy 375.530831 -248.407438) (xy 375.546893 -248.456873) (xy 375.555024 -248.508211) (xy 375.555024 -248.560189)
			(xy 375.546893 -248.611527) (xy 375.530831 -248.660962) (xy 375.507234 -248.707275) (xy 375.476682 -248.749326)
			(xy 375.439928 -248.78608) (xy 375.397876 -248.816633) (xy 375.351564 -248.84023) (xy 375.302129 -248.856293)
			(xy 375.250791 -248.864424) (xy 375.224802 -248.864882) (xy 375.213372 -248.864628) (xy 375.199148 -248.86412)
			(xy 375.174764 -248.877582) (xy 375.028206 -249.130312) (xy 375.028714 -249.158252) (xy 375.03608 -249.17019)
			(xy 375.047815 -249.189876) (xy 375.066337 -249.231798) (xy 375.078891 -249.275876) (xy 375.085237 -249.321265)
			(xy 375.08561 -249.34418) (xy 375.085128 -249.37017) (xy 375.077 -249.421511) (xy 375.060939 -249.470949)
			(xy 375.037343 -249.517265) (xy 375.006791 -249.559319) (xy 374.970036 -249.596076) (xy 374.927984 -249.626631)
			(xy 374.881669 -249.650231) (xy 374.832233 -249.666294) (xy 374.780892 -249.674427) (xy 374.754902 -249.674888)
			(xy 374.743472 -249.674634) (xy 374.729248 -249.674126) (xy 374.704864 -249.687588) (xy 374.558306 -249.940572)
			(xy 374.55856 -249.968258) (xy 374.56618 -249.98045) (xy 374.577856 -250.000122) (xy 374.596276 -250.041994)
			(xy 374.608755 -250.086004) (xy 374.615055 -250.131313) (xy 374.615456 -250.154186) (xy 374.614948 -250.180175)
			(xy 374.606819 -250.231514) (xy 374.59076 -250.28095) (xy 374.567166 -250.327265) (xy 374.536617 -250.369319)
			(xy 374.499866 -250.406077) (xy 374.457818 -250.436633) (xy 374.411507 -250.460236) (xy 374.362075 -250.476305)
			(xy 374.310737 -250.484443) (xy 374.284748 -250.484894) (xy 374.26146 -250.4845) (xy 374.215343 -250.477971)
			(xy 374.170599 -250.465036) (xy 374.128113 -250.445951) (xy 374.108218 -250.43384) (xy 374.096026 -250.42622)
			(xy 374.06834 -250.425458) (xy 373.218202 -250.9139) (xy 373.20474 -250.93803) (xy 373.205248 -250.952508)
			(xy 373.205502 -250.964192) (xy 373.205019 -250.990182) (xy 373.196889 -251.041521) (xy 373.180828 -251.090956)
			(xy 373.15723 -251.13727) (xy 373.126678 -251.179322) (xy 373.089923 -251.216077) (xy 373.047871 -251.246629)
			(xy 373.001558 -251.270227) (xy 372.952123 -251.286289) (xy 372.900783 -251.294419) (xy 372.874794 -251.2949)
			(xy 372.863618 -251.294646) (xy 372.849394 -251.294138) (xy 372.82501 -251.3076) (xy 372.678198 -251.56033)
			(xy 372.678706 -251.588016) (xy 372.686072 -251.600208) (xy 372.697806 -251.619895) (xy 372.716326 -251.661816)
			(xy 372.728878 -251.705894) (xy 372.735222 -251.751283) (xy 372.735602 -251.774198) (xy 372.735092 -251.800185)
			(xy 372.726962 -251.85152) (xy 372.710901 -251.90095) (xy 372.687305 -251.94726) (xy 372.656755 -251.989308)
			(xy 372.620004 -252.026059) (xy 372.577956 -252.056609) (xy 372.531646 -252.080205) (xy 372.482216 -252.096266)
			(xy 372.430881 -252.104396) (xy 372.378907 -252.104396) (xy 372.327572 -252.096266) (xy 372.278142 -252.080205)
			(xy 372.231832 -252.056609) (xy 372.189784 -252.026059) (xy 372.153033 -251.989308) (xy 372.122483 -251.94726)
			(xy 372.098887 -251.90095) (xy 372.082826 -251.85152) (xy 372.074696 -251.800185) (xy 372.074186 -251.774198)
			(xy 372.07444 -251.759466) (xy 372.075202 -251.744988) (xy 372.061486 -251.72035) (xy 371.214396 -251.233432)
			(xy 371.186202 -251.234194) (xy 371.17401 -251.242068) (xy 371.153875 -251.254581) (xy 371.110782 -251.27434)
			(xy 371.06531 -251.287741) (xy 371.018389 -251.29451) (xy 370.994686 -251.2949) (xy 370.9687 -251.294389)
			(xy 370.917367 -251.286257) (xy 370.867939 -251.270195) (xy 370.821632 -251.246598) (xy 370.779587 -251.216048)
			(xy 370.742838 -251.179297) (xy 370.71229 -251.137249) (xy 370.688697 -251.09094) (xy 370.672638 -251.041511)
			(xy 370.664509 -250.990178) (xy 370.663978 -250.964192) (xy 370.664397 -250.940606) (xy 370.671101 -250.893912)
			(xy 370.684372 -250.848644) (xy 370.70394 -250.805722) (xy 370.716302 -250.78563) (xy 370.724176 -250.773438)
			(xy 370.724684 -250.745244) (xy 370.580666 -250.497086) (xy 370.556028 -250.483624) (xy 370.54155 -250.484386)
			(xy 370.524786 -250.484894) (xy 370.501499 -250.484496) (xy 370.455386 -250.477959) (xy 370.410647 -250.465017)
			(xy 370.368166 -250.445926) (xy 370.348256 -250.43384) (xy 370.336064 -250.42622) (xy 370.308124 -250.425458)
			(xy 369.45824 -250.913646) (xy 369.444778 -250.93803) (xy 369.445286 -250.952254) (xy 369.44554 -250.964192)
			(xy 369.445031 -250.990181) (xy 369.436902 -251.041518) (xy 369.420842 -251.090952) (xy 369.397247 -251.137264)
			(xy 369.366698 -251.179316) (xy 369.329947 -251.216072) (xy 369.287899 -251.246626) (xy 369.241589 -251.270227)
			(xy 369.192157 -251.286292) (xy 369.14082 -251.294428) (xy 369.114832 -251.2949) (xy 369.103402 -251.294646)
			(xy 369.089178 -251.294138) (xy 369.064794 -251.3076) (xy 368.918236 -251.56033) (xy 368.91849 -251.58827)
			(xy 368.92611 -251.600462) (xy 368.937784 -251.620134) (xy 368.956201 -251.662007) (xy 368.968677 -251.706017)
			(xy 368.974975 -251.751326) (xy 368.975386 -251.774198) (xy 368.974876 -251.800185) (xy 368.966746 -251.85152)
			(xy 368.950685 -251.90095) (xy 368.927089 -251.94726) (xy 368.896539 -251.989308) (xy 368.859788 -252.026059)
			(xy 368.81774 -252.056609) (xy 368.77143 -252.080205) (xy 368.722 -252.096266) (xy 368.670665 -252.104396)
			(xy 368.618691 -252.104396) (xy 368.567356 -252.096266) (xy 368.517926 -252.080205) (xy 368.471616 -252.056609)
			(xy 368.429568 -252.026059) (xy 368.392817 -251.989308) (xy 368.362267 -251.94726) (xy 368.338671 -251.90095)
			(xy 368.32261 -251.85152) (xy 368.31448 -251.800185) (xy 368.31397 -251.774198) (xy 368.314224 -251.759212)
			(xy 368.314986 -251.744988) (xy 368.30127 -251.720096) (xy 367.454434 -251.233432) (xy 367.42624 -251.234194)
			(xy 367.414048 -251.242068) (xy 367.393912 -251.254577) (xy 367.350818 -251.274328) (xy 367.305345 -251.28772)
			(xy 367.258426 -251.29448) (xy 367.234724 -251.2949) (xy 367.208734 -251.294419) (xy 367.157393 -251.28629)
			(xy 367.107956 -251.27023) (xy 367.06164 -251.246634) (xy 367.019585 -251.216082) (xy 366.982829 -251.179327)
			(xy 366.952275 -251.137274) (xy 366.928676 -251.090959) (xy 366.912613 -251.041523) (xy 366.904483 -250.990182)
			(xy 366.904016 -250.964192) (xy 366.904454 -250.940638) (xy 366.911177 -250.894011) (xy 366.924443 -250.848808)
			(xy 366.943985 -250.805943) (xy 366.95634 -250.785884) (xy 366.964214 -250.773438) (xy 366.964722 -250.745498)
			(xy 366.820704 -250.497086) (xy 366.795812 -250.483878) (xy 366.781334 -250.484386) (xy 366.764824 -250.484894)
			(xy 366.741505 -250.48451) (xy 366.695327 -250.477989) (xy 366.650523 -250.465045) (xy 366.607981 -250.445934)
			(xy 366.58804 -250.43384) (xy 366.575848 -250.425966) (xy 366.548162 -250.425458) (xy 365.698278 -250.913646)
			(xy 365.684816 -250.93803) (xy 365.685324 -250.952254) (xy 365.685578 -250.964192) (xy 365.685095 -250.990181)
			(xy 365.676965 -251.041519) (xy 365.660903 -251.090952) (xy 365.637305 -251.137264) (xy 365.606753 -251.179315)
			(xy 365.569998 -251.216067) (xy 365.527946 -251.246617) (xy 365.481632 -251.270212) (xy 365.432197 -251.28627)
			(xy 365.380859 -251.294397) (xy 365.35487 -251.2949) (xy 365.34344 -251.294646) (xy 365.329216 -251.294138)
			(xy 365.304832 -251.3076) (xy 365.158274 -251.56033) (xy 365.158528 -251.58827) (xy 365.166148 -251.600462)
			(xy 365.177824 -251.620133) (xy 365.196244 -251.662006) (xy 365.208723 -251.706016) (xy 365.215022 -251.751325)
			(xy 365.215424 -251.774198) (xy 365.214914 -251.800185) (xy 365.206784 -251.85152) (xy 365.190723 -251.90095)
			(xy 365.167127 -251.94726) (xy 365.136577 -251.989308) (xy 365.099826 -252.026059) (xy 365.057778 -252.056609)
			(xy 365.011468 -252.080205) (xy 364.962038 -252.096266) (xy 364.910703 -252.104396) (xy 364.858729 -252.104396)
			(xy 364.807394 -252.096266) (xy 364.757964 -252.080205) (xy 364.711654 -252.056609) (xy 364.669606 -252.026059)
			(xy 364.632855 -251.989308) (xy 364.602305 -251.94726) (xy 364.578709 -251.90095) (xy 364.562648 -251.85152)
			(xy 364.554518 -251.800185) (xy 364.554008 -251.774198) (xy 364.554262 -251.759212) (xy 364.555024 -251.744988)
			(xy 364.541308 -251.720096) (xy 363.694472 -251.233432) (xy 363.666278 -251.234194) (xy 363.654086 -251.242068)
			(xy 363.63395 -251.254579) (xy 363.590857 -251.274335) (xy 363.545385 -251.287733) (xy 363.498465 -251.294498)
			(xy 363.474762 -251.2949) (xy 363.448777 -251.294388) (xy 363.397448 -251.286252) (xy 363.348023 -251.270188)
			(xy 363.301719 -251.24659) (xy 363.259677 -251.216039) (xy 363.222931 -251.179288) (xy 363.192386 -251.137242)
			(xy 363.168795 -251.090935) (xy 363.152737 -251.041508) (xy 363.144609 -250.990177) (xy 363.144054 -250.964192)
			(xy 363.144492 -250.940638) (xy 363.151215 -250.894011) (xy 363.164483 -250.848809) (xy 363.184027 -250.805945)
			(xy 363.196378 -250.785884) (xy 363.204252 -250.773438) (xy 363.20476 -250.745498) (xy 363.060742 -250.497086)
			(xy 363.03585 -250.483878) (xy 363.021372 -250.484386) (xy 363.004862 -250.484894) (xy 362.981543 -250.484513)
			(xy 362.935362 -250.477997) (xy 362.890555 -250.465057) (xy 362.84801 -250.44595) (xy 362.828078 -250.43384)
			(xy 362.81614 -250.425966) (xy 362.7882 -250.425458) (xy 361.938316 -250.913646) (xy 361.924854 -250.93803)
			(xy 361.925362 -250.952508) (xy 361.925616 -250.964192) (xy 361.925107 -250.99018) (xy 361.916978 -251.041516)
			(xy 361.900917 -251.090948) (xy 361.877322 -251.137259) (xy 361.846773 -251.179309) (xy 361.810021 -251.216062)
			(xy 361.767973 -251.246614) (xy 361.721663 -251.270211) (xy 361.672231 -251.286274) (xy 361.620896 -251.294406)
			(xy 361.594908 -251.2949) (xy 361.569148 -251.294408) (xy 361.518252 -251.286417) (xy 361.469212 -251.270628)
			(xy 361.423215 -251.247423) (xy 361.381374 -251.217363) (xy 361.344702 -251.181177) (xy 361.314088 -251.13974)
			(xy 361.301792 -251.1171) (xy 361.295188 -251.1044) (xy 361.270804 -251.089668) (xy 358.757474 -251.089668)
			(xy 358.750828 -251.089485) (xy 358.737964 -251.086146) (xy 358.732074 -251.083064) (xy 357.587804 -250.425458)
			(xy 357.559864 -250.425966) (xy 357.547926 -250.43384) (xy 357.527994 -250.44595) (xy 357.485449 -250.465057)
			(xy 357.440642 -250.477998) (xy 357.394461 -250.484515) (xy 357.371142 -250.484894) (xy 357.354632 -250.484386)
			(xy 357.340154 -250.483878) (xy 357.315262 -250.497086) (xy 357.171244 -250.745498) (xy 357.171752 -250.773438)
			(xy 357.179626 -250.785884) (xy 357.191993 -250.805936) (xy 357.211541 -250.8488) (xy 357.224802 -250.894006)
			(xy 357.231508 -250.940637) (xy 357.23195 -250.964192) (xy 357.231441 -250.990181) (xy 357.223312 -251.041519)
			(xy 357.207252 -251.090953) (xy 357.183657 -251.137267) (xy 357.153108 -251.179319) (xy 357.116357 -251.216076)
			(xy 357.074309 -251.246631) (xy 357.027999 -251.270233) (xy 356.978567 -251.2863) (xy 356.927231 -251.294437)
			(xy 356.901242 -251.2949) (xy 356.877541 -251.294489) (xy 356.830625 -251.287715) (xy 356.785156 -251.274313)
			(xy 356.742066 -251.254558) (xy 356.721918 -251.242068) (xy 356.709726 -251.234194) (xy 356.681532 -251.233432)
			(xy 355.834442 -251.72035) (xy 355.820726 -251.744988) (xy 355.821488 -251.759466) (xy 355.821742 -251.774198)
			(xy 355.821232 -251.800185) (xy 355.813102 -251.85152) (xy 355.797041 -251.90095) (xy 355.773445 -251.94726)
			(xy 355.742895 -251.989308) (xy 355.706144 -252.026059) (xy 355.664096 -252.056609) (xy 355.617786 -252.080205)
			(xy 355.568356 -252.096266) (xy 355.517021 -252.104396) (xy 355.465047 -252.104396) (xy 355.413712 -252.096266)
			(xy 355.364282 -252.080205) (xy 355.317972 -252.056609) (xy 355.275924 -252.026059) (xy 355.239173 -251.989308)
			(xy 355.208623 -251.94726) (xy 355.185027 -251.90095) (xy 355.168966 -251.85152) (xy 355.160836 -251.800185)
			(xy 355.160326 -251.774198) (xy 355.160718 -251.751283) (xy 355.167055 -251.705895) (xy 355.179606 -251.661818)
			(xy 355.19813 -251.619899) (xy 355.209856 -251.600208) (xy 355.217222 -251.588016) (xy 355.21773 -251.560076)
			(xy 355.071172 -251.3076) (xy 355.046788 -251.294138) (xy 355.032564 -251.294646) (xy 355.021134 -251.2949)
			(xy 354.997431 -251.294496) (xy 354.950509 -251.287733) (xy 354.905034 -251.274342) (xy 354.861935 -251.254596)
			(xy 354.84181 -251.242068) (xy 354.829872 -251.234194) (xy 354.801678 -251.233686) (xy 353.954588 -251.720096)
			(xy 353.940872 -251.744988) (xy 353.941634 -251.759212) (xy 353.941888 -251.774198) (xy 353.941378 -251.800185)
			(xy 353.933248 -251.85152) (xy 353.917187 -251.90095) (xy 353.893591 -251.94726) (xy 353.863041 -251.989308)
			(xy 353.82629 -252.026059) (xy 353.784242 -252.056609) (xy 353.737932 -252.080205) (xy 353.688502 -252.096266)
			(xy 353.637167 -252.104396) (xy 353.585193 -252.104396) (xy 353.533858 -252.096266) (xy 353.484428 -252.080205)
			(xy 353.438118 -252.056609) (xy 353.39607 -252.026059) (xy 353.359319 -251.989308) (xy 353.328769 -251.94726)
			(xy 353.305173 -251.90095) (xy 353.289112 -251.85152) (xy 353.280982 -251.800185) (xy 353.280472 -251.774198)
			(xy 353.280859 -251.751325) (xy 353.28716 -251.706014) (xy 353.299642 -251.662004) (xy 353.318068 -251.620132)
			(xy 353.329748 -251.600462) (xy 353.337368 -251.58827) (xy 353.337622 -251.56033) (xy 353.191064 -251.3076)
			(xy 353.16668 -251.294138) (xy 353.152456 -251.294646) (xy 353.141026 -251.2949) (xy 353.117323 -251.294495)
			(xy 353.070402 -251.287732) (xy 353.024927 -251.27434) (xy 352.981829 -251.254593) (xy 352.961702 -251.242068)
			(xy 352.949764 -251.234194) (xy 352.92157 -251.233686) (xy 352.07448 -251.72035) (xy 352.060764 -251.744988)
			(xy 352.061526 -251.759466) (xy 352.06178 -251.774198) (xy 352.06127 -251.800185) (xy 352.05314 -251.85152)
			(xy 352.037079 -251.90095) (xy 352.013483 -251.94726) (xy 351.982933 -251.989308) (xy 351.946182 -252.026059)
			(xy 351.904134 -252.056609) (xy 351.857824 -252.080205) (xy 351.808394 -252.096266) (xy 351.757059 -252.104396)
			(xy 351.705085 -252.104396) (xy 351.65375 -252.096266) (xy 351.60432 -252.080205) (xy 351.55801 -252.056609)
			(xy 351.515962 -252.026059) (xy 351.479211 -251.989308) (xy 351.448661 -251.94726) (xy 351.425065 -251.90095)
			(xy 351.409004 -251.85152) (xy 351.400874 -251.800185) (xy 351.400364 -251.774198) (xy 351.400755 -251.751283)
			(xy 351.407091 -251.705894) (xy 351.41964 -251.661816) (xy 351.438162 -251.619895) (xy 351.449894 -251.600208)
			(xy 351.45726 -251.588016) (xy 351.457768 -251.56033) (xy 351.310956 -251.3076) (xy 351.286572 -251.294138)
			(xy 351.272348 -251.294646) (xy 351.261172 -251.2949) (xy 351.23747 -251.294491) (xy 351.190552 -251.287721)
			(xy 351.145081 -251.274323) (xy 351.101988 -251.254571) (xy 351.081848 -251.242068) (xy 351.069656 -251.234194)
			(xy 351.041462 -251.233432) (xy 350.194626 -251.720096) (xy 350.18091 -251.744988) (xy 350.181672 -251.759212)
			(xy 350.181926 -251.774198) (xy 350.181417 -251.800186) (xy 350.173286 -251.851522) (xy 350.157226 -251.900954)
			(xy 350.13363 -251.947265) (xy 350.103081 -251.989315) (xy 350.06633 -252.026068) (xy 350.024282 -252.05662)
			(xy 349.977972 -252.080218) (xy 349.928541 -252.096282) (xy 349.877206 -252.104415) (xy 349.851218 -252.104906)
			(xy 349.834454 -252.104398) (xy 349.819976 -252.103636) (xy 349.795084 -252.117098) (xy 349.651066 -252.36551)
			(xy 349.651828 -252.393704) (xy 349.659448 -252.405896) (xy 349.671814 -252.425949) (xy 349.691358 -252.468813)
			(xy 349.704617 -252.514019) (xy 349.711321 -252.560649) (xy 349.711772 -252.584204) (xy 349.711289 -252.610192)
			(xy 349.703157 -252.661528) (xy 349.687094 -252.71096) (xy 349.663495 -252.75727) (xy 349.632942 -252.799318)
			(xy 349.596187 -252.836068) (xy 349.554136 -252.866616) (xy 349.507823 -252.890209) (xy 349.458389 -252.906266)
			(xy 349.407052 -252.914392) (xy 349.381064 -252.914912) (xy 349.357393 -252.914491) (xy 349.310539 -252.907709)
			(xy 349.26513 -252.894316) (xy 349.222094 -252.874588) (xy 349.201994 -252.86208) (xy 349.189802 -252.85446)
			(xy 349.161608 -252.853698) (xy 348.314518 -253.340362) (xy 348.300802 -253.365) (xy 348.301564 -253.379478)
			(xy 348.301818 -253.39421) (xy 348.301564 -253.405894) (xy 348.301056 -253.420372) (xy 348.314518 -253.444756)
			(xy 349.164402 -253.932944) (xy 349.192342 -253.932182) (xy 349.204534 -253.924562) (xy 349.224438 -253.912465)
			(xy 349.26692 -253.89337) (xy 349.311661 -253.880424) (xy 349.357776 -253.873884) (xy 349.381064 -253.873508)
			(xy 349.407054 -253.873988) (xy 349.458394 -253.882115) (xy 349.507831 -253.898173) (xy 349.554147 -253.921768)
			(xy 349.596202 -253.952318) (xy 349.632959 -253.989071) (xy 349.663513 -254.031122) (xy 349.687113 -254.077435)
			(xy 349.703177 -254.126871) (xy 349.711309 -254.17821) (xy 349.711309 -254.23019) (xy 349.703177 -254.281529)
			(xy 349.687113 -254.330965) (xy 349.663513 -254.377278) (xy 349.632959 -254.419329) (xy 349.596202 -254.456082)
			(xy 349.554147 -254.486632) (xy 349.507831 -254.510227) (xy 349.458394 -254.526285) (xy 349.407054 -254.534412)
			(xy 349.381064 -254.534924) (xy 349.357393 -254.534503) (xy 349.310539 -254.527721) (xy 349.26513 -254.514329)
			(xy 349.222094 -254.494601) (xy 349.201994 -254.482092) (xy 349.189802 -254.474472) (xy 349.161608 -254.47371)
			(xy 348.314518 -254.960374) (xy 348.300802 -254.985012) (xy 348.301564 -254.99949) (xy 348.301818 -255.014222)
			(xy 348.301398 -255.037549) (xy 348.29481 -255.083737) (xy 348.281809 -255.128544) (xy 348.262653 -255.171085)
			(xy 348.25051 -255.191006) (xy 348.24289 -255.203198) (xy 348.242382 -255.231392) (xy 348.387162 -255.48082)
			(xy 348.412054 -255.494536) (xy 348.426278 -255.493774) (xy 348.44101 -255.49352) (xy 348.466998 -255.494004)
			(xy 348.518334 -255.502137) (xy 348.567765 -255.5182) (xy 348.614075 -255.541799) (xy 348.656123 -255.572352)
			(xy 348.692873 -255.609106) (xy 348.723421 -255.651158) (xy 348.747015 -255.69747) (xy 348.763072 -255.746903)
			(xy 348.771199 -255.79824) (xy 348.771718 -255.824228) (xy 348.771309 -255.847586) (xy 348.764731 -255.893836)
			(xy 348.751723 -255.938705) (xy 348.732543 -255.981302) (xy 348.72041 -256.001266) (xy 348.71279 -256.013204)
			(xy 348.712282 -256.041398) (xy 348.856808 -256.29108) (xy 348.8817 -256.304542) (xy 348.895924 -256.30378)
			(xy 348.911164 -256.303526) (xy 348.937154 -256.304006) (xy 348.988495 -256.312133) (xy 349.037932 -256.328193)
			(xy 349.084248 -256.351789) (xy 349.126302 -256.382341) (xy 349.163057 -256.419097) (xy 349.19361 -256.46115)
			(xy 349.217206 -256.507466) (xy 349.233266 -256.556903) (xy 349.241393 -256.608244) (xy 349.241872 -256.634234)
			(xy 349.241805 -256.644036) (xy 349.240659 -256.663607) (xy 349.239586 -256.67335) (xy 349.237808 -256.687574)
			(xy 349.249492 -256.713228) (xy 350.565974 -257.618738) (xy 350.595438 -257.619754) (xy 350.608138 -257.612134)
			(xy 350.629481 -257.600075) (xy 350.674673 -257.581078) (xy 350.72198 -257.568223) (xy 350.770571 -257.561738)
			(xy 350.795082 -257.561334) (xy 350.821427 -257.561781) (xy 350.873582 -257.569278) (xy 350.924139 -257.584121)
			(xy 350.972068 -257.60601) (xy 351.016394 -257.634497) (xy 351.056214 -257.669003) (xy 351.090718 -257.708825)
			(xy 351.119202 -257.753153) (xy 351.141087 -257.801084) (xy 351.155927 -257.851641) (xy 351.163421 -257.903797)
			(xy 351.16389 -257.930142) (xy 351.163434 -257.956239) (xy 351.156068 -258.00791) (xy 351.141487 -258.058026)
			(xy 351.119985 -258.105584) (xy 351.09199 -258.149635) (xy 351.058062 -258.189297) (xy 351.01888 -258.223779)
			(xy 350.975227 -258.252389) (xy 350.9518 -258.263898) (xy 350.938338 -258.270248) (xy 350.92259 -258.294886)
			(xy 350.92259 -258.46532) (xy 350.938338 -258.489958) (xy 350.9518 -258.496308) (xy 350.976795 -258.508589)
			(xy 351.023087 -258.539544) (xy 351.064197 -258.577109) (xy 351.099189 -258.620431) (xy 351.127267 -258.668522)
			(xy 351.147793 -258.720289) (xy 351.160299 -258.774555) (xy 351.164501 -258.830085) (xy 351.160721 -258.880102)
			(xy 399.452088 -258.880102) (xy 399.456118 -258.737767) (xy 399.468193 -258.595887) (xy 399.488276 -258.454919)
			(xy 399.516303 -258.315312) (xy 399.552183 -258.177514) (xy 399.595801 -258.041967) (xy 399.647018 -257.909105)
			(xy 399.705669 -257.779353) (xy 399.771567 -257.653127) (xy 399.844501 -257.530831) (xy 399.924238 -257.412858)
			(xy 400.01052 -257.299585) (xy 400.103073 -257.191374) (xy 400.2016 -257.088573) (xy 400.305785 -256.991511)
			(xy 400.415294 -256.900499) (xy 400.529777 -256.815827) (xy 400.648867 -256.737769) (xy 400.772182 -256.666573)
			(xy 400.899328 -256.602467) (xy 401.029897 -256.545658) (xy 401.163471 -256.496326) (xy 401.299622 -256.45463)
			(xy 401.437913 -256.420704) (xy 401.577903 -256.394656) (xy 401.719142 -256.37657) (xy 401.861178 -256.366503)
			(xy 402.003556 -256.364488) (xy 402.14582 -256.370531) (xy 402.287514 -256.384613) (xy 402.428184 -256.406689)
			(xy 402.567381 -256.436689) (xy 402.704657 -256.474515) (xy 402.839573 -256.520047) (xy 402.971697 -256.573138)
			(xy 403.100606 -256.63362) (xy 403.225887 -256.701298) (xy 403.347138 -256.775955) (xy 403.463971 -256.857353)
			(xy 403.576012 -256.94523) (xy 403.682902 -257.039305) (xy 403.784299 -257.139277) (xy 403.879877 -257.244825)
			(xy 403.969331 -257.355611) (xy 404.052373 -257.47128) (xy 404.128739 -257.591463) (xy 404.198183 -257.715773)
			(xy 404.260483 -257.843814) (xy 404.315439 -257.975173) (xy 404.362876 -258.109432) (xy 404.40264 -258.246159)
			(xy 404.434606 -258.384917) (xy 404.458671 -258.525261) (xy 404.474757 -258.666742) (xy 404.482812 -258.808906)
			(xy 404.483316 -258.880102) (xy 404.482812 -258.951298) (xy 404.474757 -259.093462) (xy 404.458671 -259.234943)
			(xy 404.434606 -259.375287) (xy 404.40264 -259.514045) (xy 404.362876 -259.650772) (xy 404.315439 -259.785031)
			(xy 404.260483 -259.91639) (xy 404.198183 -260.044431) (xy 404.128739 -260.168741) (xy 404.052373 -260.288924)
			(xy 403.969331 -260.404593) (xy 403.879877 -260.515379) (xy 403.784299 -260.620927) (xy 403.682902 -260.720899)
			(xy 403.576012 -260.814974) (xy 403.463971 -260.902851) (xy 403.347138 -260.984249) (xy 403.225887 -261.058906)
			(xy 403.100606 -261.126584) (xy 402.971697 -261.187066) (xy 402.839573 -261.240157) (xy 402.704657 -261.285689)
			(xy 402.567381 -261.323515) (xy 402.428184 -261.353515) (xy 402.287514 -261.375591) (xy 402.14582 -261.389673)
			(xy 402.003556 -261.395716) (xy 401.861178 -261.393701) (xy 401.719142 -261.383634) (xy 401.577903 -261.365548)
			(xy 401.437913 -261.3395) (xy 401.299622 -261.305574) (xy 401.163471 -261.263878) (xy 401.029897 -261.214546)
			(xy 400.899328 -261.157737) (xy 400.772182 -261.093631) (xy 400.648867 -261.022435) (xy 400.529777 -260.944377)
			(xy 400.415294 -260.859705) (xy 400.305785 -260.768693) (xy 400.2016 -260.671631) (xy 400.103073 -260.56883)
			(xy 400.01052 -260.460619) (xy 399.924238 -260.347346) (xy 399.844501 -260.229373) (xy 399.771567 -260.107077)
			(xy 399.705669 -259.980851) (xy 399.647018 -259.851099) (xy 399.595801 -259.718237) (xy 399.552183 -259.58269)
			(xy 399.516303 -259.444892) (xy 399.488276 -259.305285) (xy 399.468193 -259.164317) (xy 399.456118 -259.022437)
			(xy 399.452088 -258.880102) (xy 351.160721 -258.880102) (xy 351.160304 -258.885614) (xy 351.147802 -258.939881)
			(xy 351.127281 -258.99165) (xy 351.099206 -259.039744) (xy 351.064218 -259.083068) (xy 351.023111 -259.120637)
			(xy 350.976821 -259.151596) (xy 350.9518 -259.16382) (xy 350.938338 -259.17017) (xy 350.92259 -259.194808)
			(xy 350.92259 -259.365242) (xy 350.938338 -259.38988) (xy 350.9518 -259.39623) (xy 350.975241 -259.407715)
			(xy 351.018909 -259.436314) (xy 351.058102 -259.470791) (xy 351.092035 -259.510455) (xy 351.12003 -259.554512)
			(xy 351.141525 -259.60208) (xy 351.156089 -259.652206) (xy 351.163432 -259.703886) (xy 351.16389 -259.729986)
			(xy 351.163443 -259.756332) (xy 351.155946 -259.808487) (xy 351.141102 -259.859045) (xy 351.119214 -259.906975)
			(xy 351.090727 -259.951302) (xy 351.056221 -259.991124) (xy 351.016399 -260.025629) (xy 350.972072 -260.054116)
			(xy 350.924141 -260.076003) (xy 350.873583 -260.090847) (xy 350.821428 -260.098343) (xy 350.795082 -260.098794)
			(xy 350.769907 -260.098364) (xy 350.720024 -260.091512) (xy 350.671538 -260.077936) (xy 350.64827 -260.068314)
			(xy 350.634554 -260.062472) (xy 350.605852 -260.067044) (xy 349.537528 -261.00786) (xy 349.529146 -261.034276)
			(xy 349.532702 -261.0485) (xy 349.536992 -261.067579) (xy 349.541582 -261.106416) (xy 349.541846 -261.12597)
			(xy 349.541442 -261.149589) (xy 349.534758 -261.196351) (xy 349.521493 -261.241687) (xy 349.501916 -261.284676)
			(xy 349.489522 -261.304786) (xy 349.481648 -261.316978) (xy 349.480886 -261.344918) (xy 349.624904 -261.593076)
			(xy 349.649542 -261.606538) (xy 349.66402 -261.605776) (xy 349.681038 -261.605268) (xy 349.707025 -261.60578)
			(xy 349.758359 -261.613916) (xy 349.807788 -261.629982) (xy 349.854095 -261.653581) (xy 349.896141 -261.684134)
			(xy 349.932891 -261.720888) (xy 349.963438 -261.762937) (xy 349.987033 -261.809247) (xy 350.003093 -261.858678)
			(xy 350.011223 -261.910013) (xy 350.011223 -261.961987) (xy 350.003093 -262.013322) (xy 349.987033 -262.062753)
			(xy 349.963438 -262.109063) (xy 349.932891 -262.151112) (xy 349.896141 -262.187866) (xy 349.854095 -262.218419)
			(xy 349.807788 -262.242018) (xy 349.758359 -262.258084) (xy 349.707025 -262.26622) (xy 349.681038 -262.266684)
			(xy 349.66656 -262.26643) (xy 349.652336 -262.265668) (xy 349.627444 -262.279384) (xy 349.482664 -262.529066)
			(xy 349.483172 -262.557514) (xy 349.490792 -262.569452) (xy 349.50289 -262.589355) (xy 349.521985 -262.631837)
			(xy 349.53493 -262.676579) (xy 349.541469 -262.722694) (xy 349.541846 -262.745982) (xy 349.541429 -262.769569)
			(xy 349.534729 -262.816264) (xy 349.521462 -262.861534) (xy 349.501897 -262.90446) (xy 349.489522 -262.924544)
			(xy 349.481648 -262.936736) (xy 349.480886 -262.96493) (xy 349.624904 -263.213088) (xy 349.649542 -263.22655)
			(xy 349.66402 -263.225788) (xy 349.681038 -263.22528) (xy 349.707024 -263.225792) (xy 349.758354 -263.233928)
			(xy 349.80778 -263.249992) (xy 349.854085 -263.273589) (xy 349.896129 -263.30414) (xy 349.932877 -263.34089)
			(xy 349.963424 -263.382937) (xy 349.987018 -263.429244) (xy 350.003078 -263.478671) (xy 350.01121 -263.530002)
			(xy 350.011746 -263.555988) (xy 350.011343 -263.579618) (xy 350.004608 -263.626396) (xy 349.991273 -263.671736)
			(xy 349.971612 -263.714712) (xy 349.959168 -263.734804) (xy 349.951294 -263.746996) (xy 349.950786 -263.77519)
			(xy 350.09455 -264.023094) (xy 350.119442 -264.036556) (xy 350.13392 -264.035794) (xy 350.151192 -264.035286)
			(xy 350.174593 -264.035692) (xy 350.220927 -264.042293) (xy 350.265867 -264.055364) (xy 350.308513 -264.074645)
			(xy 350.328484 -264.086848) (xy 350.340422 -264.094468) (xy 350.368616 -264.094976) (xy 351.485962 -263.453372)
			(xy 351.490788 -263.45007) (xy 353.061524 -262.294624) (xy 353.072192 -262.266938) (xy 353.069144 -262.25246)
			(xy 353.065796 -262.234551) (xy 353.062233 -262.198289) (xy 353.062032 -262.18007) (xy 353.062482 -262.153727)
			(xy 353.069984 -262.101577) (xy 353.084832 -262.051026) (xy 353.106723 -262.003103) (xy 353.135212 -261.958783)
			(xy 353.169718 -261.918968) (xy 353.209539 -261.88447) (xy 353.253864 -261.85599) (xy 353.301792 -261.834108)
			(xy 353.352346 -261.81927) (xy 353.404497 -261.811777) (xy 353.43084 -261.811262) (xy 353.462937 -261.81195)
			(xy 353.526164 -261.823055) (xy 353.55657 -261.83336) (xy 353.57054 -261.83844) (xy 353.599496 -261.83209)
			(xy 354.008182 -261.42315) (xy 354.01377 -261.39267) (xy 354.00742 -261.378192) (xy 353.997605 -261.354753)
			(xy 353.983789 -261.305853) (xy 353.976835 -261.255517) (xy 353.976432 -261.23011) (xy 353.976879 -261.203765)
			(xy 353.984377 -261.151611) (xy 353.999221 -261.101055) (xy 354.02111 -261.053127) (xy 354.049598 -261.008802)
			(xy 354.084104 -260.968982) (xy 354.123926 -260.93448) (xy 354.168253 -260.905996) (xy 354.216183 -260.884111)
			(xy 354.26674 -260.869271) (xy 354.318895 -260.861777) (xy 354.34524 -260.861302) (xy 354.373262 -260.861826)
			(xy 354.428659 -260.870309) (xy 354.482136 -260.887075) (xy 354.532462 -260.911736) (xy 354.578479 -260.943725)
			(xy 354.619127 -260.982307) (xy 354.653471 -261.026594) (xy 354.680722 -261.075566) (xy 354.700252 -261.128097)
			(xy 354.706428 -261.155434) (xy 354.710238 -261.173468) (xy 354.737924 -261.196074) (xy 355.22281 -261.196074)
			(xy 355.247702 -261.180072) (xy 355.253798 -261.166864) (xy 355.266062 -261.141792) (xy 355.297011 -261.095346)
			(xy 355.334603 -261.054094) (xy 355.377982 -261.018975) (xy 355.426156 -260.990793) (xy 355.478027 -260.970191)
			(xy 355.532409 -260.957638) (xy 355.588062 -260.953422) (xy 355.643715 -260.957638) (xy 355.698097 -260.970191)
			(xy 355.749968 -260.990793) (xy 355.798142 -261.018975) (xy 355.841521 -261.054094) (xy 355.879113 -261.095346)
			(xy 355.910062 -261.141792) (xy 355.922326 -261.166864) (xy 355.928422 -261.180072) (xy 355.953314 -261.196074)
			(xy 356.17277 -261.196074) (xy 356.197662 -261.180072) (xy 356.203758 -261.166864) (xy 356.216022 -261.141792)
			(xy 356.246971 -261.095346) (xy 356.284563 -261.054094) (xy 356.327942 -261.018975) (xy 356.376116 -260.990793)
			(xy 356.427987 -260.970191) (xy 356.482369 -260.957638) (xy 356.538022 -260.953422) (xy 356.593675 -260.957638)
			(xy 356.648057 -260.970191) (xy 356.699928 -260.990793) (xy 356.748102 -261.018975) (xy 356.791481 -261.054094)
			(xy 356.829073 -261.095346) (xy 356.860022 -261.141792) (xy 356.872286 -261.166864) (xy 356.878382 -261.180072)
			(xy 356.903274 -261.196074) (xy 357.12273 -261.196074) (xy 357.147622 -261.180072) (xy 357.153718 -261.166864)
			(xy 357.165982 -261.141792) (xy 357.196931 -261.095346) (xy 357.234523 -261.054094) (xy 357.277902 -261.018975)
			(xy 357.326076 -260.990793) (xy 357.377947 -260.970191) (xy 357.432329 -260.957638) (xy 357.487982 -260.953422)
			(xy 357.543635 -260.957638) (xy 357.598017 -260.970191) (xy 357.649888 -260.990793) (xy 357.698062 -261.018975)
			(xy 357.741441 -261.054094) (xy 357.779033 -261.095346) (xy 357.809982 -261.141792) (xy 357.822246 -261.166864)
			(xy 357.828342 -261.180072) (xy 357.853234 -261.196074) (xy 358.07269 -261.196074) (xy 358.097582 -261.180072)
			(xy 358.103678 -261.166864) (xy 358.115942 -261.141792) (xy 358.146891 -261.095346) (xy 358.184483 -261.054094)
			(xy 358.227862 -261.018975) (xy 358.276036 -260.990793) (xy 358.327907 -260.970191) (xy 358.382289 -260.957638)
			(xy 358.437942 -260.953422) (xy 358.493595 -260.957638) (xy 358.547977 -260.970191) (xy 358.599848 -260.990793)
			(xy 358.648022 -261.018975) (xy 358.691401 -261.054094) (xy 358.728993 -261.095346) (xy 358.759942 -261.141792)
			(xy 358.772206 -261.166864) (xy 358.778302 -261.180072) (xy 358.803194 -261.196074) (xy 359.02265 -261.196074)
			(xy 359.047542 -261.180072) (xy 359.053638 -261.166864) (xy 359.065902 -261.141792) (xy 359.096851 -261.095346)
			(xy 359.134443 -261.054094) (xy 359.177822 -261.018975) (xy 359.225996 -260.990793) (xy 359.277867 -260.970191)
			(xy 359.332249 -260.957638) (xy 359.387902 -260.953422) (xy 359.443555 -260.957638) (xy 359.497937 -260.970191)
			(xy 359.549808 -260.990793) (xy 359.597982 -261.018975) (xy 359.641361 -261.054094) (xy 359.678953 -261.095346)
			(xy 359.709902 -261.141792) (xy 359.722166 -261.166864) (xy 359.728262 -261.180072) (xy 359.753154 -261.196074)
			(xy 359.97261 -261.196074) (xy 359.997502 -261.180072) (xy 360.003598 -261.166864) (xy 360.015862 -261.141792)
			(xy 360.046811 -261.095346) (xy 360.084403 -261.054094) (xy 360.127782 -261.018975) (xy 360.175956 -260.990793)
			(xy 360.227827 -260.970191) (xy 360.282209 -260.957638) (xy 360.337862 -260.953422) (xy 360.393515 -260.957638)
			(xy 360.447897 -260.970191) (xy 360.499768 -260.990793) (xy 360.547942 -261.018975) (xy 360.591321 -261.054094)
			(xy 360.628913 -261.095346) (xy 360.659862 -261.141792) (xy 360.672126 -261.166864) (xy 360.678222 -261.180072)
			(xy 360.703114 -261.196074) (xy 360.922824 -261.196074) (xy 360.947716 -261.180072) (xy 360.953812 -261.166864)
			(xy 360.966076 -261.141792) (xy 360.997025 -261.095346) (xy 361.034617 -261.054094) (xy 361.077996 -261.018975)
			(xy 361.12617 -260.990793) (xy 361.178041 -260.970191) (xy 361.232423 -260.957638) (xy 361.288076 -260.953422)
			(xy 361.343729 -260.957638) (xy 361.398111 -260.970191) (xy 361.449982 -260.990793) (xy 361.498156 -261.018975)
			(xy 361.541535 -261.054094) (xy 361.579127 -261.095346) (xy 361.610076 -261.141792) (xy 361.62234 -261.166864)
			(xy 361.628436 -261.180072) (xy 361.653328 -261.196074) (xy 361.872784 -261.196074) (xy 361.897676 -261.180072)
			(xy 361.903772 -261.166864) (xy 361.916036 -261.141792) (xy 361.946985 -261.095346) (xy 361.984577 -261.054094)
			(xy 362.027956 -261.018975) (xy 362.07613 -260.990793) (xy 362.128001 -260.970191) (xy 362.182383 -260.957638)
			(xy 362.238036 -260.953422) (xy 362.293689 -260.957638) (xy 362.348071 -260.970191) (xy 362.399942 -260.990793)
			(xy 362.448116 -261.018975) (xy 362.491495 -261.054094) (xy 362.529087 -261.095346) (xy 362.560036 -261.141792)
			(xy 362.5723 -261.166864) (xy 362.578396 -261.180072) (xy 362.603288 -261.196074) (xy 362.822744 -261.196074)
			(xy 362.847636 -261.180072) (xy 362.853732 -261.166864) (xy 362.865996 -261.141792) (xy 362.896945 -261.095346)
			(xy 362.934537 -261.054094) (xy 362.977916 -261.018975) (xy 363.02609 -260.990793) (xy 363.077961 -260.970191)
			(xy 363.132343 -260.957638) (xy 363.187996 -260.953422) (xy 363.243649 -260.957638) (xy 363.298031 -260.970191)
			(xy 363.349902 -260.990793) (xy 363.398076 -261.018975) (xy 363.441455 -261.054094) (xy 363.479047 -261.095346)
			(xy 363.509996 -261.141792) (xy 363.52226 -261.166864) (xy 363.528356 -261.180072) (xy 363.553248 -261.196074)
			(xy 363.772704 -261.196074) (xy 363.797596 -261.180072) (xy 363.803692 -261.166864) (xy 363.815164 -261.14335)
			(xy 363.843759 -261.099539) (xy 363.878262 -261.060211) (xy 363.917977 -261.026156) (xy 363.962109 -260.998057)
			(xy 364.009769 -260.976479) (xy 364.060002 -260.961857) (xy 364.111797 -260.954482) (xy 364.137956 -260.954012)
			(xy 364.164303 -260.954457) (xy 364.216462 -260.961951) (xy 364.267023 -260.976792) (xy 364.314957 -260.998678)
			(xy 364.359288 -261.027165) (xy 364.399113 -261.06167) (xy 364.433621 -261.101493) (xy 364.46211 -261.145822)
			(xy 364.484 -261.193755) (xy 364.498844 -261.244315) (xy 364.506341 -261.296473) (xy 364.506764 -261.32282)
			(xy 364.50609 -261.354981) (xy 364.49498 -261.418335) (xy 364.484666 -261.448804) (xy 364.479586 -261.46252)
			(xy 364.485936 -261.491476) (xy 364.522766 -261.528306) (xy 364.530168 -261.535142) (xy 364.548766 -261.542851)
			(xy 364.558834 -261.543292) (xy 368.210592 -261.543292) (xy 368.227169 -261.543852) (xy 368.259191 -261.552453)
			(xy 368.28791 -261.569022) (xy 368.3 -261.580376) (xy 368.551206 -261.831836) (xy 368.561874 -261.839964)
			(xy 369.667282 -262.474964) (xy 369.695476 -262.474456) (xy 369.707414 -262.466836) (xy 369.727385 -262.454634)
			(xy 369.770035 -262.435364) (xy 369.814974 -262.422295) (xy 369.861306 -262.415688) (xy 369.884706 -262.415274)
			(xy 369.901978 -262.415782) (xy 369.916456 -262.416544) (xy 369.941348 -262.403082) (xy 370.085112 -262.155178)
			(xy 370.084604 -262.126984) (xy 370.07673 -262.114792) (xy 370.064284 -262.094702) (xy 370.044634 -262.051722)
			(xy 370.031303 -262.006382) (xy 370.024564 -261.959605) (xy 370.024152 -261.935976) (xy 370.024662 -261.909989)
			(xy 370.032792 -261.858654) (xy 370.048853 -261.809224) (xy 370.072449 -261.762914) (xy 370.102999 -261.720866)
			(xy 370.13975 -261.684115) (xy 370.181798 -261.653565) (xy 370.228108 -261.629969) (xy 370.277538 -261.613908)
			(xy 370.328873 -261.605778) (xy 370.380847 -261.605778) (xy 370.432182 -261.613908) (xy 370.481612 -261.629969)
			(xy 370.527922 -261.653565) (xy 370.56997 -261.684115) (xy 370.606721 -261.720866) (xy 370.637271 -261.762914)
			(xy 370.660867 -261.809224) (xy 370.676928 -261.858654) (xy 370.685058 -261.909989) (xy 370.685568 -261.935976)
			(xy 370.685314 -261.948422) (xy 370.684806 -261.962646) (xy 370.698522 -261.987284) (xy 371.54739 -262.474964)
			(xy 371.575584 -262.474456) (xy 371.587522 -262.466836) (xy 371.607494 -262.454635) (xy 371.650143 -262.435366)
			(xy 371.695082 -262.422298) (xy 371.741414 -262.415692) (xy 371.764814 -262.415274) (xy 371.790801 -262.415785)
			(xy 371.842135 -262.423917) (xy 371.891565 -262.439979) (xy 371.937874 -262.463575) (xy 371.979921 -262.494125)
			(xy 372.016673 -262.530876) (xy 372.047223 -262.572923) (xy 372.07082 -262.619232) (xy 372.086882 -262.668661)
			(xy 372.095015 -262.719995) (xy 372.095522 -262.745982) (xy 372.095268 -262.758428) (xy 372.09476 -262.772652)
			(xy 372.108476 -262.79729) (xy 372.957344 -263.28497) (xy 372.985538 -263.284462) (xy 372.997476 -263.276842)
			(xy 373.017447 -263.264638) (xy 373.060095 -263.245363) (xy 373.105034 -263.232288) (xy 373.151367 -263.225676)
			(xy 373.174768 -263.22528) (xy 373.19204 -263.225788) (xy 373.206518 -263.22655) (xy 373.23141 -263.213088)
			(xy 373.375174 -262.965184) (xy 373.374666 -262.93699) (xy 373.366792 -262.924798) (xy 373.354343 -262.904709)
			(xy 373.334689 -262.861729) (xy 373.321355 -262.816389) (xy 373.314614 -262.769612) (xy 373.314214 -262.745982)
			(xy 373.314724 -262.719995) (xy 373.322854 -262.66866) (xy 373.338915 -262.61923) (xy 373.362511 -262.57292)
			(xy 373.393061 -262.530872) (xy 373.429812 -262.494121) (xy 373.47186 -262.463571) (xy 373.51817 -262.439975)
			(xy 373.5676 -262.423914) (xy 373.618935 -262.415784) (xy 373.670909 -262.415784) (xy 373.722244 -262.423914)
			(xy 373.771674 -262.439975) (xy 373.817984 -262.463571) (xy 373.860032 -262.494121) (xy 373.896783 -262.530872)
			(xy 373.927333 -262.57292) (xy 373.950929 -262.61923) (xy 373.96699 -262.66866) (xy 373.97512 -262.719995)
			(xy 373.97563 -262.745982) (xy 373.975376 -262.758428) (xy 373.974868 -262.772652) (xy 373.988584 -262.79729)
			(xy 374.837452 -263.28497) (xy 374.865646 -263.284462) (xy 374.877584 -263.276842) (xy 374.897555 -263.264638)
			(xy 374.940204 -263.245364) (xy 374.985143 -263.232291) (xy 375.031475 -263.22568) (xy 375.054876 -263.22528)
			(xy 375.072148 -263.225788) (xy 375.086626 -263.22655) (xy 375.111264 -263.213088) (xy 375.255028 -262.965692)
			(xy 375.25452 -262.93699) (xy 375.246646 -262.925052) (xy 375.234209 -262.90492) (xy 375.214548 -262.861879)
			(xy 375.201211 -262.816478) (xy 375.194468 -262.769642) (xy 375.194068 -262.745982) (xy 375.194579 -262.719995)
			(xy 375.202712 -262.668661) (xy 375.218774 -262.619232) (xy 375.24237 -262.572923) (xy 375.27292 -262.530875)
			(xy 375.309671 -262.494124) (xy 375.351718 -262.463573) (xy 375.398026 -262.439976) (xy 375.447456 -262.423913)
			(xy 375.498789 -262.415779) (xy 375.524776 -262.415274) (xy 375.550603 -262.415769) (xy 375.60163 -262.423796)
			(xy 375.650788 -262.439658) (xy 375.696883 -262.46297) (xy 375.738793 -262.493165) (xy 375.775499 -262.529509)
			(xy 375.806108 -262.571117) (xy 375.8184 -262.593836) (xy 375.825004 -262.606536) (xy 375.849134 -262.621268)
			(xy 376.140472 -262.621268) (xy 376.164602 -262.606536) (xy 376.171206 -262.593836) (xy 376.183529 -262.571135)
			(xy 376.214133 -262.529527) (xy 376.250833 -262.493183) (xy 376.292738 -262.462987) (xy 376.338828 -262.439673)
			(xy 376.387982 -262.423808) (xy 376.439005 -262.415778) (xy 376.490655 -262.415778) (xy 376.541678 -262.423808)
			(xy 376.590832 -262.439673) (xy 376.636922 -262.462987) (xy 376.678827 -262.493183) (xy 376.715527 -262.529527)
			(xy 376.746131 -262.571135) (xy 376.758454 -262.593836) (xy 376.765058 -262.606536) (xy 376.789188 -262.621268)
			(xy 377.080526 -262.621268) (xy 377.104656 -262.606536) (xy 377.11126 -262.593836) (xy 377.123583 -262.571135)
			(xy 377.154187 -262.529527) (xy 377.190887 -262.493183) (xy 377.232792 -262.462987) (xy 377.278882 -262.439673)
			(xy 377.328036 -262.423808) (xy 377.379059 -262.415778) (xy 377.430709 -262.415778) (xy 377.481732 -262.423808)
			(xy 377.530886 -262.439673) (xy 377.576976 -262.462987) (xy 377.618881 -262.493183) (xy 377.655581 -262.529527)
			(xy 377.686185 -262.571135) (xy 377.698508 -262.593836) (xy 377.705112 -262.606536) (xy 377.729242 -262.621268)
			(xy 378.02058 -262.621268) (xy 378.04471 -262.606536) (xy 378.051314 -262.593836) (xy 378.063636 -262.571133)
			(xy 378.09424 -262.529521) (xy 378.130939 -262.493172) (xy 378.172843 -262.46297) (xy 378.218933 -262.439649)
			(xy 378.268087 -262.423776) (xy 378.319111 -262.415737) (xy 378.344938 -262.415274) (xy 378.370924 -262.415786)
			(xy 378.422255 -262.423922) (xy 378.471681 -262.439986) (xy 378.517987 -262.463583) (xy 378.560031 -262.494133)
			(xy 378.59678 -262.530884) (xy 378.627327 -262.57293) (xy 378.650922 -262.619237) (xy 378.666983 -262.668665)
			(xy 378.675115 -262.719996) (xy 378.675646 -262.745982) (xy 378.675392 -262.758428) (xy 378.674884 -262.772652)
			(xy 378.6886 -262.79729) (xy 379.537214 -263.28497) (xy 379.565662 -263.284462) (xy 379.5776 -263.276842)
			(xy 379.597571 -263.264639) (xy 379.64022 -263.245367) (xy 379.685159 -263.232296) (xy 379.731491 -263.225687)
			(xy 379.754892 -263.22528) (xy 379.780718 -263.225776) (xy 379.831743 -263.233805) (xy 379.8809 -263.24967)
			(xy 379.926992 -263.272983) (xy 379.9689 -263.303179) (xy 380.005603 -263.339523) (xy 380.03621 -263.381131)
			(xy 380.048516 -263.403842) (xy 380.05512 -263.416542) (xy 380.07925 -263.431274) (xy 380.370588 -263.431274)
			(xy 380.394718 -263.416542) (xy 380.401322 -263.403842) (xy 380.413645 -263.381141) (xy 380.444249 -263.339533)
			(xy 380.480949 -263.303189) (xy 380.522854 -263.272993) (xy 380.568944 -263.249679) (xy 380.618098 -263.233814)
			(xy 380.669121 -263.225784) (xy 380.720771 -263.225784) (xy 380.771794 -263.233814) (xy 380.820948 -263.249679)
			(xy 380.867038 -263.272993) (xy 380.908943 -263.303189) (xy 380.945643 -263.339533) (xy 380.976247 -263.381141)
			(xy 380.98857 -263.403842) (xy 380.995174 -263.416542) (xy 381.019304 -263.431274) (xy 381.310388 -263.431274)
			(xy 381.334518 -263.416542) (xy 381.341122 -263.403842) (xy 381.353445 -263.381141) (xy 381.384049 -263.339533)
			(xy 381.420749 -263.303189) (xy 381.462654 -263.272993) (xy 381.508744 -263.249679) (xy 381.557898 -263.233814)
			(xy 381.608921 -263.225784) (xy 381.660571 -263.225784) (xy 381.711594 -263.233814) (xy 381.760748 -263.249679)
			(xy 381.806838 -263.272993) (xy 381.848743 -263.303189) (xy 381.885443 -263.339533) (xy 381.916047 -263.381141)
			(xy 381.92837 -263.403842) (xy 381.934974 -263.416542) (xy 381.959104 -263.431274) (xy 382.250442 -263.431274)
			(xy 382.274572 -263.416542) (xy 382.281176 -263.403842) (xy 382.293499 -263.381141) (xy 382.324103 -263.339533)
			(xy 382.360803 -263.303189) (xy 382.402708 -263.272993) (xy 382.448798 -263.249679) (xy 382.497952 -263.233814)
			(xy 382.548975 -263.225784) (xy 382.600625 -263.225784) (xy 382.651648 -263.233814) (xy 382.700802 -263.249679)
			(xy 382.746892 -263.272993) (xy 382.788797 -263.303189) (xy 382.825497 -263.339533) (xy 382.856101 -263.381141)
			(xy 382.868424 -263.403842) (xy 382.875028 -263.416542) (xy 382.899158 -263.431274) (xy 383.190496 -263.431274)
			(xy 383.214626 -263.416542) (xy 383.22123 -263.403842) (xy 383.233553 -263.381141) (xy 383.264157 -263.339533)
			(xy 383.300857 -263.303189) (xy 383.342762 -263.272993) (xy 383.388852 -263.249679) (xy 383.438006 -263.233814)
			(xy 383.489029 -263.225784) (xy 383.540679 -263.225784) (xy 383.591702 -263.233814) (xy 383.640856 -263.249679)
			(xy 383.686946 -263.272993) (xy 383.728851 -263.303189) (xy 383.765551 -263.339533) (xy 383.796155 -263.381141)
			(xy 383.808478 -263.403842) (xy 383.815082 -263.416542) (xy 383.839212 -263.431274) (xy 384.13055 -263.431274)
			(xy 384.15468 -263.416542) (xy 384.161284 -263.403842) (xy 384.173607 -263.381142) (xy 384.204212 -263.339536)
			(xy 384.240913 -263.303194) (xy 384.282818 -263.273) (xy 384.328908 -263.249688) (xy 384.378061 -263.233825)
			(xy 384.429083 -263.225796) (xy 384.454908 -263.22528) (xy 384.480895 -263.22579) (xy 384.532229 -263.233922)
			(xy 384.58166 -263.249983) (xy 384.627969 -263.273579) (xy 384.670017 -263.304129) (xy 384.706768 -263.34088)
			(xy 384.737319 -263.382928) (xy 384.760915 -263.429237) (xy 384.776977 -263.478667) (xy 384.78511 -263.530001)
			(xy 384.785616 -263.555988) (xy 384.785222 -263.578975) (xy 384.778856 -263.624506) (xy 384.766244 -263.668717)
			(xy 384.747631 -263.710754) (xy 384.735832 -263.730486) (xy 384.728212 -263.742678) (xy 384.727958 -263.770364)
			(xy 384.874262 -264.022586) (xy 384.898646 -264.036048) (xy 384.91287 -264.03554) (xy 384.924808 -264.035286)
			(xy 384.950634 -264.035783) (xy 385.001657 -264.043815) (xy 385.050811 -264.059681) (xy 385.096901 -264.082996)
			(xy 385.138806 -264.113192) (xy 385.175507 -264.149537) (xy 385.206111 -264.191145) (xy 385.218432 -264.213848)
			(xy 385.225036 -264.226548) (xy 385.249166 -264.24128) (xy 385.540504 -264.24128) (xy 385.564634 -264.226548)
			(xy 385.571238 -264.213848) (xy 385.583561 -264.191147) (xy 385.614165 -264.149539) (xy 385.650865 -264.113195)
			(xy 385.69277 -264.082999) (xy 385.73886 -264.059685) (xy 385.788014 -264.04382) (xy 385.839037 -264.03579)
			(xy 385.890687 -264.03579) (xy 385.94171 -264.04382) (xy 385.990864 -264.059685) (xy 386.036954 -264.082999)
			(xy 386.078859 -264.113195) (xy 386.115559 -264.149539) (xy 386.146163 -264.191147) (xy 386.158486 -264.213848)
			(xy 386.16509 -264.226548) (xy 386.18922 -264.24128) (xy 386.480558 -264.24128) (xy 386.504688 -264.226548)
			(xy 386.511292 -264.213848) (xy 386.523615 -264.191147) (xy 386.554219 -264.149539) (xy 386.590919 -264.113195)
			(xy 386.632824 -264.082999) (xy 386.678914 -264.059685) (xy 386.728068 -264.04382) (xy 386.779091 -264.03579)
			(xy 386.830741 -264.03579) (xy 386.881764 -264.04382) (xy 386.930918 -264.059685) (xy 386.977008 -264.082999)
			(xy 387.018913 -264.113195) (xy 387.055613 -264.149539) (xy 387.086217 -264.191147) (xy 387.09854 -264.213848)
			(xy 387.105144 -264.226548) (xy 387.129274 -264.24128) (xy 387.420358 -264.24128) (xy 387.444488 -264.226548)
			(xy 387.451092 -264.213848) (xy 387.463415 -264.191147) (xy 387.494019 -264.149539) (xy 387.530719 -264.113195)
			(xy 387.572624 -264.082999) (xy 387.618714 -264.059685) (xy 387.667868 -264.04382) (xy 387.718891 -264.03579)
			(xy 387.770541 -264.03579) (xy 387.821564 -264.04382) (xy 387.870718 -264.059685) (xy 387.916808 -264.082999)
			(xy 387.958713 -264.113195) (xy 387.995413 -264.149539) (xy 388.026017 -264.191147) (xy 388.03834 -264.213848)
			(xy 388.044944 -264.226548) (xy 388.069074 -264.24128) (xy 388.360412 -264.24128) (xy 388.384542 -264.226548)
			(xy 388.391146 -264.213848) (xy 388.403469 -264.191147) (xy 388.434073 -264.149539) (xy 388.470773 -264.113195)
			(xy 388.512678 -264.082999) (xy 388.558768 -264.059685) (xy 388.607922 -264.04382) (xy 388.658945 -264.03579)
			(xy 388.710595 -264.03579) (xy 388.761618 -264.04382) (xy 388.810772 -264.059685) (xy 388.856862 -264.082999)
			(xy 388.898767 -264.113195) (xy 388.935467 -264.149539) (xy 388.966071 -264.191147) (xy 388.978394 -264.213848)
			(xy 388.984998 -264.226548) (xy 389.009128 -264.24128) (xy 389.300466 -264.24128) (xy 389.324596 -264.226548)
			(xy 389.3312 -264.213848) (xy 389.343523 -264.191148) (xy 389.374128 -264.149543) (xy 389.41083 -264.113203)
			(xy 389.452735 -264.08301) (xy 389.498824 -264.0597) (xy 389.547978 -264.043838) (xy 389.598999 -264.035812)
			(xy 389.624824 -264.035286) (xy 389.65081 -264.035797) (xy 389.702142 -264.043931) (xy 389.75157 -264.059994)
			(xy 389.797876 -264.083591) (xy 389.839922 -264.114141) (xy 389.876671 -264.150892) (xy 389.907219 -264.192939)
			(xy 389.930813 -264.239247) (xy 389.946873 -264.288675) (xy 389.955004 -264.340008) (xy 389.955532 -264.365994)
			(xy 389.955138 -264.388981) (xy 389.948771 -264.434512) (xy 389.936159 -264.478722) (xy 389.917546 -264.52076)
			(xy 389.905748 -264.540492) (xy 389.898128 -264.552684) (xy 389.897874 -264.580624) (xy 390.044178 -264.832592)
			(xy 390.068562 -264.846054) (xy 390.082786 -264.845546) (xy 390.094724 -264.845292) (xy 390.12071 -264.845803)
			(xy 390.172042 -264.853937) (xy 390.221469 -264.87) (xy 390.267775 -264.893597) (xy 390.30982 -264.924147)
			(xy 390.346568 -264.960898) (xy 390.377115 -265.002945) (xy 390.400709 -265.049253) (xy 390.416769 -265.098682)
			(xy 390.424899 -265.150014) (xy 390.425432 -265.176) (xy 390.425037 -265.198987) (xy 390.41867 -265.244518)
			(xy 390.406058 -265.288728) (xy 390.387444 -265.330765) (xy 390.375648 -265.350498) (xy 390.368282 -265.362436)
			(xy 390.367774 -265.390376) (xy 390.528556 -265.667236) (xy 390.55167 -265.680698) (xy 390.565386 -265.680698)
			(xy 390.589352 -265.681205) (xy 390.636685 -265.688771) (xy 390.682253 -265.703642) (xy 390.724938 -265.725451)
			(xy 390.76369 -265.753663) (xy 390.797557 -265.787585) (xy 390.825707 -265.826382) (xy 390.847447 -265.869102)
			(xy 390.862244 -265.914694) (xy 390.869734 -265.962039) (xy 390.870186 -265.986006) (xy 390.869635 -266.012325)
			(xy 390.860612 -266.064184) (xy 390.842834 -266.113728) (xy 390.830308 -266.136882) (xy 390.82345 -266.14882)
			(xy 390.823704 -266.175744) (xy 390.984232 -266.452604) (xy 391.008616 -266.466066) (xy 391.02284 -266.465558)
			(xy 391.034778 -266.465304) (xy 391.060605 -266.465799) (xy 391.11163 -266.473827) (xy 391.160787 -266.48969)
			(xy 391.20688 -266.513004) (xy 391.248788 -266.5432) (xy 391.28549 -266.579545) (xy 391.316096 -266.621155)
			(xy 391.328402 -266.643866) (xy 391.335006 -266.656566) (xy 391.359136 -266.671298) (xy 391.650474 -266.671298)
		)
		(stroke
			(width 0)
			(type solid)
		)
		(fill yes)
		(layer "In8.Cu")
		(net "PVDDCR_SOC_P0")
	)
	(gr_poly
		(pts
			(xy 100.348542 -190.745872) (xy 100.358608 -190.745441) (xy 100.377199 -190.737712) (xy 100.38461 -190.730886)
			(xy 104.2416 -186.873896) (xy 104.259642 -186.856639) (xy 104.301136 -186.828886) (xy 104.347254 -186.80978)
			(xy 104.396218 -186.800057) (xy 104.421178 -186.799474) (xy 110.585758 -186.799474) (xy 110.59424 -186.799158)
			(xy 110.610266 -186.793593) (xy 110.623569 -186.783067) (xy 110.62843 -186.776106) (xy 110.643532 -186.753314)
			(xy 110.679223 -186.711895) (xy 110.720461 -186.675994) (xy 110.7664 -186.646346) (xy 110.8161 -186.623558)
			(xy 110.868543 -186.608096) (xy 110.922656 -186.600278) (xy 110.949994 -186.59983) (xy 110.978733 -186.600351)
			(xy 111.035561 -186.608973) (xy 111.090452 -186.626024) (xy 111.142163 -186.651116) (xy 111.189525 -186.683683)
			(xy 111.210852 -186.702954) (xy 111.217964 -186.709558) (xy 111.23549 -186.71667) (xy 111.324898 -186.71667)
			(xy 111.342424 -186.709558) (xy 111.349536 -186.702954) (xy 111.369216 -186.685119) (xy 111.412614 -186.654506)
			(xy 111.45984 -186.630209) (xy 111.509981 -186.6127) (xy 111.562065 -186.602317) (xy 111.58855 -186.600338)
			(xy 111.597948 -186.59983) (xy 111.614712 -186.592464) (xy 111.6584 -186.548776) (xy 111.665243 -186.541376)
			(xy 111.672968 -186.522778) (xy 111.673386 -186.512708) (xy 111.673386 -183.963564) (xy 111.674001 -183.938609)
			(xy 111.683744 -183.889658) (xy 111.702849 -183.843548) (xy 111.730581 -183.802051) (xy 111.747808 -183.783986)
			(xy 126.247144 -169.28465) (xy 126.265185 -169.267391) (xy 126.306679 -169.239634) (xy 126.352797 -169.220522)
			(xy 126.401761 -169.21079) (xy 126.426722 -169.210228) (xy 128.337564 -169.210228) (xy 128.347616 -169.209725)
			(xy 128.366181 -169.202008) (xy 128.373632 -169.195242) (xy 129.705608 -167.863266) (xy 129.723648 -167.846003)
			(xy 129.76514 -167.818239) (xy 129.811258 -167.799119) (xy 129.860224 -167.789379) (xy 129.885186 -167.788844)
			(xy 136.0932 -167.788844) (xy 136.103211 -167.788357) (xy 136.12171 -167.780699) (xy 136.135874 -167.766547)
			(xy 136.143548 -167.748054) (xy 136.144 -167.738044) (xy 136.144 -153.707846) (xy 136.143567 -153.69778)
			(xy 136.135839 -153.67919) (xy 136.129014 -153.671778) (xy 135.562848 -153.105612) (xy 135.555447 -153.098772)
			(xy 135.536849 -153.091055) (xy 135.52678 -153.090626) (xy 134.680198 -153.090626) (xy 134.67217 -153.090869)
			(xy 134.656891 -153.095795) (xy 134.650226 -153.100278) (xy 134.628393 -153.115636) (xy 134.581291 -153.140749)
			(xy 134.531146 -153.159046) (xy 134.478938 -153.17017) (xy 134.42569 -153.173902) (xy 134.372442 -153.17017)
			(xy 134.320234 -153.159046) (xy 134.270089 -153.140749) (xy 134.222987 -153.115636) (xy 134.201154 -153.100278)
			(xy 134.194468 -153.095836) (xy 134.179203 -153.090908) (xy 134.171182 -153.090626) (xy 133.003036 -153.090626)
			(xy 132.992702 -153.091113) (xy 132.973699 -153.099241) (xy 132.966206 -153.106374) (xy 132.946473 -153.126409)
			(xy 132.902167 -153.161038) (xy 132.853255 -153.188783) (xy 132.800798 -153.209042) (xy 132.745934 -153.221376)
			(xy 132.689854 -153.225518) (xy 132.633774 -153.221376) (xy 132.57891 -153.209042) (xy 132.526453 -153.188783)
			(xy 132.477541 -153.161038) (xy 132.433235 -153.126409) (xy 132.413502 -153.106374) (xy 132.406028 -153.09921)
			(xy 132.387014 -153.09107) (xy 132.376672 -153.090626) (xy 130.695954 -153.090626) (xy 130.668522 -153.112724)
			(xy 130.664458 -153.13025) (xy 130.655225 -153.169134) (xy 130.630677 -153.245197) (xy 130.615436 -153.282142)
			(xy 130.611863 -153.291733) (xy 130.611846 -153.312183) (xy 130.615436 -153.321766) (xy 130.631212 -153.360078)
			(xy 130.656411 -153.439014) (xy 130.674165 -153.519951) (xy 130.68432 -153.602187) (xy 130.686048 -153.643584)
			(xy 130.68684 -153.654523) (xy 130.696459 -153.674208) (xy 130.713424 -153.688072) (xy 130.723894 -153.691336)
			(xy 130.740766 -153.695835) (xy 130.774177 -153.705998) (xy 130.790696 -153.711656) (xy 130.798892 -153.714179)
			(xy 130.816028 -153.714179) (xy 130.824224 -153.711656) (xy 130.859442 -153.699704) (xy 130.931449 -153.68107)
			(xy 131.004769 -153.668566) (xy 131.078881 -153.662282) (xy 131.11607 -153.661872) (xy 131.153261 -153.662256)
			(xy 131.227377 -153.668525) (xy 131.3007 -153.681029) (xy 131.372705 -153.699678) (xy 131.407916 -153.711656)
			(xy 131.416112 -153.714179) (xy 131.433248 -153.714179) (xy 131.441444 -153.711656) (xy 131.476662 -153.699701)
			(xy 131.548668 -153.68106) (xy 131.621987 -153.66855) (xy 131.6961 -153.662259) (xy 131.73329 -153.661872)
			(xy 131.775226 -153.662355) (xy 131.858719 -153.670327) (xy 131.941076 -153.686199) (xy 132.021552 -153.709828)
			(xy 132.099416 -153.740999) (xy 132.173966 -153.779431) (xy 132.244524 -153.824776) (xy 132.310453 -153.876622)
			(xy 132.371155 -153.9345) (xy 132.42608 -153.997887) (xy 132.474731 -154.066207) (xy 132.516668 -154.138843)
			(xy 132.55151 -154.215136) (xy 132.578942 -154.294395) (xy 132.598716 -154.375904) (xy 132.610652 -154.458922)
			(xy 132.614643 -154.5427) (xy 132.610652 -154.626478) (xy 132.598716 -154.709496) (xy 132.578942 -154.791005)
			(xy 132.55151 -154.870264) (xy 132.516668 -154.946557) (xy 132.474731 -155.019193) (xy 132.42608 -155.087513)
			(xy 132.371155 -155.1509) (xy 132.310453 -155.208778) (xy 132.244524 -155.260624) (xy 132.173966 -155.305969)
			(xy 132.099416 -155.344401) (xy 132.021552 -155.375572) (xy 131.941076 -155.399201) (xy 131.858719 -155.415073)
			(xy 131.775226 -155.423045) (xy 131.73329 -155.423616) (xy 131.6961 -155.42323) (xy 131.621984 -155.416958)
			(xy 131.548663 -155.404451) (xy 131.476659 -155.385798) (xy 131.441444 -155.373832) (xy 131.433248 -155.371309)
			(xy 131.416112 -155.371309) (xy 131.407916 -155.373832) (xy 131.37458 -155.385161) (xy 131.306488 -155.403091)
			(xy 131.237181 -155.415522) (xy 131.202176 -155.419298) (xy 131.192211 -155.42073) (xy 131.174495 -155.430262)
			(xy 131.161779 -155.445852) (xy 131.158488 -155.455366) (xy 131.151037 -155.480116) (xy 131.133628 -155.528788)
			(xy 131.12369 -155.552648) (xy 131.120116 -155.562239) (xy 131.120101 -155.582688) (xy 131.12369 -155.592272)
			(xy 131.140693 -155.633685) (xy 131.167264 -155.71918) (xy 131.185107 -155.806913) (xy 131.19404 -155.895995)
			(xy 131.194556 -155.94076) (xy 131.194052 -155.983108) (xy 131.186001 -156.067422) (xy 131.169972 -156.150588)
			(xy 131.146111 -156.231855) (xy 131.114632 -156.310485) (xy 131.075821 -156.385766) (xy 131.030031 -156.457018)
			(xy 130.977675 -156.523594) (xy 130.919227 -156.584892) (xy 130.855217 -156.640357) (xy 130.786225 -156.689486)
			(xy 130.712875 -156.731835) (xy 130.635832 -156.767019) (xy 130.555793 -156.794721) (xy 130.473484 -156.814689)
			(xy 130.389649 -156.826742) (xy 130.305048 -156.830773) (xy 130.220447 -156.826742) (xy 130.136612 -156.814689)
			(xy 130.054303 -156.794721) (xy 129.974264 -156.767019) (xy 129.897221 -156.731835) (xy 129.823871 -156.689486)
			(xy 129.754879 -156.640357) (xy 129.690869 -156.584892) (xy 129.632421 -156.523594) (xy 129.580065 -156.457018)
			(xy 129.534275 -156.385766) (xy 129.495464 -156.310485) (xy 129.463985 -156.231855) (xy 129.440124 -156.150588)
			(xy 129.424095 -156.067422) (xy 129.416044 -155.983108) (xy 129.41554 -155.94076) (xy 129.41607 -155.895996)
			(xy 129.425012 -155.806917) (xy 129.442852 -155.719185) (xy 129.46941 -155.633687) (xy 129.486406 -155.592272)
			(xy 129.489964 -155.582682) (xy 129.489949 -155.562245) (xy 129.486406 -155.552648) (xy 129.471432 -155.516312)
			(xy 129.447188 -155.441549) (xy 129.429633 -155.364938) (xy 129.418904 -155.287078) (xy 129.416556 -155.247848)
			(xy 129.415794 -155.233878) (xy 129.400046 -155.210256) (xy 129.292604 -155.160472) (xy 129.264664 -155.16352)
			(xy 129.253234 -155.172156) (xy 129.22 -155.19695) (xy 129.149714 -155.240949) (xy 129.07564 -155.278222)
			(xy 128.998422 -155.308446) (xy 128.918728 -155.331358) (xy 128.837249 -155.346761) (xy 128.754691 -155.354521)
			(xy 128.71323 -155.355036) (xy 128.672115 -155.354577) (xy 128.590235 -155.346992) (xy 128.509404 -155.331884)
			(xy 128.430311 -155.309383) (xy 128.353633 -155.279679) (xy 128.280023 -155.243027) (xy 128.210108 -155.199739)
			(xy 128.144486 -155.150184) (xy 128.083717 -155.094786) (xy 128.028318 -155.034017) (xy 127.978764 -154.968395)
			(xy 127.935475 -154.898481) (xy 127.898823 -154.824871) (xy 127.869119 -154.748192) (xy 127.846617 -154.6691)
			(xy 127.831508 -154.588269) (xy 127.823923 -154.506389) (xy 127.823468 -154.465274) (xy 127.824021 -154.420503)
			(xy 127.833015 -154.331415) (xy 127.850921 -154.243682) (xy 127.877557 -154.158194) (xy 127.894588 -154.116786)
			(xy 127.89815 -154.107196) (xy 127.89814 -154.086757) (xy 127.894588 -154.077162) (xy 127.877564 -154.035751)
			(xy 127.850943 -153.95026) (xy 127.833035 -153.862529) (xy 127.824022 -153.773444) (xy 127.823468 -153.728674)
			(xy 127.824021 -153.683903) (xy 127.833015 -153.594815) (xy 127.850921 -153.507082) (xy 127.877557 -153.421594)
			(xy 127.894588 -153.380186) (xy 127.89815 -153.370596) (xy 127.89814 -153.350157) (xy 127.894588 -153.340562)
			(xy 127.880819 -153.307252) (xy 127.85808 -153.238849) (xy 127.840951 -153.16883) (xy 127.834898 -153.133298)
			(xy 127.83185 -153.114756) (xy 127.803656 -153.090626) (xy 120.270524 -153.090626) (xy 120.26177 -153.091008)
			(xy 120.245285 -153.096913) (xy 120.231718 -153.107985) (xy 120.226836 -153.115264) (xy 120.204981 -153.150744)
			(xy 120.15561 -153.217881) (xy 120.100174 -153.280104) (xy 120.03916 -153.336869) (xy 119.973104 -153.387677)
			(xy 119.902584 -153.432083) (xy 119.82822 -153.469697) (xy 119.750663 -153.500189) (xy 119.670593 -153.523293)
			(xy 119.588714 -153.538805) (xy 119.505742 -153.546589) (xy 119.464074 -153.547064) (xy 119.425791 -153.546661)
			(xy 119.349506 -153.540103) (xy 119.274066 -153.527021) (xy 119.200027 -153.50751) (xy 119.163846 -153.494994)
			(xy 119.155409 -153.492343) (xy 119.137739 -153.492343) (xy 119.129302 -153.494994) (xy 119.093126 -153.507531)
			(xy 119.01909 -153.527063) (xy 118.943648 -153.54015) (xy 118.867359 -153.546695) (xy 118.829074 -153.547064)
			(xy 118.790791 -153.546661) (xy 118.714506 -153.540103) (xy 118.639066 -153.527021) (xy 118.565027 -153.50751)
			(xy 118.528846 -153.494994) (xy 118.520409 -153.492343) (xy 118.502739 -153.492343) (xy 118.494302 -153.494994)
			(xy 118.458126 -153.507531) (xy 118.38409 -153.527063) (xy 118.308648 -153.54015) (xy 118.232359 -153.546695)
			(xy 118.194074 -153.547064) (xy 118.155791 -153.546661) (xy 118.079506 -153.540103) (xy 118.004066 -153.527021)
			(xy 117.930027 -153.50751) (xy 117.893846 -153.494994) (xy 117.885409 -153.492343) (xy 117.867739 -153.492343)
			(xy 117.859302 -153.494994) (xy 117.823126 -153.507531) (xy 117.74909 -153.527063) (xy 117.673648 -153.54015)
			(xy 117.597359 -153.546695) (xy 117.559074 -153.547064) (xy 117.518861 -153.546626) (xy 117.438762 -153.539389)
			(xy 117.359641 -153.524958) (xy 117.282145 -153.50345) (xy 117.244368 -153.48966) (xy 117.235581 -153.486753)
			(xy 117.217087 -153.486753) (xy 117.2083 -153.48966) (xy 117.170525 -153.503458) (xy 117.093031 -153.52498)
			(xy 117.01391 -153.539411) (xy 116.933808 -153.546633) (xy 116.893594 -153.547064) (xy 116.855311 -153.546662)
			(xy 116.779026 -153.540106) (xy 116.703585 -153.527025) (xy 116.629546 -153.507516) (xy 116.593366 -153.494994)
			(xy 116.584929 -153.492343) (xy 116.567259 -153.492343) (xy 116.558822 -153.494994) (xy 116.522646 -153.507528)
			(xy 116.448609 -153.527053) (xy 116.373167 -153.540133) (xy 116.296878 -153.546671) (xy 116.258594 -153.547064)
			(xy 116.216927 -153.546577) (xy 116.133958 -153.538784) (xy 116.052081 -153.523266) (xy 115.972014 -153.500158)
			(xy 115.894459 -153.469665) (xy 115.820096 -153.432053) (xy 115.749575 -153.387651) (xy 115.683516 -153.33685)
			(xy 115.622497 -153.280093) (xy 115.567053 -153.217879) (xy 115.517671 -153.150753) (xy 115.495832 -153.115264)
			(xy 115.49102 -153.107923) (xy 115.477453 -153.096807) (xy 115.460916 -153.090963) (xy 115.452144 -153.090626)
			(xy 104.358948 -153.090626) (xy 104.348883 -153.091059) (xy 104.330294 -153.09879) (xy 104.32288 -153.105612)
			(xy 95.053404 -162.375088) (xy 95.035363 -162.392347) (xy 94.993869 -162.420101) (xy 94.947751 -162.43921)
			(xy 94.898787 -162.448934) (xy 94.873826 -162.44951) (xy 91.193112 -162.44951) (xy 91.18136 -162.450113)
			(xy 91.160316 -162.460582) (xy 91.152726 -162.469576) (xy 91.096592 -162.543998) (xy 91.09202 -162.567366)
			(xy 91.095576 -162.57905) (xy 91.106407 -162.618733) (xy 91.121551 -162.699592) (xy 91.129153 -162.781504)
			(xy 91.129612 -162.822636) (xy 91.129175 -162.860924) (xy 91.122548 -162.937213) (xy 91.109399 -163.012652)
			(xy 91.089824 -163.086684) (xy 91.077288 -163.122864) (xy 91.076093 -163.126674) (xy 119.365268 -163.126674)
			(xy 119.365838 -163.081905) (xy 119.374847 -162.99282) (xy 119.392749 -162.905089) (xy 119.419366 -162.819597)
			(xy 119.436388 -162.778186) (xy 119.43997 -162.7686) (xy 119.43996 -162.748153) (xy 119.436388 -162.738562)
			(xy 119.41934 -162.69716) (xy 119.392709 -162.61167) (xy 119.374808 -162.523935) (xy 119.365818 -162.434845)
			(xy 119.365268 -162.390074) (xy 119.365838 -162.345305) (xy 119.374847 -162.25622) (xy 119.392749 -162.168489)
			(xy 119.419366 -162.082997) (xy 119.436388 -162.041586) (xy 119.43997 -162.032) (xy 119.43996 -162.011553)
			(xy 119.436388 -162.001962) (xy 119.41934 -161.96056) (xy 119.392709 -161.87507) (xy 119.374808 -161.787335)
			(xy 119.365818 -161.698245) (xy 119.365268 -161.653474) (xy 119.365674 -161.612358) (xy 119.373264 -161.530476)
			(xy 119.388376 -161.449645) (xy 119.410882 -161.370552) (xy 119.440591 -161.293873) (xy 119.477247 -161.220263)
			(xy 119.520539 -161.150349) (xy 119.570097 -161.084728) (xy 119.625499 -161.023959) (xy 119.686271 -160.968561)
			(xy 119.751895 -160.919007) (xy 119.821812 -160.87572) (xy 119.895425 -160.839068) (xy 119.972105 -160.809365)
			(xy 120.051199 -160.786863) (xy 120.132032 -160.771756) (xy 120.213914 -160.764171) (xy 120.25503 -160.763712)
			(xy 120.296646 -160.764225) (xy 120.379509 -160.772042) (xy 120.461282 -160.787558) (xy 120.54125 -160.810638)
			(xy 120.618714 -160.84108) (xy 120.693 -160.878619) (xy 120.728486 -160.900364) (xy 120.737599 -160.905467)
			(xy 120.758243 -160.908514) (xy 120.778407 -160.903135) (xy 120.786906 -160.897062) (xy 120.820569 -160.871087)
			(xy 120.891995 -160.824949) (xy 120.967499 -160.785839) (xy 121.046391 -160.754113) (xy 121.127951 -160.730062)
			(xy 121.211434 -160.713905) (xy 121.296078 -160.705788) (xy 121.338594 -160.705292) (xy 121.379707 -160.705819)
			(xy 121.461582 -160.713405) (xy 121.542407 -160.728513) (xy 121.621494 -160.751013) (xy 121.698168 -160.780715)
			(xy 121.771774 -160.817365) (xy 121.841684 -160.86065) (xy 121.907303 -160.9102) (xy 121.96807 -160.965593)
			(xy 122.023467 -161.026357) (xy 122.073021 -161.091973) (xy 122.11631 -161.161881) (xy 122.152964 -161.235485)
			(xy 122.18267 -161.312156) (xy 122.205176 -161.391242) (xy 122.220288 -161.472067) (xy 122.227879 -161.553941)
			(xy 122.228356 -161.595054) (xy 122.227793 -161.639824) (xy 122.218783 -161.728909) (xy 122.200877 -161.81664)
			(xy 122.174259 -161.902131) (xy 122.157236 -161.943542) (xy 122.153699 -161.953141) (xy 122.153682 -161.973576)
			(xy 122.157236 -161.983166) (xy 122.173031 -162.021471) (xy 122.198241 -162.100407) (xy 122.215997 -162.181345)
			(xy 122.226146 -162.263585) (xy 122.227848 -162.304984) (xy 122.228707 -162.315902) (xy 122.238347 -162.335541)
			(xy 122.255257 -162.349422) (xy 122.265694 -162.352736) (xy 122.282566 -162.357234) (xy 122.315977 -162.367397)
			(xy 122.332496 -162.373056) (xy 122.340692 -162.375579) (xy 122.357828 -162.375579) (xy 122.366024 -162.373056)
			(xy 122.40124 -162.361095) (xy 122.473244 -162.342441) (xy 122.546565 -162.329932) (xy 122.62068 -162.323659)
			(xy 122.65787 -162.323272) (xy 122.695059 -162.323671) (xy 122.769172 -162.329958) (xy 122.842492 -162.342465)
			(xy 122.914498 -162.361103) (xy 122.949716 -162.373056) (xy 122.957912 -162.375579) (xy 122.975048 -162.375579)
			(xy 122.983244 -162.373056) (xy 123.018459 -162.361089) (xy 123.090462 -162.342437) (xy 123.163784 -162.32993)
			(xy 123.2379 -162.323658) (xy 123.27509 -162.323272) (xy 123.31703 -162.323667) (xy 123.400532 -162.331639)
			(xy 123.482897 -162.347513) (xy 123.56338 -162.371144) (xy 123.641253 -162.402319) (xy 123.71581 -162.440755)
			(xy 123.786375 -162.486104) (xy 123.85231 -162.537955) (xy 123.913018 -162.595839) (xy 123.967949 -162.659232)
			(xy 124.016605 -162.727559) (xy 124.058546 -162.800202) (xy 124.093391 -162.876503) (xy 124.120826 -162.95577)
			(xy 124.140602 -163.037287) (xy 124.15254 -163.120314) (xy 124.156531 -163.2041) (xy 124.15254 -163.287886)
			(xy 124.140602 -163.370913) (xy 124.120826 -163.45243) (xy 124.093391 -163.531697) (xy 124.058546 -163.607998)
			(xy 124.016605 -163.680641) (xy 123.967949 -163.748968) (xy 123.913018 -163.812361) (xy 123.85231 -163.870245)
			(xy 123.786375 -163.922096) (xy 123.71581 -163.967445) (xy 123.641253 -164.005881) (xy 123.56338 -164.037056)
			(xy 123.482897 -164.060687) (xy 123.400532 -164.076561) (xy 123.31703 -164.084533) (xy 123.27509 -164.085016)
			(xy 123.2379 -164.084629) (xy 123.163787 -164.078339) (xy 123.090468 -164.065828) (xy 123.018462 -164.047187)
			(xy 122.983244 -164.035232) (xy 122.975048 -164.032709) (xy 122.957912 -164.032709) (xy 122.949716 -164.035232)
			(xy 122.907233 -164.049509) (xy 122.820068 -164.070379) (xy 122.775726 -164.076888) (xy 122.765804 -164.078672)
			(xy 122.748385 -164.088778) (xy 122.736231 -164.104835) (xy 122.733308 -164.11448) (xy 122.724748 -164.14638)
			(xy 122.70352 -164.20893) (xy 122.69089 -164.239448) (xy 122.687347 -164.249045) (xy 122.687332 -164.269482)
			(xy 122.69089 -164.279072) (xy 122.707886 -164.320487) (xy 122.734444 -164.405985) (xy 122.752283 -164.493717)
			(xy 122.761225 -164.582796) (xy 122.761756 -164.62756) (xy 122.761252 -164.669908) (xy 122.753201 -164.754222)
			(xy 122.737172 -164.837388) (xy 122.713311 -164.918655) (xy 122.681832 -164.997285) (xy 122.643021 -165.072566)
			(xy 122.597231 -165.143818) (xy 122.544875 -165.210394) (xy 122.486427 -165.271692) (xy 122.422417 -165.327157)
			(xy 122.353425 -165.376286) (xy 122.280075 -165.418635) (xy 122.203032 -165.453819) (xy 122.122993 -165.481521)
			(xy 122.040684 -165.501489) (xy 121.956849 -165.513542) (xy 121.872248 -165.517573) (xy 121.787647 -165.513542)
			(xy 121.703812 -165.501489) (xy 121.621503 -165.481521) (xy 121.541464 -165.453819) (xy 121.464421 -165.418635)
			(xy 121.391071 -165.376286) (xy 121.322079 -165.327157) (xy 121.258069 -165.271692) (xy 121.199621 -165.210394)
			(xy 121.147265 -165.143818) (xy 121.101475 -165.072566) (xy 121.062664 -164.997285) (xy 121.031185 -164.918655)
			(xy 121.007324 -164.837388) (xy 120.991295 -164.754222) (xy 120.983244 -164.669908) (xy 120.98274 -164.62756)
			(xy 120.983256 -164.582795) (xy 120.992189 -164.493713) (xy 121.010032 -164.40598) (xy 121.036603 -164.320485)
			(xy 121.053606 -164.279072) (xy 121.057195 -164.269488) (xy 121.057181 -164.249039) (xy 121.053606 -164.239448)
			(xy 121.036797 -164.198471) (xy 121.010427 -164.113914) (xy 120.992588 -164.027156) (xy 120.983456 -163.939054)
			(xy 120.98274 -163.89477) (xy 120.982486 -163.880038) (xy 120.966992 -163.8554) (xy 120.857264 -163.803584)
			(xy 120.828308 -163.80714) (xy 120.816878 -163.816538) (xy 120.782853 -163.843559) (xy 120.710459 -163.891613)
			(xy 120.633724 -163.93238) (xy 120.55338 -163.965469) (xy 120.470192 -163.990568) (xy 120.384953 -164.007435)
			(xy 120.298476 -164.01591) (xy 120.25503 -164.016436) (xy 120.213915 -164.015973) (xy 120.132035 -164.008388)
			(xy 120.051204 -163.99328) (xy 119.972113 -163.970779) (xy 119.895435 -163.941075) (xy 119.821825 -163.904423)
			(xy 119.751911 -163.861135) (xy 119.686289 -163.811581) (xy 119.62552 -163.756183) (xy 119.570122 -163.695414)
			(xy 119.520567 -163.629793) (xy 119.477279 -163.559879) (xy 119.440626 -163.486269) (xy 119.410922 -163.409591)
			(xy 119.38842 -163.330499) (xy 119.373312 -163.249669) (xy 119.365727 -163.167789) (xy 119.365268 -163.126674)
			(xy 91.076093 -163.126674) (xy 91.074642 -163.1313) (xy 91.074654 -163.148967) (xy 91.077288 -163.157408)
			(xy 91.089855 -163.193579) (xy 91.109446 -163.26761) (xy 91.122593 -163.343052) (xy 91.129198 -163.419346)
			(xy 91.129612 -163.457636) (xy 91.12909 -163.500411) (xy 91.120858 -163.585564) (xy 91.104502 -163.669536)
			(xy 91.080173 -163.751554) (xy 91.064588 -163.791392) (xy 91.061593 -163.799863) (xy 91.061076 -163.817812)
			(xy 91.063572 -163.826444) (xy 91.078073 -163.87193) (xy 91.098402 -163.965215) (xy 91.108643 -164.060139)
			(xy 91.109292 -164.107876) (xy 91.108833 -164.148987) (xy 91.101247 -164.230859) (xy 91.086137 -164.31168)
			(xy 91.063634 -164.390763) (xy 91.033928 -164.467431) (xy 90.997273 -164.541031) (xy 90.953982 -164.610934)
			(xy 90.904425 -164.676543) (xy 90.849025 -164.737299) (xy 90.788254 -164.792683) (xy 90.722631 -164.842222)
			(xy 90.652716 -164.885493) (xy 90.579106 -164.922127) (xy 90.50243 -164.951812) (xy 90.423341 -164.974294)
			(xy 90.342515 -164.989381) (xy 90.260641 -164.996944) (xy 90.21953 -164.997384) (xy 90.177919 -164.996915)
			(xy 90.09506 -164.989168) (xy 90.013287 -164.97371) (xy 89.933317 -164.950678) (xy 89.89441 -164.935916)
			(xy 89.885722 -164.932924) (xy 89.867362 -164.932655) (xy 89.858596 -164.935408) (xy 89.822502 -164.947871)
			(xy 89.748649 -164.967302) (xy 89.673401 -164.980325) (xy 89.597313 -164.986844) (xy 89.55913 -164.987224)
			(xy 89.520847 -164.986819) (xy 89.444563 -164.980258) (xy 89.369124 -164.967173) (xy 89.295087 -164.94766)
			(xy 89.258902 -164.935154) (xy 89.250465 -164.932503) (xy 89.232795 -164.932503) (xy 89.224358 -164.935154)
			(xy 89.188182 -164.94769) (xy 89.114146 -164.967219) (xy 89.038703 -164.980303) (xy 88.962415 -164.986844)
			(xy 88.92413 -164.987224) (xy 88.885847 -164.986819) (xy 88.809563 -164.980258) (xy 88.734124 -164.967173)
			(xy 88.660087 -164.94766) (xy 88.623902 -164.935154) (xy 88.615465 -164.932503) (xy 88.597795 -164.932503)
			(xy 88.589358 -164.935154) (xy 88.553182 -164.94769) (xy 88.479146 -164.967219) (xy 88.403703 -164.980303)
			(xy 88.327415 -164.986844) (xy 88.28913 -164.987224) (xy 88.250847 -164.986819) (xy 88.174563 -164.980258)
			(xy 88.099124 -164.967173) (xy 88.025087 -164.94766) (xy 87.988902 -164.935154) (xy 87.980465 -164.932503)
			(xy 87.962795 -164.932503) (xy 87.954358 -164.935154) (xy 87.918182 -164.94769) (xy 87.844146 -164.967219)
			(xy 87.768703 -164.980303) (xy 87.692415 -164.986844) (xy 87.65413 -164.987224) (xy 87.615847 -164.986819)
			(xy 87.539563 -164.980258) (xy 87.464124 -164.967173) (xy 87.390087 -164.94766) (xy 87.353902 -164.935154)
			(xy 87.345465 -164.932503) (xy 87.327795 -164.932503) (xy 87.319358 -164.935154) (xy 87.283182 -164.94769)
			(xy 87.209146 -164.967219) (xy 87.133703 -164.980303) (xy 87.057415 -164.986844) (xy 87.01913 -164.987224)
			(xy 86.978023 -164.986751) (xy 86.896159 -164.979169) (xy 86.815344 -164.964067) (xy 86.736267 -164.941573)
			(xy 86.659602 -164.911881) (xy 86.586004 -164.875242) (xy 86.5161 -164.831969) (xy 86.450485 -164.782432)
			(xy 86.389721 -164.727053) (xy 86.334325 -164.666304) (xy 86.28477 -164.600703) (xy 86.241478 -164.530811)
			(xy 86.204819 -164.457223) (xy 86.175105 -164.380566) (xy 86.15259 -164.301495) (xy 86.137465 -164.220684)
			(xy 86.129861 -164.138823) (xy 86.129368 -164.097716) (xy 86.129892 -164.054942) (xy 86.138129 -163.96979)
			(xy 86.154491 -163.88582) (xy 86.178826 -163.803805) (xy 86.194392 -163.76396) (xy 86.197397 -163.755489)
			(xy 86.197931 -163.737534) (xy 86.195408 -163.728908) (xy 86.180904 -163.683423) (xy 86.160567 -163.590138)
			(xy 86.15032 -163.495214) (xy 86.149688 -163.447476) (xy 86.150124 -163.409188) (xy 86.15675 -163.332899)
			(xy 86.169899 -163.25746) (xy 86.189473 -163.183427) (xy 86.202012 -163.147248) (xy 86.20466 -163.138812)
			(xy 86.204652 -163.121143) (xy 86.202012 -163.112704) (xy 86.189445 -163.076533) (xy 86.169852 -163.002502)
			(xy 86.156704 -162.92706) (xy 86.150098 -162.850766) (xy 86.149688 -162.812476) (xy 86.15012 -162.772885)
			(xy 86.157152 -162.694016) (xy 86.171157 -162.616082) (xy 86.181184 -162.57778) (xy 86.184486 -162.56635)
			(xy 86.179914 -162.543236) (xy 86.12378 -162.469576) (xy 86.116189 -162.460584) (xy 86.095145 -162.450113)
			(xy 86.083394 -162.44951) (xy 60.743592 -162.44951) (xy 60.733523 -162.449935) (xy 60.714921 -162.457652)
			(xy 60.707524 -162.464496) (xy 60.395866 -162.776154) (xy 60.389021 -162.783552) (xy 60.381296 -162.802151)
			(xy 60.38088 -162.812222) (xy 60.38088 -166.86276) (xy 61.046868 -166.86276) (xy 61.047433 -166.81799)
			(xy 61.056443 -166.728905) (xy 61.074347 -166.641174) (xy 61.100966 -166.555683) (xy 61.117988 -166.514272)
			(xy 61.121578 -166.504688) (xy 61.121563 -166.484239) (xy 61.117988 -166.474648) (xy 61.100968 -166.433235)
			(xy 61.074329 -166.347749) (xy 61.05642 -166.260018) (xy 61.047422 -166.17093) (xy 61.046868 -166.12616)
			(xy 61.047433 -166.08139) (xy 61.056443 -165.992305) (xy 61.074347 -165.904574) (xy 61.100966 -165.819083)
			(xy 61.117988 -165.777672) (xy 61.121578 -165.768088) (xy 61.121563 -165.747639) (xy 61.117988 -165.738048)
			(xy 61.100968 -165.696635) (xy 61.074329 -165.611149) (xy 61.05642 -165.523418) (xy 61.047422 -165.43433)
			(xy 61.046868 -165.38956) (xy 61.047314 -165.348449) (xy 61.054905 -165.266579) (xy 61.070019 -165.185759)
			(xy 61.092527 -165.106679) (xy 61.122236 -165.030013) (xy 61.158893 -164.956415) (xy 61.202185 -164.886514)
			(xy 61.251743 -164.820907) (xy 61.307144 -164.760153) (xy 61.367915 -164.70477) (xy 61.433537 -164.655232)
			(xy 61.503451 -164.611961) (xy 61.57706 -164.575327) (xy 61.653735 -164.545641) (xy 61.732822 -164.523157)
			(xy 61.813647 -164.508068) (xy 61.895519 -164.500502) (xy 61.93663 -164.500052) (xy 61.978242 -164.500538)
			(xy 62.061103 -164.508284) (xy 62.142878 -164.523742) (xy 62.222849 -164.546778) (xy 62.300317 -164.57719)
			(xy 62.374602 -164.61471) (xy 62.410086 -164.63645) (xy 62.419198 -164.641555) (xy 62.439843 -164.644603)
			(xy 62.460007 -164.639223) (xy 62.468506 -164.633148) (xy 62.502177 -164.607195) (xy 62.573617 -164.561104)
			(xy 62.649129 -164.522038) (xy 62.728022 -164.490352) (xy 62.809578 -164.466336) (xy 62.893052 -164.450209)
			(xy 62.977685 -164.442118) (xy 63.020194 -164.441632) (xy 63.0613 -164.442118) (xy 63.143163 -164.449702)
			(xy 63.223977 -164.464805) (xy 63.303052 -164.487299) (xy 63.379716 -164.516993) (xy 63.453313 -164.553631)
			(xy 63.523217 -164.596903) (xy 63.58883 -164.64644) (xy 63.649594 -164.701818) (xy 63.70499 -164.762565)
			(xy 63.754546 -164.828164) (xy 63.797839 -164.898054) (xy 63.8345 -164.971641) (xy 63.864216 -165.048295)
			(xy 63.886734 -165.127364) (xy 63.901861 -165.208173) (xy 63.909469 -165.290034) (xy 63.909956 -165.33114)
			(xy 63.909389 -165.375909) (xy 63.900379 -165.464994) (xy 63.882475 -165.552725) (xy 63.855858 -165.638217)
			(xy 63.838836 -165.679628) (xy 63.83525 -165.689212) (xy 63.835264 -165.709661) (xy 63.838836 -165.719252)
			(xy 63.854627 -165.757559) (xy 63.879838 -165.836494) (xy 63.897595 -165.917432) (xy 63.903105 -165.962076)
			(xy 81.591411 -165.962076) (xy 81.595416 -165.856327) (xy 81.607406 -165.751184) (xy 81.627315 -165.647249)
			(xy 81.655026 -165.545117) (xy 81.690383 -165.445373) (xy 81.733181 -165.348589) (xy 81.783177 -165.255319)
			(xy 81.840084 -165.166098) (xy 81.903575 -165.081435) (xy 81.973287 -165.001817) (xy 82.048821 -164.927699)
			(xy 82.129744 -164.859506) (xy 82.215593 -164.797628) (xy 82.305876 -164.742421) (xy 82.400075 -164.694199)
			(xy 82.497652 -164.653239) (xy 82.598047 -164.619777) (xy 82.700685 -164.594003) (xy 82.804978 -164.576065)
			(xy 82.910329 -164.566066) (xy 83.016135 -164.564063) (xy 83.121789 -164.570068) (xy 83.226686 -164.584047)
			(xy 83.330226 -164.605918) (xy 83.431815 -164.635558) (xy 83.530872 -164.672796) (xy 83.626829 -164.717418)
			(xy 83.719136 -164.76917) (xy 83.807265 -164.827755) (xy 83.890711 -164.892837) (xy 83.968995 -164.964043)
			(xy 84.04167 -165.040966) (xy 84.10832 -165.123166) (xy 84.168562 -165.21017) (xy 84.222051 -165.301481)
			(xy 84.268482 -165.396576) (xy 84.307587 -165.49491) (xy 84.339144 -165.595921) (xy 84.362971 -165.699028)
			(xy 84.378932 -165.803642) (xy 84.386936 -165.909164) (xy 84.387436 -165.962076) (xy 90.989411 -165.962076)
			(xy 90.993416 -165.856327) (xy 91.005406 -165.751184) (xy 91.025315 -165.647249) (xy 91.053026 -165.545117)
			(xy 91.088383 -165.445373) (xy 91.131181 -165.348589) (xy 91.181177 -165.255319) (xy 91.238084 -165.166098)
			(xy 91.301575 -165.081435) (xy 91.371287 -165.001817) (xy 91.446821 -164.927699) (xy 91.527744 -164.859506)
			(xy 91.613593 -164.797628) (xy 91.703876 -164.742421) (xy 91.798075 -164.694199) (xy 91.895652 -164.653239)
			(xy 91.996047 -164.619777) (xy 92.098685 -164.594003) (xy 92.202978 -164.576065) (xy 92.308329 -164.566066)
			(xy 92.414135 -164.564063) (xy 92.519789 -164.570068) (xy 92.624686 -164.584047) (xy 92.728226 -164.605918)
			(xy 92.829815 -164.635558) (xy 92.928872 -164.672796) (xy 93.024829 -164.717418) (xy 93.117136 -164.76917)
			(xy 93.205265 -164.827755) (xy 93.288711 -164.892837) (xy 93.366995 -164.964043) (xy 93.43967 -165.040966)
			(xy 93.50632 -165.123166) (xy 93.566562 -165.21017) (xy 93.620051 -165.301481) (xy 93.666482 -165.396576)
			(xy 93.705587 -165.49491) (xy 93.737144 -165.595921) (xy 93.760971 -165.699028) (xy 93.776932 -165.803642)
			(xy 93.784936 -165.909164) (xy 93.785436 -165.962076) (xy 93.784936 -166.014988) (xy 93.776932 -166.12051)
			(xy 93.760971 -166.225124) (xy 93.737144 -166.328231) (xy 93.705587 -166.429242) (xy 93.666482 -166.527576)
			(xy 93.620051 -166.622671) (xy 93.566562 -166.713982) (xy 93.50632 -166.800986) (xy 93.43967 -166.883186)
			(xy 93.366995 -166.960109) (xy 93.288711 -167.031315) (xy 93.205265 -167.096397) (xy 93.117136 -167.154982)
			(xy 93.024829 -167.206734) (xy 92.928872 -167.251356) (xy 92.829815 -167.288594) (xy 92.728226 -167.318234)
			(xy 92.624686 -167.340105) (xy 92.519789 -167.354084) (xy 92.414135 -167.360089) (xy 92.308329 -167.358086)
			(xy 92.202978 -167.348087) (xy 92.098685 -167.330149) (xy 91.996047 -167.304375) (xy 91.895652 -167.270913)
			(xy 91.798075 -167.229953) (xy 91.703876 -167.181731) (xy 91.613593 -167.126524) (xy 91.527744 -167.064646)
			(xy 91.446821 -166.996453) (xy 91.371287 -166.922335) (xy 91.301575 -166.842717) (xy 91.238084 -166.758054)
			(xy 91.181177 -166.668833) (xy 91.131181 -166.575563) (xy 91.088383 -166.478779) (xy 91.053026 -166.379035)
			(xy 91.025315 -166.276903) (xy 91.005406 -166.172968) (xy 90.993416 -166.067825) (xy 90.989411 -165.962076)
			(xy 84.387436 -165.962076) (xy 84.386936 -166.014988) (xy 84.378932 -166.12051) (xy 84.362971 -166.225124)
			(xy 84.339144 -166.328231) (xy 84.307587 -166.429242) (xy 84.268482 -166.527576) (xy 84.222051 -166.622671)
			(xy 84.168562 -166.713982) (xy 84.10832 -166.800986) (xy 84.04167 -166.883186) (xy 83.968995 -166.960109)
			(xy 83.890711 -167.031315) (xy 83.807265 -167.096397) (xy 83.719136 -167.154982) (xy 83.626829 -167.206734)
			(xy 83.530872 -167.251356) (xy 83.431815 -167.288594) (xy 83.330226 -167.318234) (xy 83.226686 -167.340105)
			(xy 83.121789 -167.354084) (xy 83.016135 -167.360089) (xy 82.910329 -167.358086) (xy 82.804978 -167.348087)
			(xy 82.700685 -167.330149) (xy 82.598047 -167.304375) (xy 82.497652 -167.270913) (xy 82.400075 -167.229953)
			(xy 82.305876 -167.181731) (xy 82.215593 -167.126524) (xy 82.129744 -167.064646) (xy 82.048821 -166.996453)
			(xy 81.973287 -166.922335) (xy 81.903575 -166.842717) (xy 81.840084 -166.758054) (xy 81.783177 -166.668833)
			(xy 81.733181 -166.575563) (xy 81.690383 -166.478779) (xy 81.655026 -166.379035) (xy 81.627315 -166.276903)
			(xy 81.607406 -166.172968) (xy 81.595416 -166.067825) (xy 81.591411 -165.962076) (xy 63.903105 -165.962076)
			(xy 63.907745 -165.999671) (xy 63.909448 -166.04107) (xy 63.910317 -166.051987) (xy 63.919952 -166.071626)
			(xy 63.936858 -166.085508) (xy 63.947294 -166.088822) (xy 63.964166 -166.09332) (xy 63.997577 -166.103483)
			(xy 64.014096 -166.109142) (xy 64.022292 -166.111665) (xy 64.039428 -166.111665) (xy 64.047624 -166.109142)
			(xy 64.082842 -166.097202) (xy 64.154852 -166.078613) (xy 64.228174 -166.066171) (xy 64.302285 -166.059965)
			(xy 64.33947 -166.059612) (xy 64.376654 -166.059989) (xy 64.450761 -166.066209) (xy 64.524081 -166.078649)
			(xy 64.596093 -166.097221) (xy 64.631316 -166.109142) (xy 64.639512 -166.111665) (xy 64.656648 -166.111665)
			(xy 64.664844 -166.109142) (xy 64.70006 -166.097196) (xy 64.772071 -166.078609) (xy 64.845393 -166.066169)
			(xy 64.919504 -166.059964) (xy 64.95669 -166.059612) (xy 64.998618 -166.060035) (xy 65.082094 -166.068005)
			(xy 65.164434 -166.083874) (xy 65.244893 -166.107498) (xy 65.322742 -166.138663) (xy 65.397276 -166.177087)
			(xy 65.46782 -166.222422) (xy 65.533735 -166.274258) (xy 65.594424 -166.332124) (xy 65.649338 -166.395498)
			(xy 65.69798 -166.463804) (xy 65.739908 -166.536425) (xy 65.774743 -166.612703) (xy 65.802169 -166.691946)
			(xy 65.821939 -166.773438) (xy 65.833873 -166.85644) (xy 65.837863 -166.9402) (xy 65.833873 -167.02396)
			(xy 65.821939 -167.106962) (xy 65.802169 -167.188454) (xy 65.774743 -167.267697) (xy 65.739908 -167.343975)
			(xy 65.69798 -167.416596) (xy 65.649338 -167.484902) (xy 65.594424 -167.548276) (xy 65.533735 -167.606142)
			(xy 65.46782 -167.657978) (xy 65.397276 -167.703313) (xy 65.322742 -167.741737) (xy 65.244893 -167.772902)
			(xy 65.164434 -167.796526) (xy 65.082094 -167.812395) (xy 64.998618 -167.820365) (xy 64.95669 -167.820848)
			(xy 64.919506 -167.820485) (xy 64.845398 -167.814262) (xy 64.772078 -167.801817) (xy 64.700067 -167.783241)
			(xy 64.664844 -167.771318) (xy 64.656648 -167.768795) (xy 64.639512 -167.768795) (xy 64.631316 -167.771318)
			(xy 64.597889 -167.782662) (xy 64.529607 -167.80059) (xy 64.494918 -167.807132) (xy 64.484907 -167.809437)
			(xy 64.467748 -167.820693) (xy 64.456372 -167.837772) (xy 64.454024 -167.847772) (xy 64.44452 -167.895628)
			(xy 64.416383 -167.989057) (xy 64.39789 -168.034208) (xy 64.394312 -168.043795) (xy 64.39432 -168.064241)
			(xy 64.39789 -168.073832) (xy 64.414873 -168.115252) (xy 64.441434 -168.200748) (xy 64.459278 -168.288478)
			(xy 64.468224 -168.377557) (xy 64.468756 -168.42232) (xy 64.468252 -168.464668) (xy 64.460201 -168.548982)
			(xy 64.444172 -168.632148) (xy 64.420311 -168.713415) (xy 64.388832 -168.792045) (xy 64.350021 -168.867326)
			(xy 64.304231 -168.938578) (xy 64.251875 -169.005154) (xy 64.193427 -169.066452) (xy 64.129417 -169.121917)
			(xy 64.060425 -169.171046) (xy 63.987075 -169.213395) (xy 63.910032 -169.248579) (xy 63.829993 -169.276281)
			(xy 63.747684 -169.296249) (xy 63.663849 -169.308302) (xy 63.579248 -169.312333) (xy 63.494647 -169.308302)
			(xy 63.410812 -169.296249) (xy 63.328503 -169.276281) (xy 63.248464 -169.248579) (xy 63.171421 -169.213395)
			(xy 63.098071 -169.171046) (xy 63.029079 -169.121917) (xy 62.965069 -169.066452) (xy 62.906621 -169.005154)
			(xy 62.854265 -168.938578) (xy 62.808475 -168.867326) (xy 62.769664 -168.792045) (xy 62.738185 -168.713415)
			(xy 62.714324 -168.632148) (xy 62.698295 -168.548982) (xy 62.690244 -168.464668) (xy 62.68974 -168.42232)
			(xy 62.690277 -168.377556) (xy 62.699204 -168.288474) (xy 62.71704 -168.200741) (xy 62.743605 -168.115246)
			(xy 62.760606 -168.073832) (xy 62.764161 -168.064238) (xy 62.764168 -168.043798) (xy 62.760606 -168.034208)
			(xy 62.743603 -167.992795) (xy 62.717048 -167.907297) (xy 62.69921 -167.819564) (xy 62.69027 -167.730484)
			(xy 62.68974 -167.68572) (xy 62.689828 -167.668048) (xy 62.691224 -167.632732) (xy 62.692534 -167.615108)
			(xy 62.69355 -167.599614) (xy 62.678564 -167.57269) (xy 62.566296 -167.516556) (xy 62.535816 -167.52062)
			(xy 62.524132 -167.53078) (xy 62.493723 -167.556945) (xy 62.428954 -167.60429) (xy 62.360182 -167.645605)
			(xy 62.287967 -167.680556) (xy 62.212896 -167.708856) (xy 62.13558 -167.730277) (xy 62.056649 -167.744645)
			(xy 61.976744 -167.751841) (xy 61.93663 -167.752268) (xy 61.895524 -167.751759) (xy 61.813662 -167.744177)
			(xy 61.732849 -167.729076) (xy 61.653773 -167.706584) (xy 61.57711 -167.676893) (xy 61.503513 -167.640256)
			(xy 61.433609 -167.596985) (xy 61.367995 -167.547451) (xy 61.307231 -167.492074) (xy 61.251835 -167.431328)
			(xy 61.202279 -167.36573) (xy 61.158986 -167.295841) (xy 61.122325 -167.222256) (xy 61.092608 -167.145602)
			(xy 61.07009 -167.066534) (xy 61.054963 -166.985725) (xy 61.047355 -166.903866) (xy 61.046868 -166.86276)
			(xy 60.38088 -166.86276) (xy 60.38088 -169.857674) (xy 111.084868 -169.857674) (xy 111.085438 -169.812905)
			(xy 111.094447 -169.72382) (xy 111.112349 -169.636089) (xy 111.138966 -169.550597) (xy 111.155988 -169.509186)
			(xy 111.15957 -169.4996) (xy 111.15956 -169.479153) (xy 111.155988 -169.469562) (xy 111.13894 -169.42816)
			(xy 111.112309 -169.34267) (xy 111.094408 -169.254935) (xy 111.085418 -169.165845) (xy 111.084868 -169.121074)
			(xy 111.085438 -169.076305) (xy 111.094447 -168.98722) (xy 111.112349 -168.899489) (xy 111.138966 -168.813997)
			(xy 111.155988 -168.772586) (xy 111.15957 -168.763) (xy 111.15956 -168.742553) (xy 111.155988 -168.732962)
			(xy 111.13894 -168.69156) (xy 111.112309 -168.60607) (xy 111.094408 -168.518335) (xy 111.085418 -168.429245)
			(xy 111.084868 -168.384474) (xy 111.085274 -168.343358) (xy 111.092864 -168.261476) (xy 111.107976 -168.180645)
			(xy 111.130482 -168.101552) (xy 111.160191 -168.024873) (xy 111.196847 -167.951263) (xy 111.240139 -167.881349)
			(xy 111.289697 -167.815728) (xy 111.345099 -167.754959) (xy 111.405871 -167.699561) (xy 111.471495 -167.650007)
			(xy 111.541412 -167.60672) (xy 111.615025 -167.570068) (xy 111.691705 -167.540365) (xy 111.770799 -167.517863)
			(xy 111.851632 -167.502756) (xy 111.933514 -167.495171) (xy 111.97463 -167.494712) (xy 112.016246 -167.495225)
			(xy 112.099109 -167.503042) (xy 112.180882 -167.518558) (xy 112.26085 -167.541638) (xy 112.338314 -167.57208)
			(xy 112.4126 -167.609619) (xy 112.448086 -167.631364) (xy 112.457199 -167.636467) (xy 112.477843 -167.639514)
			(xy 112.498007 -167.634135) (xy 112.506506 -167.628062) (xy 112.540169 -167.602087) (xy 112.611595 -167.555949)
			(xy 112.687099 -167.516839) (xy 112.765991 -167.485113) (xy 112.847551 -167.461062) (xy 112.931034 -167.444905)
			(xy 113.015678 -167.436788) (xy 113.058194 -167.436292) (xy 113.099307 -167.436819) (xy 113.181182 -167.444405)
			(xy 113.262007 -167.459513) (xy 113.341094 -167.482013) (xy 113.417768 -167.511715) (xy 113.491374 -167.548365)
			(xy 113.561284 -167.59165) (xy 113.626903 -167.6412) (xy 113.68767 -167.696593) (xy 113.743067 -167.757357)
			(xy 113.792621 -167.822973) (xy 113.83591 -167.892881) (xy 113.872564 -167.966485) (xy 113.90227 -168.043156)
			(xy 113.924776 -168.122242) (xy 113.939888 -168.203067) (xy 113.947479 -168.284941) (xy 113.947956 -168.326054)
			(xy 113.947393 -168.370824) (xy 113.938383 -168.459909) (xy 113.920477 -168.54764) (xy 113.893859 -168.633131)
			(xy 113.876836 -168.674542) (xy 113.873299 -168.684141) (xy 113.873282 -168.704576) (xy 113.876836 -168.714166)
			(xy 113.892631 -168.752471) (xy 113.917841 -168.831407) (xy 113.935597 -168.912345) (xy 113.945746 -168.994585)
			(xy 113.947448 -169.035984) (xy 113.948307 -169.046902) (xy 113.957947 -169.066541) (xy 113.974857 -169.080422)
			(xy 113.985294 -169.083736) (xy 114.002166 -169.088234) (xy 114.035577 -169.098397) (xy 114.052096 -169.104056)
			(xy 114.060292 -169.106579) (xy 114.077428 -169.106579) (xy 114.085624 -169.104056) (xy 114.12084 -169.092095)
			(xy 114.192844 -169.073441) (xy 114.266165 -169.060932) (xy 114.34028 -169.054659) (xy 114.37747 -169.054272)
			(xy 114.414659 -169.054671) (xy 114.488772 -169.060958) (xy 114.562092 -169.073465) (xy 114.634098 -169.092103)
			(xy 114.669316 -169.104056) (xy 114.677512 -169.106579) (xy 114.694648 -169.106579) (xy 114.702844 -169.104056)
			(xy 114.738059 -169.092089) (xy 114.810062 -169.073437) (xy 114.883384 -169.06093) (xy 114.9575 -169.054658)
			(xy 114.99469 -169.054272) (xy 115.03663 -169.054667) (xy 115.120132 -169.062639) (xy 115.202497 -169.078513)
			(xy 115.28298 -169.102144) (xy 115.360853 -169.133319) (xy 115.43541 -169.171755) (xy 115.505975 -169.217104)
			(xy 115.57191 -169.268955) (xy 115.632618 -169.326839) (xy 115.687549 -169.390232) (xy 115.736205 -169.458559)
			(xy 115.778146 -169.531202) (xy 115.812991 -169.607503) (xy 115.840426 -169.68677) (xy 115.860202 -169.768287)
			(xy 115.87214 -169.851314) (xy 115.876131 -169.9351) (xy 115.87214 -170.018886) (xy 115.860202 -170.101913)
			(xy 115.840426 -170.18343) (xy 115.812991 -170.262697) (xy 115.778146 -170.338998) (xy 115.736205 -170.411641)
			(xy 115.687549 -170.479968) (xy 115.632618 -170.543361) (xy 115.57191 -170.601245) (xy 115.505975 -170.653096)
			(xy 115.43541 -170.698445) (xy 115.360853 -170.736881) (xy 115.28298 -170.768056) (xy 115.202497 -170.791687)
			(xy 115.120132 -170.807561) (xy 115.03663 -170.815533) (xy 114.99469 -170.816016) (xy 114.9575 -170.815629)
			(xy 114.883387 -170.809339) (xy 114.810068 -170.796828) (xy 114.738062 -170.778187) (xy 114.702844 -170.766232)
			(xy 114.694648 -170.763709) (xy 114.677512 -170.763709) (xy 114.669316 -170.766232) (xy 114.625188 -170.781068)
			(xy 114.534574 -170.80245) (xy 114.488468 -170.808904) (xy 114.478735 -170.810567) (xy 114.461516 -170.820188)
			(xy 114.449244 -170.83563) (xy 114.44605 -170.844972) (xy 114.43848 -170.870441) (xy 114.420685 -170.920512)
			(xy 114.41049 -170.945048) (xy 114.406947 -170.954645) (xy 114.406932 -170.975082) (xy 114.41049 -170.984672)
			(xy 114.427486 -171.026087) (xy 114.454044 -171.111585) (xy 114.471883 -171.199317) (xy 114.480825 -171.288396)
			(xy 114.481356 -171.33316) (xy 114.480852 -171.375508) (xy 114.472801 -171.459822) (xy 114.456772 -171.542988)
			(xy 114.432911 -171.624255) (xy 114.401432 -171.702885) (xy 114.362621 -171.778166) (xy 114.316831 -171.849418)
			(xy 114.264475 -171.915994) (xy 114.206027 -171.977292) (xy 114.142017 -172.032757) (xy 114.073025 -172.081886)
			(xy 113.999675 -172.124235) (xy 113.922632 -172.159419) (xy 113.842593 -172.187121) (xy 113.760284 -172.207089)
			(xy 113.676449 -172.219142) (xy 113.591848 -172.223173) (xy 113.507247 -172.219142) (xy 113.423412 -172.207089)
			(xy 113.341103 -172.187121) (xy 113.261064 -172.159419) (xy 113.184021 -172.124235) (xy 113.110671 -172.081886)
			(xy 113.041679 -172.032757) (xy 112.977669 -171.977292) (xy 112.919221 -171.915994) (xy 112.866865 -171.849418)
			(xy 112.821075 -171.778166) (xy 112.782264 -171.702885) (xy 112.750785 -171.624255) (xy 112.726924 -171.542988)
			(xy 112.710895 -171.459822) (xy 112.702844 -171.375508) (xy 112.70234 -171.33316) (xy 112.702856 -171.288395)
			(xy 112.711789 -171.199313) (xy 112.729632 -171.11158) (xy 112.756203 -171.026085) (xy 112.773206 -170.984672)
			(xy 112.776795 -170.975088) (xy 112.776781 -170.954639) (xy 112.773206 -170.945048) (xy 112.757425 -170.906703)
			(xy 112.7322 -170.827708) (xy 112.714437 -170.746708) (xy 112.704291 -170.664406) (xy 112.702594 -170.622976)
			(xy 112.702086 -170.608244) (xy 112.686084 -170.584114) (xy 112.576864 -170.53433) (xy 112.548162 -170.537886)
			(xy 112.536732 -170.54703) (xy 112.50272 -170.574115) (xy 112.430302 -170.622243) (xy 112.353537 -170.663082)
			(xy 112.273156 -170.696243) (xy 112.189925 -170.72141) (xy 112.104638 -170.738343) (xy 112.018106 -170.746881)
			(xy 111.97463 -170.747436) (xy 111.933515 -170.746973) (xy 111.851635 -170.739388) (xy 111.770804 -170.72428)
			(xy 111.691713 -170.701779) (xy 111.615035 -170.672075) (xy 111.541425 -170.635423) (xy 111.471511 -170.592135)
			(xy 111.405889 -170.542581) (xy 111.34512 -170.487183) (xy 111.289722 -170.426414) (xy 111.240167 -170.360793)
			(xy 111.196879 -170.290879) (xy 111.160226 -170.217269) (xy 111.130522 -170.140591) (xy 111.10802 -170.061499)
			(xy 111.092912 -169.980669) (xy 111.085327 -169.898789) (xy 111.084868 -169.857674) (xy 60.38088 -169.857674)
			(xy 60.38088 -175.559974) (xy 69.360288 -175.559974) (xy 69.360857 -175.515205) (xy 69.369865 -175.42612)
			(xy 69.387768 -175.338388) (xy 69.414386 -175.252897) (xy 69.431408 -175.211486) (xy 69.434989 -175.2019)
			(xy 69.43498 -175.181453) (xy 69.431408 -175.171862) (xy 69.414355 -175.130462) (xy 69.387726 -175.044971)
			(xy 69.369827 -174.957236) (xy 69.360838 -174.868145) (xy 69.360288 -174.823374) (xy 69.360857 -174.778605)
			(xy 69.369865 -174.68952) (xy 69.387768 -174.601788) (xy 69.414386 -174.516297) (xy 69.431408 -174.474886)
			(xy 69.434989 -174.4653) (xy 69.43498 -174.444853) (xy 69.431408 -174.435262) (xy 69.414355 -174.393862)
			(xy 69.387726 -174.308371) (xy 69.369827 -174.220636) (xy 69.360838 -174.131545) (xy 69.360288 -174.086774)
			(xy 69.360674 -174.045657) (xy 69.368264 -173.963775) (xy 69.383377 -173.882942) (xy 69.405884 -173.803848)
			(xy 69.435593 -173.727169) (xy 69.47225 -173.653557) (xy 69.515543 -173.583643) (xy 69.565103 -173.518021)
			(xy 69.620506 -173.457252) (xy 69.681279 -173.401854) (xy 69.746905 -173.3523) (xy 69.816824 -173.309013)
			(xy 69.890438 -173.272362) (xy 69.96712 -173.24266) (xy 70.046216 -173.220159) (xy 70.12705 -173.205053)
			(xy 70.208933 -173.19747) (xy 70.25005 -173.197012) (xy 70.291666 -173.197515) (xy 70.37453 -173.205334)
			(xy 70.456303 -173.220852) (xy 70.53627 -173.243934) (xy 70.613735 -173.274378) (xy 70.68802 -173.311918)
			(xy 70.723506 -173.333664) (xy 70.732652 -173.338697) (xy 70.753275 -173.341768) (xy 70.773427 -173.336419)
			(xy 70.781926 -173.330362) (xy 70.815582 -173.304378) (xy 70.88701 -173.258241) (xy 70.962515 -173.219132)
			(xy 71.041408 -173.187407) (xy 71.122969 -173.163358) (xy 71.206453 -173.147202) (xy 71.291098 -173.139088)
			(xy 71.333614 -173.138592) (xy 71.374727 -173.139099) (xy 71.456602 -173.146687) (xy 71.537428 -173.161797)
			(xy 71.616516 -173.1843) (xy 71.693189 -173.214003) (xy 71.766795 -173.250654) (xy 71.836706 -173.29394)
			(xy 71.902324 -173.343492) (xy 71.963091 -173.398886) (xy 72.018488 -173.459651) (xy 72.068042 -173.525268)
			(xy 72.11133 -173.595177) (xy 72.147984 -173.668781) (xy 72.17769 -173.745454) (xy 72.200196 -173.82454)
			(xy 72.215308 -173.905366) (xy 72.222899 -173.987241) (xy 72.223376 -174.028354) (xy 72.22282 -174.073124)
			(xy 72.213808 -174.162209) (xy 72.195901 -174.24994) (xy 72.16928 -174.335431) (xy 72.152256 -174.376842)
			(xy 72.148718 -174.38644) (xy 72.148701 -174.406876) (xy 72.152256 -174.416466) (xy 72.16811 -174.454985)
			(xy 72.19339 -174.53436) (xy 72.211148 -174.615749) (xy 72.221227 -174.69844) (xy 72.222868 -174.740062)
			(xy 72.223665 -174.750997) (xy 72.233294 -174.770671) (xy 72.250251 -174.784536) (xy 72.260714 -174.787814)
			(xy 72.277586 -174.792311) (xy 72.310997 -174.802475) (xy 72.327516 -174.808134) (xy 72.335712 -174.810657)
			(xy 72.352848 -174.810657) (xy 72.361044 -174.808134) (xy 72.39626 -174.796188) (xy 72.46827 -174.777601)
			(xy 72.541593 -174.765161) (xy 72.615704 -174.758956) (xy 72.65289 -174.758604) (xy 72.690074 -174.75897)
			(xy 72.764182 -174.765192) (xy 72.837502 -174.777635) (xy 72.909513 -174.796211) (xy 72.944736 -174.808134)
			(xy 72.952932 -174.810657) (xy 72.970068 -174.810657) (xy 72.978264 -174.808134) (xy 73.013487 -174.79621)
			(xy 73.085495 -174.777617) (xy 73.158815 -174.76517) (xy 73.232925 -174.758959) (xy 73.27011 -174.758604)
			(xy 73.312036 -174.759059) (xy 73.395508 -174.767031) (xy 73.477845 -174.7829) (xy 73.5583 -174.806525)
			(xy 73.636145 -174.83769) (xy 73.710676 -174.876114) (xy 73.781216 -174.921448) (xy 73.847128 -174.973283)
			(xy 73.907814 -175.031148) (xy 73.962725 -175.094519) (xy 74.011364 -175.162823) (xy 74.053289 -175.235441)
			(xy 74.088123 -175.311716) (xy 74.115548 -175.390956) (xy 74.135316 -175.472444) (xy 74.14725 -175.555443)
			(xy 74.15124 -175.6392) (xy 74.14725 -175.722957) (xy 74.135316 -175.805956) (xy 74.115548 -175.887444)
			(xy 74.088123 -175.966684) (xy 74.053289 -176.042959) (xy 74.01685 -176.106074) (xy 102.855268 -176.106074)
			(xy 102.855838 -176.061305) (xy 102.864847 -175.97222) (xy 102.882749 -175.884489) (xy 102.909366 -175.798997)
			(xy 102.926388 -175.757586) (xy 102.92997 -175.748) (xy 102.92996 -175.727553) (xy 102.926388 -175.717962)
			(xy 102.90934 -175.67656) (xy 102.882709 -175.59107) (xy 102.864808 -175.503335) (xy 102.855818 -175.414245)
			(xy 102.855268 -175.369474) (xy 102.855838 -175.324705) (xy 102.864847 -175.23562) (xy 102.882749 -175.147889)
			(xy 102.909366 -175.062397) (xy 102.926388 -175.020986) (xy 102.92997 -175.0114) (xy 102.92996 -174.990953)
			(xy 102.926388 -174.981362) (xy 102.90934 -174.93996) (xy 102.882709 -174.85447) (xy 102.864808 -174.766735)
			(xy 102.855818 -174.677645) (xy 102.855268 -174.632874) (xy 102.855674 -174.591758) (xy 102.863264 -174.509876)
			(xy 102.878376 -174.429045) (xy 102.900882 -174.349952) (xy 102.930591 -174.273273) (xy 102.967247 -174.199663)
			(xy 103.010539 -174.129749) (xy 103.060097 -174.064128) (xy 103.115499 -174.003359) (xy 103.176271 -173.947961)
			(xy 103.241895 -173.898407) (xy 103.311812 -173.85512) (xy 103.385425 -173.818468) (xy 103.462105 -173.788765)
			(xy 103.541199 -173.766263) (xy 103.622032 -173.751156) (xy 103.703914 -173.743571) (xy 103.74503 -173.743112)
			(xy 103.786646 -173.743625) (xy 103.869509 -173.751442) (xy 103.951282 -173.766958) (xy 104.03125 -173.790038)
			(xy 104.108714 -173.82048) (xy 104.183 -173.858019) (xy 104.218486 -173.879764) (xy 104.227599 -173.884867)
			(xy 104.248243 -173.887914) (xy 104.268407 -173.882535) (xy 104.276906 -173.876462) (xy 104.310569 -173.850487)
			(xy 104.381995 -173.804349) (xy 104.457499 -173.765239) (xy 104.536391 -173.733513) (xy 104.617951 -173.709462)
			(xy 104.701434 -173.693305) (xy 104.786078 -173.685188) (xy 104.828594 -173.684692) (xy 104.869707 -173.685219)
			(xy 104.951582 -173.692805) (xy 105.032407 -173.707913) (xy 105.111494 -173.730413) (xy 105.188168 -173.760115)
			(xy 105.261774 -173.796765) (xy 105.331684 -173.84005) (xy 105.397303 -173.8896) (xy 105.45807 -173.944993)
			(xy 105.513467 -174.005757) (xy 105.563021 -174.071373) (xy 105.60631 -174.141281) (xy 105.642964 -174.214885)
			(xy 105.67267 -174.291556) (xy 105.695176 -174.370642) (xy 105.710288 -174.451467) (xy 105.717879 -174.533341)
			(xy 105.718356 -174.574454) (xy 105.717793 -174.619224) (xy 105.708783 -174.708309) (xy 105.690877 -174.79604)
			(xy 105.664259 -174.881531) (xy 105.647236 -174.922942) (xy 105.643699 -174.932541) (xy 105.643682 -174.952976)
			(xy 105.647236 -174.962566) (xy 105.663031 -175.000871) (xy 105.688241 -175.079807) (xy 105.705997 -175.160745)
			(xy 105.716146 -175.242985) (xy 105.717848 -175.284384) (xy 105.718707 -175.295302) (xy 105.728347 -175.314941)
			(xy 105.745257 -175.328822) (xy 105.755694 -175.332136) (xy 105.772566 -175.336634) (xy 105.805977 -175.346797)
			(xy 105.822496 -175.352456) (xy 105.830692 -175.354979) (xy 105.847828 -175.354979) (xy 105.856024 -175.352456)
			(xy 105.89124 -175.340495) (xy 105.963244 -175.321841) (xy 106.036565 -175.309332) (xy 106.11068 -175.303059)
			(xy 106.14787 -175.302672) (xy 106.185059 -175.303071) (xy 106.259172 -175.309358) (xy 106.332492 -175.321865)
			(xy 106.404498 -175.340503) (xy 106.439716 -175.352456) (xy 106.447912 -175.354979) (xy 106.465048 -175.354979)
			(xy 106.473244 -175.352456) (xy 106.508459 -175.340489) (xy 106.580462 -175.321837) (xy 106.653784 -175.30933)
			(xy 106.7279 -175.303058) (xy 106.76509 -175.302672) (xy 106.80703 -175.303067) (xy 106.890532 -175.311039)
			(xy 106.972897 -175.326913) (xy 107.05338 -175.350544) (xy 107.131253 -175.381719) (xy 107.20581 -175.420155)
			(xy 107.276375 -175.465504) (xy 107.34231 -175.517355) (xy 107.403018 -175.575239) (xy 107.457949 -175.638632)
			(xy 107.506605 -175.706959) (xy 107.548546 -175.779602) (xy 107.583391 -175.855903) (xy 107.610826 -175.93517)
			(xy 107.630602 -176.016687) (xy 107.64254 -176.099714) (xy 107.646531 -176.1835) (xy 107.64254 -176.267286)
			(xy 107.630602 -176.350313) (xy 107.610826 -176.43183) (xy 107.583391 -176.511097) (xy 107.548546 -176.587398)
			(xy 107.506605 -176.660041) (xy 107.457949 -176.728368) (xy 107.403018 -176.791761) (xy 107.34231 -176.849645)
			(xy 107.276375 -176.901496) (xy 107.20581 -176.946845) (xy 107.131253 -176.985281) (xy 107.05338 -177.016456)
			(xy 106.972897 -177.040087) (xy 106.890532 -177.055961) (xy 106.80703 -177.063933) (xy 106.76509 -177.064416)
			(xy 106.7279 -177.064029) (xy 106.653787 -177.057739) (xy 106.580468 -177.045228) (xy 106.508462 -177.026587)
			(xy 106.473244 -177.014632) (xy 106.465048 -177.012109) (xy 106.447912 -177.012109) (xy 106.439716 -177.014632)
			(xy 106.394061 -177.029945) (xy 106.300252 -177.051713) (xy 106.252518 -177.058066) (xy 106.241993 -177.059881)
			(xy 106.223638 -177.070747) (xy 106.211256 -177.088115) (xy 106.208576 -177.098452) (xy 106.19911 -177.142342)
			(xy 106.172519 -177.228104) (xy 106.15549 -177.269648) (xy 106.151947 -177.279245) (xy 106.151932 -177.299682)
			(xy 106.15549 -177.309272) (xy 106.172486 -177.350687) (xy 106.199044 -177.436185) (xy 106.216883 -177.523917)
			(xy 106.225825 -177.612996) (xy 106.226356 -177.65776) (xy 106.225852 -177.700108) (xy 106.217801 -177.784422)
			(xy 106.201772 -177.867588) (xy 106.177911 -177.948855) (xy 106.146432 -178.027485) (xy 106.107621 -178.102766)
			(xy 106.061831 -178.174018) (xy 106.009475 -178.240594) (xy 105.951027 -178.301892) (xy 105.887017 -178.357357)
			(xy 105.818025 -178.406486) (xy 105.744675 -178.448835) (xy 105.667632 -178.484019) (xy 105.587593 -178.511721)
			(xy 105.505284 -178.531689) (xy 105.421449 -178.543742) (xy 105.336848 -178.547773) (xy 105.252247 -178.543742)
			(xy 105.168412 -178.531689) (xy 105.086103 -178.511721) (xy 105.006064 -178.484019) (xy 104.929021 -178.448835)
			(xy 104.855671 -178.406486) (xy 104.786679 -178.357357) (xy 104.722669 -178.301892) (xy 104.664221 -178.240594)
			(xy 104.611865 -178.174018) (xy 104.566075 -178.102766) (xy 104.527264 -178.027485) (xy 104.495785 -177.948855)
			(xy 104.471924 -177.867588) (xy 104.455895 -177.784422) (xy 104.447844 -177.700108) (xy 104.44734 -177.65776)
			(xy 104.447856 -177.612995) (xy 104.456789 -177.523913) (xy 104.474632 -177.43618) (xy 104.501203 -177.350685)
			(xy 104.518206 -177.309272) (xy 104.521795 -177.299688) (xy 104.521781 -177.279239) (xy 104.518206 -177.269648)
			(xy 104.501216 -177.22823) (xy 104.474657 -177.142734) (xy 104.456815 -177.055003) (xy 104.447871 -176.965924)
			(xy 104.44734 -176.92116) (xy 104.447594 -176.89703) (xy 104.447848 -176.882298) (xy 104.433116 -176.857152)
			(xy 104.325166 -176.802034) (xy 104.29621 -176.804574) (xy 104.284272 -176.813464) (xy 104.251077 -176.8382)
			(xy 104.180868 -176.882074) (xy 104.106889 -176.91924) (xy 104.029779 -176.949378) (xy 103.950204 -176.972227)
			(xy 103.868852 -176.98759) (xy 103.786425 -176.995334) (xy 103.74503 -176.995836) (xy 103.703915 -176.995373)
			(xy 103.622035 -176.987788) (xy 103.541204 -176.97268) (xy 103.462113 -176.950179) (xy 103.385435 -176.920475)
			(xy 103.311825 -176.883823) (xy 103.241911 -176.840535) (xy 103.176289 -176.790981) (xy 103.11552 -176.735583)
			(xy 103.060122 -176.674814) (xy 103.010567 -176.609193) (xy 102.967279 -176.539279) (xy 102.930626 -176.465669)
			(xy 102.900922 -176.388991) (xy 102.87842 -176.309899) (xy 102.863312 -176.229069) (xy 102.855727 -176.147189)
			(xy 102.855268 -176.106074) (xy 74.01685 -176.106074) (xy 74.011364 -176.115577) (xy 73.962725 -176.183881)
			(xy 73.907814 -176.247252) (xy 73.847128 -176.305117) (xy 73.781216 -176.356952) (xy 73.710676 -176.402286)
			(xy 73.636145 -176.44071) (xy 73.5583 -176.471875) (xy 73.477845 -176.4955) (xy 73.395508 -176.511369)
			(xy 73.312036 -176.519341) (xy 73.27011 -176.51984) (xy 73.232926 -176.519472) (xy 73.158818 -176.51325)
			(xy 73.085498 -176.500807) (xy 73.013487 -176.482233) (xy 72.978264 -176.47031) (xy 72.970068 -176.467787)
			(xy 72.952932 -176.467787) (xy 72.944736 -176.47031) (xy 72.910756 -176.481853) (xy 72.841327 -176.500034)
			(xy 72.806052 -176.506632) (xy 72.796131 -176.508844) (xy 72.77908 -176.519877) (xy 72.767627 -176.53665)
			(xy 72.765158 -176.54651) (xy 72.755653 -176.591261) (xy 72.728677 -176.678684) (xy 72.71131 -176.721008)
			(xy 72.707732 -176.730595) (xy 72.707739 -176.751042) (xy 72.71131 -176.760632) (xy 72.728294 -176.802052)
			(xy 72.754855 -176.887548) (xy 72.772698 -176.975278) (xy 72.781644 -177.064356) (xy 72.782176 -177.10912)
			(xy 72.781672 -177.151468) (xy 72.773621 -177.235782) (xy 72.757592 -177.318948) (xy 72.733731 -177.400215)
			(xy 72.702252 -177.478845) (xy 72.663441 -177.554126) (xy 72.617651 -177.625378) (xy 72.565295 -177.691954)
			(xy 72.506847 -177.753252) (xy 72.442837 -177.808717) (xy 72.373845 -177.857846) (xy 72.300495 -177.900195)
			(xy 72.223452 -177.935379) (xy 72.143413 -177.963081) (xy 72.061104 -177.983049) (xy 71.977269 -177.995102)
			(xy 71.892668 -177.999133) (xy 71.808067 -177.995102) (xy 71.724232 -177.983049) (xy 71.641923 -177.963081)
			(xy 71.561884 -177.935379) (xy 71.484841 -177.900195) (xy 71.411491 -177.857846) (xy 71.342499 -177.808717)
			(xy 71.278489 -177.753252) (xy 71.220041 -177.691954) (xy 71.167685 -177.625378) (xy 71.121895 -177.554126)
			(xy 71.083084 -177.478845) (xy 71.051605 -177.400215) (xy 71.027744 -177.318948) (xy 71.011715 -177.235782)
			(xy 71.003664 -177.151468) (xy 71.00316 -177.10912) (xy 71.003695 -177.064356) (xy 71.012623 -176.975274)
			(xy 71.030459 -176.887541) (xy 71.057025 -176.802046) (xy 71.074026 -176.760632) (xy 71.07758 -176.751038)
			(xy 71.077588 -176.730598) (xy 71.074026 -176.721008) (xy 71.057024 -176.679595) (xy 71.030468 -176.594097)
			(xy 71.01263 -176.506364) (xy 71.00369 -176.417284) (xy 71.00316 -176.37252) (xy 71.003216 -176.357395)
			(xy 71.004231 -176.327162) (xy 71.005192 -176.312068) (xy 71.006208 -176.296574) (xy 70.990714 -176.269904)
			(xy 70.878954 -176.214532) (xy 70.848474 -176.218596) (xy 70.83679 -176.228756) (xy 70.806403 -176.254854)
			(xy 70.741691 -176.302073) (xy 70.672994 -176.343279) (xy 70.60087 -176.378141) (xy 70.525902 -176.406374)
			(xy 70.4487 -176.427751) (xy 70.369887 -176.442098) (xy 70.290104 -176.449298) (xy 70.25005 -176.449736)
			(xy 70.208935 -176.449254) (xy 70.127056 -176.441671) (xy 70.046226 -176.426565) (xy 69.967134 -176.404065)
			(xy 69.890456 -176.374363) (xy 69.816846 -176.337712) (xy 69.746932 -176.294426) (xy 69.68131 -176.244873)
			(xy 69.620541 -176.189476) (xy 69.565143 -176.128708) (xy 69.515588 -176.063088) (xy 69.472299 -175.993175)
			(xy 69.435647 -175.919566) (xy 69.405943 -175.842889) (xy 69.383441 -175.763798) (xy 69.368332 -175.682968)
			(xy 69.360747 -175.601089) (xy 69.360288 -175.559974) (xy 60.38088 -175.559974) (xy 60.38088 -178.798474)
			(xy 77.963268 -178.798474) (xy 77.963886 -178.752072) (xy 77.973579 -178.659774) (xy 77.992835 -178.568989)
			(xy 78.021445 -178.480704) (xy 78.039722 -178.438048) (xy 78.043541 -178.42811) (xy 78.043531 -178.406843)
			(xy 78.039722 -178.3969) (xy 78.021451 -178.354243) (xy 77.99286 -178.265953) (xy 77.973605 -178.175169)
			(xy 77.963896 -178.082875) (xy 77.963268 -178.036474) (xy 77.963674 -177.995358) (xy 77.971264 -177.913476)
			(xy 77.986376 -177.832645) (xy 78.008882 -177.753552) (xy 78.038591 -177.676873) (xy 78.075247 -177.603263)
			(xy 78.118539 -177.533349) (xy 78.168097 -177.467728) (xy 78.223499 -177.406959) (xy 78.284271 -177.351561)
			(xy 78.349895 -177.302007) (xy 78.419812 -177.25872) (xy 78.493425 -177.222068) (xy 78.570105 -177.192365)
			(xy 78.649199 -177.169863) (xy 78.730032 -177.154756) (xy 78.811914 -177.147171) (xy 78.85303 -177.146712)
			(xy 78.893848 -177.147168) (xy 78.975141 -177.154659) (xy 79.055405 -177.169568) (xy 79.133966 -177.191768)
			(xy 79.210162 -177.221072) (xy 79.283352 -177.257234) (xy 79.352922 -177.29995) (xy 79.418285 -177.348861)
			(xy 79.478892 -177.403555) (xy 79.534233 -177.463571) (xy 79.559404 -177.495708) (xy 79.565179 -177.502627)
			(xy 79.580393 -177.512264) (xy 79.589122 -177.514504) (xy 79.631283 -177.524073) (xy 79.713687 -177.550242)
			(xy 79.793163 -177.584282) (xy 79.868962 -177.625872) (xy 79.940368 -177.67462) (xy 80.006708 -177.730066)
			(xy 80.067355 -177.791686) (xy 80.121738 -177.8589) (xy 80.169343 -177.931073) (xy 80.209721 -178.007525)
			(xy 80.242492 -178.087533) (xy 80.267345 -178.170343) (xy 80.284047 -178.255173) (xy 80.29244 -178.341224)
			(xy 80.292956 -178.384454) (xy 80.292754 -178.410999) (xy 80.289578 -178.463993) (xy 80.286606 -178.490372)
			(xy 80.28578 -178.501682) (xy 80.292922 -178.523179) (xy 80.300322 -178.531774) (xy 80.329261 -178.562798)
			(xy 80.381784 -178.629432) (xy 80.427728 -178.700761) (xy 80.466676 -178.776139) (xy 80.498274 -178.854881)
			(xy 80.522235 -178.936272) (xy 80.538342 -179.019574) (xy 80.546449 -179.104032) (xy 80.546956 -179.146454)
			(xy 80.546393 -179.191224) (xy 80.537383 -179.280309) (xy 80.519477 -179.36804) (xy 80.492859 -179.453531)
			(xy 80.475836 -179.494942) (xy 80.472299 -179.504541) (xy 80.472282 -179.524976) (xy 80.475836 -179.534566)
			(xy 80.491631 -179.572871) (xy 80.516841 -179.651807) (xy 80.534597 -179.732745) (xy 80.544746 -179.814985)
			(xy 80.546448 -179.856384) (xy 80.547307 -179.867302) (xy 80.556947 -179.886941) (xy 80.573857 -179.900822)
			(xy 80.584294 -179.904136) (xy 80.601166 -179.908634) (xy 80.634577 -179.918797) (xy 80.651096 -179.924456)
			(xy 80.659292 -179.926979) (xy 80.676428 -179.926979) (xy 80.684624 -179.924456) (xy 80.71984 -179.912495)
			(xy 80.791844 -179.893841) (xy 80.865165 -179.881332) (xy 80.93928 -179.875059) (xy 80.97647 -179.874672)
			(xy 81.013659 -179.875071) (xy 81.087772 -179.881358) (xy 81.161092 -179.893865) (xy 81.233098 -179.912503)
			(xy 81.268316 -179.924456) (xy 81.276512 -179.926979) (xy 81.293648 -179.926979) (xy 81.301844 -179.924456)
			(xy 81.337059 -179.912489) (xy 81.409062 -179.893837) (xy 81.482384 -179.88133) (xy 81.5565 -179.875058)
			(xy 81.59369 -179.874672) (xy 81.63563 -179.875067) (xy 81.719132 -179.883039) (xy 81.801497 -179.898913)
			(xy 81.88198 -179.922544) (xy 81.959853 -179.953719) (xy 82.03441 -179.992155) (xy 82.104975 -180.037504)
			(xy 82.17091 -180.089355) (xy 82.231618 -180.147239) (xy 82.286549 -180.210632) (xy 82.335205 -180.278959)
			(xy 82.377146 -180.351602) (xy 82.411991 -180.427903) (xy 82.439426 -180.50717) (xy 82.459202 -180.588687)
			(xy 82.462267 -180.610002) (xy 86.081108 -180.610002) (xy 86.081685 -180.565233) (xy 86.090691 -180.476148)
			(xy 86.108592 -180.388417) (xy 86.135207 -180.302925) (xy 86.152228 -180.261514) (xy 86.155792 -180.251923)
			(xy 86.155793 -180.231481) (xy 86.152228 -180.22189) (xy 86.135186 -180.180486) (xy 86.108554 -180.094996)
			(xy 86.090651 -180.007262) (xy 86.081659 -179.918173) (xy 86.081108 -179.873402) (xy 86.081685 -179.828633)
			(xy 86.090691 -179.739548) (xy 86.108592 -179.651817) (xy 86.135207 -179.566325) (xy 86.152228 -179.524914)
			(xy 86.155792 -179.515323) (xy 86.155793 -179.494881) (xy 86.152228 -179.48529) (xy 86.135186 -179.443886)
			(xy 86.108554 -179.358396) (xy 86.090651 -179.270662) (xy 86.081659 -179.181573) (xy 86.081108 -179.136802)
			(xy 86.081615 -179.095689) (xy 86.089201 -179.013813) (xy 86.10431 -178.932986) (xy 86.126812 -178.853898)
			(xy 86.156515 -178.777224) (xy 86.193165 -178.703617) (xy 86.236451 -178.633706) (xy 86.286003 -178.568087)
			(xy 86.341397 -178.50732) (xy 86.402163 -178.451923) (xy 86.46778 -178.402369) (xy 86.537689 -178.359081)
			(xy 86.611295 -178.322428) (xy 86.687968 -178.292722) (xy 86.767055 -178.270217) (xy 86.847881 -178.255106)
			(xy 86.929757 -178.247516) (xy 86.97087 -178.24704) (xy 87.012486 -178.247545) (xy 87.095349 -178.255365)
			(xy 87.177122 -178.270883) (xy 87.257089 -178.293965) (xy 87.334554 -178.324408) (xy 87.40884 -178.361947)
			(xy 87.444326 -178.383692) (xy 87.453465 -178.388739) (xy 87.474092 -178.391802) (xy 87.494246 -178.386449)
			(xy 87.502746 -178.38039) (xy 87.536398 -178.354401) (xy 87.607826 -178.308264) (xy 87.683332 -178.269155)
			(xy 87.762226 -178.237431) (xy 87.843788 -178.213382) (xy 87.927272 -178.197227) (xy 88.011917 -178.189115)
			(xy 88.054434 -178.18862) (xy 88.095548 -178.18908) (xy 88.177426 -178.19667) (xy 88.258254 -178.211782)
			(xy 88.337343 -178.234287) (xy 88.414018 -178.263994) (xy 88.487625 -178.300648) (xy 88.557536 -178.343937)
			(xy 88.623155 -178.393491) (xy 88.683922 -178.448889) (xy 88.739319 -178.509657) (xy 88.788872 -178.575277)
			(xy 88.83216 -178.645189) (xy 88.868813 -178.718797) (xy 88.898518 -178.795473) (xy 88.921021 -178.874562)
			(xy 88.936132 -178.95539) (xy 88.94372 -179.037268) (xy 88.944196 -179.078382) (xy 88.943648 -179.123152)
			(xy 88.934633 -179.212238) (xy 88.916724 -179.299969) (xy 88.890101 -179.38546) (xy 88.873076 -179.42687)
			(xy 88.869521 -179.436464) (xy 88.869514 -179.456904) (xy 88.873076 -179.466494) (xy 88.888852 -179.504807)
			(xy 88.914067 -179.58374) (xy 88.931828 -179.664676) (xy 88.941982 -179.746913) (xy 88.943688 -179.788312)
			(xy 88.944498 -179.799238) (xy 88.954157 -179.818882) (xy 88.971088 -179.832757) (xy 88.981534 -179.836064)
			(xy 88.998407 -179.840559) (xy 89.031817 -179.850724) (xy 89.048336 -179.856384) (xy 89.056532 -179.858907)
			(xy 89.073668 -179.858907) (xy 89.081864 -179.856384) (xy 89.117077 -179.844413) (xy 89.189082 -179.825761)
			(xy 89.262404 -179.813256) (xy 89.33652 -179.806985) (xy 89.37371 -179.8066) (xy 89.4109 -179.806986)
			(xy 89.485013 -179.813277) (xy 89.558333 -179.825787) (xy 89.630338 -179.844429) (xy 89.665556 -179.856384)
			(xy 89.673752 -179.858907) (xy 89.690888 -179.858907) (xy 89.699084 -179.856384) (xy 89.734295 -179.844408)
			(xy 89.8063 -179.825757) (xy 89.879623 -179.813253) (xy 89.953739 -179.806984) (xy 89.99093 -179.8066)
			(xy 90.032865 -179.807156) (xy 90.116355 -179.815131) (xy 90.198709 -179.831006) (xy 90.279182 -179.854637)
			(xy 90.357043 -179.885811) (xy 90.431589 -179.924244) (xy 90.502144 -179.969589) (xy 90.56807 -180.021436)
			(xy 90.628768 -180.079314) (xy 90.683691 -180.1427) (xy 90.732339 -180.211019) (xy 90.774274 -180.283653)
			(xy 90.809114 -180.359944) (xy 90.836544 -180.439202) (xy 90.856317 -180.520708) (xy 90.868253 -180.603725)
			(xy 90.869375 -180.627274) (xy 94.473268 -180.627274) (xy 94.473838 -180.582505) (xy 94.482847 -180.49342)
			(xy 94.500749 -180.405689) (xy 94.527366 -180.320197) (xy 94.544388 -180.278786) (xy 94.54797 -180.2692)
			(xy 94.54796 -180.248753) (xy 94.544388 -180.239162) (xy 94.52734 -180.19776) (xy 94.500709 -180.11227)
			(xy 94.482808 -180.024535) (xy 94.473818 -179.935445) (xy 94.473268 -179.890674) (xy 94.473838 -179.845905)
			(xy 94.482847 -179.75682) (xy 94.500749 -179.669089) (xy 94.527366 -179.583597) (xy 94.544388 -179.542186)
			(xy 94.54797 -179.5326) (xy 94.54796 -179.512153) (xy 94.544388 -179.502562) (xy 94.52734 -179.46116)
			(xy 94.500709 -179.37567) (xy 94.482808 -179.287935) (xy 94.473818 -179.198845) (xy 94.473268 -179.154074)
			(xy 94.473674 -179.112958) (xy 94.481264 -179.031076) (xy 94.496376 -178.950245) (xy 94.518882 -178.871152)
			(xy 94.548591 -178.794473) (xy 94.585247 -178.720863) (xy 94.628539 -178.650949) (xy 94.678097 -178.585328)
			(xy 94.733499 -178.524559) (xy 94.794271 -178.469161) (xy 94.859895 -178.419607) (xy 94.929812 -178.37632)
			(xy 95.003425 -178.339668) (xy 95.080105 -178.309965) (xy 95.159199 -178.287463) (xy 95.240032 -178.272356)
			(xy 95.321914 -178.264771) (xy 95.36303 -178.264312) (xy 95.404646 -178.264825) (xy 95.487509 -178.272642)
			(xy 95.569282 -178.288158) (xy 95.64925 -178.311238) (xy 95.726714 -178.34168) (xy 95.801 -178.379219)
			(xy 95.836486 -178.400964) (xy 95.845599 -178.406067) (xy 95.866243 -178.409114) (xy 95.886407 -178.403735)
			(xy 95.894906 -178.397662) (xy 95.928569 -178.371687) (xy 95.999995 -178.325549) (xy 96.075499 -178.286439)
			(xy 96.154391 -178.254713) (xy 96.235951 -178.230662) (xy 96.319434 -178.214505) (xy 96.404078 -178.206388)
			(xy 96.446594 -178.205892) (xy 96.487707 -178.206419) (xy 96.569582 -178.214005) (xy 96.650407 -178.229113)
			(xy 96.729494 -178.251613) (xy 96.806168 -178.281315) (xy 96.879774 -178.317965) (xy 96.949684 -178.36125)
			(xy 97.015303 -178.4108) (xy 97.07607 -178.466193) (xy 97.131467 -178.526957) (xy 97.181021 -178.592573)
			(xy 97.22431 -178.662481) (xy 97.260964 -178.736085) (xy 97.29067 -178.812756) (xy 97.313176 -178.891842)
			(xy 97.328288 -178.972667) (xy 97.335879 -179.054541) (xy 97.336356 -179.095654) (xy 97.335793 -179.140424)
			(xy 97.326783 -179.229509) (xy 97.308877 -179.31724) (xy 97.282259 -179.402731) (xy 97.265236 -179.444142)
			(xy 97.261699 -179.453741) (xy 97.261682 -179.474176) (xy 97.265236 -179.483766) (xy 97.281031 -179.522071)
			(xy 97.306241 -179.601007) (xy 97.323997 -179.681945) (xy 97.334146 -179.764185) (xy 97.335848 -179.805584)
			(xy 97.336707 -179.816502) (xy 97.346347 -179.836141) (xy 97.363257 -179.850022) (xy 97.373694 -179.853336)
			(xy 97.390566 -179.857834) (xy 97.423977 -179.867997) (xy 97.440496 -179.873656) (xy 97.448692 -179.876179)
			(xy 97.465828 -179.876179) (xy 97.474024 -179.873656) (xy 97.50924 -179.861695) (xy 97.581244 -179.843041)
			(xy 97.654565 -179.830532) (xy 97.72868 -179.824259) (xy 97.76587 -179.823872) (xy 97.803059 -179.824271)
			(xy 97.877172 -179.830558) (xy 97.950492 -179.843065) (xy 98.022498 -179.861703) (xy 98.057716 -179.873656)
			(xy 98.065912 -179.876179) (xy 98.083048 -179.876179) (xy 98.091244 -179.873656) (xy 98.126459 -179.861689)
			(xy 98.198462 -179.843037) (xy 98.271784 -179.83053) (xy 98.3459 -179.824258) (xy 98.38309 -179.823872)
			(xy 98.42503 -179.824267) (xy 98.508532 -179.832239) (xy 98.590897 -179.848113) (xy 98.67138 -179.871744)
			(xy 98.749253 -179.902919) (xy 98.82381 -179.941355) (xy 98.894375 -179.986704) (xy 98.96031 -180.038555)
			(xy 99.021018 -180.096439) (xy 99.075949 -180.159832) (xy 99.124605 -180.228159) (xy 99.166546 -180.300802)
			(xy 99.201391 -180.377103) (xy 99.228826 -180.45637) (xy 99.248602 -180.537887) (xy 99.26054 -180.620914)
			(xy 99.264531 -180.7047) (xy 99.26054 -180.788486) (xy 99.248602 -180.871513) (xy 99.228826 -180.95303)
			(xy 99.201391 -181.032297) (xy 99.166546 -181.108598) (xy 99.124605 -181.181241) (xy 99.075949 -181.249568)
			(xy 99.021018 -181.312961) (xy 98.96031 -181.370845) (xy 98.894375 -181.422696) (xy 98.82381 -181.468045)
			(xy 98.749253 -181.506481) (xy 98.67138 -181.537656) (xy 98.590897 -181.561287) (xy 98.508532 -181.577161)
			(xy 98.42503 -181.585133) (xy 98.38309 -181.585616) (xy 98.3459 -181.585229) (xy 98.271787 -181.578939)
			(xy 98.198468 -181.566428) (xy 98.126462 -181.547787) (xy 98.091244 -181.535832) (xy 98.083048 -181.533309)
			(xy 98.065912 -181.533309) (xy 98.057716 -181.535832) (xy 98.015541 -181.55005) (xy 97.929015 -181.570917)
			(xy 97.884996 -181.577488) (xy 97.875039 -181.579265) (xy 97.857602 -181.589479) (xy 97.845472 -181.605643)
			(xy 97.842578 -181.615334) (xy 97.833867 -181.648486) (xy 97.811997 -181.713456) (xy 97.79889 -181.745128)
			(xy 97.795301 -181.754712) (xy 97.795316 -181.775161) (xy 97.79889 -181.784752) (xy 97.81588 -181.82617)
			(xy 97.842439 -181.911666) (xy 97.860281 -181.999397) (xy 97.869225 -182.088476) (xy 97.869756 -182.13324)
			(xy 97.869252 -182.175588) (xy 97.861201 -182.259902) (xy 97.845172 -182.343068) (xy 97.821311 -182.424335)
			(xy 97.789832 -182.502965) (xy 97.751021 -182.578246) (xy 97.705231 -182.649498) (xy 97.652875 -182.716074)
			(xy 97.594427 -182.777372) (xy 97.530417 -182.832837) (xy 97.461425 -182.881966) (xy 97.388075 -182.924315)
			(xy 97.311032 -182.959499) (xy 97.230993 -182.987201) (xy 97.148684 -183.007169) (xy 97.064849 -183.019222)
			(xy 96.980248 -183.023253) (xy 96.895647 -183.019222) (xy 96.811812 -183.007169) (xy 96.729503 -182.987201)
			(xy 96.649464 -182.959499) (xy 96.572421 -182.924315) (xy 96.499071 -182.881966) (xy 96.430079 -182.832837)
			(xy 96.366069 -182.777372) (xy 96.307621 -182.716074) (xy 96.255265 -182.649498) (xy 96.209475 -182.578246)
			(xy 96.170664 -182.502965) (xy 96.139185 -182.424335) (xy 96.115324 -182.343068) (xy 96.099295 -182.259902)
			(xy 96.091244 -182.175588) (xy 96.09074 -182.13324) (xy 96.091249 -182.088475) (xy 96.100185 -181.999393)
			(xy 96.118029 -181.91166) (xy 96.144602 -181.826165) (xy 96.161606 -181.784752) (xy 96.165149 -181.775155)
			(xy 96.165164 -181.754718) (xy 96.161606 -181.745128) (xy 96.14461 -181.703713) (xy 96.118052 -181.618215)
			(xy 96.100212 -181.530483) (xy 96.09127 -181.441404) (xy 96.09074 -181.39664) (xy 96.09074 -181.381146)
			(xy 96.074992 -181.356254) (xy 95.965264 -181.304184) (xy 95.936308 -181.30774) (xy 95.924878 -181.317138)
			(xy 95.890853 -181.344159) (xy 95.818459 -181.392213) (xy 95.741724 -181.43298) (xy 95.66138 -181.466069)
			(xy 95.578192 -181.491168) (xy 95.492953 -181.508035) (xy 95.406476 -181.51651) (xy 95.36303 -181.517036)
			(xy 95.321915 -181.516573) (xy 95.240035 -181.508988) (xy 95.159204 -181.49388) (xy 95.080113 -181.471379)
			(xy 95.003435 -181.441675) (xy 94.929825 -181.405023) (xy 94.859911 -181.361735) (xy 94.794289 -181.312181)
			(xy 94.73352 -181.256783) (xy 94.678122 -181.196014) (xy 94.628567 -181.130393) (xy 94.585279 -181.060479)
			(xy 94.548626 -180.986869) (xy 94.518922 -180.910191) (xy 94.49642 -180.831099) (xy 94.481312 -180.750269)
			(xy 94.473727 -180.668389) (xy 94.473268 -180.627274) (xy 90.869375 -180.627274) (xy 90.872244 -180.6875)
			(xy 90.868253 -180.771275) (xy 90.856317 -180.854292) (xy 90.836544 -180.935798) (xy 90.809114 -181.015056)
			(xy 90.774274 -181.091347) (xy 90.732339 -181.163981) (xy 90.683691 -181.2323) (xy 90.628768 -181.295686)
			(xy 90.56807 -181.353564) (xy 90.502144 -181.405411) (xy 90.431589 -181.450756) (xy 90.357043 -181.489189)
			(xy 90.279182 -181.520363) (xy 90.198709 -181.543994) (xy 90.116355 -181.559869) (xy 90.032865 -181.567844)
			(xy 89.99093 -181.568344) (xy 89.953741 -181.567944) (xy 89.879628 -181.561657) (xy 89.806308 -181.54915)
			(xy 89.734302 -181.530513) (xy 89.699084 -181.51856) (xy 89.690888 -181.516037) (xy 89.673752 -181.516037)
			(xy 89.665556 -181.51856) (xy 89.623411 -181.532721) (xy 89.536959 -181.553508) (xy 89.448856 -181.565496)
			(xy 89.404444 -181.567582) (xy 89.393451 -181.568595) (xy 89.373794 -181.578587) (xy 89.360091 -181.595863)
			(xy 89.356946 -181.606444) (xy 89.347967 -181.641899) (xy 89.324947 -181.711329) (xy 89.310972 -181.745128)
			(xy 89.307384 -181.754712) (xy 89.307399 -181.775161) (xy 89.310972 -181.784752) (xy 89.327996 -181.826163)
			(xy 89.354632 -181.91165) (xy 89.37254 -181.999382) (xy 89.381538 -182.08847) (xy 89.382092 -182.13324)
			(xy 89.381588 -182.175601) (xy 89.373535 -182.259938) (xy 89.357501 -182.343128) (xy 89.333633 -182.424418)
			(xy 89.302145 -182.50307) (xy 89.263323 -182.578373) (xy 89.21752 -182.649645) (xy 89.165149 -182.716241)
			(xy 89.106684 -182.777556) (xy 89.042656 -182.833037) (xy 88.973644 -182.88218) (xy 88.900274 -182.92454)
			(xy 88.823209 -182.959735) (xy 88.743147 -182.987444) (xy 88.660814 -183.007418) (xy 88.576955 -183.019475)
			(xy 88.49233 -183.023507) (xy 88.407705 -183.019475) (xy 88.323846 -183.007418) (xy 88.241513 -182.987444)
			(xy 88.161451 -182.959735) (xy 88.084386 -182.92454) (xy 88.011016 -182.88218) (xy 87.942004 -182.833037)
			(xy 87.877976 -182.777556) (xy 87.819511 -182.716241) (xy 87.76714 -182.649645) (xy 87.721337 -182.578373)
			(xy 87.682515 -182.50307) (xy 87.651027 -182.424418) (xy 87.627159 -182.343128) (xy 87.611125 -182.259938)
			(xy 87.603072 -182.175601) (xy 87.602568 -182.13324) (xy 87.603127 -182.08847) (xy 87.612138 -181.999385)
			(xy 87.630045 -181.911654) (xy 87.656665 -181.826163) (xy 87.673688 -181.784752) (xy 87.677232 -181.775155)
			(xy 87.677247 -181.754718) (xy 87.673688 -181.745128) (xy 87.65877 -181.708939) (xy 87.634581 -181.634489)
			(xy 87.617023 -181.558202) (xy 87.606232 -181.480668) (xy 87.603838 -181.441598) (xy 87.603076 -181.427882)
			(xy 87.588598 -181.405276) (xy 87.486236 -181.352444) (xy 87.459566 -181.353714) (xy 87.447882 -181.360826)
			(xy 87.412209 -181.38294) (xy 87.337447 -181.421096) (xy 87.259425 -181.452047) (xy 87.178837 -181.475518)
			(xy 87.096397 -181.4913) (xy 87.012838 -181.499253) (xy 86.97087 -181.499764) (xy 86.929755 -181.499316)
			(xy 86.847877 -181.491726) (xy 86.767048 -181.476614) (xy 86.687959 -181.454109) (xy 86.611283 -181.424402)
			(xy 86.537675 -181.387748) (xy 86.467763 -181.344458) (xy 86.402144 -181.294902) (xy 86.341376 -181.239504)
			(xy 86.28598 -181.178735) (xy 86.236426 -181.113114) (xy 86.193139 -181.043201) (xy 86.156487 -180.969592)
			(xy 86.126782 -180.892915) (xy 86.10428 -180.813824) (xy 86.08917 -180.732995) (xy 86.081583 -180.651117)
			(xy 86.081108 -180.610002) (xy 82.462267 -180.610002) (xy 82.47114 -180.671714) (xy 82.475131 -180.7555)
			(xy 82.47114 -180.839286) (xy 82.459202 -180.922313) (xy 82.439426 -181.00383) (xy 82.411991 -181.083097)
			(xy 82.377146 -181.159398) (xy 82.335205 -181.232041) (xy 82.286549 -181.300368) (xy 82.231618 -181.363761)
			(xy 82.17091 -181.421645) (xy 82.104975 -181.473496) (xy 82.03441 -181.518845) (xy 81.959853 -181.557281)
			(xy 81.88198 -181.588456) (xy 81.801497 -181.612087) (xy 81.719132 -181.627961) (xy 81.63563 -181.635933)
			(xy 81.59369 -181.636416) (xy 81.5565 -181.636029) (xy 81.482387 -181.629739) (xy 81.409068 -181.617228)
			(xy 81.337062 -181.598587) (xy 81.301844 -181.586632) (xy 81.293648 -181.584109) (xy 81.276512 -181.584109)
			(xy 81.268316 -181.586632) (xy 81.24011 -181.596266) (xy 81.182657 -181.612157) (xy 81.153508 -181.618382)
			(xy 81.143879 -181.620834) (xy 81.127394 -181.631892) (xy 81.116335 -181.648377) (xy 81.113884 -181.658006)
			(xy 81.104396 -181.702491) (xy 81.07755 -181.789404) (xy 81.06029 -181.831488) (xy 81.056724 -181.841078)
			(xy 81.056724 -181.861522) (xy 81.06029 -181.871112) (xy 81.077299 -181.912522) (xy 81.103853 -181.998022)
			(xy 81.121689 -182.085755) (xy 81.130627 -182.174836) (xy 81.131156 -182.2196) (xy 81.130652 -182.261948)
			(xy 81.122601 -182.346262) (xy 81.106572 -182.429428) (xy 81.082711 -182.510695) (xy 81.051232 -182.589325)
			(xy 81.012421 -182.664606) (xy 80.966631 -182.735858) (xy 80.914275 -182.802434) (xy 80.855827 -182.863732)
			(xy 80.791817 -182.919197) (xy 80.722825 -182.968326) (xy 80.649475 -183.010675) (xy 80.572432 -183.045859)
			(xy 80.492393 -183.073561) (xy 80.410084 -183.093529) (xy 80.326249 -183.105582) (xy 80.241648 -183.109613)
			(xy 80.157047 -183.105582) (xy 80.073212 -183.093529) (xy 79.990903 -183.073561) (xy 79.910864 -183.045859)
			(xy 79.833821 -183.010675) (xy 79.760471 -182.968326) (xy 79.691479 -182.919197) (xy 79.627469 -182.863732)
			(xy 79.569021 -182.802434) (xy 79.516665 -182.735858) (xy 79.470875 -182.664606) (xy 79.432064 -182.589325)
			(xy 79.400585 -182.510695) (xy 79.376724 -182.429428) (xy 79.360695 -182.346262) (xy 79.352644 -182.261948)
			(xy 79.35214 -182.2196) (xy 79.35267 -182.174836) (xy 79.361599 -182.085754) (xy 79.379438 -181.998021)
			(xy 79.406005 -181.912525) (xy 79.423006 -181.871112) (xy 79.426572 -181.861522) (xy 79.426572 -181.841078)
			(xy 79.423006 -181.831488) (xy 79.405997 -181.790078) (xy 79.379443 -181.704578) (xy 79.361607 -181.616845)
			(xy 79.352669 -181.527764) (xy 79.35214 -181.483) (xy 79.352578 -181.44277) (xy 79.359832 -181.362636)
			(xy 79.366618 -181.32298) (xy 79.368904 -181.310534) (xy 79.361792 -181.287674) (xy 79.287878 -181.210204)
			(xy 79.265272 -181.20233) (xy 79.252826 -181.203854) (xy 79.222877 -181.207733) (xy 79.162627 -181.21193)
			(xy 79.13243 -181.212236) (xy 79.091315 -181.211773) (xy 79.009435 -181.204188) (xy 78.928604 -181.18908)
			(xy 78.849513 -181.166579) (xy 78.772835 -181.136875) (xy 78.699225 -181.100223) (xy 78.629311 -181.056935)
			(xy 78.563689 -181.007381) (xy 78.50292 -180.951983) (xy 78.447522 -180.891214) (xy 78.397967 -180.825593)
			(xy 78.354679 -180.755679) (xy 78.318026 -180.682069) (xy 78.288322 -180.605391) (xy 78.26582 -180.526299)
			(xy 78.250712 -180.445469) (xy 78.243127 -180.363589) (xy 78.242668 -180.322474) (xy 78.24321 -180.279763)
			(xy 78.251472 -180.194741) (xy 78.267833 -180.1109) (xy 78.292141 -180.029009) (xy 78.307692 -179.989226)
			(xy 78.311165 -179.97915) (xy 78.310363 -179.957877) (xy 78.306168 -179.948078) (xy 78.289084 -179.911782)
			(xy 78.260766 -179.83672) (xy 78.239325 -179.759412) (xy 78.224934 -179.680487) (xy 78.21771 -179.600587)
			(xy 78.217268 -179.560474) (xy 78.217473 -179.533929) (xy 78.220647 -179.480935) (xy 78.223618 -179.454556)
			(xy 78.224421 -179.443246) (xy 78.217294 -179.421752) (xy 78.209902 -179.413154) (xy 78.180933 -179.382157)
			(xy 78.128411 -179.31552) (xy 78.082469 -179.244186) (xy 78.043525 -179.168805) (xy 78.011931 -179.090059)
			(xy 77.987974 -179.008663) (xy 77.971872 -178.925358) (xy 77.963772 -178.840898) (xy 77.963268 -178.798474)
			(xy 60.38088 -178.798474) (xy 60.38088 -179.40782) (xy 60.381306 -179.417889) (xy 60.389023 -179.43649)
			(xy 60.395866 -179.443888) (xy 60.582556 -179.630578) (xy 60.589957 -179.637418) (xy 60.608555 -179.645135)
			(xy 60.618624 -179.645564) (xy 67.985386 -179.645564) (xy 68.01034 -179.646184) (xy 68.059285 -179.655934)
			(xy 68.105389 -179.675044) (xy 68.146881 -179.702779) (xy 68.164964 -179.719986) (xy 69.815964 -181.370986)
			(xy 69.833219 -181.389029) (xy 69.860967 -181.430524) (xy 69.880071 -181.476642) (xy 69.889795 -181.525604)
			(xy 69.890386 -181.550564) (xy 69.890386 -183.85917) (xy 69.890821 -183.869235) (xy 69.898552 -183.887822)
			(xy 69.905372 -183.895238) (xy 71.920862 -185.910728) (xy 71.92826 -185.917573) (xy 71.946859 -185.925296)
			(xy 71.95693 -185.925714) (xy 73.753726 -185.925714) (xy 73.778685 -185.926288) (xy 73.827644 -185.936032)
			(xy 73.873761 -185.95514) (xy 73.915264 -185.982878) (xy 73.933304 -186.000136) (xy 78.664054 -190.730886)
			(xy 78.671455 -190.737726) (xy 78.690053 -190.745443) (xy 78.700122 -190.745872)
		)
		(stroke
			(width 0)
			(type solid)
		)
		(fill yes)
		(layer "In8.Cu")
		(net "GND")
	)
	(gr_poly
		(pts
			(xy 439.223404 -341.591138) (xy 439.233473 -341.590713) (xy 439.25207 -341.58299) (xy 439.259472 -341.576152)
			(xy 440.567572 -340.268052) (xy 440.574414 -340.260652) (xy 440.582135 -340.242054) (xy 440.582558 -340.231984)
			(xy 440.582558 -268.411706) (xy 440.582135 -268.401636) (xy 440.574417 -268.383034) (xy 440.567572 -268.375638)
			(xy 439.495946 -267.304012) (xy 439.488695 -267.297437) (xy 439.470665 -267.28986) (xy 439.460894 -267.28928)
			(xy 439.379868 -267.288264) (xy 439.36158 -267.295376) (xy 439.354214 -267.302488) (xy 439.333521 -267.3214)
			(xy 439.287486 -267.353389) (xy 439.237144 -267.378051) (xy 439.183654 -267.39482) (xy 439.128243 -267.403311)
			(xy 439.100214 -267.403834) (xy 439.074247 -267.403385) (xy 439.022828 -267.39609) (xy 438.97294 -267.381656)
			(xy 438.92557 -267.360368) (xy 438.881653 -267.332648) (xy 438.842058 -267.299042) (xy 438.807566 -267.260216)
			(xy 438.778861 -267.216936) (xy 438.756509 -267.170058) (xy 438.740952 -267.120509) (xy 438.736232 -267.09497)
			(xy 438.733184 -267.076682) (xy 438.70499 -267.052552) (xy 435.39537 -267.052552) (xy 435.367176 -267.076682)
			(xy 435.364128 -267.09497) (xy 435.359195 -267.121867) (xy 435.342442 -267.17392) (xy 435.318187 -267.222929)
			(xy 435.286964 -267.267821) (xy 435.249455 -267.307612) (xy 435.206483 -267.341429) (xy 435.15899 -267.368532)
			(xy 435.108016 -267.388327) (xy 435.054679 -267.400381) (xy 435.000146 -267.404428) (xy 434.945613 -267.400381)
			(xy 434.892276 -267.388327) (xy 434.841302 -267.368532) (xy 434.793809 -267.341429) (xy 434.750837 -267.307612)
			(xy 434.713328 -267.267821) (xy 434.682105 -267.222929) (xy 434.65785 -267.17392) (xy 434.641097 -267.121867)
			(xy 434.636164 -267.09497) (xy 434.633116 -267.076682) (xy 434.604922 -267.052552) (xy 431.951384 -267.052552)
			(xy 431.92319 -267.076682) (xy 431.920142 -267.09497) (xy 431.915209 -267.121867) (xy 431.898456 -267.17392)
			(xy 431.874201 -267.222929) (xy 431.842978 -267.267821) (xy 431.805469 -267.307612) (xy 431.762497 -267.341429)
			(xy 431.715004 -267.368532) (xy 431.66403 -267.388327) (xy 431.610693 -267.400381) (xy 431.55616 -267.404428)
			(xy 431.501627 -267.400381) (xy 431.44829 -267.388327) (xy 431.397316 -267.368532) (xy 431.349823 -267.341429)
			(xy 431.306851 -267.307612) (xy 431.269342 -267.267821) (xy 431.238119 -267.222929) (xy 431.213864 -267.17392)
			(xy 431.197111 -267.121867) (xy 431.192178 -267.09497) (xy 431.18913 -267.076682) (xy 431.160936 -267.052552)
			(xy 427.851316 -267.052552) (xy 427.823122 -267.076682) (xy 427.820074 -267.09497) (xy 427.815141 -267.121867)
			(xy 427.798388 -267.17392) (xy 427.774133 -267.222929) (xy 427.74291 -267.267821) (xy 427.705401 -267.307612)
			(xy 427.662429 -267.341429) (xy 427.614936 -267.368532) (xy 427.563962 -267.388327) (xy 427.510625 -267.400381)
			(xy 427.456092 -267.404428) (xy 427.401559 -267.400381) (xy 427.348222 -267.388327) (xy 427.297248 -267.368532)
			(xy 427.249755 -267.341429) (xy 427.206783 -267.307612) (xy 427.169274 -267.267821) (xy 427.138051 -267.222929)
			(xy 427.113796 -267.17392) (xy 427.097043 -267.121867) (xy 427.09211 -267.09497) (xy 427.089062 -267.076682)
			(xy 427.060868 -267.052552) (xy 424.40733 -267.052552) (xy 424.379136 -267.076682) (xy 424.376088 -267.09497)
			(xy 424.371155 -267.121867) (xy 424.354402 -267.17392) (xy 424.330147 -267.222929) (xy 424.298924 -267.267821)
			(xy 424.261415 -267.307612) (xy 424.218443 -267.341429) (xy 424.17095 -267.368532) (xy 424.119976 -267.388327)
			(xy 424.066639 -267.400381) (xy 424.012106 -267.404428) (xy 423.957573 -267.400381) (xy 423.904236 -267.388327)
			(xy 423.853262 -267.368532) (xy 423.805769 -267.341429) (xy 423.762797 -267.307612) (xy 423.725288 -267.267821)
			(xy 423.694065 -267.222929) (xy 423.66981 -267.17392) (xy 423.653057 -267.121867) (xy 423.648124 -267.09497)
			(xy 423.645076 -267.076682) (xy 423.616882 -267.052552) (xy 420.307262 -267.052552) (xy 420.279068 -267.076682)
			(xy 420.27602 -267.09497) (xy 420.271087 -267.121867) (xy 420.254334 -267.17392) (xy 420.230079 -267.222929)
			(xy 420.198856 -267.267821) (xy 420.161347 -267.307612) (xy 420.118375 -267.341429) (xy 420.070882 -267.368532)
			(xy 420.019908 -267.388327) (xy 419.966571 -267.400381) (xy 419.912038 -267.404428) (xy 419.857505 -267.400381)
			(xy 419.804168 -267.388327) (xy 419.753194 -267.368532) (xy 419.705701 -267.341429) (xy 419.662729 -267.307612)
			(xy 419.62522 -267.267821) (xy 419.593997 -267.222929) (xy 419.569742 -267.17392) (xy 419.552989 -267.121867)
			(xy 419.548056 -267.09497) (xy 419.545008 -267.076682) (xy 419.516814 -267.052552) (xy 416.863276 -267.052552)
			(xy 416.835082 -267.076682) (xy 416.832034 -267.09497) (xy 416.827101 -267.121867) (xy 416.810348 -267.17392)
			(xy 416.786093 -267.222929) (xy 416.75487 -267.267821) (xy 416.717361 -267.307612) (xy 416.674389 -267.341429)
			(xy 416.626896 -267.368532) (xy 416.575922 -267.388327) (xy 416.522585 -267.400381) (xy 416.468052 -267.404428)
			(xy 416.413519 -267.400381) (xy 416.360182 -267.388327) (xy 416.309208 -267.368532) (xy 416.261715 -267.341429)
			(xy 416.218743 -267.307612) (xy 416.181234 -267.267821) (xy 416.150011 -267.222929) (xy 416.125756 -267.17392)
			(xy 416.109003 -267.121867) (xy 416.10407 -267.09497) (xy 416.101022 -267.076682) (xy 416.072828 -267.052552)
			(xy 393.63142 -267.052552) (xy 393.611744 -267.052184) (xy 393.572862 -267.046114) (xy 393.535383 -267.034117)
			(xy 393.517628 -267.025628) (xy 393.499458 -267.016101) (xy 393.466191 -266.992095) (xy 393.437208 -266.963061)
			(xy 393.424918 -266.946634) (xy 393.417261 -266.9372) (xy 393.395648 -266.926177) (xy 393.383516 -266.925552)
			(xy 392.311128 -266.925552) (xy 392.301946 -266.925899) (xy 392.284734 -266.932288) (xy 392.270874 -266.94433)
			(xy 392.26617 -266.952222) (xy 392.26617 -266.952476) (xy 392.253702 -266.974698) (xy 392.222994 -267.015358)
			(xy 392.186414 -267.050827) (xy 392.144825 -267.080264) (xy 392.099214 -267.102975) (xy 392.050658 -267.118421)
			(xy 392.000308 -267.126236) (xy 391.949356 -267.126236) (xy 391.899006 -267.118421) (xy 391.85045 -267.102975)
			(xy 391.804839 -267.080264) (xy 391.76325 -267.050827) (xy 391.72667 -267.015358) (xy 391.695962 -266.974698)
			(xy 391.683494 -266.952476) (xy 391.683494 -266.952222) (xy 391.678786 -266.944335) (xy 391.664926 -266.932304)
			(xy 391.647715 -266.925927) (xy 391.638536 -266.925552) (xy 391.371074 -266.925552) (xy 391.361888 -266.925891)
			(xy 391.344663 -266.93227) (xy 391.330791 -266.944309) (xy 391.326116 -266.952222) (xy 391.326116 -266.952476)
			(xy 391.313649 -266.974701) (xy 391.282943 -267.015367) (xy 391.246364 -267.050843) (xy 391.204776 -267.08029)
			(xy 391.159165 -267.10301) (xy 391.110609 -267.118466) (xy 391.060256 -267.126293) (xy 391.034778 -267.12672)
			(xy 391.008792 -267.126209) (xy 390.957459 -267.118076) (xy 390.908031 -267.102013) (xy 390.861723 -267.078416)
			(xy 390.819677 -267.047866) (xy 390.782927 -267.011115) (xy 390.752379 -266.969068) (xy 390.728783 -266.92276)
			(xy 390.712722 -266.873331) (xy 390.70459 -266.821998) (xy 390.70407 -266.796012) (xy 390.704495 -266.772686)
			(xy 390.711091 -266.726502) (xy 390.724099 -266.6817) (xy 390.743261 -266.639164) (xy 390.755378 -266.619228)
			(xy 390.755378 -266.618974) (xy 390.759996 -266.61095) (xy 390.763708 -266.592829) (xy 390.760728 -266.574574)
			(xy 390.756394 -266.566396) (xy 390.604248 -266.304776) (xy 390.580626 -266.291314) (xy 390.564878 -266.291314)
			(xy 390.540888 -266.290842) (xy 390.493498 -266.283333) (xy 390.447867 -266.268504) (xy 390.405117 -266.246719)
			(xy 390.366301 -266.218515) (xy 390.332374 -266.184587) (xy 390.304173 -266.14577) (xy 390.28239 -266.103018)
			(xy 390.267563 -266.057386) (xy 390.260057 -266.009996) (xy 390.25957 -265.986006) (xy 390.260122 -265.959247)
			(xy 390.269435 -265.906547) (xy 390.287776 -265.856271) (xy 390.300718 -265.832844) (xy 390.305002 -265.824925)
			(xy 390.308252 -265.80723) (xy 390.305161 -265.789506) (xy 390.300972 -265.781536) (xy 390.148572 -265.519154)
			(xy 390.12368 -265.505692) (xy 390.109456 -265.506454) (xy 390.094724 -265.506708) (xy 390.068734 -265.506227)
			(xy 390.017392 -265.498098) (xy 389.967954 -265.482038) (xy 389.921638 -265.458442) (xy 389.879583 -265.42789)
			(xy 389.842826 -265.391135) (xy 389.812271 -265.349083) (xy 389.788671 -265.302768) (xy 389.772607 -265.253331)
			(xy 389.764475 -265.20199) (xy 389.764016 -265.176) (xy 389.764016 -265.175492) (xy 389.764426 -265.152236)
			(xy 389.770973 -265.106186) (xy 389.783908 -265.061508) (xy 389.802976 -265.019084) (xy 389.81507 -264.999216)
			(xy 389.82269 -264.987278) (xy 389.823198 -264.959084) (xy 389.678418 -264.709148) (xy 389.653526 -264.695686)
			(xy 389.639302 -264.696448) (xy 389.624824 -264.696702) (xy 389.599346 -264.696234) (xy 389.548992 -264.688421)
			(xy 389.500432 -264.672977) (xy 389.454816 -264.650267) (xy 389.413223 -264.620829) (xy 389.376638 -264.585359)
			(xy 389.345927 -264.544696) (xy 389.333486 -264.522458) (xy 389.328808 -264.514601) (xy 389.315032 -264.502595)
			(xy 389.297919 -264.496188) (xy 389.288782 -264.495788) (xy 389.020812 -264.495788) (xy 389.011672 -264.496167)
			(xy 388.994553 -264.502579) (xy 388.980773 -264.51459) (xy 388.976108 -264.522458) (xy 388.96364 -264.54468)
			(xy 388.932932 -264.58534) (xy 388.896352 -264.620809) (xy 388.854763 -264.650246) (xy 388.809152 -264.672957)
			(xy 388.760596 -264.688403) (xy 388.710246 -264.696218) (xy 388.659294 -264.696218) (xy 388.608944 -264.688403)
			(xy 388.560388 -264.672957) (xy 388.514777 -264.650246) (xy 388.473188 -264.620809) (xy 388.436608 -264.58534)
			(xy 388.4059 -264.54468) (xy 388.393432 -264.522458) (xy 388.388756 -264.514596) (xy 388.374982 -264.502578)
			(xy 388.357868 -264.496155) (xy 388.348728 -264.495788) (xy 388.080758 -264.495788) (xy 388.071623 -264.496176)
			(xy 388.054519 -264.502599) (xy 388.040754 -264.514614) (xy 388.036054 -264.522458) (xy 388.023586 -264.54468)
			(xy 387.992878 -264.58534) (xy 387.956298 -264.620809) (xy 387.914709 -264.650246) (xy 387.869098 -264.672957)
			(xy 387.820542 -264.688403) (xy 387.770192 -264.696218) (xy 387.71924 -264.696218) (xy 387.66889 -264.688403)
			(xy 387.620334 -264.672957) (xy 387.574723 -264.650246) (xy 387.533134 -264.620809) (xy 387.496554 -264.58534)
			(xy 387.465846 -264.54468) (xy 387.453378 -264.522458) (xy 387.448699 -264.514602) (xy 387.434923 -264.502598)
			(xy 387.41781 -264.496193) (xy 387.408674 -264.495788) (xy 387.140958 -264.495788) (xy 387.131823 -264.496176)
			(xy 387.114719 -264.502599) (xy 387.100954 -264.514614) (xy 387.096254 -264.522458) (xy 387.083786 -264.54468)
			(xy 387.053078 -264.58534) (xy 387.016498 -264.620809) (xy 386.974909 -264.650246) (xy 386.929298 -264.672957)
			(xy 386.880742 -264.688403) (xy 386.830392 -264.696218) (xy 386.77944 -264.696218) (xy 386.72909 -264.688403)
			(xy 386.680534 -264.672957) (xy 386.634923 -264.650246) (xy 386.593334 -264.620809) (xy 386.556754 -264.58534)
			(xy 386.526046 -264.54468) (xy 386.513578 -264.522458) (xy 386.508899 -264.514602) (xy 386.495123 -264.502598)
			(xy 386.47801 -264.496193) (xy 386.468874 -264.495788) (xy 386.200904 -264.495788) (xy 386.191765 -264.496169)
			(xy 386.174648 -264.502582) (xy 386.160871 -264.514594) (xy 386.1562 -264.522458) (xy 386.143732 -264.54468)
			(xy 386.113024 -264.58534) (xy 386.076444 -264.620809) (xy 386.034855 -264.650246) (xy 385.989244 -264.672957)
			(xy 385.940688 -264.688403) (xy 385.890338 -264.696218) (xy 385.839386 -264.696218) (xy 385.789036 -264.688403)
			(xy 385.74048 -264.672957) (xy 385.694869 -264.650246) (xy 385.65328 -264.620809) (xy 385.6167 -264.58534)
			(xy 385.585992 -264.54468) (xy 385.573524 -264.522458) (xy 385.568847 -264.514597) (xy 385.555073 -264.502581)
			(xy 385.537959 -264.496161) (xy 385.52882 -264.495788) (xy 385.26085 -264.495788) (xy 385.251716 -264.496178)
			(xy 385.234614 -264.502602) (xy 385.220851 -264.514617) (xy 385.216146 -264.522458) (xy 385.203679 -264.544681)
			(xy 385.172972 -264.585342) (xy 385.136391 -264.620812) (xy 385.094803 -264.650252) (xy 385.049191 -264.672964)
			(xy 385.000635 -264.688411) (xy 384.950285 -264.696228) (xy 384.924808 -264.696702) (xy 384.898818 -264.696219)
			(xy 384.847479 -264.688089) (xy 384.798044 -264.672028) (xy 384.75173 -264.64843) (xy 384.709678 -264.617878)
			(xy 384.672923 -264.581123) (xy 384.642371 -264.539071) (xy 384.618773 -264.492758) (xy 384.602711 -264.443323)
			(xy 384.594581 -264.391983) (xy 384.5941 -264.365994) (xy 384.594526 -264.342668) (xy 384.601123 -264.296485)
			(xy 384.61413 -264.251682) (xy 384.633291 -264.209146) (xy 384.645408 -264.18921) (xy 384.653028 -264.177018)
			(xy 384.653536 -264.149332) (xy 384.508756 -263.899142) (xy 384.483864 -263.88568) (xy 384.46964 -263.886442)
			(xy 384.454908 -263.886696) (xy 384.42943 -263.886227) (xy 384.379078 -263.878412) (xy 384.33052 -263.862966)
			(xy 384.284906 -263.840254) (xy 384.243316 -263.810815) (xy 384.206734 -263.775344) (xy 384.176025 -263.734682)
			(xy 384.16357 -263.712452) (xy 384.16357 -263.712198) (xy 384.158868 -263.704304) (xy 384.14501 -263.692261)
			(xy 384.127794 -263.685882) (xy 384.118612 -263.685528) (xy 383.85115 -263.685528) (xy 383.841969 -263.685873)
			(xy 383.824758 -263.692263) (xy 383.810907 -263.704312) (xy 383.806192 -263.712198) (xy 383.806192 -263.712452)
			(xy 383.793724 -263.734674) (xy 383.763016 -263.775334) (xy 383.726436 -263.810803) (xy 383.684847 -263.84024)
			(xy 383.639236 -263.862951) (xy 383.59068 -263.878397) (xy 383.54033 -263.886212) (xy 383.489378 -263.886212)
			(xy 383.439028 -263.878397) (xy 383.390472 -263.862951) (xy 383.344861 -263.84024) (xy 383.303272 -263.810803)
			(xy 383.266692 -263.775334) (xy 383.235984 -263.734674) (xy 383.223516 -263.712452) (xy 383.223516 -263.712198)
			(xy 383.218816 -263.704299) (xy 383.20496 -263.692243) (xy 383.187743 -263.685849) (xy 383.178558 -263.685528)
			(xy 382.911096 -263.685528) (xy 382.901911 -263.685865) (xy 382.884688 -263.692245) (xy 382.870823 -263.704291)
			(xy 382.866138 -263.712198) (xy 382.866138 -263.712452) (xy 382.85367 -263.734674) (xy 382.822962 -263.775334)
			(xy 382.786382 -263.810803) (xy 382.744793 -263.84024) (xy 382.699182 -263.862951) (xy 382.650626 -263.878397)
			(xy 382.600276 -263.886212) (xy 382.549324 -263.886212) (xy 382.498974 -263.878397) (xy 382.450418 -263.862951)
			(xy 382.404807 -263.84024) (xy 382.363218 -263.810803) (xy 382.326638 -263.775334) (xy 382.29593 -263.734674)
			(xy 382.283462 -263.712452) (xy 382.283462 -263.712198) (xy 382.278759 -263.704305) (xy 382.264901 -263.692264)
			(xy 382.247686 -263.685887) (xy 382.238504 -263.685528) (xy 381.971042 -263.685528) (xy 381.961862 -263.685874)
			(xy 381.944653 -263.692266) (xy 381.930804 -263.704315) (xy 381.926084 -263.712198) (xy 381.926084 -263.712452)
			(xy 381.913616 -263.734674) (xy 381.882908 -263.775334) (xy 381.846328 -263.810803) (xy 381.804739 -263.84024)
			(xy 381.759128 -263.862951) (xy 381.710572 -263.878397) (xy 381.660222 -263.886212) (xy 381.60927 -263.886212)
			(xy 381.55892 -263.878397) (xy 381.510364 -263.862951) (xy 381.464753 -263.84024) (xy 381.423164 -263.810803)
			(xy 381.386584 -263.775334) (xy 381.355876 -263.734674) (xy 381.343408 -263.712452) (xy 381.343408 -263.712198)
			(xy 381.338708 -263.7043) (xy 381.324851 -263.692246) (xy 381.307634 -263.685854) (xy 381.29845 -263.685528)
			(xy 381.031242 -263.685528) (xy 381.022062 -263.685874) (xy 381.004853 -263.692266) (xy 380.991004 -263.704315)
			(xy 380.986284 -263.712198) (xy 380.986284 -263.712452) (xy 380.973816 -263.734674) (xy 380.943108 -263.775334)
			(xy 380.906528 -263.810803) (xy 380.864939 -263.84024) (xy 380.819328 -263.862951) (xy 380.770772 -263.878397)
			(xy 380.720422 -263.886212) (xy 380.66947 -263.886212) (xy 380.61912 -263.878397) (xy 380.570564 -263.862951)
			(xy 380.524953 -263.84024) (xy 380.483364 -263.810803) (xy 380.446784 -263.775334) (xy 380.416076 -263.734674)
			(xy 380.403608 -263.712452) (xy 380.403608 -263.712198) (xy 380.398908 -263.7043) (xy 380.385051 -263.692246)
			(xy 380.367834 -263.685854) (xy 380.35865 -263.685528) (xy 380.091188 -263.685528) (xy 380.082003 -263.685866)
			(xy 380.064783 -263.692248) (xy 380.05092 -263.704295) (xy 380.04623 -263.712198) (xy 380.04623 -263.712452)
			(xy 380.033763 -263.734674) (xy 380.003055 -263.775335) (xy 379.966475 -263.810804) (xy 379.924886 -263.840242)
			(xy 379.879274 -263.862953) (xy 379.830719 -263.878398) (xy 379.780369 -263.886213) (xy 379.754892 -263.886696)
			(xy 379.728918 -263.886187) (xy 379.67761 -263.878063) (xy 379.628203 -263.862017) (xy 379.581912 -263.838442)
			(xy 379.539878 -263.80792) (xy 379.503132 -263.771201) (xy 379.47258 -263.729187) (xy 379.448973 -263.682914)
			(xy 379.432892 -263.633518) (xy 379.424732 -263.582215) (xy 379.424184 -263.556242) (xy 379.424184 -263.555734)
			(xy 379.424438 -263.544812) (xy 379.424438 -263.544558) (xy 379.424379 -263.535358) (xy 379.418498 -263.51794)
			(xy 379.406824 -263.503738) (xy 379.399038 -263.498838) (xy 378.561346 -263.017508) (xy 378.533152 -263.01827)
			(xy 378.521214 -263.02589) (xy 378.501351 -263.03791) (xy 378.458978 -263.056883) (xy 378.414372 -263.069756)
			(xy 378.368405 -263.076276) (xy 378.345192 -263.07669) (xy 378.344938 -263.07669) (xy 378.319459 -263.076223)
			(xy 378.269104 -263.068412) (xy 378.220543 -263.052969) (xy 378.174926 -263.030259) (xy 378.133333 -263.000821)
			(xy 378.096747 -262.965351) (xy 378.066036 -262.924688) (xy 378.0536 -262.902446) (xy 378.048921 -262.894589)
			(xy 378.035145 -262.882582) (xy 378.018033 -262.876172) (xy 378.008896 -262.875776) (xy 377.740926 -262.875776)
			(xy 377.731784 -262.876153) (xy 377.714661 -262.88256) (xy 377.700875 -262.894569) (xy 377.696222 -262.902446)
			(xy 377.683754 -262.924668) (xy 377.653046 -262.965328) (xy 377.616466 -263.000797) (xy 377.574877 -263.030234)
			(xy 377.529266 -263.052945) (xy 377.48071 -263.068391) (xy 377.43036 -263.076206) (xy 377.379408 -263.076206)
			(xy 377.329058 -263.068391) (xy 377.280502 -263.052945) (xy 377.234891 -263.030234) (xy 377.193302 -263.000797)
			(xy 377.156722 -262.965328) (xy 377.126014 -262.924668) (xy 377.113546 -262.902446) (xy 377.108869 -262.894584)
			(xy 377.095096 -262.882564) (xy 377.077982 -262.876139) (xy 377.068842 -262.875776) (xy 376.800872 -262.875776)
			(xy 376.791735 -262.876162) (xy 376.774626 -262.882581) (xy 376.760855 -262.894593) (xy 376.756168 -262.902446)
			(xy 376.7437 -262.924668) (xy 376.712992 -262.965328) (xy 376.676412 -263.000797) (xy 376.634823 -263.030234)
			(xy 376.589212 -263.052945) (xy 376.540656 -263.068391) (xy 376.490306 -263.076206) (xy 376.439354 -263.076206)
			(xy 376.389004 -263.068391) (xy 376.340448 -263.052945) (xy 376.294837 -263.030234) (xy 376.253248 -263.000797)
			(xy 376.216668 -262.965328) (xy 376.18596 -262.924668) (xy 376.173492 -262.902446) (xy 376.168813 -262.89459)
			(xy 376.155037 -262.882585) (xy 376.137924 -262.876177) (xy 376.128788 -262.875776) (xy 375.860818 -262.875776)
			(xy 375.851677 -262.876154) (xy 375.834556 -262.882563) (xy 375.820772 -262.894573) (xy 375.816114 -262.902446)
			(xy 375.803664 -262.924636) (xy 375.773006 -262.965244) (xy 375.736492 -263.000678) (xy 375.694983 -263.030103)
			(xy 375.649458 -263.052825) (xy 375.60099 -263.068308) (xy 375.550723 -263.076188) (xy 375.525284 -263.07669)
			(xy 375.524268 -263.07669) (xy 375.515378 -263.076436) (xy 375.501408 -263.076182) (xy 375.477278 -263.08939)
			(xy 375.336562 -263.331706) (xy 375.332277 -263.339791) (xy 375.329187 -263.357813) (xy 375.332638 -263.375769)
			(xy 375.33707 -263.383776) (xy 375.348572 -263.403301) (xy 375.366709 -263.444828) (xy 375.379003 -263.488444)
			(xy 375.385223 -263.533331) (xy 375.385584 -263.555988) (xy 375.385102 -263.581977) (xy 375.376972 -263.633316)
			(xy 375.36091 -263.68275) (xy 375.337313 -263.729064) (xy 375.30676 -263.771115) (xy 375.270006 -263.807868)
			(xy 375.227953 -263.838419) (xy 375.181639 -263.862015) (xy 375.132204 -263.878075) (xy 375.080865 -263.886203)
			(xy 375.054876 -263.886696) (xy 375.028903 -263.886186) (xy 374.977597 -263.87806) (xy 374.928192 -263.862012)
			(xy 374.881904 -263.838437) (xy 374.839871 -263.807914) (xy 374.803127 -263.771195) (xy 374.772577 -263.729183)
			(xy 374.748971 -263.68291) (xy 374.732891 -263.633516) (xy 374.724732 -263.582215) (xy 374.724168 -263.556242)
			(xy 374.724168 -263.555734) (xy 374.724422 -263.544558) (xy 374.72493 -263.530334) (xy 374.711468 -263.50595)
			(xy 373.86133 -263.017508) (xy 373.833136 -263.01827) (xy 373.821198 -263.02589) (xy 373.801335 -263.037909)
			(xy 373.758962 -263.05688) (xy 373.714355 -263.069751) (xy 373.668389 -263.076269) (xy 373.645176 -263.07669)
			(xy 373.644668 -263.07669) (xy 373.635524 -263.076436) (xy 373.626414 -263.076578) (xy 373.609204 -263.082523)
			(xy 373.595178 -263.094132) (xy 373.590312 -263.101836) (xy 373.449596 -263.344152) (xy 373.44985 -263.372092)
			(xy 373.457216 -263.383776) (xy 373.468644 -263.403294) (xy 373.486679 -263.444771) (xy 373.4989 -263.488316)
			(xy 373.50508 -263.53312) (xy 373.505476 -263.555734) (xy 373.505476 -263.555988) (xy 373.504994 -263.581977)
			(xy 373.496864 -263.633315) (xy 373.480802 -263.682749) (xy 373.457205 -263.729062) (xy 373.426652 -263.771112)
			(xy 373.389897 -263.807865) (xy 373.347845 -263.838415) (xy 373.301531 -263.86201) (xy 373.252096 -263.878068)
			(xy 373.200757 -263.886195) (xy 373.174768 -263.886696) (xy 373.148795 -263.886185) (xy 373.09749 -263.878058)
			(xy 373.048086 -263.86201) (xy 373.001799 -263.838434) (xy 372.959767 -263.807912) (xy 372.923025 -263.771192)
			(xy 372.892476 -263.72918) (xy 372.868871 -263.682908) (xy 372.852791 -263.633514) (xy 372.844632 -263.582214)
			(xy 372.84406 -263.556242) (xy 372.84406 -263.555734) (xy 372.844314 -263.544558) (xy 372.844822 -263.530334)
			(xy 372.83136 -263.50595) (xy 371.993414 -263.02462) (xy 371.985256 -263.020355) (xy 371.967103 -263.017388)
			(xy 371.94908 -263.021063) (xy 371.94109 -263.025636) (xy 371.921213 -263.037714) (xy 371.878791 -263.056781)
			(xy 371.834116 -263.069716) (xy 371.788069 -263.076263) (xy 371.764814 -263.07669) (xy 371.738839 -263.076182)
			(xy 371.687529 -263.068061) (xy 371.638119 -263.052017) (xy 371.591826 -263.028444) (xy 371.549789 -262.997922)
			(xy 371.513041 -262.961202) (xy 371.482487 -262.919187) (xy 371.458879 -262.872912) (xy 371.442797 -262.823515)
			(xy 371.434637 -262.77221) (xy 371.434106 -262.746236) (xy 371.434106 -262.745728) (xy 371.43436 -262.734552)
			(xy 371.434868 -262.720328) (xy 371.421406 -262.695944) (xy 370.571268 -262.207502) (xy 370.543074 -262.208264)
			(xy 370.531136 -262.215884) (xy 370.511274 -262.227906) (xy 370.468901 -262.246882) (xy 370.424295 -262.259758)
			(xy 370.378328 -262.266282) (xy 370.355114 -262.266684) (xy 370.354606 -262.266684) (xy 370.345462 -262.26643)
			(xy 370.336348 -262.266566) (xy 370.319128 -262.272502) (xy 370.30509 -262.284107) (xy 370.30025 -262.29183)
			(xy 370.159534 -262.534146) (xy 370.159788 -262.562086) (xy 370.167154 -262.57377) (xy 370.178581 -262.593288)
			(xy 370.196615 -262.634765) (xy 370.208835 -262.678311) (xy 370.215015 -262.723114) (xy 370.215414 -262.745728)
			(xy 370.215414 -262.745982) (xy 370.214932 -262.771972) (xy 370.206803 -262.823313) (xy 370.190743 -262.872751)
			(xy 370.167146 -262.919067) (xy 370.136594 -262.961121) (xy 370.09984 -262.997879) (xy 370.057787 -263.028433)
			(xy 370.011473 -263.052033) (xy 369.962037 -263.068098) (xy 369.910696 -263.07623) (xy 369.884706 -263.07669)
			(xy 369.858732 -263.076182) (xy 369.807422 -263.06806) (xy 369.758013 -263.052015) (xy 369.711722 -263.028441)
			(xy 369.669685 -262.997919) (xy 369.632939 -262.961199) (xy 369.602386 -262.919185) (xy 369.578778 -262.87291)
			(xy 369.562697 -262.823514) (xy 369.554537 -262.77221) (xy 369.553998 -262.746236) (xy 369.553998 -262.745728)
			(xy 369.554252 -262.734552) (xy 369.55476 -262.720328) (xy 369.541298 -262.695944) (xy 368.405918 -262.043672)
			(xy 368.39525 -262.035544) (xy 368.172492 -261.812786) (xy 368.165097 -261.805932) (xy 368.146498 -261.798186)
			(xy 368.136424 -261.7978) (xy 364.453424 -261.7978) (xy 364.44336 -261.797363) (xy 364.424776 -261.789629)
			(xy 364.417356 -261.782814) (xy 364.305596 -261.671054) (xy 364.277148 -261.664704) (xy 364.263178 -261.669784)
			(xy 364.232941 -261.679955) (xy 364.170104 -261.690938) (xy 364.13821 -261.691628) (xy 364.137956 -261.691628)
			(xy 364.111859 -261.691172) (xy 364.060187 -261.683806) (xy 364.01007 -261.669226) (xy 363.962509 -261.647725)
			(xy 363.918457 -261.619731) (xy 363.878792 -261.585805) (xy 363.844308 -261.546625) (xy 363.815693 -261.502973)
			(xy 363.8042 -261.479538) (xy 363.79785 -261.466076) (xy 363.773212 -261.450328) (xy 363.567726 -261.450328)
			(xy 363.558106 -261.450736) (xy 363.540217 -261.457819) (xy 363.526198 -261.470998) (xy 363.521752 -261.479538)
			(xy 363.509473 -261.504532) (xy 363.478521 -261.550823) (xy 363.440958 -261.591931) (xy 363.39764 -261.626922)
			(xy 363.349551 -261.654999) (xy 363.297786 -261.675523) (xy 363.243523 -261.688028) (xy 363.187996 -261.692227)
			(xy 363.132469 -261.688028) (xy 363.078206 -261.675523) (xy 363.026441 -261.654999) (xy 362.978352 -261.626922)
			(xy 362.935034 -261.591931) (xy 362.897471 -261.550823) (xy 362.866519 -261.504532) (xy 362.85424 -261.479538)
			(xy 362.84789 -261.466076) (xy 362.823252 -261.450328) (xy 362.617766 -261.450328) (xy 362.608152 -261.450746)
			(xy 362.59028 -261.457842) (xy 362.57628 -261.471023) (xy 362.571792 -261.479538) (xy 362.559513 -261.504532)
			(xy 362.528561 -261.550823) (xy 362.490998 -261.591931) (xy 362.44768 -261.626922) (xy 362.399591 -261.654999)
			(xy 362.347826 -261.675523) (xy 362.293563 -261.688028) (xy 362.238036 -261.692227) (xy 362.182509 -261.688028)
			(xy 362.128246 -261.675523) (xy 362.076481 -261.654999) (xy 362.028392 -261.626922) (xy 361.985074 -261.591931)
			(xy 361.947511 -261.550823) (xy 361.916559 -261.504532) (xy 361.90428 -261.479538) (xy 361.89793 -261.466076)
			(xy 361.873292 -261.450328) (xy 361.667806 -261.450328) (xy 361.658188 -261.45074) (xy 361.640304 -261.457827)
			(xy 361.626292 -261.471006) (xy 361.621832 -261.479538) (xy 361.609553 -261.504532) (xy 361.578601 -261.550823)
			(xy 361.541038 -261.591931) (xy 361.49772 -261.626922) (xy 361.449631 -261.654999) (xy 361.397866 -261.675523)
			(xy 361.343603 -261.688028) (xy 361.288076 -261.692227) (xy 361.232549 -261.688028) (xy 361.178286 -261.675523)
			(xy 361.126521 -261.654999) (xy 361.078432 -261.626922) (xy 361.035114 -261.591931) (xy 360.997551 -261.550823)
			(xy 360.966599 -261.504532) (xy 360.95432 -261.479538) (xy 360.94797 -261.466076) (xy 360.923332 -261.450328)
			(xy 360.717592 -261.450328) (xy 360.707975 -261.450742) (xy 360.690096 -261.457832) (xy 360.676088 -261.471012)
			(xy 360.671618 -261.479538) (xy 360.659339 -261.504532) (xy 360.628387 -261.550823) (xy 360.590824 -261.591931)
			(xy 360.547506 -261.626922) (xy 360.499417 -261.654999) (xy 360.447652 -261.675523) (xy 360.393389 -261.688028)
			(xy 360.337862 -261.692227) (xy 360.282335 -261.688028) (xy 360.228072 -261.675523) (xy 360.176307 -261.654999)
			(xy 360.128218 -261.626922) (xy 360.0849 -261.591931) (xy 360.047337 -261.550823) (xy 360.016385 -261.504532)
			(xy 360.004106 -261.479538) (xy 359.997756 -261.466076) (xy 359.973118 -261.450328) (xy 359.767632 -261.450328)
			(xy 359.758011 -261.450735) (xy 359.74012 -261.457817) (xy 359.7261 -261.470995) (xy 359.721658 -261.479538)
			(xy 359.709379 -261.504532) (xy 359.678427 -261.550823) (xy 359.640864 -261.591931) (xy 359.597546 -261.626922)
			(xy 359.549457 -261.654999) (xy 359.497692 -261.675523) (xy 359.443429 -261.688028) (xy 359.387902 -261.692227)
			(xy 359.332375 -261.688028) (xy 359.278112 -261.675523) (xy 359.226347 -261.654999) (xy 359.178258 -261.626922)
			(xy 359.13494 -261.591931) (xy 359.097377 -261.550823) (xy 359.066425 -261.504532) (xy 359.054146 -261.479538)
			(xy 359.047796 -261.466076) (xy 359.023158 -261.450328) (xy 358.817672 -261.450328) (xy 358.808057 -261.450745)
			(xy 358.790184 -261.45784) (xy 358.776181 -261.471021) (xy 358.771698 -261.479538) (xy 358.759419 -261.504532)
			(xy 358.728467 -261.550823) (xy 358.690904 -261.591931) (xy 358.647586 -261.626922) (xy 358.599497 -261.654999)
			(xy 358.547732 -261.675523) (xy 358.493469 -261.688028) (xy 358.437942 -261.692227) (xy 358.382415 -261.688028)
			(xy 358.328152 -261.675523) (xy 358.276387 -261.654999) (xy 358.228298 -261.626922) (xy 358.18498 -261.591931)
			(xy 358.147417 -261.550823) (xy 358.116465 -261.504532) (xy 358.104186 -261.479538) (xy 358.097836 -261.466076)
			(xy 358.073198 -261.450328) (xy 357.867712 -261.450328) (xy 357.858093 -261.450739) (xy 357.840208 -261.457825)
			(xy 357.826194 -261.471004) (xy 357.821738 -261.479538) (xy 357.809459 -261.504532) (xy 357.778507 -261.550823)
			(xy 357.740944 -261.591931) (xy 357.697626 -261.626922) (xy 357.649537 -261.654999) (xy 357.597772 -261.675523)
			(xy 357.543509 -261.688028) (xy 357.487982 -261.692227) (xy 357.432455 -261.688028) (xy 357.378192 -261.675523)
			(xy 357.326427 -261.654999) (xy 357.278338 -261.626922) (xy 357.23502 -261.591931) (xy 357.197457 -261.550823)
			(xy 357.166505 -261.504532) (xy 357.154226 -261.479538) (xy 357.147876 -261.466076) (xy 357.123238 -261.450328)
			(xy 356.917752 -261.450328) (xy 356.908129 -261.450732) (xy 356.890232 -261.457809) (xy 356.876206 -261.470987)
			(xy 356.871778 -261.479538) (xy 356.859499 -261.504532) (xy 356.828547 -261.550823) (xy 356.790984 -261.591931)
			(xy 356.747666 -261.626922) (xy 356.699577 -261.654999) (xy 356.647812 -261.675523) (xy 356.593549 -261.688028)
			(xy 356.538022 -261.692227) (xy 356.482495 -261.688028) (xy 356.428232 -261.675523) (xy 356.376467 -261.654999)
			(xy 356.328378 -261.626922) (xy 356.28506 -261.591931) (xy 356.247497 -261.550823) (xy 356.216545 -261.504532)
			(xy 356.204266 -261.479538) (xy 356.197916 -261.466076) (xy 356.173278 -261.450328) (xy 355.967792 -261.450328)
			(xy 355.958175 -261.450742) (xy 355.940296 -261.457832) (xy 355.926288 -261.471012) (xy 355.921818 -261.479538)
			(xy 355.909539 -261.504532) (xy 355.878587 -261.550823) (xy 355.841024 -261.591931) (xy 355.797706 -261.626922)
			(xy 355.749617 -261.654999) (xy 355.697852 -261.675523) (xy 355.643589 -261.688028) (xy 355.588062 -261.692227)
			(xy 355.532535 -261.688028) (xy 355.478272 -261.675523) (xy 355.426507 -261.654999) (xy 355.378418 -261.626922)
			(xy 355.3351 -261.591931) (xy 355.297537 -261.550823) (xy 355.266585 -261.504532) (xy 355.254306 -261.479538)
			(xy 355.247956 -261.466076) (xy 355.223318 -261.450328) (xy 354.66528 -261.450328) (xy 354.65424 -261.450937)
			(xy 354.634233 -261.460293) (xy 354.626672 -261.468362) (xy 354.609059 -261.488427) (xy 354.569045 -261.523772)
			(xy 354.524356 -261.552983) (xy 354.475924 -261.575451) (xy 354.424761 -261.590707) (xy 354.371934 -261.598433)
			(xy 354.34524 -261.598918) (xy 354.344986 -261.598918) (xy 354.319306 -261.598496) (xy 354.268444 -261.591357)
			(xy 354.24364 -261.584694) (xy 354.234784 -261.582505) (xy 354.216603 -261.583841) (xy 354.200033 -261.591442)
			(xy 354.193348 -261.597648) (xy 353.789742 -262.001508) (xy 353.783197 -262.008567) (xy 353.7755 -262.026196)
			(xy 353.774888 -262.045421) (xy 353.777804 -262.054594) (xy 353.777804 -262.054848) (xy 353.787972 -262.085085)
			(xy 353.79895 -262.147922) (xy 353.799648 -262.179816) (xy 353.799648 -262.18007) (xy 353.79918 -262.206416)
			(xy 353.791686 -262.258574) (xy 353.776845 -262.309133) (xy 353.754959 -262.357067) (xy 353.726476 -262.401397)
			(xy 353.691973 -262.441223) (xy 353.652153 -262.475734) (xy 353.607828 -262.504226) (xy 353.559899 -262.52612)
			(xy 353.509342 -262.540971) (xy 353.457186 -262.548475) (xy 353.43084 -262.548878) (xy 353.400238 -262.548271)
			(xy 353.339875 -262.538162) (xy 353.282007 -262.518232) (xy 353.254818 -262.504174) (xy 353.241864 -262.497062)
			(xy 353.212654 -262.499094) (xy 351.62998 -263.66343) (xy 351.625154 -263.666732) (xy 350.4946 -264.315956)
			(xy 350.481138 -264.34034) (xy 350.481646 -264.354564) (xy 350.4819 -264.36574) (xy 350.4819 -264.366248)
			(xy 350.481372 -264.392222) (xy 350.473211 -264.443526) (xy 350.457128 -264.492923) (xy 350.433518 -264.539198)
			(xy 350.402964 -264.581211) (xy 350.366216 -264.617931) (xy 350.324179 -264.648452) (xy 350.277886 -264.672026)
			(xy 350.228477 -264.68807) (xy 350.177167 -264.696192) (xy 350.151192 -264.696702) (xy 350.125205 -264.696192)
			(xy 350.073872 -264.68806) (xy 350.024443 -264.671998) (xy 349.978135 -264.648402) (xy 349.936089 -264.617852)
			(xy 349.899339 -264.581101) (xy 349.868791 -264.539053) (xy 349.845196 -264.492744) (xy 349.829136 -264.443314)
			(xy 349.821007 -264.391981) (xy 349.820484 -264.365994) (xy 349.820484 -264.36574) (xy 349.820852 -264.343124)
			(xy 349.827019 -264.298313) (xy 349.839242 -264.254763) (xy 349.857293 -264.213289) (xy 349.868744 -264.193782)
			(xy 349.868744 -264.193528) (xy 349.873158 -264.185564) (xy 349.876578 -264.167695) (xy 349.873505 -264.149763)
			(xy 349.869252 -264.141712) (xy 349.735902 -263.911842) (xy 349.73102 -263.904156) (xy 349.716984 -263.892576)
			(xy 349.699794 -263.886611) (xy 349.69069 -263.886442) (xy 349.681292 -263.886696) (xy 349.680784 -263.886696)
			(xy 349.657642 -263.886294) (xy 349.611813 -263.879812) (xy 349.567336 -263.867005) (xy 349.525078 -263.848123)
			(xy 349.50527 -263.83615) (xy 349.497272 -263.831617) (xy 349.479262 -263.827997) (xy 349.461129 -263.830941)
			(xy 349.452946 -263.835134) (xy 348.614492 -264.316464) (xy 348.60103 -264.340848) (xy 348.601538 -264.355072)
			(xy 348.601792 -264.365994) (xy 348.601538 -264.381234) (xy 348.600776 -264.395458) (xy 348.614492 -264.420604)
			(xy 349.461328 -264.907014) (xy 349.489522 -264.906252) (xy 349.50146 -264.898378) (xy 349.521621 -264.885833)
			(xy 349.56477 -264.866012) (xy 349.610306 -264.852551) (xy 349.657297 -264.845725) (xy 349.681038 -264.845292)
			(xy 349.707023 -264.845804) (xy 349.758353 -264.85394) (xy 349.807779 -264.870004) (xy 349.854083 -264.893602)
			(xy 349.896126 -264.924152) (xy 349.932872 -264.960903) (xy 349.963418 -265.00295) (xy 349.987011 -265.049257)
			(xy 350.003069 -265.098684) (xy 350.011199 -265.150015) (xy 350.011199 -265.201985) (xy 350.003069 -265.253316)
			(xy 349.987011 -265.302743) (xy 349.963418 -265.34905) (xy 349.932872 -265.391097) (xy 349.896126 -265.427848)
			(xy 349.854083 -265.458398) (xy 349.807779 -265.481996) (xy 349.758353 -265.49806) (xy 349.707023 -265.506196)
			(xy 349.681038 -265.506708) (xy 349.657864 -265.506321) (xy 349.611969 -265.499857) (xy 349.567425 -265.48705)
			(xy 349.525106 -265.468151) (xy 349.50527 -265.456162) (xy 349.497272 -265.451628) (xy 349.479262 -265.448008)
			(xy 349.461129 -265.450952) (xy 349.452946 -265.455146) (xy 348.614492 -265.936476) (xy 348.60103 -265.96086)
			(xy 348.601538 -265.975084) (xy 348.601792 -265.986006) (xy 348.601538 -266.001246) (xy 348.600776 -266.01547)
			(xy 348.614492 -266.040616) (xy 349.448628 -266.51966) (xy 349.456909 -266.524031) (xy 349.475396 -266.526932)
			(xy 349.49368 -266.522949) (xy 349.501714 -266.518136) (xy 349.52185 -266.505624) (xy 349.564942 -266.485869)
			(xy 349.610415 -266.472471) (xy 349.657335 -266.465705) (xy 349.681038 -266.465304) (xy 349.707023 -266.465816)
			(xy 349.758352 -266.473952) (xy 349.807777 -266.490016) (xy 349.85408 -266.513614) (xy 349.896122 -266.544165)
			(xy 349.932868 -266.580916) (xy 349.963412 -266.622963) (xy 349.987003 -266.669269) (xy 350.00306 -266.718697)
			(xy 350.011188 -266.770027) (xy 350.011746 -266.796012) (xy 350.011263 -266.821643) (xy 350.003352 -266.872292)
			(xy 349.995998 -266.89685) (xy 349.995998 -266.897104) (xy 349.993546 -266.906071) (xy 349.994563 -266.924616)
			(xy 350.002156 -266.941566) (xy 350.008444 -266.948412) (xy 350.258126 -267.198094) (xy 350.265526 -267.204937)
			(xy 350.284124 -267.212663) (xy 350.294194 -267.21308) (xy 350.5708 -267.21308) (xy 350.577468 -267.212886)
			(xy 350.590344 -267.209416) (xy 350.5962 -267.206222) (xy 351.217738 -266.848082) (xy 351.2312 -266.823444)
			(xy 351.230692 -266.80922) (xy 351.230438 -266.796012) (xy 351.23092 -266.770023) (xy 351.23905 -266.718686)
			(xy 351.255112 -266.669253) (xy 351.27871 -266.622941) (xy 351.309263 -266.580892) (xy 351.346018 -266.544141)
			(xy 351.38807 -266.513592) (xy 351.434384 -266.489999) (xy 351.483819 -266.473942) (xy 351.535157 -266.465818)
			(xy 351.561146 -266.465304) (xy 351.573338 -266.465558) (xy 351.582506 -266.465494) (xy 351.599876 -266.459669)
			(xy 351.614102 -266.448125) (xy 351.619058 -266.440412) (xy 351.751138 -266.213082) (xy 351.755461 -266.204947)
			(xy 351.758543 -266.1868) (xy 351.754963 -266.168745) (xy 351.750376 -266.160758) (xy 351.738523 -266.141009)
			(xy 351.719807 -266.098925) (xy 351.707124 -266.054647) (xy 351.700719 -266.009035) (xy 351.700338 -265.986006)
			(xy 351.700821 -265.960018) (xy 351.708952 -265.908681) (xy 351.725014 -265.859249) (xy 351.748612 -265.812938)
			(xy 351.779165 -265.77089) (xy 351.81592 -265.734139) (xy 351.857972 -265.703591) (xy 351.904286 -265.679998)
			(xy 351.95372 -265.663942) (xy 352.005058 -265.655818) (xy 352.031046 -265.655298) (xy 352.057018 -265.65581)
			(xy 352.108322 -265.663938) (xy 352.157724 -265.679988) (xy 352.20401 -265.703564) (xy 352.24604 -265.734087)
			(xy 352.282781 -265.770806) (xy 352.31333 -265.812818) (xy 352.336934 -265.859089) (xy 352.353014 -265.908481)
			(xy 352.361174 -265.95978) (xy 352.361754 -265.985752) (xy 352.361754 -265.98626) (xy 352.3615 -266.001246)
			(xy 352.360738 -266.01547) (xy 352.374454 -266.040616) (xy 353.221036 -266.526772) (xy 353.249484 -266.52601)
			(xy 353.261422 -266.518136) (xy 353.28153 -266.50564) (xy 353.324561 -266.485904) (xy 353.369968 -266.472507)
			(xy 353.416821 -266.465725) (xy 353.440492 -266.465304) (xy 353.441 -266.465304) (xy 353.466989 -266.465787)
			(xy 353.518327 -266.473918) (xy 353.567761 -266.489981) (xy 353.614073 -266.513579) (xy 353.656123 -266.544131)
			(xy 353.692877 -266.580886) (xy 353.723427 -266.622937) (xy 353.747024 -266.669251) (xy 353.763084 -266.718685)
			(xy 353.771214 -266.770023) (xy 353.771708 -266.796012) (xy 353.771708 -266.796266) (xy 353.771295 -266.819781)
			(xy 353.764627 -266.866335) (xy 353.751421 -266.911472) (xy 353.731946 -266.954279) (xy 353.719638 -266.97432)
			(xy 353.712018 -266.986258) (xy 353.711256 -267.014706) (xy 353.848162 -267.250672) (xy 353.853192 -267.258501)
			(xy 353.86766 -267.270179) (xy 353.885341 -267.275931) (xy 353.894644 -267.275818) (xy 353.9109 -267.27531)
			(xy 353.911408 -267.27531) (xy 353.934809 -267.275717) (xy 353.981141 -267.282321) (xy 354.026079 -267.295395)
			(xy 354.068723 -267.314678) (xy 354.0887 -267.326872) (xy 354.100638 -267.334492) (xy 354.128832 -267.335254)
			(xy 354.9777 -266.847574) (xy 354.991162 -266.822936) (xy 354.990654 -266.808712) (xy 354.9904 -266.796012)
			(xy 354.990882 -266.770022) (xy 354.999012 -266.718683) (xy 355.015073 -266.669247) (xy 355.038671 -266.622933)
			(xy 355.069223 -266.58088) (xy 355.105977 -266.544125) (xy 355.148029 -266.513573) (xy 355.194343 -266.489975)
			(xy 355.243779 -266.473913) (xy 355.295118 -266.465783) (xy 355.321108 -266.465304) (xy 355.3333 -266.465558)
			(xy 355.342462 -266.465484) (xy 355.359816 -266.459644) (xy 355.374024 -266.448095) (xy 355.37902 -266.440412)
			(xy 355.5111 -266.213082) (xy 355.515419 -266.204946) (xy 355.518497 -266.1868) (xy 355.514921 -266.168746)
			(xy 355.510338 -266.160758) (xy 355.498486 -266.141009) (xy 355.479772 -266.098924) (xy 355.46709 -266.054646)
			(xy 355.460687 -266.009035) (xy 355.4603 -265.986006) (xy 355.460783 -265.960017) (xy 355.468913 -265.908678)
			(xy 355.484975 -265.859243) (xy 355.508573 -265.81293) (xy 355.539125 -265.770878) (xy 355.575879 -265.734124)
			(xy 355.617931 -265.703572) (xy 355.664245 -265.679974) (xy 355.71368 -265.663913) (xy 355.765019 -265.655783)
			(xy 355.791008 -265.655298) (xy 355.816982 -265.655807) (xy 355.868291 -265.663931) (xy 355.917698 -265.679977)
			(xy 355.963989 -265.703551) (xy 356.006024 -265.734074) (xy 356.04277 -265.770793) (xy 356.073323 -265.812806)
			(xy 356.096931 -265.85908) (xy 356.113013 -265.908476) (xy 356.121174 -265.959778) (xy 356.121716 -265.985752)
			(xy 356.121716 -265.98626) (xy 356.121462 -266.001246) (xy 356.1207 -266.01547) (xy 356.134416 -266.040616)
			(xy 356.968806 -266.519914) (xy 356.97704 -266.524139) (xy 356.995315 -266.526956) (xy 357.013389 -266.523056)
			(xy 357.021384 -266.51839) (xy 357.021638 -266.51839) (xy 357.041798 -266.505843) (xy 357.084947 -266.486019)
			(xy 357.130483 -266.472555) (xy 357.177474 -266.465725) (xy 357.201216 -266.465304) (xy 357.227202 -266.465815)
			(xy 357.278534 -266.473947) (xy 357.327962 -266.49001) (xy 357.374268 -266.513607) (xy 357.416313 -266.544157)
			(xy 357.453061 -266.580908) (xy 357.483608 -266.622956) (xy 357.507201 -266.669264) (xy 357.523259 -266.718693)
			(xy 357.531387 -266.770026) (xy 357.531924 -266.796012) (xy 357.531474 -266.819535) (xy 357.524739 -266.866098)
			(xy 357.511476 -266.911238) (xy 357.491955 -266.954044) (xy 357.4796 -266.974066) (xy 357.4796 -266.974574)
			(xy 357.474986 -266.982596) (xy 357.471284 -267.000712) (xy 357.474282 -267.018959) (xy 357.478584 -267.027152)
			(xy 357.608124 -267.250672) (xy 357.613157 -267.258494) (xy 357.627627 -267.270154) (xy 357.645305 -267.275885)
			(xy 357.654606 -267.275818) (xy 357.670862 -267.27531) (xy 357.67137 -267.27531) (xy 357.694771 -267.275714)
			(xy 357.741106 -267.282313) (xy 357.786047 -267.295383) (xy 357.828694 -267.314662) (xy 357.848662 -267.326872)
			(xy 357.8606 -267.334492) (xy 357.888794 -267.335254) (xy 359.03281 -266.677902) (xy 359.038628 -266.674782)
			(xy 359.05136 -266.671306) (xy 359.057956 -266.671044) (xy 359.74274 -266.671044) (xy 359.748971 -266.670833)
			(xy 359.761047 -266.66775) (xy 359.766616 -266.664948) (xy 359.792992 -266.651372) (xy 359.848351 -266.63005)
			(xy 359.905907 -266.615681) (xy 359.964792 -266.608482) (xy 359.994454 -266.608052) (xy 360.024114 -266.608492)
			(xy 360.082992 -266.615721) (xy 360.140545 -266.630091) (xy 360.195912 -266.651384) (xy 360.222292 -266.664948)
			(xy 360.227861 -266.667749) (xy 360.239937 -266.670831) (xy 360.246168 -266.671044) (xy 361.570524 -266.671044)
			(xy 361.594654 -266.656312) (xy 361.601258 -266.643866) (xy 361.61358 -266.621163) (xy 361.644182 -266.579552)
			(xy 361.680882 -266.543205) (xy 361.722787 -266.513005) (xy 361.768877 -266.489688) (xy 361.818032 -266.47382)
			(xy 361.869056 -266.465786) (xy 361.894882 -266.465304) (xy 361.918665 -266.465738) (xy 361.965736 -266.472595)
			(xy 362.011338 -266.486128) (xy 362.054529 -266.506057) (xy 362.074714 -266.518644) (xy 362.074968 -266.518644)
			(xy 362.082959 -266.52329) (xy 362.10103 -266.527117) (xy 362.119289 -266.524327) (xy 362.127546 -266.520168)
			(xy 362.961428 -266.041124) (xy 362.975144 -266.015978) (xy 362.974382 -266.001754) (xy 362.974128 -265.98626)
			(xy 362.974128 -265.985752) (xy 362.974656 -265.959779) (xy 362.982818 -265.908476) (xy 362.998901 -265.859081)
			(xy 363.022511 -265.812809) (xy 363.053065 -265.770797) (xy 363.089814 -265.734081) (xy 363.131851 -265.703562)
			(xy 363.178144 -265.679992) (xy 363.227553 -265.663951) (xy 363.278862 -265.655834) (xy 363.304836 -265.655298)
			(xy 363.330821 -265.65581) (xy 363.382151 -265.663945) (xy 363.431576 -265.68001) (xy 363.47788 -265.703607)
			(xy 363.519923 -265.734158) (xy 363.556669 -265.770909) (xy 363.587215 -265.812956) (xy 363.610807 -265.859263)
			(xy 363.626865 -265.90869) (xy 363.634993 -265.960021) (xy 363.635544 -265.986006) (xy 363.635152 -266.00892)
			(xy 363.628814 -266.054309) (xy 363.616262 -266.098385) (xy 363.597735 -266.140302) (xy 363.586014 -266.159996)
			(xy 363.578648 -266.172188) (xy 363.57814 -266.199874) (xy 363.71784 -266.440412) (xy 363.722785 -266.448142)
			(xy 363.737 -266.459725) (xy 363.754385 -266.465554) (xy 363.76356 -266.465558) (xy 363.774482 -266.465304)
			(xy 363.77499 -266.465304) (xy 363.800962 -266.465835) (xy 363.852261 -266.474002) (xy 363.901652 -266.490089)
			(xy 363.94792 -266.5137) (xy 363.989928 -266.544255) (xy 364.026641 -266.581002) (xy 364.057158 -266.623038)
			(xy 364.080727 -266.669328) (xy 364.096769 -266.718733) (xy 364.104889 -266.77004) (xy 364.105444 -266.796012)
			(xy 364.10519 -266.808204) (xy 364.104682 -266.822428) (xy 364.118144 -266.846812) (xy 364.96752 -267.335)
			(xy 364.995714 -267.334238) (xy 365.007652 -267.326618) (xy 365.02757 -267.314463) (xy 365.0701 -267.295272)
			(xy 365.11491 -267.282263) (xy 365.161106 -267.275695) (xy 365.184436 -267.27531) (xy 365.18469 -267.27531)
			(xy 365.201962 -267.275818) (xy 365.20247 -267.275818) (xy 365.216694 -267.27658) (xy 365.241586 -267.263118)
			(xy 365.385096 -267.015468) (xy 365.384334 -266.98702) (xy 365.376714 -266.975082) (xy 365.364298 -266.954977)
			(xy 365.344666 -266.911995) (xy 365.33134 -266.86666) (xy 365.32459 -266.819892) (xy 365.324136 -266.796266)
			(xy 365.324136 -266.796012) (xy 365.324618 -266.770023) (xy 365.332748 -266.718686) (xy 365.34881 -266.669253)
			(xy 365.372408 -266.622941) (xy 365.402961 -266.580891) (xy 365.439716 -266.54414) (xy 365.481768 -266.513591)
			(xy 365.528082 -266.489998) (xy 365.577517 -266.473941) (xy 365.628855 -266.465816) (xy 365.654844 -266.465304)
			(xy 365.678628 -266.465735) (xy 365.725701 -266.472588) (xy 365.771306 -266.486116) (xy 365.8145 -266.506041)
			(xy 365.834676 -266.518644) (xy 365.83493 -266.518644) (xy 365.842922 -266.523297) (xy 365.860996 -266.527137)
			(xy 365.879264 -266.524357) (xy 365.887508 -266.520168) (xy 366.72139 -266.041124) (xy 366.735106 -266.015978)
			(xy 366.734344 -266.001754) (xy 366.73409 -265.98626) (xy 366.73409 -265.985752) (xy 366.734618 -265.959778)
			(xy 366.742779 -265.908473) (xy 366.758862 -265.859075) (xy 366.782471 -265.8128) (xy 366.813025 -265.770786)
			(xy 366.849773 -265.734065) (xy 366.89181 -265.703542) (xy 366.938103 -265.679968) (xy 366.987512 -265.663922)
			(xy 367.038823 -265.655799) (xy 367.064798 -265.655298) (xy 367.090787 -265.655781) (xy 367.142126 -265.663912)
			(xy 367.19156 -265.679974) (xy 367.237873 -265.703572) (xy 367.279924 -265.734124) (xy 367.316678 -265.770879)
			(xy 367.34723 -265.81293) (xy 367.370827 -265.859244) (xy 367.386889 -265.908678) (xy 367.395019 -265.960017)
			(xy 367.395506 -265.986006) (xy 367.395114 -266.008921) (xy 367.388778 -266.05431) (xy 367.376227 -266.098387)
			(xy 367.357704 -266.140306) (xy 367.345976 -266.159996) (xy 367.33861 -266.172188) (xy 367.338102 -266.199874)
			(xy 367.477802 -266.440412) (xy 367.48275 -266.448134) (xy 367.496967 -266.4597) (xy 367.51435 -266.465509)
			(xy 367.523522 -266.465558) (xy 367.534444 -266.465304) (xy 367.534952 -266.465304) (xy 367.560926 -266.465832)
			(xy 367.612229 -266.473994) (xy 367.661625 -266.490078) (xy 367.707899 -266.513687) (xy 367.749912 -266.544241)
			(xy 367.78663 -266.580989) (xy 367.817151 -266.623026) (xy 367.840724 -266.669319) (xy 367.856768 -266.718728)
			(xy 367.864888 -266.770038) (xy 367.865406 -266.796012) (xy 367.865152 -266.808204) (xy 367.864644 -266.822428)
			(xy 367.878106 -266.846812) (xy 368.727736 -267.335) (xy 368.75593 -267.334238) (xy 368.767868 -267.326618)
			(xy 368.787786 -267.314464) (xy 368.830317 -267.295275) (xy 368.875127 -267.282268) (xy 368.921322 -267.275703)
			(xy 368.944652 -267.27531) (xy 368.944906 -267.27531) (xy 368.961924 -267.275818) (xy 368.962432 -267.275818)
			(xy 368.976656 -267.27658) (xy 369.001548 -267.263118) (xy 369.145058 -267.015468) (xy 369.144296 -266.98702)
			(xy 369.136676 -266.975082) (xy 369.124257 -266.954978) (xy 369.104622 -266.911996) (xy 369.091294 -266.866661)
			(xy 369.084542 -266.819893) (xy 369.084098 -266.796266) (xy 369.084098 -266.796012) (xy 369.08458 -266.770022)
			(xy 369.09271 -266.718683) (xy 369.108771 -266.669247) (xy 369.132368 -266.622932) (xy 369.162921 -266.58088)
			(xy 369.199675 -266.544124) (xy 369.241727 -266.513572) (xy 369.288041 -266.489974) (xy 369.337477 -266.473911)
			(xy 369.388816 -266.465781) (xy 369.414806 -266.465304) (xy 369.438591 -266.465732) (xy 369.485666 -266.47258)
			(xy 369.531274 -266.486104) (xy 369.574472 -266.506026) (xy 369.594638 -266.518644) (xy 369.594892 -266.518644)
			(xy 369.602884 -266.523304) (xy 369.620963 -266.527157) (xy 369.63924 -266.524388) (xy 369.64747 -266.520168)
			(xy 370.481352 -266.041124) (xy 370.495068 -266.015978) (xy 370.494306 -266.001754) (xy 370.494052 -265.98626)
			(xy 370.494052 -265.985752) (xy 370.49458 -265.959776) (xy 370.502741 -265.90847) (xy 370.518824 -265.85907)
			(xy 370.542432 -265.812792) (xy 370.572985 -265.770774) (xy 370.609732 -265.73405) (xy 370.651769 -265.703523)
			(xy 370.698062 -265.679944) (xy 370.747472 -265.663892) (xy 370.798784 -265.655764) (xy 370.82476 -265.655298)
			(xy 370.850751 -265.655778) (xy 370.902094 -265.663904) (xy 370.951534 -265.679963) (xy 370.997852 -265.703559)
			(xy 371.039908 -265.734111) (xy 371.076667 -265.770866) (xy 371.107223 -265.812919) (xy 371.130824 -265.859235)
			(xy 371.146888 -265.908673) (xy 371.155019 -265.960015) (xy 371.155468 -265.986006) (xy 371.155081 -266.008879)
			(xy 371.148778 -266.054189) (xy 371.136293 -266.098198) (xy 371.117865 -266.140068) (xy 371.106192 -266.159742)
			(xy 371.101715 -266.167766) (xy 371.098199 -266.185787) (xy 371.101215 -266.203899) (xy 371.10543 -266.212066)
			(xy 371.24513 -266.452604) (xy 371.269514 -266.466066) (xy 371.283484 -266.465558) (xy 371.29466 -266.465304)
			(xy 371.295168 -266.465304) (xy 371.321141 -266.465834) (xy 371.372442 -266.473997) (xy 371.421836 -266.490082)
			(xy 371.468108 -266.513692) (xy 371.510118 -266.544247) (xy 371.546835 -266.580995) (xy 371.577354 -266.623031)
			(xy 371.600925 -266.669323) (xy 371.616968 -266.71873) (xy 371.625089 -266.770039) (xy 371.625622 -266.796012)
			(xy 371.625368 -266.808204) (xy 371.625368 -266.808458) (xy 371.62543 -266.817657) (xy 371.631315 -266.83507)
			(xy 371.642991 -266.849266) (xy 371.650768 -266.854178) (xy 372.487698 -267.335) (xy 372.515892 -267.334238)
			(xy 372.52783 -267.326618) (xy 372.547747 -267.314462) (xy 372.590278 -267.295268) (xy 372.635088 -267.282256)
			(xy 372.681284 -267.275685) (xy 372.704614 -267.27531) (xy 372.704868 -267.27531) (xy 372.72214 -267.275818)
			(xy 372.722648 -267.275818) (xy 372.736872 -267.27658) (xy 372.761764 -267.263118) (xy 372.898162 -267.028168)
			(xy 372.902454 -267.019873) (xy 372.90538 -267.001441) (xy 372.901558 -266.983174) (xy 372.896892 -266.975082)
			(xy 372.884397 -266.954974) (xy 372.864663 -266.911942) (xy 372.851268 -266.866535) (xy 372.844486 -266.819682)
			(xy 372.84406 -266.796012) (xy 372.844569 -266.770023) (xy 372.852697 -266.718685) (xy 372.868757 -266.669251)
			(xy 372.892352 -266.622938) (xy 372.922901 -266.580885) (xy 372.959652 -266.544129) (xy 373.0017 -266.513575)
			(xy 373.048011 -266.489974) (xy 373.097443 -266.473908) (xy 373.148779 -266.465772) (xy 373.174768 -266.465304)
			(xy 373.200595 -266.465799) (xy 373.251622 -266.473825) (xy 373.30078 -266.489687) (xy 373.346874 -266.513)
			(xy 373.388783 -266.543196) (xy 373.425487 -266.579541) (xy 373.456093 -266.62115) (xy 373.468392 -266.643866)
			(xy 373.474996 -266.656312) (xy 373.499126 -266.671044) (xy 373.818912 -266.671044) (xy 373.84228 -266.657328)
			(xy 373.849138 -266.64539) (xy 373.86087 -266.625576) (xy 373.889356 -266.589399) (xy 373.922948 -266.557904)
			(xy 373.960883 -266.531806) (xy 374.002305 -266.511694) (xy 374.046275 -266.498023) (xy 374.091799 -266.491104)
			(xy 374.114822 -266.490704) (xy 374.138812 -266.491176) (xy 374.1862 -266.498685) (xy 374.23183 -266.513515)
			(xy 374.274579 -266.5353) (xy 374.313394 -266.563504) (xy 374.347319 -266.597432) (xy 374.375518 -266.63625)
			(xy 374.397298 -266.679001) (xy 374.412123 -266.724633) (xy 374.419626 -266.772022) (xy 374.42013 -266.796012)
			(xy 374.419586 -266.822236) (xy 374.410622 -266.873912) (xy 374.39296 -266.923296) (xy 374.380506 -266.94638)
			(xy 374.380506 -266.946634) (xy 374.376508 -266.954478) (xy 374.373563 -266.971821) (xy 374.376658 -266.989138)
			(xy 374.38076 -266.996926) (xy 374.527826 -267.250164) (xy 374.53276 -267.257923) (xy 374.546962 -267.269581)
			(xy 374.564353 -267.275509) (xy 374.573546 -267.275564) (xy 374.584468 -267.27531) (xy 374.584976 -267.27531)
			(xy 374.610948 -267.27584) (xy 374.662249 -267.284005) (xy 374.711641 -267.300091) (xy 374.757911 -267.323701)
			(xy 374.79992 -267.354256) (xy 374.836635 -267.391004) (xy 374.867152 -267.43304) (xy 374.890722 -267.479331)
			(xy 374.906764 -267.528738) (xy 374.914883 -267.580045) (xy 374.91543 -267.606018) (xy 374.915042 -267.628891)
			(xy 374.908739 -267.674201) (xy 374.896255 -267.71821) (xy 374.877828 -267.760081) (xy 374.866154 -267.779754)
			(xy 374.861663 -267.787779) (xy 374.858121 -267.80581) (xy 374.861111 -267.823941) (xy 374.865392 -267.832078)
			(xy 375.005092 -268.072616) (xy 375.029476 -268.086078) (xy 375.043446 -268.08557) (xy 375.054622 -268.085316)
			(xy 375.05513 -268.085316) (xy 375.081105 -268.085843) (xy 375.13241 -268.094002) (xy 375.181808 -268.110084)
			(xy 375.228084 -268.133692) (xy 375.270099 -268.164246) (xy 375.306819 -268.200995) (xy 375.337341 -268.243033)
			(xy 375.360914 -268.289327) (xy 375.376957 -268.338737) (xy 375.385077 -268.390049) (xy 375.385584 -268.416024)
			(xy 375.385196 -268.438897) (xy 375.378891 -268.484205) (xy 375.366405 -268.528214) (xy 375.347975 -268.570083)
			(xy 375.336308 -268.58976) (xy 375.331815 -268.597784) (xy 375.32827 -268.615815) (xy 375.331265 -268.633947)
			(xy 375.335546 -268.642084) (xy 375.46788 -268.870176) (xy 375.472818 -268.877927) (xy 375.487022 -268.889567)
			(xy 375.50441 -268.895476) (xy 375.5136 -268.895576) (xy 375.524522 -268.895322) (xy 375.52503 -268.895322)
			(xy 375.551004 -268.895849) (xy 375.602309 -268.904008) (xy 375.651707 -268.92009) (xy 375.697983 -268.943698)
			(xy 375.739997 -268.974253) (xy 375.776717 -269.011001) (xy 375.807238 -269.053039) (xy 375.83081 -269.099333)
			(xy 375.846853 -269.148744) (xy 375.854972 -269.200055) (xy 375.855484 -269.22603) (xy 375.854972 -269.252015)
			(xy 375.846838 -269.303344) (xy 375.830774 -269.352769) (xy 375.807176 -269.399073) (xy 375.776625 -269.441115)
			(xy 375.739874 -269.47786) (xy 375.697827 -269.508404) (xy 375.651519 -269.531995) (xy 375.602092 -269.54805)
			(xy 375.550761 -269.556176) (xy 375.524776 -269.556738) (xy 375.51614 -269.556738) (xy 375.50217 -269.55623)
			(xy 375.477786 -269.569692) (xy 375.329958 -269.824708) (xy 375.330212 -269.852648) (xy 375.337578 -269.864332)
			(xy 375.34896 -269.883796) (xy 375.366918 -269.925153) (xy 375.37908 -269.96857) (xy 375.385219 -270.013238)
			(xy 375.385584 -270.035782) (xy 375.385584 -270.036036) (xy 375.385072 -270.062021) (xy 375.376937 -270.113349)
			(xy 375.360872 -270.162774) (xy 375.337274 -270.209076) (xy 375.306723 -270.251118) (xy 375.269972 -270.287862)
			(xy 375.227925 -270.318405) (xy 375.181618 -270.341995) (xy 375.132191 -270.358051) (xy 375.080861 -270.366176)
			(xy 375.054876 -270.366744) (xy 375.04624 -270.366744) (xy 375.03227 -270.366236) (xy 375.007886 -270.379698)
			(xy 374.866916 -270.622776) (xy 374.862666 -270.630769) (xy 374.859555 -270.648588) (xy 374.862868 -270.666371)
			(xy 374.86717 -270.674338) (xy 374.867424 -270.674592) (xy 374.878804 -270.694056) (xy 374.896758 -270.735414)
			(xy 374.908914 -270.778831) (xy 374.915046 -270.823499) (xy 374.91543 -270.846042) (xy 374.915047 -270.868916)
			(xy 374.908754 -270.91423) (xy 374.896278 -270.958245) (xy 374.877859 -271.000122) (xy 374.866154 -271.019778)
			(xy 374.861668 -271.027803) (xy 374.858133 -271.045831) (xy 374.86113 -271.063957) (xy 374.865392 -271.072102)
			(xy 374.99798 -271.300448) (xy 375.00293 -271.308169) (xy 375.017148 -271.319732) (xy 375.034528 -271.325544)
			(xy 375.0437 -271.325594) (xy 375.054622 -271.32534) (xy 375.05513 -271.32534) (xy 375.081104 -271.325867)
			(xy 375.132408 -271.334027) (xy 375.181804 -271.350109) (xy 375.228078 -271.373717) (xy 375.270091 -271.404272)
			(xy 375.306809 -271.441021) (xy 375.337328 -271.483059) (xy 375.360898 -271.529353) (xy 375.376938 -271.578763)
			(xy 375.385055 -271.630074) (xy 375.385584 -271.656048) (xy 375.385201 -271.678922) (xy 375.378906 -271.724235)
			(xy 375.366428 -271.768249) (xy 375.348006 -271.810124) (xy 375.336308 -271.829784) (xy 375.331819 -271.837808)
			(xy 375.328282 -271.855836) (xy 375.331284 -271.873962) (xy 375.335546 -271.882108) (xy 375.46788 -272.1102)
			(xy 375.47282 -272.117948) (xy 375.487025 -272.129583) (xy 375.504411 -272.135488) (xy 375.5136 -272.1356)
			(xy 375.524522 -272.135346) (xy 375.52503 -272.135346) (xy 375.551007 -272.135873) (xy 375.602316 -272.144031)
			(xy 375.651719 -272.160112) (xy 375.698 -272.183719) (xy 375.74002 -272.214273) (xy 375.776747 -272.25102)
			(xy 375.807277 -272.293057) (xy 375.830858 -272.339351) (xy 375.846912 -272.388763) (xy 375.855042 -272.440077)
			(xy 375.855484 -272.466054) (xy 375.855004 -272.492045) (xy 375.846879 -272.543388) (xy 375.83082 -272.592827)
			(xy 375.807224 -272.639145) (xy 375.776673 -272.6812) (xy 375.739917 -272.717958) (xy 375.697863 -272.748513)
			(xy 375.651547 -272.772112) (xy 375.602109 -272.788173) (xy 375.550767 -272.796303) (xy 375.524776 -272.796762)
			(xy 375.51614 -272.796762) (xy 375.50217 -272.796254) (xy 375.477786 -272.809716) (xy 375.329958 -273.064732)
			(xy 375.330212 -273.092672) (xy 375.337578 -273.104356) (xy 375.348958 -273.12382) (xy 375.366914 -273.165178)
			(xy 375.379072 -273.208595) (xy 375.385209 -273.253262) (xy 375.385584 -273.275806) (xy 375.385584 -273.27606)
			(xy 375.385104 -273.302051) (xy 375.376977 -273.353393) (xy 375.360918 -273.402831) (xy 375.337322 -273.449148)
			(xy 375.30677 -273.491203) (xy 375.270015 -273.52796) (xy 375.227962 -273.558514) (xy 375.181646 -273.582112)
			(xy 375.132208 -273.598174) (xy 375.080867 -273.606303) (xy 375.054876 -273.606768) (xy 375.04624 -273.606768)
			(xy 375.03227 -273.60626) (xy 375.007886 -273.619722) (xy 374.866916 -273.8628) (xy 374.862652 -273.870793)
			(xy 374.859516 -273.888622) (xy 374.862808 -273.906424) (xy 374.86717 -273.914362) (xy 374.867424 -273.914616)
			(xy 374.878802 -273.93408) (xy 374.896753 -273.975439) (xy 374.908906 -274.018856) (xy 374.915035 -274.063523)
			(xy 374.91543 -274.086066) (xy 374.915046 -274.10894) (xy 374.908749 -274.154252) (xy 374.896271 -274.198266)
			(xy 374.877849 -274.240141) (xy 374.866154 -274.259802) (xy 374.861672 -274.267827) (xy 374.858146 -274.285852)
			(xy 374.861149 -274.303972) (xy 374.865392 -274.312126) (xy 374.99798 -274.540472) (xy 375.002924 -274.548202)
			(xy 375.017139 -274.559783) (xy 375.034525 -274.565604) (xy 375.0437 -274.565618) (xy 375.054622 -274.565364)
			(xy 375.05513 -274.565364) (xy 375.081106 -274.565891) (xy 375.132415 -274.57405) (xy 375.181816 -274.590131)
			(xy 375.228096 -274.613738) (xy 375.270115 -274.644291) (xy 375.30684 -274.681039) (xy 375.337368 -274.723077)
			(xy 375.360947 -274.769371) (xy 375.376998 -274.818782) (xy 375.385125 -274.870096) (xy 375.385584 -274.896072)
			(xy 375.385199 -274.918946) (xy 375.378901 -274.964257) (xy 375.366421 -275.008269) (xy 375.347996 -275.050142)
			(xy 375.336308 -275.069808) (xy 375.331823 -275.077832) (xy 375.328295 -275.095857) (xy 375.331303 -275.113977)
			(xy 375.335546 -275.122132) (xy 375.46788 -275.350224) (xy 375.472822 -275.357969) (xy 375.487028 -275.369598)
			(xy 375.504412 -275.375501) (xy 375.5136 -275.375624) (xy 375.524522 -275.37537) (xy 375.52503 -275.37537)
			(xy 375.551006 -275.375897) (xy 375.602314 -275.384056) (xy 375.651715 -275.400137) (xy 375.697994 -275.423744)
			(xy 375.740013 -275.454298) (xy 375.776738 -275.491045) (xy 375.807265 -275.533083) (xy 375.830843 -275.579377)
			(xy 375.846893 -275.628789) (xy 375.85502 -275.680102) (xy 375.855484 -275.706078) (xy 375.855003 -275.732068)
			(xy 375.846874 -275.783408) (xy 375.830813 -275.832843) (xy 375.807216 -275.879158) (xy 375.776664 -275.92121)
			(xy 375.739909 -275.957965) (xy 375.697856 -275.988517) (xy 375.651542 -276.012114) (xy 375.602106 -276.028174)
			(xy 375.550766 -276.036303) (xy 375.524776 -276.036786) (xy 375.51614 -276.036786) (xy 375.50217 -276.036278)
			(xy 375.477786 -276.04974) (xy 375.329958 -276.304756) (xy 375.330212 -276.332696) (xy 375.337578 -276.34438)
			(xy 375.348957 -276.363844) (xy 375.366909 -276.405203) (xy 375.379065 -276.448619) (xy 375.385198 -276.493287)
			(xy 375.385584 -276.51583) (xy 375.385584 -276.516084) (xy 375.385102 -276.542073) (xy 375.376973 -276.593413)
			(xy 375.360912 -276.642848) (xy 375.337314 -276.689161) (xy 375.306762 -276.731213) (xy 375.270007 -276.767967)
			(xy 375.227954 -276.798518) (xy 375.18164 -276.822115) (xy 375.132205 -276.838175) (xy 375.080865 -276.846303)
			(xy 375.054876 -276.846792) (xy 375.04624 -276.846792) (xy 375.03227 -276.846284) (xy 375.007886 -276.859746)
			(xy 374.866916 -277.102824) (xy 374.862657 -277.110817) (xy 374.859529 -277.128643) (xy 374.862827 -277.146439)
			(xy 374.86717 -277.154386) (xy 374.867424 -277.15464) (xy 374.878807 -277.174103) (xy 374.896767 -277.21546)
			(xy 374.90893 -277.258877) (xy 374.91507 -277.303546) (xy 374.91543 -277.32609) (xy 374.915044 -277.348963)
			(xy 374.908744 -277.394275) (xy 374.896264 -277.438286) (xy 374.877839 -277.480159) (xy 374.866154 -277.499826)
			(xy 374.861676 -277.507851) (xy 374.858158 -277.525873) (xy 374.861168 -277.543988) (xy 374.865392 -277.55215)
			(xy 374.99798 -277.780496) (xy 375.002926 -277.788223) (xy 375.017142 -277.799799) (xy 375.034526 -277.805617)
			(xy 375.0437 -277.805642) (xy 375.054622 -277.805388) (xy 375.05513 -277.805388) (xy 375.081105 -277.805915)
			(xy 375.132412 -277.814074) (xy 375.181812 -277.830155) (xy 375.22809 -277.853763) (xy 375.270107 -277.884317)
			(xy 375.30683 -277.921065) (xy 375.337355 -277.963103) (xy 375.360932 -278.009397) (xy 375.376979 -278.058808)
			(xy 375.385103 -278.11012) (xy 375.385584 -278.136096) (xy 375.385193 -278.159011) (xy 375.378857 -278.2044)
			(xy 375.366307 -278.248478) (xy 375.347784 -278.290397) (xy 375.336054 -278.310086) (xy 375.328688 -278.32177)
			(xy 375.328434 -278.34971) (xy 375.474992 -278.602694) (xy 375.499376 -278.616156) (xy 375.513346 -278.615648)
			(xy 375.524522 -278.615394) (xy 375.52503 -278.615394) (xy 375.551005 -278.615921) (xy 375.602312 -278.62408)
			(xy 375.651712 -278.640161) (xy 375.697989 -278.663769) (xy 375.740006 -278.694323) (xy 375.776728 -278.731071)
			(xy 375.807252 -278.773109) (xy 375.830828 -278.819403) (xy 375.846874 -278.868814) (xy 375.854998 -278.920126)
			(xy 375.855484 -278.946102) (xy 375.855001 -278.97209) (xy 375.846869 -279.023427) (xy 375.830806 -279.07286)
			(xy 375.807208 -279.119171) (xy 375.776655 -279.161221) (xy 375.739901 -279.197972) (xy 375.697849 -279.228522)
			(xy 375.651536 -279.252116) (xy 375.602102 -279.268175) (xy 375.550765 -279.276303) (xy 375.524776 -279.27681)
			(xy 375.501975 -279.276426) (xy 375.456805 -279.270157) (xy 375.412924 -279.257741) (xy 375.371166 -279.239414)
			(xy 375.351548 -279.227788) (xy 375.33961 -279.220422) (xy 375.311924 -279.219914) (xy 374.458992 -279.70988)
			(xy 374.445276 -279.734264) (xy 374.44553 -279.748234) (xy 374.44553 -279.756108) (xy 374.445143 -279.778981)
			(xy 374.438841 -279.824291) (xy 374.426358 -279.868302) (xy 374.407932 -279.910173) (xy 374.396254 -279.929844)
			(xy 374.391779 -279.937868) (xy 374.388267 -279.955889) (xy 374.391282 -279.973999) (xy 374.395492 -279.982168)
			(xy 374.527826 -280.21026) (xy 374.53276 -280.218019) (xy 374.546961 -280.229678) (xy 374.564353 -280.235607)
			(xy 374.573546 -280.23566) (xy 374.584468 -280.235406) (xy 374.584976 -280.235406) (xy 374.610949 -280.235936)
			(xy 374.662249 -280.244101) (xy 374.711642 -280.260187) (xy 374.757912 -280.283797) (xy 374.799921 -280.314352)
			(xy 374.836636 -280.3511) (xy 374.867155 -280.393136) (xy 374.890725 -280.439427) (xy 374.906767 -280.488833)
			(xy 374.914887 -280.540141) (xy 374.91543 -280.566114) (xy 374.915043 -280.588987) (xy 374.90874 -280.634297)
			(xy 374.896256 -280.678307) (xy 374.87783 -280.720178) (xy 374.866154 -280.73985) (xy 374.861663 -280.747875)
			(xy 374.858119 -280.765907) (xy 374.861107 -280.784039) (xy 374.865392 -280.792174) (xy 374.997726 -281.020266)
			(xy 375.00266 -281.028025) (xy 375.016862 -281.039682) (xy 375.034253 -281.04561) (xy 375.043446 -281.045666)
			(xy 375.054622 -281.045412) (xy 375.05513 -281.045412) (xy 375.081105 -281.045939) (xy 375.13241 -281.054098)
			(xy 375.181809 -281.07018) (xy 375.228085 -281.093788) (xy 375.2701 -281.124342) (xy 375.306821 -281.16109)
			(xy 375.337343 -281.203129) (xy 375.360916 -281.249422) (xy 375.376961 -281.298833) (xy 375.385081 -281.350145)
			(xy 375.385584 -281.37612) (xy 375.385099 -281.402108) (xy 375.376965 -281.453442) (xy 375.360901 -281.502873)
			(xy 375.337302 -281.549181) (xy 375.306749 -281.591228) (xy 375.269995 -281.627978) (xy 375.227944 -281.658525)
			(xy 375.181632 -281.682118) (xy 375.132199 -281.698176) (xy 375.080864 -281.706303) (xy 375.054876 -281.706828)
			(xy 375.045986 -281.706828) (xy 375.03227 -281.70632) (xy 375.007886 -281.719782) (xy 374.866916 -281.96286)
			(xy 374.862663 -281.970853) (xy 374.859547 -281.988674) (xy 374.862855 -282.006461) (xy 374.86717 -282.014422)
			(xy 374.867424 -282.014676) (xy 374.878805 -282.03414) (xy 374.896761 -282.075497) (xy 374.908919 -282.118914)
			(xy 374.915053 -282.163582) (xy 374.91543 -282.186126) (xy 374.915042 -282.208999) (xy 374.908737 -282.254308)
			(xy 374.896252 -282.298317) (xy 374.877825 -282.340187) (xy 374.866154 -282.359862) (xy 374.861665 -282.367887)
			(xy 374.858125 -282.385917) (xy 374.861117 -282.404047) (xy 374.865392 -282.412186) (xy 374.99798 -282.640532)
			(xy 375.002929 -282.648254) (xy 375.017146 -282.659822) (xy 375.034528 -282.665635) (xy 375.0437 -282.665678)
			(xy 375.054622 -282.665424) (xy 375.05513 -282.665424) (xy 375.081104 -282.665951) (xy 375.132409 -282.67411)
			(xy 375.181807 -282.690192) (xy 375.228082 -282.7138) (xy 375.270096 -282.744355) (xy 375.306816 -282.781103)
			(xy 375.337337 -282.823141) (xy 375.360909 -282.869435) (xy 375.376951 -282.918846) (xy 375.38507 -282.970157)
			(xy 375.385584 -282.996132) (xy 375.385195 -283.019005) (xy 375.378889 -283.064313) (xy 375.366402 -283.108321)
			(xy 375.347972 -283.150189) (xy 375.336308 -283.169868) (xy 375.331816 -283.177892) (xy 375.328274 -283.195922)
			(xy 375.331271 -283.214052) (xy 375.335546 -283.222192) (xy 375.46788 -283.450284) (xy 375.472819 -283.458034)
			(xy 375.487023 -283.469672) (xy 375.50441 -283.47558) (xy 375.5136 -283.475684) (xy 375.524522 -283.47543)
			(xy 375.52503 -283.47543) (xy 375.551004 -283.475957) (xy 375.602309 -283.484117) (xy 375.651706 -283.500198)
			(xy 375.697981 -283.523807) (xy 375.739994 -283.554361) (xy 375.776713 -283.59111) (xy 375.807233 -283.633148)
			(xy 375.830804 -283.679442) (xy 375.846846 -283.728852) (xy 375.854964 -283.780163) (xy 375.855484 -283.806138)
			(xy 375.854972 -283.832123) (xy 375.846836 -283.883451) (xy 375.830772 -283.932875) (xy 375.807173 -283.979177)
			(xy 375.776622 -284.021218) (xy 375.739871 -284.057963) (xy 375.697824 -284.088506) (xy 375.651518 -284.112095)
			(xy 375.602091 -284.128151) (xy 375.550761 -284.136276) (xy 375.524776 -284.136846) (xy 375.51614 -284.136846)
			(xy 375.50217 -284.136338) (xy 375.477786 -284.1498) (xy 375.329958 -284.404816) (xy 375.330212 -284.432756)
			(xy 375.337578 -284.44444) (xy 375.348959 -284.463904) (xy 375.366917 -284.505261) (xy 375.379078 -284.548678)
			(xy 375.385216 -284.593346) (xy 375.385584 -284.61589) (xy 375.385584 -284.616144) (xy 375.385071 -284.642128)
			(xy 375.376935 -284.693456) (xy 375.36087 -284.742879) (xy 375.337271 -284.789181) (xy 375.30672 -284.831221)
			(xy 375.269969 -284.867964) (xy 375.227923 -284.898507) (xy 375.181616 -284.922096) (xy 375.13219 -284.938151)
			(xy 375.08086 -284.946277) (xy 375.054876 -284.946852) (xy 375.04624 -284.946852) (xy 375.03227 -284.946344)
			(xy 375.007886 -284.959806) (xy 374.866916 -285.202884) (xy 374.86265 -285.210877) (xy 374.859508 -285.228709)
			(xy 374.862795 -285.246514) (xy 374.86717 -285.254446) (xy 374.867424 -285.2547) (xy 374.878803 -285.274164)
			(xy 374.896756 -285.315522) (xy 374.908911 -285.358939) (xy 374.915042 -285.403607) (xy 374.91543 -285.42615)
			(xy 374.915047 -285.449024) (xy 374.908752 -285.494338) (xy 374.896276 -285.538352) (xy 374.877856 -285.580228)
			(xy 374.866154 -285.599886) (xy 374.861669 -285.607911) (xy 374.858137 -285.625938) (xy 374.861136 -285.644062)
			(xy 374.865392 -285.65221) (xy 374.99798 -285.880556) (xy 375.002931 -285.888276) (xy 375.017149 -285.899838)
			(xy 375.034529 -285.905648) (xy 375.0437 -285.905702) (xy 375.054622 -285.905448) (xy 375.05513 -285.905448)
			(xy 375.081107 -285.905975) (xy 375.132416 -285.914133) (xy 375.181819 -285.930214) (xy 375.228099 -285.953822)
			(xy 375.27012 -285.984375) (xy 375.306846 -286.021122) (xy 375.337376 -286.06316) (xy 375.360957 -286.109454)
			(xy 375.37701 -286.158865) (xy 375.38514 -286.210179) (xy 375.385584 -286.236156) (xy 375.3852 -286.25903)
			(xy 375.378904 -286.304343) (xy 375.366426 -286.348356) (xy 375.348003 -286.39023) (xy 375.336308 -286.409892)
			(xy 375.331821 -286.417916) (xy 375.328287 -286.435943) (xy 375.331291 -286.454067) (xy 375.335546 -286.462216)
			(xy 375.46788 -286.690054) (xy 375.472816 -286.697808) (xy 375.487019 -286.709453) (xy 375.504409 -286.715364)
			(xy 375.5136 -286.715454) (xy 375.524522 -286.7152) (xy 375.52503 -286.7152) (xy 375.551005 -286.715727)
			(xy 375.602311 -286.723886) (xy 375.651711 -286.739967) (xy 375.697988 -286.763575) (xy 375.740004 -286.794129)
			(xy 375.776725 -286.830877) (xy 375.807249 -286.872916) (xy 375.830824 -286.91921) (xy 375.84687 -286.96862)
			(xy 375.854992 -287.019933) (xy 375.855484 -287.045908) (xy 375.855 -287.071896) (xy 375.846868 -287.123232)
			(xy 375.830805 -287.172664) (xy 375.807206 -287.218975) (xy 375.776653 -287.261023) (xy 375.739899 -287.297774)
			(xy 375.697847 -287.328323) (xy 375.651535 -287.351917) (xy 375.602101 -287.367975) (xy 375.550764 -287.376103)
			(xy 375.524776 -287.376616) (xy 375.51614 -287.376616) (xy 375.50217 -287.376362) (xy 375.47804 -287.38957)
			(xy 375.329958 -287.64484) (xy 375.330212 -287.67278) (xy 375.337578 -287.684464) (xy 375.348958 -287.703928)
			(xy 375.366912 -287.745286) (xy 375.37907 -287.788703) (xy 375.385205 -287.833371) (xy 375.385584 -287.855914)
			(xy 375.385584 -287.856168) (xy 375.385103 -287.882158) (xy 375.376976 -287.933499) (xy 375.360916 -287.982937)
			(xy 375.33732 -288.029252) (xy 375.306768 -288.071306) (xy 375.270012 -288.108062) (xy 375.227959 -288.138615)
			(xy 375.181644 -288.162213) (xy 375.132207 -288.178274) (xy 375.080866 -288.186403) (xy 375.054876 -288.186876)
			(xy 375.04624 -288.186876) (xy 375.03227 -288.186368) (xy 375.007886 -288.19983) (xy 374.860058 -288.4551)
			(xy 374.860312 -288.482532) (xy 374.867424 -288.49447) (xy 374.878805 -288.513934) (xy 374.896762 -288.555291)
			(xy 374.908921 -288.598708) (xy 374.915056 -288.643376) (xy 374.91543 -288.66592) (xy 374.915042 -288.688793)
			(xy 374.908739 -288.734102) (xy 374.896254 -288.778112) (xy 374.877827 -288.819982) (xy 374.866154 -288.839656)
			(xy 374.861664 -288.847681) (xy 374.858122 -288.865712) (xy 374.861112 -288.883843) (xy 374.865392 -288.89198)
			(xy 375.005092 -289.132518) (xy 375.029476 -289.14598) (xy 375.043446 -289.145472) (xy 375.054622 -289.145218)
			(xy 375.05513 -289.145218) (xy 375.081105 -289.145745) (xy 375.13241 -289.153904) (xy 375.181808 -289.169986)
			(xy 375.228084 -289.193594) (xy 375.270098 -289.224148) (xy 375.306818 -289.260897) (xy 375.33734 -289.302935)
			(xy 375.360912 -289.349229) (xy 375.376956 -289.39864) (xy 375.385075 -289.449951) (xy 375.385584 -289.475926)
			(xy 375.385196 -289.498799) (xy 375.378891 -289.544107) (xy 375.366404 -289.588116) (xy 375.347974 -289.629984)
			(xy 375.336308 -289.649662) (xy 375.331815 -289.657686) (xy 375.328271 -289.675717) (xy 375.331267 -289.693848)
			(xy 375.335546 -289.701986) (xy 375.46788 -289.930078) (xy 375.472818 -289.937829) (xy 375.487022 -289.949468)
			(xy 375.50441 -289.955377) (xy 375.5136 -289.955478) (xy 375.524522 -289.955224) (xy 375.52503 -289.955224)
			(xy 375.551004 -289.955751) (xy 375.602309 -289.96391) (xy 375.651707 -289.979992) (xy 375.697982 -290.0036)
			(xy 375.739996 -290.034155) (xy 375.776716 -290.070903) (xy 375.807237 -290.112941) (xy 375.830809 -290.159235)
			(xy 375.846851 -290.208646) (xy 375.85497 -290.259957) (xy 375.855484 -290.285932) (xy 375.855095 -290.308805)
			(xy 375.848789 -290.354113) (xy 375.836302 -290.398121) (xy 375.817872 -290.439989) (xy 375.806208 -290.459668)
			(xy 375.801716 -290.467692) (xy 375.798174 -290.485722) (xy 375.801171 -290.503852) (xy 375.805446 -290.511992)
			(xy 375.93778 -290.740084) (xy 375.942719 -290.747834) (xy 375.956923 -290.759472) (xy 375.97431 -290.76538)
			(xy 375.9835 -290.765484) (xy 375.994676 -290.76523) (xy 375.995184 -290.76523) (xy 376.021155 -290.765761)
			(xy 376.072453 -290.773927) (xy 376.121843 -290.790014) (xy 376.168111 -290.813625) (xy 376.210117 -290.844181)
			(xy 376.246829 -290.880928) (xy 376.277343 -290.922964) (xy 376.30091 -290.969255) (xy 376.316948 -291.01866)
			(xy 376.325064 -291.069966) (xy 376.325638 -291.095938) (xy 376.32525 -291.118854) (xy 376.318921 -291.164246)
			(xy 376.306376 -291.208327) (xy 376.287856 -291.250249) (xy 376.276108 -291.269928) (xy 376.268742 -291.281612)
			(xy 376.268488 -291.309552) (xy 376.407934 -291.55009) (xy 376.412871 -291.557845) (xy 376.427074 -291.569494)
			(xy 376.444463 -291.575416) (xy 376.453654 -291.57549) (xy 376.464576 -291.575236) (xy 376.465084 -291.575236)
			(xy 376.491055 -291.575767) (xy 376.542353 -291.583933) (xy 376.591742 -291.60002) (xy 376.638009 -291.623632)
			(xy 376.680015 -291.654187) (xy 376.716726 -291.690935) (xy 376.74724 -291.732971) (xy 376.770806 -291.779261)
			(xy 376.786843 -291.828667) (xy 376.794959 -291.879972) (xy 376.795538 -291.905944) (xy 376.795155 -291.928818)
			(xy 376.78886 -291.974131) (xy 376.776381 -292.018144) (xy 376.757957 -292.060018) (xy 376.746262 -292.07968)
			(xy 376.741776 -292.087705) (xy 376.738241 -292.105733) (xy 376.741239 -292.123858) (xy 376.7455 -292.132004)
			(xy 376.877834 -292.360096) (xy 376.882771 -292.36785) (xy 376.896975 -292.379498) (xy 376.914363 -292.385419)
			(xy 376.923554 -292.385496) (xy 376.934476 -292.385242) (xy 376.934984 -292.385242) (xy 376.960955 -292.385773)
			(xy 377.012252 -292.393939) (xy 377.061642 -292.410026) (xy 377.107908 -292.433638) (xy 377.149913 -292.464193)
			(xy 377.186624 -292.500941) (xy 377.217137 -292.542977) (xy 377.240702 -292.589267) (xy 377.256739 -292.638673)
			(xy 377.264853 -292.689978) (xy 377.265438 -292.71595) (xy 377.265055 -292.738824) (xy 377.258758 -292.784136)
			(xy 377.246279 -292.828149) (xy 377.227855 -292.870023) (xy 377.216162 -292.889686) (xy 377.211677 -292.897711)
			(xy 377.208144 -292.915738) (xy 377.211144 -292.933862) (xy 377.2154 -292.94201) (xy 377.3551 -293.182548)
			(xy 377.379484 -293.19601) (xy 377.393454 -293.195502) (xy 377.40463 -293.195248) (xy 377.405138 -293.195248)
			(xy 377.430945 -293.195763) (xy 377.481928 -293.20382) (xy 377.531039 -293.219701) (xy 377.577086 -293.24302)
			(xy 377.61895 -293.273212) (xy 377.655615 -293.309541) (xy 377.686189 -293.351127) (xy 377.698508 -293.37381)
			(xy 377.705112 -293.386256) (xy 377.729242 -293.400988) (xy 378.02058 -293.400988) (xy 378.04471 -293.386256)
			(xy 378.051314 -293.37381) (xy 378.063638 -293.351108) (xy 378.094242 -293.309499) (xy 378.130943 -293.273153)
			(xy 378.172847 -293.242954) (xy 378.218936 -293.219635) (xy 378.268089 -293.203763) (xy 378.319112 -293.195725)
			(xy 378.344938 -293.195248) (xy 378.370924 -293.19576) (xy 378.422257 -293.203895) (xy 378.471685 -293.219959)
			(xy 378.517993 -293.243556) (xy 378.560039 -293.274106) (xy 378.59679 -293.310856) (xy 378.627341 -293.352902)
			(xy 378.650939 -293.399209) (xy 378.667003 -293.448637) (xy 378.675139 -293.49997) (xy 378.675646 -293.525956)
			(xy 378.675257 -293.548871) (xy 378.668926 -293.594263) (xy 378.656379 -293.638342) (xy 378.637858 -293.680264)
			(xy 378.626116 -293.699946) (xy 378.61875 -293.712138) (xy 378.618242 -293.739824) (xy 378.757942 -293.980362)
			(xy 378.762892 -293.988085) (xy 378.777109 -293.999656) (xy 378.79449 -294.005479) (xy 378.803662 -294.005508)
			(xy 378.814584 -294.005254) (xy 378.815092 -294.005254) (xy 378.841065 -294.005785) (xy 378.892367 -294.013952)
			(xy 378.941761 -294.030038) (xy 378.988032 -294.053649) (xy 379.030044 -294.084203) (xy 379.066762 -294.12095)
			(xy 379.097284 -294.162985) (xy 379.120859 -294.209274) (xy 379.136908 -294.258681) (xy 379.145035 -294.309988)
			(xy 379.145546 -294.335962) (xy 379.145162 -294.358836) (xy 379.138864 -294.404148) (xy 379.126384 -294.44816)
			(xy 379.107958 -294.490033) (xy 379.09627 -294.509698) (xy 379.091786 -294.517722) (xy 379.088257 -294.535749)
			(xy 379.09126 -294.55387) (xy 379.095508 -294.562022) (xy 379.235208 -294.80256) (xy 379.259592 -294.816022)
			(xy 379.273562 -294.815514) (xy 379.284484 -294.81526) (xy 379.284992 -294.81526) (xy 379.310965 -294.815791)
			(xy 379.362266 -294.823958) (xy 379.41166 -294.840044) (xy 379.457931 -294.863655) (xy 379.499942 -294.894209)
			(xy 379.53666 -294.930956) (xy 379.567181 -294.972991) (xy 379.590755 -295.019281) (xy 379.606803 -295.068687)
			(xy 379.614929 -295.119995) (xy 379.615446 -295.145968) (xy 379.615062 -295.168842) (xy 379.608763 -295.214153)
			(xy 379.596282 -295.258165) (xy 379.577856 -295.300037) (xy 379.56617 -295.319704) (xy 379.558804 -295.331642)
			(xy 379.558296 -295.359328) (xy 379.713744 -295.627298) (xy 379.718522 -295.634792) (xy 379.732126 -295.646208)
			(xy 379.748807 -295.652301) (xy 379.757686 -295.652698) (xy 379.758448 -295.652698) (xy 379.784422 -295.653226)
			(xy 379.835726 -295.661387) (xy 379.885123 -295.67747) (xy 379.931398 -295.701079) (xy 379.973412 -295.731634)
			(xy 380.010132 -295.768381) (xy 380.040653 -295.810419) (xy 380.064227 -295.856712) (xy 380.080272 -295.906121)
			(xy 380.088394 -295.957431) (xy 380.088902 -295.983406) (xy 380.088369 -296.009981) (xy 380.079855 -296.062444)
			(xy 380.063046 -296.112866) (xy 380.038379 -296.159945) (xy 380.022862 -296.181526) (xy 380.018194 -296.188267)
			(xy 380.013014 -296.203813) (xy 380.012702 -296.212006) (xy 380.012702 -304.780188) (xy 387.951476 -304.780188)
			(xy 387.955506 -304.637824) (xy 387.967584 -304.495916) (xy 387.987672 -304.354919) (xy 388.015704 -304.215284)
			(xy 388.051591 -304.077458) (xy 388.095218 -303.941884) (xy 388.146445 -303.808995) (xy 388.205108 -303.679216)
			(xy 388.27102 -303.552965) (xy 388.343969 -303.430645) (xy 388.423721 -303.312648) (xy 388.510021 -303.199352)
			(xy 388.602593 -303.091119) (xy 388.701139 -302.988297) (xy 388.805345 -302.891216) (xy 388.914877 -302.800185)
			(xy 389.029383 -302.715497) (xy 389.148497 -302.637422) (xy 389.271837 -302.566212) (xy 389.399008 -302.502093)
			(xy 389.529604 -302.445272) (xy 389.663204 -302.395931) (xy 389.799383 -302.354226) (xy 389.937702 -302.320293)
			(xy 390.07772 -302.29424) (xy 390.218987 -302.27615) (xy 390.361052 -302.266081) (xy 390.503459 -302.264066)
			(xy 390.645752 -302.27011) (xy 390.787474 -302.284196) (xy 390.928173 -302.306276) (xy 391.067398 -302.336281)
			(xy 391.204702 -302.374115) (xy 391.339645 -302.419656) (xy 391.471796 -302.472759) (xy 391.600731 -302.533253)
			(xy 391.726037 -302.600944) (xy 391.847313 -302.675617) (xy 391.964169 -302.757031) (xy 392.076233 -302.844925)
			(xy 392.183145 -302.939019) (xy 392.284562 -303.039011) (xy 392.380159 -303.14458) (xy 392.469631 -303.255389)
			(xy 392.55269 -303.371082) (xy 392.629071 -303.491289) (xy 392.698529 -303.615624) (xy 392.760842 -303.74369)
			(xy 392.815809 -303.875077) (xy 392.863255 -304.009362) (xy 392.903028 -304.146117) (xy 392.935 -304.284903)
			(xy 392.95907 -304.425275) (xy 392.975159 -304.566785) (xy 392.983216 -304.708977) (xy 392.98372 -304.780188)
			(xy 392.983216 -304.851399) (xy 392.975159 -304.993591) (xy 392.95907 -305.135101) (xy 392.935 -305.275473)
			(xy 392.903028 -305.414259) (xy 392.863255 -305.551014) (xy 392.815809 -305.685299) (xy 392.760842 -305.816686)
			(xy 392.698529 -305.944752) (xy 392.629071 -306.069087) (xy 392.55269 -306.189294) (xy 392.469631 -306.304987)
			(xy 392.380159 -306.415796) (xy 392.284562 -306.521365) (xy 392.183145 -306.621357) (xy 392.076233 -306.715451)
			(xy 391.964169 -306.803345) (xy 391.847313 -306.884759) (xy 391.726037 -306.959432) (xy 391.600731 -307.027123)
			(xy 391.471796 -307.087617) (xy 391.339645 -307.14072) (xy 391.204702 -307.186261) (xy 391.067398 -307.224095)
			(xy 390.928173 -307.2541) (xy 390.787474 -307.27618) (xy 390.645752 -307.290266) (xy 390.503459 -307.29631)
			(xy 390.361052 -307.294295) (xy 390.218987 -307.284226) (xy 390.07772 -307.266136) (xy 389.937702 -307.240083)
			(xy 389.799383 -307.20615) (xy 389.663204 -307.164445) (xy 389.529604 -307.115104) (xy 389.399008 -307.058283)
			(xy 389.271837 -306.994164) (xy 389.148497 -306.922954) (xy 389.029383 -306.844879) (xy 388.914877 -306.760191)
			(xy 388.805345 -306.66916) (xy 388.701139 -306.572079) (xy 388.602593 -306.469257) (xy 388.510021 -306.361024)
			(xy 388.423721 -306.247728) (xy 388.343969 -306.129731) (xy 388.27102 -306.007411) (xy 388.205108 -305.88116)
			(xy 388.146445 -305.751381) (xy 388.095218 -305.618492) (xy 388.051591 -305.482918) (xy 388.015704 -305.345092)
			(xy 387.987672 -305.205457) (xy 387.967584 -305.06446) (xy 387.955506 -304.922552) (xy 387.951476 -304.780188)
			(xy 380.012702 -304.780188) (xy 380.012702 -327.47458) (xy 380.01314 -327.484644) (xy 380.020875 -327.503227)
			(xy 380.027688 -327.510648) (xy 391.08126 -338.56422) (xy 391.088658 -338.571066) (xy 391.107257 -338.578791)
			(xy 391.117328 -338.579206) (xy 407.750518 -338.579206) (xy 407.761731 -338.578604) (xy 407.782025 -338.569052)
			(xy 407.796357 -338.551799) (xy 407.799794 -338.541106) (xy 407.80714 -338.513876) (xy 407.825318 -338.46048)
			(xy 407.836116 -338.434426) (xy 407.839629 -338.424813) (xy 407.839503 -338.404366) (xy 407.835862 -338.394802)
			(xy 407.821325 -338.35936) (xy 407.798598 -338.2862) (xy 407.783312 -338.211132) (xy 407.77562 -338.13491)
			(xy 407.775156 -338.096606) (xy 407.775645 -338.057935) (xy 407.78347 -337.98099) (xy 407.799039 -337.905231)
			(xy 407.822192 -337.831436) (xy 407.852692 -337.760362) (xy 407.890227 -337.692739) (xy 407.93441 -337.629259)
			(xy 407.984788 -337.570575) (xy 408.040845 -337.517289) (xy 408.102005 -337.469948) (xy 408.167641 -337.429037)
			(xy 408.237079 -337.394976) (xy 408.309606 -337.368114) (xy 408.384479 -337.348729) (xy 408.460929 -337.337017)
			(xy 408.538172 -337.3331) (xy 408.615415 -337.337017) (xy 408.691865 -337.348729) (xy 408.766738 -337.368114)
			(xy 408.839265 -337.394976) (xy 408.908703 -337.429037) (xy 408.974339 -337.469948) (xy 409.035499 -337.517289)
			(xy 409.091556 -337.570575) (xy 409.141934 -337.629259) (xy 409.186117 -337.692739) (xy 409.223652 -337.760362)
			(xy 409.254152 -337.831436) (xy 409.277305 -337.905231) (xy 409.292874 -337.98099) (xy 409.300699 -338.057935)
			(xy 409.301188 -338.096606) (xy 409.300721 -338.134911) (xy 409.293047 -338.211136) (xy 409.277769 -338.286207)
			(xy 409.255039 -338.359368) (xy 409.240482 -338.394802) (xy 409.236874 -338.404372) (xy 409.236748 -338.424808)
			(xy 409.240228 -338.434426) (xy 409.251033 -338.460478) (xy 409.269211 -338.513874) (xy 409.27655 -338.541106)
			(xy 409.279918 -338.55183) (xy 409.294256 -338.569105) (xy 409.314598 -338.578601) (xy 409.325826 -338.579206)
			(xy 413.300418 -338.579206) (xy 413.325374 -338.579819) (xy 413.374326 -338.58956) (xy 413.420437 -338.608664)
			(xy 413.461935 -338.636396) (xy 413.479996 -338.653628) (xy 416.40252 -341.576152) (xy 416.409917 -341.583001)
			(xy 416.428516 -341.590735) (xy 416.438588 -341.591138)
		)
		(stroke
			(width 0)
			(type solid)
		)
		(fill yes)
		(layer "In8.Cu")
		(net "PVDD11_S3_P0")
	)
	(gr_poly
		(pts
			(xy 391.808208 -193.488564) (xy 391.816551 -193.48827) (xy 391.832363 -193.482948) (xy 391.839196 -193.47815)
			(xy 391.861462 -193.461766) (xy 391.909783 -193.434913) (xy 391.961475 -193.415319) (xy 392.015454 -193.403396)
			(xy 392.07059 -193.399394) (xy 392.125726 -193.403396) (xy 392.179705 -193.415319) (xy 392.231397 -193.434913)
			(xy 392.279718 -193.461766) (xy 392.301984 -193.47815) (xy 392.308842 -193.48323) (xy 392.324336 -193.488564)
			(xy 392.451844 -193.488564) (xy 392.467338 -193.48323) (xy 392.474196 -193.47815) (xy 392.496462 -193.461766)
			(xy 392.544783 -193.434913) (xy 392.596475 -193.415319) (xy 392.650454 -193.403396) (xy 392.70559 -193.399394)
			(xy 392.760726 -193.403396) (xy 392.814705 -193.415319) (xy 392.866397 -193.434913) (xy 392.914718 -193.461766)
			(xy 392.936984 -193.47815) (xy 392.943827 -193.482922) (xy 392.959635 -193.488218) (xy 392.967972 -193.488564)
			(xy 393.174982 -193.488564) (xy 393.185045 -193.488125) (xy 393.203624 -193.480386) (xy 393.21105 -193.473578)
			(xy 393.369546 -193.315082) (xy 393.376396 -193.307685) (xy 393.384132 -193.289087) (xy 393.384532 -193.279014)
			(xy 393.384532 -188.789564) (xy 393.385107 -188.764605) (xy 393.394853 -188.715648) (xy 393.413963 -188.669533)
			(xy 393.441703 -188.628033) (xy 393.458954 -188.609986) (xy 394.093954 -187.974986) (xy 394.111994 -187.957725)
			(xy 394.153488 -187.929967) (xy 394.199606 -187.910853) (xy 394.248571 -187.901121) (xy 394.273532 -187.900564)
			(xy 394.389864 -187.900564) (xy 394.401462 -187.90006) (xy 394.42236 -187.890005) (xy 394.429996 -187.88126)
			(xy 394.448176 -187.858929) (xy 394.490116 -187.819475) (xy 394.537511 -187.786774) (xy 394.589283 -187.76157)
			(xy 394.644256 -187.744436) (xy 394.70118 -187.73576) (xy 394.72997 -187.73521) (xy 394.757338 -187.735687)
			(xy 394.811511 -187.74352) (xy 394.864009 -187.759015) (xy 394.913753 -187.781854) (xy 394.959722 -187.811568)
			(xy 394.980668 -187.82919) (xy 394.98778 -187.835286) (xy 395.004798 -187.841636) (xy 395.090142 -187.841636)
			(xy 395.10716 -187.835286) (xy 395.114272 -187.82919) (xy 395.135203 -187.811547) (xy 395.181169 -187.781818)
			(xy 395.230916 -187.758972) (xy 395.283419 -187.743478) (xy 395.337599 -187.735656) (xy 395.36497 -187.73521)
			(xy 395.39376 -187.735755) (xy 395.450681 -187.744444) (xy 395.505651 -187.761585) (xy 395.557423 -187.786788)
			(xy 395.604822 -187.819481) (xy 395.646772 -187.858924) (xy 395.664944 -187.88126) (xy 395.672572 -187.890016)
			(xy 395.693474 -187.900076) (xy 395.705076 -187.900564) (xy 399.862294 -187.900564) (xy 399.872364 -187.900141)
			(xy 399.890967 -187.892424) (xy 399.898362 -187.885578) (xy 401.624546 -186.159394) (xy 401.631397 -186.151998)
			(xy 401.639138 -186.133399) (xy 401.639532 -186.123326) (xy 401.639532 -181.169564) (xy 401.640107 -181.144605)
			(xy 401.649853 -181.095648) (xy 401.668963 -181.049533) (xy 401.696703 -181.008033) (xy 401.713954 -180.989986)
			(xy 403.364954 -179.338986) (xy 403.382994 -179.321725) (xy 403.424488 -179.293967) (xy 403.470606 -179.274853)
			(xy 403.519571 -179.265121) (xy 403.544532 -179.264564) (xy 406.974294 -179.264564) (xy 406.984364 -179.264141)
			(xy 407.002967 -179.256424) (xy 407.010362 -179.249578) (xy 411.746954 -174.512986) (xy 411.764994 -174.495725)
			(xy 411.806488 -174.467967) (xy 411.852606 -174.448853) (xy 411.901571 -174.439121) (xy 411.926532 -174.438564)
			(xy 417.9062 -174.438564) (xy 417.916219 -174.438144) (xy 417.934729 -174.430473) (xy 417.948893 -174.416299)
			(xy 417.956551 -174.397783) (xy 417.957 -174.387764) (xy 417.957 -163.063174) (xy 417.956521 -163.053209)
			(xy 417.948944 -163.034774) (xy 417.942268 -163.02736) (xy 417.923466 -163.007768) (xy 417.891029 -162.964221)
			(xy 417.865095 -162.916515) (xy 417.846188 -162.865613) (xy 417.83469 -162.812544) (xy 417.830833 -162.758382)
			(xy 417.834695 -162.704219) (xy 417.846199 -162.651152) (xy 417.865111 -162.600252) (xy 417.891049 -162.552548)
			(xy 417.92349 -162.509004) (xy 417.942268 -162.489388) (xy 417.94938 -162.482022) (xy 417.957 -162.463988)
			(xy 417.957 -162.407346) (xy 417.94938 -162.389312) (xy 417.942268 -162.381946) (xy 417.923467 -162.362354)
			(xy 417.891032 -162.318808) (xy 417.8651 -162.271102) (xy 417.846195 -162.220201) (xy 417.834698 -162.167133)
			(xy 417.830843 -162.112972) (xy 417.834706 -162.058811) (xy 417.846211 -162.005745) (xy 417.865124 -161.954847)
			(xy 417.891063 -161.907145) (xy 417.923504 -161.863603) (xy 417.942268 -161.843974) (xy 417.949009 -161.836603)
			(xy 417.956597 -161.818141) (xy 417.957 -161.80816) (xy 417.957 -159.349186) (xy 417.956574 -159.339117)
			(xy 417.948856 -159.320516) (xy 417.942014 -159.313118) (xy 417.48583 -158.856934) (xy 417.478429 -158.850095)
			(xy 417.459831 -158.842381) (xy 417.449762 -158.841948) (xy 415.116772 -158.841948) (xy 415.105146 -158.842512)
			(xy 415.08424 -158.852692) (xy 415.07664 -158.861506) (xy 415.059866 -158.882147) (xy 415.021549 -158.919035)
			(xy 414.978479 -158.950242) (xy 414.931493 -158.975166) (xy 414.8815 -158.993321) (xy 414.82947 -159.004357)
			(xy 414.776412 -159.00806) (xy 414.723354 -159.004357) (xy 414.671324 -158.993321) (xy 414.621331 -158.975166)
			(xy 414.574345 -158.950242) (xy 414.531275 -158.919035) (xy 414.492958 -158.882147) (xy 414.476184 -158.861506)
			(xy 414.468599 -158.852665) (xy 414.447688 -158.842455) (xy 414.436052 -158.841948) (xy 396.729204 -158.841948)
			(xy 396.719135 -158.842372) (xy 396.700534 -158.850091) (xy 396.693136 -158.856934) (xy 393.848082 -161.701988)
			(xy 409.929076 -161.701988) (xy 409.92965 -161.657219) (xy 409.938657 -161.568134) (xy 409.956559 -161.480403)
			(xy 409.983175 -161.394911) (xy 410.000196 -161.3535) (xy 410.00377 -161.343912) (xy 410.003765 -161.323466)
			(xy 410.000196 -161.313876) (xy 409.983153 -161.272472) (xy 409.956521 -161.186983) (xy 409.938618 -161.099248)
			(xy 409.929627 -161.010159) (xy 409.929076 -160.965388) (xy 409.92965 -160.920619) (xy 409.938657 -160.831534)
			(xy 409.956559 -160.743803) (xy 409.983175 -160.658311) (xy 410.000196 -160.6169) (xy 410.00377 -160.607312)
			(xy 410.003765 -160.586866) (xy 410.000196 -160.577276) (xy 409.983153 -160.535872) (xy 409.956521 -160.450383)
			(xy 409.938618 -160.362648) (xy 409.929627 -160.273559) (xy 409.929076 -160.228788) (xy 409.929541 -160.187678)
			(xy 409.93713 -160.105808) (xy 409.952241 -160.024988) (xy 409.974747 -159.945907) (xy 410.004454 -159.869241)
			(xy 410.041109 -159.795643) (xy 410.0844 -159.725742) (xy 410.133957 -159.660134) (xy 410.189357 -159.59938)
			(xy 410.250127 -159.543997) (xy 410.315748 -159.494459) (xy 410.385662 -159.451187) (xy 410.45927 -159.414553)
			(xy 410.535944 -159.384867) (xy 410.615031 -159.362384) (xy 410.695856 -159.347295) (xy 410.777728 -159.339729)
			(xy 410.818838 -159.33928) (xy 410.86045 -159.339758) (xy 410.943312 -159.347505) (xy 411.025087 -159.362965)
			(xy 411.105058 -159.386002) (xy 411.182525 -159.416415) (xy 411.25681 -159.453937) (xy 411.292294 -159.475678)
			(xy 411.301404 -159.480786) (xy 411.32205 -159.48383) (xy 411.342214 -159.478449) (xy 411.350714 -159.472376)
			(xy 411.384386 -159.446424) (xy 411.455825 -159.400332) (xy 411.531336 -159.361265) (xy 411.610229 -159.329579)
			(xy 411.691785 -159.305563) (xy 411.77526 -159.289436) (xy 411.859893 -159.281346) (xy 411.902402 -159.28086)
			(xy 411.943509 -159.281311) (xy 412.025374 -159.288895) (xy 412.106189 -159.304) (xy 412.185267 -159.326496)
			(xy 412.261931 -159.356191) (xy 412.33553 -159.392831) (xy 412.405434 -159.436106) (xy 412.471048 -159.485644)
			(xy 412.531813 -159.541025) (xy 412.587209 -159.601775) (xy 412.636764 -159.667376) (xy 412.680057 -159.737269)
			(xy 412.716716 -159.810858) (xy 412.746431 -159.887515) (xy 412.768947 -159.966587) (xy 412.784073 -160.047398)
			(xy 412.791679 -160.129261) (xy 412.792164 -160.170368) (xy 412.791606 -160.215138) (xy 412.782594 -160.304223)
			(xy 412.764688 -160.391954) (xy 412.738068 -160.477445) (xy 412.721044 -160.518856) (xy 412.717498 -160.528452)
			(xy 412.717487 -160.548889) (xy 412.721044 -160.55848) (xy 412.736814 -160.596795) (xy 412.762031 -160.675727)
			(xy 412.779794 -160.756662) (xy 412.78995 -160.8389) (xy 412.791656 -160.880298) (xy 412.792499 -160.891219)
			(xy 412.802145 -160.910859) (xy 412.819062 -160.924738) (xy 412.829502 -160.92805) (xy 412.846374 -160.932547)
			(xy 412.879785 -160.942711) (xy 412.896304 -160.94837) (xy 412.9045 -160.950893) (xy 412.921636 -160.950893)
			(xy 412.929832 -160.94837) (xy 412.96505 -160.936429) (xy 413.037059 -160.91784) (xy 413.110382 -160.905398)
			(xy 413.184492 -160.899192) (xy 413.221678 -160.89884) (xy 413.258862 -160.899213) (xy 413.33297 -160.905434)
			(xy 413.40629 -160.917875) (xy 413.478301 -160.936448) (xy 413.513524 -160.94837) (xy 413.52172 -160.950893)
			(xy 413.538856 -160.950893) (xy 413.547052 -160.94837) (xy 413.582277 -160.936451) (xy 413.654284 -160.917856)
			(xy 413.727604 -160.905408) (xy 413.801713 -160.899196) (xy 413.838898 -160.89884) (xy 413.880822 -160.899407)
			(xy 413.964291 -160.907377) (xy 414.046623 -160.923245) (xy 414.127075 -160.946868) (xy 414.204917 -160.978031)
			(xy 414.279444 -161.016452) (xy 414.349982 -161.061784) (xy 414.415891 -161.113615) (xy 414.476575 -161.171477)
			(xy 414.531484 -161.234845) (xy 414.580121 -161.303146) (xy 414.622045 -161.37576) (xy 414.656876 -161.452031)
			(xy 414.684301 -161.531268) (xy 414.704068 -161.612752) (xy 414.716001 -161.695747) (xy 414.719991 -161.7795)
			(xy 414.716001 -161.863253) (xy 414.704068 -161.946248) (xy 414.684301 -162.027732) (xy 414.656876 -162.106969)
			(xy 414.622045 -162.18324) (xy 414.580121 -162.255854) (xy 414.531484 -162.324155) (xy 414.476575 -162.387523)
			(xy 414.415891 -162.445385) (xy 414.349982 -162.497216) (xy 414.279444 -162.542548) (xy 414.204917 -162.580969)
			(xy 414.127075 -162.612132) (xy 414.046623 -162.635755) (xy 413.964291 -162.651623) (xy 413.880822 -162.659593)
			(xy 413.838898 -162.660076) (xy 413.801714 -162.659709) (xy 413.727606 -162.653487) (xy 413.654286 -162.641044)
			(xy 413.582275 -162.622469) (xy 413.547052 -162.610546) (xy 413.538856 -162.608023) (xy 413.52172 -162.608023)
			(xy 413.513524 -162.610546) (xy 413.484703 -162.620382) (xy 413.425976 -162.636526) (xy 413.396176 -162.642804)
			(xy 413.386613 -162.645219) (xy 413.370195 -162.656115) (xy 413.359083 -162.672387) (xy 413.356552 -162.68192)
			(xy 413.346352 -162.726278) (xy 413.318104 -162.812809) (xy 413.300164 -162.85464) (xy 413.296347 -162.864579)
			(xy 413.296353 -162.885846) (xy 413.300164 -162.895788) (xy 413.318411 -162.938449) (xy 413.346955 -163.026742)
			(xy 413.366147 -163.117527) (xy 413.37578 -163.209818) (xy 413.376364 -163.256214) (xy 413.37586 -163.298562)
			(xy 413.367809 -163.382876) (xy 413.35178 -163.466042) (xy 413.327919 -163.547309) (xy 413.29644 -163.625939)
			(xy 413.257629 -163.70122) (xy 413.211839 -163.772472) (xy 413.159483 -163.839048) (xy 413.101035 -163.900346)
			(xy 413.037025 -163.955811) (xy 412.968033 -164.00494) (xy 412.894683 -164.047289) (xy 412.81764 -164.082473)
			(xy 412.737601 -164.110175) (xy 412.655292 -164.130143) (xy 412.571457 -164.142196) (xy 412.486856 -164.146227)
			(xy 412.402255 -164.142196) (xy 412.31842 -164.130143) (xy 412.236111 -164.110175) (xy 412.156072 -164.082473)
			(xy 412.079029 -164.047289) (xy 412.005679 -164.00494) (xy 411.936687 -163.955811) (xy 411.872677 -163.900346)
			(xy 411.814229 -163.839048) (xy 411.761873 -163.772472) (xy 411.716083 -163.70122) (xy 411.677272 -163.625939)
			(xy 411.645793 -163.547309) (xy 411.621932 -163.466042) (xy 411.605903 -163.382876) (xy 411.597852 -163.298562)
			(xy 411.597348 -163.256214) (xy 411.597931 -163.209818) (xy 411.607575 -163.11753) (xy 411.626771 -163.026746)
			(xy 411.65531 -162.938453) (xy 411.673548 -162.895788) (xy 411.677348 -162.885844) (xy 411.677353 -162.864582)
			(xy 411.673548 -162.85464) (xy 411.655311 -162.811974) (xy 411.626764 -162.723684) (xy 411.607569 -162.632899)
			(xy 411.597934 -162.54061) (xy 411.597348 -162.494214) (xy 411.597953 -162.446404) (xy 411.608131 -162.351329)
			(xy 411.617668 -162.304476) (xy 411.61964 -162.292071) (xy 411.612727 -162.267957) (xy 411.60446 -162.258502)
			(xy 411.56382 -162.216338) (xy 411.560264 -162.2171) (xy 411.551448 -162.219368) (xy 411.536098 -162.229138)
			(xy 411.530292 -162.23615) (xy 411.505142 -162.268826) (xy 411.44974 -162.329904) (xy 411.388921 -162.38559)
			(xy 411.323208 -162.435407) (xy 411.253166 -162.478927) (xy 411.179396 -162.515776) (xy 411.102531 -162.545637)
			(xy 411.023231 -162.568254) (xy 410.942179 -162.583432) (xy 410.860069 -162.591042) (xy 410.818838 -162.591496)
			(xy 410.777733 -162.590951) (xy 410.695873 -162.583371) (xy 410.615061 -162.568271) (xy 410.535987 -162.54578)
			(xy 410.459325 -162.516091) (xy 410.385729 -162.479456) (xy 410.315826 -162.436187) (xy 410.250213 -162.386655)
			(xy 410.18945 -162.331281) (xy 410.134053 -162.270538) (xy 410.084497 -162.204943) (xy 410.041203 -162.135056)
			(xy 410.004541 -162.061473) (xy 409.974824 -161.984822) (xy 409.952304 -161.905756) (xy 409.937174 -161.82495)
			(xy 409.929564 -161.743093) (xy 409.929076 -161.701988) (xy 393.848082 -161.701988) (xy 389.163306 -166.386764)
			(xy 389.145263 -166.404019) (xy 389.103767 -166.431765) (xy 389.057649 -166.450868) (xy 389.008687 -166.46059)
			(xy 388.983728 -166.461186) (xy 375.76506 -166.461186) (xy 375.740105 -166.460571) (xy 375.691156 -166.450826)
			(xy 375.645048 -166.431719) (xy 375.603553 -166.403984) (xy 375.585482 -166.386764) (xy 372.757446 -163.558728)
			(xy 372.750046 -163.551887) (xy 372.731447 -163.544168) (xy 372.721378 -163.543742) (xy 371.644926 -163.543742)
			(xy 371.633257 -163.544309) (xy 371.612329 -163.554628) (xy 371.604794 -163.563554) (xy 371.548152 -163.63696)
			(xy 371.54358 -163.659566) (xy 371.546628 -163.67125) (xy 371.556021 -163.708401) (xy 371.569135 -163.783907)
			(xy 371.575699 -163.860262) (xy 371.576092 -163.89858) (xy 371.575687 -163.936863) (xy 371.569125 -164.013146)
			(xy 371.556038 -164.088585) (xy 371.536524 -164.162622) (xy 371.524022 -164.198808) (xy 371.521369 -164.207245)
			(xy 371.521362 -164.224918) (xy 371.524022 -164.233352) (xy 371.536558 -164.269528) (xy 371.556087 -164.343564)
			(xy 371.56917 -164.419007) (xy 371.575711 -164.495295) (xy 371.576092 -164.53358) (xy 371.575689 -164.571359)
			(xy 371.569283 -164.646646) (xy 371.556523 -164.721119) (xy 371.537501 -164.794244) (xy 371.525292 -164.829998)
			(xy 371.522635 -164.838727) (xy 371.523012 -164.856957) (xy 371.526054 -164.865558) (xy 371.541111 -164.904826)
			(xy 371.564617 -164.98558) (xy 371.580393 -165.068193) (xy 371.588299 -165.151927) (xy 371.588792 -165.19398)
			(xy 371.588333 -165.235083) (xy 371.580749 -165.31694) (xy 371.565645 -165.397747) (xy 371.543149 -165.476817)
			(xy 371.513454 -165.553473) (xy 371.476812 -165.627062) (xy 371.433536 -165.696956) (xy 371.383996 -165.762559)
			(xy 371.328613 -165.823311) (xy 371.267862 -165.878693) (xy 371.202259 -165.928234) (xy 371.132365 -165.97151)
			(xy 371.058776 -166.008152) (xy 370.98212 -166.037848) (xy 370.903051 -166.060344) (xy 370.822244 -166.075449)
			(xy 370.740387 -166.083033) (xy 370.699284 -166.083488) (xy 370.65452 -166.082959) (xy 370.565439 -166.074019)
			(xy 370.477706 -166.056182) (xy 370.392207 -166.029628) (xy 370.350796 -166.012622) (xy 370.341205 -166.009057)
			(xy 370.320763 -166.009057) (xy 370.311172 -166.012622) (xy 370.269758 -166.029622) (xy 370.184263 -166.056187)
			(xy 370.09653 -166.074023) (xy 370.007448 -166.08295) (xy 369.962684 -166.083488) (xy 369.924401 -166.083086)
			(xy 369.848116 -166.076529) (xy 369.772675 -166.063447) (xy 369.698636 -166.043938) (xy 369.662456 -166.031418)
			(xy 369.654019 -166.028767) (xy 369.636349 -166.028767) (xy 369.627912 -166.031418) (xy 369.591737 -166.043957)
			(xy 369.517701 -166.063491) (xy 369.442258 -166.07658) (xy 369.365969 -166.083126) (xy 369.327684 -166.083488)
			(xy 369.289401 -166.083086) (xy 369.213116 -166.076529) (xy 369.137675 -166.063447) (xy 369.063636 -166.043938)
			(xy 369.027456 -166.031418) (xy 369.019019 -166.028767) (xy 369.001349 -166.028767) (xy 368.992912 -166.031418)
			(xy 368.956737 -166.043957) (xy 368.882701 -166.063491) (xy 368.807258 -166.07658) (xy 368.730969 -166.083126)
			(xy 368.692684 -166.083488) (xy 368.654401 -166.083086) (xy 368.578116 -166.076529) (xy 368.502675 -166.063447)
			(xy 368.428636 -166.043938) (xy 368.392456 -166.031418) (xy 368.384019 -166.028767) (xy 368.366349 -166.028767)
			(xy 368.357912 -166.031418) (xy 368.321737 -166.043957) (xy 368.247701 -166.063491) (xy 368.172258 -166.07658)
			(xy 368.095969 -166.083126) (xy 368.057684 -166.083488) (xy 368.017471 -166.08305) (xy 367.937372 -166.075813)
			(xy 367.858251 -166.061382) (xy 367.780755 -166.039874) (xy 367.742978 -166.026084) (xy 367.734191 -166.023177)
			(xy 367.715697 -166.023177) (xy 367.70691 -166.026084) (xy 367.669135 -166.039882) (xy 367.591641 -166.061404)
			(xy 367.51252 -166.075836) (xy 367.432418 -166.083058) (xy 367.392204 -166.083488) (xy 367.353921 -166.083082)
			(xy 367.277638 -166.076519) (xy 367.2022 -166.063431) (xy 367.128164 -166.043916) (xy 367.091976 -166.031418)
			(xy 367.083539 -166.028767) (xy 367.065869 -166.028767) (xy 367.057432 -166.031418) (xy 367.021256 -166.043953)
			(xy 366.94722 -166.063481) (xy 366.871777 -166.076563) (xy 366.795488 -166.083103) (xy 366.757204 -166.083488)
			(xy 366.716101 -166.083028) (xy 366.634246 -166.075443) (xy 366.55344 -166.060338) (xy 366.474372 -166.037841)
			(xy 366.397717 -166.008145) (xy 366.32413 -165.971502) (xy 366.254237 -165.928226) (xy 366.188636 -165.878686)
			(xy 366.127885 -165.823303) (xy 366.072504 -165.762552) (xy 366.022965 -165.69695) (xy 365.97969 -165.627056)
			(xy 365.943049 -165.553468) (xy 365.913354 -165.476813) (xy 365.890858 -165.397745) (xy 365.875755 -165.316938)
			(xy 365.868171 -165.235083) (xy 365.867696 -165.19398) (xy 365.868101 -165.156201) (xy 365.87451 -165.080916)
			(xy 365.887273 -165.006443) (xy 365.906298 -164.93332) (xy 365.918496 -164.897562) (xy 365.921146 -164.888833)
			(xy 365.920756 -164.870609) (xy 365.917734 -164.862002) (xy 365.902673 -164.822735) (xy 365.879159 -164.741981)
			(xy 365.863376 -164.659368) (xy 365.855464 -164.575634) (xy 365.854996 -164.53358) (xy 365.855398 -164.495297)
			(xy 365.861956 -164.419012) (xy 365.875037 -164.343571) (xy 365.894546 -164.269532) (xy 365.907066 -164.233352)
			(xy 365.909713 -164.224915) (xy 365.909706 -164.207247) (xy 365.907066 -164.198808) (xy 365.894528 -164.162632)
			(xy 365.874994 -164.088597) (xy 365.861906 -164.013154) (xy 365.85536 -163.936865) (xy 365.854996 -163.89858)
			(xy 365.855389 -163.860262) (xy 365.861963 -163.783909) (xy 365.875078 -163.708404) (xy 365.88446 -163.67125)
			(xy 365.887508 -163.659566) (xy 365.882936 -163.63696) (xy 365.826294 -163.563554) (xy 365.818709 -163.554693)
			(xy 365.797809 -163.54439) (xy 365.786162 -163.543742) (xy 358.13365 -163.543742) (xy 358.108692 -163.543166)
			(xy 358.059737 -163.533417) (xy 358.013625 -163.514303) (xy 357.972129 -163.48656) (xy 357.954072 -163.46932)
			(xy 351.3455 -156.860748) (xy 351.338104 -156.853896) (xy 351.319505 -156.846154) (xy 351.309432 -156.845762)
			(xy 350.068388 -156.845762) (xy 350.05949 -156.846201) (xy 350.042798 -156.852382) (xy 350.02922 -156.863893)
			(xy 350.024446 -156.871416) (xy 350.010761 -156.894401) (xy 349.977951 -156.936651) (xy 349.939563 -156.973906)
			(xy 349.896349 -157.005437) (xy 349.849157 -157.030625) (xy 349.79891 -157.048978) (xy 349.746593 -157.060135)
			(xy 349.69323 -157.063879) (xy 349.639867 -157.060135) (xy 349.58755 -157.048978) (xy 349.537303 -157.030625)
			(xy 349.490111 -157.005437) (xy 349.446897 -156.973906) (xy 349.408509 -156.936651) (xy 349.375699 -156.894401)
			(xy 349.362014 -156.871416) (xy 349.357317 -156.863824) (xy 349.343727 -156.852265) (xy 349.326992 -156.846078)
			(xy 349.318072 -156.845762) (xy 348.206314 -156.845762) (xy 348.178628 -156.86786) (xy 348.174818 -156.885132)
			(xy 348.168301 -156.911353) (xy 348.148875 -156.961769) (xy 348.122532 -157.008941) (xy 348.089797 -157.051926)
			(xy 348.051327 -157.089863) (xy 348.00789 -157.121994) (xy 347.960355 -157.147677) (xy 347.909673 -157.166398)
			(xy 347.856856 -157.177782) (xy 347.802962 -157.181602) (xy 347.749068 -157.177782) (xy 347.696251 -157.166398)
			(xy 347.645569 -157.147677) (xy 347.598034 -157.121994) (xy 347.554597 -157.089863) (xy 347.516127 -157.051926)
			(xy 347.483392 -157.008941) (xy 347.457049 -156.961769) (xy 347.437623 -156.911353) (xy 347.431106 -156.885132)
			(xy 347.427296 -156.86786) (xy 347.39961 -156.845762) (xy 345.89339 -156.845762) (xy 345.883962 -156.846142)
			(xy 345.866385 -156.852966) (xy 345.852467 -156.865686) (xy 345.847924 -156.873956) (xy 345.800934 -156.96819)
			(xy 345.803474 -156.996638) (xy 345.81211 -157.008322) (xy 345.836277 -157.041312) (xy 345.879146 -157.110962)
			(xy 345.915445 -157.184251) (xy 345.944869 -157.26056) (xy 345.967169 -157.339247) (xy 345.982157 -157.419647)
			(xy 345.989707 -157.501084) (xy 345.990164 -157.541976) (xy 345.989614 -157.586747) (xy 345.980624 -157.675837)
			(xy 345.962723 -157.763572) (xy 345.936093 -157.849063) (xy 345.919044 -157.890464) (xy 345.915475 -157.900055)
			(xy 345.915466 -157.920501) (xy 345.919044 -157.930088) (xy 345.934825 -157.968399) (xy 345.960034 -158.047334)
			(xy 345.977796 -158.12827) (xy 345.98796 -158.210507) (xy 345.989656 -158.251906) (xy 345.990452 -158.262842)
			(xy 346.000076 -158.282517) (xy 346.01704 -158.296372) (xy 346.027502 -158.299658) (xy 346.044374 -158.304158)
			(xy 346.077785 -158.314321) (xy 346.094304 -158.319978) (xy 346.1025 -158.322501) (xy 346.119636 -158.322501)
			(xy 346.127832 -158.319978) (xy 346.163055 -158.308054) (xy 346.235066 -158.289477) (xy 346.308386 -158.277032)
			(xy 346.382493 -158.270808) (xy 346.419678 -158.270448) (xy 346.456863 -158.270803) (xy 346.530973 -158.277013)
			(xy 346.604294 -158.289457) (xy 346.676303 -158.308048) (xy 346.711524 -158.319978) (xy 346.71972 -158.322501)
			(xy 346.736856 -158.322501) (xy 346.745052 -158.319978) (xy 346.780275 -158.308055) (xy 346.852286 -158.28948)
			(xy 346.925606 -158.277036) (xy 346.999714 -158.270814) (xy 347.036898 -158.270448) (xy 347.078826 -158.270931)
			(xy 347.162301 -158.278902) (xy 347.244641 -158.294771) (xy 347.3251 -158.318396) (xy 347.402949 -158.349562)
			(xy 347.477482 -158.387986) (xy 347.548026 -158.433322) (xy 347.613941 -158.485158) (xy 347.67463 -158.543024)
			(xy 347.729544 -158.606398) (xy 347.778184 -158.674705) (xy 347.820112 -158.747325) (xy 347.854947 -158.823603)
			(xy 347.882373 -158.902846) (xy 347.902143 -158.984338) (xy 347.914077 -159.06734) (xy 347.918067 -159.1511)
			(xy 347.914077 -159.23486) (xy 347.902143 -159.317862) (xy 347.882373 -159.399354) (xy 347.854947 -159.478597)
			(xy 347.820112 -159.554875) (xy 347.778184 -159.627495) (xy 347.729544 -159.695802) (xy 347.67463 -159.759176)
			(xy 347.613941 -159.817042) (xy 347.548026 -159.868878) (xy 347.477482 -159.914214) (xy 347.402949 -159.952638)
			(xy 347.3251 -159.983804) (xy 347.244641 -160.007429) (xy 347.162301 -160.023298) (xy 347.078826 -160.031269)
			(xy 347.036898 -160.031684) (xy 346.999713 -160.031328) (xy 346.925604 -160.025116) (xy 346.852284 -160.012668)
			(xy 346.780277 -159.994074) (xy 346.745052 -159.982154) (xy 346.736856 -159.979631) (xy 346.71972 -159.979631)
			(xy 346.711524 -159.982154) (xy 346.684116 -159.9915) (xy 346.628318 -160.007005) (xy 346.600018 -160.013142)
			(xy 346.590236 -160.015623) (xy 346.573599 -160.02702) (xy 346.562627 -160.04394) (xy 346.560394 -160.053782)
			(xy 346.550931 -160.102889) (xy 346.522415 -160.198749) (xy 346.503498 -160.245044) (xy 346.499922 -160.254635)
			(xy 346.499906 -160.275085) (xy 346.503498 -160.284668) (xy 346.520501 -160.326081) (xy 346.547073 -160.411576)
			(xy 346.564915 -160.499309) (xy 346.573849 -160.588391) (xy 346.574364 -160.633156) (xy 346.57386 -160.675504)
			(xy 346.565809 -160.759818) (xy 346.54978 -160.842984) (xy 346.525919 -160.924251) (xy 346.49444 -161.002881)
			(xy 346.455629 -161.078162) (xy 346.409839 -161.149414) (xy 346.357483 -161.21599) (xy 346.299035 -161.277288)
			(xy 346.235025 -161.332753) (xy 346.166033 -161.381882) (xy 346.092683 -161.424231) (xy 346.01564 -161.459415)
			(xy 345.935601 -161.487117) (xy 345.853292 -161.507085) (xy 345.769457 -161.519138) (xy 345.684856 -161.523169)
			(xy 345.600255 -161.519138) (xy 345.51642 -161.507085) (xy 345.434111 -161.487117) (xy 345.354072 -161.459415)
			(xy 345.277029 -161.424231) (xy 345.203679 -161.381882) (xy 345.134687 -161.332753) (xy 345.070677 -161.277288)
			(xy 345.012229 -161.21599) (xy 344.959873 -161.149414) (xy 344.914083 -161.078162) (xy 344.875272 -161.002881)
			(xy 344.843793 -160.924251) (xy 344.819932 -160.842984) (xy 344.803903 -160.759818) (xy 344.795852 -160.675504)
			(xy 344.795348 -160.633156) (xy 344.795879 -160.588392) (xy 344.804821 -160.499313) (xy 344.822661 -160.411581)
			(xy 344.849219 -160.326084) (xy 344.866214 -160.284668) (xy 344.869771 -160.275078) (xy 344.869755 -160.254642)
			(xy 344.866214 -160.245044) (xy 344.84921 -160.203631) (xy 344.822637 -160.118136) (xy 344.804793 -160.030403)
			(xy 344.795858 -159.941321) (xy 344.795348 -159.896556) (xy 344.795687 -159.859467) (xy 344.801777 -159.785539)
			(xy 344.814004 -159.712376) (xy 344.82278 -159.676338) (xy 344.82455 -159.668013) (xy 344.823085 -159.651066)
			(xy 344.816159 -159.635529) (xy 344.810588 -159.629094) (xy 344.78976 -159.606742) (xy 344.783674 -159.600773)
			(xy 344.768557 -159.592916) (xy 344.7517 -159.590446) (xy 344.743278 -159.591756) (xy 344.739468 -159.592518)
			(xy 344.71446 -159.626484) (xy 344.658986 -159.690029) (xy 344.597746 -159.748037) (xy 344.53129 -159.799988)
			(xy 344.460215 -159.845416) (xy 344.385159 -159.883912) (xy 344.306796 -159.915131) (xy 344.22583 -159.938792)
			(xy 344.142988 -159.954683) (xy 344.059014 -159.962662) (xy 344.016838 -159.963104) (xy 343.975729 -159.962631)
			(xy 343.893863 -159.95505) (xy 343.813044 -159.939949) (xy 343.733963 -159.917456) (xy 343.657295 -159.887765)
			(xy 343.583692 -159.851127) (xy 343.513784 -159.807855) (xy 343.448165 -159.758319) (xy 343.387396 -159.70294)
			(xy 343.331995 -159.642192) (xy 343.282434 -159.576592) (xy 343.239136 -159.5067) (xy 343.20247 -159.433111)
			(xy 343.17275 -159.356453) (xy 343.150228 -159.277381) (xy 343.135096 -159.196568) (xy 343.127484 -159.114704)
			(xy 343.127076 -159.073596) (xy 343.127628 -159.028825) (xy 343.13662 -158.939736) (xy 343.154524 -158.852003)
			(xy 343.181158 -158.766514) (xy 343.198196 -158.725108) (xy 343.201762 -158.715518) (xy 343.20176 -158.695075)
			(xy 343.198196 -158.685484) (xy 343.181175 -158.644073) (xy 343.154561 -158.558581) (xy 343.136661 -158.47085)
			(xy 343.127656 -158.381765) (xy 343.127076 -158.336996) (xy 343.127628 -158.292225) (xy 343.13662 -158.203136)
			(xy 343.154524 -158.115403) (xy 343.181158 -158.029914) (xy 343.198196 -157.988508) (xy 343.201762 -157.978918)
			(xy 343.20176 -157.958475) (xy 343.198196 -157.948884) (xy 343.181175 -157.907473) (xy 343.154561 -157.821981)
			(xy 343.136661 -157.73425) (xy 343.127656 -157.645165) (xy 343.127076 -157.600396) (xy 343.127514 -157.560386)
			(xy 343.1347 -157.48069) (xy 343.149014 -157.401962) (xy 343.17034 -157.324836) (xy 343.198505 -157.249938)
			(xy 343.233283 -157.177871) (xy 343.274391 -157.109218) (xy 343.321499 -157.044535) (xy 343.347548 -157.014164)
			(xy 343.357454 -157.002988) (xy 343.361772 -156.973524) (xy 343.317322 -156.87548) (xy 343.312906 -156.866812)
			(xy 343.298853 -156.853386) (xy 343.280812 -156.846154) (xy 343.271094 -156.845762) (xy 338.569808 -156.845762)
			(xy 338.559738 -156.846185) (xy 338.541138 -156.853905) (xy 338.53374 -156.860748) (xy 338.168742 -157.225746)
			(xy 338.161898 -157.233145) (xy 338.154174 -157.251744) (xy 338.153756 -157.261814) (xy 338.153756 -167.430196)
			(xy 351.432876 -167.430196) (xy 351.433453 -167.385427) (xy 351.442459 -167.296342) (xy 351.46036 -167.208611)
			(xy 351.486975 -167.123119) (xy 351.503996 -167.081708) (xy 351.507565 -167.072118) (xy 351.507564 -167.051674)
			(xy 351.503996 -167.042084) (xy 351.486956 -167.000679) (xy 351.460322 -166.91519) (xy 351.442419 -166.827456)
			(xy 351.433427 -166.738367) (xy 351.432876 -166.693596) (xy 351.433453 -166.648827) (xy 351.442459 -166.559742)
			(xy 351.46036 -166.472011) (xy 351.486975 -166.386519) (xy 351.503996 -166.345108) (xy 351.507565 -166.335518)
			(xy 351.507564 -166.315074) (xy 351.503996 -166.305484) (xy 351.486956 -166.264079) (xy 351.460322 -166.17859)
			(xy 351.442419 -166.090856) (xy 351.433427 -166.001767) (xy 351.432876 -165.956996) (xy 351.433349 -165.915886)
			(xy 351.440937 -165.834016) (xy 351.456047 -165.753196) (xy 351.478552 -165.674116) (xy 351.508259 -165.597449)
			(xy 351.544914 -165.523852) (xy 351.588204 -165.453951) (xy 351.63776 -165.388343) (xy 351.693159 -165.327588)
			(xy 351.753929 -165.272205) (xy 351.81955 -165.222667) (xy 351.889463 -165.179396) (xy 351.963071 -165.142761)
			(xy 352.039745 -165.113075) (xy 352.118832 -165.090592) (xy 352.199656 -165.075503) (xy 352.281528 -165.067937)
			(xy 352.322638 -165.067488) (xy 352.364249 -165.06798) (xy 352.447111 -165.075726) (xy 352.528885 -165.091184)
			(xy 352.608856 -165.114219) (xy 352.686324 -165.144629) (xy 352.760609 -165.182147) (xy 352.796094 -165.203886)
			(xy 352.805204 -165.208993) (xy 352.82585 -165.212036) (xy 352.846014 -165.206657) (xy 352.854514 -165.200584)
			(xy 352.888186 -165.174633) (xy 352.959626 -165.128541) (xy 353.035137 -165.089474) (xy 353.11403 -165.057787)
			(xy 353.195586 -165.033771) (xy 353.27906 -165.017645) (xy 353.363693 -165.009554) (xy 353.406202 -165.009068)
			(xy 353.44731 -165.009511) (xy 353.529174 -165.017096) (xy 353.60999 -165.0322) (xy 353.689068 -165.054696)
			(xy 353.765733 -165.084391) (xy 353.839332 -165.121033) (xy 353.909237 -165.164307) (xy 353.974851 -165.213846)
			(xy 354.035616 -165.269227) (xy 354.091012 -165.329978) (xy 354.140567 -165.39558) (xy 354.183859 -165.465474)
			(xy 354.220519 -165.539063) (xy 354.250233 -165.615721) (xy 354.272749 -165.694793) (xy 354.287874 -165.775606)
			(xy 354.295479 -165.857468) (xy 354.295964 -165.898576) (xy 354.295409 -165.943346) (xy 354.286396 -166.032431)
			(xy 354.268489 -166.120162) (xy 354.241868 -166.205653) (xy 354.224844 -166.247064) (xy 354.221294 -166.256659)
			(xy 354.221285 -166.277097) (xy 354.224844 -166.286688) (xy 354.240617 -166.325002) (xy 354.265832 -166.403934)
			(xy 354.283595 -166.48487) (xy 354.288919 -166.527988) (xy 401.547076 -166.527988) (xy 401.54765 -166.483219)
			(xy 401.556657 -166.394134) (xy 401.574559 -166.306403) (xy 401.601175 -166.220911) (xy 401.618196 -166.1795)
			(xy 401.62177 -166.169912) (xy 401.621765 -166.149466) (xy 401.618196 -166.139876) (xy 401.601153 -166.098472)
			(xy 401.574521 -166.012983) (xy 401.556618 -165.925248) (xy 401.547627 -165.836159) (xy 401.547076 -165.791388)
			(xy 401.54765 -165.746619) (xy 401.556657 -165.657534) (xy 401.574559 -165.569803) (xy 401.601175 -165.484311)
			(xy 401.618196 -165.4429) (xy 401.62177 -165.433312) (xy 401.621765 -165.412866) (xy 401.618196 -165.403276)
			(xy 401.601153 -165.361872) (xy 401.574521 -165.276383) (xy 401.556618 -165.188648) (xy 401.547627 -165.099559)
			(xy 401.547076 -165.054788) (xy 401.547541 -165.013678) (xy 401.55513 -164.931808) (xy 401.570241 -164.850988)
			(xy 401.592747 -164.771907) (xy 401.622454 -164.695241) (xy 401.659109 -164.621643) (xy 401.7024 -164.551742)
			(xy 401.751957 -164.486134) (xy 401.807357 -164.42538) (xy 401.868127 -164.369997) (xy 401.933748 -164.320459)
			(xy 402.003662 -164.277187) (xy 402.07727 -164.240553) (xy 402.153944 -164.210867) (xy 402.233031 -164.188384)
			(xy 402.313856 -164.173295) (xy 402.395728 -164.165729) (xy 402.436838 -164.16528) (xy 402.47845 -164.165758)
			(xy 402.561312 -164.173505) (xy 402.643087 -164.188965) (xy 402.723058 -164.212002) (xy 402.800525 -164.242415)
			(xy 402.87481 -164.279937) (xy 402.910294 -164.301678) (xy 402.919404 -164.306786) (xy 402.94005 -164.30983)
			(xy 402.960214 -164.304449) (xy 402.968714 -164.298376) (xy 403.002386 -164.272424) (xy 403.073825 -164.226332)
			(xy 403.149336 -164.187265) (xy 403.228229 -164.155579) (xy 403.309785 -164.131563) (xy 403.39326 -164.115436)
			(xy 403.477893 -164.107346) (xy 403.520402 -164.10686) (xy 403.561509 -164.107311) (xy 403.643374 -164.114895)
			(xy 403.724189 -164.13) (xy 403.803267 -164.152496) (xy 403.879931 -164.182191) (xy 403.95353 -164.218831)
			(xy 404.023434 -164.262106) (xy 404.089048 -164.311644) (xy 404.149813 -164.367025) (xy 404.205209 -164.427775)
			(xy 404.254764 -164.493376) (xy 404.298057 -164.563269) (xy 404.334716 -164.636858) (xy 404.364431 -164.713515)
			(xy 404.386947 -164.792587) (xy 404.402073 -164.873398) (xy 404.409679 -164.955261) (xy 404.410164 -164.996368)
			(xy 404.409606 -165.041138) (xy 404.400594 -165.130223) (xy 404.382688 -165.217954) (xy 404.356068 -165.303445)
			(xy 404.339044 -165.344856) (xy 404.335498 -165.354452) (xy 404.335487 -165.374889) (xy 404.339044 -165.38448)
			(xy 404.354814 -165.422795) (xy 404.380031 -165.501727) (xy 404.397794 -165.582662) (xy 404.40795 -165.6649)
			(xy 404.409656 -165.706298) (xy 404.410499 -165.717219) (xy 404.420145 -165.736859) (xy 404.437062 -165.750738)
			(xy 404.447502 -165.75405) (xy 404.464374 -165.758547) (xy 404.497785 -165.768711) (xy 404.514304 -165.77437)
			(xy 404.5225 -165.776893) (xy 404.539636 -165.776893) (xy 404.547832 -165.77437) (xy 404.58305 -165.762429)
			(xy 404.655059 -165.74384) (xy 404.728382 -165.731398) (xy 404.802492 -165.725192) (xy 404.839678 -165.72484)
			(xy 404.876862 -165.725213) (xy 404.95097 -165.731434) (xy 405.02429 -165.743875) (xy 405.096301 -165.762448)
			(xy 405.131524 -165.77437) (xy 405.13972 -165.776893) (xy 405.156856 -165.776893) (xy 405.165052 -165.77437)
			(xy 405.200277 -165.762451) (xy 405.272284 -165.743856) (xy 405.345604 -165.731408) (xy 405.419713 -165.725196)
			(xy 405.456898 -165.72484) (xy 405.498822 -165.725407) (xy 405.582291 -165.733377) (xy 405.664623 -165.749245)
			(xy 405.745075 -165.772868) (xy 405.822917 -165.804031) (xy 405.897444 -165.842452) (xy 405.967982 -165.887784)
			(xy 406.033891 -165.939615) (xy 406.094575 -165.997477) (xy 406.149484 -166.060845) (xy 406.198121 -166.129146)
			(xy 406.240045 -166.20176) (xy 406.274876 -166.278031) (xy 406.302301 -166.357268) (xy 406.322068 -166.438752)
			(xy 406.334001 -166.521747) (xy 406.337991 -166.6055) (xy 406.334001 -166.689253) (xy 406.322068 -166.772248)
			(xy 406.302301 -166.853732) (xy 406.274876 -166.932969) (xy 406.240045 -167.00924) (xy 406.198121 -167.081854)
			(xy 406.149484 -167.150155) (xy 406.094575 -167.213523) (xy 406.033891 -167.271385) (xy 405.967982 -167.323216)
			(xy 405.897444 -167.368548) (xy 405.822917 -167.406969) (xy 405.745075 -167.438132) (xy 405.664623 -167.461755)
			(xy 405.582291 -167.477623) (xy 405.498822 -167.485593) (xy 405.456898 -167.486076) (xy 405.419714 -167.485709)
			(xy 405.345606 -167.479487) (xy 405.272286 -167.467044) (xy 405.200275 -167.448469) (xy 405.165052 -167.436546)
			(xy 405.156856 -167.434023) (xy 405.13972 -167.434023) (xy 405.131524 -167.436546) (xy 405.102703 -167.446382)
			(xy 405.043976 -167.462526) (xy 405.014176 -167.468804) (xy 405.004613 -167.471219) (xy 404.988195 -167.482115)
			(xy 404.977083 -167.498387) (xy 404.974552 -167.50792) (xy 404.964352 -167.552278) (xy 404.936104 -167.638809)
			(xy 404.918164 -167.68064) (xy 404.914347 -167.690579) (xy 404.914353 -167.711846) (xy 404.918164 -167.721788)
			(xy 404.936411 -167.764449) (xy 404.964955 -167.852742) (xy 404.984147 -167.943527) (xy 404.99378 -168.035818)
			(xy 404.994364 -168.082214) (xy 404.99386 -168.124562) (xy 404.985809 -168.208876) (xy 404.96978 -168.292042)
			(xy 404.945919 -168.373309) (xy 404.91444 -168.451939) (xy 404.875629 -168.52722) (xy 404.829839 -168.598472)
			(xy 404.777483 -168.665048) (xy 404.719035 -168.726346) (xy 404.655025 -168.781811) (xy 404.586033 -168.83094)
			(xy 404.512683 -168.873289) (xy 404.43564 -168.908473) (xy 404.355601 -168.936175) (xy 404.273292 -168.956143)
			(xy 404.189457 -168.968196) (xy 404.104856 -168.972227) (xy 404.020255 -168.968196) (xy 403.93642 -168.956143)
			(xy 403.854111 -168.936175) (xy 403.774072 -168.908473) (xy 403.697029 -168.873289) (xy 403.623679 -168.83094)
			(xy 403.554687 -168.781811) (xy 403.490677 -168.726346) (xy 403.432229 -168.665048) (xy 403.379873 -168.598472)
			(xy 403.334083 -168.52722) (xy 403.295272 -168.451939) (xy 403.263793 -168.373309) (xy 403.239932 -168.292042)
			(xy 403.223903 -168.208876) (xy 403.215852 -168.124562) (xy 403.215348 -168.082214) (xy 403.215931 -168.035818)
			(xy 403.225575 -167.94353) (xy 403.244771 -167.852746) (xy 403.27331 -167.764453) (xy 403.291548 -167.721788)
			(xy 403.295348 -167.711844) (xy 403.295353 -167.690582) (xy 403.291548 -167.68064) (xy 403.273311 -167.637974)
			(xy 403.244764 -167.549684) (xy 403.225569 -167.458899) (xy 403.215934 -167.36661) (xy 403.215348 -167.320214)
			(xy 403.215953 -167.272404) (xy 403.226131 -167.177329) (xy 403.235668 -167.130476) (xy 403.23764 -167.118071)
			(xy 403.230727 -167.093957) (xy 403.22246 -167.084502) (xy 403.18182 -167.042338) (xy 403.178264 -167.0431)
			(xy 403.169448 -167.045368) (xy 403.154098 -167.055138) (xy 403.148292 -167.06215) (xy 403.123142 -167.094826)
			(xy 403.06774 -167.155904) (xy 403.006921 -167.21159) (xy 402.941208 -167.261407) (xy 402.871166 -167.304927)
			(xy 402.797396 -167.341776) (xy 402.720531 -167.371637) (xy 402.641231 -167.394254) (xy 402.560179 -167.409432)
			(xy 402.478069 -167.417042) (xy 402.436838 -167.417496) (xy 402.395733 -167.416951) (xy 402.313873 -167.409371)
			(xy 402.233061 -167.394271) (xy 402.153987 -167.37178) (xy 402.077325 -167.342091) (xy 402.003729 -167.305456)
			(xy 401.933826 -167.262187) (xy 401.868213 -167.212655) (xy 401.80745 -167.157281) (xy 401.752053 -167.096538)
			(xy 401.702497 -167.030943) (xy 401.659203 -166.961056) (xy 401.622541 -166.887473) (xy 401.592824 -166.810822)
			(xy 401.570304 -166.731756) (xy 401.555174 -166.65095) (xy 401.547564 -166.569093) (xy 401.547076 -166.527988)
			(xy 354.288919 -166.527988) (xy 354.29375 -166.567107) (xy 354.295456 -166.608506) (xy 354.296293 -166.619427)
			(xy 354.305942 -166.639068) (xy 354.322861 -166.652946) (xy 354.333302 -166.656258) (xy 354.350174 -166.660755)
			(xy 354.383585 -166.670919) (xy 354.400104 -166.676578) (xy 354.4083 -166.679101) (xy 354.425436 -166.679101)
			(xy 354.433632 -166.676578) (xy 354.468848 -166.664633) (xy 354.540859 -166.646046) (xy 354.614181 -166.633606)
			(xy 354.688292 -166.6274) (xy 354.725478 -166.627048) (xy 354.762662 -166.62742) (xy 354.83677 -166.633641)
			(xy 354.91009 -166.646083) (xy 354.982101 -166.664656) (xy 355.017324 -166.676578) (xy 355.02552 -166.679101)
			(xy 355.042656 -166.679101) (xy 355.050852 -166.676578) (xy 355.086076 -166.664655) (xy 355.158083 -166.646062)
			(xy 355.231404 -166.633616) (xy 355.305513 -166.627404) (xy 355.342698 -166.627048) (xy 355.384622 -166.627599)
			(xy 355.468092 -166.635569) (xy 355.550425 -166.651437) (xy 355.630878 -166.67506) (xy 355.70872 -166.706224)
			(xy 355.783248 -166.744645) (xy 355.853787 -166.789977) (xy 355.919696 -166.841809) (xy 355.980381 -166.899671)
			(xy 356.03529 -166.96304) (xy 356.083927 -167.031341) (xy 356.125852 -167.103957) (xy 356.160684 -167.180228)
			(xy 356.188108 -167.259465) (xy 356.207876 -167.340951) (xy 356.219809 -167.423946) (xy 356.223799 -167.5077)
			(xy 356.219809 -167.591454) (xy 356.207876 -167.674449) (xy 356.188108 -167.755935) (xy 356.160684 -167.835172)
			(xy 356.125852 -167.911443) (xy 356.083927 -167.984059) (xy 356.03529 -168.05236) (xy 355.980381 -168.115729)
			(xy 355.919696 -168.173591) (xy 355.853787 -168.225423) (xy 355.783248 -168.270755) (xy 355.70872 -168.309176)
			(xy 355.630878 -168.34034) (xy 355.550425 -168.363963) (xy 355.468092 -168.379831) (xy 355.384622 -168.387801)
			(xy 355.342698 -168.388284) (xy 355.305514 -168.387917) (xy 355.231406 -168.381694) (xy 355.158086 -168.369251)
			(xy 355.086075 -168.350676) (xy 355.050852 -168.338754) (xy 355.042656 -168.336231) (xy 355.02552 -168.336231)
			(xy 355.017324 -168.338754) (xy 354.989608 -168.348198) (xy 354.933173 -168.363832) (xy 354.904548 -168.369996)
			(xy 354.894796 -168.372455) (xy 354.878183 -168.383762) (xy 354.867189 -168.400583) (xy 354.864924 -168.410382)
			(xy 354.855394 -168.457508) (xy 354.827522 -168.549531) (xy 354.809298 -168.594024) (xy 354.805711 -168.603608)
			(xy 354.805724 -168.624057) (xy 354.809298 -168.633648) (xy 354.826287 -168.675066) (xy 354.852846 -168.760563)
			(xy 354.870688 -168.848293) (xy 354.879632 -168.937372) (xy 354.880164 -168.982136) (xy 354.87966 -169.024484)
			(xy 354.871609 -169.108798) (xy 354.85558 -169.191964) (xy 354.831719 -169.273231) (xy 354.80024 -169.351861)
			(xy 354.761429 -169.427142) (xy 354.715639 -169.498394) (xy 354.663283 -169.56497) (xy 354.604835 -169.626268)
			(xy 354.540825 -169.681733) (xy 354.471833 -169.730862) (xy 354.398483 -169.773211) (xy 354.32144 -169.808395)
			(xy 354.241401 -169.836097) (xy 354.159092 -169.856065) (xy 354.075257 -169.868118) (xy 353.990656 -169.872149)
			(xy 353.906055 -169.868118) (xy 353.82222 -169.856065) (xy 353.739911 -169.836097) (xy 353.659872 -169.808395)
			(xy 353.582829 -169.773211) (xy 353.509479 -169.730862) (xy 353.440487 -169.681733) (xy 353.376477 -169.626268)
			(xy 353.318029 -169.56497) (xy 353.265673 -169.498394) (xy 353.219883 -169.427142) (xy 353.181072 -169.351861)
			(xy 353.149593 -169.273231) (xy 353.125732 -169.191964) (xy 353.109703 -169.108798) (xy 353.101652 -169.024484)
			(xy 353.101148 -168.982136) (xy 353.101655 -168.937371) (xy 353.110591 -168.848289) (xy 353.128436 -168.760556)
			(xy 353.155009 -168.675061) (xy 353.172014 -168.633648) (xy 353.175559 -168.624052) (xy 353.175573 -168.603614)
			(xy 353.172014 -168.594024) (xy 353.155017 -168.552609) (xy 353.12846 -168.467112) (xy 353.11062 -168.37938)
			(xy 353.101678 -168.2903) (xy 353.101148 -168.245536) (xy 353.10149 -168.209754) (xy 353.107197 -168.138419)
			(xy 353.118619 -168.067773) (xy 353.126802 -168.032938) (xy 353.12847 -168.024629) (xy 353.126899 -168.007765)
			(xy 353.119933 -167.992328) (xy 353.114356 -167.985948) (xy 353.07397 -167.943276) (xy 353.064064 -167.945308)
			(xy 353.055257 -167.947603) (xy 353.039905 -167.957355) (xy 353.034092 -167.964358) (xy 353.008944 -167.997035)
			(xy 352.953542 -168.058113) (xy 352.892723 -168.113799) (xy 352.82701 -168.163616) (xy 352.756967 -168.207136)
			(xy 352.683196 -168.243984) (xy 352.606331 -168.273845) (xy 352.527031 -168.296462) (xy 352.445979 -168.31164)
			(xy 352.363869 -168.31925) (xy 352.322638 -168.319704) (xy 352.281533 -168.319151) (xy 352.199674 -168.311571)
			(xy 352.118862 -168.296471) (xy 352.039789 -168.273981) (xy 351.963127 -168.244292) (xy 351.889531 -168.207657)
			(xy 351.819629 -168.164389) (xy 351.754016 -168.114857) (xy 351.693252 -168.059484) (xy 351.637856 -167.998741)
			(xy 351.5883 -167.933147) (xy 351.545006 -167.863261) (xy 351.508343 -167.789678) (xy 351.478626 -167.713028)
			(xy 351.456106 -167.633963) (xy 351.440975 -167.553157) (xy 351.433364 -167.471301) (xy 351.432876 -167.430196)
			(xy 338.153756 -167.430196) (xy 338.153756 -171.66717) (xy 338.154193 -171.677233) (xy 338.161932 -171.695814)
			(xy 338.168742 -171.703238) (xy 338.349082 -171.883578) (xy 338.356484 -171.890414) (xy 338.375082 -171.898122)
			(xy 338.38515 -171.898564) (xy 340.118446 -171.898564) (xy 340.128512 -171.898132) (xy 340.147101 -171.890402)
			(xy 340.154514 -171.883578) (xy 340.174138 -171.864476) (xy 340.217877 -171.831523) (xy 340.265878 -171.805163)
			(xy 340.317156 -171.785937) (xy 340.370656 -171.774241) (xy 340.425278 -171.770316) (xy 340.4799 -171.774241)
			(xy 340.5334 -171.785937) (xy 340.584678 -171.805163) (xy 340.632679 -171.831523) (xy 340.676418 -171.864476)
			(xy 340.696042 -171.883578) (xy 340.703442 -171.89042) (xy 340.72204 -171.898143) (xy 340.73211 -171.898564)
			(xy 351.093532 -171.898564) (xy 351.118488 -171.899178) (xy 351.167439 -171.90892) (xy 351.21355 -171.928023)
			(xy 351.25505 -171.955753) (xy 351.27311 -171.972986) (xy 352.03511 -172.734986) (xy 352.052368 -172.753027)
			(xy 352.080122 -172.794521) (xy 352.09923 -172.84064) (xy 352.108956 -172.889604) (xy 352.109532 -172.914564)
			(xy 352.109532 -173.21911) (xy 393.739116 -173.21911) (xy 393.739743 -173.172708) (xy 393.749432 -173.08041)
			(xy 393.768686 -172.989625) (xy 393.797294 -172.90134) (xy 393.81557 -172.858684) (xy 393.819371 -172.84874)
			(xy 393.819374 -172.827478) (xy 393.81557 -172.817536) (xy 393.797307 -172.774875) (xy 393.768715 -172.686587)
			(xy 393.749458 -172.595804) (xy 393.739745 -172.503511) (xy 393.739116 -172.45711) (xy 393.739622 -172.415997)
			(xy 393.747208 -172.33412) (xy 393.762316 -172.253293) (xy 393.784818 -172.174205) (xy 393.81452 -172.097531)
			(xy 393.851171 -172.023924) (xy 393.894457 -171.954012) (xy 393.944008 -171.888393) (xy 393.999403 -171.827626)
			(xy 394.060168 -171.772229) (xy 394.125786 -171.722675) (xy 394.195696 -171.679387) (xy 394.269301 -171.642733)
			(xy 394.345975 -171.613028) (xy 394.425062 -171.590524) (xy 394.505889 -171.575413) (xy 394.587765 -171.567824)
			(xy 394.628878 -171.567348) (xy 394.670013 -171.567796) (xy 394.75193 -171.575416) (xy 394.832794 -171.590566)
			(xy 394.911913 -171.613115) (xy 394.988614 -171.642872) (xy 395.06224 -171.679583) (xy 395.132163 -171.722933)
			(xy 395.197785 -171.772553) (xy 395.258547 -171.828019) (xy 395.313929 -171.888856) (xy 395.339062 -171.921424)
			(xy 395.345281 -171.928954) (xy 395.36201 -171.939002) (xy 395.371574 -171.940982) (xy 395.41286 -171.948033)
			(xy 395.493962 -171.968978) (xy 395.572736 -171.997455) (xy 395.648484 -172.033212) (xy 395.720535 -172.075931)
			(xy 395.78825 -172.125234) (xy 395.851031 -172.180685) (xy 395.908321 -172.241793) (xy 395.959613 -172.308015)
			(xy 396.004452 -172.378766) (xy 396.042441 -172.453419) (xy 396.073244 -172.531313) (xy 396.096588 -172.611757)
			(xy 396.112266 -172.69404) (xy 396.120139 -172.777432) (xy 396.12062 -172.819314) (xy 396.120152 -172.860082)
			(xy 396.112652 -172.941273) (xy 396.097752 -173.021436) (xy 396.075577 -173.099899) (xy 396.046313 -173.176003)
			(xy 396.028672 -173.21276) (xy 396.024359 -173.222451) (xy 396.023438 -173.243625) (xy 396.026894 -173.253654)
			(xy 396.041217 -173.292003) (xy 396.063564 -173.370761) (xy 396.07857 -173.451241) (xy 396.086111 -173.53276)
			(xy 396.086584 -173.573694) (xy 396.086007 -173.618463) (xy 396.077001 -173.707548) (xy 396.0591 -173.795279)
			(xy 396.032485 -173.880771) (xy 396.015464 -173.922182) (xy 396.011903 -173.931774) (xy 396.0119 -173.952215)
			(xy 396.015464 -173.961806) (xy 396.031243 -174.000118) (xy 396.056457 -174.079051) (xy 396.074218 -174.159987)
			(xy 396.084371 -174.242225) (xy 396.086076 -174.283624) (xy 396.086886 -174.29455) (xy 396.096546 -174.314192)
			(xy 396.113476 -174.328068) (xy 396.123922 -174.331376) (xy 396.140795 -174.335871) (xy 396.174205 -174.346036)
			(xy 396.190724 -174.351696) (xy 396.19892 -174.354219) (xy 396.216056 -174.354219) (xy 396.224252 -174.351696)
			(xy 396.259466 -174.339729) (xy 396.33147 -174.321076) (xy 396.404792 -174.308569) (xy 396.478908 -174.302297)
			(xy 396.516098 -174.301912) (xy 396.553288 -174.302301) (xy 396.627401 -174.30859) (xy 396.70072 -174.3211)
			(xy 396.772726 -174.339741) (xy 396.807944 -174.351696) (xy 396.81614 -174.354219) (xy 396.833276 -174.354219)
			(xy 396.841472 -174.351696) (xy 396.876685 -174.339723) (xy 396.948689 -174.321072) (xy 397.022011 -174.308567)
			(xy 397.096127 -174.302297) (xy 397.133318 -174.301912) (xy 397.175254 -174.302444) (xy 397.258746 -174.310418)
			(xy 397.341102 -174.326292) (xy 397.421577 -174.349923) (xy 397.49944 -174.381096) (xy 397.573988 -174.41953)
			(xy 397.644545 -174.464875) (xy 397.710473 -174.516722) (xy 397.771173 -174.574601) (xy 397.826097 -174.637988)
			(xy 397.874747 -174.706309) (xy 397.916683 -174.778944) (xy 397.951524 -174.855237) (xy 397.978955 -174.934497)
			(xy 397.998729 -175.016005) (xy 398.010665 -175.099023) (xy 398.014656 -175.1828) (xy 398.010665 -175.266577)
			(xy 397.998729 -175.349595) (xy 397.978955 -175.431103) (xy 397.951524 -175.510363) (xy 397.916683 -175.586656)
			(xy 397.874747 -175.659291) (xy 397.826097 -175.727612) (xy 397.771173 -175.790999) (xy 397.710473 -175.848878)
			(xy 397.644545 -175.900725) (xy 397.573988 -175.94607) (xy 397.49944 -175.984504) (xy 397.421577 -176.015677)
			(xy 397.341102 -176.039308) (xy 397.258746 -176.055182) (xy 397.175254 -176.063156) (xy 397.133318 -176.063656)
			(xy 397.096129 -176.063259) (xy 397.022016 -176.056971) (xy 396.948696 -176.044464) (xy 396.87669 -176.025825)
			(xy 396.841472 -176.013872) (xy 396.833276 -176.011349) (xy 396.81614 -176.011349) (xy 396.807944 -176.013872)
			(xy 396.778999 -176.023726) (xy 396.720017 -176.039869) (xy 396.690088 -176.04613) (xy 396.680526 -176.048543)
			(xy 396.664116 -176.059448) (xy 396.653002 -176.075716) (xy 396.650464 -176.085246) (xy 396.640294 -176.12901)
			(xy 396.612299 -176.21439) (xy 396.594584 -176.25568) (xy 396.590807 -176.265631) (xy 396.590789 -176.286886)
			(xy 396.594584 -176.296828) (xy 396.612812 -176.339497) (xy 396.641361 -176.427787) (xy 396.660559 -176.51857)
			(xy 396.670197 -176.610859) (xy 396.670784 -176.657254) (xy 396.67028 -176.699602) (xy 396.662229 -176.783916)
			(xy 396.6462 -176.867082) (xy 396.622339 -176.948349) (xy 396.59086 -177.026979) (xy 396.552049 -177.10226)
			(xy 396.506259 -177.173512) (xy 396.453903 -177.240088) (xy 396.395455 -177.301386) (xy 396.331445 -177.356851)
			(xy 396.262453 -177.40598) (xy 396.189103 -177.448329) (xy 396.11206 -177.483513) (xy 396.032021 -177.511215)
			(xy 395.949712 -177.531183) (xy 395.865877 -177.543236) (xy 395.781276 -177.547267) (xy 395.696675 -177.543236)
			(xy 395.61284 -177.531183) (xy 395.530531 -177.511215) (xy 395.450492 -177.483513) (xy 395.373449 -177.448329)
			(xy 395.300099 -177.40598) (xy 395.231107 -177.356851) (xy 395.167097 -177.301386) (xy 395.108649 -177.240088)
			(xy 395.056293 -177.173512) (xy 395.010503 -177.10226) (xy 394.971692 -177.026979) (xy 394.940213 -176.948349)
			(xy 394.916352 -176.867082) (xy 394.900323 -176.783916) (xy 394.892272 -176.699602) (xy 394.891768 -176.657254)
			(xy 394.892372 -176.610859) (xy 394.902011 -176.518571) (xy 394.921201 -176.427788) (xy 394.949733 -176.339493)
			(xy 394.967968 -176.296828) (xy 394.971802 -176.286894) (xy 394.971784 -176.265622) (xy 394.967968 -176.25568)
			(xy 394.949707 -176.213025) (xy 394.921167 -176.12473) (xy 394.901979 -176.033943) (xy 394.89235 -175.941651)
			(xy 394.891768 -175.895254) (xy 394.89209 -175.858508) (xy 394.898067 -175.785262) (xy 394.903706 -175.74895)
			(xy 394.905738 -175.737012) (xy 394.898626 -175.713898) (xy 394.824966 -175.637698) (xy 394.802106 -175.629824)
			(xy 394.790168 -175.631602) (xy 394.760779 -175.635286) (xy 394.701676 -175.63923) (xy 394.672058 -175.639476)
			(xy 394.630944 -175.639027) (xy 394.549066 -175.631436) (xy 394.468237 -175.616324) (xy 394.389148 -175.593818)
			(xy 394.312473 -175.564111) (xy 394.238865 -175.527456) (xy 394.168954 -175.484166) (xy 394.103335 -175.434611)
			(xy 394.042568 -175.379212) (xy 393.987171 -175.318444) (xy 393.937618 -175.252823) (xy 393.89433 -175.18291)
			(xy 393.857678 -175.109302) (xy 393.827973 -175.032625) (xy 393.80547 -174.953535) (xy 393.79036 -174.872707)
			(xy 393.782772 -174.790829) (xy 393.782296 -174.749714) (xy 393.782849 -174.707004) (xy 393.791108 -174.621982)
			(xy 393.807465 -174.53814) (xy 393.831771 -174.456249) (xy 393.84732 -174.416466) (xy 393.850767 -174.406384)
			(xy 393.849981 -174.385117) (xy 393.845796 -174.375318) (xy 393.828728 -174.339015) (xy 393.800407 -174.263955)
			(xy 393.778962 -174.186649) (xy 393.764567 -174.107726) (xy 393.75734 -174.027827) (xy 393.756896 -173.987714)
			(xy 393.757452 -173.943459) (xy 393.766275 -173.855391) (xy 393.783795 -173.768633) (xy 393.809839 -173.684042)
			(xy 393.826492 -173.643036) (xy 393.830085 -173.632871) (xy 393.829579 -173.611348) (xy 393.825476 -173.60138)
			(xy 393.808875 -173.565511) (xy 393.781358 -173.491412) (xy 393.760529 -173.415162) (xy 393.746554 -173.337364)
			(xy 393.739543 -173.258632) (xy 393.739116 -173.21911) (xy 352.109532 -173.21911) (xy 352.109532 -175.705516)
			(xy 359.713276 -175.705516) (xy 359.713826 -175.660746) (xy 359.72284 -175.571661) (xy 359.740749 -175.48393)
			(xy 359.767371 -175.398439) (xy 359.784396 -175.357028) (xy 359.787954 -175.347435) (xy 359.78796 -175.326994)
			(xy 359.784396 -175.317404) (xy 359.767362 -175.275997) (xy 359.740727 -175.190508) (xy 359.722822 -175.102775)
			(xy 359.713828 -175.013687) (xy 359.713276 -174.968916) (xy 359.713826 -174.924146) (xy 359.72284 -174.835061)
			(xy 359.740749 -174.74733) (xy 359.767371 -174.661839) (xy 359.784396 -174.620428) (xy 359.787954 -174.610835)
			(xy 359.78796 -174.590394) (xy 359.784396 -174.580804) (xy 359.767362 -174.539397) (xy 359.740727 -174.453908)
			(xy 359.722822 -174.366175) (xy 359.713828 -174.277087) (xy 359.713276 -174.232316) (xy 359.713768 -174.191206)
			(xy 359.721354 -174.109337) (xy 359.736463 -174.028517) (xy 359.758966 -173.949437) (xy 359.788671 -173.872771)
			(xy 359.825324 -173.799173) (xy 359.868613 -173.729272) (xy 359.918168 -173.663664) (xy 359.973567 -173.602909)
			(xy 360.034335 -173.547526) (xy 360.099955 -173.497988) (xy 360.169867 -173.454716) (xy 360.243474 -173.418081)
			(xy 360.320148 -173.388396) (xy 360.399234 -173.365912) (xy 360.480057 -173.350823) (xy 360.561928 -173.343257)
			(xy 360.603038 -173.342808) (xy 360.64465 -173.343297) (xy 360.727511 -173.351043) (xy 360.809285 -173.366502)
			(xy 360.889257 -173.389537) (xy 360.966724 -173.419948) (xy 361.041009 -173.457467) (xy 361.076494 -173.479206)
			(xy 361.085605 -173.48431) (xy 361.10625 -173.487353) (xy 361.126414 -173.481975) (xy 361.134914 -173.475904)
			(xy 361.168589 -173.449956) (xy 361.240028 -173.403863) (xy 361.315538 -173.364795) (xy 361.39443 -173.333108)
			(xy 361.475986 -173.309092) (xy 361.55946 -173.292965) (xy 361.644093 -173.284874) (xy 361.686602 -173.284388)
			(xy 361.72771 -173.284811) (xy 361.809576 -173.292396) (xy 361.890393 -173.307501) (xy 361.969472 -173.329998)
			(xy 362.046138 -173.359694) (xy 362.119738 -173.396336) (xy 362.189643 -173.439612) (xy 362.255258 -173.489152)
			(xy 362.316023 -173.544534) (xy 362.371419 -173.605287) (xy 362.420974 -173.67089) (xy 362.464266 -173.740786)
			(xy 362.500925 -173.814377) (xy 362.530638 -173.891036) (xy 362.553153 -173.97011) (xy 362.568276 -174.050924)
			(xy 362.57588 -174.132788) (xy 362.576364 -174.173896) (xy 362.575781 -174.218665) (xy 362.566776 -174.307749)
			(xy 362.548877 -174.395481) (xy 362.522264 -174.480972) (xy 362.505244 -174.522384) (xy 362.501683 -174.531976)
			(xy 362.501681 -174.552417) (xy 362.505244 -174.562008) (xy 362.522284 -174.603413) (xy 362.548917 -174.688902)
			(xy 362.56682 -174.776636) (xy 362.575812 -174.865725) (xy 362.576364 -174.910496) (xy 362.575094 -174.95393)
			(xy 362.575081 -174.965654) (xy 362.584392 -174.987145) (xy 362.602236 -175.002315) (xy 362.613448 -175.005746)
			(xy 362.632326 -175.010612) (xy 362.669677 -175.021792) (xy 362.688124 -175.028098) (xy 362.69632 -175.030621)
			(xy 362.713456 -175.030621) (xy 362.721652 -175.028098) (xy 362.756876 -175.016176) (xy 362.828883 -174.997583)
			(xy 362.902204 -174.985136) (xy 362.976313 -174.978924) (xy 363.013498 -174.978568) (xy 363.050682 -174.978934)
			(xy 363.12479 -174.985156) (xy 363.19811 -174.997599) (xy 363.270121 -175.016175) (xy 363.305344 -175.028098)
			(xy 363.31354 -175.030621) (xy 363.330676 -175.030621) (xy 363.338872 -175.028098) (xy 363.374094 -175.01617)
			(xy 363.446102 -174.997579) (xy 363.519423 -174.985133) (xy 363.593533 -174.978923) (xy 363.630718 -174.978568)
			(xy 363.672642 -174.979095) (xy 363.75611 -174.987067) (xy 363.838443 -175.002937) (xy 363.918894 -175.026561)
			(xy 363.996736 -175.057726) (xy 364.071262 -175.096148) (xy 364.141799 -175.141481) (xy 364.207708 -175.193313)
			(xy 364.268391 -175.251175) (xy 364.323299 -175.314544) (xy 364.371935 -175.382845) (xy 364.413859 -175.45546)
			(xy 364.44869 -175.531731) (xy 364.476114 -175.610968) (xy 364.495881 -175.692452) (xy 364.507814 -175.775447)
			(xy 364.511804 -175.8592) (xy 364.507814 -175.942953) (xy 364.495881 -176.025948) (xy 364.476114 -176.107432)
			(xy 364.44869 -176.186669) (xy 364.413859 -176.26294) (xy 364.371935 -176.335555) (xy 364.323299 -176.403856)
			(xy 364.268391 -176.467225) (xy 364.207708 -176.525087) (xy 364.141799 -176.576919) (xy 364.071262 -176.622252)
			(xy 363.996736 -176.660674) (xy 363.918894 -176.691839) (xy 363.838443 -176.715463) (xy 363.75611 -176.731333)
			(xy 363.672642 -176.739305) (xy 363.630718 -176.739804) (xy 363.593534 -176.739435) (xy 363.519426 -176.733214)
			(xy 363.446106 -176.720772) (xy 363.374095 -176.702197) (xy 363.338872 -176.690274) (xy 363.330676 -176.687751)
			(xy 363.31354 -176.687751) (xy 363.305344 -176.690274) (xy 363.271301 -176.701822) (xy 363.201745 -176.720004)
			(xy 363.166406 -176.726596) (xy 363.157145 -176.728648) (xy 363.140992 -176.738571) (xy 363.129516 -176.75366)
			(xy 363.126528 -176.762664) (xy 363.118751 -176.789183) (xy 363.100323 -176.841292) (xy 363.089698 -176.866804)
			(xy 363.086123 -176.876392) (xy 363.086128 -176.896837) (xy 363.089698 -176.906428) (xy 363.10668 -176.947849)
			(xy 363.133241 -177.033344) (xy 363.151085 -177.121074) (xy 363.160031 -177.210153) (xy 363.160564 -177.254916)
			(xy 363.16006 -177.297264) (xy 363.152009 -177.381578) (xy 363.13598 -177.464744) (xy 363.112119 -177.546011)
			(xy 363.08064 -177.624641) (xy 363.041829 -177.699922) (xy 362.996039 -177.771174) (xy 362.943683 -177.83775)
			(xy 362.885235 -177.899048) (xy 362.821225 -177.954513) (xy 362.752233 -178.003642) (xy 362.678883 -178.045991)
			(xy 362.60184 -178.081175) (xy 362.521801 -178.108877) (xy 362.439492 -178.128845) (xy 362.355657 -178.140898)
			(xy 362.271056 -178.144929) (xy 362.186455 -178.140898) (xy 362.10262 -178.128845) (xy 362.020311 -178.108877)
			(xy 361.940272 -178.081175) (xy 361.863229 -178.045991) (xy 361.789879 -178.003642) (xy 361.720887 -177.954513)
			(xy 361.656877 -177.899048) (xy 361.598429 -177.83775) (xy 361.546073 -177.771174) (xy 361.500283 -177.699922)
			(xy 361.461472 -177.624641) (xy 361.429993 -177.546011) (xy 361.406132 -177.464744) (xy 361.390103 -177.381578)
			(xy 361.382052 -177.297264) (xy 361.381548 -177.254916) (xy 361.382083 -177.210152) (xy 361.39101 -177.12107)
			(xy 361.408847 -177.033337) (xy 361.435413 -176.947842) (xy 361.452414 -176.906428) (xy 361.455971 -176.896835)
			(xy 361.455977 -176.876394) (xy 361.452414 -176.866804) (xy 361.435411 -176.825392) (xy 361.408855 -176.739893)
			(xy 361.391017 -176.65216) (xy 361.382077 -176.56308) (xy 361.381548 -176.518316) (xy 361.381877 -176.482967)
			(xy 361.387485 -176.412493) (xy 361.398676 -176.342687) (xy 361.406694 -176.308258) (xy 361.408272 -176.299927)
			(xy 361.406606 -176.283067) (xy 361.399568 -176.267656) (xy 361.393994 -176.261268) (xy 361.353608 -176.218596)
			(xy 361.344464 -176.220628) (xy 361.335655 -176.222917) (xy 361.320303 -176.232673) (xy 361.314492 -176.239678)
			(xy 361.289321 -176.272337) (xy 361.233923 -176.333418) (xy 361.173108 -176.389107) (xy 361.107398 -176.438926)
			(xy 361.037358 -176.482448) (xy 360.96359 -176.519299) (xy 360.886727 -176.549162) (xy 360.807429 -176.57178)
			(xy 360.726377 -176.586959) (xy 360.644268 -176.594569) (xy 360.603038 -176.595024) (xy 360.561931 -176.594551)
			(xy 360.480067 -176.58697) (xy 360.399251 -176.571868) (xy 360.320173 -176.549375) (xy 360.243508 -176.519683)
			(xy 360.169909 -176.483044) (xy 360.100004 -176.439772) (xy 360.034389 -176.390235) (xy 359.973624 -176.334856)
			(xy 359.918228 -176.274107) (xy 359.868672 -176.208506) (xy 359.825379 -176.138613) (xy 359.78872 -176.065025)
			(xy 359.759005 -175.988368) (xy 359.73649 -175.909296) (xy 359.721365 -175.828485) (xy 359.713761 -175.746623)
			(xy 359.713276 -175.705516) (xy 352.109532 -175.705516) (xy 352.109532 -178.503326) (xy 352.109961 -178.513393)
			(xy 352.117685 -178.531988) (xy 352.124518 -178.539394) (xy 352.789998 -179.204874) (xy 368.074448 -179.204874)
			(xy 368.074947 -179.16192) (xy 368.083214 -179.076411) (xy 368.099688 -178.992098) (xy 368.124215 -178.909766)
			(xy 368.156566 -178.830183) (xy 368.196441 -178.75409) (xy 368.243467 -178.682196) (xy 368.297207 -178.615173)
			(xy 368.357158 -178.553643) (xy 368.422764 -178.498181) (xy 368.493412 -178.449303) (xy 368.568443 -178.407466)
			(xy 368.607594 -178.389788) (xy 368.616013 -178.385775) (xy 368.629319 -178.372724) (xy 368.633502 -178.364388)
			(xy 368.645948 -178.33721) (xy 368.64947 -178.328554) (xy 368.650638 -178.309919) (xy 368.648234 -178.300888)
			(xy 368.635415 -178.257999) (xy 368.617464 -178.170297) (xy 368.608423 -178.081234) (xy 368.607848 -178.036474)
			(xy 368.608352 -177.994113) (xy 368.616405 -177.909776) (xy 368.632439 -177.826586) (xy 368.656307 -177.745296)
			(xy 368.687795 -177.666644) (xy 368.726617 -177.591341) (xy 368.77242 -177.520069) (xy 368.824791 -177.453473)
			(xy 368.883256 -177.392158) (xy 368.947284 -177.336677) (xy 369.016296 -177.287534) (xy 369.089666 -177.245174)
			(xy 369.166731 -177.209979) (xy 369.246793 -177.18227) (xy 369.329126 -177.162296) (xy 369.412985 -177.150239)
			(xy 369.49761 -177.146208) (xy 369.582235 -177.150239) (xy 369.666094 -177.162296) (xy 369.748427 -177.18227)
			(xy 369.828489 -177.209979) (xy 369.905554 -177.245174) (xy 369.978924 -177.287534) (xy 370.047936 -177.336677)
			(xy 370.111964 -177.392158) (xy 370.170429 -177.453473) (xy 370.2228 -177.520069) (xy 370.268603 -177.591341)
			(xy 370.307425 -177.666644) (xy 370.338913 -177.745296) (xy 370.362781 -177.826586) (xy 370.378815 -177.909776)
			(xy 370.386868 -177.994113) (xy 370.387372 -178.036474) (xy 370.386957 -178.074882) (xy 370.380322 -178.151412)
			(xy 370.367108 -178.227083) (xy 370.357654 -178.264312) (xy 370.35562 -178.273261) (xy 370.357441 -178.291512)
			(xy 370.365595 -178.307941) (xy 370.37903 -178.320427) (xy 370.387372 -178.324256) (xy 370.427603 -178.341379)
			(xy 370.50477 -178.382506) (xy 370.577528 -178.431007) (xy 370.645175 -178.486413) (xy 370.707059 -178.548191)
			(xy 370.762582 -178.615743) (xy 370.811207 -178.688417) (xy 370.852467 -178.765513) (xy 370.885962 -178.846285)
			(xy 370.911369 -178.929954) (xy 370.928442 -179.015713) (xy 370.937018 -179.102733) (xy 370.937536 -179.146454)
			(xy 370.936975 -179.191224) (xy 370.927964 -179.280309) (xy 370.910058 -179.36804) (xy 370.883439 -179.453531)
			(xy 370.866416 -179.494942) (xy 370.86288 -179.504541) (xy 370.862862 -179.524975) (xy 370.866416 -179.534566)
			(xy 370.883441 -179.575977) (xy 370.910078 -179.661464) (xy 370.927986 -179.749196) (xy 370.936982 -179.838284)
			(xy 370.937536 -179.883054) (xy 370.937282 -179.904136) (xy 370.937602 -179.915409) (xy 370.946803 -179.935973)
			(xy 370.963911 -179.950631) (xy 370.97462 -179.954174) (xy 370.989618 -179.95835) (xy 371.019344 -179.967623)
			(xy 371.034056 -179.972716) (xy 371.042252 -179.975239) (xy 371.059388 -179.975239) (xy 371.067584 -179.972716)
			(xy 371.102796 -179.960741) (xy 371.174801 -179.94209) (xy 371.248123 -179.929585) (xy 371.322239 -179.923316)
			(xy 371.35943 -179.922932) (xy 371.396619 -179.923339) (xy 371.470732 -179.929623) (xy 371.544052 -179.942128)
			(xy 371.616058 -179.960764) (xy 371.651276 -179.972716) (xy 371.659472 -179.975239) (xy 371.676608 -179.975239)
			(xy 371.684804 -179.972716) (xy 371.720023 -179.960763) (xy 371.792025 -179.942106) (xy 371.865345 -179.929595)
			(xy 371.93946 -179.923319) (xy 371.97665 -179.922932) (xy 372.01859 -179.923405) (xy 372.10209 -179.931374)
			(xy 372.184455 -179.947244) (xy 372.264938 -179.970872) (xy 372.34281 -180.002043) (xy 372.417367 -180.040476)
			(xy 372.487932 -180.085822) (xy 372.553868 -180.137671) (xy 372.614576 -180.195553) (xy 372.669507 -180.258944)
			(xy 372.718163 -180.327269) (xy 372.760105 -180.39991) (xy 372.794951 -180.476209) (xy 372.822386 -180.555475)
			(xy 372.842162 -180.63699) (xy 372.848069 -180.678074) (xy 376.477276 -180.678074) (xy 376.477846 -180.633305)
			(xy 376.486854 -180.54422) (xy 376.504757 -180.456489) (xy 376.531374 -180.370997) (xy 376.548396 -180.329586)
			(xy 376.551978 -180.32) (xy 376.551968 -180.299553) (xy 376.548396 -180.289962) (xy 376.531349 -180.24856)
			(xy 376.504717 -180.16307) (xy 376.486816 -180.075335) (xy 376.477826 -179.986245) (xy 376.477276 -179.941474)
			(xy 376.477846 -179.896705) (xy 376.486854 -179.80762) (xy 376.504757 -179.719889) (xy 376.531374 -179.634397)
			(xy 376.548396 -179.592986) (xy 376.551978 -179.5834) (xy 376.551968 -179.562953) (xy 376.548396 -179.553362)
			(xy 376.531349 -179.51196) (xy 376.504717 -179.42647) (xy 376.486816 -179.338735) (xy 376.477826 -179.249645)
			(xy 376.477276 -179.204874) (xy 376.477674 -179.163758) (xy 376.485264 -179.081876) (xy 376.500376 -179.001043)
			(xy 376.522883 -178.92195) (xy 376.552591 -178.845272) (xy 376.589248 -178.771661) (xy 376.632541 -178.701747)
			(xy 376.682099 -178.636125) (xy 376.737501 -178.575356) (xy 376.798274 -178.519958) (xy 376.863899 -178.470404)
			(xy 376.933817 -178.427117) (xy 377.00743 -178.390466) (xy 377.084111 -178.360763) (xy 377.163206 -178.338262)
			(xy 377.244039 -178.323155) (xy 377.325922 -178.315571) (xy 377.367038 -178.315112) (xy 377.408654 -178.315621)
			(xy 377.491518 -178.323439) (xy 377.57329 -178.338956) (xy 377.653258 -178.362036) (xy 377.730723 -178.392479)
			(xy 377.805008 -178.430018) (xy 377.840494 -178.451764) (xy 377.849603 -178.456874) (xy 377.87025 -178.459919)
			(xy 377.890415 -178.454537) (xy 377.898914 -178.448462) (xy 377.932574 -178.422483) (xy 378.004001 -178.376346)
			(xy 378.079506 -178.337236) (xy 378.158398 -178.305511) (xy 378.239958 -178.28146) (xy 378.323442 -178.265303)
			(xy 378.408086 -178.257188) (xy 378.450602 -178.256692) (xy 378.491715 -178.257211) (xy 378.57359 -178.264798)
			(xy 378.654416 -178.279906) (xy 378.733503 -178.302408) (xy 378.810176 -178.33211) (xy 378.883782 -178.368761)
			(xy 378.953693 -178.412046) (xy 379.019312 -178.461597) (xy 379.080078 -178.51699) (xy 379.135475 -178.577755)
			(xy 379.185029 -178.643371) (xy 379.228318 -178.713279) (xy 379.264972 -178.786883) (xy 379.294678 -178.863555)
			(xy 379.317184 -178.942641) (xy 379.332296 -179.023466) (xy 379.339887 -179.105341) (xy 379.340364 -179.146454)
			(xy 379.339801 -179.191224) (xy 379.330791 -179.280309) (xy 379.312886 -179.36804) (xy 379.286267 -179.453531)
			(xy 379.269244 -179.494942) (xy 379.265706 -179.50454) (xy 379.265689 -179.524976) (xy 379.269244 -179.534566)
			(xy 379.28504 -179.572871) (xy 379.310249 -179.651807) (xy 379.328005 -179.732745) (xy 379.338154 -179.814985)
			(xy 379.339856 -179.856384) (xy 379.340709 -179.867303) (xy 379.350351 -179.886943) (xy 379.367263 -179.900823)
			(xy 379.377702 -179.904136) (xy 379.394574 -179.908633) (xy 379.427985 -179.918797) (xy 379.444504 -179.924456)
			(xy 379.4527 -179.926979) (xy 379.469836 -179.926979) (xy 379.478032 -179.924456) (xy 379.513248 -179.912493)
			(xy 379.585251 -179.893839) (xy 379.658572 -179.881331) (xy 379.732688 -179.875058) (xy 379.769878 -179.874672)
			(xy 379.807067 -179.875069) (xy 379.88118 -179.881356) (xy 379.9545 -179.893864) (xy 380.026506 -179.912502)
			(xy 380.061724 -179.924456) (xy 380.06992 -179.926979) (xy 380.087056 -179.926979) (xy 380.095252 -179.924456)
			(xy 380.130466 -179.912487) (xy 380.20247 -179.893835) (xy 380.275792 -179.881329) (xy 380.349908 -179.875057)
			(xy 380.387098 -179.874672) (xy 380.429038 -179.875067) (xy 380.512539 -179.88304) (xy 380.594904 -179.898915)
			(xy 380.675386 -179.922546) (xy 380.753258 -179.953722) (xy 380.827814 -179.992158) (xy 380.898379 -180.037507)
			(xy 380.964314 -180.089358) (xy 381.025021 -180.147242) (xy 381.079951 -180.210635) (xy 381.128607 -180.278962)
			(xy 381.170547 -180.351604) (xy 381.205392 -180.427905) (xy 381.232827 -180.507172) (xy 381.252602 -180.588688)
			(xy 381.26454 -180.671715) (xy 381.264843 -180.678074) (xy 384.808476 -180.678074) (xy 384.809046 -180.633305)
			(xy 384.818054 -180.54422) (xy 384.835957 -180.456489) (xy 384.862574 -180.370997) (xy 384.879596 -180.329586)
			(xy 384.883178 -180.32) (xy 384.883168 -180.299553) (xy 384.879596 -180.289962) (xy 384.862549 -180.24856)
			(xy 384.835917 -180.16307) (xy 384.818016 -180.075335) (xy 384.809026 -179.986245) (xy 384.808476 -179.941474)
			(xy 384.809046 -179.896705) (xy 384.818054 -179.80762) (xy 384.835957 -179.719889) (xy 384.862574 -179.634397)
			(xy 384.879596 -179.592986) (xy 384.883178 -179.5834) (xy 384.883168 -179.562953) (xy 384.879596 -179.553362)
			(xy 384.862549 -179.51196) (xy 384.835917 -179.42647) (xy 384.818016 -179.338735) (xy 384.809026 -179.249645)
			(xy 384.808476 -179.204874) (xy 384.808874 -179.163758) (xy 384.816464 -179.081876) (xy 384.831576 -179.001043)
			(xy 384.854083 -178.92195) (xy 384.883791 -178.845272) (xy 384.920448 -178.771661) (xy 384.963741 -178.701747)
			(xy 385.013299 -178.636125) (xy 385.068701 -178.575356) (xy 385.129474 -178.519958) (xy 385.195099 -178.470404)
			(xy 385.265017 -178.427117) (xy 385.33863 -178.390466) (xy 385.415311 -178.360763) (xy 385.494406 -178.338262)
			(xy 385.575239 -178.323155) (xy 385.657122 -178.315571) (xy 385.698238 -178.315112) (xy 385.739854 -178.315621)
			(xy 385.822718 -178.323439) (xy 385.90449 -178.338956) (xy 385.984458 -178.362036) (xy 386.061923 -178.392479)
			(xy 386.136208 -178.430018) (xy 386.171694 -178.451764) (xy 386.180803 -178.456874) (xy 386.20145 -178.459919)
			(xy 386.221615 -178.454537) (xy 386.230114 -178.448462) (xy 386.263774 -178.422483) (xy 386.335201 -178.376346)
			(xy 386.410706 -178.337236) (xy 386.489598 -178.305511) (xy 386.571158 -178.28146) (xy 386.654642 -178.265303)
			(xy 386.739286 -178.257188) (xy 386.781802 -178.256692) (xy 386.822915 -178.257211) (xy 386.90479 -178.264798)
			(xy 386.985616 -178.279906) (xy 387.064703 -178.302408) (xy 387.141376 -178.33211) (xy 387.214982 -178.368761)
			(xy 387.284893 -178.412046) (xy 387.350512 -178.461597) (xy 387.411278 -178.51699) (xy 387.466675 -178.577755)
			(xy 387.516229 -178.643371) (xy 387.559518 -178.713279) (xy 387.596172 -178.786883) (xy 387.625878 -178.863555)
			(xy 387.648384 -178.942641) (xy 387.663496 -179.023466) (xy 387.671087 -179.105341) (xy 387.671564 -179.146454)
			(xy 387.671001 -179.191224) (xy 387.661991 -179.280309) (xy 387.644086 -179.36804) (xy 387.617467 -179.453531)
			(xy 387.600444 -179.494942) (xy 387.596906 -179.50454) (xy 387.596889 -179.524976) (xy 387.600444 -179.534566)
			(xy 387.61624 -179.572871) (xy 387.641449 -179.651807) (xy 387.659205 -179.732745) (xy 387.669354 -179.814985)
			(xy 387.671056 -179.856384) (xy 387.671909 -179.867303) (xy 387.681551 -179.886943) (xy 387.698463 -179.900823)
			(xy 387.708902 -179.904136) (xy 387.725774 -179.908633) (xy 387.759185 -179.918797) (xy 387.775704 -179.924456)
			(xy 387.7839 -179.926979) (xy 387.801036 -179.926979) (xy 387.809232 -179.924456) (xy 387.844448 -179.912493)
			(xy 387.916451 -179.893839) (xy 387.989772 -179.881331) (xy 388.063888 -179.875058) (xy 388.101078 -179.874672)
			(xy 388.138267 -179.875069) (xy 388.21238 -179.881356) (xy 388.2857 -179.893864) (xy 388.357706 -179.912502)
			(xy 388.392924 -179.924456) (xy 388.40112 -179.926979) (xy 388.418256 -179.926979) (xy 388.426452 -179.924456)
			(xy 388.461666 -179.912487) (xy 388.53367 -179.893835) (xy 388.606992 -179.881329) (xy 388.681108 -179.875057)
			(xy 388.718298 -179.874672) (xy 388.760238 -179.875067) (xy 388.843739 -179.88304) (xy 388.926104 -179.898915)
			(xy 389.006586 -179.922546) (xy 389.084458 -179.953722) (xy 389.159014 -179.992158) (xy 389.229579 -180.037507)
			(xy 389.295514 -180.089358) (xy 389.356221 -180.147242) (xy 389.411151 -180.210635) (xy 389.459807 -180.278962)
			(xy 389.501747 -180.351604) (xy 389.536592 -180.427905) (xy 389.564027 -180.507172) (xy 389.583802 -180.588688)
			(xy 389.59574 -180.671715) (xy 389.599731 -180.7555) (xy 389.59574 -180.839285) (xy 389.583802 -180.922312)
			(xy 389.564027 -181.003828) (xy 389.536592 -181.083095) (xy 389.501747 -181.159396) (xy 389.459807 -181.232038)
			(xy 389.411151 -181.300365) (xy 389.356221 -181.363758) (xy 389.295514 -181.421642) (xy 389.229579 -181.473493)
			(xy 389.159014 -181.518842) (xy 389.084458 -181.557278) (xy 389.006586 -181.588454) (xy 388.926104 -181.612085)
			(xy 388.843739 -181.62796) (xy 388.760238 -181.635933) (xy 388.718298 -181.636416) (xy 388.681108 -181.636027)
			(xy 388.606996 -181.629737) (xy 388.533676 -181.617227) (xy 388.46167 -181.598587) (xy 388.426452 -181.586632)
			(xy 388.418256 -181.584109) (xy 388.40112 -181.584109) (xy 388.392924 -181.586632) (xy 388.365208 -181.596078)
			(xy 388.308773 -181.611711) (xy 388.280148 -181.617874) (xy 388.270401 -181.620348) (xy 388.25379 -181.63165)
			(xy 388.242792 -181.648464) (xy 388.240524 -181.65826) (xy 388.231054 -181.705587) (xy 388.203179 -181.797995)
			(xy 388.184898 -181.842664) (xy 388.181345 -181.852258) (xy 388.181336 -181.872698) (xy 388.184898 -181.882288)
			(xy 388.2019 -181.923701) (xy 388.228456 -182.009199) (xy 388.246294 -182.096932) (xy 388.255234 -182.186012)
			(xy 388.255764 -182.230776) (xy 388.25526 -182.273124) (xy 388.247209 -182.357438) (xy 388.23118 -182.440604)
			(xy 388.207319 -182.521871) (xy 388.17584 -182.600501) (xy 388.137029 -182.675782) (xy 388.091239 -182.747034)
			(xy 388.038883 -182.81361) (xy 387.980435 -182.874908) (xy 387.916425 -182.930373) (xy 387.847433 -182.979502)
			(xy 387.774083 -183.021851) (xy 387.69704 -183.057035) (xy 387.617001 -183.084737) (xy 387.534692 -183.104705)
			(xy 387.450857 -183.116758) (xy 387.366256 -183.120789) (xy 387.281655 -183.116758) (xy 387.19782 -183.104705)
			(xy 387.115511 -183.084737) (xy 387.035472 -183.057035) (xy 386.958429 -183.021851) (xy 386.885079 -182.979502)
			(xy 386.816087 -182.930373) (xy 386.752077 -182.874908) (xy 386.693629 -182.81361) (xy 386.641273 -182.747034)
			(xy 386.595483 -182.675782) (xy 386.556672 -182.600501) (xy 386.525193 -182.521871) (xy 386.501332 -182.440604)
			(xy 386.485303 -182.357438) (xy 386.477252 -182.273124) (xy 386.476748 -182.230776) (xy 386.477269 -182.186011)
			(xy 386.486201 -182.096929) (xy 386.504042 -182.009196) (xy 386.530611 -181.923701) (xy 386.547614 -181.882288)
			(xy 386.551194 -181.872702) (xy 386.551185 -181.852255) (xy 386.547614 -181.842664) (xy 386.53063 -181.801244)
			(xy 386.504069 -181.715748) (xy 386.486226 -181.628018) (xy 386.47728 -181.53894) (xy 386.476748 -181.494176)
			(xy 386.477087 -181.458262) (xy 386.482864 -181.386666) (xy 386.494395 -181.315769) (xy 386.502656 -181.280816)
			(xy 386.504286 -181.272505) (xy 386.502711 -181.255655) (xy 386.495751 -181.24023) (xy 386.49021 -181.233826)
			(xy 386.44957 -181.1909) (xy 386.439664 -181.193186) (xy 386.430849 -181.195458) (xy 386.415499 -181.205225)
			(xy 386.409692 -181.212236) (xy 386.384552 -181.244927) (xy 386.329156 -181.306026) (xy 386.268343 -181.361734)
			(xy 386.202634 -181.411575) (xy 386.132593 -181.455119) (xy 386.058822 -181.491993) (xy 385.981955 -181.521881)
			(xy 385.902652 -181.544524) (xy 385.821593 -181.55973) (xy 385.739474 -181.567368) (xy 385.698238 -181.567836)
			(xy 385.657123 -181.567365) (xy 385.575243 -181.559781) (xy 385.494413 -181.544674) (xy 385.415321 -181.522173)
			(xy 385.338643 -181.49247) (xy 385.265033 -181.455819) (xy 385.195119 -181.412532) (xy 385.129497 -181.362978)
			(xy 385.068728 -181.30758) (xy 385.01333 -181.246812) (xy 384.963775 -181.181191) (xy 384.920487 -181.111277)
			(xy 384.883834 -181.037668) (xy 384.854131 -180.96099) (xy 384.831629 -180.881899) (xy 384.81652 -180.801068)
			(xy 384.808935 -180.719189) (xy 384.808476 -180.678074) (xy 381.264843 -180.678074) (xy 381.268531 -180.7555)
			(xy 381.26454 -180.839285) (xy 381.252602 -180.922312) (xy 381.232827 -181.003828) (xy 381.205392 -181.083095)
			(xy 381.170547 -181.159396) (xy 381.128607 -181.232038) (xy 381.079951 -181.300365) (xy 381.025021 -181.363758)
			(xy 380.964314 -181.421642) (xy 380.898379 -181.473493) (xy 380.827814 -181.518842) (xy 380.753258 -181.557278)
			(xy 380.675386 -181.588454) (xy 380.594904 -181.612085) (xy 380.512539 -181.62796) (xy 380.429038 -181.635933)
			(xy 380.387098 -181.636416) (xy 380.349908 -181.636027) (xy 380.275796 -181.629737) (xy 380.202476 -181.617227)
			(xy 380.13047 -181.598587) (xy 380.095252 -181.586632) (xy 380.087056 -181.584109) (xy 380.06992 -181.584109)
			(xy 380.061724 -181.586632) (xy 380.034008 -181.596078) (xy 379.977573 -181.611711) (xy 379.948948 -181.617874)
			(xy 379.939201 -181.620348) (xy 379.92259 -181.63165) (xy 379.911592 -181.648464) (xy 379.909324 -181.65826)
			(xy 379.899854 -181.705587) (xy 379.871979 -181.797995) (xy 379.853698 -181.842664) (xy 379.850145 -181.852258)
			(xy 379.850136 -181.872698) (xy 379.853698 -181.882288) (xy 379.8707 -181.923701) (xy 379.897256 -182.009199)
			(xy 379.915094 -182.096932) (xy 379.924034 -182.186012) (xy 379.924564 -182.230776) (xy 379.92406 -182.273124)
			(xy 379.916009 -182.357438) (xy 379.89998 -182.440604) (xy 379.876119 -182.521871) (xy 379.84464 -182.600501)
			(xy 379.805829 -182.675782) (xy 379.760039 -182.747034) (xy 379.707683 -182.81361) (xy 379.649235 -182.874908)
			(xy 379.585225 -182.930373) (xy 379.516233 -182.979502) (xy 379.442883 -183.021851) (xy 379.36584 -183.057035)
			(xy 379.285801 -183.084737) (xy 379.203492 -183.104705) (xy 379.119657 -183.116758) (xy 379.035056 -183.120789)
			(xy 378.950455 -183.116758) (xy 378.86662 -183.104705) (xy 378.784311 -183.084737) (xy 378.704272 -183.057035)
			(xy 378.627229 -183.021851) (xy 378.553879 -182.979502) (xy 378.484887 -182.930373) (xy 378.420877 -182.874908)
			(xy 378.362429 -182.81361) (xy 378.310073 -182.747034) (xy 378.264283 -182.675782) (xy 378.225472 -182.600501)
			(xy 378.193993 -182.521871) (xy 378.170132 -182.440604) (xy 378.154103 -182.357438) (xy 378.146052 -182.273124)
			(xy 378.145548 -182.230776) (xy 378.146069 -182.186011) (xy 378.155001 -182.096929) (xy 378.172842 -182.009196)
			(xy 378.199411 -181.923701) (xy 378.216414 -181.882288) (xy 378.219994 -181.872702) (xy 378.219985 -181.852255)
			(xy 378.216414 -181.842664) (xy 378.19943 -181.801244) (xy 378.172869 -181.715748) (xy 378.155026 -181.628018)
			(xy 378.14608 -181.53894) (xy 378.145548 -181.494176) (xy 378.145887 -181.458262) (xy 378.151664 -181.386666)
			(xy 378.163195 -181.315769) (xy 378.171456 -181.280816) (xy 378.173086 -181.272505) (xy 378.171511 -181.255655)
			(xy 378.164551 -181.24023) (xy 378.15901 -181.233826) (xy 378.11837 -181.1909) (xy 378.108464 -181.193186)
			(xy 378.099649 -181.195458) (xy 378.084299 -181.205225) (xy 378.078492 -181.212236) (xy 378.053352 -181.244927)
			(xy 377.997956 -181.306026) (xy 377.937143 -181.361734) (xy 377.871434 -181.411575) (xy 377.801393 -181.455119)
			(xy 377.727622 -181.491993) (xy 377.650755 -181.521881) (xy 377.571452 -181.544524) (xy 377.490393 -181.55973)
			(xy 377.408274 -181.567368) (xy 377.367038 -181.567836) (xy 377.325923 -181.567365) (xy 377.244043 -181.559781)
			(xy 377.163213 -181.544674) (xy 377.084121 -181.522173) (xy 377.007443 -181.49247) (xy 376.933833 -181.455819)
			(xy 376.863919 -181.412532) (xy 376.798297 -181.362978) (xy 376.737528 -181.30758) (xy 376.68213 -181.246812)
			(xy 376.632575 -181.181191) (xy 376.589287 -181.111277) (xy 376.552634 -181.037668) (xy 376.522931 -180.96099)
			(xy 376.500429 -180.881899) (xy 376.48532 -180.801068) (xy 376.477735 -180.719189) (xy 376.477276 -180.678074)
			(xy 372.848069 -180.678074) (xy 372.8541 -180.720015) (xy 372.858091 -180.8038) (xy 372.8541 -180.887585)
			(xy 372.842162 -180.97061) (xy 372.822386 -181.052125) (xy 372.794951 -181.131391) (xy 372.760105 -181.20769)
			(xy 372.718163 -181.280331) (xy 372.669507 -181.348656) (xy 372.614576 -181.412047) (xy 372.553868 -181.469929)
			(xy 372.487932 -181.521778) (xy 372.417367 -181.567124) (xy 372.34281 -181.605557) (xy 372.264938 -181.636728)
			(xy 372.184455 -181.660356) (xy 372.10209 -181.676226) (xy 372.01859 -181.684195) (xy 371.97665 -181.684676)
			(xy 371.939461 -181.684274) (xy 371.865348 -181.677988) (xy 371.792028 -181.665482) (xy 371.720022 -181.646845)
			(xy 371.684804 -181.634892) (xy 371.676608 -181.632369) (xy 371.659472 -181.632369) (xy 371.651276 -181.634892)
			(xy 371.611916 -181.648156) (xy 371.531285 -181.66812) (xy 371.449135 -181.680416) (xy 371.40769 -181.683152)
			(xy 371.397914 -181.684226) (xy 371.380178 -181.69268) (xy 371.366873 -181.707139) (xy 371.362986 -181.716172)
			(xy 371.348 -181.753764) (xy 371.344447 -181.763358) (xy 371.344438 -181.783798) (xy 371.348 -181.793388)
			(xy 371.365037 -181.834794) (xy 371.39167 -181.920283) (xy 371.409574 -182.008016) (xy 371.418568 -182.097105)
			(xy 371.41912 -182.141876) (xy 371.418616 -182.184237) (xy 371.410563 -182.268574) (xy 371.394529 -182.351764)
			(xy 371.370661 -182.433054) (xy 371.339173 -182.511706) (xy 371.300351 -182.587009) (xy 371.254548 -182.658281)
			(xy 371.202177 -182.724877) (xy 371.143712 -182.786192) (xy 371.079684 -182.841673) (xy 371.010672 -182.890816)
			(xy 370.937302 -182.933176) (xy 370.860237 -182.968371) (xy 370.780175 -182.99608) (xy 370.697842 -183.016054)
			(xy 370.613983 -183.028111) (xy 370.529358 -183.032143) (xy 370.444733 -183.028111) (xy 370.360874 -183.016054)
			(xy 370.278541 -182.99608) (xy 370.198479 -182.968371) (xy 370.121414 -182.933176) (xy 370.048044 -182.890816)
			(xy 369.979032 -182.841673) (xy 369.915004 -182.786192) (xy 369.856539 -182.724877) (xy 369.804168 -182.658281)
			(xy 369.758365 -182.587009) (xy 369.719543 -182.511706) (xy 369.688055 -182.433054) (xy 369.664187 -182.351764)
			(xy 369.648153 -182.268574) (xy 369.6401 -182.184237) (xy 369.639596 -182.141876) (xy 369.640165 -182.097107)
			(xy 369.649173 -182.008022) (xy 369.667076 -181.92029) (xy 369.693694 -181.834799) (xy 369.710716 -181.793388)
			(xy 369.714296 -181.783802) (xy 369.714287 -181.763355) (xy 369.710716 -181.753764) (xy 369.693665 -181.712364)
			(xy 369.667035 -181.626872) (xy 369.649135 -181.539137) (xy 369.640146 -181.450047) (xy 369.639596 -181.405276)
			(xy 369.639771 -181.384669) (xy 369.641804 -181.343504) (xy 369.64366 -181.32298) (xy 369.644676 -181.311804)
			(xy 369.637818 -181.291738) (xy 369.571016 -181.22011) (xy 369.551458 -181.211728) (xy 369.540282 -181.211982)
			(xy 369.52301 -181.212236) (xy 369.481895 -181.211792) (xy 369.400014 -181.204205) (xy 369.319183 -181.189096)
			(xy 369.240091 -181.166593) (xy 369.163413 -181.136888) (xy 369.089803 -181.100234) (xy 369.019889 -181.056945)
			(xy 368.954268 -181.007389) (xy 368.893499 -180.95199) (xy 368.838101 -180.89122) (xy 368.788546 -180.825598)
			(xy 368.745258 -180.755683) (xy 368.708606 -180.682072) (xy 368.678902 -180.605393) (xy 368.6564 -180.526301)
			(xy 368.641292 -180.44547) (xy 368.633707 -180.36359) (xy 368.633248 -180.322474) (xy 368.6337 -180.283493)
			(xy 368.640575 -180.205835) (xy 368.654226 -180.129077) (xy 368.663982 -180.091334) (xy 368.666037 -180.082278)
			(xy 368.664208 -180.063813) (xy 368.655908 -180.047218) (xy 368.642231 -180.034679) (xy 368.633756 -180.030882)
			(xy 368.596114 -180.015301) (xy 368.523548 -179.97826) (xy 368.454673 -179.934739) (xy 368.390066 -179.885102)
			(xy 368.330268 -179.829767) (xy 368.27578 -179.769195) (xy 368.227059 -179.703896) (xy 368.184512 -179.634415)
			(xy 368.148496 -179.561335) (xy 368.119314 -179.485268) (xy 368.097208 -179.406851) (xy 368.082365 -179.326741)
			(xy 368.074909 -179.24561) (xy 368.074448 -179.204874) (xy 352.789998 -179.204874) (xy 353.723702 -180.138578)
			(xy 353.7311 -180.145426) (xy 353.749698 -180.153164) (xy 353.75977 -180.153564) (xy 359.221532 -180.153564)
			(xy 359.246488 -180.154178) (xy 359.295439 -180.16392) (xy 359.34155 -180.183023) (xy 359.38305 -180.210753)
			(xy 359.40111 -180.227986) (xy 360.41711 -181.243986) (xy 360.434368 -181.262027) (xy 360.462122 -181.303521)
			(xy 360.48123 -181.34964) (xy 360.490956 -181.398604) (xy 360.491532 -181.423564) (xy 360.491532 -186.885326)
			(xy 360.491961 -186.895393) (xy 360.499685 -186.913988) (xy 360.506518 -186.921394) (xy 362.105702 -188.520578)
			(xy 362.1131 -188.527426) (xy 362.131698 -188.535164) (xy 362.14177 -188.535564) (xy 366.907318 -188.535564)
			(xy 366.932274 -188.536177) (xy 366.981227 -188.545917) (xy 367.02734 -188.565018) (xy 367.068842 -188.592747)
			(xy 367.086896 -188.609986) (xy 371.950488 -193.473578) (xy 371.957885 -193.480429) (xy 371.976483 -193.488171)
			(xy 371.986556 -193.488564)
		)
		(stroke
			(width 0)
			(type solid)
		)
		(fill yes)
		(layer "In8.Cu")
		(net "GND")
	)
	(gr_poly
		(pts
			(xy 372.218458 -251.50064) (xy 372.23065 -251.493274) (xy 372.250358 -251.481499) (xy 372.292333 -251.462908)
			(xy 372.336477 -251.450302) (xy 372.38194 -251.443923) (xy 372.404894 -251.44349) (xy 372.420134 -251.443744)
			(xy 372.434358 -251.444506) (xy 372.45925 -251.431044) (xy 372.603776 -251.18187) (xy 372.603268 -251.153676)
			(xy 372.595648 -251.141484) (xy 372.583446 -251.121513) (xy 372.564176 -251.078863) (xy 372.551107 -251.033924)
			(xy 372.5445 -250.987592) (xy 372.544086 -250.964192) (xy 372.544596 -250.938205) (xy 372.552728 -250.886871)
			(xy 372.568789 -250.837441) (xy 372.592385 -250.791133) (xy 372.622935 -250.749085) (xy 372.659686 -250.712334)
			(xy 372.701734 -250.681784) (xy 372.748043 -250.658188) (xy 372.797473 -250.642127) (xy 372.848807 -250.633996)
			(xy 372.874794 -250.633484) (xy 372.898153 -250.63389) (xy 372.944405 -250.640464) (xy 372.989276 -250.653468)
			(xy 373.031876 -250.672645) (xy 373.051832 -250.684792) (xy 373.06377 -250.692412) (xy 373.091964 -250.69292)
			(xy 373.941086 -250.20524) (xy 373.954802 -250.180602) (xy 373.954294 -250.166378) (xy 373.95404 -250.154186)
			(xy 373.954524 -250.128199) (xy 373.962657 -250.076865) (xy 373.978722 -250.027435) (xy 374.002321 -249.981127)
			(xy 374.032874 -249.939082) (xy 374.069629 -249.902334) (xy 374.11168 -249.871788) (xy 374.157993 -249.848198)
			(xy 374.207425 -249.832143) (xy 374.258761 -249.824019) (xy 374.284748 -249.823478) (xy 374.300242 -249.823732)
			(xy 374.314466 -249.824494) (xy 374.339358 -249.811032) (xy 374.483884 -249.561604) (xy 374.483376 -249.53341)
			(xy 374.475756 -249.521472) (xy 374.463555 -249.501501) (xy 374.444285 -249.458851) (xy 374.431217 -249.413912)
			(xy 374.424612 -249.36758) (xy 374.424194 -249.34418) (xy 374.424705 -249.318194) (xy 374.432838 -249.266862)
			(xy 374.448901 -249.217434) (xy 374.472498 -249.171128) (xy 374.503048 -249.129082) (xy 374.539799 -249.092334)
			(xy 374.581846 -249.061786) (xy 374.628155 -249.038192) (xy 374.677583 -249.022133) (xy 374.728916 -249.014003)
			(xy 374.754902 -249.013472) (xy 374.770142 -249.013726) (xy 374.784366 -249.014488) (xy 374.809258 -249.001026)
			(xy 374.953784 -248.751598) (xy 374.953276 -248.723404) (xy 374.945656 -248.711466) (xy 374.933455 -248.691494)
			(xy 374.914186 -248.648845) (xy 374.901119 -248.603906) (xy 374.894515 -248.557574) (xy 374.894094 -248.534174)
			(xy 374.894507 -248.510586) (xy 374.901201 -248.463888) (xy 374.914463 -248.418614) (xy 374.934024 -248.375685)
			(xy 374.946418 -248.355612) (xy 374.954292 -248.343166) (xy 374.955054 -248.315226) (xy 374.811036 -248.067068)
			(xy 374.786398 -248.053606) (xy 374.77192 -248.054368) (xy 374.754902 -248.054876) (xy 374.728914 -248.054393)
			(xy 374.677577 -248.046262) (xy 374.628144 -248.030199) (xy 374.581833 -248.006601) (xy 374.539784 -247.976048)
			(xy 374.503032 -247.939294) (xy 374.472483 -247.897242) (xy 374.448889 -247.850928) (xy 374.432831 -247.801494)
			(xy 374.424705 -247.750156) (xy 374.424194 -247.724168) (xy 374.424592 -247.700537) (xy 374.431319 -247.653755)
			(xy 374.444645 -247.60841) (xy 374.464298 -247.565427) (xy 374.476772 -247.545352) (xy 374.484392 -247.53316)
			(xy 374.485154 -247.504966) (xy 374.34139 -247.257062) (xy 374.316498 -247.2436) (xy 374.30202 -247.244362)
			(xy 374.284748 -247.24487) (xy 374.258759 -247.244391) (xy 374.207421 -247.236266) (xy 374.157986 -247.22021)
			(xy 374.111671 -247.196618) (xy 374.069618 -247.16607) (xy 374.032862 -247.129319) (xy 374.002308 -247.08727)
			(xy 373.978708 -247.040959) (xy 373.962645 -246.991526) (xy 373.954513 -246.940189) (xy 373.954513 -246.888211)
			(xy 373.962645 -246.836874) (xy 373.978708 -246.787441) (xy 374.002308 -246.74113) (xy 374.032862 -246.699081)
			(xy 374.069618 -246.66233) (xy 374.111671 -246.631782) (xy 374.157985 -246.60819) (xy 374.207421 -246.592134)
			(xy 374.258759 -246.584009) (xy 374.284748 -246.583454) (xy 374.300242 -246.583708) (xy 374.31472 -246.58447)
			(xy 374.339358 -246.571008) (xy 374.483884 -246.321834) (xy 374.483376 -246.293386) (xy 374.475756 -246.281448)
			(xy 374.463556 -246.261476) (xy 374.44429 -246.218826) (xy 374.431225 -246.173887) (xy 374.424623 -246.127556)
			(xy 374.424194 -246.104156) (xy 374.424707 -246.078171) (xy 374.432843 -246.026842) (xy 374.448908 -245.977418)
			(xy 374.472506 -245.931114) (xy 374.503057 -245.889072) (xy 374.539807 -245.852327) (xy 374.581854 -245.821782)
			(xy 374.62816 -245.79819) (xy 374.677587 -245.782132) (xy 374.728917 -245.774003) (xy 374.754902 -245.773448)
			(xy 374.770142 -245.773702) (xy 374.784366 -245.774464) (xy 374.809258 -245.761002) (xy 374.953784 -245.511574)
			(xy 374.953276 -245.48338) (xy 374.945656 -245.471442) (xy 374.933456 -245.45147) (xy 374.914191 -245.40882)
			(xy 374.901127 -245.363881) (xy 374.894526 -245.31755) (xy 374.894094 -245.29415) (xy 374.894509 -245.270563)
			(xy 374.901206 -245.223866) (xy 374.91447 -245.178594) (xy 374.934034 -245.135667) (xy 374.946418 -245.115588)
			(xy 374.954292 -245.103142) (xy 374.955054 -245.075202) (xy 374.811036 -244.827044) (xy 374.786398 -244.813582)
			(xy 374.77192 -244.814344) (xy 374.754902 -244.814852) (xy 374.728913 -244.814343) (xy 374.677576 -244.806213)
			(xy 374.628143 -244.790152) (xy 374.58183 -244.766557) (xy 374.539777 -244.736008) (xy 374.503022 -244.699258)
			(xy 374.472467 -244.65721) (xy 374.448865 -244.6109) (xy 374.432798 -244.561469) (xy 374.424661 -244.510132)
			(xy 374.424194 -244.484144) (xy 374.424594 -244.460513) (xy 374.431324 -244.413733) (xy 374.444653 -244.368389)
			(xy 374.464308 -244.325409) (xy 374.476772 -244.305328) (xy 374.484392 -244.293136) (xy 374.485154 -244.264942)
			(xy 374.34139 -244.017038) (xy 374.316498 -244.003576) (xy 374.30202 -244.004338) (xy 374.284748 -244.004846)
			(xy 374.258753 -244.004366) (xy 374.207403 -243.99624) (xy 374.157956 -243.98018) (xy 374.111631 -243.956582)
			(xy 374.069568 -243.926028) (xy 374.032804 -243.889268) (xy 374.002243 -243.84721) (xy 373.978638 -243.800888)
			(xy 373.962571 -243.751444) (xy 373.954437 -243.700095) (xy 373.954437 -243.648105) (xy 373.962571 -243.596756)
			(xy 373.978638 -243.547312) (xy 374.002243 -243.50099) (xy 374.032804 -243.458932) (xy 374.069568 -243.422172)
			(xy 374.111631 -243.391618) (xy 374.157956 -243.36802) (xy 374.207403 -243.35196) (xy 374.258753 -243.343834)
			(xy 374.284748 -243.34343) (xy 374.300242 -243.343684) (xy 374.31472 -243.344446) (xy 374.339358 -243.330984)
			(xy 374.483884 -243.08181) (xy 374.483376 -243.053362) (xy 374.475756 -243.041424) (xy 374.463551 -243.021453)
			(xy 374.444275 -242.978805) (xy 374.4312 -242.933866) (xy 374.424588 -242.887533) (xy 374.424194 -242.864132)
			(xy 374.424675 -242.838141) (xy 374.432802 -242.786799) (xy 374.448861 -242.73736) (xy 374.472458 -242.691043)
			(xy 374.503009 -242.648987) (xy 374.539764 -242.612229) (xy 374.581817 -242.581673) (xy 374.628132 -242.558073)
			(xy 374.67757 -242.542009) (xy 374.728911 -242.533877) (xy 374.754902 -242.533424) (xy 374.770142 -242.533678)
			(xy 374.784366 -242.53444) (xy 374.809258 -242.520978) (xy 374.953784 -242.27155) (xy 374.953276 -242.243356)
			(xy 374.945656 -242.231418) (xy 374.933452 -242.211447) (xy 374.914176 -242.168799) (xy 374.901102 -242.12386)
			(xy 374.894491 -242.077527) (xy 374.894094 -242.054126) (xy 374.894511 -242.030539) (xy 374.901211 -241.983843)
			(xy 374.914478 -241.938574) (xy 374.934044 -241.895649) (xy 374.946418 -241.875564) (xy 374.954292 -241.863118)
			(xy 374.955054 -241.835178) (xy 374.811036 -241.58702) (xy 374.786398 -241.573558) (xy 374.77192 -241.57432)
			(xy 374.754902 -241.574828) (xy 374.728914 -241.574319) (xy 374.677578 -241.566188) (xy 374.628146 -241.550128)
			(xy 374.581835 -241.526532) (xy 374.539785 -241.495983) (xy 374.503031 -241.459232) (xy 374.472479 -241.417184)
			(xy 374.448881 -241.370874) (xy 374.432817 -241.321443) (xy 374.424683 -241.270108) (xy 374.424194 -241.24412)
			(xy 374.424596 -241.22049) (xy 374.431329 -241.173711) (xy 374.44466 -241.128369) (xy 374.464318 -241.08539)
			(xy 374.476772 -241.065304) (xy 374.484392 -241.053112) (xy 374.485154 -241.024918) (xy 374.34139 -240.777014)
			(xy 374.316498 -240.763552) (xy 374.30202 -240.764314) (xy 374.284748 -240.764822) (xy 374.258755 -240.764342)
			(xy 374.207409 -240.756217) (xy 374.157966 -240.740158) (xy 374.111644 -240.716562) (xy 374.069584 -240.686009)
			(xy 374.032822 -240.649253) (xy 374.002263 -240.607197) (xy 373.97866 -240.560879) (xy 373.962594 -240.511438)
			(xy 373.954461 -240.460093) (xy 373.954461 -240.408107) (xy 373.962594 -240.356762) (xy 373.97866 -240.307321)
			(xy 374.002263 -240.261003) (xy 374.032822 -240.218947) (xy 374.069584 -240.182191) (xy 374.111644 -240.151638)
			(xy 374.157966 -240.128042) (xy 374.207409 -240.111983) (xy 374.258755 -240.103858) (xy 374.284748 -240.103406)
			(xy 374.300242 -240.10366) (xy 374.31472 -240.104422) (xy 374.339358 -240.09096) (xy 374.483884 -239.841786)
			(xy 374.483376 -239.813592) (xy 374.475756 -239.8014) (xy 374.463553 -239.781429) (xy 374.44428 -239.73878)
			(xy 374.431208 -239.693841) (xy 374.424599 -239.647509) (xy 374.424194 -239.624108) (xy 374.424677 -239.598118)
			(xy 374.432807 -239.546779) (xy 374.448868 -239.497343) (xy 374.472466 -239.451029) (xy 374.503018 -239.408977)
			(xy 374.539772 -239.372222) (xy 374.581824 -239.341669) (xy 374.628138 -239.318071) (xy 374.677573 -239.302008)
			(xy 374.728912 -239.293877) (xy 374.754902 -239.2934) (xy 374.770142 -239.293654) (xy 374.784366 -239.294416)
			(xy 374.809258 -239.280954) (xy 374.953784 -239.03178) (xy 374.953276 -239.003332) (xy 374.945656 -238.991394)
			(xy 374.933453 -238.971423) (xy 374.914181 -238.928774) (xy 374.90111 -238.883835) (xy 374.894502 -238.837503)
			(xy 374.894094 -238.814102) (xy 374.894348 -238.798862) (xy 374.89511 -238.784384) (xy 374.881648 -238.759746)
			(xy 374.034558 -238.273336) (xy 374.006364 -238.274098) (xy 373.994172 -238.281972) (xy 373.974036 -238.294482)
			(xy 373.930943 -238.314236) (xy 373.88547 -238.327632) (xy 373.83855 -238.334395) (xy 373.814848 -238.334804)
			(xy 373.788857 -238.334324) (xy 373.737513 -238.326199) (xy 373.688072 -238.310142) (xy 373.641753 -238.286547)
			(xy 373.599696 -238.255996) (xy 373.562936 -238.219241) (xy 373.532379 -238.177188) (xy 373.508777 -238.130872)
			(xy 373.492712 -238.081434) (xy 373.484579 -238.030091) (xy 373.484579 -237.978109) (xy 373.492712 -237.926766)
			(xy 373.508777 -237.877328) (xy 373.532379 -237.831012) (xy 373.562936 -237.788959) (xy 373.599696 -237.752204)
			(xy 373.641753 -237.721653) (xy 373.688072 -237.698058) (xy 373.737513 -237.682001) (xy 373.788857 -237.673876)
			(xy 373.814848 -237.673388) (xy 373.830088 -237.673642) (xy 373.844566 -237.674404) (xy 373.869204 -237.660942)
			(xy 374.01373 -237.411768) (xy 374.013222 -237.383574) (xy 374.005602 -237.371382) (xy 373.993402 -237.35141)
			(xy 373.974134 -237.30876) (xy 373.961067 -237.263821) (xy 373.954462 -237.21749) (xy 373.95404 -237.19409)
			(xy 373.954524 -237.168103) (xy 373.962657 -237.116768) (xy 373.97872 -237.067338) (xy 374.002319 -237.02103)
			(xy 374.032873 -236.978983) (xy 374.069628 -236.942235) (xy 374.111679 -236.911689) (xy 374.157992 -236.888098)
			(xy 374.207425 -236.872043) (xy 374.258761 -236.863919) (xy 374.284748 -236.863382) (xy 374.300242 -236.863636)
			(xy 374.314466 -236.864398) (xy 374.339358 -236.850936) (xy 374.483884 -236.601508) (xy 374.483376 -236.573314)
			(xy 374.475756 -236.561376) (xy 374.463554 -236.541405) (xy 374.444284 -236.498755) (xy 374.431216 -236.453816)
			(xy 374.42461 -236.407484) (xy 374.424194 -236.384084) (xy 374.4246 -236.360466) (xy 374.431289 -236.313706)
			(xy 374.444558 -236.268372) (xy 374.464136 -236.225385) (xy 374.476518 -236.205268) (xy 374.484392 -236.193076)
			(xy 374.485154 -236.164882) (xy 374.34139 -235.916978) (xy 374.316498 -235.903516) (xy 374.30202 -235.904278)
			(xy 374.284748 -235.904786) (xy 374.258758 -235.904307) (xy 374.207417 -235.896182) (xy 374.157979 -235.880125)
			(xy 374.111663 -235.856531) (xy 374.069607 -235.825982) (xy 374.032849 -235.789229) (xy 374.002294 -235.747178)
			(xy 373.978694 -235.700865) (xy 373.962629 -235.65143) (xy 373.954497 -235.60009) (xy 373.954497 -235.54811)
			(xy 373.962629 -235.49677) (xy 373.978694 -235.447335) (xy 374.002294 -235.401022) (xy 374.032849 -235.358971)
			(xy 374.069607 -235.322218) (xy 374.111663 -235.291669) (xy 374.157979 -235.268075) (xy 374.207417 -235.252018)
			(xy 374.258758 -235.243893) (xy 374.284748 -235.24337) (xy 374.300242 -235.243624) (xy 374.31472 -235.244386)
			(xy 374.339358 -235.230924) (xy 374.483884 -234.98175) (xy 374.483376 -234.953302) (xy 374.475756 -234.941364)
			(xy 374.463555 -234.921392) (xy 374.444287 -234.878743) (xy 374.43122 -234.833804) (xy 374.424616 -234.787472)
			(xy 374.424194 -234.764072) (xy 374.424706 -234.738086) (xy 374.43284 -234.686755) (xy 374.448903 -234.637329)
			(xy 374.472501 -234.591023) (xy 374.503051 -234.548979) (xy 374.539802 -234.512231) (xy 374.581849 -234.481685)
			(xy 374.628156 -234.458092) (xy 374.677585 -234.442033) (xy 374.728916 -234.433903) (xy 374.754902 -234.433364)
			(xy 374.770142 -234.433618) (xy 374.784366 -234.43438) (xy 374.809258 -234.420918) (xy 374.953784 -234.17149)
			(xy 374.953276 -234.143296) (xy 374.945656 -234.131358) (xy 374.933455 -234.111386) (xy 374.914188 -234.068737)
			(xy 374.901122 -234.023798) (xy 374.894518 -233.977466) (xy 374.894094 -233.954066) (xy 374.894508 -233.930478)
			(xy 374.901203 -233.88378) (xy 374.914465 -233.838508) (xy 374.934027 -233.795579) (xy 374.946418 -233.775504)
			(xy 374.954292 -233.763058) (xy 374.955054 -233.735118) (xy 374.811036 -233.48696) (xy 374.786398 -233.473498)
			(xy 374.77192 -233.47426) (xy 374.754902 -233.474768) (xy 374.728914 -233.474285) (xy 374.677577 -233.466154)
			(xy 374.628145 -233.450091) (xy 374.581834 -233.426493) (xy 374.539786 -233.39594) (xy 374.503035 -233.359185)
			(xy 374.472487 -233.317133) (xy 374.448894 -233.27082) (xy 374.432837 -233.221386) (xy 374.424712 -233.170048)
			(xy 374.424194 -233.14406) (xy 374.424593 -233.120429) (xy 374.431321 -233.073647) (xy 374.444648 -233.028303)
			(xy 374.464302 -232.985321) (xy 374.476772 -232.965244) (xy 374.484392 -232.953052) (xy 374.485154 -232.924858)
			(xy 374.34139 -232.676954) (xy 374.316498 -232.663492) (xy 374.30202 -232.664254) (xy 374.284748 -232.664762)
			(xy 374.25876 -232.664283) (xy 374.207423 -232.656158) (xy 374.157989 -232.640103) (xy 374.111675 -232.616511)
			(xy 374.069623 -232.585964) (xy 374.032868 -232.549214) (xy 374.002314 -232.507166) (xy 373.978716 -232.460856)
			(xy 373.962653 -232.411424) (xy 373.954521 -232.360088) (xy 373.954521 -232.308112) (xy 373.962653 -232.256776)
			(xy 373.978716 -232.207344) (xy 374.002314 -232.161034) (xy 374.032868 -232.118986) (xy 374.069623 -232.082236)
			(xy 374.111675 -232.051689) (xy 374.157989 -232.028097) (xy 374.207423 -232.012042) (xy 374.25876 -232.003917)
			(xy 374.284748 -232.003346) (xy 374.300242 -232.0036) (xy 374.314466 -232.004362) (xy 374.339358 -231.9909)
			(xy 374.483884 -231.741472) (xy 374.483376 -231.713278) (xy 374.475756 -231.70134) (xy 374.46355 -231.68137)
			(xy 374.444272 -231.638721) (xy 374.431195 -231.593782) (xy 374.42458 -231.547449) (xy 374.424194 -231.524048)
			(xy 374.424596 -231.500429) (xy 374.431277 -231.453665) (xy 374.444538 -231.408326) (xy 374.46411 -231.365333)
			(xy 374.476518 -231.345232) (xy 374.484392 -231.33304) (xy 374.485154 -231.304846) (xy 374.341644 -231.05745)
			(xy 374.316498 -231.043734) (xy 374.30202 -231.044496) (xy 374.284748 -231.045004) (xy 374.258757 -231.044524)
			(xy 374.207413 -231.036399) (xy 374.157972 -231.020342) (xy 374.111653 -230.996747) (xy 374.069596 -230.966196)
			(xy 374.032836 -230.929441) (xy 374.002279 -230.887388) (xy 373.978677 -230.841072) (xy 373.962612 -230.791634)
			(xy 373.954479 -230.740291) (xy 373.954479 -230.688309) (xy 373.962612 -230.636966) (xy 373.978677 -230.587528)
			(xy 374.002279 -230.541212) (xy 374.032836 -230.499159) (xy 374.069596 -230.462404) (xy 374.111653 -230.431853)
			(xy 374.157972 -230.408258) (xy 374.207413 -230.392201) (xy 374.258757 -230.384076) (xy 374.284748 -230.383588)
			(xy 374.299988 -230.383842) (xy 374.314466 -230.384604) (xy 374.339104 -230.371142) (xy 374.483884 -230.12146)
			(xy 374.483376 -230.093266) (xy 374.475756 -230.081328) (xy 374.463551 -230.061357) (xy 374.444275 -230.018709)
			(xy 374.431199 -229.97377) (xy 374.424586 -229.927437) (xy 374.424194 -229.904036) (xy 374.424597 -229.880417)
			(xy 374.431279 -229.833654) (xy 374.444542 -229.788316) (xy 374.464115 -229.745324) (xy 374.476518 -229.72522)
			(xy 374.484392 -229.713028) (xy 374.485154 -229.684834) (xy 374.341644 -229.437438) (xy 374.316498 -229.423722)
			(xy 374.30202 -229.424484) (xy 374.284748 -229.424992) (xy 374.258758 -229.424513) (xy 374.207416 -229.416388)
			(xy 374.157977 -229.40033) (xy 374.111659 -229.376736) (xy 374.069603 -229.346186) (xy 374.032845 -229.309433)
			(xy 374.002289 -229.267382) (xy 373.978688 -229.221067) (xy 373.962624 -229.171631) (xy 373.954491 -229.12029)
			(xy 373.954491 -229.06831) (xy 373.962624 -229.016969) (xy 373.978688 -228.967533) (xy 374.002289 -228.921218)
			(xy 374.032845 -228.879167) (xy 374.069603 -228.842414) (xy 374.111659 -228.811864) (xy 374.157977 -228.78827)
			(xy 374.207416 -228.772212) (xy 374.258758 -228.764087) (xy 374.284748 -228.763576) (xy 374.300242 -228.76383)
			(xy 374.314466 -228.764592) (xy 374.339358 -228.75113) (xy 374.483884 -228.501702) (xy 374.483376 -228.473508)
			(xy 374.475756 -228.46157) (xy 374.463555 -228.441599) (xy 374.444286 -228.398949) (xy 374.431218 -228.35401)
			(xy 374.424613 -228.307678) (xy 374.424194 -228.284278) (xy 374.424705 -228.258292) (xy 374.432839 -228.20696)
			(xy 374.448901 -228.157533) (xy 374.472499 -228.111227) (xy 374.503049 -228.069182) (xy 374.5398 -228.032433)
			(xy 374.581847 -228.001886) (xy 374.628155 -227.978292) (xy 374.677584 -227.962233) (xy 374.728916 -227.954103)
			(xy 374.754902 -227.95357) (xy 374.780419 -227.954044) (xy 374.830846 -227.961886) (xy 374.87947 -227.977383)
			(xy 374.925135 -228.000167) (xy 374.966756 -228.029698) (xy 375.003346 -228.065273) (xy 375.034035 -228.106048)
			(xy 375.046494 -228.128322) (xy 375.053352 -228.141022) (xy 375.077228 -228.155246) (xy 375.372376 -228.155246)
			(xy 375.396252 -228.141022) (xy 375.40311 -228.128322) (xy 375.415561 -228.106045) (xy 375.446256 -228.065278)
			(xy 375.48285 -228.02971) (xy 375.524473 -228.000185) (xy 375.570138 -227.977406) (xy 375.618761 -227.961913)
			(xy 375.669186 -227.954073) (xy 375.720218 -227.954073) (xy 375.770643 -227.961913) (xy 375.819266 -227.977406)
			(xy 375.864931 -228.000185) (xy 375.906554 -228.02971) (xy 375.943148 -228.065278) (xy 375.973843 -228.106045)
			(xy 375.986294 -228.128322) (xy 375.993152 -228.141022) (xy 376.017028 -228.155246) (xy 376.31243 -228.155246)
			(xy 376.336306 -228.141022) (xy 376.343164 -228.128322) (xy 376.355619 -228.10605) (xy 376.386321 -228.065292)
			(xy 376.422917 -228.029731) (xy 376.46454 -228.000213) (xy 376.510203 -227.977437) (xy 376.558821 -227.961944)
			(xy 376.609242 -227.954101) (xy 376.634756 -227.95357) (xy 376.649996 -227.953824) (xy 376.664474 -227.954586)
			(xy 376.689112 -227.941124) (xy 376.833892 -227.691696) (xy 376.833384 -227.663502) (xy 376.825764 -227.65131)
			(xy 376.813575 -227.631367) (xy 376.794318 -227.58878) (xy 376.781246 -227.543907) (xy 376.774617 -227.497641)
			(xy 376.774202 -227.474272) (xy 376.774714 -227.448287) (xy 376.782848 -227.396956) (xy 376.798911 -227.34753)
			(xy 376.822509 -227.301225) (xy 376.853059 -227.259181) (xy 376.88981 -227.222435) (xy 376.931857 -227.191889)
			(xy 376.978165 -227.168297) (xy 377.027593 -227.152239) (xy 377.078924 -227.144111) (xy 377.10491 -227.143564)
			(xy 377.12015 -227.143818) (xy 377.134374 -227.14458) (xy 377.159266 -227.131118) (xy 377.303792 -226.88169)
			(xy 377.303284 -226.853496) (xy 377.295664 -226.841558) (xy 377.283463 -226.821586) (xy 377.264195 -226.778937)
			(xy 377.251129 -226.733998) (xy 377.244525 -226.687666) (xy 377.244102 -226.664266) (xy 377.244614 -226.638281)
			(xy 377.252749 -226.586951) (xy 377.268813 -226.537526) (xy 377.292411 -226.491222) (xy 377.322961 -226.449179)
			(xy 377.359712 -226.412433) (xy 377.401759 -226.381888) (xy 377.448066 -226.358296) (xy 377.497494 -226.342239)
			(xy 377.548825 -226.334111) (xy 377.57481 -226.333558) (xy 377.59005 -226.333812) (xy 377.604528 -226.334574)
			(xy 377.629166 -226.321112) (xy 377.773692 -226.071938) (xy 377.773184 -226.043744) (xy 377.765564 -226.031552)
			(xy 377.753363 -226.01158) (xy 377.734096 -225.968931) (xy 377.721031 -225.923992) (xy 377.714428 -225.87766)
			(xy 377.714002 -225.85426) (xy 377.714515 -225.828275) (xy 377.72265 -225.776946) (xy 377.738715 -225.727522)
			(xy 377.762313 -225.681218) (xy 377.792864 -225.639176) (xy 377.829615 -225.602431) (xy 377.871661 -225.571887)
			(xy 377.917968 -225.548296) (xy 377.967395 -225.532238) (xy 378.018725 -225.524111) (xy 378.04471 -225.523552)
			(xy 378.060204 -225.523806) (xy 378.074428 -225.524568) (xy 378.09932 -225.511106) (xy 378.243846 -225.261678)
			(xy 378.243338 -225.233484) (xy 378.235718 -225.221546) (xy 378.223519 -225.201574) (xy 378.204256 -225.158923)
			(xy 378.191193 -225.113984) (xy 378.184592 -225.067653) (xy 378.184156 -225.044254) (xy 378.184669 -225.018268)
			(xy 378.192805 -224.966937) (xy 378.20887 -224.91751) (xy 378.232467 -224.871205) (xy 378.263017 -224.82916)
			(xy 378.299767 -224.792411) (xy 378.341813 -224.761862) (xy 378.38812 -224.738266) (xy 378.437547 -224.722203)
			(xy 378.488878 -224.714068) (xy 378.514864 -224.713546) (xy 378.530104 -224.7138) (xy 378.544582 -224.714562)
			(xy 378.56922 -224.7011) (xy 378.713746 -224.451926) (xy 378.713238 -224.423732) (xy 378.705618 -224.41154)
			(xy 378.693414 -224.391569) (xy 378.674138 -224.348921) (xy 378.661062 -224.303982) (xy 378.654448 -224.257649)
			(xy 378.654056 -224.234248) (xy 378.654536 -224.208255) (xy 378.662661 -224.156909) (xy 378.678718 -224.107466)
			(xy 378.702313 -224.061143) (xy 378.732863 -224.019082) (xy 378.769618 -223.982318) (xy 378.811671 -223.951757)
			(xy 378.857988 -223.92815) (xy 378.907427 -223.91208) (xy 378.958771 -223.903942) (xy 378.984764 -223.90354)
			(xy 379.000258 -223.903794) (xy 379.014482 -223.904556) (xy 379.039374 -223.891094) (xy 380.170182 -221.942152)
			(xy 380.171452 -221.917768) (xy 380.166372 -221.906592) (xy 380.155966 -221.881825) (xy 380.1447 -221.829308)
			(xy 380.14402 -221.802452) (xy 380.14402 -221.080076) (xy 380.144594 -221.055117) (xy 380.154337 -221.006158)
			(xy 380.173445 -220.960041) (xy 380.201184 -220.918538) (xy 380.218442 -220.900498) (xy 387.950456 -213.168484)
			(xy 387.958076 -213.148164) (xy 387.957568 -213.137242) (xy 387.953632 -213.066255) (xy 387.952792 -212.92407)
			(xy 387.959985 -212.782064) (xy 387.975189 -212.640691) (xy 387.998356 -212.500403) (xy 388.02941 -212.361648)
			(xy 388.068254 -212.224868) (xy 388.114763 -212.090502) (xy 388.168788 -211.958977) (xy 388.230156 -211.830715)
			(xy 388.298673 -211.706124) (xy 388.374119 -211.585603) (xy 388.456253 -211.469536) (xy 388.544812 -211.358295)
			(xy 388.639514 -211.252234) (xy 388.740057 -211.151693) (xy 388.846119 -211.056992) (xy 388.957362 -210.968433)
			(xy 389.073429 -210.886301) (xy 389.193951 -210.810857) (xy 389.318543 -210.742342) (xy 389.446806 -210.680975)
			(xy 389.578332 -210.626951) (xy 389.712699 -210.580444) (xy 389.849479 -210.541603) (xy 389.988234 -210.51055)
			(xy 390.128523 -210.487385) (xy 390.269896 -210.472183) (xy 390.411902 -210.464991) (xy 390.554087 -210.465833)
			(xy 390.625076 -210.469734) (xy 390.635998 -210.470242) (xy 390.656318 -210.462622) (xy 393.369546 -207.749394)
			(xy 393.376397 -207.741998) (xy 393.384138 -207.723399) (xy 393.384532 -207.713326) (xy 393.384532 -194.202558)
			(xy 393.384102 -194.19249) (xy 393.376381 -194.173894) (xy 393.369546 -194.16649) (xy 393.214606 -194.01155)
			(xy 393.20721 -194.004697) (xy 393.188612 -193.996953) (xy 393.178538 -193.996564) (xy 393.046458 -193.996564)
			(xy 393.034831 -193.997128) (xy 393.013918 -194.0073) (xy 393.006326 -194.016122) (xy 392.988134 -194.038563)
			(xy 392.946131 -194.078223) (xy 392.898631 -194.111098) (xy 392.846718 -194.136439) (xy 392.791579 -194.153667)
			(xy 392.734474 -194.162387) (xy 392.70559 -194.162934) (xy 392.678221 -194.162461) (xy 392.624044 -194.154635)
			(xy 392.571543 -194.139145) (xy 392.521795 -194.116309) (xy 392.475822 -194.086596) (xy 392.454892 -194.068954)
			(xy 392.44778 -194.062858) (xy 392.430762 -194.056508) (xy 392.345418 -194.056508) (xy 392.3284 -194.062858)
			(xy 392.321288 -194.068954) (xy 392.300357 -194.086597) (xy 392.254392 -194.116325) (xy 392.204645 -194.13917)
			(xy 392.152141 -194.15466) (xy 392.097961 -194.162478) (xy 392.07059 -194.162934) (xy 392.041706 -194.1624)
			(xy 391.984599 -194.153686) (xy 391.92946 -194.136457) (xy 391.877551 -194.111108) (xy 391.830058 -194.07822)
			(xy 391.78807 -194.038545) (xy 391.769854 -194.016122) (xy 391.762268 -194.007284) (xy 391.741357 -193.997082)
			(xy 391.729722 -193.996564) (xy 371.860318 -193.996564) (xy 371.835361 -193.995985) (xy 371.786409 -193.986231)
			(xy 371.7403 -193.967115) (xy 371.698807 -193.93937) (xy 371.68074 -193.922142) (xy 366.817148 -189.05855)
			(xy 366.809749 -189.051706) (xy 366.79115 -189.043983) (xy 366.78108 -189.043564) (xy 362.015532 -189.043564)
			(xy 361.990574 -189.042986) (xy 361.941621 -189.033235) (xy 361.89551 -189.01412) (xy 361.854015 -188.986377)
			(xy 361.835954 -188.969142) (xy 360.057954 -187.191142) (xy 360.040696 -187.1731) (xy 360.012941 -187.131606)
			(xy 359.99383 -187.085488) (xy 359.984101 -187.036525) (xy 359.983532 -187.011564) (xy 359.983532 -181.549802)
			(xy 359.98311 -181.539731) (xy 359.9754 -181.521123) (xy 359.968546 -181.513734) (xy 359.131362 -180.67655)
			(xy 359.123964 -180.669704) (xy 359.105365 -180.661976) (xy 359.095294 -180.661564) (xy 353.633532 -180.661564)
			(xy 353.608574 -180.660986) (xy 353.559621 -180.651235) (xy 353.51351 -180.63212) (xy 353.472015 -180.604377)
			(xy 353.453954 -180.587142) (xy 351.675954 -178.809142) (xy 351.658696 -178.7911) (xy 351.630941 -178.749606)
			(xy 351.61183 -178.703488) (xy 351.602101 -178.654525) (xy 351.601532 -178.629564) (xy 351.601532 -173.040802)
			(xy 351.60111 -173.030731) (xy 351.5934 -173.012123) (xy 351.586546 -173.004734) (xy 351.003362 -172.42155)
			(xy 350.995964 -172.414704) (xy 350.977365 -172.406976) (xy 350.967294 -172.406564) (xy 341.17915 -172.406564)
			(xy 341.169072 -172.406993) (xy 341.150476 -172.414769) (xy 341.136334 -172.42913) (xy 341.13216 -172.438314)
			(xy 341.116949 -172.474599) (xy 341.080083 -172.544112) (xy 341.036256 -172.609458) (xy 340.985933 -172.669944)
			(xy 340.929648 -172.724927) (xy 340.868001 -172.773821) (xy 340.801646 -172.816107) (xy 340.73129 -172.851335)
			(xy 340.65768 -172.879131) (xy 340.581599 -172.899199) (xy 340.503856 -172.911326) (xy 340.425278 -172.915382)
			(xy 340.3467 -172.911326) (xy 340.268957 -172.899199) (xy 340.192876 -172.879131) (xy 340.119266 -172.851335)
			(xy 340.04891 -172.816107) (xy 339.982555 -172.773821) (xy 339.920908 -172.724927) (xy 339.864623 -172.669944)
			(xy 339.8143 -172.609458) (xy 339.770473 -172.544112) (xy 339.733607 -172.474599) (xy 339.718396 -172.438314)
			(xy 339.714209 -172.429144) (xy 339.700048 -172.414819) (xy 339.681476 -172.40702) (xy 339.671406 -172.406564)
			(xy 337.660996 -172.406564) (xy 337.653122 -172.406856) (xy 337.638118 -172.411638) (xy 337.631532 -172.415962)
			(xy 337.609767 -172.430685) (xy 337.56165 -172.451774) (xy 337.510227 -172.462534) (xy 337.483958 -172.463206)
			(xy 333.800196 -172.463206) (xy 333.790126 -172.46363) (xy 333.771523 -172.471346) (xy 333.764128 -172.478192)
			(xy 333.434944 -172.807376) (xy 333.428105 -172.814776) (xy 333.420391 -172.833375) (xy 333.419958 -172.843444)
			(xy 333.419958 -214.864188) (xy 333.42038 -214.874258) (xy 333.428098 -214.89286) (xy 333.434944 -214.900256)
			(xy 336.083262 -217.548574) (xy 338.152884 -217.548574) (xy 338.152884 -217.494026) (xy 338.160647 -217.440032)
			(xy 338.176017 -217.387693) (xy 338.198679 -217.338074) (xy 338.228172 -217.292186) (xy 338.263897 -217.250963)
			(xy 338.305125 -217.215244) (xy 338.351016 -217.185756) (xy 338.400638 -217.1631) (xy 338.452979 -217.147737)
			(xy 338.506973 -217.13998) (xy 338.534248 -217.13952) (xy 339.550248 -217.13952) (xy 339.577514 -217.140046)
			(xy 339.63149 -217.147813) (xy 339.683811 -217.163181) (xy 339.733413 -217.185839) (xy 339.779286 -217.215325)
			(xy 339.820495 -217.251039) (xy 339.856204 -217.292253) (xy 339.885684 -217.338129) (xy 339.908336 -217.387734)
			(xy 339.923698 -217.440057) (xy 339.931458 -217.494034) (xy 339.931458 -217.548566) (xy 339.923698 -217.602543)
			(xy 339.908336 -217.654866) (xy 339.885684 -217.704471) (xy 339.856204 -217.750347) (xy 339.820495 -217.791561)
			(xy 339.779286 -217.827275) (xy 339.733413 -217.856761) (xy 339.683811 -217.879419) (xy 339.63149 -217.894787)
			(xy 339.577514 -217.902554) (xy 339.550248 -217.903044) (xy 338.534248 -217.903044) (xy 338.506973 -217.90262)
			(xy 338.452979 -217.894863) (xy 338.400638 -217.8795) (xy 338.351016 -217.856844) (xy 338.305125 -217.827356)
			(xy 338.263897 -217.791637) (xy 338.228172 -217.750414) (xy 338.198679 -217.704526) (xy 338.176017 -217.654907)
			(xy 338.160647 -217.602568) (xy 338.152884 -217.548574) (xy 336.083262 -217.548574) (xy 338.659978 -220.12529)
			(xy 338.6963 -220.128846) (xy 338.71154 -220.118178) (xy 338.733862 -220.103534) (xy 338.78196 -220.080375)
			(xy 338.832973 -220.064644) (xy 338.885762 -220.056694) (xy 338.912454 -220.056202) (xy 338.940441 -220.056719)
			(xy 338.995728 -220.065469) (xy 339.048965 -220.082761) (xy 339.098841 -220.108169) (xy 339.144127 -220.141067)
			(xy 339.183709 -220.180645) (xy 339.216612 -220.225929) (xy 339.242025 -220.275802) (xy 339.259322 -220.329037)
			(xy 339.268078 -220.384323) (xy 339.268562 -220.41231) (xy 339.268105 -220.439004) (xy 339.260166 -220.491799)
			(xy 339.244423 -220.542813) (xy 339.22123 -220.5909) (xy 339.206586 -220.613224) (xy 339.195918 -220.628464)
			(xy 339.199474 -220.664786) (xy 340.157562 -221.622874) (xy 340.174818 -221.640916) (xy 340.202569 -221.682412)
			(xy 340.221675 -221.72853) (xy 340.231401 -221.777492) (xy 340.231984 -221.802452) (xy 340.231306 -221.829307)
			(xy 340.220025 -221.881819) (xy 340.209632 -221.906592) (xy 340.204552 -221.917768) (xy 340.205822 -221.942152)
			(xy 340.396576 -222.271082) (xy 340.421468 -222.284544) (xy 340.435692 -222.283782) (xy 340.451186 -222.283528)
			(xy 340.477175 -222.28401) (xy 340.528513 -222.29214) (xy 340.577947 -222.308201) (xy 340.62426 -222.331799)
			(xy 340.66631 -222.362351) (xy 340.703063 -222.399107) (xy 340.733613 -222.441159) (xy 340.757207 -222.487473)
			(xy 340.773265 -222.536908) (xy 340.781392 -222.588247) (xy 340.781894 -222.614236) (xy 340.781492 -222.637638)
			(xy 340.774898 -222.683975) (xy 340.761832 -222.728918) (xy 340.742556 -222.771569) (xy 340.730332 -222.791528)
			(xy 340.722712 -222.80372) (xy 340.72195 -222.831914) (xy 341.33663 -223.891094) (xy 341.361268 -223.904556)
			(xy 341.375746 -223.903794) (xy 341.390986 -223.90354) (xy 341.416975 -223.904022) (xy 341.468312 -223.912152)
			(xy 341.517745 -223.928214) (xy 341.564057 -223.951811) (xy 341.606106 -223.982364) (xy 341.642858 -224.019119)
			(xy 341.673406 -224.061172) (xy 341.697 -224.107486) (xy 341.713056 -224.156921) (xy 341.721181 -224.208259)
			(xy 341.721694 -224.234248) (xy 341.721291 -224.25765) (xy 341.714695 -224.303986) (xy 341.701628 -224.348929)
			(xy 341.682351 -224.391578) (xy 341.670132 -224.41154) (xy 341.662512 -224.423478) (xy 341.662004 -224.451926)
			(xy 341.80653 -224.7011) (xy 341.831422 -224.714562) (xy 341.845646 -224.7138) (xy 341.86114 -224.713546)
			(xy 341.887126 -224.714058) (xy 341.938459 -224.722194) (xy 341.987887 -224.738258) (xy 342.034194 -224.761855)
			(xy 342.076241 -224.792405) (xy 342.112992 -224.829155) (xy 342.143542 -224.871201) (xy 342.16714 -224.917508)
			(xy 342.183205 -224.966935) (xy 342.191341 -225.018268) (xy 342.191848 -225.044254) (xy 342.191445 -225.067656)
			(xy 342.184847 -225.113991) (xy 342.171778 -225.158932) (xy 342.152498 -225.20158) (xy 342.140286 -225.221546)
			(xy 342.132666 -225.233738) (xy 342.132158 -225.261932) (xy 342.276684 -225.511106) (xy 342.301322 -225.524568)
			(xy 342.3158 -225.523806) (xy 342.33104 -225.523552) (xy 342.357026 -225.524064) (xy 342.408358 -225.5322)
			(xy 342.457786 -225.548264) (xy 342.504093 -225.571861) (xy 342.546139 -225.602411) (xy 342.582889 -225.639161)
			(xy 342.613439 -225.681207) (xy 342.637036 -225.727514) (xy 342.6531 -225.776942) (xy 342.661236 -225.828274)
			(xy 342.661748 -225.85426) (xy 342.661344 -225.877661) (xy 342.654746 -225.923997) (xy 342.641676 -225.968937)
			(xy 342.622396 -226.011584) (xy 342.610186 -226.031552) (xy 342.602566 -226.04349) (xy 342.602058 -226.071684)
			(xy 342.746584 -226.321112) (xy 342.771476 -226.334574) (xy 342.7857 -226.333812) (xy 342.801194 -226.333558)
			(xy 342.827182 -226.334067) (xy 342.87852 -226.342197) (xy 342.927953 -226.358257) (xy 342.974266 -226.381852)
			(xy 343.016318 -226.412401) (xy 343.053073 -226.449152) (xy 343.083627 -226.4912) (xy 343.107228 -226.53751)
			(xy 343.123294 -226.586941) (xy 343.13143 -226.638278) (xy 343.131902 -226.664266) (xy 343.131498 -226.687667)
			(xy 343.1249 -226.734003) (xy 343.111831 -226.778944) (xy 343.092553 -226.821592) (xy 343.08034 -226.841558)
			(xy 343.07272 -226.85375) (xy 343.072212 -226.881944) (xy 343.216738 -227.131118) (xy 343.24163 -227.14458)
			(xy 343.255854 -227.143818) (xy 343.271094 -227.143564) (xy 343.297082 -227.144073) (xy 343.348419 -227.152203)
			(xy 343.397852 -227.168263) (xy 343.444165 -227.191858) (xy 343.486216 -227.222407) (xy 343.522971 -227.259158)
			(xy 343.553524 -227.301206) (xy 343.577124 -227.347516) (xy 343.593189 -227.396948) (xy 343.601324 -227.448284)
			(xy 343.601802 -227.474272) (xy 343.601386 -227.497642) (xy 343.594776 -227.543914) (xy 343.581713 -227.588793)
			(xy 343.562457 -227.631384) (xy 343.55024 -227.65131) (xy 343.54262 -227.663502) (xy 343.542112 -227.691696)
			(xy 343.686892 -227.941124) (xy 343.71153 -227.954586) (xy 343.725754 -227.953824) (xy 343.740994 -227.95357)
			(xy 343.766511 -227.954043) (xy 343.816939 -227.961884) (xy 343.865564 -227.97738) (xy 343.91123 -228.000164)
			(xy 343.952852 -228.029695) (xy 343.989443 -228.06527) (xy 344.020133 -228.106045) (xy 344.032586 -228.128322)
			(xy 344.039444 -228.141022) (xy 344.06332 -228.155246) (xy 344.358722 -228.155246) (xy 344.382598 -228.141022)
			(xy 344.389456 -228.128322) (xy 344.401911 -228.10605) (xy 344.432612 -228.06529) (xy 344.469208 -228.029729)
			(xy 344.510831 -228.00021) (xy 344.556494 -227.977433) (xy 344.605113 -227.961939) (xy 344.655534 -227.954095)
			(xy 344.681048 -227.95357) (xy 344.707033 -227.954083) (xy 344.758363 -227.962219) (xy 344.807789 -227.978284)
			(xy 344.854093 -228.001882) (xy 344.896137 -228.032433) (xy 344.932884 -228.069183) (xy 344.963431 -228.111229)
			(xy 344.987026 -228.157535) (xy 345.003087 -228.206962) (xy 345.011219 -228.258293) (xy 345.011756 -228.284278)
			(xy 345.011351 -228.307679) (xy 345.004751 -228.354013) (xy 344.991679 -228.398953) (xy 344.972397 -228.441598)
			(xy 344.960194 -228.46157) (xy 344.952574 -228.473508) (xy 344.952066 -228.501702) (xy 345.096592 -228.75113)
			(xy 345.121484 -228.764592) (xy 345.135708 -228.76383) (xy 345.151202 -228.763576) (xy 345.17719 -228.764086)
			(xy 345.228527 -228.772217) (xy 345.27796 -228.788279) (xy 345.324271 -228.811876) (xy 345.366321 -228.842427)
			(xy 345.403074 -228.87918) (xy 345.433625 -228.921231) (xy 345.457222 -228.967542) (xy 345.473284 -229.016975)
			(xy 345.481414 -229.068312) (xy 345.481414 -229.120288) (xy 345.473284 -229.171625) (xy 345.457222 -229.221058)
			(xy 345.433625 -229.267369) (xy 345.403074 -229.30942) (xy 345.366321 -229.346173) (xy 345.324271 -229.376724)
			(xy 345.27796 -229.400321) (xy 345.228527 -229.416383) (xy 345.17719 -229.424514) (xy 345.151202 -229.424992)
			(xy 345.13393 -229.424484) (xy 345.119452 -229.423722) (xy 345.094306 -229.437438) (xy 344.950796 -229.684834)
			(xy 344.951558 -229.713028) (xy 344.959432 -229.72522) (xy 344.971851 -229.745317) (xy 344.991444 -229.788306)
			(xy 345.004715 -229.833646) (xy 345.011395 -229.880414) (xy 345.011756 -229.904036) (xy 345.011354 -229.927438)
			(xy 345.004759 -229.973775) (xy 344.991692 -230.018717) (xy 344.972414 -230.061366) (xy 344.960194 -230.081328)
			(xy 344.952574 -230.093266) (xy 344.952066 -230.12146) (xy 345.096846 -230.371142) (xy 345.121484 -230.384604)
			(xy 345.135962 -230.383842) (xy 345.151202 -230.383588) (xy 345.177189 -230.384098) (xy 345.228524 -230.392229)
			(xy 345.277955 -230.40829) (xy 345.324265 -230.431886) (xy 345.366313 -230.462436) (xy 345.403065 -230.499188)
			(xy 345.433615 -230.541237) (xy 345.457211 -230.587547) (xy 345.473272 -230.636978) (xy 345.481402 -230.688313)
			(xy 345.481402 -230.740287) (xy 345.473272 -230.791622) (xy 345.457211 -230.841053) (xy 345.433615 -230.887363)
			(xy 345.403065 -230.929412) (xy 345.366313 -230.966164) (xy 345.324265 -230.996714) (xy 345.277955 -231.02031)
			(xy 345.228524 -231.036371) (xy 345.177189 -231.044502) (xy 345.151202 -231.045004) (xy 345.13393 -231.044496)
			(xy 345.119452 -231.043734) (xy 345.094306 -231.05745) (xy 344.950796 -231.304846) (xy 344.951558 -231.33304)
			(xy 344.959432 -231.345232) (xy 344.97185 -231.36533) (xy 344.991441 -231.408318) (xy 345.004711 -231.453659)
			(xy 345.011389 -231.500426) (xy 345.011756 -231.524048) (xy 345.011353 -231.54745) (xy 345.004757 -231.593786)
			(xy 344.991688 -231.638727) (xy 344.972409 -231.681376) (xy 344.960194 -231.70134) (xy 344.952574 -231.713278)
			(xy 344.952066 -231.741472) (xy 345.096592 -231.9909) (xy 345.121484 -232.004362) (xy 345.135708 -232.0036)
			(xy 345.151202 -232.003346) (xy 345.177193 -232.003856) (xy 345.228534 -232.011988) (xy 345.277971 -232.028051)
			(xy 345.324287 -232.05165) (xy 345.366341 -232.082204) (xy 345.403097 -232.118961) (xy 345.433651 -232.161015)
			(xy 345.45725 -232.207331) (xy 345.473313 -232.256768) (xy 345.481444 -232.308109) (xy 345.481444 -232.360091)
			(xy 345.473313 -232.411432) (xy 345.45725 -232.460869) (xy 345.433651 -232.507185) (xy 345.403097 -232.549239)
			(xy 345.366341 -232.585996) (xy 345.324287 -232.61655) (xy 345.277971 -232.640149) (xy 345.228534 -232.656212)
			(xy 345.177193 -232.664344) (xy 345.151202 -232.664762) (xy 345.13393 -232.664254) (xy 345.119452 -232.663492)
			(xy 345.09456 -232.676954) (xy 344.950796 -232.924858) (xy 344.951304 -232.953052) (xy 344.959178 -232.965244)
			(xy 344.971622 -232.985335) (xy 344.991267 -233.028316) (xy 345.004592 -233.073656) (xy 345.011326 -233.120431)
			(xy 345.011756 -233.14406) (xy 345.011249 -233.170051) (xy 345.003124 -233.221393) (xy 344.987067 -233.270832)
			(xy 344.963474 -233.31715) (xy 344.932926 -233.359208) (xy 344.896175 -233.395969) (xy 344.854125 -233.426528)
			(xy 344.807813 -233.450134) (xy 344.758378 -233.466204) (xy 344.707038 -233.474343) (xy 344.681048 -233.474768)
			(xy 344.66403 -233.47426) (xy 344.649298 -233.473498) (xy 344.62466 -233.48696) (xy 344.480896 -233.734864)
			(xy 344.481404 -233.763058) (xy 344.489278 -233.77525) (xy 344.501721 -233.795341) (xy 344.521365 -233.838322)
			(xy 344.53469 -233.883662) (xy 344.541423 -233.930437) (xy 344.541856 -233.954066) (xy 344.541452 -233.977467)
			(xy 344.534853 -234.023802) (xy 344.521783 -234.068743) (xy 344.502502 -234.111389) (xy 344.490294 -234.131358)
			(xy 344.482674 -234.14355) (xy 344.481912 -234.171744) (xy 344.626438 -234.420918) (xy 344.65133 -234.43438)
			(xy 344.665554 -234.433618) (xy 344.681048 -234.433364) (xy 344.707034 -234.433877) (xy 344.758364 -234.442013)
			(xy 344.80779 -234.458078) (xy 344.854095 -234.481676) (xy 344.896139 -234.512226) (xy 344.932887 -234.548977)
			(xy 344.963434 -234.591022) (xy 344.987029 -234.637329) (xy 345.003091 -234.686756) (xy 345.011224 -234.738086)
			(xy 345.011756 -234.764072) (xy 345.011351 -234.787473) (xy 345.004752 -234.833808) (xy 344.991681 -234.878748)
			(xy 344.972399 -234.921394) (xy 344.960194 -234.941364) (xy 344.952574 -234.953556) (xy 344.952066 -234.98175)
			(xy 345.096592 -235.230924) (xy 345.12123 -235.244386) (xy 345.135708 -235.243624) (xy 345.151202 -235.24337)
			(xy 345.177191 -235.24388) (xy 345.228528 -235.252011) (xy 345.277962 -235.268073) (xy 345.324274 -235.291671)
			(xy 345.366325 -235.322223) (xy 345.403079 -235.358977) (xy 345.43363 -235.401027) (xy 345.457227 -235.44734)
			(xy 345.473289 -235.496773) (xy 345.48142 -235.548111) (xy 345.48142 -235.600089) (xy 345.473289 -235.651427)
			(xy 345.457227 -235.70086) (xy 345.43363 -235.747173) (xy 345.403079 -235.789223) (xy 345.366325 -235.825977)
			(xy 345.324274 -235.856529) (xy 345.277962 -235.880127) (xy 345.228528 -235.896189) (xy 345.177191 -235.90432)
			(xy 345.151202 -235.904786) (xy 345.13393 -235.904278) (xy 345.119452 -235.903516) (xy 345.09456 -235.916978)
			(xy 344.950796 -236.164882) (xy 344.951558 -236.193076) (xy 344.959432 -236.205268) (xy 344.971848 -236.225366)
			(xy 344.991434 -236.268355) (xy 345.004699 -236.313696) (xy 345.011372 -236.360463) (xy 345.011756 -236.384084)
			(xy 345.011351 -236.407485) (xy 345.004749 -236.453819) (xy 344.991677 -236.498758) (xy 344.972395 -236.541403)
			(xy 344.960194 -236.561376) (xy 344.952574 -236.573314) (xy 344.952066 -236.601508) (xy 345.096592 -236.850936)
			(xy 345.121484 -236.864398) (xy 345.135708 -236.863636) (xy 345.151202 -236.863382) (xy 345.177189 -236.863892)
			(xy 345.228524 -236.872022) (xy 345.277955 -236.888083) (xy 345.324265 -236.911679) (xy 345.366314 -236.942229)
			(xy 345.403066 -236.97898) (xy 345.433617 -237.021028) (xy 345.457213 -237.067337) (xy 345.473276 -237.116768)
			(xy 345.481408 -237.168103) (xy 345.48191 -237.19409) (xy 345.481504 -237.217491) (xy 345.474903 -237.263825)
			(xy 345.461832 -237.308765) (xy 345.442552 -237.351411) (xy 345.430348 -237.371382) (xy 345.422728 -237.383574)
			(xy 345.42222 -237.411768) (xy 345.566746 -237.660942) (xy 345.591384 -237.674404) (xy 345.605862 -237.673642)
			(xy 345.621102 -237.673388) (xy 345.647089 -237.673898) (xy 345.698424 -237.682029) (xy 345.747855 -237.69809)
			(xy 345.794165 -237.721686) (xy 345.836213 -237.752236) (xy 345.872965 -237.788988) (xy 345.903515 -237.831037)
			(xy 345.927111 -237.877347) (xy 345.943172 -237.926778) (xy 345.951302 -237.978113) (xy 345.951302 -238.030087)
			(xy 345.943172 -238.081422) (xy 345.927111 -238.130853) (xy 345.903515 -238.177163) (xy 345.872965 -238.219212)
			(xy 345.836213 -238.255964) (xy 345.794165 -238.286514) (xy 345.747855 -238.31011) (xy 345.698424 -238.326171)
			(xy 345.647089 -238.334302) (xy 345.621102 -238.334804) (xy 345.597399 -238.334398) (xy 345.55048 -238.327631)
			(xy 345.505006 -238.314236) (xy 345.461911 -238.294488) (xy 345.441778 -238.281972) (xy 345.429586 -238.274098)
			(xy 345.401392 -238.273336) (xy 344.554302 -238.759746) (xy 344.54084 -238.784384) (xy 344.541602 -238.798862)
			(xy 344.541856 -238.814102) (xy 344.541449 -238.837503) (xy 344.534846 -238.883835) (xy 344.521771 -238.928773)
			(xy 344.502487 -238.971417) (xy 344.490294 -238.991394) (xy 344.482674 -239.003332) (xy 344.482166 -239.03178)
			(xy 344.626692 -239.280954) (xy 344.651584 -239.294416) (xy 344.665808 -239.293654) (xy 344.681048 -239.2934)
			(xy 344.707032 -239.293913) (xy 344.758361 -239.30205) (xy 344.807784 -239.318115) (xy 344.854087 -239.341714)
			(xy 344.896128 -239.372264) (xy 344.932872 -239.409015) (xy 344.963416 -239.451061) (xy 344.987006 -239.497367)
			(xy 345.003063 -239.546794) (xy 345.011191 -239.598123) (xy 345.011756 -239.624108) (xy 345.011349 -239.647508)
			(xy 345.004745 -239.693841) (xy 344.991669 -239.738778) (xy 344.972385 -239.781421) (xy 344.960194 -239.8014)
			(xy 344.952574 -239.813592) (xy 344.952066 -239.841786) (xy 345.096592 -240.09096) (xy 345.12123 -240.104422)
			(xy 345.135708 -240.10366) (xy 345.151202 -240.103406) (xy 345.177188 -240.103916) (xy 345.22852 -240.112046)
			(xy 345.277948 -240.128107) (xy 345.324256 -240.151702) (xy 345.366302 -240.18225) (xy 345.403051 -240.219)
			(xy 345.433599 -240.261046) (xy 345.457194 -240.307354) (xy 345.473254 -240.356782) (xy 345.481385 -240.408114)
			(xy 345.481385 -240.460086) (xy 345.473254 -240.511418) (xy 345.457194 -240.560846) (xy 345.433599 -240.607154)
			(xy 345.403051 -240.6492) (xy 345.366302 -240.68595) (xy 345.324256 -240.716498) (xy 345.277948 -240.740093)
			(xy 345.22852 -240.756154) (xy 345.177188 -240.764284) (xy 345.151202 -240.764822) (xy 345.13393 -240.764314)
			(xy 345.119452 -240.763552) (xy 345.09456 -240.777014) (xy 344.950796 -241.024918) (xy 344.951304 -241.053112)
			(xy 344.959178 -241.065304) (xy 344.971624 -241.085394) (xy 344.991274 -241.128374) (xy 345.004605 -241.173714)
			(xy 345.011345 -241.220491) (xy 345.011756 -241.24412) (xy 345.011245 -241.270108) (xy 345.003112 -241.321442)
			(xy 344.98705 -241.370873) (xy 344.963454 -241.417184) (xy 344.932905 -241.459233) (xy 344.896154 -241.495986)
			(xy 344.854107 -241.526539) (xy 344.807799 -241.550139) (xy 344.75837 -241.566206) (xy 344.707035 -241.574343)
			(xy 344.681048 -241.574828) (xy 344.66403 -241.57432) (xy 344.649298 -241.573558) (xy 344.62466 -241.58702)
			(xy 344.480896 -241.834924) (xy 344.481404 -241.863118) (xy 344.489278 -241.87531) (xy 344.501724 -241.8954)
			(xy 344.521373 -241.938381) (xy 344.534703 -241.983721) (xy 344.541442 -242.030497) (xy 344.541856 -242.054126)
			(xy 344.541455 -242.077528) (xy 344.534861 -242.123865) (xy 344.521795 -242.168809) (xy 344.502518 -242.211459)
			(xy 344.490294 -242.231418) (xy 344.482674 -242.24361) (xy 344.481912 -242.271804) (xy 344.626438 -242.520978)
			(xy 344.65133 -242.53444) (xy 344.665554 -242.533678) (xy 344.681048 -242.533424) (xy 344.707032 -242.533937)
			(xy 344.758359 -242.542074) (xy 344.807781 -242.55814) (xy 344.854081 -242.581738) (xy 344.89612 -242.61229)
			(xy 344.932862 -242.649041) (xy 344.963403 -242.691087) (xy 344.986991 -242.737393) (xy 345.003045 -242.786819)
			(xy 345.011169 -242.838148) (xy 345.011756 -242.864132) (xy 345.011354 -242.887534) (xy 345.00476 -242.933871)
			(xy 344.991693 -242.978814) (xy 344.972416 -243.021463) (xy 344.960194 -243.041424) (xy 344.952574 -243.053616)
			(xy 344.952066 -243.08181) (xy 345.096592 -243.330984) (xy 345.12123 -243.344446) (xy 345.135708 -243.343684)
			(xy 345.151202 -243.34343) (xy 345.177186 -243.34394) (xy 345.228514 -243.35207) (xy 345.277939 -243.368129)
			(xy 345.324243 -243.391722) (xy 345.366286 -243.422269) (xy 345.403033 -243.459016) (xy 345.433579 -243.501059)
			(xy 345.457172 -243.547363) (xy 345.473231 -243.596788) (xy 345.48136 -243.648116) (xy 345.48136 -243.6741)
			(xy 361.758723 -243.6741) (xy 361.762898 -243.623721) (xy 361.775308 -243.574716) (xy 361.795615 -243.528421)
			(xy 361.823265 -243.486101) (xy 361.857503 -243.448909) (xy 361.897396 -243.41786) (xy 361.941856 -243.393801)
			(xy 361.989669 -243.377388) (xy 362.039532 -243.369068) (xy 362.064808 -243.368576) (xy 363.004862 -243.368576)
			(xy 363.030146 -243.36899) (xy 363.080025 -243.377308) (xy 363.127854 -243.393722) (xy 363.172329 -243.417786)
			(xy 363.212237 -243.448843) (xy 363.246487 -243.486045) (xy 363.274147 -243.528377) (xy 363.294462 -243.574685)
			(xy 363.306876 -243.623705) (xy 363.311053 -243.6741) (xy 363.306876 -243.724495) (xy 363.294462 -243.773515)
			(xy 363.274147 -243.819823) (xy 363.246487 -243.862155) (xy 363.212237 -243.899357) (xy 363.172329 -243.930414)
			(xy 363.127854 -243.954478) (xy 363.080025 -243.970892) (xy 363.030146 -243.97921) (xy 363.004862 -243.9797)
			(xy 362.064808 -243.9797) (xy 362.039532 -243.979132) (xy 361.989669 -243.970812) (xy 361.941856 -243.954399)
			(xy 361.897396 -243.93034) (xy 361.857503 -243.899291) (xy 361.823265 -243.862099) (xy 361.795615 -243.819779)
			(xy 361.775308 -243.773484) (xy 361.762898 -243.724479) (xy 361.758723 -243.6741) (xy 345.48136 -243.6741)
			(xy 345.48136 -243.700084) (xy 345.473231 -243.751412) (xy 345.457172 -243.800837) (xy 345.433579 -243.847141)
			(xy 345.403033 -243.889184) (xy 345.366286 -243.925931) (xy 345.324243 -243.956478) (xy 345.277939 -243.980071)
			(xy 345.228514 -243.99613) (xy 345.177186 -244.00426) (xy 345.151202 -244.004846) (xy 345.13393 -244.004338)
			(xy 345.119452 -244.003576) (xy 345.09456 -244.017038) (xy 344.950796 -244.264942) (xy 344.951304 -244.293136)
			(xy 344.959178 -244.305328) (xy 344.971623 -244.325418) (xy 344.99127 -244.368399) (xy 345.004597 -244.413739)
			(xy 345.011333 -244.460515) (xy 345.011755 -244.4841) (xy 364.108984 -244.4841) (xy 364.113155 -244.433763)
			(xy 364.125555 -244.384799) (xy 364.145845 -244.338543) (xy 364.173472 -244.296259) (xy 364.207683 -244.259098)
			(xy 364.247543 -244.228076) (xy 364.291966 -244.204037) (xy 364.33974 -244.187639) (xy 364.389561 -244.179327)
			(xy 364.414816 -244.178836) (xy 365.35487 -244.178836) (xy 365.380133 -244.179238) (xy 365.42997 -244.18755)
			(xy 365.47776 -244.203952) (xy 365.522198 -244.227997) (xy 365.562072 -244.259028) (xy 365.596293 -244.2962)
			(xy 365.62393 -244.338497) (xy 365.644227 -244.384767) (xy 365.656631 -244.433747) (xy 365.660804 -244.4841)
			(xy 366.928884 -244.4841) (xy 366.933055 -244.433762) (xy 366.945456 -244.384797) (xy 366.965746 -244.338541)
			(xy 366.993374 -244.296256) (xy 367.027586 -244.259095) (xy 367.067447 -244.228073) (xy 367.111871 -244.204035)
			(xy 367.159646 -244.187637) (xy 367.209469 -244.179327) (xy 367.234724 -244.178836) (xy 368.174778 -244.178836)
			(xy 368.200041 -244.179239) (xy 368.249877 -244.187552) (xy 368.297665 -244.203955) (xy 368.342102 -244.228)
			(xy 368.381975 -244.259031) (xy 368.416196 -244.296203) (xy 368.443831 -244.3385) (xy 368.464128 -244.384769)
			(xy 368.476531 -244.433748) (xy 368.480704 -244.4841) (xy 369.749113 -244.4841) (xy 369.753283 -244.433771)
			(xy 369.76568 -244.384814) (xy 369.785966 -244.338565) (xy 369.813587 -244.296286) (xy 369.847791 -244.25913)
			(xy 369.887643 -244.22811) (xy 369.932057 -244.204073) (xy 369.979822 -244.187673) (xy 370.029635 -244.179359)
			(xy 370.054886 -244.178836) (xy 370.99494 -244.178836) (xy 371.020197 -244.179272) (xy 371.070021 -244.187592)
			(xy 371.117796 -244.203999) (xy 371.162219 -244.228045) (xy 371.202079 -244.259074) (xy 371.236289 -244.296241)
			(xy 371.263916 -244.33853) (xy 371.284205 -244.38479) (xy 371.296604 -244.433759) (xy 371.300776 -244.4841)
			(xy 372.569013 -244.4841) (xy 372.573183 -244.43377) (xy 372.585581 -244.384812) (xy 372.605867 -244.338563)
			(xy 372.63349 -244.296284) (xy 372.667694 -244.259127) (xy 372.707547 -244.228107) (xy 372.751963 -244.20407)
			(xy 372.799729 -244.187671) (xy 372.849543 -244.179358) (xy 372.874794 -244.178836) (xy 373.814848 -244.178836)
			(xy 373.840104 -244.179273) (xy 373.889927 -244.187594) (xy 373.937701 -244.204002) (xy 373.982123 -244.228048)
			(xy 374.021982 -244.259077) (xy 374.056191 -244.296243) (xy 374.083817 -244.338533) (xy 374.104106 -244.384792)
			(xy 374.116505 -244.43376) (xy 374.120676 -244.4841) (xy 374.116505 -244.53444) (xy 374.104106 -244.583408)
			(xy 374.083817 -244.629667) (xy 374.056191 -244.671957) (xy 374.021982 -244.709123) (xy 373.982123 -244.740152)
			(xy 373.937701 -244.764198) (xy 373.889927 -244.780606) (xy 373.840104 -244.788927) (xy 373.814848 -244.789452)
			(xy 372.874794 -244.789452) (xy 372.849543 -244.788842) (xy 372.799729 -244.780529) (xy 372.751963 -244.76413)
			(xy 372.707547 -244.740093) (xy 372.667694 -244.709073) (xy 372.63349 -244.671916) (xy 372.605867 -244.629637)
			(xy 372.585581 -244.583388) (xy 372.573183 -244.53443) (xy 372.569013 -244.4841) (xy 371.300776 -244.4841)
			(xy 371.296604 -244.534441) (xy 371.284205 -244.58341) (xy 371.263915 -244.62967) (xy 371.236289 -244.671959)
			(xy 371.202079 -244.709126) (xy 371.162219 -244.740155) (xy 371.117796 -244.764201) (xy 371.070021 -244.780608)
			(xy 371.020197 -244.788928) (xy 370.99494 -244.789452) (xy 370.054886 -244.789452) (xy 370.029635 -244.788841)
			(xy 369.979822 -244.780527) (xy 369.932057 -244.764127) (xy 369.887643 -244.74009) (xy 369.847791 -244.70907)
			(xy 369.813587 -244.671914) (xy 369.785966 -244.629635) (xy 369.76568 -244.583386) (xy 369.753283 -244.534429)
			(xy 369.749113 -244.4841) (xy 368.480704 -244.4841) (xy 368.476531 -244.534452) (xy 368.464128 -244.583431)
			(xy 368.443831 -244.6297) (xy 368.416196 -244.671997) (xy 368.381975 -244.709169) (xy 368.342102 -244.7402)
			(xy 368.297665 -244.764245) (xy 368.249877 -244.780648) (xy 368.200041 -244.788961) (xy 368.174778 -244.789452)
			(xy 367.234724 -244.789452) (xy 367.209469 -244.788873) (xy 367.159646 -244.780563) (xy 367.111871 -244.764165)
			(xy 367.067447 -244.740127) (xy 367.027586 -244.709105) (xy 366.993374 -244.671944) (xy 366.965746 -244.629659)
			(xy 366.945456 -244.583403) (xy 366.933055 -244.534438) (xy 366.928884 -244.4841) (xy 365.660804 -244.4841)
			(xy 365.656631 -244.534453) (xy 365.644227 -244.583433) (xy 365.62393 -244.629703) (xy 365.596293 -244.672)
			(xy 365.562072 -244.709172) (xy 365.522198 -244.740203) (xy 365.47776 -244.764248) (xy 365.42997 -244.78065)
			(xy 365.380133 -244.788962) (xy 365.35487 -244.789452) (xy 364.414816 -244.789452) (xy 364.389561 -244.788873)
			(xy 364.33974 -244.780561) (xy 364.291966 -244.764163) (xy 364.247543 -244.740124) (xy 364.207683 -244.709102)
			(xy 364.173472 -244.671941) (xy 364.145845 -244.629657) (xy 364.125555 -244.583401) (xy 364.113155 -244.534437)
			(xy 364.108984 -244.4841) (xy 345.011755 -244.4841) (xy 345.011756 -244.484144) (xy 345.011243 -244.51013)
			(xy 345.003107 -244.561462) (xy 344.987043 -244.61089) (xy 344.963446 -244.657197) (xy 344.932896 -244.699243)
			(xy 344.896146 -244.735993) (xy 344.8541 -244.766544) (xy 344.807794 -244.790142) (xy 344.758366 -244.806207)
			(xy 344.707034 -244.814343) (xy 344.681048 -244.814852) (xy 344.66403 -244.814344) (xy 344.649298 -244.813582)
			(xy 344.62466 -244.827044) (xy 344.480896 -245.074948) (xy 344.481404 -245.103142) (xy 344.489278 -245.115334)
			(xy 344.501722 -245.135425) (xy 344.521369 -245.178405) (xy 344.534695 -245.223745) (xy 344.541431 -245.270521)
			(xy 344.541855 -245.2941) (xy 361.758735 -245.2941) (xy 361.76291 -245.243723) (xy 361.775319 -245.194719)
			(xy 361.795626 -245.148427) (xy 361.823274 -245.106109) (xy 361.857511 -245.068918) (xy 361.897403 -245.03787)
			(xy 361.941861 -245.013812) (xy 361.989672 -244.997399) (xy 362.039533 -244.98908) (xy 362.064808 -244.988588)
			(xy 363.004862 -244.988588) (xy 363.030147 -244.988978) (xy 363.080028 -244.997296) (xy 363.127859 -245.013711)
			(xy 363.172336 -245.037776) (xy 363.212245 -245.068834) (xy 363.246497 -245.106037) (xy 363.274158 -245.148371)
			(xy 363.294473 -245.194681) (xy 363.306888 -245.243703) (xy 363.311065 -245.2941) (xy 363.306888 -245.344497)
			(xy 363.294473 -245.393519) (xy 363.274158 -245.439829) (xy 363.246497 -245.482163) (xy 363.212245 -245.519366)
			(xy 363.172336 -245.550424) (xy 363.127859 -245.574489) (xy 363.080028 -245.590904) (xy 363.030147 -245.599222)
			(xy 363.004862 -245.599712) (xy 362.064808 -245.599712) (xy 362.039533 -245.59912) (xy 361.989672 -245.590801)
			(xy 361.941861 -245.574388) (xy 361.897403 -245.55033) (xy 361.857511 -245.519282) (xy 361.823274 -245.482091)
			(xy 361.795626 -245.439773) (xy 361.775319 -245.393481) (xy 361.76291 -245.344477) (xy 361.758735 -245.2941)
			(xy 344.541855 -245.2941) (xy 344.541856 -245.29415) (xy 344.541453 -245.317552) (xy 344.534856 -245.363888)
			(xy 344.521788 -245.408829) (xy 344.502509 -245.451477) (xy 344.490294 -245.471442) (xy 344.482674 -245.483634)
			(xy 344.481912 -245.511828) (xy 344.626438 -245.761002) (xy 344.65133 -245.774464) (xy 344.665554 -245.773702)
			(xy 344.681048 -245.773448) (xy 344.707034 -245.773961) (xy 344.758365 -245.782097) (xy 344.807792 -245.798162)
			(xy 344.854098 -245.82176) (xy 344.896143 -245.85231) (xy 344.932893 -245.88906) (xy 344.963442 -245.931105)
			(xy 344.98704 -245.977412) (xy 345.003104 -246.026839) (xy 345.011239 -246.07817) (xy 345.011756 -246.104156)
			(xy 345.011755 -246.1042) (xy 364.108896 -246.1042) (xy 364.113068 -246.053848) (xy 364.125472 -246.00487)
			(xy 364.145768 -245.958601) (xy 364.173403 -245.916305) (xy 364.207623 -245.879133) (xy 364.247495 -245.848102)
			(xy 364.291931 -245.824057) (xy 364.339718 -245.807653) (xy 364.389554 -245.79934) (xy 364.414816 -245.798848)
			(xy 365.35487 -245.798848) (xy 365.380126 -245.799426) (xy 365.429949 -245.807736) (xy 365.477725 -245.824133)
			(xy 365.52215 -245.848171) (xy 365.562012 -245.879193) (xy 365.596224 -245.916354) (xy 365.623853 -245.958639)
			(xy 365.644144 -246.004896) (xy 365.656545 -246.053861) (xy 365.660716 -246.1042) (xy 366.928796 -246.1042)
			(xy 366.932969 -246.053847) (xy 366.945372 -246.004868) (xy 366.965669 -245.958599) (xy 366.993305 -245.916302)
			(xy 367.027526 -245.879131) (xy 367.067399 -245.848099) (xy 367.111836 -245.824054) (xy 367.159625 -245.807652)
			(xy 367.209461 -245.799339) (xy 367.234724 -245.798848) (xy 368.174778 -245.798848) (xy 368.200033 -245.799427)
			(xy 368.249855 -245.807737) (xy 368.29763 -245.824135) (xy 368.342054 -245.848173) (xy 368.381915 -245.879196)
			(xy 368.416126 -245.916357) (xy 368.443754 -245.958642) (xy 368.464045 -246.004897) (xy 368.476445 -246.053862)
			(xy 368.480616 -246.1042) (xy 369.749024 -246.1042) (xy 369.753196 -246.053856) (xy 369.765597 -246.004885)
			(xy 369.785888 -245.958623) (xy 369.813518 -245.916332) (xy 369.847731 -245.879165) (xy 369.887595 -245.848136)
			(xy 369.932022 -245.824092) (xy 369.979801 -245.807687) (xy 370.029628 -245.79937) (xy 370.054886 -245.798848)
			(xy 370.99494 -245.798848) (xy 371.02019 -245.799461) (xy 371.069999 -245.807778) (xy 371.11776 -245.82418)
			(xy 371.162171 -245.848219) (xy 371.202019 -245.879239) (xy 371.236219 -245.916395) (xy 371.263838 -245.958673)
			(xy 371.284121 -246.004919) (xy 371.296517 -246.053873) (xy 371.300687 -246.1042) (xy 372.568924 -246.1042)
			(xy 372.573096 -246.053855) (xy 372.585497 -246.004884) (xy 372.60579 -245.958621) (xy 372.63342 -245.916329)
			(xy 372.667634 -245.879162) (xy 372.707499 -245.848133) (xy 372.751927 -245.824089) (xy 372.799707 -245.807685)
			(xy 372.849535 -245.79937) (xy 372.874794 -245.798848) (xy 373.814848 -245.798848) (xy 373.840097 -245.799461)
			(xy 373.889906 -245.80778) (xy 373.937666 -245.824183) (xy 373.982075 -245.848222) (xy 374.021923 -245.879242)
			(xy 374.056121 -245.916398) (xy 374.083739 -245.958675) (xy 374.104022 -246.004921) (xy 374.116417 -246.053874)
			(xy 374.120587 -246.1042) (xy 374.116417 -246.154526) (xy 374.104022 -246.203479) (xy 374.083739 -246.249725)
			(xy 374.056121 -246.292002) (xy 374.021923 -246.329158) (xy 373.982075 -246.360178) (xy 373.937666 -246.384217)
			(xy 373.889906 -246.40062) (xy 373.840097 -246.408939) (xy 373.814848 -246.409464) (xy 372.874794 -246.409464)
			(xy 372.849535 -246.40903) (xy 372.799707 -246.400715) (xy 372.751927 -246.384311) (xy 372.707499 -246.360267)
			(xy 372.667634 -246.329238) (xy 372.63342 -246.292071) (xy 372.60579 -246.249779) (xy 372.585497 -246.203516)
			(xy 372.573096 -246.154545) (xy 372.568924 -246.1042) (xy 371.300687 -246.1042) (xy 371.296517 -246.154527)
			(xy 371.284121 -246.203481) (xy 371.263838 -246.249727) (xy 371.236219 -246.292005) (xy 371.202019 -246.329161)
			(xy 371.162171 -246.360181) (xy 371.11776 -246.38422) (xy 371.069999 -246.400622) (xy 371.02019 -246.408939)
			(xy 370.99494 -246.409464) (xy 370.054886 -246.409464) (xy 370.029628 -246.40903) (xy 369.979801 -246.400713)
			(xy 369.932022 -246.384308) (xy 369.887595 -246.360264) (xy 369.847731 -246.329235) (xy 369.813518 -246.292068)
			(xy 369.785888 -246.249777) (xy 369.765597 -246.203515) (xy 369.753196 -246.154544) (xy 369.749024 -246.1042)
			(xy 368.480616 -246.1042) (xy 368.476445 -246.154538) (xy 368.464045 -246.203503) (xy 368.443754 -246.249758)
			(xy 368.416126 -246.292043) (xy 368.381915 -246.329204) (xy 368.342054 -246.360227) (xy 368.29763 -246.384265)
			(xy 368.249855 -246.400663) (xy 368.200033 -246.408973) (xy 368.174778 -246.409464) (xy 367.234724 -246.409464)
			(xy 367.209461 -246.409061) (xy 367.159625 -246.400748) (xy 367.111836 -246.384346) (xy 367.067399 -246.360301)
			(xy 367.027526 -246.329269) (xy 366.993305 -246.292098) (xy 366.965669 -246.249801) (xy 366.945372 -246.203532)
			(xy 366.932969 -246.154553) (xy 366.928796 -246.1042) (xy 365.660716 -246.1042) (xy 365.656545 -246.154539)
			(xy 365.644144 -246.203504) (xy 365.623853 -246.249761) (xy 365.596224 -246.292046) (xy 365.562012 -246.329207)
			(xy 365.52215 -246.360229) (xy 365.477725 -246.384267) (xy 365.429949 -246.400664) (xy 365.380126 -246.408974)
			(xy 365.35487 -246.409464) (xy 364.414816 -246.409464) (xy 364.389554 -246.40906) (xy 364.339718 -246.400747)
			(xy 364.291931 -246.384343) (xy 364.247495 -246.360298) (xy 364.207623 -246.329267) (xy 364.173403 -246.292095)
			(xy 364.145768 -246.249799) (xy 364.125472 -246.20353) (xy 364.113068 -246.154552) (xy 364.108896 -246.1042)
			(xy 345.011755 -246.1042) (xy 345.011353 -246.127558) (xy 345.004755 -246.173893) (xy 344.991686 -246.218834)
			(xy 344.972406 -246.261482) (xy 344.960194 -246.281448) (xy 344.952574 -246.29364) (xy 344.952066 -246.321834)
			(xy 345.096592 -246.571008) (xy 345.12123 -246.58447) (xy 345.135708 -246.583708) (xy 345.151202 -246.583454)
			(xy 345.177192 -246.583964) (xy 345.228532 -246.592096) (xy 345.277968 -246.608159) (xy 345.324283 -246.631757)
			(xy 345.366335 -246.662311) (xy 345.403091 -246.699066) (xy 345.433644 -246.741119) (xy 345.457242 -246.787434)
			(xy 345.473305 -246.83687) (xy 345.481436 -246.88821) (xy 345.481436 -246.9142) (xy 361.758647 -246.9142)
			(xy 361.762823 -246.863808) (xy 361.775236 -246.814791) (xy 361.795548 -246.768485) (xy 361.823205 -246.726155)
			(xy 361.857452 -246.688953) (xy 361.897355 -246.657897) (xy 361.941825 -246.633831) (xy 361.989651 -246.617414)
			(xy 362.039526 -246.609093) (xy 362.064808 -246.6086) (xy 363.004862 -246.6086) (xy 363.03014 -246.609166)
			(xy 363.080006 -246.617481) (xy 363.127824 -246.633892) (xy 363.172288 -246.65795) (xy 363.212185 -246.688999)
			(xy 363.246428 -246.726191) (xy 363.274081 -246.768513) (xy 363.29439 -246.81481) (xy 363.306801 -246.863818)
			(xy 363.310977 -246.9142) (xy 363.306801 -246.964582) (xy 363.29439 -247.01359) (xy 363.274081 -247.059887)
			(xy 363.246428 -247.102209) (xy 363.212185 -247.139401) (xy 363.172288 -247.17045) (xy 363.127824 -247.194508)
			(xy 363.080006 -247.210919) (xy 363.03014 -247.219234) (xy 363.004862 -247.219724) (xy 362.064808 -247.219724)
			(xy 362.039526 -247.219307) (xy 361.989651 -247.210986) (xy 361.941825 -247.194569) (xy 361.897355 -247.170503)
			(xy 361.857452 -247.139447) (xy 361.823205 -247.102245) (xy 361.795548 -247.059915) (xy 361.775236 -247.013609)
			(xy 361.762823 -246.964592) (xy 361.758647 -246.9142) (xy 345.481436 -246.9142) (xy 345.481436 -246.94019)
			(xy 345.473305 -246.99153) (xy 345.457242 -247.040966) (xy 345.433644 -247.087281) (xy 345.403091 -247.129334)
			(xy 345.366335 -247.166089) (xy 345.324283 -247.196643) (xy 345.277968 -247.220241) (xy 345.228532 -247.236304)
			(xy 345.177192 -247.244436) (xy 345.151202 -247.24487) (xy 345.13393 -247.244362) (xy 345.119452 -247.2436)
			(xy 345.09456 -247.257062) (xy 344.950796 -247.504966) (xy 344.951558 -247.53316) (xy 344.959178 -247.545352)
			(xy 344.971621 -247.565443) (xy 344.991265 -247.608424) (xy 345.004589 -247.653764) (xy 345.011322 -247.700539)
			(xy 345.011756 -247.724168) (xy 345.011755 -247.7242) (xy 364.108908 -247.7242) (xy 364.11308 -247.67385)
			(xy 364.125483 -247.624874) (xy 364.145778 -247.578607) (xy 364.173412 -247.536312) (xy 364.207631 -247.499142)
			(xy 364.247501 -247.468112) (xy 364.291935 -247.444068) (xy 364.339721 -247.427665) (xy 364.389555 -247.419352)
			(xy 364.414816 -247.41886) (xy 365.35487 -247.41886) (xy 365.380127 -247.419414) (xy 365.429952 -247.427724)
			(xy 365.477729 -247.444122) (xy 365.522156 -247.468161) (xy 365.56202 -247.499184) (xy 365.596233 -247.536347)
			(xy 365.623863 -247.578634) (xy 365.644155 -247.624892) (xy 365.656556 -247.673859) (xy 365.660728 -247.7242)
			(xy 366.928808 -247.7242) (xy 366.93298 -247.673849) (xy 366.945384 -247.624872) (xy 366.96568 -247.578605)
			(xy 366.993314 -247.536309) (xy 367.027534 -247.499139) (xy 367.067406 -247.468109) (xy 367.111841 -247.444065)
			(xy 367.159628 -247.427663) (xy 367.209462 -247.419351) (xy 367.234724 -247.41886) (xy 368.174778 -247.41886)
			(xy 368.200034 -247.419415) (xy 368.249858 -247.427726) (xy 368.297635 -247.444124) (xy 368.34206 -247.468163)
			(xy 368.381923 -247.499187) (xy 368.416136 -247.536349) (xy 368.443764 -247.578636) (xy 368.464056 -247.624893)
			(xy 368.476457 -247.67386) (xy 368.480628 -247.7242) (xy 369.749037 -247.7242) (xy 369.753208 -247.673858)
			(xy 369.765609 -247.624889) (xy 369.785899 -247.578629) (xy 369.813527 -247.53634) (xy 369.847739 -247.499174)
			(xy 369.887601 -247.468147) (xy 369.932027 -247.444103) (xy 369.979804 -247.427699) (xy 370.029629 -247.419383)
			(xy 370.054886 -247.41886) (xy 370.99494 -247.41886) (xy 371.020191 -247.419449) (xy 371.070002 -247.427767)
			(xy 371.117765 -247.444169) (xy 371.162177 -247.468209) (xy 371.202028 -247.499231) (xy 371.236229 -247.536388)
			(xy 371.263848 -247.578667) (xy 371.284133 -247.624915) (xy 371.296529 -247.673871) (xy 371.300699 -247.7242)
			(xy 372.568937 -247.7242) (xy 372.573108 -247.673857) (xy 372.585509 -247.624888) (xy 372.605801 -247.578627)
			(xy 372.63343 -247.536337) (xy 372.667642 -247.499171) (xy 372.707506 -247.468144) (xy 372.751932 -247.444101)
			(xy 372.79971 -247.427698) (xy 372.849536 -247.419382) (xy 372.874794 -247.41886) (xy 373.814848 -247.41886)
			(xy 373.840098 -247.419449) (xy 373.889908 -247.427768) (xy 373.93767 -247.444172) (xy 373.982082 -247.468212)
			(xy 374.021931 -247.499233) (xy 374.056131 -247.53639) (xy 374.083749 -247.578669) (xy 374.104033 -247.624917)
			(xy 374.116429 -247.673872) (xy 374.120599 -247.7242) (xy 374.116429 -247.774528) (xy 374.104033 -247.823483)
			(xy 374.083749 -247.869731) (xy 374.056131 -247.91201) (xy 374.021931 -247.949166) (xy 373.982082 -247.980188)
			(xy 373.937671 -248.004228) (xy 373.889908 -248.020632) (xy 373.840098 -248.028951) (xy 373.814848 -248.029476)
			(xy 372.874794 -248.029476) (xy 372.849536 -248.029018) (xy 372.79971 -248.020702) (xy 372.751932 -248.004299)
			(xy 372.707506 -247.980256) (xy 372.667642 -247.949229) (xy 372.63343 -247.912063) (xy 372.605801 -247.869773)
			(xy 372.585509 -247.823512) (xy 372.573108 -247.774543) (xy 372.568937 -247.7242) (xy 371.300699 -247.7242)
			(xy 371.296529 -247.774529) (xy 371.284133 -247.823485) (xy 371.263848 -247.869733) (xy 371.236229 -247.912012)
			(xy 371.202028 -247.949169) (xy 371.162177 -247.980191) (xy 371.117765 -248.004231) (xy 371.070002 -248.020633)
			(xy 371.020191 -248.028951) (xy 370.99494 -248.029476) (xy 370.054886 -248.029476) (xy 370.029629 -248.029017)
			(xy 369.979804 -248.020701) (xy 369.932027 -248.004297) (xy 369.887601 -247.980253) (xy 369.847739 -247.949226)
			(xy 369.813527 -247.91206) (xy 369.785899 -247.869771) (xy 369.765609 -247.823511) (xy 369.753208 -247.774542)
			(xy 369.749037 -247.7242) (xy 368.480628 -247.7242) (xy 368.476457 -247.77454) (xy 368.464056 -247.823507)
			(xy 368.443764 -247.869764) (xy 368.416136 -247.912051) (xy 368.381923 -247.949213) (xy 368.34206 -247.980237)
			(xy 368.297635 -248.004276) (xy 368.249858 -248.020674) (xy 368.200034 -248.028985) (xy 368.174778 -248.029476)
			(xy 367.234724 -248.029476) (xy 367.209462 -248.029049) (xy 367.159628 -248.020737) (xy 367.111841 -248.004335)
			(xy 367.067406 -247.980291) (xy 367.027534 -247.949261) (xy 366.993314 -247.912091) (xy 366.96568 -247.869795)
			(xy 366.945384 -247.823528) (xy 366.93298 -247.774551) (xy 366.928808 -247.7242) (xy 365.660728 -247.7242)
			(xy 365.656556 -247.774541) (xy 365.644155 -247.823508) (xy 365.623863 -247.869766) (xy 365.596233 -247.912053)
			(xy 365.56202 -247.949216) (xy 365.522156 -247.980239) (xy 365.477729 -248.004278) (xy 365.429952 -248.020676)
			(xy 365.380127 -248.028986) (xy 365.35487 -248.029476) (xy 364.414816 -248.029476) (xy 364.389555 -248.029048)
			(xy 364.339721 -248.020735) (xy 364.291935 -248.004332) (xy 364.247501 -247.980288) (xy 364.207631 -247.949258)
			(xy 364.173412 -247.912088) (xy 364.145778 -247.869793) (xy 364.125483 -247.823526) (xy 364.11308 -247.77455)
			(xy 364.108908 -247.7242) (xy 345.011755 -247.7242) (xy 345.011249 -247.750158) (xy 345.003123 -247.801499)
			(xy 344.987065 -247.850937) (xy 344.963472 -247.897255) (xy 344.932923 -247.939311) (xy 344.896172 -247.976071)
			(xy 344.854123 -248.00663) (xy 344.807811 -248.030234) (xy 344.758377 -248.046304) (xy 344.707038 -248.054443)
			(xy 344.681048 -248.054876) (xy 344.66403 -248.054368) (xy 344.649552 -248.053606) (xy 344.62466 -248.067068)
			(xy 344.480896 -248.314972) (xy 344.481658 -248.343166) (xy 344.489532 -248.355358) (xy 344.501949 -248.375456)
			(xy 344.521536 -248.418445) (xy 344.534803 -248.463785) (xy 344.541477 -248.510553) (xy 344.541856 -248.534174)
			(xy 344.541602 -248.546366) (xy 344.541094 -248.56059) (xy 344.55481 -248.585228) (xy 345.404186 -249.073162)
			(xy 345.432126 -249.0724) (xy 345.444318 -249.06478) (xy 345.464237 -249.05263) (xy 345.506769 -249.03345)
			(xy 345.551579 -249.020451) (xy 345.597773 -249.013894) (xy 345.621102 -249.013472) (xy 345.644058 -249.013879)
			(xy 345.689525 -249.020257) (xy 345.733673 -249.032863) (xy 345.775653 -249.051454) (xy 345.795346 -249.063256)
			(xy 345.807284 -249.070622) (xy 345.835224 -249.07113) (xy 346.68714 -248.581672) (xy 346.700856 -248.557288)
			(xy 346.700348 -248.543318) (xy 346.700348 -248.534174) (xy 346.700858 -248.508187) (xy 346.708988 -248.456852)
			(xy 346.725049 -248.407422) (xy 346.748645 -248.361112) (xy 346.779195 -248.319064) (xy 346.815946 -248.282313)
			(xy 346.857994 -248.251763) (xy 346.904304 -248.228167) (xy 346.953734 -248.212106) (xy 347.005069 -248.203976)
			(xy 347.057043 -248.203976) (xy 347.108378 -248.212106) (xy 347.157808 -248.228167) (xy 347.204118 -248.251763)
			(xy 347.246166 -248.282313) (xy 347.282917 -248.319064) (xy 347.313467 -248.361112) (xy 347.337063 -248.407422)
			(xy 347.353124 -248.456852) (xy 347.361254 -248.508187) (xy 347.361764 -248.534174) (xy 347.361764 -248.5342)
			(xy 361.758659 -248.5342) (xy 361.762835 -248.48381) (xy 361.775248 -248.434795) (xy 361.795559 -248.388491)
			(xy 361.823214 -248.346162) (xy 361.85746 -248.308962) (xy 361.897361 -248.277907) (xy 361.94183 -248.253842)
			(xy 361.989653 -248.237426) (xy 362.039527 -248.229104) (xy 362.064808 -248.228612) (xy 363.004862 -248.228612)
			(xy 363.030141 -248.229154) (xy 363.080009 -248.23747) (xy 363.127829 -248.253881) (xy 363.172294 -248.27794)
			(xy 363.212193 -248.30899) (xy 363.246437 -248.346184) (xy 363.274091 -248.388507) (xy 363.294401 -248.434806)
			(xy 363.306813 -248.483816) (xy 363.310989 -248.5342) (xy 363.306813 -248.584584) (xy 363.294401 -248.633594)
			(xy 363.274091 -248.679893) (xy 363.246437 -248.722216) (xy 363.212193 -248.75941) (xy 363.172294 -248.79046)
			(xy 363.127829 -248.814519) (xy 363.080009 -248.83093) (xy 363.030141 -248.839246) (xy 363.004862 -248.839736)
			(xy 362.064808 -248.839736) (xy 362.039527 -248.839296) (xy 361.989653 -248.830974) (xy 361.94183 -248.814558)
			(xy 361.897361 -248.790493) (xy 361.85746 -248.759438) (xy 361.823214 -248.722238) (xy 361.795559 -248.679909)
			(xy 361.775248 -248.633605) (xy 361.762835 -248.58459) (xy 361.758659 -248.5342) (xy 347.361764 -248.5342)
			(xy 347.361359 -248.557575) (xy 347.35476 -248.60391) (xy 347.341688 -248.64885) (xy 347.322407 -248.691496)
			(xy 347.310202 -248.711466) (xy 347.302582 -248.723404) (xy 347.302074 -248.751852) (xy 347.4466 -249.001026)
			(xy 347.471492 -249.014488) (xy 347.485716 -249.013726) (xy 347.50121 -249.013472) (xy 347.527197 -249.013982)
			(xy 347.578532 -249.022114) (xy 347.627962 -249.038176) (xy 347.674272 -249.061772) (xy 347.71632 -249.092321)
			(xy 347.753072 -249.129072) (xy 347.783623 -249.17112) (xy 347.807221 -249.217429) (xy 347.823284 -249.266859)
			(xy 347.831417 -249.318193) (xy 347.831918 -249.34418) (xy 347.831513 -249.367581) (xy 347.824911 -249.413915)
			(xy 347.811838 -249.458853) (xy 347.792554 -249.501498) (xy 347.780356 -249.521472) (xy 347.772736 -249.533664)
			(xy 347.772228 -249.561858) (xy 347.916754 -249.811032) (xy 347.941392 -249.824494) (xy 347.95587 -249.823732)
			(xy 347.97111 -249.823478) (xy 347.997097 -249.823988) (xy 348.048431 -249.83212) (xy 348.097861 -249.848182)
			(xy 348.14417 -249.871778) (xy 348.186218 -249.902328) (xy 348.22297 -249.939079) (xy 348.25352 -249.981126)
			(xy 348.277117 -250.027435) (xy 348.293179 -250.076865) (xy 348.301311 -250.128199) (xy 348.301818 -250.154186)
			(xy 348.301564 -250.166378) (xy 348.301056 -250.180348) (xy 348.314772 -250.204986) (xy 349.164148 -250.69292)
			(xy 349.192088 -250.692412) (xy 349.20428 -250.684792) (xy 349.224198 -250.67264) (xy 349.26673 -250.653454)
			(xy 349.31154 -250.640449) (xy 349.357735 -250.633886) (xy 349.381064 -250.633484) (xy 349.407055 -250.633964)
			(xy 349.458399 -250.642091) (xy 349.507839 -250.65815) (xy 349.554157 -250.681746) (xy 349.596214 -250.712297)
			(xy 349.632974 -250.749052) (xy 349.663531 -250.791105) (xy 349.687133 -250.837421) (xy 349.703199 -250.886858)
			(xy 349.711332 -250.938201) (xy 349.711772 -250.964192) (xy 349.711366 -250.987593) (xy 349.704764 -251.033926)
			(xy 349.691691 -251.078865) (xy 349.672409 -251.12151) (xy 349.66021 -251.141484) (xy 349.65259 -251.153422)
			(xy 349.652082 -251.181616) (xy 349.796862 -251.431044) (xy 349.8215 -251.444506) (xy 349.835978 -251.443744)
			(xy 349.851218 -251.44349) (xy 349.874166 -251.443858) (xy 349.919626 -251.450165) (xy 349.963774 -251.462711)
			(xy 350.005757 -251.481253) (xy 350.025462 -251.49302) (xy 350.0374 -251.50064) (xy 350.06534 -251.500894)
			(xy 350.917256 -251.011436) (xy 350.930972 -250.987052) (xy 350.930464 -250.973082) (xy 350.930464 -250.964192)
			(xy 350.930974 -250.938205) (xy 350.939104 -250.88687) (xy 350.955165 -250.83744) (xy 350.978761 -250.79113)
			(xy 351.009311 -250.749082) (xy 351.046062 -250.712331) (xy 351.08811 -250.681781) (xy 351.13442 -250.658185)
			(xy 351.18385 -250.642124) (xy 351.235185 -250.633994) (xy 351.287159 -250.633994) (xy 351.338494 -250.642124)
			(xy 351.387924 -250.658185) (xy 351.434234 -250.681781) (xy 351.476282 -250.712331) (xy 351.513033 -250.749082)
			(xy 351.543583 -250.79113) (xy 351.567179 -250.83744) (xy 351.58324 -250.88687) (xy 351.59137 -250.938205)
			(xy 351.59188 -250.964192) (xy 351.591474 -250.987593) (xy 351.584872 -251.033927) (xy 351.5718 -251.078865)
			(xy 351.552518 -251.121511) (xy 351.540318 -251.141484) (xy 351.532698 -251.153676) (xy 351.53219 -251.18187)
			(xy 351.676716 -251.431044) (xy 351.701608 -251.444506) (xy 351.715832 -251.443744) (xy 351.731072 -251.44349)
			(xy 351.754026 -251.443902) (xy 351.799489 -251.450289) (xy 351.843632 -251.462903) (xy 351.885605 -251.481502)
			(xy 351.905316 -251.493274) (xy 351.917254 -251.50064) (xy 351.945194 -251.501148) (xy 352.79711 -251.01169)
			(xy 352.810826 -250.987306) (xy 352.810318 -250.973336) (xy 352.810318 -250.964192) (xy 352.810828 -250.938205)
			(xy 352.818958 -250.88687) (xy 352.835019 -250.83744) (xy 352.858615 -250.79113) (xy 352.889165 -250.749082)
			(xy 352.925916 -250.712331) (xy 352.967964 -250.681781) (xy 353.014274 -250.658185) (xy 353.063704 -250.642124)
			(xy 353.115039 -250.633994) (xy 353.167013 -250.633994) (xy 353.218348 -250.642124) (xy 353.267778 -250.658185)
			(xy 353.314088 -250.681781) (xy 353.356136 -250.712331) (xy 353.392887 -250.749082) (xy 353.423437 -250.79113)
			(xy 353.447033 -250.83744) (xy 353.463094 -250.88687) (xy 353.471224 -250.938205) (xy 353.471734 -250.964192)
			(xy 353.471328 -250.987593) (xy 353.464725 -251.033926) (xy 353.451651 -251.078864) (xy 353.432367 -251.121508)
			(xy 353.420172 -251.141484) (xy 353.412552 -251.153422) (xy 353.412044 -251.181616) (xy 353.556824 -251.431044)
			(xy 353.581462 -251.444506) (xy 353.59594 -251.443744) (xy 353.61118 -251.44349) (xy 353.634127 -251.443863)
			(xy 353.679584 -251.450177) (xy 353.723727 -251.46273) (xy 353.765705 -251.481278) (xy 353.785424 -251.49302)
			(xy 353.797362 -251.50064) (xy 353.825302 -251.500894) (xy 354.677218 -251.01169) (xy 354.690934 -250.987306)
			(xy 354.690426 -250.973082) (xy 354.690426 -250.964192) (xy 354.690936 -250.938205) (xy 354.699066 -250.88687)
			(xy 354.715127 -250.83744) (xy 354.738723 -250.79113) (xy 354.769273 -250.749082) (xy 354.806024 -250.712331)
			(xy 354.848072 -250.681781) (xy 354.894382 -250.658185) (xy 354.943812 -250.642124) (xy 354.995147 -250.633994)
			(xy 355.047121 -250.633994) (xy 355.098456 -250.642124) (xy 355.147886 -250.658185) (xy 355.194196 -250.681781)
			(xy 355.236244 -250.712331) (xy 355.272995 -250.749082) (xy 355.303545 -250.79113) (xy 355.327141 -250.83744)
			(xy 355.343202 -250.88687) (xy 355.351332 -250.938205) (xy 355.351842 -250.964192) (xy 355.351436 -250.987593)
			(xy 355.344834 -251.033926) (xy 355.33176 -251.078864) (xy 355.312476 -251.121508) (xy 355.30028 -251.141484)
			(xy 355.29266 -251.153422) (xy 355.292152 -251.181616) (xy 355.436932 -251.431044) (xy 355.46157 -251.444506)
			(xy 355.475794 -251.443744) (xy 355.491034 -251.44349) (xy 355.513989 -251.443899) (xy 355.559454 -251.450282)
			(xy 355.603599 -251.462892) (xy 355.645576 -251.481487) (xy 355.665278 -251.493274) (xy 355.67747 -251.50064)
			(xy 355.705156 -251.501148) (xy 356.557326 -251.01169) (xy 356.571042 -250.987306) (xy 356.570534 -250.973082)
			(xy 356.570534 -250.964192) (xy 356.571018 -250.938204) (xy 356.57915 -250.886869) (xy 356.595214 -250.837438)
			(xy 356.618813 -250.791129) (xy 356.649366 -250.749082) (xy 356.686121 -250.712333) (xy 356.728172 -250.681786)
			(xy 356.774485 -250.658195) (xy 356.823918 -250.642139) (xy 356.875254 -250.634014) (xy 356.901242 -250.633484)
			(xy 356.911148 -250.633738) (xy 356.925118 -250.633992) (xy 356.949502 -250.62053) (xy 357.096822 -250.366784)
			(xy 357.096568 -250.338844) (xy 357.089202 -250.326906) (xy 357.077655 -250.307326) (xy 357.059443 -250.265679)
			(xy 357.04709 -250.221935) (xy 357.040828 -250.176913) (xy 357.040434 -250.154186) (xy 357.040944 -250.128199)
			(xy 357.049074 -250.076864) (xy 357.065135 -250.027434) (xy 357.088731 -249.981124) (xy 357.119281 -249.939076)
			(xy 357.156032 -249.902325) (xy 357.19808 -249.871775) (xy 357.24439 -249.848179) (xy 357.29382 -249.832118)
			(xy 357.345155 -249.823988) (xy 357.397129 -249.823988) (xy 357.448464 -249.832118) (xy 357.497894 -249.848179)
			(xy 357.544204 -249.871775) (xy 357.586252 -249.902325) (xy 357.623003 -249.939076) (xy 357.653553 -249.981124)
			(xy 357.677149 -250.027434) (xy 357.69321 -250.076864) (xy 357.70134 -250.128199) (xy 357.70185 -250.154186)
			(xy 357.701596 -250.166124) (xy 357.701088 -250.180602) (xy 357.71455 -250.204986) (xy 358.800146 -250.828556)
			(xy 358.805965 -250.831674) (xy 358.818696 -250.835145) (xy 358.825292 -250.835414) (xy 361.272582 -250.835414)
			(xy 361.296458 -250.82119) (xy 361.303062 -250.80849) (xy 361.315521 -250.786186) (xy 361.346238 -250.745366)
			(xy 361.38286 -250.709747) (xy 361.424517 -250.680176) (xy 361.470222 -250.657352) (xy 361.518889 -250.641819)
			(xy 361.569365 -250.633944) (xy 361.594908 -250.633484) (xy 361.618266 -250.633891) (xy 361.664518 -250.640467)
			(xy 361.709388 -250.653473) (xy 361.751987 -250.672651) (xy 361.771946 -250.684792) (xy 361.783884 -250.692412)
			(xy 361.812078 -250.69292) (xy 362.661454 -250.204986) (xy 362.674916 -250.180602) (xy 362.674408 -250.166124)
			(xy 362.674154 -250.154186) (xy 362.674664 -250.128199) (xy 362.682794 -250.076864) (xy 362.698855 -250.027434)
			(xy 362.722451 -249.981124) (xy 362.753001 -249.939076) (xy 362.789752 -249.902325) (xy 362.8318 -249.871775)
			(xy 362.87811 -249.848179) (xy 362.92754 -249.832118) (xy 362.978875 -249.823988) (xy 363.030849 -249.823988)
			(xy 363.082184 -249.832118) (xy 363.131614 -249.848179) (xy 363.177924 -249.871775) (xy 363.219972 -249.902325)
			(xy 363.256723 -249.939076) (xy 363.287273 -249.981124) (xy 363.310869 -250.027434) (xy 363.32693 -250.076864)
			(xy 363.33506 -250.128199) (xy 363.33557 -250.154186) (xy 363.335197 -250.176916) (xy 363.328968 -250.221947)
			(xy 363.316613 -250.265696) (xy 363.298366 -250.307333) (xy 363.286802 -250.326906) (xy 363.279436 -250.338844)
			(xy 363.279182 -250.366784) (xy 363.426502 -250.62053) (xy 363.450886 -250.633992) (xy 363.464856 -250.633738)
			(xy 363.474762 -250.633484) (xy 363.500753 -250.633964) (xy 363.552097 -250.642091) (xy 363.601537 -250.65815)
			(xy 363.647856 -250.681745) (xy 363.689914 -250.712297) (xy 363.726674 -250.749051) (xy 363.757231 -250.791104)
			(xy 363.780833 -250.83742) (xy 363.796899 -250.886858) (xy 363.805032 -250.938201) (xy 363.80547 -250.964192)
			(xy 363.80547 -250.973082) (xy 363.804962 -250.987306) (xy 363.818678 -251.01169) (xy 364.670594 -251.500894)
			(xy 364.698534 -251.50064) (xy 364.710472 -251.49302) (xy 364.730192 -251.481285) (xy 364.77218 -251.46277)
			(xy 364.816321 -251.450227) (xy 364.861772 -251.443895) (xy 364.884716 -251.44349) (xy 364.899956 -251.443744)
			(xy 364.914434 -251.444506) (xy 364.939072 -251.431044) (xy 365.083852 -251.181616) (xy 365.083344 -251.153422)
			(xy 365.075724 -251.141484) (xy 365.063523 -251.121512) (xy 365.044254 -251.078863) (xy 365.031186 -251.033924)
			(xy 365.024579 -250.987592) (xy 365.024162 -250.964192) (xy 365.024672 -250.938204) (xy 365.032803 -250.886869)
			(xy 365.048865 -250.837438) (xy 365.072461 -250.791127) (xy 365.10301 -250.749078) (xy 365.139761 -250.712324)
			(xy 365.181808 -250.681772) (xy 365.228117 -250.658173) (xy 365.277548 -250.642109) (xy 365.328882 -250.633974)
			(xy 365.35487 -250.633484) (xy 365.378196 -250.633907) (xy 365.424381 -250.640502) (xy 365.469184 -250.653508)
			(xy 365.511721 -250.672669) (xy 365.531654 -250.684792) (xy 365.543846 -250.692412) (xy 365.571786 -250.69292)
			(xy 366.421416 -250.204986) (xy 366.434878 -250.180602) (xy 366.43437 -250.166124) (xy 366.434116 -250.154186)
			(xy 366.434626 -250.128199) (xy 366.442756 -250.076864) (xy 366.458817 -250.027434) (xy 366.482413 -249.981124)
			(xy 366.512963 -249.939076) (xy 366.549714 -249.902325) (xy 366.591762 -249.871775) (xy 366.638072 -249.848179)
			(xy 366.687502 -249.832118) (xy 366.738837 -249.823988) (xy 366.790811 -249.823988) (xy 366.842146 -249.832118)
			(xy 366.891576 -249.848179) (xy 366.937886 -249.871775) (xy 366.979934 -249.902325) (xy 367.016685 -249.939076)
			(xy 367.047235 -249.981124) (xy 367.070831 -250.027434) (xy 367.086892 -250.076864) (xy 367.095022 -250.128199)
			(xy 367.095532 -250.154186) (xy 367.095159 -250.176916) (xy 367.088931 -250.221948) (xy 367.076578 -250.265698)
			(xy 367.058334 -250.307337) (xy 367.046764 -250.326906) (xy 367.039398 -250.338844) (xy 367.039144 -250.366784)
			(xy 367.186464 -250.62053) (xy 367.210848 -250.633992) (xy 367.224818 -250.633738) (xy 367.234724 -250.633484)
			(xy 367.26071 -250.633995) (xy 367.312042 -250.642129) (xy 367.36147 -250.658192) (xy 367.407777 -250.681789)
			(xy 367.449822 -250.712339) (xy 367.486572 -250.74909) (xy 367.51712 -250.791137) (xy 367.540714 -250.837445)
			(xy 367.556775 -250.886873) (xy 367.564906 -250.938206) (xy 367.565432 -250.964192) (xy 367.565432 -250.973082)
			(xy 367.564924 -250.987306) (xy 367.57864 -251.01169) (xy 368.430556 -251.500894) (xy 368.458496 -251.50064)
			(xy 368.470434 -251.49302) (xy 368.490154 -251.481283) (xy 368.532141 -251.462763) (xy 368.576282 -251.450214)
			(xy 368.621733 -251.443878) (xy 368.644678 -251.44349) (xy 368.659918 -251.443744) (xy 368.674396 -251.444506)
			(xy 368.699034 -251.431044) (xy 368.843814 -251.181616) (xy 368.843306 -251.153422) (xy 368.835686 -251.141484)
			(xy 368.823483 -251.121513) (xy 368.80421 -251.078864) (xy 368.791139 -251.033925) (xy 368.784532 -250.987593)
			(xy 368.784124 -250.964192) (xy 368.784608 -250.938204) (xy 368.79274 -250.886868) (xy 368.808804 -250.837437)
			(xy 368.832402 -250.791127) (xy 368.862955 -250.749079) (xy 368.89971 -250.712329) (xy 368.941761 -250.681781)
			(xy 368.988074 -250.658188) (xy 369.037507 -250.642131) (xy 369.088844 -250.634005) (xy 369.114832 -250.633484)
			(xy 369.138159 -250.633905) (xy 369.184346 -250.640494) (xy 369.229152 -250.653496) (xy 369.271692 -250.672653)
			(xy 369.291616 -250.684792) (xy 369.303808 -250.692412) (xy 369.331748 -250.69292) (xy 370.181124 -250.20524)
			(xy 370.19484 -250.180348) (xy 370.194332 -250.166378) (xy 370.194078 -250.154186) (xy 370.194588 -250.128199)
			(xy 370.202718 -250.076864) (xy 370.218779 -250.027434) (xy 370.242375 -249.981124) (xy 370.272925 -249.939076)
			(xy 370.309676 -249.902325) (xy 370.351724 -249.871775) (xy 370.398034 -249.848179) (xy 370.447464 -249.832118)
			(xy 370.498799 -249.823988) (xy 370.550773 -249.823988) (xy 370.602108 -249.832118) (xy 370.651538 -249.848179)
			(xy 370.697848 -249.871775) (xy 370.739896 -249.902325) (xy 370.776647 -249.939076) (xy 370.807197 -249.981124)
			(xy 370.830793 -250.027434) (xy 370.846854 -250.076864) (xy 370.854984 -250.128199) (xy 370.855494 -250.154186)
			(xy 370.855121 -250.176916) (xy 370.848893 -250.221948) (xy 370.836538 -250.265697) (xy 370.818292 -250.307335)
			(xy 370.806726 -250.326906) (xy 370.799614 -250.338844) (xy 370.799106 -250.366784) (xy 370.946426 -250.62053)
			(xy 370.97081 -250.633992) (xy 370.98478 -250.633738) (xy 370.994686 -250.633484) (xy 371.020676 -250.633966)
			(xy 371.072017 -250.642096) (xy 371.121454 -250.658156) (xy 371.16777 -250.681753) (xy 371.209824 -250.712305)
			(xy 371.246581 -250.74906) (xy 371.277135 -250.791112) (xy 371.300735 -250.837426) (xy 371.316799 -250.886862)
			(xy 371.324932 -250.938202) (xy 371.325394 -250.964192) (xy 371.325394 -250.973082) (xy 371.324886 -250.987306)
			(xy 371.338602 -251.01169) (xy 372.190772 -251.501148)
		)
		(stroke
			(width 0)
			(type solid)
		)
		(fill yes)
		(layer "In8.Cu")
		(net "PVDDCR_CPU0_P0")
	)
	(gr_poly
		(pts
			(xy 162.954716 -127.702056) (xy 162.95751 -127.683006) (xy 162.961665 -127.655922) (xy 162.976729 -127.603241)
			(xy 162.999176 -127.553257) (xy 163.028545 -127.507) (xy 163.064231 -127.465421) (xy 163.105499 -127.429377)
			(xy 163.1515 -127.399609) (xy 163.201288 -127.376729) (xy 163.253837 -127.36121) (xy 163.308066 -127.353369)
			(xy 163.362858 -127.353369) (xy 163.417087 -127.36121) (xy 163.469636 -127.376729) (xy 163.519424 -127.399609)
			(xy 163.565425 -127.429377) (xy 163.606693 -127.465421) (xy 163.642379 -127.507) (xy 163.671748 -127.553257)
			(xy 163.694195 -127.603241) (xy 163.709259 -127.655922) (xy 163.713414 -127.683006) (xy 163.716208 -127.702056)
			(xy 163.744656 -127.726948) (xy 190.944754 -127.726948) (xy 190.951858 -127.726752) (xy 190.965525 -127.722884)
			(xy 190.971678 -127.719328) (xy 190.99448 -127.705591) (xy 191.043106 -127.683925) (xy 191.094276 -127.669243)
			(xy 191.146991 -127.66183) (xy 191.173608 -127.661416) (xy 191.200221 -127.661897) (xy 191.252926 -127.669324)
			(xy 191.304092 -127.68399) (xy 191.352728 -127.705612) (xy 191.375538 -127.719328) (xy 191.381701 -127.722862)
			(xy 191.395362 -127.72674) (xy 191.402462 -127.726948) (xy 203.152502 -127.726948) (xy 203.159232 -127.726772)
			(xy 203.17223 -127.723287) (xy 203.178156 -127.72009) (xy 203.20019 -127.70762) (xy 203.24685 -127.687967)
			(xy 203.2957 -127.674661) (xy 203.345881 -127.667936) (xy 203.371196 -127.667512) (xy 203.39651 -127.667944)
			(xy 203.446688 -127.674676) (xy 203.495536 -127.687983) (xy 203.542196 -127.707631) (xy 203.564236 -127.72009)
			(xy 203.570173 -127.723256) (xy 203.583165 -127.726729) (xy 203.58989 -127.726948) (xy 206.107792 -127.726948)
			(xy 206.11631 -127.726631) (xy 206.132409 -127.721059) (xy 206.139288 -127.716026) (xy 206.161813 -127.698976)
			(xy 206.210892 -127.671005) (xy 206.26356 -127.650577) (xy 206.318664 -127.638139) (xy 206.375 -127.633962)
			(xy 206.431336 -127.638139) (xy 206.48644 -127.650577) (xy 206.539108 -127.671005) (xy 206.588187 -127.698976)
			(xy 206.610712 -127.716026) (xy 206.617596 -127.72105) (xy 206.633691 -127.726622) (xy 206.642208 -127.726948)
			(xy 211.23529 -127.726948) (xy 211.243926 -127.726604) (xy 211.26021 -127.720847) (xy 211.273642 -127.709987)
			(xy 211.27847 -127.702818) (xy 211.29245 -127.680927) (xy 211.325751 -127.641068) (xy 211.36449 -127.60647)
			(xy 211.407845 -127.577867) (xy 211.454895 -127.555867) (xy 211.504642 -127.540935) (xy 211.55603 -127.533389)
			(xy 211.60797 -127.533389) (xy 211.659358 -127.540935) (xy 211.709105 -127.555867) (xy 211.756155 -127.577867)
			(xy 211.79951 -127.60647) (xy 211.838249 -127.641068) (xy 211.87155 -127.680927) (xy 211.88553 -127.702818)
			(xy 211.890364 -127.709975) (xy 211.903808 -127.7208) (xy 211.920081 -127.726553) (xy 211.92871 -127.726948)
			(xy 215.033098 -127.726948) (xy 215.058244 -127.710184) (xy 215.06434 -127.695706) (xy 215.07557 -127.669964)
			(xy 215.104481 -127.621817) (xy 215.140138 -127.578429) (xy 215.181772 -127.540738) (xy 215.228482 -127.509558)
			(xy 215.279258 -127.485564) (xy 215.333004 -127.469273) (xy 215.388558 -127.461039) (xy 215.444718 -127.461039)
			(xy 215.500272 -127.469273) (xy 215.554018 -127.485564) (xy 215.604794 -127.509558) (xy 215.651504 -127.540738)
			(xy 215.693138 -127.578429) (xy 215.728795 -127.621817) (xy 215.757706 -127.669964) (xy 215.768936 -127.695706)
			(xy 215.775032 -127.710184) (xy 215.800178 -127.726948) (xy 218.129612 -127.726948) (xy 218.156536 -127.707136)
			(xy 218.161362 -127.69088) (xy 218.169644 -127.665079) (xy 218.192483 -127.615941) (xy 218.222044 -127.570528)
			(xy 218.257734 -127.529755) (xy 218.298833 -127.494441) (xy 218.344516 -127.465298) (xy 218.393862 -127.442911)
			(xy 218.445879 -127.427732) (xy 218.499521 -127.420065) (xy 218.553707 -127.420065) (xy 218.607349 -127.427732)
			(xy 218.659366 -127.442911) (xy 218.708712 -127.465298) (xy 218.754395 -127.494441) (xy 218.795494 -127.529755)
			(xy 218.831184 -127.570528) (xy 218.860745 -127.615941) (xy 218.883584 -127.665079) (xy 218.891866 -127.69088)
			(xy 218.896692 -127.707136) (xy 218.923616 -127.726948) (xy 233.68127 -127.726948) (xy 233.7054 -127.712216)
			(xy 233.712004 -127.69977) (xy 233.724418 -127.67713) (xy 233.754782 -127.635369) (xy 233.79086 -127.598432)
			(xy 233.831894 -127.567094) (xy 233.877024 -127.54201) (xy 233.925304 -127.523708) (xy 233.975721 -127.51257)
			(xy 234.027218 -127.508832) (xy 234.078715 -127.51257) (xy 234.129132 -127.523708) (xy 234.177412 -127.54201)
			(xy 234.222542 -127.567094) (xy 234.263576 -127.598432) (xy 234.299654 -127.635369) (xy 234.330018 -127.67713)
			(xy 234.342432 -127.69977) (xy 234.349036 -127.712216) (xy 234.373166 -127.726948) (xy 234.44327 -127.726948)
			(xy 234.4674 -127.712216) (xy 234.474004 -127.69977) (xy 234.486418 -127.67713) (xy 234.516782 -127.635369)
			(xy 234.55286 -127.598432) (xy 234.593894 -127.567094) (xy 234.639024 -127.54201) (xy 234.687304 -127.523708)
			(xy 234.737721 -127.51257) (xy 234.789218 -127.508832) (xy 234.840715 -127.51257) (xy 234.891132 -127.523708)
			(xy 234.939412 -127.54201) (xy 234.984542 -127.567094) (xy 235.025576 -127.598432) (xy 235.061654 -127.635369)
			(xy 235.092018 -127.67713) (xy 235.104432 -127.69977) (xy 235.111036 -127.712216) (xy 235.135166 -127.726948)
			(xy 274.749006 -127.726948) (xy 274.759075 -127.726522) (xy 274.777673 -127.718801) (xy 274.785074 -127.711962)
			(xy 278.118316 -124.37872) (xy 278.125936 -124.35713) (xy 278.124666 -124.3457) (xy 278.123688 -124.335633)
			(xy 278.12267 -124.315429) (xy 278.122634 -124.305314) (xy 278.123096 -124.278062) (xy 278.130852 -124.224111)
			(xy 278.146207 -124.171814) (xy 278.16885 -124.122235) (xy 278.198318 -124.076383) (xy 278.234012 -124.035192)
			(xy 278.275206 -123.999501) (xy 278.32106 -123.970036) (xy 278.370641 -123.947397) (xy 278.422939 -123.932046)
			(xy 278.47689 -123.924294) (xy 278.504142 -123.923806) (xy 278.514257 -123.923846) (xy 278.53446 -123.924865)
			(xy 278.544528 -123.925838) (xy 278.555958 -123.927108) (xy 278.577548 -123.919488) (xy 303.84369 -98.653346)
			(xy 303.861733 -98.63609) (xy 303.903228 -98.608342) (xy 303.949346 -98.589238) (xy 303.998308 -98.579515)
			(xy 304.023268 -98.578924) (xy 319.785746 -98.578924) (xy 319.795906 -98.574352) (xy 319.820753 -98.563603)
			(xy 319.872724 -98.548441) (xy 319.926317 -98.540783) (xy 319.980455 -98.540783) (xy 320.034048 -98.548441)
			(xy 320.086019 -98.563603) (xy 320.110866 -98.574352) (xy 320.121026 -98.578924) (xy 328.96683 -98.578924)
			(xy 328.972672 -98.5774) (xy 328.994631 -98.57249) (xy 329.039326 -98.567268) (xy 329.061826 -98.566986)
			(xy 329.084325 -98.567287) (xy 329.129017 -98.57251) (xy 329.15098 -98.5774) (xy 329.156822 -98.578924)
			(xy 329.725782 -98.578924) (xy 329.732823 -98.578705) (xy 329.746365 -98.574848) (xy 329.752452 -98.571304)
			(xy 329.775114 -98.557855) (xy 329.823353 -98.536646) (xy 329.874057 -98.522292) (xy 329.926256 -98.515067)
			(xy 329.952604 -98.514662) (xy 329.978949 -98.51511) (xy 330.031137 -98.522359) (xy 330.081836 -98.536706)
			(xy 330.130085 -98.557878) (xy 330.152756 -98.571304) (xy 330.158871 -98.574785) (xy 330.172395 -98.57865)
			(xy 330.179426 -98.578924) (xy 330.538582 -98.578924) (xy 330.545623 -98.578705) (xy 330.559165 -98.574848)
			(xy 330.565252 -98.571304) (xy 330.587914 -98.557855) (xy 330.636153 -98.536646) (xy 330.686857 -98.522292)
			(xy 330.739056 -98.515067) (xy 330.765404 -98.514662) (xy 330.791749 -98.51511) (xy 330.843937 -98.522359)
			(xy 330.894636 -98.536706) (xy 330.942885 -98.557878) (xy 330.965556 -98.571304) (xy 330.971671 -98.574785)
			(xy 330.985195 -98.57865) (xy 330.992226 -98.578924) (xy 331.351382 -98.578924) (xy 331.358423 -98.578705)
			(xy 331.371965 -98.574848) (xy 331.378052 -98.571304) (xy 331.400714 -98.557855) (xy 331.448953 -98.536646)
			(xy 331.499657 -98.522292) (xy 331.551856 -98.515067) (xy 331.578204 -98.514662) (xy 331.604549 -98.51511)
			(xy 331.656737 -98.522359) (xy 331.707436 -98.536706) (xy 331.755685 -98.557878) (xy 331.778356 -98.571304)
			(xy 331.784471 -98.574785) (xy 331.797995 -98.57865) (xy 331.805026 -98.578924) (xy 434.876194 -98.578924)
			(xy 434.904642 -98.554286) (xy 434.907436 -98.53549) (xy 434.911845 -98.50864) (xy 434.927278 -98.456465)
			(xy 434.949968 -98.407012) (xy 434.979454 -98.361285) (xy 435.015139 -98.320212) (xy 435.056299 -98.284627)
			(xy 435.102097 -98.255251) (xy 435.151605 -98.232681) (xy 435.203817 -98.217375) (xy 435.257675 -98.209644)
			(xy 435.312085 -98.209644) (xy 435.365943 -98.217375) (xy 435.418155 -98.232681) (xy 435.467663 -98.255251)
			(xy 435.513461 -98.284627) (xy 435.554621 -98.320212) (xy 435.590306 -98.361285) (xy 435.619792 -98.407012)
			(xy 435.642482 -98.456465) (xy 435.657915 -98.50864) (xy 435.662324 -98.53549) (xy 435.665118 -98.554286)
			(xy 435.693566 -98.578924) (xy 435.765194 -98.578924) (xy 435.793642 -98.554286) (xy 435.796436 -98.53549)
			(xy 435.800845 -98.50864) (xy 435.816278 -98.456465) (xy 435.838968 -98.407012) (xy 435.868454 -98.361285)
			(xy 435.904139 -98.320212) (xy 435.945299 -98.284627) (xy 435.991097 -98.255251) (xy 436.040605 -98.232681)
			(xy 436.092817 -98.217375) (xy 436.146675 -98.209644) (xy 436.201085 -98.209644) (xy 436.254943 -98.217375)
			(xy 436.307155 -98.232681) (xy 436.356663 -98.255251) (xy 436.402461 -98.284627) (xy 436.443621 -98.320212)
			(xy 436.479306 -98.361285) (xy 436.508792 -98.407012) (xy 436.531482 -98.456465) (xy 436.546915 -98.50864)
			(xy 436.551324 -98.53549) (xy 436.554118 -98.554286) (xy 436.582566 -98.578924) (xy 449.123816 -98.578924)
			(xy 449.133885 -98.578499) (xy 449.152488 -98.570783) (xy 449.159884 -98.563938) (xy 452.022972 -95.70085)
			(xy 452.029813 -95.69345) (xy 452.037534 -95.674852) (xy 452.037958 -95.664782) (xy 452.037958 -74.851768)
			(xy 452.038532 -74.826809) (xy 452.048279 -74.777852) (xy 452.06739 -74.731738) (xy 452.095132 -74.690239)
			(xy 452.11238 -74.67219) (xy 453.087486 -73.697084) (xy 453.105528 -73.679826) (xy 453.147022 -73.652073)
			(xy 453.19314 -73.632965) (xy 453.242104 -73.62324) (xy 453.267064 -73.622662) (xy 457.412344 -73.622662)
			(xy 457.42241 -73.62223) (xy 457.440999 -73.6145) (xy 457.448412 -73.607676) (xy 459.405228 -71.65086)
			(xy 459.412076 -71.643463) (xy 459.419807 -71.624864) (xy 459.420214 -71.614792) (xy 459.420214 -63.811404)
			(xy 459.419792 -63.801333) (xy 459.41208 -63.782726) (xy 459.405228 -63.775336) (xy 457.727558 -62.097666)
			(xy 457.72016 -62.090819) (xy 457.701561 -62.083089) (xy 457.69149 -62.08268) (xy 449.739258 -62.08268)
			(xy 449.714299 -62.082105) (xy 449.665342 -62.072358) (xy 449.619228 -62.053248) (xy 449.577727 -62.025508)
			(xy 449.55968 -62.008258) (xy 442.522356 -54.970934) (xy 442.514957 -54.964091) (xy 442.496358 -54.956367)
			(xy 442.486288 -54.955948) (xy 422.782746 -54.955948) (xy 422.772024 -54.95637) (xy 422.752427 -54.965062)
			(xy 422.7449 -54.972712) (xy 422.726373 -54.992456) (xy 422.684407 -55.026663) (xy 422.637746 -55.054123)
			(xy 422.587466 -55.074201) (xy 422.534725 -55.086437) (xy 422.48074 -55.090547) (xy 422.426755 -55.086437)
			(xy 422.374014 -55.074201) (xy 422.323734 -55.054123) (xy 422.277073 -55.026663) (xy 422.235107 -54.992456)
			(xy 422.21658 -54.972712) (xy 422.20898 -54.965172) (xy 422.189425 -54.956522) (xy 422.178734 -54.955948)
			(xy 271.882108 -54.955948) (xy 271.876526 -54.956094) (xy 271.865631 -54.95853) (xy 271.860518 -54.960774)
			(xy 271.831548 -54.973762) (xy 271.771125 -54.993252) (xy 271.708745 -55.005069) (xy 271.64538 -55.009028)
			(xy 271.582015 -55.005069) (xy 271.519635 -54.993252) (xy 271.459212 -54.973762) (xy 271.430242 -54.960774)
			(xy 271.425128 -54.958534) (xy 271.414233 -54.9561) (xy 271.408652 -54.955948) (xy 270.06042 -54.955948)
			(xy 270.050006 -54.960774) (xy 269.97693 -54.9949) (xy 269.827974 -55.056784) (xy 269.676152 -55.111262)
			(xy 269.521834 -55.158203) (xy 269.365393 -55.197494) (xy 269.207207 -55.229037) (xy 269.047661 -55.252759)
			(xy 268.887141 -55.2686) (xy 268.726036 -55.276522) (xy 268.645386 -55.277004) (xy 268.564737 -55.276511)
			(xy 268.403634 -55.268572) (xy 268.243117 -55.25272) (xy 268.083573 -55.228992) (xy 267.92539 -55.197446)
			(xy 267.76895 -55.158158) (xy 267.614631 -55.111224) (xy 267.462807 -55.056757) (xy 267.313846 -54.994889)
			(xy 267.240766 -54.960774) (xy 267.230352 -54.955948) (xy 265.88212 -54.955948) (xy 265.876538 -54.956093)
			(xy 265.865642 -54.958527) (xy 265.86053 -54.960774) (xy 265.83156 -54.973762) (xy 265.771137 -54.993252)
			(xy 265.708757 -55.005069) (xy 265.645392 -55.009028) (xy 265.582027 -55.005069) (xy 265.519647 -54.993252)
			(xy 265.459224 -54.973762) (xy 265.430254 -54.960774) (xy 265.42514 -54.958533) (xy 265.414246 -54.956096)
			(xy 265.408664 -54.955948) (xy 257.139694 -54.955948) (xy 257.133683 -54.956109) (xy 257.121994 -54.958921)
			(xy 257.11658 -54.961536) (xy 257.08441 -54.977442) (xy 257.017665 -55.003829) (xy 256.948734 -55.023819)
			(xy 256.878228 -55.037236) (xy 256.806772 -55.043959) (xy 256.770886 -55.04434) (xy 256.735003 -55.043924)
			(xy 256.663553 -55.037179) (xy 256.593053 -55.023757) (xy 256.524122 -55.003779) (xy 256.457371 -54.977419)
			(xy 256.425192 -54.961536) (xy 256.419766 -54.958947) (xy 256.408087 -54.956114) (xy 256.402078 -54.955948)
			(xy 255.575816 -54.955948) (xy 255.56718 -54.95925) (xy 255.534752 -54.970596) (xy 255.467161 -54.98286)
			(xy 255.432814 -54.983634) (xy 255.398461 -54.982927) (xy 255.330861 -54.970655) (xy 255.298448 -54.95925)
			(xy 255.289812 -54.955948) (xy 254.342138 -54.955948) (xy 254.330962 -54.958488) (xy 254.325628 -54.961282)
			(xy 254.296918 -54.97489) (xy 254.236145 -54.993403) (xy 254.204724 -54.998112) (xy 254.196342 -54.999382)
			(xy 254.18161 -55.006494) (xy 253.417578 -55.770526) (xy 253.399538 -55.787788) (xy 253.358045 -55.815551)
			(xy 253.311927 -55.83467) (xy 253.262962 -55.844407) (xy 253.238 -55.844948) (xy 249.699272 -55.844948)
			(xy 249.686721 -55.845598) (xy 249.664603 -55.857465) (xy 249.657108 -55.867554) (xy 249.634801 -55.900043)
			(xy 249.584484 -55.960705) (xy 249.528179 -56.015853) (xy 249.466485 -56.064899) (xy 249.400061 -56.10732)
			(xy 249.329616 -56.142663) (xy 249.2559 -56.17055) (xy 249.179702 -56.190685) (xy 249.101833 -56.202853)
			(xy 249.023124 -56.206923) (xy 248.944415 -56.202853) (xy 248.866546 -56.190685) (xy 248.790348 -56.17055)
			(xy 248.716632 -56.142663) (xy 248.646187 -56.10732) (xy 248.579763 -56.064899) (xy 248.518069 -56.015853)
			(xy 248.461764 -55.960705) (xy 248.411447 -55.900043) (xy 248.38914 -55.867554) (xy 248.381626 -55.857486)
			(xy 248.359519 -55.845613) (xy 248.346976 -55.844948) (xy 247.08104 -55.844948) (xy 247.054116 -55.865268)
			(xy 247.04929 -55.881524) (xy 247.041247 -55.907662) (xy 247.018716 -55.957491) (xy 246.989302 -56.003593)
			(xy 246.953606 -56.045022) (xy 246.91236 -56.08093) (xy 246.866409 -56.11058) (xy 246.816696 -56.133366)
			(xy 246.764238 -56.148819) (xy 246.710111 -56.156623) (xy 246.682768 -56.157114) (xy 246.655399 -56.15664)
			(xy 246.601222 -56.148812) (xy 246.548721 -56.133322) (xy 246.498973 -56.110488) (xy 246.452998 -56.080778)
			(xy 246.43207 -56.063134) (xy 246.424958 -56.057038) (xy 246.40794 -56.050688) (xy 246.322596 -56.050688)
			(xy 246.305578 -56.057038) (xy 246.298466 -56.063134) (xy 246.277533 -56.080773) (xy 246.231565 -56.110492)
			(xy 246.181818 -56.133329) (xy 246.129315 -56.148813) (xy 246.075137 -56.156626) (xy 246.047768 -56.157114)
			(xy 246.020426 -56.156642) (xy 245.966302 -56.14883) (xy 245.913848 -56.13337) (xy 245.864139 -56.110579)
			(xy 245.818193 -56.080925) (xy 245.776952 -56.045014) (xy 245.741261 -56.003583) (xy 245.711851 -55.95748)
			(xy 245.689324 -55.907651) (xy 245.681246 -55.881524) (xy 245.67642 -55.865268) (xy 245.649496 -55.844948)
			(xy 202.819 -55.844948) (xy 202.79404 -55.844377) (xy 202.745079 -55.834636) (xy 202.698961 -55.815529)
			(xy 202.657457 -55.78779) (xy 202.639422 -55.770526) (xy 201.851768 -54.982872) (xy 201.823828 -54.976522)
			(xy 201.809858 -54.981094) (xy 201.783299 -54.989792) (xy 201.72876 -55.001995) (xy 201.67321 -55.008132)
			(xy 201.645266 -55.008526) (xy 201.614536 -55.00806) (xy 201.553524 -55.000648) (xy 201.493851 -54.985937)
			(xy 201.436386 -54.96414) (xy 201.381966 -54.935576) (xy 201.331386 -54.900662) (xy 201.285384 -54.859905)
			(xy 201.244629 -54.813901) (xy 201.209715 -54.76332) (xy 201.181153 -54.7089) (xy 201.159359 -54.651434)
			(xy 201.144649 -54.59176) (xy 201.137239 -54.530748) (xy 201.136758 -54.500018) (xy 201.137158 -54.472075)
			(xy 201.143315 -54.416529) (xy 201.155514 -54.361991) (xy 201.16419 -54.335426) (xy 201.168762 -54.321456)
			(xy 201.162412 -54.293516) (xy 194.559682 -47.690786) (xy 194.524884 -47.686722) (xy 194.509644 -47.69612)
			(xy 194.487025 -47.709495) (xy 194.438895 -47.730585) (xy 194.388326 -47.744867) (xy 194.336274 -47.752069)
			(xy 194.31 -47.752508) (xy 194.282749 -47.752022) (xy 194.228801 -47.744266) (xy 194.176506 -47.728911)
			(xy 194.126929 -47.706269) (xy 194.081079 -47.676803) (xy 194.039888 -47.641112) (xy 194.004197 -47.599921)
			(xy 193.974731 -47.554071) (xy 193.952089 -47.504494) (xy 193.936734 -47.452199) (xy 193.928978 -47.398251)
			(xy 193.928492 -47.371) (xy 193.92893 -47.344726) (xy 193.936138 -47.292675) (xy 193.950418 -47.242105)
			(xy 193.9715 -47.193972) (xy 193.98488 -47.171356) (xy 193.994278 -47.156116) (xy 193.990214 -47.121318)
			(xy 181.833774 -34.964878) (xy 181.828694 -34.96183) (xy 181.798524 -34.942783) (xy 181.741507 -34.899881)
			(xy 181.688748 -34.85184) (xy 181.640708 -34.79908) (xy 181.597808 -34.742063) (xy 181.578758 -34.711894)
			(xy 181.57571 -34.706814) (xy 179.138326 -32.26943) (xy 179.112164 -32.262572) (xy 179.098702 -32.266382)
			(xy 179.073556 -32.272933) (xy 179.022068 -32.279948) (xy 178.996086 -32.280352) (xy 178.968834 -32.279865)
			(xy 178.914886 -32.272107) (xy 178.86259 -32.256752) (xy 178.813012 -32.23411) (xy 178.76716 -32.204644)
			(xy 178.725968 -32.168953) (xy 178.690274 -32.127764) (xy 178.660804 -32.081914) (xy 178.638159 -32.032338)
			(xy 178.622799 -31.980044) (xy 178.615037 -31.926096) (xy 178.614578 -31.898844) (xy 178.615003 -31.872863)
			(xy 178.622018 -31.821378) (xy 178.628548 -31.796228) (xy 178.632358 -31.782766) (xy 178.6255 -31.756604)
			(xy 177.07483 -30.205934) (xy 177.067429 -30.199095) (xy 177.048831 -30.191381) (xy 177.038762 -30.190948)
			(xy 172.456856 -30.190948) (xy 172.431964 -30.207204) (xy 172.425614 -30.22092) (xy 172.414033 -30.245697)
			(xy 172.384405 -30.291665) (xy 172.348093 -30.33256) (xy 172.305952 -30.367419) (xy 172.258975 -30.395421)
			(xy 172.208267 -30.415907) (xy 172.155022 -30.428394) (xy 172.100494 -30.43259) (xy 172.045966 -30.428394)
			(xy 171.992721 -30.415907) (xy 171.942013 -30.395421) (xy 171.895036 -30.367419) (xy 171.852895 -30.33256)
			(xy 171.816583 -30.291665) (xy 171.786955 -30.245697) (xy 171.775374 -30.22092) (xy 171.769024 -30.207204)
			(xy 171.744132 -30.190948) (xy 145.371566 -30.190948) (xy 145.347182 -30.206188) (xy 145.340578 -30.219396)
			(xy 145.327453 -30.244847) (xy 145.294738 -30.291845) (xy 145.255374 -30.333433) (xy 145.233136 -30.351476)
			(xy 145.223738 -30.358842) (xy 145.213578 -30.37967) (xy 145.213578 -30.483556) (xy 145.223738 -30.504384)
			(xy 145.233136 -30.51175) (xy 145.255594 -30.529956) (xy 145.295279 -30.571994) (xy 145.328169 -30.619536)
			(xy 145.353514 -30.671495) (xy 145.370732 -30.726682) (xy 145.37943 -30.783834) (xy 145.379948 -30.81274)
			(xy 145.379948 -31.67634) (xy 145.379462 -31.703591) (xy 145.371706 -31.757539) (xy 145.356351 -31.809834)
			(xy 145.333709 -31.859411) (xy 145.304243 -31.905261) (xy 145.268552 -31.946452) (xy 145.227361 -31.982143)
			(xy 145.181511 -32.011609) (xy 145.131934 -32.034251) (xy 145.079639 -32.049606) (xy 145.025691 -32.057362)
			(xy 144.971189 -32.057362) (xy 144.917241 -32.049606) (xy 144.864946 -32.034251) (xy 144.815369 -32.011609)
			(xy 144.769519 -31.982143) (xy 144.728328 -31.946452) (xy 144.692637 -31.905261) (xy 144.663171 -31.859411)
			(xy 144.640529 -31.809834) (xy 144.625174 -31.757539) (xy 144.617418 -31.703591) (xy 144.616932 -31.67634)
			(xy 144.616932 -30.81274) (xy 144.617448 -30.783834) (xy 144.626138 -30.72668) (xy 144.643354 -30.671493)
			(xy 144.668702 -30.619536) (xy 144.701602 -30.572) (xy 144.7413 -30.529974) (xy 144.763744 -30.51175)
			(xy 144.773142 -30.504384) (xy 144.783302 -30.483556) (xy 144.783302 -30.37967) (xy 144.773142 -30.358842)
			(xy 144.763744 -30.351476) (xy 144.741481 -30.33346) (xy 144.702103 -30.291877) (xy 144.669393 -30.244868)
			(xy 144.656302 -30.219396) (xy 144.649698 -30.206188) (xy 144.625314 -30.190948) (xy 141.066266 -30.190948)
			(xy 141.038326 -30.214062) (xy 141.03477 -30.232096) (xy 141.029627 -30.256703) (xy 141.013719 -30.304391)
			(xy 140.991673 -30.349571) (xy 140.963873 -30.391456) (xy 140.947648 -30.410658) (xy 140.941552 -30.41777)
			(xy 140.935202 -30.434534) (xy 140.935202 -30.520132) (xy 140.941552 -30.53715) (xy 140.947648 -30.544008)
			(xy 140.96529 -30.564968) (xy 140.995011 -30.610991) (xy 141.017848 -30.660789) (xy 141.03333 -30.713342)
			(xy 141.04114 -30.767567) (xy 141.041628 -30.79496) (xy 141.041628 -31.65856) (xy 141.041142 -31.685811)
			(xy 141.033386 -31.739759) (xy 141.018031 -31.792054) (xy 140.995389 -31.841631) (xy 140.965923 -31.887481)
			(xy 140.930232 -31.928672) (xy 140.889041 -31.964363) (xy 140.843191 -31.993829) (xy 140.793614 -32.016471)
			(xy 140.741319 -32.031826) (xy 140.687371 -32.039582) (xy 140.632869 -32.039582) (xy 140.578921 -32.031826)
			(xy 140.526626 -32.016471) (xy 140.477049 -31.993829) (xy 140.431199 -31.964363) (xy 140.390008 -31.928672)
			(xy 140.354317 -31.887481) (xy 140.324851 -31.841631) (xy 140.302209 -31.792054) (xy 140.286854 -31.739759)
			(xy 140.279098 -31.685811) (xy 140.278612 -31.65856) (xy 140.278612 -30.79496) (xy 140.279068 -30.767566)
			(xy 140.286874 -30.713338) (xy 140.302364 -30.660785) (xy 140.325218 -30.610992) (xy 140.354966 -30.564984)
			(xy 140.372592 -30.544008) (xy 140.378688 -30.53715) (xy 140.385038 -30.520132) (xy 140.385038 -30.434534)
			(xy 140.378688 -30.41777) (xy 140.372592 -30.410658) (xy 140.35638 -30.391448) (xy 140.328606 -30.34955)
			(xy 140.306564 -30.304373) (xy 140.290632 -30.256697) (xy 140.28547 -30.232096) (xy 140.281914 -30.214062)
			(xy 140.253974 -30.190948) (xy 136.16686 -30.190948) (xy 136.159588 -30.191172) (xy 136.145642 -30.195293)
			(xy 136.139428 -30.199076) (xy 136.116233 -30.213377) (xy 136.066651 -30.235976) (xy 136.014362 -30.251301)
			(xy 135.960425 -30.25904) (xy 135.93318 -30.259528) (xy 135.90593 -30.25909) (xy 135.85198 -30.251377)
			(xy 135.799679 -30.236054) (xy 135.750096 -30.213434) (xy 135.726932 -30.199076) (xy 135.720683 -30.19537)
			(xy 135.706759 -30.191241) (xy 135.6995 -30.190948) (xy 69.056758 -30.190948) (xy 69.031104 -30.20822)
			(xy 69.025262 -30.222444) (xy 69.014087 -30.248301) (xy 68.985241 -30.296684) (xy 68.949594 -30.340298)
			(xy 68.90792 -30.378196) (xy 68.861126 -30.409553) (xy 68.810229 -30.433688) (xy 68.756337 -30.450075)
			(xy 68.70062 -30.458359) (xy 68.644292 -30.458359) (xy 68.588575 -30.450075) (xy 68.534683 -30.433688)
			(xy 68.483786 -30.409553) (xy 68.436992 -30.378196) (xy 68.395318 -30.340298) (xy 68.359671 -30.296684)
			(xy 68.330825 -30.248301) (xy 68.31965 -30.222444) (xy 68.313808 -30.20822) (xy 68.288154 -30.190948)
			(xy 66.421 -30.190948) (xy 66.39604 -30.190377) (xy 66.347079 -30.180636) (xy 66.300961 -30.161529)
			(xy 66.259457 -30.13379) (xy 66.241422 -30.116526) (xy 64.04483 -27.919934) (xy 64.037429 -27.913095)
			(xy 64.018831 -27.905381) (xy 64.008762 -27.904948) (xy 60.070238 -27.904948) (xy 60.060174 -27.905384)
			(xy 60.04159 -27.913119) (xy 60.03417 -27.919934) (xy 57.672986 -30.281118) (xy 57.666133 -30.288513)
			(xy 57.658392 -30.307112) (xy 57.658 -30.317186) (xy 57.658 -32.94761) (xy 102.642416 -32.94761)
			(xy 102.642416 -31.95701) (xy 102.642902 -31.929759) (xy 102.650658 -31.875811) (xy 102.666013 -31.823516)
			(xy 102.688655 -31.773939) (xy 102.718121 -31.728089) (xy 102.753812 -31.686898) (xy 102.795003 -31.651207)
			(xy 102.840853 -31.621741) (xy 102.89043 -31.599099) (xy 102.942725 -31.583744) (xy 102.996673 -31.575988)
			(xy 103.051175 -31.575988) (xy 103.105123 -31.583744) (xy 103.157418 -31.599099) (xy 103.206995 -31.621741)
			(xy 103.252845 -31.651207) (xy 103.294036 -31.686898) (xy 103.329727 -31.728089) (xy 103.359193 -31.773939)
			(xy 103.381835 -31.823516) (xy 103.39719 -31.875811) (xy 103.404946 -31.929759) (xy 103.405432 -31.95701)
			(xy 103.405432 -32.405066) (xy 105.659936 -32.405066) (xy 105.659936 -31.541466) (xy 105.660422 -31.514215)
			(xy 105.668178 -31.460267) (xy 105.683533 -31.407972) (xy 105.706175 -31.358395) (xy 105.735641 -31.312545)
			(xy 105.771332 -31.271354) (xy 105.812523 -31.235663) (xy 105.858373 -31.206197) (xy 105.90795 -31.183555)
			(xy 105.960245 -31.1682) (xy 106.014193 -31.160444) (xy 106.068695 -31.160444) (xy 106.122643 -31.1682)
			(xy 106.174938 -31.183555) (xy 106.224515 -31.206197) (xy 106.270365 -31.235663) (xy 106.311556 -31.271354)
			(xy 106.347247 -31.312545) (xy 106.376713 -31.358395) (xy 106.399355 -31.407972) (xy 106.41471 -31.460267)
			(xy 106.422466 -31.514215) (xy 106.422952 -31.541466) (xy 106.422952 -32.405066) (xy 106.422466 -32.432317)
			(xy 106.41471 -32.486265) (xy 106.399355 -32.53856) (xy 106.376713 -32.588137) (xy 106.347247 -32.633987)
			(xy 106.311556 -32.675178) (xy 106.270365 -32.710869) (xy 106.224515 -32.740335) (xy 106.174938 -32.762977)
			(xy 106.122643 -32.778332) (xy 106.068695 -32.786088) (xy 106.014193 -32.786088) (xy 105.960245 -32.778332)
			(xy 105.90795 -32.762977) (xy 105.858373 -32.740335) (xy 105.812523 -32.710869) (xy 105.771332 -32.675178)
			(xy 105.735641 -32.633987) (xy 105.706175 -32.588137) (xy 105.683533 -32.53856) (xy 105.668178 -32.486265)
			(xy 105.660422 -32.432317) (xy 105.659936 -32.405066) (xy 103.405432 -32.405066) (xy 103.405432 -32.94761)
			(xy 103.404946 -32.974861) (xy 103.39719 -33.028809) (xy 103.390276 -33.052356) (xy 119.734235 -33.052356)
			(xy 119.734235 -32.997844) (xy 119.741993 -32.943888) (xy 119.757352 -32.891585) (xy 119.779997 -32.842)
			(xy 119.80947 -32.796143) (xy 119.845169 -32.754947) (xy 119.886367 -32.719252) (xy 119.932226 -32.689783)
			(xy 119.981813 -32.667141) (xy 120.034117 -32.651787) (xy 120.088074 -32.644033) (xy 120.11533 -32.643572)
			(xy 120.97893 -32.643572) (xy 121.006178 -32.6441) (xy 121.06012 -32.65186) (xy 121.112408 -32.667217)
			(xy 121.161979 -32.689858) (xy 121.207823 -32.719324) (xy 121.249008 -32.755014) (xy 121.284694 -32.796201)
			(xy 121.314156 -32.842047) (xy 121.336794 -32.89162) (xy 121.352147 -32.943909) (xy 121.359902 -32.997852)
			(xy 121.359902 -33.052348) (xy 121.352147 -33.106291) (xy 121.336794 -33.15858) (xy 121.314156 -33.208153)
			(xy 121.284694 -33.253999) (xy 121.249008 -33.295186) (xy 121.207823 -33.330876) (xy 121.161979 -33.360342)
			(xy 121.112408 -33.382983) (xy 121.06012 -33.39834) (xy 121.006178 -33.4061) (xy 120.97893 -33.406588)
			(xy 120.11533 -33.406588) (xy 120.088074 -33.406167) (xy 120.034117 -33.398413) (xy 119.981813 -33.383059)
			(xy 119.932226 -33.360417) (xy 119.886367 -33.330948) (xy 119.845169 -33.295253) (xy 119.80947 -33.254057)
			(xy 119.779997 -33.2082) (xy 119.757352 -33.158615) (xy 119.741993 -33.106312) (xy 119.734235 -33.052356)
			(xy 103.390276 -33.052356) (xy 103.381835 -33.081104) (xy 103.359193 -33.130681) (xy 103.329727 -33.176531)
			(xy 103.294036 -33.217722) (xy 103.252845 -33.253413) (xy 103.206995 -33.282879) (xy 103.157418 -33.305521)
			(xy 103.105123 -33.320876) (xy 103.051175 -33.328632) (xy 102.996673 -33.328632) (xy 102.942725 -33.320876)
			(xy 102.89043 -33.305521) (xy 102.840853 -33.282879) (xy 102.795003 -33.253413) (xy 102.753812 -33.217722)
			(xy 102.718121 -33.176531) (xy 102.688655 -33.130681) (xy 102.666013 -33.081104) (xy 102.650658 -33.028809)
			(xy 102.642902 -32.974861) (xy 102.642416 -32.94761) (xy 57.658 -32.94761) (xy 57.658 -33.838388)
			(xy 122.111008 -33.838388) (xy 122.111008 -32.974788) (xy 122.111494 -32.947519) (xy 122.119256 -32.893535)
			(xy 122.134621 -32.841205) (xy 122.157278 -32.791595) (xy 122.186764 -32.745714) (xy 122.222479 -32.704497)
			(xy 122.263696 -32.668782) (xy 122.309577 -32.639296) (xy 122.359187 -32.616639) (xy 122.411517 -32.601274)
			(xy 122.465501 -32.593512) (xy 122.520039 -32.593512) (xy 122.574023 -32.601274) (xy 122.626353 -32.616639)
			(xy 122.675963 -32.639296) (xy 122.721844 -32.668782) (xy 122.763061 -32.704497) (xy 122.798776 -32.745714)
			(xy 122.828262 -32.791595) (xy 122.850919 -32.841205) (xy 122.866284 -32.893535) (xy 122.874046 -32.947519)
			(xy 122.874532 -32.974788) (xy 122.874532 -33.413556) (xy 124.175423 -33.413556) (xy 124.175423 -33.359044)
			(xy 124.183181 -33.305087) (xy 124.198539 -33.252783) (xy 124.221185 -33.203197) (xy 124.250658 -33.157339)
			(xy 124.286357 -33.116142) (xy 124.327555 -33.080446) (xy 124.373415 -33.050976) (xy 124.423002 -33.028332)
			(xy 124.475306 -33.012977) (xy 124.529264 -33.005222) (xy 124.55652 -33.00476) (xy 125.42012 -33.00476)
			(xy 125.447368 -33.005312) (xy 125.501309 -33.01307) (xy 125.553597 -33.028425) (xy 125.603167 -33.051066)
			(xy 125.649011 -33.08053) (xy 125.690196 -33.116218) (xy 125.725882 -33.157405) (xy 125.755344 -33.20325)
			(xy 125.777982 -33.252822) (xy 125.793335 -33.305111) (xy 125.80109 -33.359052) (xy 125.80109 -33.413548)
			(xy 125.793335 -33.467489) (xy 125.777982 -33.519778) (xy 125.755344 -33.56935) (xy 125.725882 -33.615195)
			(xy 125.690196 -33.656382) (xy 125.649011 -33.69207) (xy 125.603167 -33.721534) (xy 125.553597 -33.744175)
			(xy 125.501309 -33.75953) (xy 125.447368 -33.767288) (xy 125.42012 -33.767776) (xy 124.55652 -33.767776)
			(xy 124.529264 -33.767378) (xy 124.475306 -33.759623) (xy 124.423002 -33.744268) (xy 124.373415 -33.721624)
			(xy 124.327555 -33.692154) (xy 124.286357 -33.656458) (xy 124.250658 -33.615261) (xy 124.221185 -33.569403)
			(xy 124.198539 -33.519817) (xy 124.183181 -33.467513) (xy 124.175423 -33.413556) (xy 122.874532 -33.413556)
			(xy 122.874532 -33.838388) (xy 122.874046 -33.865657) (xy 122.866284 -33.919641) (xy 122.850919 -33.971971)
			(xy 122.828262 -34.021581) (xy 122.798776 -34.067462) (xy 122.763061 -34.108679) (xy 122.721844 -34.144394)
			(xy 122.675963 -34.17388) (xy 122.626353 -34.196537) (xy 122.574023 -34.211902) (xy 122.520039 -34.219664)
			(xy 122.465501 -34.219664) (xy 122.411517 -34.211902) (xy 122.359187 -34.196537) (xy 122.309577 -34.17388)
			(xy 122.263696 -34.144394) (xy 122.222479 -34.108679) (xy 122.186764 -34.067462) (xy 122.157278 -34.021581)
			(xy 122.134621 -33.971971) (xy 122.119256 -33.919641) (xy 122.111494 -33.865657) (xy 122.111008 -33.838388)
			(xy 57.658 -33.838388) (xy 57.658 -36.080556) (xy 122.143423 -36.080556) (xy 122.143423 -36.026044)
			(xy 122.151181 -35.972087) (xy 122.166539 -35.919783) (xy 122.189185 -35.870197) (xy 122.218658 -35.824339)
			(xy 122.254357 -35.783142) (xy 122.295555 -35.747446) (xy 122.341415 -35.717976) (xy 122.391002 -35.695332)
			(xy 122.443306 -35.679977) (xy 122.497264 -35.672222) (xy 122.52452 -35.67176) (xy 123.38812 -35.67176)
			(xy 123.415368 -35.672312) (xy 123.469309 -35.68007) (xy 123.521597 -35.695425) (xy 123.571167 -35.718066)
			(xy 123.617011 -35.74753) (xy 123.658196 -35.783218) (xy 123.693882 -35.824405) (xy 123.723344 -35.87025)
			(xy 123.745982 -35.919822) (xy 123.761335 -35.972111) (xy 123.76909 -36.026052) (xy 123.76909 -36.080548)
			(xy 123.761335 -36.134489) (xy 123.745982 -36.186778) (xy 123.723344 -36.23635) (xy 123.693882 -36.282195)
			(xy 123.658196 -36.323382) (xy 123.617011 -36.35907) (xy 123.571167 -36.388534) (xy 123.521597 -36.411175)
			(xy 123.469309 -36.42653) (xy 123.415368 -36.434288) (xy 123.38812 -36.434776) (xy 122.52452 -36.434776)
			(xy 122.497264 -36.434378) (xy 122.443306 -36.426623) (xy 122.391002 -36.411268) (xy 122.341415 -36.388624)
			(xy 122.295555 -36.359154) (xy 122.254357 -36.323458) (xy 122.218658 -36.282261) (xy 122.189185 -36.236403)
			(xy 122.166539 -36.186817) (xy 122.151181 -36.134513) (xy 122.143423 -36.080556) (xy 57.658 -36.080556)
			(xy 57.658 -37.099618) (xy 170.601124 -37.099618) (xy 170.601124 -37.00031) (xy 170.609115 -36.901323)
			(xy 170.625045 -36.8033) (xy 170.648811 -36.706877) (xy 170.680259 -36.612679) (xy 170.719185 -36.521316)
			(xy 170.765336 -36.433383) (xy 170.818413 -36.349448) (xy 170.878072 -36.270056) (xy 170.943926 -36.195722)
			(xy 171.015548 -36.126929) (xy 171.092473 -36.064121) (xy 171.174203 -36.007707) (xy 171.260207 -35.958053)
			(xy 171.349927 -35.91548) (xy 171.442783 -35.880264) (xy 171.538171 -35.852635) (xy 171.635473 -35.832771)
			(xy 171.734058 -35.8208) (xy 171.833286 -35.816802) (xy 171.932514 -35.8208) (xy 172.031099 -35.832771)
			(xy 172.128401 -35.852635) (xy 172.223789 -35.880264) (xy 172.316645 -35.91548) (xy 172.406365 -35.958053)
			(xy 172.492369 -36.007707) (xy 172.574099 -36.064121) (xy 172.651024 -36.126929) (xy 172.722646 -36.195722)
			(xy 172.7885 -36.270056) (xy 172.848159 -36.349448) (xy 172.901236 -36.433383) (xy 172.947387 -36.521316)
			(xy 172.986313 -36.612679) (xy 173.017761 -36.706877) (xy 173.041527 -36.8033) (xy 173.057457 -36.901323)
			(xy 173.065448 -37.00031) (xy 173.065948 -37.049964) (xy 173.065448 -37.099618) (xy 173.057457 -37.198605)
			(xy 173.041527 -37.296628) (xy 173.017761 -37.393051) (xy 172.986313 -37.487249) (xy 172.947387 -37.578612)
			(xy 172.901236 -37.666545) (xy 172.848159 -37.75048) (xy 172.7885 -37.829872) (xy 172.722646 -37.904206)
			(xy 172.651024 -37.972999) (xy 172.574099 -38.035807) (xy 172.492369 -38.092221) (xy 172.406365 -38.141875)
			(xy 172.316645 -38.184448) (xy 172.223789 -38.219664) (xy 172.128401 -38.247293) (xy 172.031099 -38.267157)
			(xy 171.932514 -38.279128) (xy 171.833286 -38.283127) (xy 171.734058 -38.279128) (xy 171.635473 -38.267157)
			(xy 171.538171 -38.247293) (xy 171.442783 -38.219664) (xy 171.349927 -38.184448) (xy 171.260207 -38.141875)
			(xy 171.174203 -38.092221) (xy 171.092473 -38.035807) (xy 171.015548 -37.972999) (xy 170.943926 -37.904206)
			(xy 170.878072 -37.829872) (xy 170.818413 -37.75048) (xy 170.765336 -37.666545) (xy 170.719185 -37.578612)
			(xy 170.680259 -37.487249) (xy 170.648811 -37.393051) (xy 170.625045 -37.296628) (xy 170.609115 -37.198605)
			(xy 170.601124 -37.099618) (xy 57.658 -37.099618) (xy 57.658 -43.481752) (xy 178.630072 -43.481752)
			(xy 178.630072 -42.618152) (xy 178.630558 -42.590883) (xy 178.63832 -42.536899) (xy 178.653685 -42.484569)
			(xy 178.676342 -42.434959) (xy 178.705828 -42.389078) (xy 178.741543 -42.347861) (xy 178.78276 -42.312146)
			(xy 178.828641 -42.28266) (xy 178.878251 -42.260003) (xy 178.930581 -42.244638) (xy 178.984565 -42.236876)
			(xy 179.039103 -42.236876) (xy 179.093087 -42.244638) (xy 179.145417 -42.260003) (xy 179.195027 -42.28266)
			(xy 179.240908 -42.312146) (xy 179.282125 -42.347861) (xy 179.31784 -42.389078) (xy 179.347326 -42.434959)
			(xy 179.369983 -42.484569) (xy 179.385348 -42.536899) (xy 179.39311 -42.590883) (xy 179.393596 -42.618152)
			(xy 179.393596 -43.481752) (xy 179.39311 -43.509021) (xy 179.385348 -43.563005) (xy 179.369983 -43.615335)
			(xy 179.347326 -43.664945) (xy 179.31784 -43.710826) (xy 179.282125 -43.752043) (xy 179.240908 -43.787758)
			(xy 179.195027 -43.817244) (xy 179.145417 -43.839901) (xy 179.093087 -43.855266) (xy 179.039103 -43.863028)
			(xy 178.984565 -43.863028) (xy 178.930581 -43.855266) (xy 178.878251 -43.839901) (xy 178.828641 -43.817244)
			(xy 178.78276 -43.787758) (xy 178.741543 -43.752043) (xy 178.705828 -43.710826) (xy 178.676342 -43.664945)
			(xy 178.653685 -43.615335) (xy 178.63832 -43.563005) (xy 178.630558 -43.509021) (xy 178.630072 -43.481752)
			(xy 57.658 -43.481752) (xy 57.658 -47.04994) (xy 59.582066 -47.04994) (xy 59.586045 -46.890389) (xy 59.597972 -46.731234)
			(xy 59.617818 -46.572872) (xy 59.645532 -46.415696) (xy 59.681047 -46.260096) (xy 59.724273 -46.10646)
			(xy 59.775104 -45.95517) (xy 59.833413 -45.806602) (xy 59.899054 -45.661125) (xy 59.971866 -45.519101)
			(xy 60.051666 -45.380882) (xy 60.138257 -45.246813) (xy 60.231423 -45.117227) (xy 60.330933 -44.992446)
			(xy 60.436538 -44.87278) (xy 60.547978 -44.758527) (xy 60.664973 -44.649971) (xy 60.787235 -44.547381)
			(xy 60.914458 -44.451014) (xy 61.046326 -44.361107) (xy 61.182512 -44.277886) (xy 61.322677 -44.201556)
			(xy 61.466472 -44.132307) (xy 61.613541 -44.070313) (xy 61.763517 -44.015726) (xy 61.916027 -43.968683)
			(xy 62.070693 -43.9293) (xy 62.227129 -43.897676) (xy 62.384947 -43.873888) (xy 62.543755 -43.857997)
			(xy 62.703158 -43.850041) (xy 62.782958 -43.849544) (xy 64.382904 -43.849544) (xy 64.462705 -43.850033)
			(xy 64.622107 -43.857989) (xy 64.780916 -43.87388) (xy 64.938734 -43.897668) (xy 65.095171 -43.929293)
			(xy 65.249837 -43.968675) (xy 65.402347 -44.015719) (xy 65.552323 -44.070306) (xy 65.699392 -44.132301)
			(xy 65.843188 -44.201549) (xy 65.983353 -44.277879) (xy 66.119539 -44.361101) (xy 66.251408 -44.451008)
			(xy 66.378631 -44.547376) (xy 66.500893 -44.649966) (xy 66.617889 -44.758522) (xy 66.729328 -44.872775)
			(xy 66.834934 -44.992442) (xy 66.934444 -45.117223) (xy 67.02761 -45.246809) (xy 67.114201 -45.380878)
			(xy 67.194001 -45.519097) (xy 67.266813 -45.661122) (xy 67.332455 -45.806599) (xy 67.390764 -45.955168)
			(xy 67.441595 -46.106458) (xy 67.484821 -46.260094) (xy 67.520336 -46.415694) (xy 67.54805 -46.572871)
			(xy 67.567896 -46.731233) (xy 67.579823 -46.890388) (xy 67.583802 -47.04994) (xy 89.78165 -47.04994)
			(xy 89.78563 -46.895439) (xy 89.797557 -46.741349) (xy 89.817402 -46.588076) (xy 89.84511 -46.436028)
			(xy 89.880608 -46.285609) (xy 89.923803 -46.137216) (xy 89.97458 -45.991243) (xy 90.032804 -45.848078)
			(xy 90.098321 -45.708101) (xy 90.170957 -45.571681) (xy 90.250519 -45.439181) (xy 90.336796 -45.310953)
			(xy 90.42956 -45.187337) (xy 90.528565 -45.068659) (xy 90.633548 -44.955236) (xy 90.74423 -44.847368)
			(xy 90.860319 -44.74534) (xy 90.981506 -44.649424) (xy 91.10747 -44.559873) (xy 91.237877 -44.476926)
			(xy 91.372381 -44.400801) (xy 91.510626 -44.331702) (xy 91.652244 -44.269811) (xy 91.796861 -44.215293)
			(xy 91.944092 -44.168291) (xy 92.093548 -44.128931) (xy 92.244832 -44.097317) (xy 92.397543 -44.073533)
			(xy 92.551275 -44.057642) (xy 92.705622 -44.049686) (xy 92.782898 -44.049188) (xy 94.383098 -44.049188)
			(xy 94.460374 -44.049669) (xy 94.614722 -44.057625) (xy 94.768456 -44.073516) (xy 94.921168 -44.0973)
			(xy 95.072452 -44.128914) (xy 95.221909 -44.168274) (xy 95.369142 -44.215276) (xy 95.513759 -44.269795)
			(xy 95.655379 -44.331686) (xy 95.793624 -44.400785) (xy 95.928129 -44.47691) (xy 96.058537 -44.559858)
			(xy 96.184502 -44.649409) (xy 96.30569 -44.745326) (xy 96.421779 -44.847354) (xy 96.532463 -44.955223)
			(xy 96.555487 -44.980098) (xy 181.659784 -44.980098) (xy 181.659784 -44.116498) (xy 181.66027 -44.089229)
			(xy 181.668032 -44.035245) (xy 181.683397 -43.982915) (xy 181.706054 -43.933305) (xy 181.73554 -43.887424)
			(xy 181.771255 -43.846207) (xy 181.812472 -43.810492) (xy 181.858353 -43.781006) (xy 181.907963 -43.758349)
			(xy 181.960293 -43.742984) (xy 182.014277 -43.735222) (xy 182.068815 -43.735222) (xy 182.122799 -43.742984)
			(xy 182.175129 -43.758349) (xy 182.224739 -43.781006) (xy 182.27062 -43.810492) (xy 182.311837 -43.846207)
			(xy 182.347552 -43.887424) (xy 182.377038 -43.933305) (xy 182.399695 -43.982915) (xy 182.41506 -44.035245)
			(xy 182.422822 -44.089229) (xy 182.423308 -44.116498) (xy 182.423308 -44.980098) (xy 182.422822 -45.007367)
			(xy 182.41506 -45.061351) (xy 182.399695 -45.113681) (xy 182.377038 -45.163291) (xy 182.347552 -45.209172)
			(xy 182.311837 -45.250389) (xy 182.27062 -45.286104) (xy 182.224739 -45.31559) (xy 182.175129 -45.338247)
			(xy 182.122799 -45.353612) (xy 182.068815 -45.361374) (xy 182.014277 -45.361374) (xy 181.960293 -45.353612)
			(xy 181.907963 -45.338247) (xy 181.858353 -45.31559) (xy 181.812472 -45.286104) (xy 181.771255 -45.250389)
			(xy 181.73554 -45.209172) (xy 181.706054 -45.163291) (xy 181.683397 -45.113681) (xy 181.668032 -45.061351)
			(xy 181.66027 -45.007367) (xy 181.659784 -44.980098) (xy 96.555487 -44.980098) (xy 96.637446 -45.068647)
			(xy 96.736452 -45.187325) (xy 96.829216 -45.310943) (xy 96.915495 -45.439171) (xy 96.995057 -45.571672)
			(xy 97.067693 -45.708092) (xy 97.133211 -45.848071) (xy 97.191435 -45.991237) (xy 97.242212 -46.13721)
			(xy 97.285407 -46.285604) (xy 97.320906 -46.436025) (xy 97.329238 -46.481746) (xy 178.630072 -46.481746)
			(xy 178.630072 -45.618146) (xy 178.630558 -45.590877) (xy 178.63832 -45.536893) (xy 178.653685 -45.484563)
			(xy 178.676342 -45.434953) (xy 178.705828 -45.389072) (xy 178.741543 -45.347855) (xy 178.78276 -45.31214)
			(xy 178.828641 -45.282654) (xy 178.878251 -45.259997) (xy 178.930581 -45.244632) (xy 178.984565 -45.23687)
			(xy 179.039103 -45.23687) (xy 179.093087 -45.244632) (xy 179.145417 -45.259997) (xy 179.195027 -45.282654)
			(xy 179.240908 -45.31214) (xy 179.282125 -45.347855) (xy 179.31784 -45.389072) (xy 179.347326 -45.434953)
			(xy 179.369983 -45.484563) (xy 179.385348 -45.536893) (xy 179.39311 -45.590877) (xy 179.393596 -45.618146)
			(xy 179.393596 -46.481746) (xy 179.39311 -46.509015) (xy 179.385348 -46.562999) (xy 179.369983 -46.615329)
			(xy 179.347326 -46.664939) (xy 179.31784 -46.71082) (xy 179.282125 -46.752037) (xy 179.240908 -46.787752)
			(xy 179.195027 -46.817238) (xy 179.145417 -46.839895) (xy 179.093087 -46.85526) (xy 179.039103 -46.863022)
			(xy 178.984565 -46.863022) (xy 178.930581 -46.85526) (xy 178.878251 -46.839895) (xy 178.828641 -46.817238)
			(xy 178.78276 -46.787752) (xy 178.741543 -46.752037) (xy 178.705828 -46.71082) (xy 178.676342 -46.664939)
			(xy 178.653685 -46.615329) (xy 178.63832 -46.562999) (xy 178.630558 -46.509015) (xy 178.630072 -46.481746)
			(xy 97.329238 -46.481746) (xy 97.348615 -46.588073) (xy 97.368459 -46.741347) (xy 97.380387 -46.895438)
			(xy 97.384366 -47.04994) (xy 97.380387 -47.204442) (xy 97.368459 -47.358533) (xy 97.348615 -47.511807)
			(xy 97.320906 -47.663855) (xy 97.285407 -47.814276) (xy 97.242212 -47.96267) (xy 97.219453 -48.028098)
			(xy 181.659784 -48.028098) (xy 181.659784 -47.164498) (xy 181.66027 -47.137229) (xy 181.668032 -47.083245)
			(xy 181.683397 -47.030915) (xy 181.706054 -46.981305) (xy 181.73554 -46.935424) (xy 181.771255 -46.894207)
			(xy 181.812472 -46.858492) (xy 181.858353 -46.829006) (xy 181.907963 -46.806349) (xy 181.960293 -46.790984)
			(xy 182.014277 -46.783222) (xy 182.068815 -46.783222) (xy 182.122799 -46.790984) (xy 182.175129 -46.806349)
			(xy 182.224739 -46.829006) (xy 182.27062 -46.858492) (xy 182.311837 -46.894207) (xy 182.347552 -46.935424)
			(xy 182.377038 -46.981305) (xy 182.399695 -47.030915) (xy 182.41506 -47.083245) (xy 182.422822 -47.137229)
			(xy 182.423308 -47.164498) (xy 182.423308 -48.028098) (xy 182.422822 -48.055367) (xy 182.41506 -48.109351)
			(xy 182.399695 -48.161681) (xy 182.377038 -48.211291) (xy 182.347552 -48.257172) (xy 182.311837 -48.298389)
			(xy 182.27062 -48.334104) (xy 182.224739 -48.36359) (xy 182.175129 -48.386247) (xy 182.122799 -48.401612)
			(xy 182.068815 -48.409374) (xy 182.014277 -48.409374) (xy 181.960293 -48.401612) (xy 181.907963 -48.386247)
			(xy 181.858353 -48.36359) (xy 181.812472 -48.334104) (xy 181.771255 -48.298389) (xy 181.73554 -48.257172)
			(xy 181.706054 -48.211291) (xy 181.683397 -48.161681) (xy 181.668032 -48.109351) (xy 181.66027 -48.055367)
			(xy 181.659784 -48.028098) (xy 97.219453 -48.028098) (xy 97.191435 -48.108643) (xy 97.133211 -48.251809)
			(xy 97.067693 -48.391788) (xy 96.995057 -48.528208) (xy 96.915495 -48.660709) (xy 96.829216 -48.788937)
			(xy 96.736452 -48.912555) (xy 96.637446 -49.031233) (xy 96.532463 -49.144657) (xy 96.421779 -49.252526)
			(xy 96.30569 -49.354554) (xy 96.184502 -49.450471) (xy 96.140518 -49.48174) (xy 178.630072 -49.48174)
			(xy 178.630072 -48.61814) (xy 178.630558 -48.590871) (xy 178.63832 -48.536887) (xy 178.653685 -48.484557)
			(xy 178.676342 -48.434947) (xy 178.705828 -48.389066) (xy 178.741543 -48.347849) (xy 178.78276 -48.312134)
			(xy 178.828641 -48.282648) (xy 178.878251 -48.259991) (xy 178.930581 -48.244626) (xy 178.984565 -48.236864)
			(xy 179.039103 -48.236864) (xy 179.093087 -48.244626) (xy 179.145417 -48.259991) (xy 179.195027 -48.282648)
			(xy 179.240908 -48.312134) (xy 179.282125 -48.347849) (xy 179.31784 -48.389066) (xy 179.347326 -48.434947)
			(xy 179.369983 -48.484557) (xy 179.385348 -48.536887) (xy 179.39311 -48.590871) (xy 179.393596 -48.61814)
			(xy 179.393596 -49.48174) (xy 179.39311 -49.509009) (xy 179.385348 -49.562993) (xy 179.369983 -49.615323)
			(xy 179.347326 -49.664933) (xy 179.31784 -49.710814) (xy 179.282125 -49.752031) (xy 179.240908 -49.787746)
			(xy 179.195027 -49.817232) (xy 179.145417 -49.839889) (xy 179.093087 -49.855254) (xy 179.039103 -49.863016)
			(xy 178.984565 -49.863016) (xy 178.930581 -49.855254) (xy 178.878251 -49.839889) (xy 178.828641 -49.817232)
			(xy 178.78276 -49.787746) (xy 178.741543 -49.752031) (xy 178.705828 -49.710814) (xy 178.676342 -49.664933)
			(xy 178.653685 -49.615323) (xy 178.63832 -49.562993) (xy 178.630558 -49.509009) (xy 178.630072 -49.48174)
			(xy 96.140518 -49.48174) (xy 96.058537 -49.540022) (xy 95.928129 -49.62297) (xy 95.793624 -49.699095)
			(xy 95.655379 -49.768194) (xy 95.513759 -49.830085) (xy 95.369142 -49.884604) (xy 95.221909 -49.931606)
			(xy 95.072452 -49.970966) (xy 94.921168 -50.00258) (xy 94.768456 -50.026364) (xy 94.614722 -50.042255)
			(xy 94.460374 -50.050211) (xy 94.383098 -50.0507) (xy 92.782898 -50.0507) (xy 92.705622 -50.050194)
			(xy 92.551275 -50.042238) (xy 92.397543 -50.026347) (xy 92.244832 -50.002563) (xy 92.093548 -49.970949)
			(xy 91.944092 -49.931589) (xy 91.796861 -49.884587) (xy 91.652244 -49.830069) (xy 91.510626 -49.768178)
			(xy 91.372381 -49.699079) (xy 91.237877 -49.622954) (xy 91.10747 -49.540007) (xy 90.981506 -49.450456)
			(xy 90.860319 -49.35454) (xy 90.74423 -49.252512) (xy 90.633548 -49.144644) (xy 90.528565 -49.031221)
			(xy 90.42956 -48.912543) (xy 90.336796 -48.788927) (xy 90.250519 -48.660699) (xy 90.170957 -48.528199)
			(xy 90.098321 -48.391779) (xy 90.032804 -48.251802) (xy 89.97458 -48.108637) (xy 89.923803 -47.962664)
			(xy 89.880608 -47.814271) (xy 89.84511 -47.663852) (xy 89.817402 -47.511804) (xy 89.797557 -47.358531)
			(xy 89.78563 -47.204441) (xy 89.78165 -47.04994) (xy 67.583802 -47.04994) (xy 67.579823 -47.209492)
			(xy 67.567896 -47.368647) (xy 67.54805 -47.527009) (xy 67.520336 -47.684186) (xy 67.484821 -47.839786)
			(xy 67.441595 -47.993422) (xy 67.390764 -48.144712) (xy 67.332455 -48.293281) (xy 67.266813 -48.438758)
			(xy 67.194001 -48.580783) (xy 67.114201 -48.719002) (xy 67.02761 -48.853071) (xy 66.934444 -48.982657)
			(xy 66.834934 -49.107438) (xy 66.729328 -49.227105) (xy 66.617889 -49.341358) (xy 66.500893 -49.449914)
			(xy 66.378631 -49.552504) (xy 66.251408 -49.648872) (xy 66.119539 -49.738779) (xy 65.983353 -49.822001)
			(xy 65.843188 -49.898331) (xy 65.699392 -49.967579) (xy 65.552323 -50.029574) (xy 65.402347 -50.084161)
			(xy 65.249837 -50.131205) (xy 65.095171 -50.170587) (xy 64.938734 -50.202212) (xy 64.780916 -50.226)
			(xy 64.622107 -50.241891) (xy 64.462705 -50.249847) (xy 64.382904 -50.250344) (xy 62.782958 -50.250344)
			(xy 62.703158 -50.249839) (xy 62.543755 -50.241883) (xy 62.384947 -50.225992) (xy 62.227129 -50.202204)
			(xy 62.070693 -50.17058) (xy 61.916027 -50.131197) (xy 61.763517 -50.084154) (xy 61.613541 -50.029567)
			(xy 61.466472 -49.967573) (xy 61.322677 -49.898324) (xy 61.182512 -49.821994) (xy 61.046326 -49.738773)
			(xy 60.914458 -49.648866) (xy 60.787235 -49.552499) (xy 60.664973 -49.449909) (xy 60.547978 -49.341353)
			(xy 60.436538 -49.2271) (xy 60.330933 -49.107434) (xy 60.231423 -48.982653) (xy 60.138257 -48.853067)
			(xy 60.051666 -48.718998) (xy 59.971866 -48.580779) (xy 59.899054 -48.438755) (xy 59.833413 -48.293278)
			(xy 59.775104 -48.14471) (xy 59.724273 -47.99342) (xy 59.681047 -47.839784) (xy 59.645532 -47.684184)
			(xy 59.617818 -47.527008) (xy 59.597972 -47.368646) (xy 59.586045 -47.209491) (xy 59.582066 -47.04994)
			(xy 57.658 -47.04994) (xy 57.658 -50.949098) (xy 181.659784 -50.949098) (xy 181.659784 -50.085498)
			(xy 181.66027 -50.058229) (xy 181.668032 -50.004245) (xy 181.683397 -49.951915) (xy 181.706054 -49.902305)
			(xy 181.73554 -49.856424) (xy 181.771255 -49.815207) (xy 181.812472 -49.779492) (xy 181.858353 -49.750006)
			(xy 181.907963 -49.727349) (xy 181.960293 -49.711984) (xy 182.014277 -49.704222) (xy 182.068815 -49.704222)
			(xy 182.122799 -49.711984) (xy 182.175129 -49.727349) (xy 182.224739 -49.750006) (xy 182.27062 -49.779492)
			(xy 182.311837 -49.815207) (xy 182.347552 -49.856424) (xy 182.377038 -49.902305) (xy 182.399695 -49.951915)
			(xy 182.41506 -50.004245) (xy 182.422822 -50.058229) (xy 182.423308 -50.085498) (xy 182.423308 -50.949098)
			(xy 182.422822 -50.976367) (xy 182.41506 -51.030351) (xy 182.399695 -51.082681) (xy 182.377038 -51.132291)
			(xy 182.347552 -51.178172) (xy 182.311837 -51.219389) (xy 182.27062 -51.255104) (xy 182.224739 -51.28459)
			(xy 182.175129 -51.307247) (xy 182.122799 -51.322612) (xy 182.068815 -51.330374) (xy 182.014277 -51.330374)
			(xy 181.960293 -51.322612) (xy 181.907963 -51.307247) (xy 181.858353 -51.28459) (xy 181.812472 -51.255104)
			(xy 181.771255 -51.219389) (xy 181.73554 -51.178172) (xy 181.706054 -51.132291) (xy 181.683397 -51.082681)
			(xy 181.668032 -51.030351) (xy 181.66027 -50.976367) (xy 181.659784 -50.949098) (xy 57.658 -50.949098)
			(xy 57.658 -52.481734) (xy 178.630072 -52.481734) (xy 178.630072 -51.618134) (xy 178.630558 -51.590865)
			(xy 178.63832 -51.536881) (xy 178.653685 -51.484551) (xy 178.676342 -51.434941) (xy 178.705828 -51.38906)
			(xy 178.741543 -51.347843) (xy 178.78276 -51.312128) (xy 178.828641 -51.282642) (xy 178.878251 -51.259985)
			(xy 178.930581 -51.24462) (xy 178.984565 -51.236858) (xy 179.039103 -51.236858) (xy 179.093087 -51.24462)
			(xy 179.145417 -51.259985) (xy 179.195027 -51.282642) (xy 179.240908 -51.312128) (xy 179.282125 -51.347843)
			(xy 179.31784 -51.38906) (xy 179.347326 -51.434941) (xy 179.369983 -51.484551) (xy 179.385348 -51.536881)
			(xy 179.39311 -51.590865) (xy 179.393596 -51.618134) (xy 179.393596 -52.481734) (xy 179.39311 -52.509003)
			(xy 179.385348 -52.562987) (xy 179.369983 -52.615317) (xy 179.347326 -52.664927) (xy 179.31784 -52.710808)
			(xy 179.282125 -52.752025) (xy 179.240908 -52.78774) (xy 179.195027 -52.817226) (xy 179.145417 -52.839883)
			(xy 179.093087 -52.855248) (xy 179.039103 -52.86301) (xy 178.984565 -52.86301) (xy 178.930581 -52.855248)
			(xy 178.878251 -52.839883) (xy 178.828641 -52.817226) (xy 178.78276 -52.78774) (xy 178.741543 -52.752025)
			(xy 178.705828 -52.710808) (xy 178.676342 -52.664927) (xy 178.653685 -52.615317) (xy 178.63832 -52.562987)
			(xy 178.630558 -52.509003) (xy 178.630072 -52.481734) (xy 57.658 -52.481734) (xy 57.658 -53.954934)
			(xy 181.659784 -53.954934) (xy 181.659784 -53.091334) (xy 181.66027 -53.064065) (xy 181.668032 -53.010081)
			(xy 181.683397 -52.957751) (xy 181.706054 -52.908141) (xy 181.73554 -52.86226) (xy 181.771255 -52.821043)
			(xy 181.812472 -52.785328) (xy 181.858353 -52.755842) (xy 181.907963 -52.733185) (xy 181.960293 -52.71782)
			(xy 182.014277 -52.710058) (xy 182.068815 -52.710058) (xy 182.122799 -52.71782) (xy 182.175129 -52.733185)
			(xy 182.224739 -52.755842) (xy 182.27062 -52.785328) (xy 182.311837 -52.821043) (xy 182.347552 -52.86226)
			(xy 182.377038 -52.908141) (xy 182.399695 -52.957751) (xy 182.41506 -53.010081) (xy 182.422822 -53.064065)
			(xy 182.423308 -53.091334) (xy 182.423308 -53.954934) (xy 182.422822 -53.982203) (xy 182.41506 -54.036187)
			(xy 182.399695 -54.088517) (xy 182.377038 -54.138127) (xy 182.347552 -54.184008) (xy 182.311837 -54.225225)
			(xy 182.27062 -54.26094) (xy 182.224739 -54.290426) (xy 182.175129 -54.313083) (xy 182.122799 -54.328448)
			(xy 182.068815 -54.33621) (xy 182.014277 -54.33621) (xy 181.960293 -54.328448) (xy 181.907963 -54.313083)
			(xy 181.858353 -54.290426) (xy 181.812472 -54.26094) (xy 181.771255 -54.225225) (xy 181.73554 -54.184008)
			(xy 181.706054 -54.138127) (xy 181.683397 -54.088517) (xy 181.668032 -54.036187) (xy 181.66027 -53.982203)
			(xy 181.659784 -53.954934) (xy 57.658 -53.954934) (xy 57.658 -55.481728) (xy 178.630072 -55.481728)
			(xy 178.630072 -54.618128) (xy 178.630558 -54.590859) (xy 178.63832 -54.536875) (xy 178.653685 -54.484545)
			(xy 178.676342 -54.434935) (xy 178.705828 -54.389054) (xy 178.741543 -54.347837) (xy 178.78276 -54.312122)
			(xy 178.828641 -54.282636) (xy 178.878251 -54.259979) (xy 178.930581 -54.244614) (xy 178.984565 -54.236852)
			(xy 179.039103 -54.236852) (xy 179.093087 -54.244614) (xy 179.145417 -54.259979) (xy 179.195027 -54.282636)
			(xy 179.240908 -54.312122) (xy 179.282125 -54.347837) (xy 179.31784 -54.389054) (xy 179.347326 -54.434935)
			(xy 179.369983 -54.484545) (xy 179.385348 -54.536875) (xy 179.39311 -54.590859) (xy 179.393596 -54.618128)
			(xy 179.393596 -55.481728) (xy 179.39311 -55.508997) (xy 179.385348 -55.562981) (xy 179.369983 -55.615311)
			(xy 179.347326 -55.664921) (xy 179.31784 -55.710802) (xy 179.282125 -55.752019) (xy 179.240908 -55.787734)
			(xy 179.195027 -55.81722) (xy 179.145417 -55.839877) (xy 179.093087 -55.855242) (xy 179.039103 -55.863004)
			(xy 178.984565 -55.863004) (xy 178.930581 -55.855242) (xy 178.878251 -55.839877) (xy 178.828641 -55.81722)
			(xy 178.78276 -55.787734) (xy 178.741543 -55.752019) (xy 178.705828 -55.710802) (xy 178.676342 -55.664921)
			(xy 178.653685 -55.615311) (xy 178.63832 -55.562981) (xy 178.630558 -55.508997) (xy 178.630072 -55.481728)
			(xy 57.658 -55.481728) (xy 57.658 -57.094424) (xy 170.842423 -57.094424) (xy 170.842423 -57.005424)
			(xy 170.850401 -56.916783) (xy 170.866293 -56.829214) (xy 170.88997 -56.743422) (xy 170.921242 -56.660098)
			(xy 170.959857 -56.579912) (xy 171.005505 -56.50351) (xy 171.057817 -56.431508) (xy 171.116374 -56.364486)
			(xy 171.180702 -56.302981) (xy 171.250284 -56.247491) (xy 171.324561 -56.198462) (xy 171.402933 -56.156288)
			(xy 171.484771 -56.121309) (xy 171.569414 -56.093806) (xy 171.656182 -56.074002) (xy 171.744376 -56.062055)
			(xy 171.833286 -56.058063) (xy 171.922196 -56.062055) (xy 172.01039 -56.074002) (xy 172.097158 -56.093806)
			(xy 172.181801 -56.121309) (xy 172.263639 -56.156288) (xy 172.342011 -56.198462) (xy 172.416288 -56.247491)
			(xy 172.48587 -56.302981) (xy 172.550198 -56.364486) (xy 172.608755 -56.431508) (xy 172.661067 -56.50351)
			(xy 172.706715 -56.579912) (xy 172.74533 -56.660098) (xy 172.776602 -56.743422) (xy 172.800279 -56.829214)
			(xy 172.816171 -56.916783) (xy 172.824149 -57.005424) (xy 172.824648 -57.049924) (xy 172.824149 -57.094424)
			(xy 172.816171 -57.183065) (xy 172.800279 -57.270634) (xy 172.776602 -57.356426) (xy 172.74533 -57.43975)
			(xy 172.706715 -57.519936) (xy 172.661067 -57.596338) (xy 172.608755 -57.66834) (xy 172.550198 -57.735362)
			(xy 172.48587 -57.796867) (xy 172.416288 -57.852357) (xy 172.342011 -57.901386) (xy 172.263639 -57.94356)
			(xy 172.181801 -57.978539) (xy 172.097158 -58.006042) (xy 172.01039 -58.025846) (xy 171.922196 -58.037793)
			(xy 171.833286 -58.041786) (xy 171.744376 -58.037793) (xy 171.656182 -58.025846) (xy 171.569414 -58.006042)
			(xy 171.484771 -57.978539) (xy 171.402933 -57.94356) (xy 171.324561 -57.901386) (xy 171.250284 -57.852357)
			(xy 171.180702 -57.796867) (xy 171.116374 -57.735362) (xy 171.057817 -57.66834) (xy 171.005505 -57.596338)
			(xy 170.959857 -57.519936) (xy 170.921242 -57.43975) (xy 170.88997 -57.356426) (xy 170.866293 -57.270634)
			(xy 170.850401 -57.183065) (xy 170.842423 -57.094424) (xy 57.658 -57.094424) (xy 57.658 -60.375038)
			(xy 233.333551 -60.375038) (xy 233.337555 -60.287153) (xy 233.349535 -60.199996) (xy 233.36939 -60.114289)
			(xy 233.396957 -60.030744) (xy 233.432007 -59.950051) (xy 233.474249 -59.872879) (xy 233.523334 -59.799869)
			(xy 233.578855 -59.731625) (xy 233.640352 -59.668712) (xy 233.707314 -59.611652) (xy 233.779188 -59.560918)
			(xy 233.855378 -59.51693) (xy 233.935252 -59.480052) (xy 234.018149 -59.450591) (xy 234.103381 -59.428789)
			(xy 234.190243 -59.414829) (xy 234.278014 -59.408825) (xy 234.365968 -59.410828) (xy 234.453375 -59.42082)
			(xy 234.539511 -59.43872) (xy 234.623663 -59.464378) (xy 234.705133 -59.497582) (xy 234.783246 -59.538056)
			(xy 234.857354 -59.585467) (xy 234.926845 -59.63942) (xy 234.991141 -59.699468) (xy 235.04971 -59.765115)
			(xy 235.102067 -59.835815) (xy 235.147779 -59.910984) (xy 235.186465 -59.989998) (xy 235.217806 -60.072203)
			(xy 235.241541 -60.156917) (xy 235.257475 -60.243438) (xy 235.265475 -60.33105) (xy 235.265976 -60.375038)
			(xy 235.265475 -60.419026) (xy 235.257475 -60.506638) (xy 235.241541 -60.593159) (xy 235.217806 -60.677873)
			(xy 235.186465 -60.760078) (xy 235.147779 -60.839092) (xy 235.102067 -60.914261) (xy 235.04971 -60.984961)
			(xy 234.991141 -61.050608) (xy 234.926845 -61.110656) (xy 234.857354 -61.164609) (xy 234.783246 -61.21202)
			(xy 234.705133 -61.252494) (xy 234.623663 -61.285698) (xy 234.539511 -61.311356) (xy 234.453375 -61.329256)
			(xy 234.365968 -61.339248) (xy 234.278014 -61.341251) (xy 234.190243 -61.335247) (xy 234.103381 -61.321287)
			(xy 234.018149 -61.299485) (xy 233.935252 -61.270024) (xy 233.855378 -61.233146) (xy 233.779188 -61.189158)
			(xy 233.707314 -61.138424) (xy 233.640352 -61.081364) (xy 233.578855 -61.018451) (xy 233.523334 -60.950207)
			(xy 233.474249 -60.877197) (xy 233.432007 -60.800025) (xy 233.396957 -60.719332) (xy 233.36939 -60.635787)
			(xy 233.349535 -60.55008) (xy 233.337555 -60.462923) (xy 233.333551 -60.375038) (xy 57.658 -60.375038)
			(xy 57.658 -74.767948) (xy 173.354492 -74.767948) (xy 173.354492 -66.06794) (xy 173.354997 -65.962416)
			(xy 173.363081 -65.751522) (xy 173.379237 -65.541093) (xy 173.40344 -65.331436) (xy 173.435657 -65.122861)
			(xy 173.475839 -64.915673) (xy 173.523927 -64.710176) (xy 173.579851 -64.506672) (xy 173.643528 -64.305459)
			(xy 173.714866 -64.106832) (xy 173.79376 -63.911084) (xy 173.880093 -63.718502) (xy 173.97374 -63.529367)
			(xy 174.074562 -63.343958) (xy 174.182412 -63.162547) (xy 174.297131 -62.9854) (xy 174.418551 -62.812778)
			(xy 174.546494 -62.644932) (xy 174.680772 -62.48211) (xy 174.821188 -62.324551) (xy 174.967536 -62.172486)
			(xy 175.119601 -62.026138) (xy 175.27716 -61.885722) (xy 175.439982 -61.751444) (xy 175.607828 -61.623501)
			(xy 175.78045 -61.502081) (xy 175.957597 -61.387362) (xy 176.139008 -61.279512) (xy 176.324417 -61.17869)
			(xy 176.513552 -61.085043) (xy 176.706134 -60.99871) (xy 176.901882 -60.919816) (xy 177.100509 -60.848478)
			(xy 177.301722 -60.784801) (xy 177.505226 -60.728877) (xy 177.710723 -60.680789) (xy 177.917911 -60.640607)
			(xy 178.126486 -60.60839) (xy 178.336143 -60.584187) (xy 178.546572 -60.568031) (xy 178.757466 -60.559947)
			(xy 178.968514 -60.559947) (xy 179.179408 -60.568031) (xy 179.389837 -60.584187) (xy 179.599494 -60.60839)
			(xy 179.808069 -60.640607) (xy 180.015257 -60.680789) (xy 180.220754 -60.728877) (xy 180.424258 -60.784801)
			(xy 180.625471 -60.848478) (xy 180.824098 -60.919816) (xy 181.019846 -60.99871) (xy 181.212428 -61.085043)
			(xy 181.401563 -61.17869) (xy 181.586972 -61.279512) (xy 181.768383 -61.387362) (xy 181.94553 -61.502081)
			(xy 182.118152 -61.623501) (xy 182.285998 -61.751444) (xy 182.44882 -61.885722) (xy 182.606379 -62.026138)
			(xy 182.758444 -62.172486) (xy 182.904792 -62.324551) (xy 183.045208 -62.48211) (xy 183.179486 -62.644932)
			(xy 183.307429 -62.812778) (xy 183.428849 -62.9854) (xy 183.543568 -63.162547) (xy 183.651418 -63.343958)
			(xy 183.75224 -63.529367) (xy 183.845887 -63.718502) (xy 183.93222 -63.911084) (xy 184.011114 -64.106832)
			(xy 184.082452 -64.305459) (xy 184.146129 -64.506672) (xy 184.202053 -64.710176) (xy 184.250141 -64.915673)
			(xy 184.290323 -65.122861) (xy 184.32254 -65.331436) (xy 184.346743 -65.541093) (xy 184.362899 -65.751522)
			(xy 184.370983 -65.962416) (xy 184.371488 -66.06794) (xy 184.371488 -74.760836) (xy 287.494472 -74.760836)
			(xy 287.494472 -66.060828) (xy 287.494977 -65.955304) (xy 287.503061 -65.74441) (xy 287.519217 -65.533981)
			(xy 287.54342 -65.324324) (xy 287.575637 -65.115749) (xy 287.615819 -64.908561) (xy 287.663907 -64.703064)
			(xy 287.719831 -64.49956) (xy 287.783508 -64.298347) (xy 287.854846 -64.09972) (xy 287.93374 -63.903972)
			(xy 288.020073 -63.71139) (xy 288.11372 -63.522255) (xy 288.214542 -63.336846) (xy 288.322392 -63.155435)
			(xy 288.437111 -62.978288) (xy 288.558531 -62.805666) (xy 288.686474 -62.63782) (xy 288.820752 -62.474998)
			(xy 288.961168 -62.317439) (xy 289.107516 -62.165374) (xy 289.259581 -62.019026) (xy 289.41714 -61.87861)
			(xy 289.579962 -61.744332) (xy 289.747808 -61.616389) (xy 289.92043 -61.494969) (xy 290.097577 -61.38025)
			(xy 290.278988 -61.2724) (xy 290.464397 -61.171578) (xy 290.653532 -61.077931) (xy 290.846114 -60.991598)
			(xy 291.041862 -60.912704) (xy 291.240489 -60.841366) (xy 291.441702 -60.777689) (xy 291.645206 -60.721765)
			(xy 291.850703 -60.673677) (xy 292.057891 -60.633495) (xy 292.266466 -60.601278) (xy 292.476123 -60.577075)
			(xy 292.686552 -60.560919) (xy 292.897446 -60.552835) (xy 293.108494 -60.552835) (xy 293.319388 -60.560919)
			(xy 293.529817 -60.577075) (xy 293.739474 -60.601278) (xy 293.948049 -60.633495) (xy 294.155237 -60.673677)
			(xy 294.360734 -60.721765) (xy 294.564238 -60.777689) (xy 294.765451 -60.841366) (xy 294.964078 -60.912704)
			(xy 295.159826 -60.991598) (xy 295.352408 -61.077931) (xy 295.541543 -61.171578) (xy 295.726952 -61.2724)
			(xy 295.908363 -61.38025) (xy 296.08551 -61.494969) (xy 296.258132 -61.616389) (xy 296.425978 -61.744332)
			(xy 296.5888 -61.87861) (xy 296.746359 -62.019026) (xy 296.898424 -62.165374) (xy 297.044772 -62.317439)
			(xy 297.185188 -62.474998) (xy 297.319466 -62.63782) (xy 297.447409 -62.805666) (xy 297.568829 -62.978288)
			(xy 297.683548 -63.155435) (xy 297.791398 -63.336846) (xy 297.89222 -63.522255) (xy 297.985867 -63.71139)
			(xy 298.0722 -63.903972) (xy 298.151094 -64.09972) (xy 298.222432 -64.298347) (xy 298.286109 -64.49956)
			(xy 298.342033 -64.703064) (xy 298.390121 -64.908561) (xy 298.430303 -65.115749) (xy 298.46252 -65.324324)
			(xy 298.486723 -65.533981) (xy 298.502879 -65.74441) (xy 298.510963 -65.955304) (xy 298.511468 -66.060828)
			(xy 298.511468 -74.760836) (xy 298.511434 -74.767948) (xy 421.29456 -74.767948) (xy 421.29456 -66.06794)
			(xy 421.295065 -65.962416) (xy 421.303149 -65.751522) (xy 421.319305 -65.541093) (xy 421.343508 -65.331436)
			(xy 421.375725 -65.122861) (xy 421.415907 -64.915673) (xy 421.463995 -64.710176) (xy 421.519919 -64.506672)
			(xy 421.583596 -64.305459) (xy 421.654934 -64.106832) (xy 421.733828 -63.911084) (xy 421.820161 -63.718502)
			(xy 421.913808 -63.529367) (xy 422.01463 -63.343958) (xy 422.12248 -63.162547) (xy 422.237199 -62.9854)
			(xy 422.358619 -62.812778) (xy 422.486562 -62.644932) (xy 422.62084 -62.48211) (xy 422.761256 -62.324551)
			(xy 422.907604 -62.172486) (xy 423.059669 -62.026138) (xy 423.217228 -61.885722) (xy 423.38005 -61.751444)
			(xy 423.547896 -61.623501) (xy 423.720518 -61.502081) (xy 423.897665 -61.387362) (xy 424.079076 -61.279512)
			(xy 424.264485 -61.17869) (xy 424.45362 -61.085043) (xy 424.646202 -60.99871) (xy 424.84195 -60.919816)
			(xy 425.040577 -60.848478) (xy 425.24179 -60.784801) (xy 425.445294 -60.728877) (xy 425.650791 -60.680789)
			(xy 425.857979 -60.640607) (xy 426.066554 -60.60839) (xy 426.276211 -60.584187) (xy 426.48664 -60.568031)
			(xy 426.697534 -60.559947) (xy 426.908582 -60.559947) (xy 427.119476 -60.568031) (xy 427.329905 -60.584187)
			(xy 427.539562 -60.60839) (xy 427.748137 -60.640607) (xy 427.955325 -60.680789) (xy 428.160822 -60.728877)
			(xy 428.364326 -60.784801) (xy 428.565539 -60.848478) (xy 428.764166 -60.919816) (xy 428.959914 -60.99871)
			(xy 429.152496 -61.085043) (xy 429.341631 -61.17869) (xy 429.52704 -61.279512) (xy 429.708451 -61.387362)
			(xy 429.885598 -61.502081) (xy 430.05822 -61.623501) (xy 430.226066 -61.751444) (xy 430.388888 -61.885722)
			(xy 430.546447 -62.026138) (xy 430.698512 -62.172486) (xy 430.84486 -62.324551) (xy 430.985276 -62.48211)
			(xy 431.119554 -62.644932) (xy 431.247497 -62.812778) (xy 431.368917 -62.9854) (xy 431.483636 -63.162547)
			(xy 431.591486 -63.343958) (xy 431.692308 -63.529367) (xy 431.785955 -63.718502) (xy 431.872288 -63.911084)
			(xy 431.951182 -64.106832) (xy 432.02252 -64.305459) (xy 432.086197 -64.506672) (xy 432.142121 -64.710176)
			(xy 432.190209 -64.915673) (xy 432.230391 -65.122861) (xy 432.262608 -65.331436) (xy 432.286811 -65.541093)
			(xy 432.302967 -65.751522) (xy 432.311051 -65.962416) (xy 432.311556 -66.06794) (xy 432.311556 -74.767948)
			(xy 432.311051 -74.873472) (xy 432.302967 -75.084366) (xy 432.286811 -75.294795) (xy 432.262608 -75.504452)
			(xy 432.230391 -75.713027) (xy 432.190209 -75.920215) (xy 432.142121 -76.125712) (xy 432.086197 -76.329216)
			(xy 432.02252 -76.530429) (xy 431.951182 -76.729056) (xy 431.872288 -76.924804) (xy 431.785955 -77.117386)
			(xy 431.692308 -77.306521) (xy 431.591486 -77.49193) (xy 431.483636 -77.673341) (xy 431.368917 -77.850488)
			(xy 431.247497 -78.02311) (xy 431.119554 -78.190956) (xy 430.985276 -78.353778) (xy 430.84486 -78.511337)
			(xy 430.698512 -78.663402) (xy 430.546447 -78.80975) (xy 430.388888 -78.950166) (xy 430.226066 -79.084444)
			(xy 430.05822 -79.212387) (xy 429.885598 -79.333807) (xy 429.708451 -79.448526) (xy 429.52704 -79.556376)
			(xy 429.341631 -79.657198) (xy 429.152496 -79.750845) (xy 428.959914 -79.837178) (xy 428.764166 -79.916072)
			(xy 428.565539 -79.98741) (xy 428.364326 -80.051087) (xy 428.160822 -80.107011) (xy 427.955325 -80.155099)
			(xy 427.748137 -80.195281) (xy 427.539562 -80.227498) (xy 427.329905 -80.251701) (xy 427.119476 -80.267857)
			(xy 426.908582 -80.275941) (xy 426.697534 -80.275941) (xy 426.48664 -80.267857) (xy 426.276211 -80.251701)
			(xy 426.066554 -80.227498) (xy 425.857979 -80.195281) (xy 425.650791 -80.155099) (xy 425.445294 -80.107011)
			(xy 425.24179 -80.051087) (xy 425.040577 -79.98741) (xy 424.84195 -79.916072) (xy 424.646202 -79.837178)
			(xy 424.45362 -79.750845) (xy 424.264485 -79.657198) (xy 424.079076 -79.556376) (xy 423.897665 -79.448526)
			(xy 423.720518 -79.333807) (xy 423.547896 -79.212387) (xy 423.38005 -79.084444) (xy 423.217228 -78.950166)
			(xy 423.059669 -78.80975) (xy 422.907604 -78.663402) (xy 422.761256 -78.511337) (xy 422.62084 -78.353778)
			(xy 422.486562 -78.190956) (xy 422.358619 -78.02311) (xy 422.237199 -77.850488) (xy 422.12248 -77.673341)
			(xy 422.01463 -77.49193) (xy 421.913808 -77.306521) (xy 421.820161 -77.117386) (xy 421.733828 -76.924804)
			(xy 421.654934 -76.729056) (xy 421.583596 -76.530429) (xy 421.519919 -76.329216) (xy 421.463995 -76.125712)
			(xy 421.415907 -75.920215) (xy 421.375725 -75.713027) (xy 421.343508 -75.504452) (xy 421.319305 -75.294795)
			(xy 421.303149 -75.084366) (xy 421.295065 -74.873472) (xy 421.29456 -74.767948) (xy 298.511434 -74.767948)
			(xy 298.510963 -74.86636) (xy 298.502879 -75.077254) (xy 298.486723 -75.287683) (xy 298.46252 -75.49734)
			(xy 298.430303 -75.705915) (xy 298.390121 -75.913103) (xy 298.342033 -76.1186) (xy 298.286109 -76.322104)
			(xy 298.222432 -76.523317) (xy 298.151094 -76.721944) (xy 298.0722 -76.917692) (xy 297.985867 -77.110274)
			(xy 297.89222 -77.299409) (xy 297.791398 -77.484818) (xy 297.683548 -77.666229) (xy 297.568829 -77.843376)
			(xy 297.447409 -78.015998) (xy 297.319466 -78.183844) (xy 297.185188 -78.346666) (xy 297.044772 -78.504225)
			(xy 296.898424 -78.65629) (xy 296.746359 -78.802638) (xy 296.5888 -78.943054) (xy 296.425978 -79.077332)
			(xy 296.258132 -79.205275) (xy 296.08551 -79.326695) (xy 295.908363 -79.441414) (xy 295.726952 -79.549264)
			(xy 295.541543 -79.650086) (xy 295.352408 -79.743733) (xy 295.159826 -79.830066) (xy 294.964078 -79.90896)
			(xy 294.765451 -79.980298) (xy 294.564238 -80.043975) (xy 294.360734 -80.099899) (xy 294.155237 -80.147987)
			(xy 293.948049 -80.188169) (xy 293.739474 -80.220386) (xy 293.529817 -80.244589) (xy 293.319388 -80.260745)
			(xy 293.108494 -80.268829) (xy 292.897446 -80.268829) (xy 292.686552 -80.260745) (xy 292.476123 -80.244589)
			(xy 292.266466 -80.220386) (xy 292.057891 -80.188169) (xy 291.850703 -80.147987) (xy 291.645206 -80.099899)
			(xy 291.441702 -80.043975) (xy 291.240489 -79.980298) (xy 291.041862 -79.90896) (xy 290.846114 -79.830066)
			(xy 290.653532 -79.743733) (xy 290.464397 -79.650086) (xy 290.278988 -79.549264) (xy 290.097577 -79.441414)
			(xy 289.92043 -79.326695) (xy 289.747808 -79.205275) (xy 289.579962 -79.077332) (xy 289.41714 -78.943054)
			(xy 289.259581 -78.802638) (xy 289.107516 -78.65629) (xy 288.961168 -78.504225) (xy 288.820752 -78.346666)
			(xy 288.686474 -78.183844) (xy 288.558531 -78.015998) (xy 288.437111 -77.843376) (xy 288.322392 -77.666229)
			(xy 288.214542 -77.484818) (xy 288.11372 -77.299409) (xy 288.020073 -77.110274) (xy 287.93374 -76.917692)
			(xy 287.854846 -76.721944) (xy 287.783508 -76.523317) (xy 287.719831 -76.322104) (xy 287.663907 -76.1186)
			(xy 287.615819 -75.913103) (xy 287.575637 -75.705915) (xy 287.54342 -75.49734) (xy 287.519217 -75.287683)
			(xy 287.503061 -75.077254) (xy 287.494977 -74.86636) (xy 287.494472 -74.760836) (xy 184.371488 -74.760836)
			(xy 184.371488 -74.767948) (xy 184.370983 -74.873472) (xy 184.362899 -75.084366) (xy 184.346743 -75.294795)
			(xy 184.32254 -75.504452) (xy 184.290323 -75.713027) (xy 184.250141 -75.920215) (xy 184.202053 -76.125712)
			(xy 184.146129 -76.329216) (xy 184.082452 -76.530429) (xy 184.011114 -76.729056) (xy 183.93222 -76.924804)
			(xy 183.845887 -77.117386) (xy 183.75224 -77.306521) (xy 183.651418 -77.49193) (xy 183.543568 -77.673341)
			(xy 183.428849 -77.850488) (xy 183.307429 -78.02311) (xy 183.179486 -78.190956) (xy 183.045208 -78.353778)
			(xy 182.904792 -78.511337) (xy 182.758444 -78.663402) (xy 182.606379 -78.80975) (xy 182.44882 -78.950166)
			(xy 182.285998 -79.084444) (xy 182.118152 -79.212387) (xy 181.94553 -79.333807) (xy 181.768383 -79.448526)
			(xy 181.586972 -79.556376) (xy 181.401563 -79.657198) (xy 181.212428 -79.750845) (xy 181.019846 -79.837178)
			(xy 180.824098 -79.916072) (xy 180.625471 -79.98741) (xy 180.424258 -80.051087) (xy 180.220754 -80.107011)
			(xy 180.015257 -80.155099) (xy 179.808069 -80.195281) (xy 179.599494 -80.227498) (xy 179.389837 -80.251701)
			(xy 179.179408 -80.267857) (xy 178.968514 -80.275941) (xy 178.757466 -80.275941) (xy 178.546572 -80.267857)
			(xy 178.336143 -80.251701) (xy 178.126486 -80.227498) (xy 177.917911 -80.195281) (xy 177.710723 -80.155099)
			(xy 177.505226 -80.107011) (xy 177.301722 -80.051087) (xy 177.100509 -79.98741) (xy 176.901882 -79.916072)
			(xy 176.706134 -79.837178) (xy 176.513552 -79.750845) (xy 176.324417 -79.657198) (xy 176.139008 -79.556376)
			(xy 175.957597 -79.448526) (xy 175.78045 -79.333807) (xy 175.607828 -79.212387) (xy 175.439982 -79.084444)
			(xy 175.27716 -78.950166) (xy 175.119601 -78.80975) (xy 174.967536 -78.663402) (xy 174.821188 -78.511337)
			(xy 174.680772 -78.353778) (xy 174.546494 -78.190956) (xy 174.418551 -78.02311) (xy 174.297131 -77.850488)
			(xy 174.182412 -77.673341) (xy 174.074562 -77.49193) (xy 173.97374 -77.306521) (xy 173.880093 -77.117386)
			(xy 173.79376 -76.924804) (xy 173.714866 -76.729056) (xy 173.643528 -76.530429) (xy 173.579851 -76.329216)
			(xy 173.523927 -76.125712) (xy 173.475839 -75.920215) (xy 173.435657 -75.713027) (xy 173.40344 -75.504452)
			(xy 173.379237 -75.294795) (xy 173.363081 -75.084366) (xy 173.354997 -74.873472) (xy 173.354492 -74.767948)
			(xy 57.658 -74.767948) (xy 57.658 -81.70037) (xy 230.62845 -81.70037) (xy 230.632464 -81.494686)
			(xy 230.6445 -81.289316) (xy 230.664539 -81.084572) (xy 230.692552 -80.880765) (xy 230.728495 -80.678206)
			(xy 230.772314 -80.477204) (xy 230.823941 -80.278065) (xy 230.883299 -80.081092) (xy 230.950297 -79.886584)
			(xy 231.024833 -79.694839) (xy 231.106793 -79.506148) (xy 231.196053 -79.320798) (xy 231.292476 -79.139072)
			(xy 231.395917 -78.961246) (xy 231.506216 -78.787592) (xy 231.623207 -78.618373) (xy 231.746711 -78.453847)
			(xy 231.87654 -78.294266) (xy 232.012497 -78.139871) (xy 232.154374 -77.990899) (xy 232.301955 -77.847575)
			(xy 232.455016 -77.710119) (xy 232.613323 -77.578739) (xy 232.776636 -77.453636) (xy 232.944705 -77.334999)
			(xy 233.117275 -77.223011) (xy 233.294083 -77.11784) (xy 233.47486 -77.019649) (xy 233.65933 -76.928585)
			(xy 233.847212 -76.844788) (xy 234.038222 -76.768385) (xy 234.232066 -76.699492) (xy 234.428451 -76.638215)
			(xy 234.627077 -76.584647) (xy 234.827642 -76.53887) (xy 235.02984 -76.500952) (xy 235.233364 -76.470953)
			(xy 235.437903 -76.448916) (xy 235.643146 -76.434877) (xy 235.848781 -76.428857) (xy 236.054494 -76.430864)
			(xy 236.259972 -76.440896) (xy 236.464902 -76.458937) (xy 236.668972 -76.48496) (xy 236.871872 -76.518925)
			(xy 237.073292 -76.56078) (xy 237.272925 -76.610462) (xy 237.470468 -76.667896) (xy 237.66562 -76.732993)
			(xy 237.858084 -76.805654) (xy 238.047566 -76.88577) (xy 238.233777 -76.973217) (xy 238.416436 -77.067863)
			(xy 238.595262 -77.169563) (xy 238.769984 -77.278163) (xy 238.940337 -77.393498) (xy 239.106059 -77.515391)
			(xy 239.2669 -77.643657) (xy 239.422613 -77.7781) (xy 239.572963 -77.918517) (xy 239.71772 -78.064693)
			(xy 239.856663 -78.216405) (xy 239.989581 -78.373423) (xy 240.116272 -78.535508) (xy 240.236542 -78.702411)
			(xy 240.350209 -78.873881) (xy 240.457099 -79.049654) (xy 240.55705 -79.229464) (xy 240.649909 -79.413037)
			(xy 240.735536 -79.600093) (xy 240.813798 -79.790348) (xy 240.884579 -79.983511) (xy 240.947769 -80.179289)
			(xy 241.003272 -80.377383) (xy 241.051004 -80.577492) (xy 241.090893 -80.77931) (xy 241.122877 -80.982532)
			(xy 241.135929 -81.093507) (xy 398.275806 -81.093507) (xy 398.275806 -81.008785) (xy 398.283859 -80.924448)
			(xy 398.299893 -80.841258) (xy 398.323761 -80.759968) (xy 398.355249 -80.681316) (xy 398.394071 -80.606013)
			(xy 398.439874 -80.534741) (xy 398.492245 -80.468145) (xy 398.55071 -80.40683) (xy 398.614738 -80.351349)
			(xy 398.68375 -80.302206) (xy 398.75712 -80.259846) (xy 398.834185 -80.224651) (xy 398.914247 -80.196942)
			(xy 398.99658 -80.176968) (xy 399.080439 -80.164911) (xy 399.165064 -80.16088) (xy 399.249689 -80.164911)
			(xy 399.333548 -80.176968) (xy 399.415881 -80.196942) (xy 399.495943 -80.224651) (xy 399.573008 -80.259846)
			(xy 399.646378 -80.302206) (xy 399.71539 -80.351349) (xy 399.779418 -80.40683) (xy 399.837883 -80.468145)
			(xy 399.890254 -80.534741) (xy 399.936057 -80.606013) (xy 399.974879 -80.681316) (xy 400.006367 -80.759968)
			(xy 400.030235 -80.841258) (xy 400.046269 -80.924448) (xy 400.054322 -81.008785) (xy 400.054826 -81.051146)
			(xy 400.054322 -81.093507) (xy 400.046269 -81.177844) (xy 400.030235 -81.261034) (xy 400.006367 -81.342324)
			(xy 399.974879 -81.420976) (xy 399.936057 -81.496279) (xy 399.890254 -81.567551) (xy 399.837883 -81.634147)
			(xy 399.779418 -81.695462) (xy 399.71539 -81.750943) (xy 399.646378 -81.800086) (xy 399.573008 -81.842446)
			(xy 399.495943 -81.877641) (xy 399.415881 -81.90535) (xy 399.333548 -81.925324) (xy 399.249689 -81.937381)
			(xy 399.165064 -81.941413) (xy 399.080439 -81.937381) (xy 398.99658 -81.925324) (xy 398.914247 -81.90535)
			(xy 398.834185 -81.877641) (xy 398.75712 -81.842446) (xy 398.68375 -81.800086) (xy 398.614738 -81.750943)
			(xy 398.55071 -81.695462) (xy 398.492245 -81.634147) (xy 398.439874 -81.567551) (xy 398.394071 -81.496279)
			(xy 398.355249 -81.420976) (xy 398.323761 -81.342324) (xy 398.299893 -81.261034) (xy 398.283859 -81.177844)
			(xy 398.275806 -81.093507) (xy 241.135929 -81.093507) (xy 241.146907 -81.186846) (xy 241.162948 -81.391942)
			(xy 241.170974 -81.597509) (xy 241.171476 -81.70037) (xy 241.170974 -81.803231) (xy 241.162948 -82.008798)
			(xy 241.146907 -82.213894) (xy 241.122877 -82.418208) (xy 241.090893 -82.62143) (xy 241.051004 -82.823248)
			(xy 241.003272 -83.023357) (xy 240.947769 -83.221451) (xy 240.884579 -83.417229) (xy 240.813798 -83.610392)
			(xy 240.735536 -83.800647) (xy 240.649909 -83.987703) (xy 240.55705 -84.171276) (xy 240.457099 -84.351086)
			(xy 240.350209 -84.526859) (xy 240.236542 -84.698329) (xy 240.116272 -84.865232) (xy 239.989581 -85.027317)
			(xy 239.856663 -85.184335) (xy 239.71772 -85.336047) (xy 239.572963 -85.482223) (xy 239.422613 -85.62264)
			(xy 239.2669 -85.757083) (xy 239.106059 -85.885349) (xy 238.940337 -86.007242) (xy 238.769984 -86.122577)
			(xy 238.595262 -86.231177) (xy 238.416436 -86.332877) (xy 238.233777 -86.427523) (xy 238.047566 -86.51497)
			(xy 237.858084 -86.595086) (xy 237.66562 -86.667747) (xy 237.470468 -86.732844) (xy 237.272925 -86.790278)
			(xy 237.073292 -86.83996) (xy 236.871872 -86.881815) (xy 236.668972 -86.91578) (xy 236.464902 -86.941803)
			(xy 236.259972 -86.959844) (xy 236.054494 -86.969876) (xy 235.848781 -86.971883) (xy 235.643146 -86.965863)
			(xy 235.437903 -86.951824) (xy 235.233364 -86.929787) (xy 235.02984 -86.899788) (xy 234.827642 -86.86187)
			(xy 234.627077 -86.816093) (xy 234.428451 -86.762525) (xy 234.232066 -86.701248) (xy 234.038222 -86.632355)
			(xy 233.847212 -86.555952) (xy 233.65933 -86.472155) (xy 233.47486 -86.381091) (xy 233.294083 -86.2829)
			(xy 233.117275 -86.177729) (xy 232.944705 -86.065741) (xy 232.776636 -85.947104) (xy 232.613323 -85.822001)
			(xy 232.455016 -85.690621) (xy 232.301955 -85.553165) (xy 232.154374 -85.409841) (xy 232.012497 -85.260869)
			(xy 231.87654 -85.106474) (xy 231.746711 -84.946893) (xy 231.623207 -84.782367) (xy 231.506216 -84.613148)
			(xy 231.395917 -84.439494) (xy 231.292476 -84.261668) (xy 231.196053 -84.079942) (xy 231.106793 -83.894592)
			(xy 231.024833 -83.705901) (xy 230.950297 -83.514156) (xy 230.883299 -83.319648) (xy 230.823941 -83.122675)
			(xy 230.772314 -82.923536) (xy 230.728495 -82.722534) (xy 230.692552 -82.519975) (xy 230.664539 -82.316168)
			(xy 230.6445 -82.111424) (xy 230.632464 -81.906054) (xy 230.62845 -81.70037) (xy 57.658 -81.70037)
			(xy 57.658 -84.065147) (xy 218.29831 -84.065147) (xy 218.29831 -84.010653) (xy 218.306065 -83.956712)
			(xy 218.321417 -83.904424) (xy 218.344054 -83.854854) (xy 218.373515 -83.809009) (xy 218.4092 -83.767823)
			(xy 218.450383 -83.732134) (xy 218.496225 -83.70267) (xy 218.545794 -83.680029) (xy 218.598081 -83.664672)
			(xy 218.652021 -83.656912) (xy 218.679268 -83.656424) (xy 219.542868 -83.656424) (xy 219.570125 -83.656821)
			(xy 219.624084 -83.664575) (xy 219.67639 -83.679929) (xy 219.725978 -83.702572) (xy 219.771839 -83.732041)
			(xy 219.813039 -83.767738) (xy 219.848739 -83.808935) (xy 219.878213 -83.854794) (xy 219.90086 -83.90438)
			(xy 219.916219 -83.956685) (xy 219.923977 -84.010643) (xy 219.923977 -84.065157) (xy 219.916219 -84.119115)
			(xy 219.90086 -84.17142) (xy 219.878213 -84.221006) (xy 219.848739 -84.266865) (xy 219.813039 -84.308062)
			(xy 219.771839 -84.343759) (xy 219.725978 -84.373228) (xy 219.67639 -84.395871) (xy 219.624084 -84.411225)
			(xy 219.570125 -84.418979) (xy 219.542868 -84.41944) (xy 218.679268 -84.41944) (xy 218.652021 -84.418888)
			(xy 218.598081 -84.411128) (xy 218.545794 -84.395771) (xy 218.496225 -84.37313) (xy 218.450383 -84.343666)
			(xy 218.4092 -84.307977) (xy 218.373515 -84.266791) (xy 218.344054 -84.220946) (xy 218.321417 -84.171376)
			(xy 218.306065 -84.119088) (xy 218.29831 -84.065147) (xy 57.658 -84.065147) (xy 57.658 -86.948548)
			(xy 217.344518 -86.948548) (xy 217.344518 -86.894052) (xy 217.352274 -86.84011) (xy 217.367627 -86.787821)
			(xy 217.390266 -86.738249) (xy 217.419729 -86.692404) (xy 217.455416 -86.651218) (xy 217.496602 -86.61553)
			(xy 217.542447 -86.586067) (xy 217.592019 -86.563428) (xy 217.644308 -86.548074) (xy 217.69825 -86.540318)
			(xy 217.725498 -86.539832) (xy 218.589098 -86.539832) (xy 218.616354 -86.540215) (xy 218.670311 -86.547972)
			(xy 218.722614 -86.56333) (xy 218.7722 -86.585975) (xy 218.818058 -86.615446) (xy 218.859255 -86.651143)
			(xy 218.894953 -86.69234) (xy 218.924424 -86.738198) (xy 218.947069 -86.787784) (xy 218.962427 -86.840087)
			(xy 218.970185 -86.894044) (xy 218.970185 -86.948556) (xy 218.962427 -87.002513) (xy 218.947069 -87.054816)
			(xy 218.924424 -87.104402) (xy 218.894953 -87.15026) (xy 218.859255 -87.191457) (xy 218.818058 -87.227154)
			(xy 218.7722 -87.256625) (xy 218.722614 -87.27927) (xy 218.670311 -87.294628) (xy 218.616354 -87.302385)
			(xy 218.589098 -87.302848) (xy 217.725498 -87.302848) (xy 217.69825 -87.302282) (xy 217.644308 -87.294526)
			(xy 217.592019 -87.279172) (xy 217.542447 -87.256533) (xy 217.496602 -87.22707) (xy 217.455416 -87.191382)
			(xy 217.419729 -87.150196) (xy 217.390266 -87.104351) (xy 217.367627 -87.054779) (xy 217.352274 -87.00249)
			(xy 217.344518 -86.948548) (xy 57.658 -86.948548) (xy 57.658 -90.64371) (xy 57.658425 -90.653779)
			(xy 57.666142 -90.672381) (xy 57.672986 -90.679778) (xy 62.7888 -95.795592) (xy 62.814454 -95.802704)
			(xy 62.827662 -95.799402) (xy 62.848963 -95.794388) (xy 62.892395 -95.789035) (xy 62.914276 -95.788734)
			(xy 62.939035 -95.789157) (xy 62.988078 -95.796008) (xy 63.035701 -95.809581) (xy 63.080986 -95.829615)
			(xy 63.102236 -95.842328) (xy 63.10834 -95.845836) (xy 63.12187 -95.849714) (xy 63.128906 -95.849948)
			(xy 63.334646 -95.849948) (xy 63.341684 -95.84972) (xy 63.355214 -95.845843) (xy 63.361316 -95.842328)
			(xy 63.385647 -95.827864) (xy 63.437849 -95.805987) (xy 63.492853 -95.792637) (xy 63.549276 -95.78815)
			(xy 63.605699 -95.792637) (xy 63.660703 -95.805987) (xy 63.712905 -95.827864) (xy 63.737236 -95.842328)
			(xy 63.74334 -95.845836) (xy 63.75687 -95.849714) (xy 63.763906 -95.849948) (xy 64.477646 -95.849948)
			(xy 64.484684 -95.84972) (xy 64.498214 -95.845843) (xy 64.504316 -95.842328) (xy 64.528647 -95.827864)
			(xy 64.580849 -95.805987) (xy 64.635853 -95.792637) (xy 64.692276 -95.78815) (xy 64.748699 -95.792637)
			(xy 64.803703 -95.805987) (xy 64.855905 -95.827864) (xy 64.880236 -95.842328) (xy 64.88634 -95.845836)
			(xy 64.89987 -95.849714) (xy 64.906906 -95.849948) (xy 103.886 -95.849948) (xy 103.91096 -95.850519)
			(xy 103.959921 -95.86026) (xy 104.00604 -95.879367) (xy 104.047544 -95.907105) (xy 104.065578 -95.92437)
			(xy 130.506216 -122.365008) (xy 130.513616 -122.371851) (xy 130.532214 -122.379579) (xy 130.542284 -122.379994)
			(xy 141.457172 -122.379994) (xy 141.483842 -122.36069) (xy 141.488922 -122.344688) (xy 141.497393 -122.319602)
			(xy 141.520706 -122.272064) (xy 141.550803 -122.228503) (xy 141.587019 -122.18988) (xy 141.628555 -122.157046)
			(xy 141.674497 -122.130726) (xy 141.723829 -122.1115) (xy 141.775465 -122.099792) (xy 141.828266 -122.095861)
			(xy 141.881067 -122.099792) (xy 141.932703 -122.1115) (xy 141.982035 -122.130726) (xy 142.027977 -122.157046)
			(xy 142.069513 -122.18988) (xy 142.105729 -122.228503) (xy 142.135826 -122.272064) (xy 142.159139 -122.319602)
			(xy 142.16761 -122.344688) (xy 142.17269 -122.36069) (xy 142.19936 -122.379994) (xy 156.121862 -122.379994)
			(xy 156.146816 -122.380611) (xy 156.195764 -122.390359) (xy 156.24187 -122.409467) (xy 156.283362 -122.437203)
			(xy 156.30144 -122.454416) (xy 161.558986 -127.711962) (xy 161.566387 -127.718799) (xy 161.584986 -127.726508)
			(xy 161.595054 -127.726948) (xy 162.926268 -127.726948)
		)
		(stroke
			(width 0)
			(type solid)
		)
		(fill yes)
		(layer "In8.Cu")
		(net "P3V3")
	)
	(gr_poly
		(pts
			(xy 124.278644 -251.50064) (xy 124.290582 -251.493274) (xy 124.310303 -251.481541) (xy 124.352291 -251.46303)
			(xy 124.396433 -251.45049) (xy 124.441882 -251.444161) (xy 124.464826 -251.443744) (xy 124.479812 -251.443998)
			(xy 124.49429 -251.44476) (xy 124.518928 -251.431298) (xy 124.663708 -251.18187) (xy 124.6632 -251.153676)
			(xy 124.65558 -251.141738) (xy 124.643374 -251.121768) (xy 124.624094 -251.07912) (xy 124.611017 -251.034181)
			(xy 124.604402 -250.987847) (xy 124.604018 -250.964446) (xy 124.604498 -250.938455) (xy 124.612623 -250.887113)
			(xy 124.628682 -250.837674) (xy 124.652278 -250.791356) (xy 124.682829 -250.7493) (xy 124.719585 -250.712542)
			(xy 124.761639 -250.681988) (xy 124.807955 -250.65839) (xy 124.857393 -250.642328) (xy 124.908735 -250.634199)
			(xy 124.934726 -250.633738) (xy 124.958053 -250.634158) (xy 125.004241 -250.640746) (xy 125.049048 -250.653746)
			(xy 125.09159 -250.6729) (xy 125.11151 -250.685046) (xy 125.123702 -250.692666) (xy 125.151388 -250.693174)
			(xy 126.001272 -250.20524) (xy 126.014734 -250.180856) (xy 126.014226 -250.166378) (xy 126.013972 -250.15444)
			(xy 126.014452 -250.128448) (xy 126.022578 -250.077104) (xy 126.038637 -250.027662) (xy 126.062232 -249.981342)
			(xy 126.092783 -249.939284) (xy 126.129538 -249.902522) (xy 126.171591 -249.871963) (xy 126.217907 -249.84836)
			(xy 126.267345 -249.832292) (xy 126.318688 -249.824157) (xy 126.34468 -249.823732) (xy 126.35992 -249.823986)
			(xy 126.374398 -249.824748) (xy 126.399036 -249.811286) (xy 126.543816 -249.561858) (xy 126.543308 -249.533664)
			(xy 126.535434 -249.521472) (xy 126.523262 -249.501527) (xy 126.504049 -249.458935) (xy 126.491035 -249.414059)
			(xy 126.484482 -249.367797) (xy 126.484126 -249.344434) (xy 126.484607 -249.318444) (xy 126.492734 -249.267103)
			(xy 126.508793 -249.217666) (xy 126.53239 -249.171351) (xy 126.562942 -249.129298) (xy 126.599698 -249.092542)
			(xy 126.641751 -249.06199) (xy 126.688066 -249.038393) (xy 126.737503 -249.022334) (xy 126.788844 -249.014207)
			(xy 126.814834 -249.013726) (xy 126.82982 -249.01398) (xy 126.844298 -249.014742) (xy 126.868936 -249.00128)
			(xy 127.013716 -248.751852) (xy 127.013208 -248.723658) (xy 127.005334 -248.711466) (xy 126.993162 -248.691521)
			(xy 126.97395 -248.648929) (xy 126.960937 -248.604053) (xy 126.954385 -248.557791) (xy 126.954026 -248.534428)
			(xy 126.954428 -248.510798) (xy 126.96116 -248.464019) (xy 126.974492 -248.418677) (xy 126.994151 -248.375699)
			(xy 127.006604 -248.355612) (xy 127.014478 -248.34342) (xy 127.014986 -248.315226) (xy 126.871222 -248.067322)
			(xy 126.84633 -248.05386) (xy 126.831852 -248.054622) (xy 126.814834 -248.05513) (xy 126.788842 -248.054649)
			(xy 126.737498 -248.046523) (xy 126.688058 -248.030464) (xy 126.641738 -248.006868) (xy 126.59968 -247.976317)
			(xy 126.56292 -247.939562) (xy 126.532361 -247.897509) (xy 126.508758 -247.851194) (xy 126.492691 -247.801756)
			(xy 126.484555 -247.750414) (xy 126.484126 -247.724422) (xy 126.484528 -247.700792) (xy 126.491262 -247.654013)
			(xy 126.504594 -247.608672) (xy 126.524253 -247.565694) (xy 126.536704 -247.545606) (xy 126.544578 -247.533414)
			(xy 126.545086 -247.50522) (xy 126.401576 -247.25757) (xy 126.37643 -247.243854) (xy 126.361952 -247.244616)
			(xy 126.34468 -247.245124) (xy 126.318693 -247.244613) (xy 126.267358 -247.236479) (xy 126.217928 -247.220416)
			(xy 126.171619 -247.196818) (xy 126.129571 -247.166266) (xy 126.092821 -247.129513) (xy 126.062272 -247.087464)
			(xy 126.038676 -247.041154) (xy 126.022616 -246.991722) (xy 126.014486 -246.940387) (xy 126.014486 -246.888413)
			(xy 126.022616 -246.837078) (xy 126.038676 -246.787646) (xy 126.062272 -246.741336) (xy 126.092821 -246.699287)
			(xy 126.129571 -246.662534) (xy 126.171619 -246.631982) (xy 126.217928 -246.608384) (xy 126.267358 -246.592321)
			(xy 126.318693 -246.584187) (xy 126.34468 -246.583708) (xy 126.360174 -246.583962) (xy 126.374398 -246.584724)
			(xy 126.39929 -246.571262) (xy 126.543816 -246.321834) (xy 126.543308 -246.29364) (xy 126.535688 -246.281448)
			(xy 126.523505 -246.261503) (xy 126.504261 -246.218914) (xy 126.4912 -246.174041) (xy 126.484581 -246.127777)
			(xy 126.484126 -246.10441) (xy 126.484608 -246.078421) (xy 126.492739 -246.027083) (xy 126.5088 -245.97765)
			(xy 126.532398 -245.931338) (xy 126.562951 -245.889288) (xy 126.599706 -245.852535) (xy 126.641758 -245.821986)
			(xy 126.688072 -245.798391) (xy 126.737507 -245.782333) (xy 126.788845 -245.774207) (xy 126.814834 -245.773702)
			(xy 126.830074 -245.773956) (xy 126.844298 -245.774718) (xy 126.868936 -245.761256) (xy 127.013716 -245.511828)
			(xy 127.013208 -245.483634) (xy 127.005334 -245.471442) (xy 126.993164 -245.451496) (xy 126.973955 -245.408904)
			(xy 126.960945 -245.364028) (xy 126.954396 -245.317766) (xy 126.954026 -245.294404) (xy 126.954429 -245.270774)
			(xy 126.961165 -245.223997) (xy 126.9745 -245.178657) (xy 126.994161 -245.135681) (xy 127.006604 -245.115588)
			(xy 127.014478 -245.103396) (xy 127.014986 -245.075202) (xy 126.871222 -244.827298) (xy 126.84633 -244.813836)
			(xy 126.831852 -244.814598) (xy 126.814834 -244.815106) (xy 126.788843 -244.814625) (xy 126.7375 -244.806498)
			(xy 126.688062 -244.790439) (xy 126.641744 -244.766843) (xy 126.599688 -244.736291) (xy 126.562929 -244.699537)
			(xy 126.532374 -244.657484) (xy 126.508773 -244.611168) (xy 126.492709 -244.561731) (xy 126.484577 -244.510389)
			(xy 126.484126 -244.484398) (xy 126.48453 -244.460768) (xy 126.491266 -244.413991) (xy 126.504602 -244.368652)
			(xy 126.524263 -244.325676) (xy 126.536704 -244.305582) (xy 126.544578 -244.29339) (xy 126.545086 -244.265196)
			(xy 126.401576 -244.017546) (xy 126.37643 -244.00383) (xy 126.361952 -244.004592) (xy 126.34468 -244.0051)
			(xy 126.318694 -244.004589) (xy 126.267364 -243.996456) (xy 126.217937 -243.980394) (xy 126.171631 -243.956797)
			(xy 126.129587 -243.926248) (xy 126.092839 -243.889498) (xy 126.062292 -243.847452) (xy 126.038699 -243.801145)
			(xy 126.022639 -243.751717) (xy 126.014509 -243.700386) (xy 126.014509 -243.648414) (xy 126.022639 -243.597083)
			(xy 126.038699 -243.547655) (xy 126.062292 -243.501348) (xy 126.092839 -243.459302) (xy 126.129587 -243.422552)
			(xy 126.171631 -243.392003) (xy 126.217937 -243.368406) (xy 126.267364 -243.352344) (xy 126.318694 -243.344211)
			(xy 126.34468 -243.343684) (xy 126.360174 -243.343938) (xy 126.374398 -243.3447) (xy 126.39929 -243.331238)
			(xy 126.543816 -243.08181) (xy 126.543308 -243.053616) (xy 126.535688 -243.041424) (xy 126.523501 -243.02148)
			(xy 126.504247 -242.978893) (xy 126.491175 -242.93402) (xy 126.484546 -242.887755) (xy 126.484126 -242.864386)
			(xy 126.48461 -242.838398) (xy 126.492743 -242.787064) (xy 126.508807 -242.737633) (xy 126.532406 -242.691324)
			(xy 126.562959 -242.649277) (xy 126.599714 -242.612528) (xy 126.641765 -242.581981) (xy 126.688077 -242.558389)
			(xy 126.73751 -242.542332) (xy 126.788846 -242.534206) (xy 126.814834 -242.533678) (xy 126.830074 -242.533932)
			(xy 126.844298 -242.534694) (xy 126.868936 -242.521232) (xy 127.013716 -242.271804) (xy 127.013208 -242.24361)
			(xy 127.005334 -242.231418) (xy 126.993165 -242.211472) (xy 126.973959 -242.16888) (xy 126.960953 -242.124004)
			(xy 126.954407 -242.077742) (xy 126.954026 -242.05438) (xy 126.954431 -242.030751) (xy 126.96117 -241.983974)
			(xy 126.974507 -241.938636) (xy 126.994171 -241.895662) (xy 127.006604 -241.875564) (xy 127.014478 -241.863372)
			(xy 127.014986 -241.835178) (xy 126.871222 -241.587274) (xy 126.84633 -241.573812) (xy 126.831852 -241.574574)
			(xy 126.814834 -241.575082) (xy 126.788844 -241.574601) (xy 126.737503 -241.566474) (xy 126.688065 -241.550415)
			(xy 126.641749 -241.526818) (xy 126.599695 -241.496266) (xy 126.562939 -241.459511) (xy 126.532386 -241.417458)
			(xy 126.508788 -241.371142) (xy 126.492728 -241.321705) (xy 126.484599 -241.270364) (xy 126.484126 -241.244374)
			(xy 126.484532 -241.220745) (xy 126.491271 -241.173969) (xy 126.504609 -241.128631) (xy 126.524273 -241.085658)
			(xy 126.536704 -241.065558) (xy 126.544578 -241.053366) (xy 126.545086 -241.025172) (xy 126.401576 -240.777522)
			(xy 126.37643 -240.763806) (xy 126.361952 -240.764568) (xy 126.34468 -240.765076) (xy 126.318696 -240.764565)
			(xy 126.267369 -240.756433) (xy 126.217946 -240.740372) (xy 126.171644 -240.716777) (xy 126.129603 -240.68623)
			(xy 126.092857 -240.649482) (xy 126.062313 -240.607439) (xy 126.038721 -240.561135) (xy 126.022663 -240.511711)
			(xy 126.014533 -240.460384) (xy 126.014533 -240.408416) (xy 126.022663 -240.357089) (xy 126.038721 -240.307665)
			(xy 126.062313 -240.261361) (xy 126.092857 -240.219318) (xy 126.129603 -240.18257) (xy 126.171644 -240.152023)
			(xy 126.217946 -240.128428) (xy 126.267369 -240.112367) (xy 126.318696 -240.104235) (xy 126.34468 -240.10366)
			(xy 126.360174 -240.103914) (xy 126.374398 -240.104676) (xy 126.39929 -240.091214) (xy 126.543816 -239.841786)
			(xy 126.543308 -239.813592) (xy 126.535688 -239.8014) (xy 126.523502 -239.781456) (xy 126.504251 -239.738868)
			(xy 126.491183 -239.693995) (xy 126.484557 -239.64773) (xy 126.484126 -239.624362) (xy 126.484638 -239.598378)
			(xy 126.492774 -239.54705) (xy 126.508839 -239.497627) (xy 126.532437 -239.451325) (xy 126.562988 -239.409285)
			(xy 126.599739 -239.372541) (xy 126.641786 -239.341999) (xy 126.688093 -239.318411) (xy 126.73752 -239.302357)
			(xy 126.78885 -239.294233) (xy 126.814834 -239.293654) (xy 126.830074 -239.293908) (xy 126.844298 -239.29467)
			(xy 126.868936 -239.281208) (xy 127.013716 -239.03178) (xy 127.013208 -239.003586) (xy 127.005588 -238.991394)
			(xy 126.993403 -238.97145) (xy 126.974152 -238.928862) (xy 126.961085 -238.883989) (xy 126.95446 -238.837724)
			(xy 126.954026 -238.814356) (xy 126.95428 -238.798862) (xy 126.955042 -238.784384) (xy 126.94158 -238.759746)
			(xy 126.094744 -238.273336) (xy 126.06655 -238.274098) (xy 126.054358 -238.281972) (xy 126.034198 -238.29452)
			(xy 125.99105 -238.314346) (xy 125.945514 -238.327811) (xy 125.898522 -238.334641) (xy 125.87478 -238.335058)
			(xy 125.84879 -238.334547) (xy 125.79745 -238.326413) (xy 125.748015 -238.310347) (xy 125.701701 -238.286747)
			(xy 125.659649 -238.256192) (xy 125.622895 -238.219435) (xy 125.592343 -238.177382) (xy 125.568745 -238.131067)
			(xy 125.552683 -238.08163) (xy 125.544552 -238.03029) (xy 125.544552 -237.97831) (xy 125.552683 -237.92697)
			(xy 125.568745 -237.877533) (xy 125.592343 -237.831218) (xy 125.622895 -237.789165) (xy 125.659649 -237.752408)
			(xy 125.701701 -237.721853) (xy 125.748015 -237.698253) (xy 125.79745 -237.682187) (xy 125.84879 -237.674053)
			(xy 125.87478 -237.673642) (xy 125.89002 -237.673896) (xy 125.904244 -237.674658) (xy 125.929136 -237.661196)
			(xy 126.073662 -237.411768) (xy 126.073154 -237.383574) (xy 126.065534 -237.371636) (xy 126.053329 -237.351665)
			(xy 126.034053 -237.309017) (xy 126.020977 -237.264078) (xy 126.014364 -237.217745) (xy 126.013972 -237.194344)
			(xy 126.014452 -237.168352) (xy 126.022577 -237.117007) (xy 126.038636 -237.067565) (xy 126.062231 -237.021244)
			(xy 126.092782 -236.979185) (xy 126.129536 -236.942423) (xy 126.17159 -236.911864) (xy 126.217906 -236.88826)
			(xy 126.267344 -236.872192) (xy 126.318688 -236.864057) (xy 126.34468 -236.863636) (xy 126.35992 -236.86389)
			(xy 126.374144 -236.864652) (xy 126.399036 -236.85119) (xy 126.543816 -236.601762) (xy 126.543308 -236.573568)
			(xy 126.535434 -236.561376) (xy 126.523262 -236.541431) (xy 126.504048 -236.498839) (xy 126.491034 -236.453964)
			(xy 126.48448 -236.407701) (xy 126.484126 -236.384338) (xy 126.484527 -236.360707) (xy 126.491258 -236.313928)
			(xy 126.504589 -236.268585) (xy 126.524247 -236.225606) (xy 126.536704 -236.205522) (xy 126.544578 -236.19333)
			(xy 126.545086 -236.165136) (xy 126.401576 -235.917486) (xy 126.37643 -235.90377) (xy 126.361952 -235.904532)
			(xy 126.34468 -235.90504) (xy 126.318691 -235.904529) (xy 126.267354 -235.896395) (xy 126.217922 -235.880331)
			(xy 126.17161 -235.856732) (xy 126.129561 -235.826178) (xy 126.092809 -235.789424) (xy 126.062258 -235.747372)
			(xy 126.038662 -235.70106) (xy 126.0226 -235.651626) (xy 126.01447 -235.600289) (xy 126.01447 -235.548311)
			(xy 126.0226 -235.496974) (xy 126.038662 -235.44754) (xy 126.062258 -235.401228) (xy 126.092809 -235.359176)
			(xy 126.129561 -235.322422) (xy 126.17161 -235.291868) (xy 126.217922 -235.268269) (xy 126.267354 -235.252205)
			(xy 126.318691 -235.244071) (xy 126.34468 -235.243624) (xy 126.360174 -235.243878) (xy 126.374398 -235.24464)
			(xy 126.39929 -235.231178) (xy 126.543816 -234.98175) (xy 126.543308 -234.953556) (xy 126.535688 -234.941364)
			(xy 126.523504 -234.92142) (xy 126.504258 -234.878831) (xy 126.491194 -234.833958) (xy 126.484574 -234.787693)
			(xy 126.484126 -234.764326) (xy 126.484607 -234.738336) (xy 126.492735 -234.686997) (xy 126.508796 -234.637561)
			(xy 126.532393 -234.591246) (xy 126.562945 -234.549194) (xy 126.5997 -234.51244) (xy 126.641753 -234.481889)
			(xy 126.688068 -234.458293) (xy 126.737504 -234.442234) (xy 126.788844 -234.434107) (xy 126.814834 -234.433618)
			(xy 126.830074 -234.433872) (xy 126.844298 -234.434634) (xy 126.868936 -234.421172) (xy 127.013716 -234.171744)
			(xy 127.013208 -234.14355) (xy 127.005334 -234.131358) (xy 126.993163 -234.111413) (xy 126.973951 -234.068821)
			(xy 126.96094 -234.023945) (xy 126.954389 -233.977682) (xy 126.954026 -233.95432) (xy 126.954428 -233.93069)
			(xy 126.961162 -233.883911) (xy 126.974495 -233.83857) (xy 126.994154 -233.795593) (xy 127.006604 -233.775504)
			(xy 127.014478 -233.763312) (xy 127.014986 -233.735118) (xy 126.871222 -233.487214) (xy 126.84633 -233.473752)
			(xy 126.831852 -233.474514) (xy 126.814834 -233.475022) (xy 126.788843 -233.474541) (xy 126.737499 -233.466415)
			(xy 126.688059 -233.450355) (xy 126.64174 -233.42676) (xy 126.599683 -233.396208) (xy 126.562923 -233.359454)
			(xy 126.532365 -233.317401) (xy 126.508763 -233.271085) (xy 126.492697 -233.221648) (xy 126.484562 -233.170305)
			(xy 126.484126 -233.144314) (xy 126.484529 -233.120684) (xy 126.491263 -233.073906) (xy 126.504597 -233.028565)
			(xy 126.524256 -232.985588) (xy 126.536704 -232.965498) (xy 126.544578 -232.953306) (xy 126.545086 -232.925112)
			(xy 126.401576 -232.677462) (xy 126.37643 -232.663746) (xy 126.361952 -232.664508) (xy 126.34468 -232.665016)
			(xy 126.318693 -232.664505) (xy 126.26736 -232.656372) (xy 126.217931 -232.640309) (xy 126.171623 -232.616711)
			(xy 126.129577 -232.58616) (xy 126.092827 -232.549408) (xy 126.062278 -232.50736) (xy 126.038684 -232.461051)
			(xy 126.022624 -232.411621) (xy 126.014493 -232.360287) (xy 126.014493 -232.308313) (xy 126.022624 -232.256979)
			(xy 126.038684 -232.207549) (xy 126.062278 -232.16124) (xy 126.092827 -232.119192) (xy 126.129577 -232.08244)
			(xy 126.171623 -232.051889) (xy 126.217931 -232.028291) (xy 126.26736 -232.012228) (xy 126.318693 -232.004095)
			(xy 126.34468 -232.0036) (xy 126.35992 -232.003854) (xy 126.374398 -232.004616) (xy 126.399036 -231.991154)
			(xy 126.543816 -231.741726) (xy 126.543308 -231.713532) (xy 126.535434 -231.70134) (xy 126.523264 -231.681394)
			(xy 126.504055 -231.638802) (xy 126.491046 -231.593926) (xy 126.484497 -231.547664) (xy 126.484126 -231.524302)
			(xy 126.48453 -231.500672) (xy 126.491266 -231.453895) (xy 126.5046 -231.408555) (xy 126.524261 -231.365579)
			(xy 126.536704 -231.345486) (xy 126.544578 -231.333294) (xy 126.545086 -231.3051) (xy 126.401576 -231.057704)
			(xy 126.37643 -231.043988) (xy 126.362206 -231.04475) (xy 126.34468 -231.045258) (xy 126.31869 -231.044747)
			(xy 126.26735 -231.036613) (xy 126.217915 -231.020547) (xy 126.171601 -230.996947) (xy 126.129549 -230.966392)
			(xy 126.092795 -230.929635) (xy 126.062243 -230.887582) (xy 126.038645 -230.841267) (xy 126.022583 -230.79183)
			(xy 126.014452 -230.74049) (xy 126.014452 -230.68851) (xy 126.022583 -230.63717) (xy 126.038645 -230.587733)
			(xy 126.062243 -230.541418) (xy 126.092795 -230.499365) (xy 126.129549 -230.462608) (xy 126.171601 -230.432053)
			(xy 126.217915 -230.408453) (xy 126.26735 -230.392387) (xy 126.31869 -230.384253) (xy 126.34468 -230.383842)
			(xy 126.35992 -230.384096) (xy 126.374144 -230.384858) (xy 126.399036 -230.371396) (xy 126.543816 -230.121714)
			(xy 126.543308 -230.09352) (xy 126.535434 -230.081328) (xy 126.523265 -230.061382) (xy 126.504057 -230.01879)
			(xy 126.49105 -229.973914) (xy 126.484503 -229.927652) (xy 126.484126 -229.90429) (xy 126.48453 -229.88066)
			(xy 126.491268 -229.833884) (xy 126.504604 -229.788545) (xy 126.524266 -229.74557) (xy 126.536704 -229.725474)
			(xy 126.544578 -229.713282) (xy 126.545086 -229.685088) (xy 126.401576 -229.437692) (xy 126.37643 -229.423976)
			(xy 126.362206 -229.424738) (xy 126.34468 -229.425246) (xy 126.318691 -229.424735) (xy 126.267353 -229.416601)
			(xy 126.217919 -229.400536) (xy 126.171607 -229.376937) (xy 126.129557 -229.346383) (xy 126.092804 -229.309628)
			(xy 126.062253 -229.267576) (xy 126.038656 -229.221262) (xy 126.022594 -229.171828) (xy 126.014464 -229.120489)
			(xy 126.014464 -229.068511) (xy 126.022594 -229.017172) (xy 126.038656 -228.967738) (xy 126.062253 -228.921424)
			(xy 126.092804 -228.879372) (xy 126.129557 -228.842617) (xy 126.171607 -228.812063) (xy 126.217919 -228.788464)
			(xy 126.267353 -228.772399) (xy 126.318691 -228.764265) (xy 126.34468 -228.76383) (xy 126.35992 -228.764084)
			(xy 126.374144 -228.764846) (xy 126.399036 -228.751384) (xy 126.543816 -228.501956) (xy 126.543308 -228.473762)
			(xy 126.535434 -228.46157) (xy 126.523262 -228.441625) (xy 126.504049 -228.399033) (xy 126.491036 -228.354157)
			(xy 126.484483 -228.307895) (xy 126.484126 -228.284532) (xy 126.484607 -228.258542) (xy 126.492734 -228.207202)
			(xy 126.508794 -228.157765) (xy 126.532391 -228.11145) (xy 126.562943 -228.069397) (xy 126.599698 -228.032642)
			(xy 126.641752 -228.00209) (xy 126.688067 -227.978493) (xy 126.737504 -227.962434) (xy 126.788844 -227.954307)
			(xy 126.814834 -227.953824) (xy 126.84034 -227.954291) (xy 126.890747 -227.962112) (xy 126.939357 -227.977579)
			(xy 126.985015 -228.000325) (xy 127.026641 -228.029811) (xy 127.063246 -228.065338) (xy 127.093963 -228.106064)
			(xy 127.106426 -228.128322) (xy 127.11303 -228.141022) (xy 127.136906 -228.155246) (xy 127.432562 -228.155246)
			(xy 127.456438 -228.141022) (xy 127.463042 -228.128322) (xy 127.475515 -228.106073) (xy 127.506241 -228.065363)
			(xy 127.54285 -228.029848) (xy 127.584474 -228.000372) (xy 127.630128 -227.977631) (xy 127.678731 -227.962165)
			(xy 127.729132 -227.954339) (xy 127.780136 -227.954339) (xy 127.830537 -227.962165) (xy 127.87914 -227.977631)
			(xy 127.924794 -228.000372) (xy 127.966418 -228.029848) (xy 128.003027 -228.065363) (xy 128.033753 -228.106073)
			(xy 128.046226 -228.128322) (xy 128.05283 -228.141022) (xy 128.076706 -228.155246) (xy 128.372616 -228.155246)
			(xy 128.396492 -228.141022) (xy 128.403096 -228.128322) (xy 128.415572 -228.106074) (xy 128.446301 -228.065365)
			(xy 128.482911 -228.029851) (xy 128.524534 -228.000371) (xy 128.570186 -227.977624) (xy 128.618786 -227.962148)
			(xy 128.669186 -227.954308) (xy 128.694688 -227.953824) (xy 128.709928 -227.954078) (xy 128.724152 -227.95484)
			(xy 128.749044 -227.941378) (xy 128.893824 -227.69195) (xy 128.893062 -227.663756) (xy 128.885442 -227.651564)
			(xy 128.873274 -227.631618) (xy 128.854067 -227.589025) (xy 128.841058 -227.544149) (xy 128.834508 -227.497888)
			(xy 128.834134 -227.474526) (xy 128.834615 -227.448537) (xy 128.842743 -227.397197) (xy 128.858804 -227.347762)
			(xy 128.882401 -227.301448) (xy 128.912953 -227.259397) (xy 128.949709 -227.222643) (xy 128.991762 -227.192093)
			(xy 129.038077 -227.168498) (xy 129.087513 -227.15244) (xy 129.138853 -227.144314) (xy 129.164842 -227.143818)
			(xy 129.179828 -227.144072) (xy 129.194306 -227.144834) (xy 129.218944 -227.131372) (xy 129.363724 -226.881944)
			(xy 129.363216 -226.85375) (xy 129.355342 -226.841558) (xy 129.343174 -226.821612) (xy 129.323968 -226.779019)
			(xy 129.31096 -226.734143) (xy 129.304411 -226.687882) (xy 129.304034 -226.66452) (xy 129.304516 -226.638531)
			(xy 129.312645 -226.587192) (xy 129.328706 -226.537758) (xy 129.352303 -226.491445) (xy 129.382856 -226.449394)
			(xy 129.419611 -226.412641) (xy 129.461664 -226.382092) (xy 129.507978 -226.358497) (xy 129.557414 -226.34244)
			(xy 129.608753 -226.334314) (xy 129.634742 -226.333812) (xy 129.649982 -226.334066) (xy 129.664206 -226.334828)
			(xy 129.689098 -226.321366) (xy 129.833624 -226.071938) (xy 129.833116 -226.043744) (xy 129.825496 -226.031806)
			(xy 129.813295 -226.011834) (xy 129.794024 -225.969185) (xy 129.780954 -225.924246) (xy 129.774345 -225.877914)
			(xy 129.773934 -225.854514) (xy 129.774416 -225.828525) (xy 129.782546 -225.777187) (xy 129.798607 -225.727754)
			(xy 129.822205 -225.681442) (xy 129.852758 -225.639392) (xy 129.889513 -225.60264) (xy 129.931566 -225.57209)
			(xy 129.97788 -225.548497) (xy 130.027315 -225.532439) (xy 130.078653 -225.524314) (xy 130.104642 -225.523806)
			(xy 130.119882 -225.52406) (xy 130.134106 -225.524822) (xy 130.158998 -225.51136) (xy 130.303778 -225.261932)
			(xy 130.303016 -225.233738) (xy 130.295396 -225.221546) (xy 130.283227 -225.2016) (xy 130.264019 -225.159008)
			(xy 130.251011 -225.114132) (xy 130.244462 -225.06787) (xy 130.244088 -225.044508) (xy 130.244571 -225.018518)
			(xy 130.252701 -224.967178) (xy 130.268762 -224.917743) (xy 130.292359 -224.871428) (xy 130.322911 -224.829375)
			(xy 130.359666 -224.792619) (xy 130.401718 -224.762066) (xy 130.448031 -224.738467) (xy 130.497467 -224.722404)
			(xy 130.548806 -224.714271) (xy 130.574796 -224.7138) (xy 130.589782 -224.714054) (xy 130.60426 -224.714816)
			(xy 130.628898 -224.701354) (xy 130.773678 -224.451926) (xy 130.77317 -224.423732) (xy 130.76555 -224.41154)
			(xy 130.75336 -224.391598) (xy 130.7341 -224.349011) (xy 130.721024 -224.304138) (xy 130.714391 -224.257871)
			(xy 130.713988 -224.234502) (xy 130.714497 -224.208515) (xy 130.722628 -224.15718) (xy 130.738688 -224.107749)
			(xy 130.762284 -224.061439) (xy 130.792834 -224.01939) (xy 130.829585 -223.982638) (xy 130.871633 -223.952087)
			(xy 130.917943 -223.928491) (xy 130.967374 -223.912429) (xy 131.018709 -223.904298) (xy 131.044696 -223.903794)
			(xy 131.059936 -223.904048) (xy 131.07416 -223.90481) (xy 131.099052 -223.891348) (xy 131.243832 -223.64192)
			(xy 131.24307 -223.613726) (xy 131.23545 -223.601534) (xy 131.223283 -223.581587) (xy 131.20408 -223.538994)
			(xy 131.191075 -223.494119) (xy 131.184529 -223.447857) (xy 131.184142 -223.424496) (xy 131.184645 -223.398617)
			(xy 131.192714 -223.347493) (xy 131.208656 -223.298252) (xy 131.232079 -223.252098) (xy 131.262412 -223.21016)
			(xy 131.298911 -223.173464) (xy 131.340686 -223.142907) (xy 131.363466 -223.130618) (xy 131.376166 -223.124014)
			(xy 131.390898 -223.099884) (xy 131.390898 -222.129096) (xy 131.376166 -222.104966) (xy 131.363466 -222.098362)
			(xy 131.340682 -222.086079) (xy 131.298909 -222.055521) (xy 131.26241 -222.018824) (xy 131.232079 -221.976885)
			(xy 131.208658 -221.93073) (xy 131.192719 -221.881488) (xy 131.184652 -221.830363) (xy 131.184142 -221.804484)
			(xy 131.184669 -221.777238) (xy 131.193557 -221.723477) (xy 131.211155 -221.671905) (xy 131.236984 -221.623925)
			(xy 131.25323 -221.602046) (xy 131.258139 -221.595259) (xy 131.26358 -221.579428) (xy 131.263898 -221.571058)
			(xy 131.263898 -217.924888) (xy 131.24307 -217.897456) (xy 131.22656 -217.892884) (xy 131.200314 -217.885224)
			(xy 131.150376 -217.862969) (xy 131.104429 -217.833339) (xy 131.063554 -217.797029) (xy 131.028713 -217.754896)
			(xy 131.000726 -217.707929) (xy 130.980252 -217.657235) (xy 130.967772 -217.604005) (xy 130.96358 -217.549494)
			(xy 130.967774 -217.494982) (xy 130.980256 -217.441753) (xy 131.000732 -217.39106) (xy 131.02872 -217.344094)
			(xy 131.063563 -217.301962) (xy 131.104439 -217.265654) (xy 131.150387 -217.236025) (xy 131.200326 -217.213772)
			(xy 131.22656 -217.206068) (xy 131.24307 -217.201496) (xy 131.263898 -217.174064) (xy 131.263898 -211.935314)
			(xy 131.263459 -211.925251) (xy 131.255722 -211.906669) (xy 131.248912 -211.899246) (xy 111.747808 -192.398142)
			(xy 111.730547 -192.380102) (xy 111.702786 -192.338609) (xy 111.683672 -192.292491) (xy 111.67394 -192.243526)
			(xy 111.673386 -192.218564) (xy 111.673386 -187.59424) (xy 111.672952 -187.584175) (xy 111.66522 -187.565588)
			(xy 111.6584 -187.558172) (xy 111.422688 -187.32246) (xy 111.415292 -187.315609) (xy 111.396693 -187.307869)
			(xy 111.38662 -187.307474) (xy 111.161576 -187.307474) (xy 111.155059 -187.307705) (xy 111.142456 -187.311042)
			(xy 111.136684 -187.314078) (xy 111.112118 -187.327269) (xy 111.060032 -187.347172) (xy 111.005604 -187.359285)
			(xy 110.949994 -187.363352) (xy 110.894384 -187.359285) (xy 110.839956 -187.347172) (xy 110.78787 -187.327269)
			(xy 110.763304 -187.314078) (xy 110.75754 -187.311019) (xy 110.744934 -187.307666) (xy 110.738412 -187.307474)
			(xy 104.547416 -187.307474) (xy 104.537366 -187.30798) (xy 104.518806 -187.315703) (xy 104.511348 -187.32246)
			(xy 100.654358 -191.17945) (xy 100.636317 -191.196709) (xy 100.594823 -191.224466) (xy 100.548705 -191.243579)
			(xy 100.499741 -191.253312) (xy 100.47478 -191.253872) (xy 78.573884 -191.253872) (xy 78.548924 -191.253299)
			(xy 78.499965 -191.243557) (xy 78.453847 -191.224449) (xy 78.412344 -191.196711) (xy 78.394306 -191.17945)
			(xy 73.663556 -186.4487) (xy 73.656155 -186.44186) (xy 73.637557 -186.434142) (xy 73.627488 -186.433714)
			(xy 71.830692 -186.433714) (xy 71.805736 -186.433102) (xy 71.756782 -186.423363) (xy 71.710669 -186.404262)
			(xy 71.669167 -186.376532) (xy 71.651114 -186.359292) (xy 69.456808 -184.164986) (xy 69.439543 -184.146947)
			(xy 69.411775 -184.105456) (xy 69.392653 -184.059337) (xy 69.382913 -184.010371) (xy 69.382386 -183.985408)
			(xy 69.382386 -181.676802) (xy 69.381963 -181.666732) (xy 69.374247 -181.648128) (xy 69.3674 -181.640734)
			(xy 67.895216 -180.16855) (xy 67.887816 -180.161711) (xy 67.869217 -180.153999) (xy 67.859148 -180.153564)
			(xy 60.618624 -180.153564) (xy 60.608561 -180.154003) (xy 60.589983 -180.161744) (xy 60.582556 -180.16855)
			(xy 60.395866 -180.35524) (xy 60.389019 -180.362637) (xy 60.381288 -180.381236) (xy 60.38088 -180.391308)
			(xy 60.38088 -202.52182) (xy 60.381306 -202.531889) (xy 60.389023 -202.55049) (xy 60.395866 -202.557888)
			(xy 65.337436 -207.499458) (xy 97.408492 -207.499458) (xy 97.408492 -206.635858) (xy 97.408978 -206.608589)
			(xy 97.41674 -206.554605) (xy 97.432105 -206.502275) (xy 97.454762 -206.452665) (xy 97.484248 -206.406784)
			(xy 97.519963 -206.365567) (xy 97.56118 -206.329852) (xy 97.607061 -206.300366) (xy 97.656671 -206.277709)
			(xy 97.709001 -206.262344) (xy 97.762985 -206.254582) (xy 97.817523 -206.254582) (xy 97.871507 -206.262344)
			(xy 97.923837 -206.277709) (xy 97.973447 -206.300366) (xy 98.019328 -206.329852) (xy 98.060545 -206.365567)
			(xy 98.09626 -206.406784) (xy 98.125746 -206.452665) (xy 98.148403 -206.502275) (xy 98.163768 -206.554605)
			(xy 98.17153 -206.608589) (xy 98.172016 -206.635858) (xy 98.172016 -207.499458) (xy 98.17153 -207.526727)
			(xy 98.163768 -207.580711) (xy 98.148403 -207.633041) (xy 98.125746 -207.682651) (xy 98.09626 -207.728532)
			(xy 98.060545 -207.769749) (xy 98.019328 -207.805464) (xy 97.973447 -207.83495) (xy 97.923837 -207.857607)
			(xy 97.871507 -207.872972) (xy 97.817523 -207.880734) (xy 97.762985 -207.880734) (xy 97.709001 -207.872972)
			(xy 97.656671 -207.857607) (xy 97.607061 -207.83495) (xy 97.56118 -207.805464) (xy 97.519963 -207.769749)
			(xy 97.484248 -207.728532) (xy 97.454762 -207.682651) (xy 97.432105 -207.633041) (xy 97.41674 -207.580711)
			(xy 97.408978 -207.526727) (xy 97.408492 -207.499458) (xy 65.337436 -207.499458) (xy 66.861436 -209.023458)
			(xy 94.105984 -209.023458) (xy 94.105984 -208.159858) (xy 94.10647 -208.132589) (xy 94.114232 -208.078605)
			(xy 94.129597 -208.026275) (xy 94.152254 -207.976665) (xy 94.18174 -207.930784) (xy 94.217455 -207.889567)
			(xy 94.258672 -207.853852) (xy 94.304553 -207.824366) (xy 94.354163 -207.801709) (xy 94.406493 -207.786344)
			(xy 94.460477 -207.778582) (xy 94.515015 -207.778582) (xy 94.568999 -207.786344) (xy 94.621329 -207.801709)
			(xy 94.670939 -207.824366) (xy 94.71682 -207.853852) (xy 94.758037 -207.889567) (xy 94.793752 -207.930784)
			(xy 94.823238 -207.976665) (xy 94.845895 -208.026275) (xy 94.86126 -208.078605) (xy 94.869022 -208.132589)
			(xy 94.869508 -208.159858) (xy 94.869508 -209.023458) (xy 94.869022 -209.050727) (xy 94.86126 -209.104711)
			(xy 94.845895 -209.157041) (xy 94.823238 -209.206651) (xy 94.793752 -209.252532) (xy 94.758037 -209.293749)
			(xy 94.71682 -209.329464) (xy 94.670939 -209.35895) (xy 94.621329 -209.381607) (xy 94.568999 -209.396972)
			(xy 94.515015 -209.404734) (xy 94.460477 -209.404734) (xy 94.406493 -209.396972) (xy 94.354163 -209.381607)
			(xy 94.304553 -209.35895) (xy 94.258672 -209.329464) (xy 94.217455 -209.293749) (xy 94.18174 -209.252532)
			(xy 94.152254 -209.206651) (xy 94.129597 -209.157041) (xy 94.114232 -209.104711) (xy 94.10647 -209.050727)
			(xy 94.105984 -209.023458) (xy 66.861436 -209.023458) (xy 70.818248 -212.98027) (xy 78.812394 -212.98027)
			(xy 78.816423 -212.837949) (xy 78.828498 -212.696084) (xy 78.848579 -212.55513) (xy 78.876602 -212.415537)
			(xy 78.912478 -212.277753) (xy 78.956092 -212.14222) (xy 79.007304 -212.009371) (xy 79.06595 -211.879632)
			(xy 79.131841 -211.753419) (xy 79.204768 -211.631136) (xy 79.284496 -211.513174) (xy 79.37077 -211.399912)
			(xy 79.463314 -211.291713) (xy 79.56183 -211.188922) (xy 79.666005 -211.09187) (xy 79.775503 -211.000866)
			(xy 79.889974 -210.916204) (xy 80.009052 -210.838153) (xy 80.132355 -210.766964) (xy 80.259488 -210.702865)
			(xy 80.390044 -210.646061) (xy 80.523604 -210.596735) (xy 80.659741 -210.555043) (xy 80.798019 -210.52112)
			(xy 80.937994 -210.495075) (xy 81.079219 -210.47699) (xy 81.22124 -210.466925) (xy 81.363604 -210.46491)
			(xy 81.505854 -210.470953) (xy 81.647534 -210.485033) (xy 81.78819 -210.507107) (xy 81.927372 -210.537103)
			(xy 82.064634 -210.574925) (xy 82.199537 -210.620453) (xy 82.331648 -210.673539) (xy 82.460544 -210.734015)
			(xy 82.585812 -210.801686) (xy 82.707051 -210.876336) (xy 82.823872 -210.957725) (xy 82.935902 -211.045593)
			(xy 83.042781 -211.139659) (xy 83.144167 -211.23962) (xy 83.239736 -211.345158) (xy 83.329181 -211.455933)
			(xy 83.412215 -211.571591) (xy 83.488573 -211.691761) (xy 83.55801 -211.816059) (xy 83.620303 -211.944086)
			(xy 83.675254 -212.075433) (xy 83.698081 -212.140038) (xy 94.106492 -212.140038) (xy 94.106492 -211.276438)
			(xy 94.106978 -211.249187) (xy 94.114734 -211.195239) (xy 94.130089 -211.142944) (xy 94.152731 -211.093367)
			(xy 94.182197 -211.047517) (xy 94.217888 -211.006326) (xy 94.259079 -210.970635) (xy 94.304929 -210.941169)
			(xy 94.354506 -210.918527) (xy 94.406801 -210.903172) (xy 94.460749 -210.895416) (xy 94.515251 -210.895416)
			(xy 94.569199 -210.903172) (xy 94.621494 -210.918527) (xy 94.671071 -210.941169) (xy 94.716921 -210.970635)
			(xy 94.758112 -211.006326) (xy 94.793803 -211.047517) (xy 94.823269 -211.093367) (xy 94.845911 -211.142944)
			(xy 94.861266 -211.195239) (xy 94.869022 -211.249187) (xy 94.869508 -211.276438) (xy 94.869508 -212.140038)
			(xy 94.869022 -212.167289) (xy 94.861266 -212.221237) (xy 94.845911 -212.273532) (xy 94.823269 -212.323109)
			(xy 94.793803 -212.368959) (xy 94.758112 -212.41015) (xy 94.716921 -212.445841) (xy 94.671071 -212.475307)
			(xy 94.621494 -212.497949) (xy 94.569199 -212.513304) (xy 94.515251 -212.52106) (xy 94.460749 -212.52106)
			(xy 94.406801 -212.513304) (xy 94.354506 -212.497949) (xy 94.304929 -212.475307) (xy 94.259079 -212.445841)
			(xy 94.217888 -212.41015) (xy 94.182197 -212.368959) (xy 94.152731 -212.323109) (xy 94.130089 -212.273532)
			(xy 94.114734 -212.221237) (xy 94.106978 -212.167289) (xy 94.106492 -212.140038) (xy 83.698081 -212.140038)
			(xy 83.722686 -212.209678) (xy 83.762447 -212.346391) (xy 83.794409 -212.485135) (xy 83.818471 -212.625465)
			(xy 83.834555 -212.766931) (xy 83.842611 -212.909081) (xy 83.843114 -212.98027) (xy 83.842611 -213.051459)
			(xy 83.834555 -213.193609) (xy 83.818471 -213.335075) (xy 83.794409 -213.475405) (xy 83.762447 -213.614149)
			(xy 83.722686 -213.750862) (xy 83.675254 -213.885107) (xy 83.620303 -214.016454) (xy 83.55801 -214.144481)
			(xy 83.488573 -214.268779) (xy 83.412215 -214.388949) (xy 83.329181 -214.504607) (xy 83.239736 -214.615382)
			(xy 83.144167 -214.72092) (xy 83.042781 -214.820881) (xy 82.935902 -214.914947) (xy 82.837077 -214.992458)
			(xy 94.106492 -214.992458) (xy 94.106492 -214.128858) (xy 94.106978 -214.101607) (xy 94.114734 -214.047659)
			(xy 94.130089 -213.995364) (xy 94.152731 -213.945787) (xy 94.182197 -213.899937) (xy 94.217888 -213.858746)
			(xy 94.259079 -213.823055) (xy 94.304929 -213.793589) (xy 94.354506 -213.770947) (xy 94.406801 -213.755592)
			(xy 94.460749 -213.747836) (xy 94.515251 -213.747836) (xy 94.569199 -213.755592) (xy 94.621494 -213.770947)
			(xy 94.671071 -213.793589) (xy 94.716921 -213.823055) (xy 94.758112 -213.858746) (xy 94.793803 -213.899937)
			(xy 94.823269 -213.945787) (xy 94.845911 -213.995364) (xy 94.861266 -214.047659) (xy 94.869022 -214.101607)
			(xy 94.869508 -214.128858) (xy 94.869508 -214.992458) (xy 94.869022 -215.019709) (xy 94.861266 -215.073657)
			(xy 94.845911 -215.125952) (xy 94.823269 -215.175529) (xy 94.793803 -215.221379) (xy 94.758112 -215.26257)
			(xy 94.716921 -215.298261) (xy 94.671071 -215.327727) (xy 94.621494 -215.350369) (xy 94.569199 -215.365724)
			(xy 94.515251 -215.37348) (xy 94.460749 -215.37348) (xy 94.406801 -215.365724) (xy 94.354506 -215.350369)
			(xy 94.304929 -215.327727) (xy 94.259079 -215.298261) (xy 94.217888 -215.26257) (xy 94.182197 -215.221379)
			(xy 94.152731 -215.175529) (xy 94.130089 -215.125952) (xy 94.114734 -215.073657) (xy 94.106978 -215.019709)
			(xy 94.106492 -214.992458) (xy 82.837077 -214.992458) (xy 82.823872 -215.002815) (xy 82.707051 -215.084204)
			(xy 82.585812 -215.158854) (xy 82.460544 -215.226525) (xy 82.331648 -215.287001) (xy 82.199537 -215.340087)
			(xy 82.064634 -215.385615) (xy 81.927372 -215.423437) (xy 81.78819 -215.453433) (xy 81.647534 -215.475507)
			(xy 81.505854 -215.489587) (xy 81.363604 -215.49563) (xy 81.22124 -215.493615) (xy 81.079219 -215.48355)
			(xy 80.937994 -215.465465) (xy 80.798019 -215.43942) (xy 80.659741 -215.405497) (xy 80.523604 -215.363805)
			(xy 80.390044 -215.314479) (xy 80.259488 -215.257675) (xy 80.132355 -215.193576) (xy 80.009052 -215.122387)
			(xy 79.889974 -215.044336) (xy 79.775503 -214.959674) (xy 79.666005 -214.86867) (xy 79.56183 -214.771618)
			(xy 79.463314 -214.668827) (xy 79.37077 -214.560628) (xy 79.284496 -214.447366) (xy 79.204768 -214.329404)
			(xy 79.131841 -214.207121) (xy 79.06595 -214.080908) (xy 79.007304 -213.951169) (xy 78.956092 -213.81832)
			(xy 78.912478 -213.682787) (xy 78.876602 -213.545003) (xy 78.848579 -213.40541) (xy 78.828498 -213.264456)
			(xy 78.816423 -213.122591) (xy 78.812394 -212.98027) (xy 70.818248 -212.98027) (xy 76.838556 -219.000578)
			(xy 76.845957 -219.007418) (xy 76.864555 -219.015135) (xy 76.874624 -219.015564) (xy 84.622386 -219.015564)
			(xy 84.646483 -219.01613) (xy 84.693813 -219.02522) (xy 84.738578 -219.043075) (xy 84.779171 -219.069055)
			(xy 84.814134 -219.102227) (xy 84.828634 -219.121482) (xy 84.836296 -219.130904) (xy 84.857909 -219.141902)
			(xy 84.870036 -219.142564) (xy 92.496894 -219.142564) (xy 92.51347 -219.143126) (xy 92.545488 -219.15173)
			(xy 92.574201 -219.168306) (xy 92.586302 -219.179648) (xy 93.221302 -219.814648) (xy 93.226655 -219.820372)
			(xy 129.049982 -219.820372) (xy 129.049982 -219.765828) (xy 129.057745 -219.71184) (xy 129.073111 -219.659505)
			(xy 129.095769 -219.609891) (xy 129.125257 -219.564005) (xy 129.160975 -219.522783) (xy 129.202196 -219.487064)
			(xy 129.24808 -219.457575) (xy 129.297694 -219.434915) (xy 129.350028 -219.419547) (xy 129.404016 -219.411783)
			(xy 129.431288 -219.411296) (xy 130.447288 -219.411296) (xy 130.474557 -219.411843) (xy 130.528539 -219.419602)
			(xy 130.580867 -219.434966) (xy 130.630476 -219.45762) (xy 130.676357 -219.487104) (xy 130.717574 -219.522818)
			(xy 130.753288 -219.564034) (xy 130.782774 -219.609913) (xy 130.80543 -219.659522) (xy 130.820795 -219.711849)
			(xy 130.828557 -219.765831) (xy 130.828557 -219.820369) (xy 130.820795 -219.874351) (xy 130.80543 -219.926678)
			(xy 130.782774 -219.976287) (xy 130.753288 -220.022166) (xy 130.717574 -220.063382) (xy 130.676357 -220.099096)
			(xy 130.630476 -220.12858) (xy 130.580867 -220.151234) (xy 130.528539 -220.166598) (xy 130.474557 -220.174357)
			(xy 130.447288 -220.17482) (xy 129.431288 -220.17482) (xy 129.404016 -220.174417) (xy 129.350028 -220.166653)
			(xy 129.297694 -220.151285) (xy 129.24808 -220.128625) (xy 129.202196 -220.099136) (xy 129.160975 -220.063417)
			(xy 129.125257 -220.022195) (xy 129.095769 -219.976309) (xy 129.073111 -219.926695) (xy 129.057745 -219.87436)
			(xy 129.049982 -219.820372) (xy 93.226655 -219.820372) (xy 93.23263 -219.826761) (xy 93.249205 -219.855471)
			(xy 93.257828 -219.887482) (xy 93.258386 -219.904056) (xy 93.258386 -222.191072) (xy 93.257816 -222.207645)
			(xy 93.249198 -222.239653) (xy 93.232616 -222.268356) (xy 93.221302 -222.28048) (xy 93.146372 -222.355156)
			(xy 93.139526 -222.362554) (xy 93.131801 -222.381153) (xy 93.131386 -222.391224) (xy 93.131386 -223.678496)
			(xy 93.131808 -223.688567) (xy 93.13952 -223.707174) (xy 93.146372 -223.714564) (xy 93.200728 -223.768666)
			(xy 93.20911 -223.778064) (xy 93.318076 -223.91116) (xy 93.347032 -223.920304) (xy 93.36151 -223.915986)
			(xy 93.383419 -223.910277) (xy 93.42828 -223.904161) (xy 93.450918 -223.903794) (xy 93.476904 -223.904305)
			(xy 93.528236 -223.912438) (xy 93.577664 -223.9285) (xy 93.623971 -223.952097) (xy 93.666017 -223.982647)
			(xy 93.702766 -224.019398) (xy 93.733313 -224.061446) (xy 93.756907 -224.107754) (xy 93.772967 -224.157183)
			(xy 93.781097 -224.208516) (xy 93.781626 -224.234502) (xy 93.781142 -224.260488) (xy 93.773005 -224.311821)
			(xy 93.756932 -224.361246) (xy 93.745558 -224.384616) (xy 93.7387 -224.398078) (xy 93.742002 -224.42805)
			(xy 93.97492 -224.712022) (xy 93.98889 -224.720658) (xy 93.997018 -224.72269) (xy 94.02315 -224.729403)
			(xy 94.072952 -224.750151) (xy 94.118725 -224.77871) (xy 94.159254 -224.81432) (xy 94.193464 -224.856038)
			(xy 94.220447 -224.902756) (xy 94.239488 -224.953235) (xy 94.250081 -225.006136) (xy 94.251526 -225.033078)
			(xy 94.25178 -225.04146) (xy 94.257622 -225.056954) (xy 96.633284 -227.954078) (xy 96.659954 -227.963476)
			(xy 96.673924 -227.960682) (xy 96.690501 -227.957465) (xy 96.724095 -227.95403) (xy 96.74098 -227.953824)
			(xy 96.766969 -227.954306) (xy 96.818308 -227.962435) (xy 96.867744 -227.978495) (xy 96.914057 -228.002093)
			(xy 96.956109 -228.032645) (xy 96.992863 -228.0694) (xy 97.023414 -228.111453) (xy 97.047009 -228.157767)
			(xy 97.063068 -228.207203) (xy 97.071195 -228.258543) (xy 97.071688 -228.284532) (xy 97.071279 -228.30789)
			(xy 97.064702 -228.354141) (xy 97.051696 -228.399011) (xy 97.032519 -228.44161) (xy 97.02038 -228.46157)
			(xy 97.012506 -228.473762) (xy 97.011998 -228.501956) (xy 97.156778 -228.751384) (xy 97.18167 -228.764846)
			(xy 97.195894 -228.764084) (xy 97.211134 -228.76383) (xy 97.237116 -228.764342) (xy 97.288441 -228.772476)
			(xy 97.337861 -228.788538) (xy 97.38416 -228.812133) (xy 97.426199 -228.84268) (xy 97.462942 -228.879427)
			(xy 97.493484 -228.921469) (xy 97.517075 -228.96777) (xy 97.533132 -229.017192) (xy 97.54126 -229.068518)
			(xy 97.54126 -229.120482) (xy 97.533132 -229.171808) (xy 97.517075 -229.22123) (xy 97.493484 -229.267531)
			(xy 97.462942 -229.309573) (xy 97.426199 -229.34632) (xy 97.38416 -229.376867) (xy 97.337861 -229.400462)
			(xy 97.288441 -229.416524) (xy 97.237116 -229.424658) (xy 97.211134 -229.425246) (xy 97.193608 -229.424738)
			(xy 97.179384 -229.423976) (xy 97.154238 -229.437692) (xy 97.010728 -229.685088) (xy 97.011236 -229.713282)
			(xy 97.01911 -229.725474) (xy 97.03156 -229.745563) (xy 97.051218 -229.788542) (xy 97.064556 -229.833882)
			(xy 97.071301 -229.880659) (xy 97.071688 -229.90429) (xy 97.071282 -229.927649) (xy 97.06471 -229.973902)
			(xy 97.051709 -230.018775) (xy 97.032536 -230.061378) (xy 97.02038 -230.081328) (xy 97.012506 -230.09352)
			(xy 97.011998 -230.121714) (xy 97.156778 -230.371396) (xy 97.18167 -230.384858) (xy 97.195894 -230.384096)
			(xy 97.211134 -230.383842) (xy 97.237115 -230.384354) (xy 97.288438 -230.392488) (xy 97.337856 -230.40855)
			(xy 97.384154 -230.432144) (xy 97.426191 -230.462689) (xy 97.462933 -230.499435) (xy 97.493474 -230.541475)
			(xy 97.517064 -230.587775) (xy 97.53312 -230.637195) (xy 97.541248 -230.688518) (xy 97.541248 -230.740482)
			(xy 97.53312 -230.791805) (xy 97.517064 -230.841225) (xy 97.493474 -230.887525) (xy 97.462933 -230.929565)
			(xy 97.426191 -230.966311) (xy 97.384154 -230.996856) (xy 97.337856 -231.02045) (xy 97.288438 -231.036512)
			(xy 97.237115 -231.044646) (xy 97.211134 -231.045258) (xy 97.193608 -231.04475) (xy 97.179384 -231.043988)
			(xy 97.154238 -231.057704) (xy 97.010728 -231.3051) (xy 97.011236 -231.333294) (xy 97.01911 -231.345486)
			(xy 97.03156 -231.365575) (xy 97.051216 -231.408554) (xy 97.064552 -231.453894) (xy 97.071296 -231.500672)
			(xy 97.071688 -231.524302) (xy 97.071281 -231.547661) (xy 97.064708 -231.593913) (xy 97.051705 -231.638785)
			(xy 97.032531 -231.681387) (xy 97.02038 -231.70134) (xy 97.012506 -231.713532) (xy 97.011998 -231.741726)
			(xy 97.156778 -231.991154) (xy 97.181416 -232.004616) (xy 97.195894 -232.003854) (xy 97.211134 -232.0036)
			(xy 97.237119 -232.004112) (xy 97.288448 -232.012247) (xy 97.337873 -232.02831) (xy 97.384176 -232.051907)
			(xy 97.426219 -232.082457) (xy 97.462965 -232.119207) (xy 97.49351 -232.161253) (xy 97.517103 -232.207559)
			(xy 97.533161 -232.256985) (xy 97.541291 -232.308315) (xy 97.541291 -232.360285) (xy 97.533161 -232.411615)
			(xy 97.517103 -232.461041) (xy 97.49351 -232.507347) (xy 97.462965 -232.549393) (xy 97.426219 -232.586143)
			(xy 97.384176 -232.616693) (xy 97.337873 -232.64029) (xy 97.288448 -232.656353) (xy 97.237119 -232.664488)
			(xy 97.211134 -232.665016) (xy 97.193608 -232.664508) (xy 97.179384 -232.663746) (xy 97.154238 -232.677462)
			(xy 97.010728 -232.925112) (xy 97.011236 -232.953306) (xy 97.01911 -232.965498) (xy 97.031559 -232.985587)
			(xy 97.051214 -233.028567) (xy 97.064548 -233.073907) (xy 97.07129 -233.120684) (xy 97.071688 -233.144314)
			(xy 97.071204 -233.170302) (xy 97.063071 -233.221638) (xy 97.047007 -233.271069) (xy 97.023408 -233.317379)
			(xy 96.992855 -233.359427) (xy 96.956101 -233.396177) (xy 96.91405 -233.426726) (xy 96.867738 -233.45032)
			(xy 96.818305 -233.466379) (xy 96.766968 -233.474506) (xy 96.74098 -233.475022) (xy 96.723708 -233.474514)
			(xy 96.70923 -233.473752) (xy 96.684338 -233.487214) (xy 96.540574 -233.734864) (xy 96.541336 -233.763058)
			(xy 96.54921 -233.775504) (xy 96.561659 -233.795593) (xy 96.581313 -233.838573) (xy 96.594646 -233.883913)
			(xy 96.601387 -233.93069) (xy 96.601788 -233.95432) (xy 96.601387 -233.977722) (xy 96.594795 -234.02406)
			(xy 96.581731 -234.069005) (xy 96.562456 -234.111656) (xy 96.550226 -234.131612) (xy 96.542606 -234.143804)
			(xy 96.542098 -234.171998) (xy 96.686624 -234.421172) (xy 96.711516 -234.434634) (xy 96.72574 -234.433872)
			(xy 96.74098 -234.433618) (xy 96.76697 -234.4341) (xy 96.818309 -234.442229) (xy 96.867745 -234.458289)
			(xy 96.914059 -234.481886) (xy 96.956111 -234.512439) (xy 96.992865 -234.549194) (xy 97.023417 -234.591246)
			(xy 97.047013 -234.637561) (xy 97.063073 -234.686997) (xy 97.071201 -234.738336) (xy 97.071688 -234.764326)
			(xy 97.071287 -234.787728) (xy 97.064694 -234.834066) (xy 97.051629 -234.87901) (xy 97.032354 -234.921661)
			(xy 97.020126 -234.941618) (xy 97.012506 -234.953556) (xy 97.011998 -234.98175) (xy 97.156524 -235.231178)
			(xy 97.181416 -235.24464) (xy 97.19564 -235.243878) (xy 97.211134 -235.243624) (xy 97.237117 -235.244136)
			(xy 97.288442 -235.25227) (xy 97.337864 -235.268332) (xy 97.384164 -235.291928) (xy 97.426203 -235.322475)
			(xy 97.462947 -235.359223) (xy 97.49349 -235.401265) (xy 97.517081 -235.447568) (xy 97.533138 -235.496991)
			(xy 97.541267 -235.548317) (xy 97.541267 -235.600283) (xy 97.533138 -235.651609) (xy 97.517081 -235.701032)
			(xy 97.49349 -235.747335) (xy 97.462947 -235.789377) (xy 97.426203 -235.826125) (xy 97.384164 -235.856672)
			(xy 97.337864 -235.880268) (xy 97.288442 -235.89633) (xy 97.237117 -235.904464) (xy 97.211134 -235.90504)
			(xy 97.193862 -235.904532) (xy 97.179384 -235.90377) (xy 97.154238 -235.917486) (xy 97.010728 -236.165136)
			(xy 97.011236 -236.19333) (xy 97.01911 -236.205522) (xy 97.031557 -236.225611) (xy 97.051209 -236.268591)
			(xy 97.06454 -236.313932) (xy 97.071279 -236.360708) (xy 97.071688 -236.384338) (xy 97.071279 -236.407696)
			(xy 97.064701 -236.453947) (xy 97.051694 -236.498816) (xy 97.032517 -236.541414) (xy 97.02038 -236.561376)
			(xy 97.012506 -236.573568) (xy 97.011998 -236.601762) (xy 97.156778 -236.85119) (xy 97.18167 -236.864652)
			(xy 97.195894 -236.86389) (xy 97.211134 -236.863636) (xy 97.23712 -236.864122) (xy 97.288452 -236.872257)
			(xy 97.337879 -236.888323) (xy 97.384185 -236.911923) (xy 97.426228 -236.942477) (xy 97.462974 -236.979232)
			(xy 97.493517 -237.021282) (xy 97.517107 -237.067593) (xy 97.533161 -237.117024) (xy 97.541284 -237.168358)
			(xy 97.541842 -237.194344) (xy 97.541439 -237.217746) (xy 97.534843 -237.264082) (xy 97.521775 -237.309024)
			(xy 97.502496 -237.351672) (xy 97.49028 -237.371636) (xy 97.48266 -237.383574) (xy 97.482152 -237.411768)
			(xy 97.626678 -237.661196) (xy 97.65157 -237.674658) (xy 97.665794 -237.673896) (xy 97.681034 -237.673642)
			(xy 97.707015 -237.674154) (xy 97.758338 -237.682288) (xy 97.807756 -237.69835) (xy 97.854054 -237.721944)
			(xy 97.896091 -237.752489) (xy 97.932833 -237.789235) (xy 97.963374 -237.831275) (xy 97.986964 -237.877575)
			(xy 98.00302 -237.926995) (xy 98.011148 -237.978318) (xy 98.011148 -238.030282) (xy 98.00302 -238.081605)
			(xy 97.986964 -238.131025) (xy 97.963374 -238.177325) (xy 97.932833 -238.219365) (xy 97.896091 -238.256111)
			(xy 97.854054 -238.286656) (xy 97.807756 -238.31025) (xy 97.758338 -238.326312) (xy 97.707015 -238.334446)
			(xy 97.681034 -238.335058) (xy 97.657289 -238.334654) (xy 97.610286 -238.327863) (xy 97.564744 -238.314401)
			(xy 97.521602 -238.294547) (xy 97.501456 -238.281972) (xy 97.489264 -238.274098) (xy 97.46107 -238.273336)
			(xy 96.614234 -238.759746) (xy 96.600772 -238.784384) (xy 96.601534 -238.798862) (xy 96.601788 -238.814356)
			(xy 96.601366 -238.837725) (xy 96.594745 -238.883991) (xy 96.581672 -238.928864) (xy 96.562407 -238.971447)
			(xy 96.550226 -238.991394) (xy 96.542606 -239.003586) (xy 96.542098 -239.03178) (xy 96.686878 -239.281208)
			(xy 96.711516 -239.29467) (xy 96.72574 -239.293908) (xy 96.74098 -239.293654) (xy 96.766969 -239.294162)
			(xy 96.818308 -239.30229) (xy 96.867744 -239.318349) (xy 96.914059 -239.341943) (xy 96.956113 -239.372492)
			(xy 96.992871 -239.409243) (xy 97.023427 -239.451291) (xy 97.047029 -239.497602) (xy 97.063097 -239.547035)
			(xy 97.071233 -239.598373) (xy 97.071688 -239.624362) (xy 97.071265 -239.647731) (xy 97.064644 -239.693997)
			(xy 97.05157 -239.738869) (xy 97.032305 -239.781451) (xy 97.020126 -239.8014) (xy 97.012506 -239.813592)
			(xy 97.011998 -239.841786) (xy 97.156524 -240.091214) (xy 97.181416 -240.104676) (xy 97.19564 -240.103914)
			(xy 97.211134 -240.10366) (xy 97.237122 -240.104172) (xy 97.288457 -240.112308) (xy 97.337888 -240.128373)
			(xy 97.384197 -240.151973) (xy 97.426245 -240.182527) (xy 97.462996 -240.219281) (xy 97.493545 -240.261332)
			(xy 97.51714 -240.307643) (xy 97.5332 -240.357076) (xy 97.54133 -240.408412) (xy 97.54133 -240.460388)
			(xy 97.5332 -240.511724) (xy 97.51714 -240.561157) (xy 97.493545 -240.607468) (xy 97.462996 -240.649519)
			(xy 97.426245 -240.686273) (xy 97.384197 -240.716827) (xy 97.337888 -240.740427) (xy 97.288457 -240.756492)
			(xy 97.237122 -240.764628) (xy 97.211134 -240.765076) (xy 97.193608 -240.764568) (xy 97.179384 -240.763806)
			(xy 97.154238 -240.777522) (xy 97.010728 -241.025172) (xy 97.011236 -241.053366) (xy 97.01911 -241.065558)
			(xy 97.031561 -241.085646) (xy 97.051221 -241.128625) (xy 97.064561 -241.173965) (xy 97.071309 -241.220743)
			(xy 97.071688 -241.244374) (xy 97.071207 -241.270364) (xy 97.063079 -241.321705) (xy 97.047018 -241.371141)
			(xy 97.023422 -241.417457) (xy 96.99287 -241.45951) (xy 96.956115 -241.496266) (xy 96.914062 -241.526819)
			(xy 96.867747 -241.550416) (xy 96.81831 -241.566477) (xy 96.76697 -241.574606) (xy 96.74098 -241.575082)
			(xy 96.723708 -241.574574) (xy 96.70923 -241.573812) (xy 96.684338 -241.587274) (xy 96.540574 -241.834924)
			(xy 96.541336 -241.863118) (xy 96.54921 -241.875564) (xy 96.561661 -241.895653) (xy 96.58132 -241.938631)
			(xy 96.594659 -241.983972) (xy 96.601406 -242.030749) (xy 96.601788 -242.05438) (xy 96.601383 -242.077781)
			(xy 96.594783 -242.124116) (xy 96.581712 -242.169056) (xy 96.562431 -242.211702) (xy 96.550226 -242.231672)
			(xy 96.542606 -242.243864) (xy 96.542098 -242.272058) (xy 96.686624 -242.521232) (xy 96.711516 -242.534694)
			(xy 96.72574 -242.533932) (xy 96.74098 -242.533678) (xy 96.766971 -242.53416) (xy 96.818313 -242.542288)
			(xy 96.867751 -242.558349) (xy 96.914068 -242.581945) (xy 96.956123 -242.612497) (xy 96.992881 -242.649251)
			(xy 97.023437 -242.691303) (xy 97.047038 -242.737618) (xy 97.063104 -242.787054) (xy 97.071238 -242.838395)
			(xy 97.071688 -242.864386) (xy 97.071283 -242.887787) (xy 97.064682 -242.934121) (xy 97.05161 -242.979061)
			(xy 97.032329 -243.021706) (xy 97.020126 -243.041678) (xy 97.012506 -243.053616) (xy 97.011998 -243.08181)
			(xy 97.156524 -243.331238) (xy 97.181416 -243.3447) (xy 97.19564 -243.343938) (xy 97.211134 -243.343684)
			(xy 97.23712 -243.344196) (xy 97.288452 -243.352331) (xy 97.337879 -243.368395) (xy 97.384185 -243.391994)
			(xy 97.426229 -243.422545) (xy 97.462977 -243.459297) (xy 97.493524 -243.501344) (xy 97.517118 -243.547653)
			(xy 97.533177 -243.597081) (xy 97.541307 -243.648414) (xy 97.541307 -243.6744) (xy 108.185132 -243.6744)
			(xy 108.189304 -243.624054) (xy 108.201706 -243.575081) (xy 108.222 -243.528817) (xy 108.249632 -243.486525)
			(xy 108.283849 -243.449358) (xy 108.323717 -243.418331) (xy 108.368148 -243.394288) (xy 108.41593 -243.377887)
			(xy 108.465761 -243.369575) (xy 108.49102 -243.369084) (xy 109.431074 -243.369084) (xy 109.456332 -243.369591)
			(xy 109.506161 -243.377902) (xy 109.553942 -243.394301) (xy 109.598371 -243.418342) (xy 109.638238 -243.449368)
			(xy 109.672453 -243.486533) (xy 109.700085 -243.528823) (xy 109.720378 -243.575085) (xy 109.73278 -243.624056)
			(xy 109.736952 -243.6744) (xy 109.73278 -243.724744) (xy 109.720378 -243.773715) (xy 109.700085 -243.819977)
			(xy 109.672453 -243.862267) (xy 109.638238 -243.899432) (xy 109.598371 -243.930458) (xy 109.553942 -243.954499)
			(xy 109.506161 -243.970898) (xy 109.456332 -243.979209) (xy 109.431074 -243.9797) (xy 108.49102 -243.9797)
			(xy 108.465761 -243.979225) (xy 108.41593 -243.970913) (xy 108.368148 -243.954512) (xy 108.323717 -243.930469)
			(xy 108.283849 -243.899442) (xy 108.249632 -243.862275) (xy 108.222 -243.819983) (xy 108.201706 -243.773719)
			(xy 108.189304 -243.724746) (xy 108.185132 -243.6744) (xy 97.541307 -243.6744) (xy 97.541307 -243.700386)
			(xy 97.533177 -243.751719) (xy 97.517118 -243.801147) (xy 97.493524 -243.847456) (xy 97.462977 -243.889503)
			(xy 97.426229 -243.926255) (xy 97.384185 -243.956806) (xy 97.337879 -243.980405) (xy 97.288452 -243.996469)
			(xy 97.23712 -244.004604) (xy 97.211134 -244.0051) (xy 97.193608 -244.004592) (xy 97.179384 -244.00383)
			(xy 97.154238 -244.017546) (xy 97.010728 -244.265196) (xy 97.011236 -244.29339) (xy 97.01911 -244.305582)
			(xy 97.03156 -244.325671) (xy 97.051217 -244.36865) (xy 97.064553 -244.41399) (xy 97.071298 -244.460768)
			(xy 97.071688 -244.484398) (xy 97.071688 -244.4844) (xy 97.374883 -244.4844) (xy 97.379059 -244.434011)
			(xy 97.391472 -244.384997) (xy 97.411784 -244.338695) (xy 97.43944 -244.296368) (xy 97.473686 -244.259171)
			(xy 97.513588 -244.228118) (xy 97.558057 -244.204057) (xy 97.605881 -244.187644) (xy 97.655753 -244.179326)
			(xy 97.681034 -244.178836) (xy 98.621088 -244.178836) (xy 98.646367 -244.179332) (xy 98.696236 -244.187652)
			(xy 98.744056 -244.204067) (xy 98.788521 -244.228129) (xy 98.82842 -244.259181) (xy 98.862663 -244.296378)
			(xy 98.890316 -244.338703) (xy 98.910626 -244.385003) (xy 98.923037 -244.434014) (xy 98.927213 -244.4844)
			(xy 100.194783 -244.4844) (xy 100.198959 -244.434011) (xy 100.211373 -244.384996) (xy 100.231685 -244.338693)
			(xy 100.259342 -244.296365) (xy 100.293589 -244.259168) (xy 100.333492 -244.228115) (xy 100.377963 -244.204054)
			(xy 100.425787 -244.187642) (xy 100.475661 -244.179326) (xy 100.500942 -244.178836) (xy 101.440996 -244.178836)
			(xy 101.466275 -244.179333) (xy 101.516143 -244.187654) (xy 101.563961 -244.204069) (xy 101.608426 -244.228131)
			(xy 101.648323 -244.259184) (xy 101.682565 -244.29638) (xy 101.710217 -244.338705) (xy 101.730526 -244.385005)
			(xy 101.742937 -244.434015) (xy 101.747113 -244.4844) (xy 103.014983 -244.4844) (xy 103.019159 -244.434014)
			(xy 103.03157 -244.385003) (xy 103.051879 -244.338704) (xy 103.079532 -244.296378) (xy 103.113774 -244.259181)
			(xy 103.153672 -244.228128) (xy 103.198137 -244.204065) (xy 103.245956 -244.18765) (xy 103.295825 -244.179329)
			(xy 103.321104 -244.178836) (xy 104.261158 -244.178836) (xy 104.286439 -244.17933) (xy 104.336312 -244.187646)
			(xy 104.384136 -244.204058) (xy 104.428605 -244.228118) (xy 104.468508 -244.259171) (xy 104.502755 -244.296368)
			(xy 104.530412 -244.338695) (xy 104.550724 -244.384997) (xy 104.563137 -244.434011) (xy 104.567313 -244.4844)
			(xy 105.834883 -244.4844) (xy 105.839059 -244.434014) (xy 105.851471 -244.385002) (xy 105.87178 -244.338701)
			(xy 105.899434 -244.296375) (xy 105.933678 -244.259178) (xy 105.973577 -244.228125) (xy 106.018043 -244.204063)
			(xy 106.065863 -244.187648) (xy 106.115732 -244.179328) (xy 106.141012 -244.178836) (xy 107.081066 -244.178836)
			(xy 107.106346 -244.17933) (xy 107.156218 -244.187647) (xy 107.204041 -244.20406) (xy 107.24851 -244.228121)
			(xy 107.288411 -244.259174) (xy 107.322657 -244.29637) (xy 107.350313 -244.338697) (xy 107.370624 -244.384999)
			(xy 107.383037 -244.434012) (xy 107.387213 -244.4844) (xy 107.383037 -244.534788) (xy 107.370624 -244.583801)
			(xy 107.350313 -244.630103) (xy 107.322657 -244.67243) (xy 107.288411 -244.709626) (xy 107.24851 -244.740679)
			(xy 107.204041 -244.76474) (xy 107.156218 -244.781153) (xy 107.106346 -244.78947) (xy 107.081066 -244.78996)
			(xy 106.141012 -244.78996) (xy 106.115732 -244.789472) (xy 106.065863 -244.781152) (xy 106.018043 -244.764737)
			(xy 105.973577 -244.740675) (xy 105.933678 -244.709622) (xy 105.899434 -244.672425) (xy 105.87178 -244.630099)
			(xy 105.851471 -244.583798) (xy 105.839059 -244.534786) (xy 105.834883 -244.4844) (xy 104.567313 -244.4844)
			(xy 104.563137 -244.534789) (xy 104.550724 -244.583803) (xy 104.530412 -244.630105) (xy 104.502755 -244.672432)
			(xy 104.468508 -244.709629) (xy 104.428605 -244.740682) (xy 104.384136 -244.764742) (xy 104.336312 -244.781154)
			(xy 104.286439 -244.78947) (xy 104.261158 -244.78996) (xy 103.321104 -244.78996) (xy 103.295825 -244.789471)
			(xy 103.245956 -244.78115) (xy 103.198137 -244.764735) (xy 103.153672 -244.740672) (xy 103.113774 -244.709619)
			(xy 103.079532 -244.672422) (xy 103.051879 -244.630096) (xy 103.03157 -244.583797) (xy 103.019159 -244.534786)
			(xy 103.014983 -244.4844) (xy 101.747113 -244.4844) (xy 101.742937 -244.534785) (xy 101.730526 -244.583795)
			(xy 101.710217 -244.630095) (xy 101.682565 -244.67242) (xy 101.648323 -244.709616) (xy 101.608426 -244.740669)
			(xy 101.563961 -244.764731) (xy 101.516143 -244.781146) (xy 101.466275 -244.789467) (xy 101.440996 -244.78996)
			(xy 100.500942 -244.78996) (xy 100.475661 -244.789474) (xy 100.425787 -244.781158) (xy 100.377963 -244.764746)
			(xy 100.333492 -244.740685) (xy 100.293589 -244.709632) (xy 100.259342 -244.672435) (xy 100.231685 -244.630107)
			(xy 100.211373 -244.583804) (xy 100.198959 -244.534789) (xy 100.194783 -244.4844) (xy 98.927213 -244.4844)
			(xy 98.923037 -244.534786) (xy 98.910626 -244.583797) (xy 98.890316 -244.630097) (xy 98.862663 -244.672422)
			(xy 98.82842 -244.709619) (xy 98.788521 -244.740671) (xy 98.744056 -244.764733) (xy 98.696236 -244.781148)
			(xy 98.646367 -244.789468) (xy 98.621088 -244.78996) (xy 97.681034 -244.78996) (xy 97.655753 -244.789474)
			(xy 97.605881 -244.781156) (xy 97.558057 -244.764743) (xy 97.513588 -244.740682) (xy 97.473686 -244.709629)
			(xy 97.43944 -244.672432) (xy 97.411784 -244.630105) (xy 97.391472 -244.583803) (xy 97.379059 -244.534789)
			(xy 97.374883 -244.4844) (xy 97.071688 -244.4844) (xy 97.071205 -244.510387) (xy 97.063074 -244.561724)
			(xy 97.047012 -244.611158) (xy 97.023414 -244.65747) (xy 96.992861 -244.69952) (xy 96.956106 -244.736273)
			(xy 96.914055 -244.766823) (xy 96.867741 -244.790418) (xy 96.818307 -244.806478) (xy 96.766969 -244.814606)
			(xy 96.74098 -244.815106) (xy 96.723708 -244.814598) (xy 96.70923 -244.813836) (xy 96.684338 -244.827298)
			(xy 96.540574 -245.074948) (xy 96.541336 -245.103142) (xy 96.54921 -245.115588) (xy 96.56166 -245.135677)
			(xy 96.581316 -245.178656) (xy 96.594651 -245.223997) (xy 96.601395 -245.270774) (xy 96.601788 -245.2944)
			(xy 108.185144 -245.2944) (xy 108.189316 -245.244056) (xy 108.201717 -245.195085) (xy 108.222011 -245.148823)
			(xy 108.249642 -245.106533) (xy 108.283857 -245.069367) (xy 108.323723 -245.038341) (xy 108.368153 -245.014299)
			(xy 108.415933 -244.997899) (xy 108.465762 -244.989587) (xy 108.49102 -244.989096) (xy 109.431074 -244.989096)
			(xy 109.456333 -244.989579) (xy 109.506164 -244.99789) (xy 109.553947 -245.01429) (xy 109.598378 -245.038332)
			(xy 109.638246 -245.069359) (xy 109.672463 -245.106526) (xy 109.700095 -245.148818) (xy 109.72039 -245.195081)
			(xy 109.732792 -245.244054) (xy 109.736964 -245.2944) (xy 109.732792 -245.344746) (xy 109.72039 -245.393719)
			(xy 109.700095 -245.439982) (xy 109.672463 -245.482274) (xy 109.638246 -245.519441) (xy 109.598378 -245.550468)
			(xy 109.553947 -245.57451) (xy 109.506164 -245.59091) (xy 109.456333 -245.599221) (xy 109.431074 -245.599712)
			(xy 108.49102 -245.599712) (xy 108.465762 -245.599213) (xy 108.415933 -245.590901) (xy 108.368153 -245.574501)
			(xy 108.323723 -245.550459) (xy 108.283857 -245.519433) (xy 108.249642 -245.482267) (xy 108.222011 -245.439977)
			(xy 108.201717 -245.393715) (xy 108.189316 -245.344744) (xy 108.185144 -245.2944) (xy 96.601788 -245.2944)
			(xy 96.601788 -245.294404) (xy 96.601381 -245.317805) (xy 96.594778 -245.364138) (xy 96.581704 -245.409076)
			(xy 96.562422 -245.45172) (xy 96.550226 -245.471696) (xy 96.542606 -245.483888) (xy 96.542098 -245.512082)
			(xy 96.686624 -245.761256) (xy 96.711516 -245.774718) (xy 96.72574 -245.773956) (xy 96.74098 -245.773702)
			(xy 96.76697 -245.774184) (xy 96.81831 -245.782312) (xy 96.867747 -245.798373) (xy 96.914062 -245.82197)
			(xy 96.956116 -245.852522) (xy 96.992872 -245.889277) (xy 97.023425 -245.931329) (xy 97.047023 -245.977644)
			(xy 97.063085 -246.02708) (xy 97.071216 -246.07842) (xy 97.071688 -246.1044) (xy 97.374895 -246.1044)
			(xy 97.379071 -246.054013) (xy 97.391483 -246.005001) (xy 97.411794 -245.958701) (xy 97.439449 -245.916375)
			(xy 97.473694 -245.879179) (xy 97.513595 -245.848128) (xy 97.558062 -245.824068) (xy 97.605884 -245.807655)
			(xy 97.655754 -245.799338) (xy 97.681034 -245.798848) (xy 98.621088 -245.798848) (xy 98.646368 -245.79932)
			(xy 98.696239 -245.80764) (xy 98.744061 -245.824056) (xy 98.788528 -245.848119) (xy 98.828428 -245.879173)
			(xy 98.862672 -245.91637) (xy 98.890327 -245.958698) (xy 98.910637 -246.004999) (xy 98.923049 -246.054012)
			(xy 98.927225 -246.1044) (xy 100.194795 -246.1044) (xy 100.198971 -246.054012) (xy 100.211384 -246.005)
			(xy 100.231695 -245.958699) (xy 100.259351 -245.916373) (xy 100.293597 -245.879177) (xy 100.333499 -245.848125)
			(xy 100.377968 -245.824065) (xy 100.42579 -245.807654) (xy 100.475662 -245.799338) (xy 100.500942 -245.798848)
			(xy 101.440996 -245.798848) (xy 101.466276 -245.799321) (xy 101.516146 -245.807642) (xy 101.563966 -245.824058)
			(xy 101.608432 -245.848121) (xy 101.648331 -245.879175) (xy 101.682574 -245.916373) (xy 101.710228 -245.9587)
			(xy 101.730538 -246.005001) (xy 101.742949 -246.054013) (xy 101.747125 -246.1044) (xy 103.014995 -246.1044)
			(xy 103.01917 -246.054016) (xy 103.031581 -246.005007) (xy 103.05189 -245.958709) (xy 103.079542 -245.916385)
			(xy 103.113783 -245.87919) (xy 103.153679 -245.848138) (xy 103.198142 -245.824076) (xy 103.245959 -245.807661)
			(xy 103.295826 -245.799341) (xy 103.321104 -245.798848) (xy 104.261158 -245.798848) (xy 104.28644 -245.799318)
			(xy 104.336315 -245.807634) (xy 104.38414 -245.824047) (xy 104.428612 -245.848108) (xy 104.468516 -245.879162)
			(xy 104.502764 -245.91636) (xy 104.530422 -245.958689) (xy 104.550735 -246.004993) (xy 104.563149 -246.054009)
			(xy 104.567325 -246.1044) (xy 105.834895 -246.1044) (xy 105.839071 -246.054016) (xy 105.851482 -246.005006)
			(xy 105.871791 -245.958707) (xy 105.899444 -245.916383) (xy 105.933686 -245.879187) (xy 105.973583 -245.848135)
			(xy 106.018047 -245.824074) (xy 106.065866 -245.80766) (xy 106.115733 -245.79934) (xy 106.141012 -245.798848)
			(xy 107.081066 -245.798848) (xy 107.106347 -245.799318) (xy 107.156221 -245.807636) (xy 107.204046 -245.824049)
			(xy 107.248516 -245.848111) (xy 107.288419 -245.879165) (xy 107.322666 -245.916363) (xy 107.350323 -245.958691)
			(xy 107.370636 -246.004995) (xy 107.383049 -246.05401) (xy 107.387225 -246.1044) (xy 107.383049 -246.15479)
			(xy 107.370636 -246.203805) (xy 107.350323 -246.250109) (xy 107.322666 -246.292437) (xy 107.288419 -246.329635)
			(xy 107.248516 -246.360689) (xy 107.204046 -246.384751) (xy 107.156221 -246.401164) (xy 107.106347 -246.409482)
			(xy 107.081066 -246.409972) (xy 106.141012 -246.409972) (xy 106.115733 -246.40946) (xy 106.065866 -246.40114)
			(xy 106.018047 -246.384726) (xy 105.973583 -246.360665) (xy 105.933686 -246.329613) (xy 105.899444 -246.292417)
			(xy 105.871791 -246.250093) (xy 105.851482 -246.203794) (xy 105.839071 -246.154784) (xy 105.834895 -246.1044)
			(xy 104.567325 -246.1044) (xy 104.563149 -246.154791) (xy 104.550735 -246.203807) (xy 104.530422 -246.250111)
			(xy 104.502764 -246.29244) (xy 104.468516 -246.329638) (xy 104.428612 -246.360692) (xy 104.38414 -246.384753)
			(xy 104.336315 -246.401166) (xy 104.28644 -246.409482) (xy 104.261158 -246.409972) (xy 103.321104 -246.409972)
			(xy 103.295826 -246.409459) (xy 103.245959 -246.401139) (xy 103.198142 -246.384724) (xy 103.153679 -246.360662)
			(xy 103.113783 -246.32961) (xy 103.079542 -246.292415) (xy 103.05189 -246.250091) (xy 103.031581 -246.203793)
			(xy 103.01917 -246.154784) (xy 103.014995 -246.1044) (xy 101.747125 -246.1044) (xy 101.742949 -246.154787)
			(xy 101.730538 -246.203799) (xy 101.710228 -246.2501) (xy 101.682574 -246.292427) (xy 101.648331 -246.329625)
			(xy 101.608432 -246.360679) (xy 101.563966 -246.384742) (xy 101.516146 -246.401158) (xy 101.466276 -246.409479)
			(xy 101.440996 -246.409972) (xy 100.500942 -246.409972) (xy 100.475662 -246.409462) (xy 100.42579 -246.401146)
			(xy 100.377968 -246.384735) (xy 100.333499 -246.360675) (xy 100.293597 -246.329623) (xy 100.259351 -246.292427)
			(xy 100.231695 -246.250101) (xy 100.211384 -246.2038) (xy 100.198971 -246.154788) (xy 100.194795 -246.1044)
			(xy 98.927225 -246.1044) (xy 98.923049 -246.154788) (xy 98.910637 -246.203801) (xy 98.890327 -246.250102)
			(xy 98.862672 -246.29243) (xy 98.828428 -246.329627) (xy 98.788528 -246.360681) (xy 98.744061 -246.384744)
			(xy 98.696239 -246.40116) (xy 98.646368 -246.40948) (xy 98.621088 -246.409972) (xy 97.681034 -246.409972)
			(xy 97.655754 -246.409462) (xy 97.605884 -246.401145) (xy 97.558062 -246.384732) (xy 97.513595 -246.360672)
			(xy 97.473694 -246.329621) (xy 97.439449 -246.292425) (xy 97.411794 -246.250099) (xy 97.391483 -246.203799)
			(xy 97.379071 -246.154787) (xy 97.374895 -246.1044) (xy 97.071688 -246.1044) (xy 97.071688 -246.10441)
			(xy 97.071281 -246.127811) (xy 97.064677 -246.174143) (xy 97.051602 -246.219081) (xy 97.032319 -246.261725)
			(xy 97.020126 -246.281702) (xy 97.012506 -246.29364) (xy 97.011998 -246.321834) (xy 97.156524 -246.571262)
			(xy 97.181416 -246.584724) (xy 97.19564 -246.583962) (xy 97.211134 -246.583708) (xy 97.237118 -246.58422)
			(xy 97.288446 -246.592354) (xy 97.33787 -246.608418) (xy 97.384172 -246.632014) (xy 97.426214 -246.662563)
			(xy 97.462959 -246.699312) (xy 97.493504 -246.741357) (xy 97.517095 -246.787662) (xy 97.533154 -246.837087)
			(xy 97.541283 -246.888416) (xy 97.541283 -246.9144) (xy 108.185156 -246.9144) (xy 108.189328 -246.864058)
			(xy 108.201729 -246.815089) (xy 108.222021 -246.768829) (xy 108.249651 -246.72654) (xy 108.283865 -246.689376)
			(xy 108.32373 -246.658351) (xy 108.368157 -246.63431) (xy 108.415936 -246.617911) (xy 108.465763 -246.609599)
			(xy 108.49102 -246.609108) (xy 109.431074 -246.609108) (xy 109.456334 -246.609567) (xy 109.506167 -246.617878)
			(xy 109.553951 -246.634279) (xy 109.598385 -246.658322) (xy 109.638254 -246.68935) (xy 109.672472 -246.726518)
			(xy 109.700106 -246.768812) (xy 109.720401 -246.815077) (xy 109.732804 -246.864052) (xy 109.736976 -246.9144)
			(xy 109.732804 -246.964748) (xy 109.720401 -247.013723) (xy 109.700106 -247.059988) (xy 109.672472 -247.102282)
			(xy 109.638254 -247.13945) (xy 109.598385 -247.170478) (xy 109.553951 -247.194521) (xy 109.506167 -247.210922)
			(xy 109.456334 -247.219233) (xy 109.431074 -247.219724) (xy 108.49102 -247.219724) (xy 108.465763 -247.219201)
			(xy 108.415936 -247.210889) (xy 108.368157 -247.19449) (xy 108.32373 -247.170449) (xy 108.283865 -247.139424)
			(xy 108.249651 -247.10226) (xy 108.222021 -247.059971) (xy 108.201729 -247.013711) (xy 108.189328 -246.964742)
			(xy 108.185156 -246.9144) (xy 97.541283 -246.9144) (xy 97.541283 -246.940384) (xy 97.533154 -246.991713)
			(xy 97.517095 -247.041138) (xy 97.493504 -247.087443) (xy 97.462959 -247.129488) (xy 97.426214 -247.166237)
			(xy 97.384172 -247.196786) (xy 97.33787 -247.220382) (xy 97.288446 -247.236446) (xy 97.237118 -247.24458)
			(xy 97.211134 -247.245124) (xy 97.193862 -247.244616) (xy 97.179384 -247.243854) (xy 97.154238 -247.25757)
			(xy 97.010728 -247.50522) (xy 97.011236 -247.533414) (xy 97.01911 -247.545606) (xy 97.031558 -247.565695)
			(xy 97.051212 -247.608675) (xy 97.064545 -247.654015) (xy 97.071286 -247.700792) (xy 97.071688 -247.7244)
			(xy 97.374907 -247.7244) (xy 97.379083 -247.674015) (xy 97.391495 -247.625005) (xy 97.411805 -247.578707)
			(xy 97.439459 -247.536383) (xy 97.473702 -247.499188) (xy 97.513601 -247.468138) (xy 97.558067 -247.444079)
			(xy 97.605887 -247.427667) (xy 97.655755 -247.41935) (xy 97.681034 -247.41886) (xy 98.621088 -247.41886)
			(xy 98.646369 -247.419308) (xy 98.696242 -247.427629) (xy 98.744066 -247.444045) (xy 98.788534 -247.468109)
			(xy 98.828436 -247.499164) (xy 98.862682 -247.536363) (xy 98.890337 -247.578692) (xy 98.910648 -247.624995)
			(xy 98.923061 -247.67401) (xy 98.927237 -247.7244) (xy 100.194807 -247.7244) (xy 100.198983 -247.674014)
			(xy 100.211395 -247.625004) (xy 100.231706 -247.578704) (xy 100.259361 -247.53638) (xy 100.293605 -247.499185)
			(xy 100.333506 -247.468135) (xy 100.377972 -247.444076) (xy 100.425793 -247.427665) (xy 100.475663 -247.41935)
			(xy 100.500942 -247.41886) (xy 101.440996 -247.41886) (xy 101.466277 -247.419309) (xy 101.516149 -247.42763)
			(xy 101.563971 -247.444047) (xy 101.608439 -247.468111) (xy 101.648339 -247.499167) (xy 101.682584 -247.536366)
			(xy 101.710238 -247.578694) (xy 101.730549 -247.624997) (xy 101.742961 -247.674011) (xy 101.747137 -247.7244)
			(xy 103.015007 -247.7244) (xy 103.019182 -247.674018) (xy 103.031593 -247.625011) (xy 103.0519 -247.578715)
			(xy 103.079551 -247.536393) (xy 103.113791 -247.499199) (xy 103.153685 -247.468148) (xy 103.198147 -247.444087)
			(xy 103.245962 -247.427673) (xy 103.295827 -247.419353) (xy 103.321104 -247.41886) (xy 104.261158 -247.41886)
			(xy 104.286441 -247.419306) (xy 104.336318 -247.427622) (xy 104.384145 -247.444036) (xy 104.428619 -247.468098)
			(xy 104.468524 -247.499153) (xy 104.502774 -247.536353) (xy 104.530433 -247.578683) (xy 104.550746 -247.624989)
			(xy 104.56316 -247.674007) (xy 104.567337 -247.7244) (xy 105.834907 -247.7244) (xy 105.839082 -247.674018)
			(xy 105.851493 -247.62501) (xy 105.871801 -247.578713) (xy 105.899453 -247.53639) (xy 105.933694 -247.499196)
			(xy 105.97359 -247.468145) (xy 106.018052 -247.444085) (xy 106.065869 -247.427671) (xy 106.115734 -247.419352)
			(xy 106.141012 -247.41886) (xy 107.081066 -247.41886) (xy 107.106348 -247.419306) (xy 107.156224 -247.427624)
			(xy 107.204051 -247.444038) (xy 107.248523 -247.468101) (xy 107.288427 -247.499156) (xy 107.322676 -247.536356)
			(xy 107.350334 -247.578686) (xy 107.370647 -247.624991) (xy 107.383061 -247.674008) (xy 107.387237 -247.7244)
			(xy 107.383061 -247.774792) (xy 107.370647 -247.823809) (xy 107.350334 -247.870114) (xy 107.322676 -247.912444)
			(xy 107.288427 -247.949644) (xy 107.248523 -247.980699) (xy 107.204051 -248.004762) (xy 107.156224 -248.021176)
			(xy 107.106348 -248.029494) (xy 107.081066 -248.029984) (xy 106.141012 -248.029984) (xy 106.115734 -248.029448)
			(xy 106.065869 -248.021129) (xy 106.018052 -248.004715) (xy 105.97359 -247.980655) (xy 105.933694 -247.949604)
			(xy 105.899453 -247.91241) (xy 105.871801 -247.870087) (xy 105.851493 -247.82379) (xy 105.839082 -247.774782)
			(xy 105.834907 -247.7244) (xy 104.567337 -247.7244) (xy 104.56316 -247.774793) (xy 104.550746 -247.823811)
			(xy 104.530433 -247.870117) (xy 104.502774 -247.912447) (xy 104.468524 -247.949647) (xy 104.428619 -247.980702)
			(xy 104.384145 -248.004764) (xy 104.336318 -248.021178) (xy 104.286441 -248.029494) (xy 104.261158 -248.029984)
			(xy 103.321104 -248.029984) (xy 103.295827 -248.029447) (xy 103.245962 -248.021127) (xy 103.198147 -248.004713)
			(xy 103.153685 -247.980652) (xy 103.113791 -247.949601) (xy 103.079551 -247.912407) (xy 103.0519 -247.870085)
			(xy 103.031593 -247.823789) (xy 103.019182 -247.774782) (xy 103.015007 -247.7244) (xy 101.747137 -247.7244)
			(xy 101.742961 -247.774789) (xy 101.730549 -247.823803) (xy 101.710238 -247.870106) (xy 101.682584 -247.912434)
			(xy 101.648339 -247.949633) (xy 101.608439 -247.980689) (xy 101.563971 -248.004753) (xy 101.516149 -248.02117)
			(xy 101.466277 -248.029491) (xy 101.440996 -248.029984) (xy 100.500942 -248.029984) (xy 100.475663 -248.02945)
			(xy 100.425793 -248.021135) (xy 100.377972 -248.004724) (xy 100.333506 -247.980665) (xy 100.293605 -247.949615)
			(xy 100.259361 -247.91242) (xy 100.231706 -247.870096) (xy 100.211395 -247.823796) (xy 100.198983 -247.774786)
			(xy 100.194807 -247.7244) (xy 98.927237 -247.7244) (xy 98.923061 -247.77479) (xy 98.910648 -247.823805)
			(xy 98.890337 -247.870108) (xy 98.862682 -247.912437) (xy 98.828436 -247.949636) (xy 98.788534 -247.980691)
			(xy 98.744066 -248.004755) (xy 98.696242 -248.021171) (xy 98.646369 -248.029492) (xy 98.621088 -248.029984)
			(xy 97.681034 -248.029984) (xy 97.655755 -248.02945) (xy 97.605887 -248.021133) (xy 97.558067 -248.004721)
			(xy 97.513601 -247.980662) (xy 97.473702 -247.949612) (xy 97.439459 -247.912417) (xy 97.411805 -247.870093)
			(xy 97.391495 -247.823795) (xy 97.379083 -247.774785) (xy 97.374907 -247.7244) (xy 97.071688 -247.7244)
			(xy 97.071688 -247.724422) (xy 97.071177 -247.750407) (xy 97.063043 -247.801738) (xy 97.04698 -247.851164)
			(xy 97.023383 -247.897469) (xy 96.992832 -247.939513) (xy 96.956081 -247.97626) (xy 96.914034 -248.006805)
			(xy 96.867726 -248.030396) (xy 96.818297 -248.046453) (xy 96.766966 -248.05458) (xy 96.74098 -248.05513)
			(xy 96.723962 -248.054622) (xy 96.70923 -248.05386) (xy 96.684592 -248.067322) (xy 96.540828 -248.315226)
			(xy 96.541336 -248.34342) (xy 96.54921 -248.355612) (xy 96.561658 -248.375701) (xy 96.581311 -248.418681)
			(xy 96.594643 -248.464021) (xy 96.601383 -248.510798) (xy 96.601788 -248.534428) (xy 96.601534 -248.546366)
			(xy 96.601026 -248.56059) (xy 96.614742 -248.585228) (xy 97.464372 -249.073162) (xy 97.492312 -249.072654)
			(xy 97.50425 -249.06478) (xy 97.524182 -249.052668) (xy 97.566725 -249.033556) (xy 97.611533 -249.020612)
			(xy 97.657714 -249.014091) (xy 97.681034 -249.013726) (xy 97.703982 -249.014095) (xy 97.749442 -249.020403)
			(xy 97.793589 -249.032948) (xy 97.835573 -249.051489) (xy 97.855278 -249.063256) (xy 97.867216 -249.070622)
			(xy 97.895156 -249.07113) (xy 98.747072 -248.581672) (xy 98.760788 -248.557288) (xy 98.76028 -248.543318)
			(xy 98.76028 -248.534428) (xy 98.76079 -248.508441) (xy 98.76892 -248.457106) (xy 98.784981 -248.407676)
			(xy 98.808577 -248.361366) (xy 98.839127 -248.319318) (xy 98.875878 -248.282567) (xy 98.917926 -248.252017)
			(xy 98.964236 -248.228421) (xy 99.013666 -248.21236) (xy 99.065001 -248.20423) (xy 99.116975 -248.20423)
			(xy 99.16831 -248.21236) (xy 99.21774 -248.228421) (xy 99.26405 -248.252017) (xy 99.306098 -248.282567)
			(xy 99.342849 -248.319318) (xy 99.373399 -248.361366) (xy 99.396995 -248.407676) (xy 99.413056 -248.457106)
			(xy 99.421186 -248.508441) (xy 99.421695 -248.5344) (xy 108.185168 -248.5344) (xy 108.189339 -248.48406)
			(xy 108.20174 -248.435093) (xy 108.222032 -248.388834) (xy 108.249661 -248.346547) (xy 108.283873 -248.309385)
			(xy 108.323736 -248.278361) (xy 108.368162 -248.254321) (xy 108.415939 -248.237922) (xy 108.465764 -248.229611)
			(xy 108.49102 -248.22912) (xy 109.431074 -248.22912) (xy 109.456335 -248.229555) (xy 109.50617 -248.237867)
			(xy 109.553956 -248.254268) (xy 109.598391 -248.278312) (xy 109.638262 -248.309342) (xy 109.672482 -248.346511)
			(xy 109.700117 -248.388806) (xy 109.720412 -248.435073) (xy 109.732816 -248.48405) (xy 109.736988 -248.5344)
			(xy 109.732816 -248.58475) (xy 109.720412 -248.633727) (xy 109.700117 -248.679994) (xy 109.672482 -248.722289)
			(xy 109.638262 -248.759458) (xy 109.598391 -248.790488) (xy 109.553956 -248.814532) (xy 109.50617 -248.830933)
			(xy 109.456335 -248.839245) (xy 109.431074 -248.839736) (xy 108.49102 -248.839736) (xy 108.465764 -248.839189)
			(xy 108.415939 -248.830878) (xy 108.368162 -248.814479) (xy 108.323736 -248.790439) (xy 108.283873 -248.759415)
			(xy 108.249661 -248.722253) (xy 108.222032 -248.679966) (xy 108.20174 -248.633707) (xy 108.189339 -248.58474)
			(xy 108.185168 -248.5344) (xy 99.421695 -248.5344) (xy 99.421696 -248.534428) (xy 99.421276 -248.557797)
			(xy 99.414659 -248.604066) (xy 99.401589 -248.64894) (xy 99.382328 -248.691526) (xy 99.370134 -248.711466)
			(xy 99.362514 -248.723658) (xy 99.362006 -248.751852) (xy 99.506786 -249.00128) (xy 99.531424 -249.014742)
			(xy 99.545902 -249.01398) (xy 99.561142 -249.013726) (xy 99.587126 -249.014239) (xy 99.638453 -249.022375)
			(xy 99.687876 -249.03844) (xy 99.734177 -249.062038) (xy 99.776217 -249.09259) (xy 99.81296 -249.129341)
			(xy 99.843501 -249.171387) (xy 99.867089 -249.217694) (xy 99.883143 -249.267121) (xy 99.891267 -249.31845)
			(xy 99.89185 -249.344434) (xy 99.891448 -249.367836) (xy 99.884853 -249.414173) (xy 99.871786 -249.459115)
			(xy 99.852508 -249.501765) (xy 99.840288 -249.521726) (xy 99.832668 -249.533664) (xy 99.83216 -249.561858)
			(xy 99.976686 -249.811286) (xy 100.001578 -249.824748) (xy 100.015802 -249.823986) (xy 100.031042 -249.823732)
			(xy 100.057026 -249.824245) (xy 100.108353 -249.832381) (xy 100.157775 -249.848446) (xy 100.204076 -249.872045)
			(xy 100.246115 -249.902596) (xy 100.282857 -249.939348) (xy 100.313398 -249.981394) (xy 100.336985 -250.027701)
			(xy 100.353038 -250.077127) (xy 100.361161 -250.128456) (xy 100.36175 -250.15444) (xy 100.361496 -250.166378)
			(xy 100.360988 -250.180602) (xy 100.37445 -250.204986) (xy 101.224334 -250.693174) (xy 101.252274 -250.692666)
			(xy 101.264212 -250.684792) (xy 101.284144 -250.672683) (xy 101.326689 -250.653579) (xy 101.371496 -250.640642)
			(xy 101.417677 -250.63413) (xy 101.440996 -250.633738) (xy 101.466984 -250.634221) (xy 101.518321 -250.642352)
			(xy 101.567753 -250.658414) (xy 101.614063 -250.682013) (xy 101.656111 -250.712566) (xy 101.692862 -250.749321)
			(xy 101.723409 -250.791373) (xy 101.747002 -250.837686) (xy 101.763058 -250.88712) (xy 101.771182 -250.938458)
			(xy 101.771704 -250.964446) (xy 101.771294 -250.987804) (xy 101.764715 -251.034054) (xy 101.751708 -251.078923)
			(xy 101.732531 -251.121521) (xy 101.720396 -251.141484) (xy 101.712522 -251.153676) (xy 101.712014 -251.18187)
			(xy 101.856794 -251.431298) (xy 101.881686 -251.44476) (xy 101.89591 -251.443998) (xy 101.91115 -251.443744)
			(xy 101.934066 -251.444133) (xy 101.979457 -251.450463) (xy 102.023537 -251.463009) (xy 102.06546 -251.481529)
			(xy 102.08514 -251.493274) (xy 102.097078 -251.50064) (xy 102.125018 -251.501148) (xy 102.977188 -251.011436)
			(xy 102.990904 -250.987052) (xy 102.990396 -250.973082) (xy 102.990396 -250.964446) (xy 102.990906 -250.938459)
			(xy 102.999036 -250.887124) (xy 103.015097 -250.837694) (xy 103.038693 -250.791384) (xy 103.069243 -250.749336)
			(xy 103.105994 -250.712585) (xy 103.148042 -250.682035) (xy 103.194352 -250.658439) (xy 103.243782 -250.642378)
			(xy 103.295117 -250.634248) (xy 103.347091 -250.634248) (xy 103.398426 -250.642378) (xy 103.447856 -250.658439)
			(xy 103.494166 -250.682035) (xy 103.536214 -250.712585) (xy 103.572965 -250.749336) (xy 103.603515 -250.791384)
			(xy 103.627111 -250.837694) (xy 103.643172 -250.887124) (xy 103.651302 -250.938459) (xy 103.651812 -250.964446)
			(xy 103.651409 -250.987848) (xy 103.644814 -251.034185) (xy 103.631748 -251.079127) (xy 103.612472 -251.121777)
			(xy 103.60025 -251.141738) (xy 103.59263 -251.153676) (xy 103.592122 -251.18187) (xy 103.736902 -251.431298)
			(xy 103.76154 -251.44476) (xy 103.776018 -251.443998) (xy 103.791004 -251.443744) (xy 103.813953 -251.444111)
			(xy 103.859414 -251.450416) (xy 103.903563 -251.462958) (xy 103.945549 -251.481496) (xy 103.965248 -251.493274)
			(xy 103.977186 -251.50064) (xy 104.005126 -251.501148) (xy 104.857042 -251.01169) (xy 104.870758 -250.987306)
			(xy 104.87025 -250.973336) (xy 104.87025 -250.964446) (xy 104.87076 -250.938459) (xy 104.87889 -250.887124)
			(xy 104.894951 -250.837694) (xy 104.918547 -250.791384) (xy 104.949097 -250.749336) (xy 104.985848 -250.712585)
			(xy 105.027896 -250.682035) (xy 105.074206 -250.658439) (xy 105.123636 -250.642378) (xy 105.174971 -250.634248)
			(xy 105.226945 -250.634248) (xy 105.27828 -250.642378) (xy 105.32771 -250.658439) (xy 105.37402 -250.682035)
			(xy 105.416068 -250.712585) (xy 105.452819 -250.749336) (xy 105.483369 -250.791384) (xy 105.506965 -250.837694)
			(xy 105.523026 -250.887124) (xy 105.531156 -250.938459) (xy 105.531666 -250.964446) (xy 105.531256 -250.987804)
			(xy 105.524677 -251.034054) (xy 105.511668 -251.078922) (xy 105.492489 -251.121519) (xy 105.480358 -251.141484)
			(xy 105.472484 -251.153676) (xy 105.471976 -251.18187) (xy 105.616756 -251.431298) (xy 105.641648 -251.44476)
			(xy 105.655872 -251.443998) (xy 105.671112 -251.443744) (xy 105.694026 -251.444137) (xy 105.739414 -251.450475)
			(xy 105.78349 -251.463028) (xy 105.825407 -251.481554) (xy 105.845102 -251.493274) (xy 105.85704 -251.50064)
			(xy 105.88498 -251.501148) (xy 106.73715 -251.01169) (xy 106.750866 -250.987306) (xy 106.750358 -250.973336)
			(xy 106.750358 -250.964446) (xy 106.750868 -250.938459) (xy 106.758998 -250.887124) (xy 106.775059 -250.837694)
			(xy 106.798655 -250.791384) (xy 106.829205 -250.749336) (xy 106.865956 -250.712585) (xy 106.908004 -250.682035)
			(xy 106.954314 -250.658439) (xy 107.003744 -250.642378) (xy 107.055079 -250.634248) (xy 107.107053 -250.634248)
			(xy 107.158388 -250.642378) (xy 107.207818 -250.658439) (xy 107.254128 -250.682035) (xy 107.296176 -250.712585)
			(xy 107.332927 -250.749336) (xy 107.363477 -250.791384) (xy 107.387073 -250.837694) (xy 107.403134 -250.887124)
			(xy 107.411264 -250.938459) (xy 107.411774 -250.964446) (xy 107.411364 -250.987804) (xy 107.404785 -251.034054)
			(xy 107.391777 -251.078922) (xy 107.372598 -251.121519) (xy 107.360466 -251.141484) (xy 107.352592 -251.153676)
			(xy 107.352084 -251.18187) (xy 107.496864 -251.431298) (xy 107.521756 -251.44476) (xy 107.53598 -251.443998)
			(xy 107.550966 -251.443744) (xy 107.573913 -251.444115) (xy 107.619371 -251.450428) (xy 107.663516 -251.462977)
			(xy 107.705497 -251.481522) (xy 107.72521 -251.493274) (xy 107.737148 -251.50064) (xy 107.765088 -251.501148)
			(xy 108.617258 -251.01169) (xy 108.630974 -250.987306) (xy 108.630466 -250.973082) (xy 108.630466 -250.964446)
			(xy 108.630946 -250.938454) (xy 108.639071 -250.887108) (xy 108.655129 -250.837666) (xy 108.678724 -250.791344)
			(xy 108.709275 -250.749284) (xy 108.746029 -250.712522) (xy 108.788083 -250.681961) (xy 108.834399 -250.658356)
			(xy 108.883838 -250.642288) (xy 108.935182 -250.634151) (xy 108.961174 -250.633738) (xy 108.97108 -250.633992)
			(xy 108.98505 -250.634246) (xy 109.009434 -250.620784) (xy 109.156754 -250.367038) (xy 109.156246 -250.339098)
			(xy 109.149134 -250.32716) (xy 109.137589 -250.30758) (xy 109.11938 -250.265933) (xy 109.107032 -250.222188)
			(xy 109.100776 -250.177167) (xy 109.100366 -250.15444) (xy 109.100876 -250.128453) (xy 109.109006 -250.077118)
			(xy 109.125067 -250.027688) (xy 109.148663 -249.981378) (xy 109.179213 -249.93933) (xy 109.215964 -249.902579)
			(xy 109.258012 -249.872029) (xy 109.304322 -249.848433) (xy 109.353752 -249.832372) (xy 109.405087 -249.824242)
			(xy 109.457061 -249.824242) (xy 109.508396 -249.832372) (xy 109.557826 -249.848433) (xy 109.604136 -249.872029)
			(xy 109.646184 -249.902579) (xy 109.682935 -249.93933) (xy 109.713485 -249.981378) (xy 109.737081 -250.027688)
			(xy 109.753142 -250.077118) (xy 109.761272 -250.128453) (xy 109.761782 -250.15444) (xy 109.761528 -250.166378)
			(xy 109.76102 -250.180602) (xy 109.774482 -250.204986) (xy 110.860078 -250.828556) (xy 110.865897 -250.83167)
			(xy 110.878629 -250.835133) (xy 110.885224 -250.835414) (xy 113.332514 -250.835414) (xy 113.35639 -250.82119)
			(xy 113.363248 -250.80849) (xy 113.3757 -250.786214) (xy 113.406397 -250.745446) (xy 113.44299 -250.709877)
			(xy 113.484613 -250.68035) (xy 113.530277 -250.657567) (xy 113.578899 -250.642068) (xy 113.629324 -250.634221)
			(xy 113.65484 -250.633738) (xy 113.678167 -250.634159) (xy 113.724354 -250.640749) (xy 113.76916 -250.65375)
			(xy 113.811701 -250.672906) (xy 113.831624 -250.685046) (xy 113.843816 -250.692666) (xy 113.871502 -250.693174)
			(xy 114.721386 -250.204986) (xy 114.734848 -250.180602) (xy 114.73434 -250.166378) (xy 114.734086 -250.15444)
			(xy 114.734596 -250.128453) (xy 114.742726 -250.077118) (xy 114.758787 -250.027688) (xy 114.782383 -249.981378)
			(xy 114.812933 -249.93933) (xy 114.849684 -249.902579) (xy 114.891732 -249.872029) (xy 114.938042 -249.848433)
			(xy 114.987472 -249.832372) (xy 115.038807 -249.824242) (xy 115.090781 -249.824242) (xy 115.142116 -249.832372)
			(xy 115.191546 -249.848433) (xy 115.237856 -249.872029) (xy 115.279904 -249.902579) (xy 115.316655 -249.93933)
			(xy 115.347205 -249.981378) (xy 115.370801 -250.027688) (xy 115.386862 -250.077118) (xy 115.394992 -250.128453)
			(xy 115.395502 -250.15444) (xy 115.395132 -250.177171) (xy 115.38891 -250.222205) (xy 115.376561 -250.265958)
			(xy 115.358319 -250.3076) (xy 115.346734 -250.32716) (xy 115.339622 -250.339098) (xy 115.339114 -250.367038)
			(xy 115.486434 -250.620784) (xy 115.510818 -250.634246) (xy 115.524788 -250.633992) (xy 115.534694 -250.633738)
			(xy 115.560682 -250.634221) (xy 115.612019 -250.642352) (xy 115.661451 -250.658414) (xy 115.707762 -250.682012)
			(xy 115.74981 -250.712565) (xy 115.786561 -250.74932) (xy 115.817109 -250.791372) (xy 115.840702 -250.837686)
			(xy 115.856758 -250.88712) (xy 115.864882 -250.938458) (xy 115.865402 -250.964446) (xy 115.865402 -250.973082)
			(xy 115.864894 -250.987306) (xy 115.87861 -251.01169) (xy 116.73078 -251.501148) (xy 116.75872 -251.50064)
			(xy 116.770658 -251.493274) (xy 116.790346 -251.481545) (xy 116.832269 -251.463034) (xy 116.876347 -251.450491)
			(xy 116.921734 -251.444155) (xy 116.944648 -251.443744) (xy 116.959888 -251.443998) (xy 116.974112 -251.44476)
			(xy 116.999004 -251.431298) (xy 117.143784 -251.18187) (xy 117.143276 -251.153676) (xy 117.135402 -251.141484)
			(xy 117.123236 -251.121537) (xy 117.104036 -251.078944) (xy 117.091036 -251.034068) (xy 117.084496 -250.987807)
			(xy 117.084094 -250.964446) (xy 117.084574 -250.938454) (xy 117.092699 -250.88711) (xy 117.108757 -250.83767)
			(xy 117.132353 -250.79135) (xy 117.162904 -250.749293) (xy 117.199659 -250.712533) (xy 117.241713 -250.681976)
			(xy 117.288029 -250.658374) (xy 117.337468 -250.64231) (xy 117.38881 -250.634177) (xy 117.414802 -250.633738)
			(xy 117.438122 -250.634117) (xy 117.484306 -250.640627) (xy 117.529117 -250.65356) (xy 117.571666 -250.672661)
			(xy 117.591586 -250.684792) (xy 117.603524 -250.692666) (xy 117.631464 -250.693174) (xy 118.481348 -250.204986)
			(xy 118.49481 -250.180602) (xy 118.494302 -250.166124) (xy 118.494048 -250.15444) (xy 118.494558 -250.128453)
			(xy 118.502688 -250.077118) (xy 118.518749 -250.027688) (xy 118.542345 -249.981378) (xy 118.572895 -249.93933)
			(xy 118.609646 -249.902579) (xy 118.651694 -249.872029) (xy 118.698004 -249.848433) (xy 118.747434 -249.832372)
			(xy 118.798769 -249.824242) (xy 118.850743 -249.824242) (xy 118.902078 -249.832372) (xy 118.951508 -249.848433)
			(xy 118.997818 -249.872029) (xy 119.039866 -249.902579) (xy 119.076617 -249.93933) (xy 119.107167 -249.981378)
			(xy 119.130763 -250.027688) (xy 119.146824 -250.077118) (xy 119.154954 -250.128453) (xy 119.155464 -250.15444)
			(xy 119.155094 -250.177171) (xy 119.148871 -250.222205) (xy 119.136521 -250.265957) (xy 119.118278 -250.307598)
			(xy 119.106696 -250.32716) (xy 119.099584 -250.339098) (xy 119.099076 -250.367038) (xy 119.246396 -250.620784)
			(xy 119.27078 -250.634246) (xy 119.28475 -250.633992) (xy 119.294656 -250.633738) (xy 119.320646 -250.634218)
			(xy 119.371987 -250.642344) (xy 119.421425 -250.658403) (xy 119.467741 -250.681999) (xy 119.509795 -250.712551)
			(xy 119.54655 -250.749307) (xy 119.577102 -250.791361) (xy 119.600698 -250.837677) (xy 119.616757 -250.887115)
			(xy 119.624882 -250.938456) (xy 119.625364 -250.964446) (xy 119.625364 -250.973082) (xy 119.624856 -250.987306)
			(xy 119.638572 -251.01169) (xy 120.490742 -251.501148) (xy 120.518682 -251.50064) (xy 120.53062 -251.493274)
			(xy 120.550307 -251.481542) (xy 120.59223 -251.463027) (xy 120.636307 -251.450479) (xy 120.681696 -251.444137)
			(xy 120.70461 -251.443744) (xy 120.71985 -251.443998) (xy 120.734074 -251.44476) (xy 120.758966 -251.431298)
			(xy 120.903746 -251.18187) (xy 120.903238 -251.153676) (xy 120.895364 -251.141484) (xy 120.8832 -251.121537)
			(xy 120.864002 -251.078943) (xy 120.851003 -251.034067) (xy 120.844464 -250.987807) (xy 120.844056 -250.964446)
			(xy 120.844536 -250.938453) (xy 120.852661 -250.887107) (xy 120.868719 -250.837664) (xy 120.892313 -250.791342)
			(xy 120.922864 -250.749281) (xy 120.959619 -250.712518) (xy 121.001672 -250.681956) (xy 121.047988 -250.65835)
			(xy 121.097427 -250.64228) (xy 121.148771 -250.634142) (xy 121.174764 -250.633738) (xy 121.198083 -250.634121)
			(xy 121.244263 -250.640639) (xy 121.289069 -250.65358) (xy 121.331614 -250.672686) (xy 121.351548 -250.684792)
			(xy 121.363486 -250.692666) (xy 121.391426 -250.693174) (xy 122.24131 -250.204986) (xy 122.254772 -250.180602)
			(xy 122.254264 -250.166378) (xy 122.25401 -250.15444) (xy 122.25452 -250.128453) (xy 122.26265 -250.077118)
			(xy 122.278711 -250.027688) (xy 122.302307 -249.981378) (xy 122.332857 -249.93933) (xy 122.369608 -249.902579)
			(xy 122.411656 -249.872029) (xy 122.457966 -249.848433) (xy 122.507396 -249.832372) (xy 122.558731 -249.824242)
			(xy 122.610705 -249.824242) (xy 122.66204 -249.832372) (xy 122.71147 -249.848433) (xy 122.75778 -249.872029)
			(xy 122.799828 -249.902579) (xy 122.836579 -249.93933) (xy 122.867129 -249.981378) (xy 122.890725 -250.027688)
			(xy 122.906786 -250.077118) (xy 122.914916 -250.128453) (xy 122.915426 -250.15444) (xy 122.91505 -250.177128)
			(xy 122.908845 -250.222077) (xy 122.896557 -250.265756) (xy 122.878416 -250.307348) (xy 122.866912 -250.326906)
			(xy 122.859546 -250.338844) (xy 122.859292 -250.366784) (xy 123.006358 -250.620784) (xy 123.030742 -250.634246)
			(xy 123.044966 -250.633992) (xy 123.054618 -250.633738) (xy 123.080605 -250.634223) (xy 123.131939 -250.642356)
			(xy 123.181368 -250.658421) (xy 123.227675 -250.68202) (xy 123.26972 -250.712573) (xy 123.306468 -250.749328)
			(xy 123.337013 -250.791379) (xy 123.360604 -250.837691) (xy 123.376659 -250.887124) (xy 123.384783 -250.938459)
			(xy 123.385326 -250.964446) (xy 123.385326 -250.973082) (xy 123.384818 -250.987306) (xy 123.398534 -251.01169)
			(xy 124.250704 -251.501148)
		)
		(stroke
			(width 0)
			(type solid)
		)
		(fill yes)
		(layer "In8.Cu")
		(net "PVDDCR_CPU0_P1")
	)
	(gr_poly
		(pts
			(xy 181.346602 -389.076692) (xy 181.356672 -389.076268) (xy 181.375275 -389.068552) (xy 181.38267 -389.061706)
			(xy 184.122822 -386.321554) (xy 184.12967 -386.314157) (xy 184.1374 -386.295558) (xy 184.137808 -386.285486)
			(xy 184.137808 -369.556284) (xy 184.137382 -369.546215) (xy 184.129665 -369.527614) (xy 184.122822 -369.520216)
			(xy 181.865778 -367.263172) (xy 181.858382 -367.256321) (xy 181.839783 -367.248583) (xy 181.82971 -367.248186)
			(xy 70.670674 -367.248186) (xy 70.660606 -367.248613) (xy 70.642007 -367.256333) (xy 70.634606 -367.263172)
			(xy 69.858382 -368.039396) (xy 69.851526 -368.04679) (xy 69.843777 -368.065389) (xy 69.843396 -368.075464)
			(xy 69.843396 -368.086894) (xy 69.850508 -368.104674) (xy 69.857366 -368.11204) (xy 69.875234 -368.131454)
			(xy 69.906 -368.174318) (xy 69.93056 -368.221016) (xy 69.948445 -368.270654) (xy 69.959314 -368.322285)
			(xy 69.962958 -368.374922) (xy 69.959308 -368.427558) (xy 69.948434 -368.479187) (xy 69.930543 -368.528824)
			(xy 69.905977 -368.575519) (xy 69.875206 -368.618379) (xy 69.857366 -368.63782) (xy 69.850981 -368.64514)
			(xy 69.843793 -368.663167) (xy 69.843396 -368.672872) (xy 69.843396 -369.062569) (xy 76.863431 -369.062569)
			(xy 76.863431 -369.008031) (xy 76.871193 -368.954048) (xy 76.886558 -368.90172) (xy 76.909214 -368.85211)
			(xy 76.9387 -368.80623) (xy 76.974414 -368.765013) (xy 77.015632 -368.729298) (xy 77.061512 -368.699813)
			(xy 77.111121 -368.677157) (xy 77.16345 -368.661793) (xy 77.217433 -368.654031) (xy 77.244702 -368.653568)
			(xy 78.108302 -368.653568) (xy 78.135573 -368.653995) (xy 78.189561 -368.661757) (xy 78.241894 -368.677124)
			(xy 78.291508 -368.699782) (xy 78.337393 -368.72927) (xy 78.378613 -368.764988) (xy 78.414331 -368.806209)
			(xy 78.443819 -368.852093) (xy 78.466477 -368.901707) (xy 78.481843 -368.954041) (xy 78.489606 -369.008029)
			(xy 78.489606 -369.062569) (xy 83.670631 -369.062569) (xy 83.670631 -369.008031) (xy 83.678393 -368.954048)
			(xy 83.693758 -368.90172) (xy 83.716414 -368.85211) (xy 83.7459 -368.80623) (xy 83.781614 -368.765013)
			(xy 83.822832 -368.729298) (xy 83.868712 -368.699813) (xy 83.918321 -368.677157) (xy 83.97065 -368.661793)
			(xy 84.024633 -368.654031) (xy 84.051902 -368.653568) (xy 84.915502 -368.653568) (xy 84.942773 -368.653995)
			(xy 84.996761 -368.661757) (xy 85.049094 -368.677124) (xy 85.098708 -368.699782) (xy 85.144593 -368.72927)
			(xy 85.185813 -368.764988) (xy 85.221531 -368.806209) (xy 85.251019 -368.852093) (xy 85.273677 -368.901707)
			(xy 85.289043 -368.954041) (xy 85.296806 -369.008029) (xy 85.296806 -369.062569) (xy 90.477831 -369.062569)
			(xy 90.477831 -369.008031) (xy 90.485593 -368.954048) (xy 90.500958 -368.90172) (xy 90.523614 -368.85211)
			(xy 90.5531 -368.80623) (xy 90.588814 -368.765013) (xy 90.630032 -368.729298) (xy 90.675912 -368.699813)
			(xy 90.725521 -368.677157) (xy 90.77785 -368.661793) (xy 90.831833 -368.654031) (xy 90.859102 -368.653568)
			(xy 91.722702 -368.653568) (xy 91.749973 -368.653995) (xy 91.803961 -368.661757) (xy 91.856294 -368.677124)
			(xy 91.905908 -368.699782) (xy 91.951793 -368.72927) (xy 91.993013 -368.764988) (xy 92.028731 -368.806209)
			(xy 92.058219 -368.852093) (xy 92.080877 -368.901707) (xy 92.096243 -368.954041) (xy 92.104006 -369.008029)
			(xy 92.104006 -369.062569) (xy 97.285031 -369.062569) (xy 97.285031 -369.008031) (xy 97.292793 -368.954048)
			(xy 97.308158 -368.90172) (xy 97.330814 -368.85211) (xy 97.3603 -368.80623) (xy 97.396014 -368.765013)
			(xy 97.437232 -368.729298) (xy 97.483112 -368.699813) (xy 97.532721 -368.677157) (xy 97.58505 -368.661793)
			(xy 97.639033 -368.654031) (xy 97.666302 -368.653568) (xy 98.529902 -368.653568) (xy 98.557173 -368.653995)
			(xy 98.611161 -368.661757) (xy 98.663494 -368.677124) (xy 98.713108 -368.699782) (xy 98.758993 -368.72927)
			(xy 98.800213 -368.764988) (xy 98.835931 -368.806209) (xy 98.865419 -368.852093) (xy 98.888077 -368.901707)
			(xy 98.903443 -368.954041) (xy 98.911206 -369.008029) (xy 98.911206 -369.062569) (xy 100.688631 -369.062569)
			(xy 100.688631 -369.008031) (xy 100.696393 -368.954048) (xy 100.711758 -368.90172) (xy 100.734414 -368.85211)
			(xy 100.7639 -368.80623) (xy 100.799614 -368.765013) (xy 100.840832 -368.729298) (xy 100.886712 -368.699813)
			(xy 100.936321 -368.677157) (xy 100.98865 -368.661793) (xy 101.042633 -368.654031) (xy 101.069902 -368.653568)
			(xy 101.933502 -368.653568) (xy 101.960773 -368.653995) (xy 102.014761 -368.661757) (xy 102.067094 -368.677124)
			(xy 102.116708 -368.699782) (xy 102.162593 -368.72927) (xy 102.203813 -368.764988) (xy 102.239531 -368.806209)
			(xy 102.269019 -368.852093) (xy 102.291677 -368.901707) (xy 102.307043 -368.954041) (xy 102.314806 -369.008029)
			(xy 102.314806 -369.062567) (xy 111.435654 -369.062567) (xy 111.435654 -369.008033) (xy 111.443415 -368.954054)
			(xy 111.458779 -368.901729) (xy 111.481433 -368.852123) (xy 111.510917 -368.806246) (xy 111.546629 -368.765031)
			(xy 111.587842 -368.729319) (xy 111.633719 -368.699835) (xy 111.683325 -368.677181) (xy 111.73565 -368.661816)
			(xy 111.789629 -368.654055) (xy 111.816896 -368.653568) (xy 112.680496 -368.653568) (xy 112.707769 -368.653971)
			(xy 112.761761 -368.661734) (xy 112.814098 -368.677101) (xy 112.863716 -368.69976) (xy 112.909603 -368.72925)
			(xy 112.950827 -368.76497) (xy 112.986548 -368.806193) (xy 113.016038 -368.852081) (xy 113.038698 -368.901698)
			(xy 113.054066 -368.954035) (xy 113.061828 -369.008027) (xy 113.061828 -369.062567) (xy 118.242854 -369.062567)
			(xy 118.242854 -369.008033) (xy 118.250615 -368.954054) (xy 118.265979 -368.901729) (xy 118.288633 -368.852123)
			(xy 118.318117 -368.806246) (xy 118.353829 -368.765031) (xy 118.395042 -368.729319) (xy 118.440919 -368.699835)
			(xy 118.490525 -368.677181) (xy 118.54285 -368.661816) (xy 118.596829 -368.654055) (xy 118.624096 -368.653568)
			(xy 119.487696 -368.653568) (xy 119.514969 -368.653971) (xy 119.568961 -368.661734) (xy 119.621298 -368.677101)
			(xy 119.670916 -368.69976) (xy 119.716803 -368.72925) (xy 119.758027 -368.76497) (xy 119.793748 -368.806193)
			(xy 119.823238 -368.852081) (xy 119.845898 -368.901698) (xy 119.861266 -368.954035) (xy 119.869028 -369.008027)
			(xy 119.869028 -369.062567) (xy 125.050054 -369.062567) (xy 125.050054 -369.008033) (xy 125.057815 -368.954054)
			(xy 125.073179 -368.901729) (xy 125.095833 -368.852123) (xy 125.125317 -368.806246) (xy 125.161029 -368.765031)
			(xy 125.202242 -368.729319) (xy 125.248119 -368.699835) (xy 125.297725 -368.677181) (xy 125.35005 -368.661816)
			(xy 125.404029 -368.654055) (xy 125.431296 -368.653568) (xy 126.294896 -368.653568) (xy 126.322169 -368.653971)
			(xy 126.376161 -368.661734) (xy 126.428498 -368.677101) (xy 126.478116 -368.69976) (xy 126.524003 -368.72925)
			(xy 126.565227 -368.76497) (xy 126.600948 -368.806193) (xy 126.630438 -368.852081) (xy 126.653098 -368.901698)
			(xy 126.668466 -368.954035) (xy 126.676228 -369.008027) (xy 126.676228 -369.062567) (xy 131.857254 -369.062567)
			(xy 131.857254 -369.008033) (xy 131.865015 -368.954054) (xy 131.880379 -368.901729) (xy 131.903033 -368.852123)
			(xy 131.932517 -368.806246) (xy 131.968229 -368.765031) (xy 132.009442 -368.729319) (xy 132.055319 -368.699835)
			(xy 132.104925 -368.677181) (xy 132.15725 -368.661816) (xy 132.211229 -368.654055) (xy 132.238496 -368.653568)
			(xy 133.102096 -368.653568) (xy 133.129369 -368.653971) (xy 133.183361 -368.661734) (xy 133.235698 -368.677101)
			(xy 133.285316 -368.69976) (xy 133.331203 -368.72925) (xy 133.372427 -368.76497) (xy 133.408148 -368.806193)
			(xy 133.437638 -368.852081) (xy 133.460298 -368.901698) (xy 133.475666 -368.954035) (xy 133.483428 -369.008027)
			(xy 133.483428 -369.062567) (xy 135.260854 -369.062567) (xy 135.260854 -369.008033) (xy 135.268615 -368.954054)
			(xy 135.283979 -368.901729) (xy 135.306633 -368.852123) (xy 135.336117 -368.806246) (xy 135.371829 -368.765031)
			(xy 135.413042 -368.729319) (xy 135.458919 -368.699835) (xy 135.508525 -368.677181) (xy 135.56085 -368.661816)
			(xy 135.614829 -368.654055) (xy 135.642096 -368.653568) (xy 136.505696 -368.653568) (xy 136.532969 -368.653971)
			(xy 136.586961 -368.661734) (xy 136.639298 -368.677101) (xy 136.688916 -368.69976) (xy 136.734803 -368.72925)
			(xy 136.776027 -368.76497) (xy 136.811748 -368.806193) (xy 136.841238 -368.852081) (xy 136.863898 -368.901698)
			(xy 136.879266 -368.954035) (xy 136.887028 -369.008027) (xy 136.887028 -369.062573) (xy 136.879266 -369.116565)
			(xy 136.863898 -369.168902) (xy 136.841238 -369.218519) (xy 136.811748 -369.264407) (xy 136.776027 -369.30563)
			(xy 136.734803 -369.34135) (xy 136.688916 -369.37084) (xy 136.639298 -369.393499) (xy 136.586961 -369.408866)
			(xy 136.532969 -369.416629) (xy 136.505696 -369.417092) (xy 135.642096 -369.417092) (xy 135.614829 -369.416545)
			(xy 135.56085 -369.408784) (xy 135.508525 -369.393419) (xy 135.458919 -369.370765) (xy 135.413042 -369.341281)
			(xy 135.371829 -369.305569) (xy 135.336117 -369.264354) (xy 135.306633 -369.218477) (xy 135.283979 -369.168871)
			(xy 135.268615 -369.116546) (xy 135.260854 -369.062567) (xy 133.483428 -369.062567) (xy 133.483428 -369.062573)
			(xy 133.475666 -369.116565) (xy 133.460298 -369.168902) (xy 133.437638 -369.218519) (xy 133.408148 -369.264407)
			(xy 133.372427 -369.30563) (xy 133.331203 -369.34135) (xy 133.285316 -369.37084) (xy 133.235698 -369.393499)
			(xy 133.183361 -369.408866) (xy 133.129369 -369.416629) (xy 133.102096 -369.417092) (xy 132.238496 -369.417092)
			(xy 132.211229 -369.416545) (xy 132.15725 -369.408784) (xy 132.104925 -369.393419) (xy 132.055319 -369.370765)
			(xy 132.009442 -369.341281) (xy 131.968229 -369.305569) (xy 131.932517 -369.264354) (xy 131.903033 -369.218477)
			(xy 131.880379 -369.168871) (xy 131.865015 -369.116546) (xy 131.857254 -369.062567) (xy 126.676228 -369.062567)
			(xy 126.676228 -369.062573) (xy 126.668466 -369.116565) (xy 126.653098 -369.168902) (xy 126.630438 -369.218519)
			(xy 126.600948 -369.264407) (xy 126.565227 -369.30563) (xy 126.524003 -369.34135) (xy 126.478116 -369.37084)
			(xy 126.428498 -369.393499) (xy 126.376161 -369.408866) (xy 126.322169 -369.416629) (xy 126.294896 -369.417092)
			(xy 125.431296 -369.417092) (xy 125.404029 -369.416545) (xy 125.35005 -369.408784) (xy 125.297725 -369.393419)
			(xy 125.248119 -369.370765) (xy 125.202242 -369.341281) (xy 125.161029 -369.305569) (xy 125.125317 -369.264354)
			(xy 125.095833 -369.218477) (xy 125.073179 -369.168871) (xy 125.057815 -369.116546) (xy 125.050054 -369.062567)
			(xy 119.869028 -369.062567) (xy 119.869028 -369.062573) (xy 119.861266 -369.116565) (xy 119.845898 -369.168902)
			(xy 119.823238 -369.218519) (xy 119.793748 -369.264407) (xy 119.758027 -369.30563) (xy 119.716803 -369.34135)
			(xy 119.670916 -369.37084) (xy 119.621298 -369.393499) (xy 119.568961 -369.408866) (xy 119.514969 -369.416629)
			(xy 119.487696 -369.417092) (xy 118.624096 -369.417092) (xy 118.596829 -369.416545) (xy 118.54285 -369.408784)
			(xy 118.490525 -369.393419) (xy 118.440919 -369.370765) (xy 118.395042 -369.341281) (xy 118.353829 -369.305569)
			(xy 118.318117 -369.264354) (xy 118.288633 -369.218477) (xy 118.265979 -369.168871) (xy 118.250615 -369.116546)
			(xy 118.242854 -369.062567) (xy 113.061828 -369.062567) (xy 113.061828 -369.062573) (xy 113.054066 -369.116565)
			(xy 113.038698 -369.168902) (xy 113.016038 -369.218519) (xy 112.986548 -369.264407) (xy 112.950827 -369.30563)
			(xy 112.909603 -369.34135) (xy 112.863716 -369.37084) (xy 112.814098 -369.393499) (xy 112.761761 -369.408866)
			(xy 112.707769 -369.416629) (xy 112.680496 -369.417092) (xy 111.816896 -369.417092) (xy 111.789629 -369.416545)
			(xy 111.73565 -369.408784) (xy 111.683325 -369.393419) (xy 111.633719 -369.370765) (xy 111.587842 -369.341281)
			(xy 111.546629 -369.305569) (xy 111.510917 -369.264354) (xy 111.481433 -369.218477) (xy 111.458779 -369.168871)
			(xy 111.443415 -369.116546) (xy 111.435654 -369.062567) (xy 102.314806 -369.062567) (xy 102.314806 -369.062571)
			(xy 102.307043 -369.116559) (xy 102.291677 -369.168893) (xy 102.269019 -369.218507) (xy 102.239531 -369.264391)
			(xy 102.203813 -369.305612) (xy 102.162593 -369.34133) (xy 102.116708 -369.370818) (xy 102.067094 -369.393476)
			(xy 102.014761 -369.408843) (xy 101.960773 -369.416605) (xy 101.933502 -369.417092) (xy 101.069902 -369.417092)
			(xy 101.042633 -369.416569) (xy 100.98865 -369.408807) (xy 100.936321 -369.393443) (xy 100.886712 -369.370787)
			(xy 100.840832 -369.341302) (xy 100.799614 -369.305587) (xy 100.7639 -369.26437) (xy 100.734414 -369.21849)
			(xy 100.711758 -369.16888) (xy 100.696393 -369.116552) (xy 100.688631 -369.062569) (xy 98.911206 -369.062569)
			(xy 98.911206 -369.062571) (xy 98.903443 -369.116559) (xy 98.888077 -369.168893) (xy 98.865419 -369.218507)
			(xy 98.835931 -369.264391) (xy 98.800213 -369.305612) (xy 98.758993 -369.34133) (xy 98.713108 -369.370818)
			(xy 98.663494 -369.393476) (xy 98.611161 -369.408843) (xy 98.557173 -369.416605) (xy 98.529902 -369.417092)
			(xy 97.666302 -369.417092) (xy 97.639033 -369.416569) (xy 97.58505 -369.408807) (xy 97.532721 -369.393443)
			(xy 97.483112 -369.370787) (xy 97.437232 -369.341302) (xy 97.396014 -369.305587) (xy 97.3603 -369.26437)
			(xy 97.330814 -369.21849) (xy 97.308158 -369.16888) (xy 97.292793 -369.116552) (xy 97.285031 -369.062569)
			(xy 92.104006 -369.062569) (xy 92.104006 -369.062571) (xy 92.096243 -369.116559) (xy 92.080877 -369.168893)
			(xy 92.058219 -369.218507) (xy 92.028731 -369.264391) (xy 91.993013 -369.305612) (xy 91.951793 -369.34133)
			(xy 91.905908 -369.370818) (xy 91.856294 -369.393476) (xy 91.803961 -369.408843) (xy 91.749973 -369.416605)
			(xy 91.722702 -369.417092) (xy 90.859102 -369.417092) (xy 90.831833 -369.416569) (xy 90.77785 -369.408807)
			(xy 90.725521 -369.393443) (xy 90.675912 -369.370787) (xy 90.630032 -369.341302) (xy 90.588814 -369.305587)
			(xy 90.5531 -369.26437) (xy 90.523614 -369.21849) (xy 90.500958 -369.16888) (xy 90.485593 -369.116552)
			(xy 90.477831 -369.062569) (xy 85.296806 -369.062569) (xy 85.296806 -369.062571) (xy 85.289043 -369.116559)
			(xy 85.273677 -369.168893) (xy 85.251019 -369.218507) (xy 85.221531 -369.264391) (xy 85.185813 -369.305612)
			(xy 85.144593 -369.34133) (xy 85.098708 -369.370818) (xy 85.049094 -369.393476) (xy 84.996761 -369.408843)
			(xy 84.942773 -369.416605) (xy 84.915502 -369.417092) (xy 84.051902 -369.417092) (xy 84.024633 -369.416569)
			(xy 83.97065 -369.408807) (xy 83.918321 -369.393443) (xy 83.868712 -369.370787) (xy 83.822832 -369.341302)
			(xy 83.781614 -369.305587) (xy 83.7459 -369.26437) (xy 83.716414 -369.21849) (xy 83.693758 -369.16888)
			(xy 83.678393 -369.116552) (xy 83.670631 -369.062569) (xy 78.489606 -369.062569) (xy 78.489606 -369.062571)
			(xy 78.481843 -369.116559) (xy 78.466477 -369.168893) (xy 78.443819 -369.218507) (xy 78.414331 -369.264391)
			(xy 78.378613 -369.305612) (xy 78.337393 -369.34133) (xy 78.291508 -369.370818) (xy 78.241894 -369.393476)
			(xy 78.189561 -369.408843) (xy 78.135573 -369.416605) (xy 78.108302 -369.417092) (xy 77.244702 -369.417092)
			(xy 77.217433 -369.416569) (xy 77.16345 -369.408807) (xy 77.111121 -369.393443) (xy 77.061512 -369.370787)
			(xy 77.015632 -369.341302) (xy 76.974414 -369.305587) (xy 76.9387 -369.26437) (xy 76.909214 -369.21849)
			(xy 76.886558 -369.16888) (xy 76.871193 -369.116552) (xy 76.863431 -369.062569) (xy 69.843396 -369.062569)
			(xy 69.843396 -369.397788) (xy 69.843831 -369.407484) (xy 69.85102 -369.425495) (xy 69.857366 -369.43284)
			(xy 69.875234 -369.452254) (xy 69.906 -369.495118) (xy 69.93056 -369.541816) (xy 69.948445 -369.591454)
			(xy 69.959314 -369.643085) (xy 69.962958 -369.695722) (xy 69.959308 -369.748358) (xy 69.948434 -369.799987)
			(xy 69.930543 -369.849624) (xy 69.905977 -369.896319) (xy 69.875206 -369.939179) (xy 69.857366 -369.95862)
			(xy 69.850981 -369.96594) (xy 69.843793 -369.983967) (xy 69.843396 -369.993672) (xy 69.843396 -370.206778)
			(xy 138.3665 -370.206778) (xy 138.3665 -369.343178) (xy 138.366986 -369.315909) (xy 138.374748 -369.261925)
			(xy 138.390113 -369.209595) (xy 138.41277 -369.159985) (xy 138.442256 -369.114104) (xy 138.477971 -369.072887)
			(xy 138.519188 -369.037172) (xy 138.565069 -369.007686) (xy 138.614679 -368.985029) (xy 138.667009 -368.969664)
			(xy 138.720993 -368.961902) (xy 138.775531 -368.961902) (xy 138.829515 -368.969664) (xy 138.881845 -368.985029)
			(xy 138.931455 -369.007686) (xy 138.977336 -369.037172) (xy 139.006648 -369.062571) (xy 143.963332 -369.062571)
			(xy 143.963332 -369.008029) (xy 143.971094 -368.954043) (xy 143.986461 -368.901711) (xy 144.009121 -368.852098)
			(xy 144.03861 -368.806216) (xy 144.074329 -368.764998) (xy 144.115551 -368.729284) (xy 144.161437 -368.699799)
			(xy 144.211052 -368.677146) (xy 144.263386 -368.661785) (xy 144.317373 -368.654028) (xy 144.344644 -368.653568)
			(xy 145.208244 -368.653568) (xy 145.235513 -368.653998) (xy 145.289497 -368.661765) (xy 145.341825 -368.677135)
			(xy 145.391433 -368.699796) (xy 145.437312 -368.729285) (xy 145.478528 -368.765003) (xy 145.514241 -368.806223)
			(xy 145.543725 -368.852105) (xy 145.56638 -368.901716) (xy 145.581744 -368.954047) (xy 145.589506 -369.00803)
			(xy 145.589506 -369.06257) (xy 145.589506 -369.062571) (xy 150.770532 -369.062571) (xy 150.770532 -369.008029)
			(xy 150.778294 -368.954043) (xy 150.793661 -368.901711) (xy 150.816321 -368.852098) (xy 150.84581 -368.806216)
			(xy 150.881529 -368.764998) (xy 150.922751 -368.729284) (xy 150.968637 -368.699799) (xy 151.018252 -368.677146)
			(xy 151.070586 -368.661785) (xy 151.124573 -368.654028) (xy 151.151844 -368.653568) (xy 152.015444 -368.653568)
			(xy 152.042713 -368.653998) (xy 152.096697 -368.661765) (xy 152.149025 -368.677135) (xy 152.198633 -368.699796)
			(xy 152.244512 -368.729285) (xy 152.285728 -368.765003) (xy 152.321441 -368.806223) (xy 152.350925 -368.852105)
			(xy 152.37358 -368.901716) (xy 152.388944 -368.954047) (xy 152.396706 -369.00803) (xy 152.396706 -369.06257)
			(xy 152.396706 -369.062571) (xy 157.577732 -369.062571) (xy 157.577732 -369.008029) (xy 157.585494 -368.954043)
			(xy 157.600861 -368.901711) (xy 157.623521 -368.852098) (xy 157.65301 -368.806216) (xy 157.688729 -368.764998)
			(xy 157.729951 -368.729284) (xy 157.775837 -368.699799) (xy 157.825452 -368.677146) (xy 157.877786 -368.661785)
			(xy 157.931773 -368.654028) (xy 157.959044 -368.653568) (xy 158.822644 -368.653568) (xy 158.849913 -368.653998)
			(xy 158.903897 -368.661765) (xy 158.956225 -368.677135) (xy 159.005833 -368.699796) (xy 159.051712 -368.729285)
			(xy 159.092928 -368.765003) (xy 159.128641 -368.806223) (xy 159.158125 -368.852105) (xy 159.18078 -368.901716)
			(xy 159.196144 -368.954047) (xy 159.203906 -369.00803) (xy 159.203906 -369.06257) (xy 159.203906 -369.062571)
			(xy 164.384932 -369.062571) (xy 164.384932 -369.008029) (xy 164.392694 -368.954043) (xy 164.408061 -368.901711)
			(xy 164.430721 -368.852098) (xy 164.46021 -368.806216) (xy 164.495929 -368.764998) (xy 164.537151 -368.729284)
			(xy 164.583037 -368.699799) (xy 164.632652 -368.677146) (xy 164.684986 -368.661785) (xy 164.738973 -368.654028)
			(xy 164.766244 -368.653568) (xy 165.629844 -368.653568) (xy 165.657113 -368.653998) (xy 165.711097 -368.661765)
			(xy 165.763425 -368.677135) (xy 165.813033 -368.699796) (xy 165.858912 -368.729285) (xy 165.900128 -368.765003)
			(xy 165.935841 -368.806223) (xy 165.965325 -368.852105) (xy 165.98798 -368.901716) (xy 166.003344 -368.954047)
			(xy 166.011106 -369.00803) (xy 166.011106 -369.06257) (xy 166.011106 -369.062571) (xy 167.788532 -369.062571)
			(xy 167.788532 -369.008029) (xy 167.796294 -368.954043) (xy 167.811661 -368.901711) (xy 167.834321 -368.852098)
			(xy 167.86381 -368.806216) (xy 167.899529 -368.764998) (xy 167.940751 -368.729284) (xy 167.986637 -368.699799)
			(xy 168.036252 -368.677146) (xy 168.088586 -368.661785) (xy 168.142573 -368.654028) (xy 168.169844 -368.653568)
			(xy 169.033444 -368.653568) (xy 169.060713 -368.653998) (xy 169.114697 -368.661765) (xy 169.167025 -368.677135)
			(xy 169.216633 -368.699796) (xy 169.262512 -368.729285) (xy 169.303728 -368.765003) (xy 169.339441 -368.806223)
			(xy 169.368925 -368.852105) (xy 169.39158 -368.901716) (xy 169.406944 -368.954047) (xy 169.414706 -369.00803)
			(xy 169.414706 -369.06257) (xy 169.406944 -369.116553) (xy 169.39158 -369.168884) (xy 169.368925 -369.218495)
			(xy 169.339441 -369.264377) (xy 169.303728 -369.305597) (xy 169.262512 -369.341315) (xy 169.216633 -369.370804)
			(xy 169.167025 -369.393465) (xy 169.114697 -369.408835) (xy 169.060713 -369.416602) (xy 169.033444 -369.417092)
			(xy 168.169844 -369.417092) (xy 168.142573 -369.416572) (xy 168.088586 -369.408815) (xy 168.036252 -369.393454)
			(xy 167.986637 -369.370801) (xy 167.940751 -369.341316) (xy 167.899529 -369.305602) (xy 167.86381 -369.264384)
			(xy 167.834321 -369.218502) (xy 167.811661 -369.168889) (xy 167.796294 -369.116557) (xy 167.788532 -369.062571)
			(xy 166.011106 -369.062571) (xy 166.003344 -369.116553) (xy 165.98798 -369.168884) (xy 165.965325 -369.218495)
			(xy 165.935841 -369.264377) (xy 165.900128 -369.305597) (xy 165.858912 -369.341315) (xy 165.813033 -369.370804)
			(xy 165.763425 -369.393465) (xy 165.711097 -369.408835) (xy 165.657113 -369.416602) (xy 165.629844 -369.417092)
			(xy 164.766244 -369.417092) (xy 164.738973 -369.416572) (xy 164.684986 -369.408815) (xy 164.632652 -369.393454)
			(xy 164.583037 -369.370801) (xy 164.537151 -369.341316) (xy 164.495929 -369.305602) (xy 164.46021 -369.264384)
			(xy 164.430721 -369.218502) (xy 164.408061 -369.168889) (xy 164.392694 -369.116557) (xy 164.384932 -369.062571)
			(xy 159.203906 -369.062571) (xy 159.196144 -369.116553) (xy 159.18078 -369.168884) (xy 159.158125 -369.218495)
			(xy 159.128641 -369.264377) (xy 159.092928 -369.305597) (xy 159.051712 -369.341315) (xy 159.005833 -369.370804)
			(xy 158.956225 -369.393465) (xy 158.903897 -369.408835) (xy 158.849913 -369.416602) (xy 158.822644 -369.417092)
			(xy 157.959044 -369.417092) (xy 157.931773 -369.416572) (xy 157.877786 -369.408815) (xy 157.825452 -369.393454)
			(xy 157.775837 -369.370801) (xy 157.729951 -369.341316) (xy 157.688729 -369.305602) (xy 157.65301 -369.264384)
			(xy 157.623521 -369.218502) (xy 157.600861 -369.168889) (xy 157.585494 -369.116557) (xy 157.577732 -369.062571)
			(xy 152.396706 -369.062571) (xy 152.388944 -369.116553) (xy 152.37358 -369.168884) (xy 152.350925 -369.218495)
			(xy 152.321441 -369.264377) (xy 152.285728 -369.305597) (xy 152.244512 -369.341315) (xy 152.198633 -369.370804)
			(xy 152.149025 -369.393465) (xy 152.096697 -369.408835) (xy 152.042713 -369.416602) (xy 152.015444 -369.417092)
			(xy 151.151844 -369.417092) (xy 151.124573 -369.416572) (xy 151.070586 -369.408815) (xy 151.018252 -369.393454)
			(xy 150.968637 -369.370801) (xy 150.922751 -369.341316) (xy 150.881529 -369.305602) (xy 150.84581 -369.264384)
			(xy 150.816321 -369.218502) (xy 150.793661 -369.168889) (xy 150.778294 -369.116557) (xy 150.770532 -369.062571)
			(xy 145.589506 -369.062571) (xy 145.581744 -369.116553) (xy 145.56638 -369.168884) (xy 145.543725 -369.218495)
			(xy 145.514241 -369.264377) (xy 145.478528 -369.305597) (xy 145.437312 -369.341315) (xy 145.391433 -369.370804)
			(xy 145.341825 -369.393465) (xy 145.289497 -369.408835) (xy 145.235513 -369.416602) (xy 145.208244 -369.417092)
			(xy 144.344644 -369.417092) (xy 144.317373 -369.416572) (xy 144.263386 -369.408815) (xy 144.211052 -369.393454)
			(xy 144.161437 -369.370801) (xy 144.115551 -369.341316) (xy 144.074329 -369.305602) (xy 144.03861 -369.264384)
			(xy 144.009121 -369.218502) (xy 143.986461 -369.168889) (xy 143.971094 -369.116557) (xy 143.963332 -369.062571)
			(xy 139.006648 -369.062571) (xy 139.018553 -369.072887) (xy 139.054268 -369.114104) (xy 139.083754 -369.159985)
			(xy 139.106411 -369.209595) (xy 139.121776 -369.261925) (xy 139.129538 -369.315909) (xy 139.130024 -369.343178)
			(xy 139.130024 -370.206778) (xy 139.129538 -370.234047) (xy 139.121776 -370.288031) (xy 139.106411 -370.340361)
			(xy 139.083754 -370.389971) (xy 139.071223 -370.40947) (xy 141.572996 -370.40947) (xy 141.572996 -369.54587)
			(xy 141.573482 -369.518619) (xy 141.581238 -369.464671) (xy 141.596593 -369.412376) (xy 141.619235 -369.362799)
			(xy 141.648701 -369.316949) (xy 141.684392 -369.275758) (xy 141.725583 -369.240067) (xy 141.771433 -369.210601)
			(xy 141.82101 -369.187959) (xy 141.873305 -369.172604) (xy 141.927253 -369.164848) (xy 141.981755 -369.164848)
			(xy 142.035703 -369.172604) (xy 142.087998 -369.187959) (xy 142.137575 -369.210601) (xy 142.183425 -369.240067)
			(xy 142.224616 -369.275758) (xy 142.260307 -369.316949) (xy 142.289773 -369.362799) (xy 142.312415 -369.412376)
			(xy 142.32777 -369.464671) (xy 142.335526 -369.518619) (xy 142.336012 -369.54587) (xy 142.336012 -369.62565)
			(xy 175.203103 -369.62565) (xy 175.203103 -369.57115) (xy 175.210859 -369.517206) (xy 175.226214 -369.464914)
			(xy 175.248854 -369.41534) (xy 175.278318 -369.369493) (xy 175.314008 -369.328305) (xy 175.355196 -369.292616)
			(xy 175.401044 -369.263152) (xy 175.450618 -369.240512) (xy 175.50291 -369.225158) (xy 175.556854 -369.217403)
			(xy 175.584104 -369.21694) (xy 176.447704 -369.21694) (xy 176.474958 -369.21733) (xy 176.528913 -369.225088)
			(xy 176.581213 -369.240446) (xy 176.630796 -369.26309) (xy 176.676652 -369.29256) (xy 176.717847 -369.328256)
			(xy 176.753543 -369.369451) (xy 176.783012 -369.415307) (xy 176.805656 -369.46489) (xy 176.821013 -369.517191)
			(xy 176.82877 -369.571146) (xy 176.82877 -369.625654) (xy 176.821013 -369.679609) (xy 176.805656 -369.73191)
			(xy 176.783012 -369.781493) (xy 176.753543 -369.827349) (xy 176.717847 -369.868544) (xy 176.676652 -369.90424)
			(xy 176.630796 -369.93371) (xy 176.581213 -369.956354) (xy 176.528913 -369.971712) (xy 176.474958 -369.97947)
			(xy 176.447704 -369.979956) (xy 175.584104 -369.979956) (xy 175.556854 -369.979397) (xy 175.50291 -369.971642)
			(xy 175.450618 -369.956288) (xy 175.401044 -369.933648) (xy 175.355196 -369.904184) (xy 175.314008 -369.868495)
			(xy 175.278318 -369.827307) (xy 175.248854 -369.78146) (xy 175.226214 -369.731886) (xy 175.210859 -369.679594)
			(xy 175.203103 -369.62565) (xy 142.336012 -369.62565) (xy 142.336012 -370.40947) (xy 142.335526 -370.436721)
			(xy 142.32777 -370.490669) (xy 142.312415 -370.542964) (xy 142.289773 -370.592541) (xy 142.260307 -370.638391)
			(xy 142.224616 -370.679582) (xy 142.183425 -370.715273) (xy 142.137575 -370.744739) (xy 142.087998 -370.767381)
			(xy 142.035703 -370.782736) (xy 141.981755 -370.790492) (xy 141.927253 -370.790492) (xy 141.873305 -370.782736)
			(xy 141.82101 -370.767381) (xy 141.771433 -370.744739) (xy 141.725583 -370.715273) (xy 141.684392 -370.679582)
			(xy 141.648701 -370.638391) (xy 141.619235 -370.592541) (xy 141.596593 -370.542964) (xy 141.581238 -370.490669)
			(xy 141.573482 -370.436721) (xy 141.572996 -370.40947) (xy 139.071223 -370.40947) (xy 139.054268 -370.435852)
			(xy 139.018553 -370.477069) (xy 138.977336 -370.512784) (xy 138.931455 -370.54227) (xy 138.881845 -370.564927)
			(xy 138.829515 -370.580292) (xy 138.775531 -370.588054) (xy 138.720993 -370.588054) (xy 138.667009 -370.580292)
			(xy 138.614679 -370.564927) (xy 138.565069 -370.54227) (xy 138.519188 -370.512784) (xy 138.477971 -370.477069)
			(xy 138.442256 -370.435852) (xy 138.41277 -370.389971) (xy 138.390113 -370.340361) (xy 138.374748 -370.288031)
			(xy 138.366986 -370.234047) (xy 138.3665 -370.206778) (xy 69.843396 -370.206778) (xy 69.843396 -371.526369)
			(xy 75.161631 -371.526369) (xy 75.161631 -371.471831) (xy 75.169393 -371.417848) (xy 75.184758 -371.36552)
			(xy 75.207414 -371.31591) (xy 75.2369 -371.27003) (xy 75.272614 -371.228813) (xy 75.313832 -371.193098)
			(xy 75.359712 -371.163613) (xy 75.409321 -371.140957) (xy 75.46165 -371.125593) (xy 75.515633 -371.117831)
			(xy 75.542902 -371.117368) (xy 76.406502 -371.117368) (xy 76.433773 -371.117795) (xy 76.487761 -371.125557)
			(xy 76.540094 -371.140924) (xy 76.589708 -371.163582) (xy 76.635593 -371.19307) (xy 76.676813 -371.228788)
			(xy 76.712531 -371.270009) (xy 76.742019 -371.315893) (xy 76.764677 -371.365507) (xy 76.780043 -371.417841)
			(xy 76.787806 -371.471829) (xy 76.787806 -371.526369) (xy 81.968831 -371.526369) (xy 81.968831 -371.471831)
			(xy 81.976593 -371.417848) (xy 81.991958 -371.36552) (xy 82.014614 -371.31591) (xy 82.0441 -371.27003)
			(xy 82.079814 -371.228813) (xy 82.121032 -371.193098) (xy 82.166912 -371.163613) (xy 82.216521 -371.140957)
			(xy 82.26885 -371.125593) (xy 82.322833 -371.117831) (xy 82.350102 -371.117368) (xy 83.213702 -371.117368)
			(xy 83.240973 -371.117795) (xy 83.294961 -371.125557) (xy 83.347294 -371.140924) (xy 83.396908 -371.163582)
			(xy 83.442793 -371.19307) (xy 83.484013 -371.228788) (xy 83.519731 -371.270009) (xy 83.549219 -371.315893)
			(xy 83.571877 -371.365507) (xy 83.587243 -371.417841) (xy 83.595006 -371.471829) (xy 83.595006 -371.526369)
			(xy 88.776031 -371.526369) (xy 88.776031 -371.471831) (xy 88.783793 -371.417848) (xy 88.799158 -371.36552)
			(xy 88.821814 -371.31591) (xy 88.8513 -371.27003) (xy 88.887014 -371.228813) (xy 88.928232 -371.193098)
			(xy 88.974112 -371.163613) (xy 89.023721 -371.140957) (xy 89.07605 -371.125593) (xy 89.130033 -371.117831)
			(xy 89.157302 -371.117368) (xy 90.020902 -371.117368) (xy 90.048173 -371.117795) (xy 90.102161 -371.125557)
			(xy 90.154494 -371.140924) (xy 90.204108 -371.163582) (xy 90.249993 -371.19307) (xy 90.291213 -371.228788)
			(xy 90.326931 -371.270009) (xy 90.356419 -371.315893) (xy 90.379077 -371.365507) (xy 90.394443 -371.417841)
			(xy 90.402206 -371.471829) (xy 90.402206 -371.526369) (xy 95.583231 -371.526369) (xy 95.583231 -371.471831)
			(xy 95.590993 -371.417848) (xy 95.606358 -371.36552) (xy 95.629014 -371.31591) (xy 95.6585 -371.27003)
			(xy 95.694214 -371.228813) (xy 95.735432 -371.193098) (xy 95.781312 -371.163613) (xy 95.830921 -371.140957)
			(xy 95.88325 -371.125593) (xy 95.937233 -371.117831) (xy 95.964502 -371.117368) (xy 96.828102 -371.117368)
			(xy 96.855373 -371.117795) (xy 96.909361 -371.125557) (xy 96.961694 -371.140924) (xy 97.011308 -371.163582)
			(xy 97.057193 -371.19307) (xy 97.098413 -371.228788) (xy 97.134131 -371.270009) (xy 97.163619 -371.315893)
			(xy 97.186277 -371.365507) (xy 97.201643 -371.417841) (xy 97.209406 -371.471829) (xy 97.209406 -371.526367)
			(xy 109.733854 -371.526367) (xy 109.733854 -371.471833) (xy 109.741615 -371.417854) (xy 109.756979 -371.365529)
			(xy 109.779633 -371.315923) (xy 109.809117 -371.270046) (xy 109.844829 -371.228831) (xy 109.886042 -371.193119)
			(xy 109.931919 -371.163635) (xy 109.981525 -371.140981) (xy 110.03385 -371.125616) (xy 110.087829 -371.117855)
			(xy 110.115096 -371.117368) (xy 110.978696 -371.117368) (xy 111.005969 -371.117771) (xy 111.059961 -371.125534)
			(xy 111.112298 -371.140901) (xy 111.161916 -371.16356) (xy 111.207803 -371.19305) (xy 111.249027 -371.22877)
			(xy 111.284748 -371.269993) (xy 111.314238 -371.315881) (xy 111.336898 -371.365498) (xy 111.352266 -371.417835)
			(xy 111.360028 -371.471827) (xy 111.360028 -371.526367) (xy 116.541054 -371.526367) (xy 116.541054 -371.471833)
			(xy 116.548815 -371.417854) (xy 116.564179 -371.365529) (xy 116.586833 -371.315923) (xy 116.616317 -371.270046)
			(xy 116.652029 -371.228831) (xy 116.693242 -371.193119) (xy 116.739119 -371.163635) (xy 116.788725 -371.140981)
			(xy 116.84105 -371.125616) (xy 116.895029 -371.117855) (xy 116.922296 -371.117368) (xy 117.785896 -371.117368)
			(xy 117.813169 -371.117771) (xy 117.867161 -371.125534) (xy 117.919498 -371.140901) (xy 117.969116 -371.16356)
			(xy 118.015003 -371.19305) (xy 118.056227 -371.22877) (xy 118.091948 -371.269993) (xy 118.121438 -371.315881)
			(xy 118.144098 -371.365498) (xy 118.159466 -371.417835) (xy 118.167228 -371.471827) (xy 118.167228 -371.526367)
			(xy 123.348254 -371.526367) (xy 123.348254 -371.471833) (xy 123.356015 -371.417854) (xy 123.371379 -371.365529)
			(xy 123.394033 -371.315923) (xy 123.423517 -371.270046) (xy 123.459229 -371.228831) (xy 123.500442 -371.193119)
			(xy 123.546319 -371.163635) (xy 123.595925 -371.140981) (xy 123.64825 -371.125616) (xy 123.702229 -371.117855)
			(xy 123.729496 -371.117368) (xy 124.593096 -371.117368) (xy 124.620369 -371.117771) (xy 124.674361 -371.125534)
			(xy 124.726698 -371.140901) (xy 124.776316 -371.16356) (xy 124.822203 -371.19305) (xy 124.863427 -371.22877)
			(xy 124.899148 -371.269993) (xy 124.928638 -371.315881) (xy 124.951298 -371.365498) (xy 124.966666 -371.417835)
			(xy 124.974428 -371.471827) (xy 124.974428 -371.526367) (xy 130.155454 -371.526367) (xy 130.155454 -371.471833)
			(xy 130.163215 -371.417854) (xy 130.178579 -371.365529) (xy 130.201233 -371.315923) (xy 130.230717 -371.270046)
			(xy 130.266429 -371.228831) (xy 130.307642 -371.193119) (xy 130.353519 -371.163635) (xy 130.403125 -371.140981)
			(xy 130.45545 -371.125616) (xy 130.509429 -371.117855) (xy 130.536696 -371.117368) (xy 131.400296 -371.117368)
			(xy 131.427569 -371.117771) (xy 131.481561 -371.125534) (xy 131.533898 -371.140901) (xy 131.583516 -371.16356)
			(xy 131.629403 -371.19305) (xy 131.670627 -371.22877) (xy 131.706348 -371.269993) (xy 131.735838 -371.315881)
			(xy 131.758498 -371.365498) (xy 131.773866 -371.417835) (xy 131.781628 -371.471827) (xy 131.781628 -371.526371)
			(xy 142.261532 -371.526371) (xy 142.261532 -371.471829) (xy 142.269294 -371.417843) (xy 142.284661 -371.365511)
			(xy 142.307321 -371.315898) (xy 142.33681 -371.270016) (xy 142.372529 -371.228798) (xy 142.413751 -371.193084)
			(xy 142.459637 -371.163599) (xy 142.509252 -371.140946) (xy 142.561586 -371.125585) (xy 142.615573 -371.117828)
			(xy 142.642844 -371.117368) (xy 143.506444 -371.117368) (xy 143.533713 -371.117798) (xy 143.587697 -371.125565)
			(xy 143.640025 -371.140935) (xy 143.689633 -371.163596) (xy 143.735512 -371.193085) (xy 143.776728 -371.228803)
			(xy 143.812441 -371.270023) (xy 143.841925 -371.315905) (xy 143.86458 -371.365516) (xy 143.879944 -371.417847)
			(xy 143.887706 -371.47183) (xy 143.887706 -371.52637) (xy 143.887706 -371.526371) (xy 149.068732 -371.526371)
			(xy 149.068732 -371.471829) (xy 149.076494 -371.417843) (xy 149.091861 -371.365511) (xy 149.114521 -371.315898)
			(xy 149.14401 -371.270016) (xy 149.179729 -371.228798) (xy 149.220951 -371.193084) (xy 149.266837 -371.163599)
			(xy 149.316452 -371.140946) (xy 149.368786 -371.125585) (xy 149.422773 -371.117828) (xy 149.450044 -371.117368)
			(xy 150.313644 -371.117368) (xy 150.340913 -371.117798) (xy 150.394897 -371.125565) (xy 150.447225 -371.140935)
			(xy 150.496833 -371.163596) (xy 150.542712 -371.193085) (xy 150.583928 -371.228803) (xy 150.619641 -371.270023)
			(xy 150.649125 -371.315905) (xy 150.67178 -371.365516) (xy 150.687144 -371.417847) (xy 150.694906 -371.47183)
			(xy 150.694906 -371.52637) (xy 150.694906 -371.526371) (xy 155.875932 -371.526371) (xy 155.875932 -371.471829)
			(xy 155.883694 -371.417843) (xy 155.899061 -371.365511) (xy 155.921721 -371.315898) (xy 155.95121 -371.270016)
			(xy 155.986929 -371.228798) (xy 156.028151 -371.193084) (xy 156.074037 -371.163599) (xy 156.123652 -371.140946)
			(xy 156.175986 -371.125585) (xy 156.229973 -371.117828) (xy 156.257244 -371.117368) (xy 157.120844 -371.117368)
			(xy 157.148113 -371.117798) (xy 157.202097 -371.125565) (xy 157.254425 -371.140935) (xy 157.304033 -371.163596)
			(xy 157.349912 -371.193085) (xy 157.391128 -371.228803) (xy 157.426841 -371.270023) (xy 157.456325 -371.315905)
			(xy 157.47898 -371.365516) (xy 157.494344 -371.417847) (xy 157.502106 -371.47183) (xy 157.502106 -371.52637)
			(xy 157.502106 -371.526371) (xy 162.683132 -371.526371) (xy 162.683132 -371.471829) (xy 162.690894 -371.417843)
			(xy 162.706261 -371.365511) (xy 162.728921 -371.315898) (xy 162.75841 -371.270016) (xy 162.794129 -371.228798)
			(xy 162.835351 -371.193084) (xy 162.881237 -371.163599) (xy 162.930852 -371.140946) (xy 162.983186 -371.125585)
			(xy 163.037173 -371.117828) (xy 163.064444 -371.117368) (xy 163.928044 -371.117368) (xy 163.955313 -371.117798)
			(xy 164.009297 -371.125565) (xy 164.061625 -371.140935) (xy 164.111233 -371.163596) (xy 164.157112 -371.193085)
			(xy 164.198328 -371.228803) (xy 164.234041 -371.270023) (xy 164.263525 -371.315905) (xy 164.28618 -371.365516)
			(xy 164.301544 -371.417847) (xy 164.309306 -371.47183) (xy 164.309306 -371.52637) (xy 164.301544 -371.580353)
			(xy 164.28618 -371.632684) (xy 164.263525 -371.682295) (xy 164.234041 -371.728177) (xy 164.198328 -371.769397)
			(xy 164.157112 -371.805115) (xy 164.111233 -371.834604) (xy 164.061625 -371.857265) (xy 164.009297 -371.872635)
			(xy 163.955313 -371.880402) (xy 163.928044 -371.880892) (xy 163.064444 -371.880892) (xy 163.037173 -371.880372)
			(xy 162.983186 -371.872615) (xy 162.930852 -371.857254) (xy 162.881237 -371.834601) (xy 162.835351 -371.805116)
			(xy 162.794129 -371.769402) (xy 162.75841 -371.728184) (xy 162.728921 -371.682302) (xy 162.706261 -371.632689)
			(xy 162.690894 -371.580357) (xy 162.683132 -371.526371) (xy 157.502106 -371.526371) (xy 157.494344 -371.580353)
			(xy 157.47898 -371.632684) (xy 157.456325 -371.682295) (xy 157.426841 -371.728177) (xy 157.391128 -371.769397)
			(xy 157.349912 -371.805115) (xy 157.304033 -371.834604) (xy 157.254425 -371.857265) (xy 157.202097 -371.872635)
			(xy 157.148113 -371.880402) (xy 157.120844 -371.880892) (xy 156.257244 -371.880892) (xy 156.229973 -371.880372)
			(xy 156.175986 -371.872615) (xy 156.123652 -371.857254) (xy 156.074037 -371.834601) (xy 156.028151 -371.805116)
			(xy 155.986929 -371.769402) (xy 155.95121 -371.728184) (xy 155.921721 -371.682302) (xy 155.899061 -371.632689)
			(xy 155.883694 -371.580357) (xy 155.875932 -371.526371) (xy 150.694906 -371.526371) (xy 150.687144 -371.580353)
			(xy 150.67178 -371.632684) (xy 150.649125 -371.682295) (xy 150.619641 -371.728177) (xy 150.583928 -371.769397)
			(xy 150.542712 -371.805115) (xy 150.496833 -371.834604) (xy 150.447225 -371.857265) (xy 150.394897 -371.872635)
			(xy 150.340913 -371.880402) (xy 150.313644 -371.880892) (xy 149.450044 -371.880892) (xy 149.422773 -371.880372)
			(xy 149.368786 -371.872615) (xy 149.316452 -371.857254) (xy 149.266837 -371.834601) (xy 149.220951 -371.805116)
			(xy 149.179729 -371.769402) (xy 149.14401 -371.728184) (xy 149.114521 -371.682302) (xy 149.091861 -371.632689)
			(xy 149.076494 -371.580357) (xy 149.068732 -371.526371) (xy 143.887706 -371.526371) (xy 143.879944 -371.580353)
			(xy 143.86458 -371.632684) (xy 143.841925 -371.682295) (xy 143.812441 -371.728177) (xy 143.776728 -371.769397)
			(xy 143.735512 -371.805115) (xy 143.689633 -371.834604) (xy 143.640025 -371.857265) (xy 143.587697 -371.872635)
			(xy 143.533713 -371.880402) (xy 143.506444 -371.880892) (xy 142.642844 -371.880892) (xy 142.615573 -371.880372)
			(xy 142.561586 -371.872615) (xy 142.509252 -371.857254) (xy 142.459637 -371.834601) (xy 142.413751 -371.805116)
			(xy 142.372529 -371.769402) (xy 142.33681 -371.728184) (xy 142.307321 -371.682302) (xy 142.284661 -371.632689)
			(xy 142.269294 -371.580357) (xy 142.261532 -371.526371) (xy 131.781628 -371.526371) (xy 131.781628 -371.526373)
			(xy 131.773866 -371.580365) (xy 131.758498 -371.632702) (xy 131.735838 -371.682319) (xy 131.706348 -371.728207)
			(xy 131.670627 -371.76943) (xy 131.629403 -371.80515) (xy 131.583516 -371.83464) (xy 131.533898 -371.857299)
			(xy 131.481561 -371.872666) (xy 131.427569 -371.880429) (xy 131.400296 -371.880892) (xy 130.536696 -371.880892)
			(xy 130.509429 -371.880345) (xy 130.45545 -371.872584) (xy 130.403125 -371.857219) (xy 130.353519 -371.834565)
			(xy 130.307642 -371.805081) (xy 130.266429 -371.769369) (xy 130.230717 -371.728154) (xy 130.201233 -371.682277)
			(xy 130.178579 -371.632671) (xy 130.163215 -371.580346) (xy 130.155454 -371.526367) (xy 124.974428 -371.526367)
			(xy 124.974428 -371.526373) (xy 124.966666 -371.580365) (xy 124.951298 -371.632702) (xy 124.928638 -371.682319)
			(xy 124.899148 -371.728207) (xy 124.863427 -371.76943) (xy 124.822203 -371.80515) (xy 124.776316 -371.83464)
			(xy 124.726698 -371.857299) (xy 124.674361 -371.872666) (xy 124.620369 -371.880429) (xy 124.593096 -371.880892)
			(xy 123.729496 -371.880892) (xy 123.702229 -371.880345) (xy 123.64825 -371.872584) (xy 123.595925 -371.857219)
			(xy 123.546319 -371.834565) (xy 123.500442 -371.805081) (xy 123.459229 -371.769369) (xy 123.423517 -371.728154)
			(xy 123.394033 -371.682277) (xy 123.371379 -371.632671) (xy 123.356015 -371.580346) (xy 123.348254 -371.526367)
			(xy 118.167228 -371.526367) (xy 118.167228 -371.526373) (xy 118.159466 -371.580365) (xy 118.144098 -371.632702)
			(xy 118.121438 -371.682319) (xy 118.091948 -371.728207) (xy 118.056227 -371.76943) (xy 118.015003 -371.80515)
			(xy 117.969116 -371.83464) (xy 117.919498 -371.857299) (xy 117.867161 -371.872666) (xy 117.813169 -371.880429)
			(xy 117.785896 -371.880892) (xy 116.922296 -371.880892) (xy 116.895029 -371.880345) (xy 116.84105 -371.872584)
			(xy 116.788725 -371.857219) (xy 116.739119 -371.834565) (xy 116.693242 -371.805081) (xy 116.652029 -371.769369)
			(xy 116.616317 -371.728154) (xy 116.586833 -371.682277) (xy 116.564179 -371.632671) (xy 116.548815 -371.580346)
			(xy 116.541054 -371.526367) (xy 111.360028 -371.526367) (xy 111.360028 -371.526373) (xy 111.352266 -371.580365)
			(xy 111.336898 -371.632702) (xy 111.314238 -371.682319) (xy 111.284748 -371.728207) (xy 111.249027 -371.76943)
			(xy 111.207803 -371.80515) (xy 111.161916 -371.83464) (xy 111.112298 -371.857299) (xy 111.059961 -371.872666)
			(xy 111.005969 -371.880429) (xy 110.978696 -371.880892) (xy 110.115096 -371.880892) (xy 110.087829 -371.880345)
			(xy 110.03385 -371.872584) (xy 109.981525 -371.857219) (xy 109.931919 -371.834565) (xy 109.886042 -371.805081)
			(xy 109.844829 -371.769369) (xy 109.809117 -371.728154) (xy 109.779633 -371.682277) (xy 109.756979 -371.632671)
			(xy 109.741615 -371.580346) (xy 109.733854 -371.526367) (xy 97.209406 -371.526367) (xy 97.209406 -371.526371)
			(xy 97.201643 -371.580359) (xy 97.186277 -371.632693) (xy 97.163619 -371.682307) (xy 97.134131 -371.728191)
			(xy 97.098413 -371.769412) (xy 97.057193 -371.80513) (xy 97.011308 -371.834618) (xy 96.961694 -371.857276)
			(xy 96.909361 -371.872643) (xy 96.855373 -371.880405) (xy 96.828102 -371.880892) (xy 95.964502 -371.880892)
			(xy 95.937233 -371.880369) (xy 95.88325 -371.872607) (xy 95.830921 -371.857243) (xy 95.781312 -371.834587)
			(xy 95.735432 -371.805102) (xy 95.694214 -371.769387) (xy 95.6585 -371.72817) (xy 95.629014 -371.68229)
			(xy 95.606358 -371.63268) (xy 95.590993 -371.580352) (xy 95.583231 -371.526369) (xy 90.402206 -371.526369)
			(xy 90.402206 -371.526371) (xy 90.394443 -371.580359) (xy 90.379077 -371.632693) (xy 90.356419 -371.682307)
			(xy 90.326931 -371.728191) (xy 90.291213 -371.769412) (xy 90.249993 -371.80513) (xy 90.204108 -371.834618)
			(xy 90.154494 -371.857276) (xy 90.102161 -371.872643) (xy 90.048173 -371.880405) (xy 90.020902 -371.880892)
			(xy 89.157302 -371.880892) (xy 89.130033 -371.880369) (xy 89.07605 -371.872607) (xy 89.023721 -371.857243)
			(xy 88.974112 -371.834587) (xy 88.928232 -371.805102) (xy 88.887014 -371.769387) (xy 88.8513 -371.72817)
			(xy 88.821814 -371.68229) (xy 88.799158 -371.63268) (xy 88.783793 -371.580352) (xy 88.776031 -371.526369)
			(xy 83.595006 -371.526369) (xy 83.595006 -371.526371) (xy 83.587243 -371.580359) (xy 83.571877 -371.632693)
			(xy 83.549219 -371.682307) (xy 83.519731 -371.728191) (xy 83.484013 -371.769412) (xy 83.442793 -371.80513)
			(xy 83.396908 -371.834618) (xy 83.347294 -371.857276) (xy 83.294961 -371.872643) (xy 83.240973 -371.880405)
			(xy 83.213702 -371.880892) (xy 82.350102 -371.880892) (xy 82.322833 -371.880369) (xy 82.26885 -371.872607)
			(xy 82.216521 -371.857243) (xy 82.166912 -371.834587) (xy 82.121032 -371.805102) (xy 82.079814 -371.769387)
			(xy 82.0441 -371.72817) (xy 82.014614 -371.68229) (xy 81.991958 -371.63268) (xy 81.976593 -371.580352)
			(xy 81.968831 -371.526369) (xy 76.787806 -371.526369) (xy 76.787806 -371.526371) (xy 76.780043 -371.580359)
			(xy 76.764677 -371.632693) (xy 76.742019 -371.682307) (xy 76.712531 -371.728191) (xy 76.676813 -371.769412)
			(xy 76.635593 -371.80513) (xy 76.589708 -371.834618) (xy 76.540094 -371.857276) (xy 76.487761 -371.872643)
			(xy 76.433773 -371.880405) (xy 76.406502 -371.880892) (xy 75.542902 -371.880892) (xy 75.515633 -371.880369)
			(xy 75.46165 -371.872607) (xy 75.409321 -371.857243) (xy 75.359712 -371.834587) (xy 75.313832 -371.805102)
			(xy 75.272614 -371.769387) (xy 75.2369 -371.72817) (xy 75.207414 -371.68229) (xy 75.184758 -371.63268)
			(xy 75.169393 -371.580352) (xy 75.161631 -371.526369) (xy 69.843396 -371.526369) (xy 69.843396 -373.990169)
			(xy 80.267031 -373.990169) (xy 80.267031 -373.935631) (xy 80.274793 -373.881648) (xy 80.290158 -373.82932)
			(xy 80.312814 -373.77971) (xy 80.3423 -373.73383) (xy 80.378014 -373.692613) (xy 80.419232 -373.656898)
			(xy 80.465112 -373.627413) (xy 80.514721 -373.604757) (xy 80.56705 -373.589393) (xy 80.621033 -373.581631)
			(xy 80.648302 -373.581168) (xy 81.511902 -373.581168) (xy 81.539173 -373.581595) (xy 81.593161 -373.589357)
			(xy 81.645494 -373.604724) (xy 81.695108 -373.627382) (xy 81.740993 -373.65687) (xy 81.782213 -373.692588)
			(xy 81.817931 -373.733809) (xy 81.847419 -373.779693) (xy 81.870077 -373.829307) (xy 81.885443 -373.881641)
			(xy 81.893206 -373.935629) (xy 81.893206 -373.990169) (xy 87.074231 -373.990169) (xy 87.074231 -373.935631)
			(xy 87.081993 -373.881648) (xy 87.097358 -373.82932) (xy 87.120014 -373.77971) (xy 87.1495 -373.73383)
			(xy 87.185214 -373.692613) (xy 87.226432 -373.656898) (xy 87.272312 -373.627413) (xy 87.321921 -373.604757)
			(xy 87.37425 -373.589393) (xy 87.428233 -373.581631) (xy 87.455502 -373.581168) (xy 88.319102 -373.581168)
			(xy 88.346373 -373.581595) (xy 88.400361 -373.589357) (xy 88.452694 -373.604724) (xy 88.502308 -373.627382)
			(xy 88.548193 -373.65687) (xy 88.589413 -373.692588) (xy 88.625131 -373.733809) (xy 88.654619 -373.779693)
			(xy 88.677277 -373.829307) (xy 88.692643 -373.881641) (xy 88.700406 -373.935629) (xy 88.700406 -373.990169)
			(xy 93.881431 -373.990169) (xy 93.881431 -373.935631) (xy 93.889193 -373.881648) (xy 93.904558 -373.82932)
			(xy 93.927214 -373.77971) (xy 93.9567 -373.73383) (xy 93.992414 -373.692613) (xy 94.033632 -373.656898)
			(xy 94.079512 -373.627413) (xy 94.129121 -373.604757) (xy 94.18145 -373.589393) (xy 94.235433 -373.581631)
			(xy 94.262702 -373.581168) (xy 95.126302 -373.581168) (xy 95.153573 -373.581595) (xy 95.207561 -373.589357)
			(xy 95.259894 -373.604724) (xy 95.309508 -373.627382) (xy 95.355393 -373.65687) (xy 95.396613 -373.692588)
			(xy 95.432331 -373.733809) (xy 95.461819 -373.779693) (xy 95.484477 -373.829307) (xy 95.499843 -373.881641)
			(xy 95.507606 -373.935629) (xy 95.507606 -373.990167) (xy 114.839254 -373.990167) (xy 114.839254 -373.935633)
			(xy 114.847015 -373.881654) (xy 114.862379 -373.829329) (xy 114.885033 -373.779723) (xy 114.914517 -373.733846)
			(xy 114.950229 -373.692631) (xy 114.991442 -373.656919) (xy 115.037319 -373.627435) (xy 115.086925 -373.604781)
			(xy 115.13925 -373.589416) (xy 115.193229 -373.581655) (xy 115.220496 -373.581168) (xy 116.084096 -373.581168)
			(xy 116.111369 -373.581571) (xy 116.165361 -373.589334) (xy 116.217698 -373.604701) (xy 116.267316 -373.62736)
			(xy 116.313203 -373.65685) (xy 116.354427 -373.69257) (xy 116.390148 -373.733793) (xy 116.419638 -373.779681)
			(xy 116.442298 -373.829298) (xy 116.457666 -373.881635) (xy 116.465428 -373.935627) (xy 116.465428 -373.990167)
			(xy 121.646454 -373.990167) (xy 121.646454 -373.935633) (xy 121.654215 -373.881654) (xy 121.669579 -373.829329)
			(xy 121.692233 -373.779723) (xy 121.721717 -373.733846) (xy 121.757429 -373.692631) (xy 121.798642 -373.656919)
			(xy 121.844519 -373.627435) (xy 121.894125 -373.604781) (xy 121.94645 -373.589416) (xy 122.000429 -373.581655)
			(xy 122.027696 -373.581168) (xy 122.891296 -373.581168) (xy 122.918569 -373.581571) (xy 122.972561 -373.589334)
			(xy 123.024898 -373.604701) (xy 123.074516 -373.62736) (xy 123.120403 -373.65685) (xy 123.161627 -373.69257)
			(xy 123.197348 -373.733793) (xy 123.226838 -373.779681) (xy 123.249498 -373.829298) (xy 123.264866 -373.881635)
			(xy 123.272628 -373.935627) (xy 123.272628 -373.990167) (xy 128.453654 -373.990167) (xy 128.453654 -373.935633)
			(xy 128.461415 -373.881654) (xy 128.476779 -373.829329) (xy 128.499433 -373.779723) (xy 128.528917 -373.733846)
			(xy 128.564629 -373.692631) (xy 128.605842 -373.656919) (xy 128.651719 -373.627435) (xy 128.701325 -373.604781)
			(xy 128.75365 -373.589416) (xy 128.807629 -373.581655) (xy 128.834896 -373.581168) (xy 129.698496 -373.581168)
			(xy 129.725769 -373.581571) (xy 129.779761 -373.589334) (xy 129.832098 -373.604701) (xy 129.881716 -373.62736)
			(xy 129.927603 -373.65685) (xy 129.968827 -373.69257) (xy 130.004548 -373.733793) (xy 130.034038 -373.779681)
			(xy 130.056698 -373.829298) (xy 130.072066 -373.881635) (xy 130.079828 -373.935627) (xy 130.079828 -373.990171)
			(xy 147.366932 -373.990171) (xy 147.366932 -373.935629) (xy 147.374694 -373.881643) (xy 147.390061 -373.829311)
			(xy 147.412721 -373.779698) (xy 147.44221 -373.733816) (xy 147.477929 -373.692598) (xy 147.519151 -373.656884)
			(xy 147.565037 -373.627399) (xy 147.614652 -373.604746) (xy 147.666986 -373.589385) (xy 147.720973 -373.581628)
			(xy 147.748244 -373.581168) (xy 148.611844 -373.581168) (xy 148.639113 -373.581598) (xy 148.693097 -373.589365)
			(xy 148.745425 -373.604735) (xy 148.795033 -373.627396) (xy 148.840912 -373.656885) (xy 148.882128 -373.692603)
			(xy 148.917841 -373.733823) (xy 148.947325 -373.779705) (xy 148.96998 -373.829316) (xy 148.985344 -373.881647)
			(xy 148.993106 -373.93563) (xy 148.993106 -373.99017) (xy 148.993106 -373.990171) (xy 154.174132 -373.990171)
			(xy 154.174132 -373.935629) (xy 154.181894 -373.881643) (xy 154.197261 -373.829311) (xy 154.219921 -373.779698)
			(xy 154.24941 -373.733816) (xy 154.285129 -373.692598) (xy 154.326351 -373.656884) (xy 154.372237 -373.627399)
			(xy 154.421852 -373.604746) (xy 154.474186 -373.589385) (xy 154.528173 -373.581628) (xy 154.555444 -373.581168)
			(xy 155.419044 -373.581168) (xy 155.446313 -373.581598) (xy 155.500297 -373.589365) (xy 155.552625 -373.604735)
			(xy 155.602233 -373.627396) (xy 155.648112 -373.656885) (xy 155.689328 -373.692603) (xy 155.725041 -373.733823)
			(xy 155.754525 -373.779705) (xy 155.77718 -373.829316) (xy 155.792544 -373.881647) (xy 155.800306 -373.93563)
			(xy 155.800306 -373.99017) (xy 155.800306 -373.990171) (xy 160.981332 -373.990171) (xy 160.981332 -373.935629)
			(xy 160.989094 -373.881643) (xy 161.004461 -373.829311) (xy 161.027121 -373.779698) (xy 161.05661 -373.733816)
			(xy 161.092329 -373.692598) (xy 161.133551 -373.656884) (xy 161.179437 -373.627399) (xy 161.229052 -373.604746)
			(xy 161.281386 -373.589385) (xy 161.335373 -373.581628) (xy 161.362644 -373.581168) (xy 162.226244 -373.581168)
			(xy 162.253513 -373.581598) (xy 162.307497 -373.589365) (xy 162.359825 -373.604735) (xy 162.409433 -373.627396)
			(xy 162.455312 -373.656885) (xy 162.496528 -373.692603) (xy 162.532241 -373.733823) (xy 162.561725 -373.779705)
			(xy 162.58438 -373.829316) (xy 162.599744 -373.881647) (xy 162.607506 -373.93563) (xy 162.607506 -373.99017)
			(xy 162.599744 -374.044153) (xy 162.58438 -374.096484) (xy 162.561725 -374.146095) (xy 162.532241 -374.191977)
			(xy 162.496528 -374.233197) (xy 162.455312 -374.268915) (xy 162.409433 -374.298404) (xy 162.359825 -374.321065)
			(xy 162.307497 -374.336435) (xy 162.253513 -374.344202) (xy 162.226244 -374.344692) (xy 161.362644 -374.344692)
			(xy 161.335373 -374.344172) (xy 161.281386 -374.336415) (xy 161.229052 -374.321054) (xy 161.179437 -374.298401)
			(xy 161.133551 -374.268916) (xy 161.092329 -374.233202) (xy 161.05661 -374.191984) (xy 161.027121 -374.146102)
			(xy 161.004461 -374.096489) (xy 160.989094 -374.044157) (xy 160.981332 -373.990171) (xy 155.800306 -373.990171)
			(xy 155.792544 -374.044153) (xy 155.77718 -374.096484) (xy 155.754525 -374.146095) (xy 155.725041 -374.191977)
			(xy 155.689328 -374.233197) (xy 155.648112 -374.268915) (xy 155.602233 -374.298404) (xy 155.552625 -374.321065)
			(xy 155.500297 -374.336435) (xy 155.446313 -374.344202) (xy 155.419044 -374.344692) (xy 154.555444 -374.344692)
			(xy 154.528173 -374.344172) (xy 154.474186 -374.336415) (xy 154.421852 -374.321054) (xy 154.372237 -374.298401)
			(xy 154.326351 -374.268916) (xy 154.285129 -374.233202) (xy 154.24941 -374.191984) (xy 154.219921 -374.146102)
			(xy 154.197261 -374.096489) (xy 154.181894 -374.044157) (xy 154.174132 -373.990171) (xy 148.993106 -373.990171)
			(xy 148.985344 -374.044153) (xy 148.96998 -374.096484) (xy 148.947325 -374.146095) (xy 148.917841 -374.191977)
			(xy 148.882128 -374.233197) (xy 148.840912 -374.268915) (xy 148.795033 -374.298404) (xy 148.745425 -374.321065)
			(xy 148.693097 -374.336435) (xy 148.639113 -374.344202) (xy 148.611844 -374.344692) (xy 147.748244 -374.344692)
			(xy 147.720973 -374.344172) (xy 147.666986 -374.336415) (xy 147.614652 -374.321054) (xy 147.565037 -374.298401)
			(xy 147.519151 -374.268916) (xy 147.477929 -374.233202) (xy 147.44221 -374.191984) (xy 147.412721 -374.146102)
			(xy 147.390061 -374.096489) (xy 147.374694 -374.044157) (xy 147.366932 -373.990171) (xy 130.079828 -373.990171)
			(xy 130.079828 -373.990173) (xy 130.072066 -374.044165) (xy 130.056698 -374.096502) (xy 130.034038 -374.146119)
			(xy 130.004548 -374.192007) (xy 129.968827 -374.23323) (xy 129.927603 -374.26895) (xy 129.881716 -374.29844)
			(xy 129.832098 -374.321099) (xy 129.779761 -374.336466) (xy 129.725769 -374.344229) (xy 129.698496 -374.344692)
			(xy 128.834896 -374.344692) (xy 128.807629 -374.344145) (xy 128.75365 -374.336384) (xy 128.701325 -374.321019)
			(xy 128.651719 -374.298365) (xy 128.605842 -374.268881) (xy 128.564629 -374.233169) (xy 128.528917 -374.191954)
			(xy 128.499433 -374.146077) (xy 128.476779 -374.096471) (xy 128.461415 -374.044146) (xy 128.453654 -373.990167)
			(xy 123.272628 -373.990167) (xy 123.272628 -373.990173) (xy 123.264866 -374.044165) (xy 123.249498 -374.096502)
			(xy 123.226838 -374.146119) (xy 123.197348 -374.192007) (xy 123.161627 -374.23323) (xy 123.120403 -374.26895)
			(xy 123.074516 -374.29844) (xy 123.024898 -374.321099) (xy 122.972561 -374.336466) (xy 122.918569 -374.344229)
			(xy 122.891296 -374.344692) (xy 122.027696 -374.344692) (xy 122.000429 -374.344145) (xy 121.94645 -374.336384)
			(xy 121.894125 -374.321019) (xy 121.844519 -374.298365) (xy 121.798642 -374.268881) (xy 121.757429 -374.233169)
			(xy 121.721717 -374.191954) (xy 121.692233 -374.146077) (xy 121.669579 -374.096471) (xy 121.654215 -374.044146)
			(xy 121.646454 -373.990167) (xy 116.465428 -373.990167) (xy 116.465428 -373.990173) (xy 116.457666 -374.044165)
			(xy 116.442298 -374.096502) (xy 116.419638 -374.146119) (xy 116.390148 -374.192007) (xy 116.354427 -374.23323)
			(xy 116.313203 -374.26895) (xy 116.267316 -374.29844) (xy 116.217698 -374.321099) (xy 116.165361 -374.336466)
			(xy 116.111369 -374.344229) (xy 116.084096 -374.344692) (xy 115.220496 -374.344692) (xy 115.193229 -374.344145)
			(xy 115.13925 -374.336384) (xy 115.086925 -374.321019) (xy 115.037319 -374.298365) (xy 114.991442 -374.268881)
			(xy 114.950229 -374.233169) (xy 114.914517 -374.191954) (xy 114.885033 -374.146077) (xy 114.862379 -374.096471)
			(xy 114.847015 -374.044146) (xy 114.839254 -373.990167) (xy 95.507606 -373.990167) (xy 95.507606 -373.990171)
			(xy 95.499843 -374.044159) (xy 95.484477 -374.096493) (xy 95.461819 -374.146107) (xy 95.432331 -374.191991)
			(xy 95.396613 -374.233212) (xy 95.355393 -374.26893) (xy 95.309508 -374.298418) (xy 95.259894 -374.321076)
			(xy 95.207561 -374.336443) (xy 95.153573 -374.344205) (xy 95.126302 -374.344692) (xy 94.262702 -374.344692)
			(xy 94.235433 -374.344169) (xy 94.18145 -374.336407) (xy 94.129121 -374.321043) (xy 94.079512 -374.298387)
			(xy 94.033632 -374.268902) (xy 93.992414 -374.233187) (xy 93.9567 -374.19197) (xy 93.927214 -374.14609)
			(xy 93.904558 -374.09648) (xy 93.889193 -374.044152) (xy 93.881431 -373.990169) (xy 88.700406 -373.990169)
			(xy 88.700406 -373.990171) (xy 88.692643 -374.044159) (xy 88.677277 -374.096493) (xy 88.654619 -374.146107)
			(xy 88.625131 -374.191991) (xy 88.589413 -374.233212) (xy 88.548193 -374.26893) (xy 88.502308 -374.298418)
			(xy 88.452694 -374.321076) (xy 88.400361 -374.336443) (xy 88.346373 -374.344205) (xy 88.319102 -374.344692)
			(xy 87.455502 -374.344692) (xy 87.428233 -374.344169) (xy 87.37425 -374.336407) (xy 87.321921 -374.321043)
			(xy 87.272312 -374.298387) (xy 87.226432 -374.268902) (xy 87.185214 -374.233187) (xy 87.1495 -374.19197)
			(xy 87.120014 -374.14609) (xy 87.097358 -374.09648) (xy 87.081993 -374.044152) (xy 87.074231 -373.990169)
			(xy 81.893206 -373.990169) (xy 81.893206 -373.990171) (xy 81.885443 -374.044159) (xy 81.870077 -374.096493)
			(xy 81.847419 -374.146107) (xy 81.817931 -374.191991) (xy 81.782213 -374.233212) (xy 81.740993 -374.26893)
			(xy 81.695108 -374.298418) (xy 81.645494 -374.321076) (xy 81.593161 -374.336443) (xy 81.539173 -374.344205)
			(xy 81.511902 -374.344692) (xy 80.648302 -374.344692) (xy 80.621033 -374.344169) (xy 80.56705 -374.336407)
			(xy 80.514721 -374.321043) (xy 80.465112 -374.298387) (xy 80.419232 -374.268902) (xy 80.378014 -374.233187)
			(xy 80.3423 -374.19197) (xy 80.312814 -374.14609) (xy 80.290158 -374.09648) (xy 80.274793 -374.044152)
			(xy 80.267031 -373.990169) (xy 69.843396 -373.990169) (xy 69.843396 -376.956828) (xy 70.895972 -376.956828)
			(xy 70.895972 -376.093228) (xy 70.896458 -376.065959) (xy 70.90422 -376.011975) (xy 70.919585 -375.959645)
			(xy 70.942242 -375.910035) (xy 70.971728 -375.864154) (xy 71.007443 -375.822937) (xy 71.04866 -375.787222)
			(xy 71.094541 -375.757736) (xy 71.144151 -375.735079) (xy 71.196481 -375.719714) (xy 71.250465 -375.711952)
			(xy 71.305003 -375.711952) (xy 71.358987 -375.719714) (xy 71.411317 -375.735079) (xy 71.460927 -375.757736)
			(xy 71.506808 -375.787222) (xy 71.548025 -375.822937) (xy 71.58374 -375.864154) (xy 71.613226 -375.910035)
			(xy 71.635883 -375.959645) (xy 71.651248 -376.011975) (xy 71.65901 -376.065959) (xy 71.659496 -376.093228)
			(xy 71.659496 -376.83186) (xy 73.576688 -376.83186) (xy 73.576688 -375.96826) (xy 73.577174 -375.940991)
			(xy 73.584936 -375.887007) (xy 73.600301 -375.834677) (xy 73.622958 -375.785067) (xy 73.652444 -375.739186)
			(xy 73.688159 -375.697969) (xy 73.729376 -375.662254) (xy 73.775257 -375.632768) (xy 73.824867 -375.610111)
			(xy 73.877197 -375.594746) (xy 73.931181 -375.586984) (xy 73.985719 -375.586984) (xy 74.039703 -375.594746)
			(xy 74.092033 -375.610111) (xy 74.141643 -375.632768) (xy 74.187524 -375.662254) (xy 74.228741 -375.697969)
			(xy 74.264456 -375.739186) (xy 74.293942 -375.785067) (xy 74.316599 -375.834677) (xy 74.331964 -375.887007)
			(xy 74.339726 -375.940991) (xy 74.340212 -375.96826) (xy 74.340212 -376.83186) (xy 74.339726 -376.859129)
			(xy 74.331964 -376.913113) (xy 74.319129 -376.956828) (xy 103.42372 -376.956828) (xy 103.42372 -376.093228)
			(xy 103.424206 -376.065959) (xy 103.431968 -376.011975) (xy 103.447333 -375.959645) (xy 103.46999 -375.910035)
			(xy 103.499476 -375.864154) (xy 103.535191 -375.822937) (xy 103.576408 -375.787222) (xy 103.622289 -375.757736)
			(xy 103.671899 -375.735079) (xy 103.724229 -375.719714) (xy 103.778213 -375.711952) (xy 103.832751 -375.711952)
			(xy 103.886735 -375.719714) (xy 103.939065 -375.735079) (xy 103.988675 -375.757736) (xy 104.034556 -375.787222)
			(xy 104.075773 -375.822937) (xy 104.111488 -375.864154) (xy 104.140974 -375.910035) (xy 104.163631 -375.959645)
			(xy 104.178996 -376.011975) (xy 104.186758 -376.065959) (xy 104.187244 -376.093228) (xy 104.187244 -376.83186)
			(xy 108.149136 -376.83186) (xy 108.149136 -375.96826) (xy 108.149622 -375.941009) (xy 108.157378 -375.887061)
			(xy 108.172733 -375.834766) (xy 108.195375 -375.785189) (xy 108.224841 -375.739339) (xy 108.260532 -375.698148)
			(xy 108.301723 -375.662457) (xy 108.347573 -375.632991) (xy 108.39715 -375.610349) (xy 108.449445 -375.594994)
			(xy 108.503393 -375.587238) (xy 108.557895 -375.587238) (xy 108.611843 -375.594994) (xy 108.664138 -375.610349)
			(xy 108.713715 -375.632991) (xy 108.759565 -375.662457) (xy 108.800756 -375.698148) (xy 108.836447 -375.739339)
			(xy 108.865913 -375.785189) (xy 108.888555 -375.834766) (xy 108.90391 -375.887061) (xy 108.911666 -375.941009)
			(xy 108.912152 -375.96826) (xy 108.912152 -376.83186) (xy 108.911666 -376.859111) (xy 108.90391 -376.913059)
			(xy 108.891058 -376.956828) (xy 137.996168 -376.956828) (xy 137.996168 -376.093228) (xy 137.996654 -376.065977)
			(xy 138.00441 -376.012029) (xy 138.019765 -375.959734) (xy 138.042407 -375.910157) (xy 138.071873 -375.864307)
			(xy 138.107564 -375.823116) (xy 138.148755 -375.787425) (xy 138.194605 -375.757959) (xy 138.244182 -375.735317)
			(xy 138.296477 -375.719962) (xy 138.350425 -375.712206) (xy 138.404927 -375.712206) (xy 138.458875 -375.719962)
			(xy 138.51117 -375.735317) (xy 138.560747 -375.757959) (xy 138.606597 -375.787425) (xy 138.647788 -375.823116)
			(xy 138.683479 -375.864307) (xy 138.712945 -375.910157) (xy 138.735587 -375.959734) (xy 138.750942 -376.012029)
			(xy 138.758698 -376.065977) (xy 138.759184 -376.093228) (xy 138.759184 -376.83186) (xy 140.676884 -376.83186)
			(xy 140.676884 -375.96826) (xy 140.67737 -375.941009) (xy 140.685126 -375.887061) (xy 140.700481 -375.834766)
			(xy 140.723123 -375.785189) (xy 140.752589 -375.739339) (xy 140.78828 -375.698148) (xy 140.829471 -375.662457)
			(xy 140.875321 -375.632991) (xy 140.924898 -375.610349) (xy 140.977193 -375.594994) (xy 141.031141 -375.587238)
			(xy 141.085643 -375.587238) (xy 141.139591 -375.594994) (xy 141.191886 -375.610349) (xy 141.241463 -375.632991)
			(xy 141.287313 -375.662457) (xy 141.328504 -375.698148) (xy 141.364195 -375.739339) (xy 141.393661 -375.785189)
			(xy 141.416303 -375.834766) (xy 141.431658 -375.887061) (xy 141.439414 -375.941009) (xy 141.4399 -375.96826)
			(xy 141.4399 -376.83186) (xy 141.439414 -376.859111) (xy 141.431658 -376.913059) (xy 141.418806 -376.956828)
			(xy 170.523916 -376.956828) (xy 170.523916 -376.093228) (xy 170.524402 -376.065977) (xy 170.532158 -376.012029)
			(xy 170.547513 -375.959734) (xy 170.570155 -375.910157) (xy 170.599621 -375.864307) (xy 170.635312 -375.823116)
			(xy 170.676503 -375.787425) (xy 170.722353 -375.757959) (xy 170.77193 -375.735317) (xy 170.824225 -375.719962)
			(xy 170.878173 -375.712206) (xy 170.932675 -375.712206) (xy 170.986623 -375.719962) (xy 171.038918 -375.735317)
			(xy 171.088495 -375.757959) (xy 171.134345 -375.787425) (xy 171.175536 -375.823116) (xy 171.211227 -375.864307)
			(xy 171.240693 -375.910157) (xy 171.263335 -375.959734) (xy 171.27869 -376.012029) (xy 171.286446 -376.065977)
			(xy 171.286932 -376.093228) (xy 171.286932 -376.589497) (xy 173.177954 -376.589497) (xy 173.177954 -376.403663)
			(xy 173.185949 -376.218) (xy 173.201924 -376.032854) (xy 173.22585 -375.848566) (xy 173.257682 -375.665478)
			(xy 173.297362 -375.483929) (xy 173.344815 -375.304255) (xy 173.399955 -375.126789) (xy 173.462678 -374.95186)
			(xy 173.532869 -374.779791) (xy 173.610398 -374.610902) (xy 173.695121 -374.445504) (xy 173.786882 -374.283904)
			(xy 173.88551 -374.126402) (xy 173.990823 -373.973288) (xy 174.102625 -373.824848) (xy 174.22071 -373.681354)
			(xy 174.34486 -373.543074) (xy 174.474843 -373.410263) (xy 174.61042 -373.283167) (xy 174.75134 -373.162022)
			(xy 174.89734 -373.047051) (xy 175.048152 -372.938468) (xy 175.203496 -372.836475) (xy 175.363084 -372.741258)
			(xy 175.526621 -372.652996) (xy 175.693803 -372.571851) (xy 175.864322 -372.497974) (xy 176.037861 -372.431501)
			(xy 176.2141 -372.372556) (xy 176.392711 -372.321248) (xy 176.573364 -372.277671) (xy 176.755725 -372.241907)
			(xy 176.939455 -372.214021) (xy 177.124215 -372.194066) (xy 177.309662 -372.182078) (xy 177.495454 -372.17808)
			(xy 177.681246 -372.182078) (xy 177.866693 -372.194066) (xy 178.051453 -372.214021) (xy 178.235183 -372.241907)
			(xy 178.417544 -372.277671) (xy 178.598197 -372.321248) (xy 178.776808 -372.372556) (xy 178.953047 -372.431501)
			(xy 179.126586 -372.497974) (xy 179.297105 -372.571851) (xy 179.464287 -372.652996) (xy 179.627824 -372.741258)
			(xy 179.787412 -372.836475) (xy 179.942756 -372.938468) (xy 180.093568 -373.047051) (xy 180.239568 -373.162022)
			(xy 180.380488 -373.283167) (xy 180.516065 -373.410263) (xy 180.646048 -373.543074) (xy 180.770198 -373.681354)
			(xy 180.888283 -373.824848) (xy 181.000085 -373.973288) (xy 181.105398 -374.126402) (xy 181.204026 -374.283904)
			(xy 181.295787 -374.445504) (xy 181.38051 -374.610902) (xy 181.458039 -374.779791) (xy 181.52823 -374.95186)
			(xy 181.590953 -375.126789) (xy 181.646093 -375.304255) (xy 181.693546 -375.483929) (xy 181.733226 -375.665478)
			(xy 181.765058 -375.848566) (xy 181.788984 -376.032854) (xy 181.804959 -376.218) (xy 181.812954 -376.403663)
			(xy 181.813454 -376.49658) (xy 181.812954 -376.589497) (xy 181.804959 -376.77516) (xy 181.788984 -376.960306)
			(xy 181.765058 -377.144594) (xy 181.733226 -377.327682) (xy 181.693546 -377.509231) (xy 181.646093 -377.688905)
			(xy 181.590953 -377.866371) (xy 181.52823 -378.0413) (xy 181.458039 -378.213369) (xy 181.38051 -378.382258)
			(xy 181.295787 -378.547656) (xy 181.204026 -378.709256) (xy 181.105398 -378.866758) (xy 181.000085 -379.019872)
			(xy 180.888283 -379.168312) (xy 180.770198 -379.311806) (xy 180.646048 -379.450086) (xy 180.516065 -379.582897)
			(xy 180.380488 -379.709993) (xy 180.239568 -379.831138) (xy 180.093568 -379.946109) (xy 179.942756 -380.054692)
			(xy 179.787412 -380.156685) (xy 179.627824 -380.251902) (xy 179.464287 -380.340164) (xy 179.297105 -380.421309)
			(xy 179.126586 -380.495186) (xy 178.953047 -380.561659) (xy 178.776808 -380.620604) (xy 178.598197 -380.671912)
			(xy 178.417544 -380.715489) (xy 178.235183 -380.751253) (xy 178.051453 -380.779139) (xy 177.866693 -380.799094)
			(xy 177.681246 -380.811082) (xy 177.495454 -380.81508) (xy 177.309662 -380.811082) (xy 177.124215 -380.799094)
			(xy 176.939455 -380.779139) (xy 176.755725 -380.751253) (xy 176.573364 -380.715489) (xy 176.392711 -380.671912)
			(xy 176.2141 -380.620604) (xy 176.037861 -380.561659) (xy 175.864322 -380.495186) (xy 175.693803 -380.421309)
			(xy 175.526621 -380.340164) (xy 175.363084 -380.251902) (xy 175.203496 -380.156685) (xy 175.048152 -380.054692)
			(xy 174.89734 -379.946109) (xy 174.75134 -379.831138) (xy 174.61042 -379.709993) (xy 174.474843 -379.582897)
			(xy 174.34486 -379.450086) (xy 174.22071 -379.311806) (xy 174.102625 -379.168312) (xy 173.990823 -379.019872)
			(xy 173.88551 -378.866758) (xy 173.786882 -378.709256) (xy 173.695121 -378.547656) (xy 173.610398 -378.382258)
			(xy 173.532869 -378.213369) (xy 173.462678 -378.0413) (xy 173.399955 -377.866371) (xy 173.344815 -377.688905)
			(xy 173.297362 -377.509231) (xy 173.257682 -377.327682) (xy 173.22585 -377.144594) (xy 173.201924 -376.960306)
			(xy 173.185949 -376.77516) (xy 173.177954 -376.589497) (xy 171.286932 -376.589497) (xy 171.286932 -376.956828)
			(xy 171.286446 -376.984079) (xy 171.27869 -377.038027) (xy 171.263335 -377.090322) (xy 171.240693 -377.139899)
			(xy 171.211227 -377.185749) (xy 171.175536 -377.22694) (xy 171.134345 -377.262631) (xy 171.088495 -377.292097)
			(xy 171.038918 -377.314739) (xy 170.986623 -377.330094) (xy 170.932675 -377.33785) (xy 170.878173 -377.33785)
			(xy 170.824225 -377.330094) (xy 170.77193 -377.314739) (xy 170.722353 -377.292097) (xy 170.676503 -377.262631)
			(xy 170.635312 -377.22694) (xy 170.599621 -377.185749) (xy 170.570155 -377.139899) (xy 170.547513 -377.090322)
			(xy 170.532158 -377.038027) (xy 170.524402 -376.984079) (xy 170.523916 -376.956828) (xy 141.418806 -376.956828)
			(xy 141.416303 -376.965354) (xy 141.393661 -377.014931) (xy 141.364195 -377.060781) (xy 141.328504 -377.101972)
			(xy 141.287313 -377.137663) (xy 141.241463 -377.167129) (xy 141.191886 -377.189771) (xy 141.139591 -377.205126)
			(xy 141.085643 -377.212882) (xy 141.031141 -377.212882) (xy 140.977193 -377.205126) (xy 140.924898 -377.189771)
			(xy 140.875321 -377.167129) (xy 140.829471 -377.137663) (xy 140.78828 -377.101972) (xy 140.752589 -377.060781)
			(xy 140.723123 -377.014931) (xy 140.700481 -376.965354) (xy 140.685126 -376.913059) (xy 140.67737 -376.859111)
			(xy 140.676884 -376.83186) (xy 138.759184 -376.83186) (xy 138.759184 -376.956828) (xy 138.758698 -376.984079)
			(xy 138.750942 -377.038027) (xy 138.735587 -377.090322) (xy 138.712945 -377.139899) (xy 138.683479 -377.185749)
			(xy 138.647788 -377.22694) (xy 138.606597 -377.262631) (xy 138.560747 -377.292097) (xy 138.51117 -377.314739)
			(xy 138.458875 -377.330094) (xy 138.404927 -377.33785) (xy 138.350425 -377.33785) (xy 138.296477 -377.330094)
			(xy 138.244182 -377.314739) (xy 138.194605 -377.292097) (xy 138.148755 -377.262631) (xy 138.107564 -377.22694)
			(xy 138.071873 -377.185749) (xy 138.042407 -377.139899) (xy 138.019765 -377.090322) (xy 138.00441 -377.038027)
			(xy 137.996654 -376.984079) (xy 137.996168 -376.956828) (xy 108.891058 -376.956828) (xy 108.888555 -376.965354)
			(xy 108.865913 -377.014931) (xy 108.836447 -377.060781) (xy 108.800756 -377.101972) (xy 108.759565 -377.137663)
			(xy 108.713715 -377.167129) (xy 108.664138 -377.189771) (xy 108.611843 -377.205126) (xy 108.557895 -377.212882)
			(xy 108.503393 -377.212882) (xy 108.449445 -377.205126) (xy 108.39715 -377.189771) (xy 108.347573 -377.167129)
			(xy 108.301723 -377.137663) (xy 108.260532 -377.101972) (xy 108.224841 -377.060781) (xy 108.195375 -377.014931)
			(xy 108.172733 -376.965354) (xy 108.157378 -376.913059) (xy 108.149622 -376.859111) (xy 108.149136 -376.83186)
			(xy 104.187244 -376.83186) (xy 104.187244 -376.956828) (xy 104.186758 -376.984097) (xy 104.178996 -377.038081)
			(xy 104.163631 -377.090411) (xy 104.140974 -377.140021) (xy 104.111488 -377.185902) (xy 104.075773 -377.227119)
			(xy 104.034556 -377.262834) (xy 103.988675 -377.29232) (xy 103.939065 -377.314977) (xy 103.886735 -377.330342)
			(xy 103.832751 -377.338104) (xy 103.778213 -377.338104) (xy 103.724229 -377.330342) (xy 103.671899 -377.314977)
			(xy 103.622289 -377.29232) (xy 103.576408 -377.262834) (xy 103.535191 -377.227119) (xy 103.499476 -377.185902)
			(xy 103.46999 -377.140021) (xy 103.447333 -377.090411) (xy 103.431968 -377.038081) (xy 103.424206 -376.984097)
			(xy 103.42372 -376.956828) (xy 74.319129 -376.956828) (xy 74.316599 -376.965443) (xy 74.293942 -377.015053)
			(xy 74.264456 -377.060934) (xy 74.228741 -377.102151) (xy 74.187524 -377.137866) (xy 74.141643 -377.167352)
			(xy 74.092033 -377.190009) (xy 74.039703 -377.205374) (xy 73.985719 -377.213136) (xy 73.931181 -377.213136)
			(xy 73.877197 -377.205374) (xy 73.824867 -377.190009) (xy 73.775257 -377.167352) (xy 73.729376 -377.137866)
			(xy 73.688159 -377.102151) (xy 73.652444 -377.060934) (xy 73.622958 -377.015053) (xy 73.600301 -376.965443)
			(xy 73.584936 -376.913113) (xy 73.577174 -376.859129) (xy 73.576688 -376.83186) (xy 71.659496 -376.83186)
			(xy 71.659496 -376.956828) (xy 71.65901 -376.984097) (xy 71.651248 -377.038081) (xy 71.635883 -377.090411)
			(xy 71.613226 -377.140021) (xy 71.58374 -377.185902) (xy 71.548025 -377.227119) (xy 71.506808 -377.262834)
			(xy 71.460927 -377.29232) (xy 71.411317 -377.314977) (xy 71.358987 -377.330342) (xy 71.305003 -377.338104)
			(xy 71.250465 -377.338104) (xy 71.196481 -377.330342) (xy 71.144151 -377.314977) (xy 71.094541 -377.29232)
			(xy 71.04866 -377.262834) (xy 71.007443 -377.227119) (xy 70.971728 -377.185902) (xy 70.942242 -377.140021)
			(xy 70.919585 -377.090411) (xy 70.90422 -377.038081) (xy 70.896458 -376.984097) (xy 70.895972 -376.956828)
			(xy 69.843396 -376.956828) (xy 69.843396 -380.360428) (xy 70.895972 -380.360428) (xy 70.895972 -379.496828)
			(xy 70.896458 -379.469559) (xy 70.90422 -379.415575) (xy 70.919585 -379.363245) (xy 70.942242 -379.313635)
			(xy 70.971728 -379.267754) (xy 71.007443 -379.226537) (xy 71.04866 -379.190822) (xy 71.094541 -379.161336)
			(xy 71.144151 -379.138679) (xy 71.196481 -379.123314) (xy 71.250465 -379.115552) (xy 71.305003 -379.115552)
			(xy 71.358987 -379.123314) (xy 71.411317 -379.138679) (xy 71.460927 -379.161336) (xy 71.506808 -379.190822)
			(xy 71.548025 -379.226537) (xy 71.58374 -379.267754) (xy 71.613226 -379.313635) (xy 71.635883 -379.363245)
			(xy 71.651248 -379.415575) (xy 71.65901 -379.469559) (xy 71.659496 -379.496828) (xy 71.659496 -380.360428)
			(xy 103.42372 -380.360428) (xy 103.42372 -379.496828) (xy 103.424206 -379.469559) (xy 103.431968 -379.415575)
			(xy 103.447333 -379.363245) (xy 103.46999 -379.313635) (xy 103.499476 -379.267754) (xy 103.535191 -379.226537)
			(xy 103.576408 -379.190822) (xy 103.622289 -379.161336) (xy 103.671899 -379.138679) (xy 103.724229 -379.123314)
			(xy 103.778213 -379.115552) (xy 103.832751 -379.115552) (xy 103.886735 -379.123314) (xy 103.939065 -379.138679)
			(xy 103.988675 -379.161336) (xy 104.034556 -379.190822) (xy 104.075773 -379.226537) (xy 104.111488 -379.267754)
			(xy 104.140974 -379.313635) (xy 104.163631 -379.363245) (xy 104.178996 -379.415575) (xy 104.186758 -379.469559)
			(xy 104.187244 -379.496828) (xy 104.187244 -380.360428) (xy 137.996168 -380.360428) (xy 137.996168 -379.496828)
			(xy 137.996654 -379.469577) (xy 138.00441 -379.415629) (xy 138.019765 -379.363334) (xy 138.042407 -379.313757)
			(xy 138.071873 -379.267907) (xy 138.107564 -379.226716) (xy 138.148755 -379.191025) (xy 138.194605 -379.161559)
			(xy 138.244182 -379.138917) (xy 138.296477 -379.123562) (xy 138.350425 -379.115806) (xy 138.404927 -379.115806)
			(xy 138.458875 -379.123562) (xy 138.51117 -379.138917) (xy 138.560747 -379.161559) (xy 138.606597 -379.191025)
			(xy 138.647788 -379.226716) (xy 138.683479 -379.267907) (xy 138.712945 -379.313757) (xy 138.735587 -379.363334)
			(xy 138.750942 -379.415629) (xy 138.758698 -379.469577) (xy 138.759184 -379.496828) (xy 138.759184 -380.360428)
			(xy 170.523916 -380.360428) (xy 170.523916 -379.496828) (xy 170.524402 -379.469577) (xy 170.532158 -379.415629)
			(xy 170.547513 -379.363334) (xy 170.570155 -379.313757) (xy 170.599621 -379.267907) (xy 170.635312 -379.226716)
			(xy 170.676503 -379.191025) (xy 170.722353 -379.161559) (xy 170.77193 -379.138917) (xy 170.824225 -379.123562)
			(xy 170.878173 -379.115806) (xy 170.932675 -379.115806) (xy 170.986623 -379.123562) (xy 171.038918 -379.138917)
			(xy 171.088495 -379.161559) (xy 171.134345 -379.191025) (xy 171.175536 -379.226716) (xy 171.211227 -379.267907)
			(xy 171.240693 -379.313757) (xy 171.263335 -379.363334) (xy 171.27869 -379.415629) (xy 171.286446 -379.469577)
			(xy 171.286932 -379.496828) (xy 171.286932 -380.360428) (xy 171.286446 -380.387679) (xy 171.27869 -380.441627)
			(xy 171.263335 -380.493922) (xy 171.240693 -380.543499) (xy 171.211227 -380.589349) (xy 171.175536 -380.63054)
			(xy 171.134345 -380.666231) (xy 171.088495 -380.695697) (xy 171.038918 -380.718339) (xy 170.986623 -380.733694)
			(xy 170.932675 -380.74145) (xy 170.878173 -380.74145) (xy 170.824225 -380.733694) (xy 170.77193 -380.718339)
			(xy 170.722353 -380.695697) (xy 170.676503 -380.666231) (xy 170.635312 -380.63054) (xy 170.599621 -380.589349)
			(xy 170.570155 -380.543499) (xy 170.547513 -380.493922) (xy 170.532158 -380.441627) (xy 170.524402 -380.387679)
			(xy 170.523916 -380.360428) (xy 138.759184 -380.360428) (xy 138.758698 -380.387679) (xy 138.750942 -380.441627)
			(xy 138.735587 -380.493922) (xy 138.712945 -380.543499) (xy 138.683479 -380.589349) (xy 138.647788 -380.63054)
			(xy 138.606597 -380.666231) (xy 138.560747 -380.695697) (xy 138.51117 -380.718339) (xy 138.458875 -380.733694)
			(xy 138.404927 -380.74145) (xy 138.350425 -380.74145) (xy 138.296477 -380.733694) (xy 138.244182 -380.718339)
			(xy 138.194605 -380.695697) (xy 138.148755 -380.666231) (xy 138.107564 -380.63054) (xy 138.071873 -380.589349)
			(xy 138.042407 -380.543499) (xy 138.019765 -380.493922) (xy 138.00441 -380.441627) (xy 137.996654 -380.387679)
			(xy 137.996168 -380.360428) (xy 104.187244 -380.360428) (xy 104.186758 -380.387697) (xy 104.178996 -380.441681)
			(xy 104.163631 -380.494011) (xy 104.140974 -380.543621) (xy 104.111488 -380.589502) (xy 104.075773 -380.630719)
			(xy 104.034556 -380.666434) (xy 103.988675 -380.69592) (xy 103.939065 -380.718577) (xy 103.886735 -380.733942)
			(xy 103.832751 -380.741704) (xy 103.778213 -380.741704) (xy 103.724229 -380.733942) (xy 103.671899 -380.718577)
			(xy 103.622289 -380.69592) (xy 103.576408 -380.666434) (xy 103.535191 -380.630719) (xy 103.499476 -380.589502)
			(xy 103.46999 -380.543621) (xy 103.447333 -380.494011) (xy 103.431968 -380.441681) (xy 103.424206 -380.387697)
			(xy 103.42372 -380.360428) (xy 71.659496 -380.360428) (xy 71.65901 -380.387697) (xy 71.651248 -380.441681)
			(xy 71.635883 -380.494011) (xy 71.613226 -380.543621) (xy 71.58374 -380.589502) (xy 71.548025 -380.630719)
			(xy 71.506808 -380.666434) (xy 71.460927 -380.69592) (xy 71.411317 -380.718577) (xy 71.358987 -380.733942)
			(xy 71.305003 -380.741704) (xy 71.250465 -380.741704) (xy 71.196481 -380.733942) (xy 71.144151 -380.718577)
			(xy 71.094541 -380.69592) (xy 71.04866 -380.666434) (xy 71.007443 -380.630719) (xy 70.971728 -380.589502)
			(xy 70.942242 -380.543621) (xy 70.919585 -380.494011) (xy 70.90422 -380.441681) (xy 70.896458 -380.387697)
			(xy 70.895972 -380.360428) (xy 69.843396 -380.360428) (xy 69.843396 -382.36906) (xy 73.576688 -382.36906)
			(xy 73.576688 -381.50546) (xy 73.577174 -381.478191) (xy 73.584936 -381.424207) (xy 73.600301 -381.371877)
			(xy 73.622958 -381.322267) (xy 73.652444 -381.276386) (xy 73.688159 -381.235169) (xy 73.729376 -381.199454)
			(xy 73.775257 -381.169968) (xy 73.824867 -381.147311) (xy 73.877197 -381.131946) (xy 73.931181 -381.124184)
			(xy 73.985719 -381.124184) (xy 74.039703 -381.131946) (xy 74.092033 -381.147311) (xy 74.141643 -381.169968)
			(xy 74.187524 -381.199454) (xy 74.228741 -381.235169) (xy 74.264456 -381.276386) (xy 74.293942 -381.322267)
			(xy 74.316599 -381.371877) (xy 74.331964 -381.424207) (xy 74.339726 -381.478191) (xy 74.340212 -381.50546)
			(xy 74.340212 -382.36906) (xy 108.149136 -382.36906) (xy 108.149136 -381.50546) (xy 108.149622 -381.478209)
			(xy 108.157378 -381.424261) (xy 108.172733 -381.371966) (xy 108.195375 -381.322389) (xy 108.224841 -381.276539)
			(xy 108.260532 -381.235348) (xy 108.301723 -381.199657) (xy 108.347573 -381.170191) (xy 108.39715 -381.147549)
			(xy 108.449445 -381.132194) (xy 108.503393 -381.124438) (xy 108.557895 -381.124438) (xy 108.611843 -381.132194)
			(xy 108.664138 -381.147549) (xy 108.713715 -381.170191) (xy 108.759565 -381.199657) (xy 108.800756 -381.235348)
			(xy 108.836447 -381.276539) (xy 108.865913 -381.322389) (xy 108.888555 -381.371966) (xy 108.90391 -381.424261)
			(xy 108.911666 -381.478209) (xy 108.912152 -381.50546) (xy 108.912152 -382.36906) (xy 140.676884 -382.36906)
			(xy 140.676884 -381.50546) (xy 140.67737 -381.478209) (xy 140.685126 -381.424261) (xy 140.700481 -381.371966)
			(xy 140.723123 -381.322389) (xy 140.752589 -381.276539) (xy 140.78828 -381.235348) (xy 140.829471 -381.199657)
			(xy 140.875321 -381.170191) (xy 140.924898 -381.147549) (xy 140.977193 -381.132194) (xy 141.031141 -381.124438)
			(xy 141.085643 -381.124438) (xy 141.139591 -381.132194) (xy 141.191886 -381.147549) (xy 141.241463 -381.170191)
			(xy 141.287313 -381.199657) (xy 141.328504 -381.235348) (xy 141.364195 -381.276539) (xy 141.393661 -381.322389)
			(xy 141.416303 -381.371966) (xy 141.431658 -381.424261) (xy 141.439414 -381.478209) (xy 141.4399 -381.50546)
			(xy 141.4399 -382.36906) (xy 141.439414 -382.396311) (xy 141.431658 -382.450259) (xy 141.416303 -382.502554)
			(xy 141.393661 -382.552131) (xy 141.364195 -382.597981) (xy 141.328504 -382.639172) (xy 141.287313 -382.674863)
			(xy 141.241463 -382.704329) (xy 141.191886 -382.726971) (xy 141.139591 -382.742326) (xy 141.085643 -382.750082)
			(xy 141.031141 -382.750082) (xy 140.977193 -382.742326) (xy 140.924898 -382.726971) (xy 140.875321 -382.704329)
			(xy 140.829471 -382.674863) (xy 140.78828 -382.639172) (xy 140.752589 -382.597981) (xy 140.723123 -382.552131)
			(xy 140.700481 -382.502554) (xy 140.685126 -382.450259) (xy 140.67737 -382.396311) (xy 140.676884 -382.36906)
			(xy 108.912152 -382.36906) (xy 108.911666 -382.396311) (xy 108.90391 -382.450259) (xy 108.888555 -382.502554)
			(xy 108.865913 -382.552131) (xy 108.836447 -382.597981) (xy 108.800756 -382.639172) (xy 108.759565 -382.674863)
			(xy 108.713715 -382.704329) (xy 108.664138 -382.726971) (xy 108.611843 -382.742326) (xy 108.557895 -382.750082)
			(xy 108.503393 -382.750082) (xy 108.449445 -382.742326) (xy 108.39715 -382.726971) (xy 108.347573 -382.704329)
			(xy 108.301723 -382.674863) (xy 108.260532 -382.639172) (xy 108.224841 -382.597981) (xy 108.195375 -382.552131)
			(xy 108.172733 -382.502554) (xy 108.157378 -382.450259) (xy 108.149622 -382.396311) (xy 108.149136 -382.36906)
			(xy 74.340212 -382.36906) (xy 74.339726 -382.396329) (xy 74.331964 -382.450313) (xy 74.316599 -382.502643)
			(xy 74.293942 -382.552253) (xy 74.264456 -382.598134) (xy 74.228741 -382.639351) (xy 74.187524 -382.675066)
			(xy 74.141643 -382.704552) (xy 74.092033 -382.727209) (xy 74.039703 -382.742574) (xy 73.985719 -382.750336)
			(xy 73.931181 -382.750336) (xy 73.877197 -382.742574) (xy 73.824867 -382.727209) (xy 73.775257 -382.704552)
			(xy 73.729376 -382.675066) (xy 73.688159 -382.639351) (xy 73.652444 -382.598134) (xy 73.622958 -382.552253)
			(xy 73.600301 -382.502643) (xy 73.584936 -382.450313) (xy 73.577174 -382.396329) (xy 73.576688 -382.36906)
			(xy 69.843396 -382.36906) (xy 69.843396 -383.351278) (xy 69.843833 -383.361342) (xy 69.851567 -383.379926)
			(xy 69.858382 -383.387346) (xy 70.113398 -383.642362) (xy 70.130659 -383.660402) (xy 70.158418 -383.701895)
			(xy 70.177531 -383.748014) (xy 70.187262 -383.796979) (xy 70.18782 -383.82194) (xy 70.18782 -384.62077)
			(xy 70.187262 -384.644816) (xy 70.178224 -384.692051) (xy 70.160465 -384.736744) (xy 70.134618 -384.7773)
			(xy 70.101605 -384.812272) (xy 70.08241 -384.826764) (xy 70.072994 -384.834428) (xy 70.062011 -384.856042)
			(xy 70.061328 -384.868166) (xy 70.061328 -386.174488) (xy 70.060908 -386.18456) (xy 70.0532 -386.20317)
			(xy 70.046342 -386.210556) (xy 69.89826 -386.358384) (xy 69.891577 -386.365795) (xy 69.883996 -386.38423)
			(xy 69.883528 -386.394198) (xy 69.883528 -386.44195) (xy 69.884142 -386.454091) (xy 69.895145 -386.475726)
			(xy 69.90461 -386.483352) (xy 69.923785 -386.497872) (xy 69.956804 -386.532835) (xy 69.98266 -386.573383)
			(xy 70.000431 -386.61807) (xy 70.009484 -386.665301) (xy 70.01002 -386.689346) (xy 70.01002 -386.70357)
			(xy 70.061074 -386.73405) (xy 70.07202 -386.739694) (xy 70.096573 -386.74102) (xy 70.108064 -386.73659)
			(xy 70.132953 -386.725831) (xy 70.185009 -386.710659) (xy 70.238687 -386.703003) (xy 70.265798 -386.702554)
			(xy 70.29375 -386.70305) (xy 70.349053 -386.711224) (xy 70.402571 -386.727383) (xy 70.453157 -386.75118)
			(xy 70.499728 -386.782105) (xy 70.541286 -386.819497) (xy 70.576942 -386.862555) (xy 70.605931 -386.910355)
			(xy 70.627632 -386.961875) (xy 70.635114 -386.988812) (xy 70.639686 -387.00583) (xy 70.666864 -387.026912)
			(xy 71.576692 -387.026912) (xy 71.586763 -387.026491) (xy 71.605371 -387.01878) (xy 71.61276 -387.011926)
			(xy 73.00976 -385.614926) (xy 73.016599 -385.607525) (xy 73.024313 -385.588927) (xy 73.024746 -385.578858)
			(xy 73.024746 -384.41249) (xy 73.025318 -384.38753) (xy 73.035061 -384.338571) (xy 73.054168 -384.292453)
			(xy 73.081907 -384.25095) (xy 73.099168 -384.232912) (xy 73.7997 -383.53238) (xy 73.817742 -383.515123)
			(xy 73.859237 -383.487373) (xy 73.905355 -383.468268) (xy 73.954318 -383.458546) (xy 73.979278 -383.457958)
			(xy 76.321666 -383.457958) (xy 76.33036 -383.457617) (xy 76.346736 -383.451781) (xy 76.35367 -383.446528)
			(xy 76.374141 -383.430549) (xy 76.418585 -383.403686) (xy 76.466258 -383.383093) (xy 76.516282 -383.369149)
			(xy 76.567734 -383.362112) (xy 76.5937 -383.361692) (xy 76.619667 -383.362111) (xy 76.671124 -383.369125)
			(xy 76.721151 -383.383063) (xy 76.768822 -383.403667) (xy 76.813253 -383.430555) (xy 76.83373 -383.446528)
			(xy 76.840692 -383.451732) (xy 76.857051 -383.457575) (xy 76.865734 -383.457958) (xy 86.228682 -383.457958)
			(xy 86.253639 -383.458537) (xy 86.30259 -383.468292) (xy 86.348698 -383.487409) (xy 86.39019 -383.515155)
			(xy 86.40826 -383.53238) (xy 86.522814 -383.646934) (xy 86.530226 -383.653618) (xy 86.548659 -383.661215)
			(xy 86.568597 -383.661215) (xy 86.58703 -383.653618) (xy 86.594442 -383.646934) (xy 86.886288 -383.355342)
			(xy 86.904331 -383.338086) (xy 86.945826 -383.310338) (xy 86.991944 -383.291234) (xy 87.040906 -383.281511)
			(xy 87.065866 -383.28092) (xy 102.181406 -383.28092) (xy 102.206366 -383.281492) (xy 102.255327 -383.291233)
			(xy 102.301446 -383.310338) (xy 102.342952 -383.338075) (xy 102.360984 -383.355342) (xy 102.641146 -383.635504)
			(xy 102.658401 -383.653547) (xy 102.686148 -383.695043) (xy 102.70525 -383.741161) (xy 102.714971 -383.790123)
			(xy 102.715568 -383.815082) (xy 102.715568 -384.62077) (xy 102.71501 -384.644815) (xy 102.705971 -384.692049)
			(xy 102.688209 -384.736739) (xy 102.662358 -384.777291) (xy 102.629342 -384.812257) (xy 102.610158 -384.826764)
			(xy 102.600735 -384.834425) (xy 102.589741 -384.856039) (xy 102.589076 -384.868166) (xy 102.589076 -386.174488)
			(xy 102.588655 -386.184559) (xy 102.580941 -386.203164) (xy 102.57409 -386.210556) (xy 102.426008 -386.358384)
			(xy 102.41932 -386.365792) (xy 102.411731 -386.384229) (xy 102.411276 -386.394198) (xy 102.411276 -386.44195)
			(xy 102.411889 -386.454093) (xy 102.422884 -386.475736) (xy 102.432358 -386.483352) (xy 102.45153 -386.497874)
			(xy 102.484543 -386.532839) (xy 102.510394 -386.573388) (xy 102.528162 -386.618073) (xy 102.537212 -386.665302)
			(xy 102.537768 -386.689346) (xy 102.537768 -387.19887) (xy 102.538272 -387.208921) (xy 102.54599 -387.227485)
			(xy 102.552754 -387.234938) (xy 102.559104 -387.241288) (xy 102.566502 -387.248135) (xy 102.5851 -387.25587)
			(xy 102.595172 -387.256274) (xy 107.950508 -387.256274) (xy 107.960526 -387.255852) (xy 107.979036 -387.24818)
			(xy 107.993199 -387.234007) (xy 108.000859 -387.215493) (xy 108.001308 -387.205474) (xy 108.001308 -386.926074)
			(xy 108.001794 -386.898823) (xy 108.00955 -386.844875) (xy 108.024905 -386.79258) (xy 108.047547 -386.743003)
			(xy 108.077013 -386.697153) (xy 108.112704 -386.655962) (xy 108.153895 -386.620271) (xy 108.199745 -386.590805)
			(xy 108.249322 -386.568163) (xy 108.301617 -386.552808) (xy 108.355565 -386.545052) (xy 108.410067 -386.545052)
			(xy 108.464015 -386.552808) (xy 108.51631 -386.568163) (xy 108.565887 -386.590805) (xy 108.611737 -386.620271)
			(xy 108.652928 -386.655962) (xy 108.688619 -386.697153) (xy 108.718085 -386.743003) (xy 108.740727 -386.79258)
			(xy 108.756082 -386.844875) (xy 108.763838 -386.898823) (xy 108.764324 -386.926074) (xy 108.764324 -387.205474)
			(xy 108.76474 -387.215497) (xy 108.772406 -387.234019) (xy 108.78658 -387.248193) (xy 108.805101 -387.25586)
			(xy 108.815124 -387.256274) (xy 109.633258 -387.256274) (xy 109.643323 -387.25584) (xy 109.66191 -387.248108)
			(xy 109.669326 -387.241288) (xy 110.066582 -386.844032) (xy 110.07342 -386.836631) (xy 110.081132 -386.818032)
			(xy 110.081568 -386.807964) (xy 110.081568 -384.090926) (xy 110.082186 -384.065972) (xy 110.091935 -384.017025)
			(xy 110.111044 -383.97092) (xy 110.138778 -383.929427) (xy 110.15599 -383.911348) (xy 110.569502 -383.497836)
			(xy 110.587545 -383.480582) (xy 110.629041 -383.452836) (xy 110.675159 -383.433735) (xy 110.724121 -383.424015)
			(xy 110.74908 -383.423414) (xy 110.94339 -383.423414) (xy 110.950278 -383.423154) (xy 110.963545 -383.419429)
			(xy 110.969552 -383.416048) (xy 110.995114 -383.401357) (xy 111.049734 -383.37917) (xy 111.107115 -383.365643)
			(xy 111.165894 -383.361098) (xy 111.224673 -383.365643) (xy 111.282054 -383.37917) (xy 111.336674 -383.401357)
			(xy 111.362236 -383.416048) (xy 111.36823 -383.419464) (xy 111.381502 -383.423215) (xy 111.388398 -383.423414)
			(xy 120.79478 -383.423414) (xy 120.819733 -383.424033) (xy 120.868678 -383.433784) (xy 120.914781 -383.452896)
			(xy 120.95627 -383.480634) (xy 120.974358 -383.497836) (xy 121.159778 -383.683256) (xy 121.16719 -383.68994)
			(xy 121.185623 -383.697537) (xy 121.205561 -383.697537) (xy 121.223994 -383.68994) (xy 121.231406 -383.683256)
			(xy 121.616724 -383.297938) (xy 121.634765 -383.280678) (xy 121.676259 -383.25292) (xy 121.722377 -383.233804)
			(xy 121.771341 -383.224069) (xy 121.796302 -383.223516) (xy 136.689338 -383.223516) (xy 136.714297 -383.224091)
			(xy 136.763254 -383.233837) (xy 136.80937 -383.252946) (xy 136.850871 -383.280686) (xy 136.868916 -383.297938)
			(xy 137.21334 -383.642362) (xy 137.230599 -383.660403) (xy 137.258353 -383.701898) (xy 137.277463 -383.748016)
			(xy 137.287192 -383.796979) (xy 137.287762 -383.82194) (xy 137.287762 -384.62077) (xy 137.287204 -384.644815)
			(xy 137.278164 -384.692049) (xy 137.260402 -384.736739) (xy 137.234552 -384.77729) (xy 137.201535 -384.812256)
			(xy 137.182352 -384.826764) (xy 137.172853 -384.834385) (xy 137.161727 -384.856007) (xy 137.161016 -384.868166)
			(xy 137.161016 -386.174488) (xy 137.160572 -386.184518) (xy 137.15299 -386.203085) (xy 137.146284 -386.210556)
			(xy 136.998202 -386.358384) (xy 136.991404 -386.365734) (xy 136.983702 -386.384197) (xy 136.983216 -386.394198)
			(xy 136.983216 -386.44195) (xy 136.983918 -386.454107) (xy 136.995065 -386.475716) (xy 137.004552 -386.483352)
			(xy 137.023724 -386.497874) (xy 137.056738 -386.532839) (xy 137.08259 -386.573387) (xy 137.100358 -386.618073)
			(xy 137.109408 -386.665302) (xy 137.109962 -386.689346) (xy 137.109962 -387.32079) (xy 137.110448 -387.330802)
			(xy 137.118104 -387.349304) (xy 137.132256 -387.363469) (xy 137.150751 -387.371143) (xy 137.160762 -387.37159)
			(xy 138.462258 -387.37159) (xy 138.472323 -387.371156) (xy 138.490911 -387.363426) (xy 138.498326 -387.356604)
			(xy 139.953238 -385.901692) (xy 139.96009 -385.894296) (xy 139.967831 -385.875697) (xy 139.968224 -385.865624)
			(xy 139.968224 -384.1369) (xy 139.968795 -384.11194) (xy 139.978535 -384.062978) (xy 139.997641 -384.016858)
			(xy 140.025377 -383.975352) (xy 140.042646 -383.957322) (xy 140.839952 -383.160016) (xy 140.857992 -383.142754)
			(xy 140.899484 -383.114992) (xy 140.945603 -383.095875) (xy 140.994568 -383.086142) (xy 141.01953 -383.085594)
			(xy 169.051478 -383.085594) (xy 169.076432 -383.086213) (xy 169.125378 -383.095963) (xy 169.171481 -383.115074)
			(xy 169.212972 -383.14281) (xy 169.231056 -383.160016) (xy 169.72534 -383.6543) (xy 169.742595 -383.672343)
			(xy 169.770344 -383.713838) (xy 169.789447 -383.759956) (xy 169.799169 -383.808918) (xy 169.799762 -383.833878)
			(xy 169.799762 -388.19328) (xy 169.800201 -388.203342) (xy 169.807943 -388.22192) (xy 169.814748 -388.229348)
			(xy 170.647106 -389.061706) (xy 170.654505 -389.068551) (xy 170.673103 -389.076282) (xy 170.683174 -389.076692)
		)
		(stroke
			(width 0)
			(type solid)
		)
		(fill yes)
		(layer "In8.Cu")
		(net "P1V8_CPU1_RT_1D")
	)
	(gr_poly
		(pts
			(xy 143.734536 -266.656566) (xy 143.74114 -266.643866) (xy 143.753486 -266.621193) (xy 143.784122 -266.579643)
			(xy 143.820838 -266.543355) (xy 143.862744 -266.513208) (xy 143.908822 -266.489933) (xy 143.957956 -266.474096)
			(xy 144.008953 -266.46608) (xy 144.060575 -266.46608) (xy 144.111572 -266.474096) (xy 144.160706 -266.489933)
			(xy 144.206784 -266.513208) (xy 144.24869 -266.543355) (xy 144.285406 -266.579643) (xy 144.316042 -266.621193)
			(xy 144.328388 -266.643866) (xy 144.334992 -266.656566) (xy 144.359122 -266.671298) (xy 145.443194 -266.671298)
			(xy 145.455331 -266.670675) (xy 145.476954 -266.659665) (xy 145.484596 -266.650216) (xy 145.499095 -266.63096)
			(xy 145.534057 -266.597788) (xy 145.57465 -266.571809) (xy 145.619416 -266.553956) (xy 145.666747 -266.54487)
			(xy 145.690844 -266.544298) (xy 163.992814 -266.544298) (xy 164.002883 -266.543872) (xy 164.021484 -266.536154)
			(xy 164.028882 -266.529312) (xy 164.110416 -266.447778) (xy 164.118255 -266.439219) (xy 164.125885 -266.417326)
			(xy 164.123114 -266.394307) (xy 164.117274 -266.384278) (xy 164.103508 -266.361903) (xy 164.081757 -266.314085)
			(xy 164.067007 -266.263665) (xy 164.059557 -266.211663) (xy 164.059108 -266.185396) (xy 164.059633 -266.157225)
			(xy 164.068186 -266.101537) (xy 164.085108 -266.047797) (xy 164.110004 -265.997255) (xy 164.142297 -265.951087)
			(xy 164.181234 -265.910366) (xy 164.225911 -265.876039) (xy 164.25037 -265.862054) (xy 164.258137 -265.85736)
			(xy 164.270004 -265.843646) (xy 164.276387 -265.82667) (xy 164.276786 -265.817604) (xy 164.276786 -264.853166)
			(xy 164.27642 -264.844089) (xy 164.270075 -264.827081) (xy 164.258166 -264.813379) (xy 164.25037 -264.808716)
			(xy 164.227564 -264.795642) (xy 164.185567 -264.764029) (xy 164.148481 -264.726775) (xy 164.117057 -264.684636)
			(xy 164.091931 -264.638463) (xy 164.073613 -264.589192) (xy 164.062472 -264.537821) (xy 164.058734 -264.485387)
			(xy 164.062475 -264.432955) (xy 164.07362 -264.381583) (xy 164.091942 -264.332314) (xy 164.117071 -264.286143)
			(xy 164.148497 -264.244006) (xy 164.185586 -264.206755) (xy 164.227585 -264.175144) (xy 164.25037 -264.162032)
			(xy 164.258135 -264.157337) (xy 164.269996 -264.143622) (xy 164.276372 -264.126646) (xy 164.276786 -264.117582)
			(xy 164.276786 -263.153144) (xy 164.276433 -263.14406) (xy 164.270104 -263.127031) (xy 164.258201 -263.113307)
			(xy 164.25037 -263.108694) (xy 164.227566 -263.09562) (xy 164.185572 -263.064007) (xy 164.148489 -263.026755)
			(xy 164.117068 -262.984617) (xy 164.091945 -262.938446) (xy 164.073628 -262.889177) (xy 164.06249 -262.837807)
			(xy 164.058754 -262.785377) (xy 164.062496 -262.732947) (xy 164.073641 -262.681579) (xy 164.091964 -262.632312)
			(xy 164.117092 -262.586144) (xy 164.148519 -262.54401) (xy 164.185606 -262.506762) (xy 164.227605 -262.475154)
			(xy 164.25037 -262.46201) (xy 164.258132 -262.457314) (xy 164.269988 -262.443598) (xy 164.276356 -262.426623)
			(xy 164.276786 -262.41756) (xy 164.276786 -255.503172) (xy 164.276421 -255.494094) (xy 164.270077 -255.477085)
			(xy 164.258169 -255.463381) (xy 164.25037 -255.458722) (xy 164.227564 -255.445648) (xy 164.185566 -255.414035)
			(xy 164.148479 -255.376781) (xy 164.117054 -255.334641) (xy 164.091928 -255.288468) (xy 164.073609 -255.239197)
			(xy 164.062467 -255.187824) (xy 164.058729 -255.13539) (xy 164.06247 -255.082957) (xy 164.073614 -255.031585)
			(xy 164.091936 -254.982314) (xy 164.117065 -254.936143) (xy 164.148491 -254.894004) (xy 164.18558 -254.856752)
			(xy 164.22758 -254.825141) (xy 164.25037 -254.812038) (xy 164.258135 -254.807343) (xy 164.269998 -254.793628)
			(xy 164.276376 -254.776653) (xy 164.276786 -254.767588) (xy 164.276786 -252.953012) (xy 164.276427 -252.943931)
			(xy 164.270092 -252.92691) (xy 164.258187 -252.913196) (xy 164.25037 -252.908562) (xy 164.227561 -252.895488)
			(xy 164.185557 -252.863874) (xy 164.148465 -252.826619) (xy 164.117035 -252.784476) (xy 164.091904 -252.7383)
			(xy 164.07358 -252.689025) (xy 164.062435 -252.637648) (xy 164.058694 -252.58521) (xy 164.062432 -252.532771)
			(xy 164.073575 -252.481393) (xy 164.091896 -252.432117) (xy 164.117025 -252.38594) (xy 164.148452 -252.343796)
			(xy 164.185543 -252.306539) (xy 164.227545 -252.274922) (xy 164.25037 -252.261878) (xy 164.258129 -252.25718)
			(xy 164.269976 -252.243462) (xy 164.276334 -252.226489) (xy 164.276786 -252.217428) (xy 164.276786 -251.25299)
			(xy 164.276424 -251.243911) (xy 164.270084 -251.226896) (xy 164.258177 -251.213188) (xy 164.25037 -251.20854)
			(xy 164.227563 -251.195466) (xy 164.185562 -251.163852) (xy 164.148472 -251.126598) (xy 164.117046 -251.084457)
			(xy 164.091917 -251.038283) (xy 164.073596 -250.989009) (xy 164.062453 -250.937635) (xy 164.058713 -250.885199)
			(xy 164.062453 -250.832763) (xy 164.073596 -250.781389) (xy 164.091918 -250.732116) (xy 164.117047 -250.685941)
			(xy 164.148474 -250.643801) (xy 164.185563 -250.606546) (xy 164.227564 -250.574933) (xy 164.25037 -250.561856)
			(xy 164.258137 -250.557162) (xy 164.270005 -250.543448) (xy 164.276388 -250.526472) (xy 164.276786 -250.517406)
			(xy 164.276786 -249.553222) (xy 164.276429 -249.54414) (xy 164.270096 -249.527117) (xy 164.258191 -249.513399)
			(xy 164.25037 -249.508772) (xy 164.22756 -249.495698) (xy 164.185555 -249.464084) (xy 164.148461 -249.426828)
			(xy 164.11703 -249.384685) (xy 164.091898 -249.338508) (xy 164.073573 -249.289232) (xy 164.062427 -249.237854)
			(xy 164.058685 -249.185414) (xy 164.062423 -249.132974) (xy 164.073565 -249.081596) (xy 164.091886 -249.032318)
			(xy 164.117015 -248.986139) (xy 164.148442 -248.943994) (xy 164.185533 -248.906735) (xy 164.227536 -248.875118)
			(xy 164.25037 -248.862088) (xy 164.25813 -248.857391) (xy 164.269979 -248.843673) (xy 164.276341 -248.826699)
			(xy 164.276786 -248.817638) (xy 164.276786 -247.8532) (xy 164.276426 -247.84412) (xy 164.270088 -247.827103)
			(xy 164.258182 -247.813391) (xy 164.25037 -247.80875) (xy 164.227562 -247.795676) (xy 164.18556 -247.764062)
			(xy 164.148469 -247.726807) (xy 164.117041 -247.684666) (xy 164.091911 -247.638491) (xy 164.073589 -247.589217)
			(xy 164.062445 -247.537841) (xy 164.058704 -247.485404) (xy 164.062444 -247.432967) (xy 164.073587 -247.381591)
			(xy 164.091908 -247.332316) (xy 164.117037 -247.286141) (xy 164.148464 -247.243998) (xy 164.185554 -247.206743)
			(xy 164.227556 -247.175128) (xy 164.25037 -247.162066) (xy 164.258138 -247.157372) (xy 164.270009 -247.143659)
			(xy 164.276395 -247.126683) (xy 164.276786 -247.117616) (xy 164.276786 -246.153178) (xy 164.276422 -246.1441)
			(xy 164.270079 -246.127089) (xy 164.258172 -246.113384) (xy 164.25037 -246.108728) (xy 164.227564 -246.095654)
			(xy 164.185564 -246.064041) (xy 164.148477 -246.026787) (xy 164.117051 -245.984647) (xy 164.091924 -245.938473)
			(xy 164.073604 -245.889201) (xy 164.062462 -245.837828) (xy 164.058724 -245.785393) (xy 164.062464 -245.732959)
			(xy 164.073608 -245.681586) (xy 164.09193 -245.632315) (xy 164.117059 -245.586142) (xy 164.148485 -245.544003)
			(xy 164.185575 -245.50675) (xy 164.227575 -245.475138) (xy 164.25037 -245.462044) (xy 164.258136 -245.45735)
			(xy 164.27 -245.443635) (xy 164.27638 -245.426659) (xy 164.276786 -245.417594) (xy 164.276786 -244.453156)
			(xy 164.276418 -244.44408) (xy 164.270071 -244.427074) (xy 164.258162 -244.413376) (xy 164.25037 -244.408706)
			(xy 164.227565 -244.395632) (xy 164.185569 -244.364019) (xy 164.148484 -244.326766) (xy 164.117062 -244.284627)
			(xy 164.091937 -244.238455) (xy 164.07362 -244.189185) (xy 164.06248 -244.137815) (xy 164.058743 -244.085383)
			(xy 164.062485 -244.032951) (xy 164.07363 -243.981581) (xy 164.091952 -243.932313) (xy 164.117081 -243.886144)
			(xy 164.148507 -243.844008) (xy 164.185595 -243.806758) (xy 164.227594 -243.775149) (xy 164.25037 -243.762022)
			(xy 164.258134 -243.757327) (xy 164.269992 -243.743611) (xy 164.276365 -243.726636) (xy 164.276786 -243.717572)
			(xy 164.276786 -242.753134) (xy 164.276431 -242.744051) (xy 164.270101 -242.727024) (xy 164.258197 -242.713303)
			(xy 164.25037 -242.708684) (xy 164.22756 -242.69561) (xy 164.185553 -242.663995) (xy 164.148457 -242.626739)
			(xy 164.117025 -242.584596) (xy 164.091891 -242.538418) (xy 164.073565 -242.489141) (xy 164.062418 -242.437761)
			(xy 164.058675 -242.38532) (xy 164.062412 -242.332879) (xy 164.073553 -242.281498) (xy 164.091874 -242.232219)
			(xy 164.117003 -242.186038) (xy 164.148431 -242.143891) (xy 164.185522 -242.106631) (xy 164.227526 -242.075012)
			(xy 164.25037 -242.062) (xy 164.258131 -242.057303) (xy 164.269984 -242.043586) (xy 164.276349 -242.026612)
			(xy 164.276786 -242.01755) (xy 164.276786 -236.803184) (xy 164.276423 -236.794105) (xy 164.270081 -236.777092)
			(xy 164.258174 -236.763386) (xy 164.25037 -236.758734) (xy 164.227563 -236.74566) (xy 164.185563 -236.714047)
			(xy 164.148475 -236.676792) (xy 164.117048 -236.634652) (xy 164.091921 -236.588478) (xy 164.0736 -236.539205)
			(xy 164.062458 -236.487831) (xy 164.058718 -236.435396) (xy 164.062459 -236.382961) (xy 164.073602 -236.331587)
			(xy 164.091924 -236.282315) (xy 164.117053 -236.236142) (xy 164.14848 -236.194002) (xy 164.185569 -236.156748)
			(xy 164.22757 -236.125136) (xy 164.25037 -236.11205) (xy 164.258137 -236.107356) (xy 164.270003 -236.093641)
			(xy 164.276384 -236.076666) (xy 164.276786 -236.0676) (xy 164.276786 -235.103162) (xy 164.276419 -235.094085)
			(xy 164.270073 -235.077078) (xy 164.258165 -235.063378) (xy 164.25037 -235.058712) (xy 164.227565 -235.045638)
			(xy 164.185568 -235.014025) (xy 164.148482 -234.976772) (xy 164.117059 -234.934632) (xy 164.091934 -234.88846)
			(xy 164.073616 -234.83919) (xy 164.062475 -234.787818) (xy 164.058738 -234.735386) (xy 164.062479 -234.682953)
			(xy 164.073624 -234.631583) (xy 164.091946 -234.582313) (xy 164.117075 -234.536143) (xy 164.148501 -234.494006)
			(xy 164.18559 -234.456756) (xy 164.227589 -234.425146) (xy 164.25037 -234.412028) (xy 164.258134 -234.407333)
			(xy 164.269995 -234.393617) (xy 164.276369 -234.376642) (xy 164.276786 -234.367578) (xy 164.276786 -233.40314)
			(xy 164.276432 -233.394056) (xy 164.270103 -233.377028) (xy 164.258199 -233.363306) (xy 164.25037 -233.35869)
			(xy 164.227559 -233.345616) (xy 164.185551 -233.314001) (xy 164.148455 -233.276745) (xy 164.117022 -233.234601)
			(xy 164.091887 -233.188423) (xy 164.073561 -233.139145) (xy 164.062413 -233.087765) (xy 164.058669 -233.035323)
			(xy 164.062406 -232.982881) (xy 164.073548 -232.931499) (xy 164.091868 -232.882219) (xy 164.116997 -232.836038)
			(xy 164.148425 -232.79389) (xy 164.185516 -232.756629) (xy 164.22752 -232.725009) (xy 164.25037 -232.712006)
			(xy 164.258132 -232.70731) (xy 164.269986 -232.693593) (xy 164.276353 -232.676619) (xy 164.276786 -232.667556)
			(xy 164.276786 -227.45319) (xy 164.276424 -227.444111) (xy 164.270084 -227.427096) (xy 164.258177 -227.413388)
			(xy 164.25037 -227.40874) (xy 164.227563 -227.395666) (xy 164.185562 -227.364052) (xy 164.148472 -227.326798)
			(xy 164.117046 -227.284657) (xy 164.091917 -227.238483) (xy 164.073596 -227.189209) (xy 164.062453 -227.137835)
			(xy 164.058713 -227.085399) (xy 164.062453 -227.032963) (xy 164.073596 -226.981589) (xy 164.091918 -226.932316)
			(xy 164.117047 -226.886141) (xy 164.148474 -226.844001) (xy 164.185563 -226.806746) (xy 164.227564 -226.775133)
			(xy 164.25037 -226.762056) (xy 164.258137 -226.757362) (xy 164.270005 -226.743648) (xy 164.276388 -226.726672)
			(xy 164.276786 -226.717606) (xy 164.276786 -225.753168) (xy 164.27642 -225.744091) (xy 164.270075 -225.727082)
			(xy 164.258167 -225.71338) (xy 164.25037 -225.708718) (xy 164.227564 -225.695644) (xy 164.185566 -225.664031)
			(xy 164.14848 -225.626777) (xy 164.117056 -225.584638) (xy 164.09193 -225.538465) (xy 164.073611 -225.489194)
			(xy 164.06247 -225.437822) (xy 164.058733 -225.385388) (xy 164.062474 -225.332955) (xy 164.073618 -225.281584)
			(xy 164.09194 -225.232314) (xy 164.117069 -225.186143) (xy 164.148495 -225.144005) (xy 164.185584 -225.106754)
			(xy 164.227584 -225.075143) (xy 164.25037 -225.062034) (xy 164.258135 -225.057339) (xy 164.269997 -225.043624)
			(xy 164.276373 -225.026648) (xy 164.276786 -225.017584) (xy 164.276786 -224.053146) (xy 164.276433 -224.044061)
			(xy 164.270105 -224.027032) (xy 164.258202 -224.013308) (xy 164.25037 -224.008696) (xy 164.227566 -223.995622)
			(xy 164.185571 -223.964009) (xy 164.148488 -223.926757) (xy 164.117067 -223.884618) (xy 164.091943 -223.838447)
			(xy 164.073627 -223.789178) (xy 164.062488 -223.737808) (xy 164.058752 -223.685378) (xy 164.062494 -223.632948)
			(xy 164.073639 -223.581579) (xy 164.091962 -223.532312) (xy 164.117091 -223.486144) (xy 164.148517 -223.44401)
			(xy 164.185605 -223.406761) (xy 164.227603 -223.375154) (xy 164.25037 -223.362012) (xy 164.258133 -223.357316)
			(xy 164.269989 -223.3436) (xy 164.276358 -223.326625) (xy 164.276786 -223.317562) (xy 164.276786 -218.103196)
			(xy 164.276425 -218.094116) (xy 164.270086 -218.0771) (xy 164.25818 -218.06339) (xy 164.25037 -218.058746)
			(xy 164.227562 -218.045672) (xy 164.185561 -218.014058) (xy 164.14847 -217.976804) (xy 164.117043 -217.934662)
			(xy 164.091914 -217.888487) (xy 164.073592 -217.839214) (xy 164.062448 -217.787839) (xy 164.058708 -217.735402)
			(xy 164.062447 -217.682965) (xy 164.073591 -217.63159) (xy 164.091912 -217.582316) (xy 164.117041 -217.536141)
			(xy 164.148468 -217.493999) (xy 164.185558 -217.456744) (xy 164.227559 -217.42513) (xy 164.25037 -217.412062)
			(xy 164.258138 -217.407368) (xy 164.270007 -217.393654) (xy 164.276392 -217.376678) (xy 164.276786 -217.367612)
			(xy 164.276786 -216.403174) (xy 164.276421 -216.394096) (xy 164.270078 -216.377086) (xy 164.25817 -216.363382)
			(xy 164.25037 -216.358724) (xy 164.227564 -216.34565) (xy 164.185565 -216.314037) (xy 164.148478 -216.276783)
			(xy 164.117053 -216.234643) (xy 164.091927 -216.18847) (xy 164.073607 -216.139198) (xy 164.062466 -216.087825)
			(xy 164.058727 -216.035391) (xy 164.062468 -215.982957) (xy 164.073612 -215.931585) (xy 164.091934 -215.882314)
			(xy 164.117063 -215.836142) (xy 164.148489 -215.794004) (xy 164.185578 -215.756752) (xy 164.227578 -215.72514)
			(xy 164.25037 -215.71204) (xy 164.258135 -215.707345) (xy 164.269999 -215.69363) (xy 164.276377 -215.676655)
			(xy 164.276786 -215.66759) (xy 164.276786 -214.703152) (xy 164.276418 -214.694076) (xy 164.270069 -214.677072)
			(xy 164.25816 -214.663374) (xy 164.25037 -214.658702) (xy 164.227565 -214.645628) (xy 164.18557 -214.614015)
			(xy 164.148486 -214.576762) (xy 164.117064 -214.534624) (xy 164.09194 -214.488452) (xy 164.073623 -214.439183)
			(xy 164.062483 -214.387812) (xy 164.058747 -214.335381) (xy 164.062489 -214.28295) (xy 164.073634 -214.23158)
			(xy 164.091956 -214.182313) (xy 164.117085 -214.136144) (xy 164.148511 -214.094008) (xy 164.185599 -214.056759)
			(xy 164.227598 -214.025151) (xy 164.25037 -214.012018) (xy 164.258133 -214.007322) (xy 164.269991 -213.993606)
			(xy 164.276362 -213.976631) (xy 164.276786 -213.967568) (xy 164.276786 -208.753202) (xy 164.276426 -208.744122)
			(xy 164.270088 -208.727104) (xy 164.258182 -208.713392) (xy 164.25037 -208.708752) (xy 164.227562 -208.695678)
			(xy 164.185559 -208.664064) (xy 164.148468 -208.626809) (xy 164.11704 -208.584668) (xy 164.09191 -208.538492)
			(xy 164.073587 -208.489218) (xy 164.062443 -208.437842) (xy 164.058703 -208.385405) (xy 164.062442 -208.332967)
			(xy 164.073585 -208.281591) (xy 164.091906 -208.232316) (xy 164.117035 -208.186141) (xy 164.148462 -208.143998)
			(xy 164.185552 -208.106742) (xy 164.227554 -208.075127) (xy 164.25037 -208.062068) (xy 164.258138 -208.057375)
			(xy 164.270009 -208.043661) (xy 164.276397 -208.026685) (xy 164.276786 -208.017618) (xy 164.276786 -207.05318)
			(xy 164.276422 -207.044102) (xy 164.27008 -207.02709) (xy 164.258173 -207.013384) (xy 164.25037 -207.00873)
			(xy 164.227563 -206.995656) (xy 164.185564 -206.964043) (xy 164.148476 -206.926789) (xy 164.11705 -206.884648)
			(xy 164.091923 -206.838475) (xy 164.073603 -206.789202) (xy 164.062461 -206.737829) (xy 164.058722 -206.685394)
			(xy 164.062462 -206.63296) (xy 164.073606 -206.581586) (xy 164.091928 -206.532315) (xy 164.117057 -206.486142)
			(xy 164.148484 -206.444003) (xy 164.185573 -206.40675) (xy 164.227573 -206.375137) (xy 164.25037 -206.362046)
			(xy 164.258136 -206.357352) (xy 164.270001 -206.343637) (xy 164.276381 -206.326661) (xy 164.276786 -206.317596)
			(xy 164.276786 -205.353158) (xy 164.276419 -205.344082) (xy 164.270072 -205.327076) (xy 164.258163 -205.313376)
			(xy 164.25037 -205.308708) (xy 164.227565 -205.295634) (xy 164.185569 -205.264021) (xy 164.148484 -205.226768)
			(xy 164.117061 -205.184629) (xy 164.091936 -205.138457) (xy 164.073618 -205.089187) (xy 164.062478 -205.037816)
			(xy 164.058741 -204.985384) (xy 164.062483 -204.932952) (xy 164.073628 -204.881582) (xy 164.09195 -204.832313)
			(xy 164.117079 -204.786143) (xy 164.148505 -204.744007) (xy 164.185593 -204.706757) (xy 164.227593 -204.675148)
			(xy 164.25037 -204.662024) (xy 164.258134 -204.657329) (xy 164.269993 -204.643613) (xy 164.276366 -204.626638)
			(xy 164.276786 -204.617574) (xy 164.276786 -199.403208) (xy 164.276427 -199.394127) (xy 164.270091 -199.377108)
			(xy 164.258185 -199.363394) (xy 164.25037 -199.358758) (xy 164.227561 -199.345684) (xy 164.185558 -199.31407)
			(xy 164.148466 -199.276815) (xy 164.117037 -199.234673) (xy 164.091906 -199.188497) (xy 164.073583 -199.139222)
			(xy 164.062438 -199.087846) (xy 164.058697 -199.035408) (xy 164.062436 -198.982969) (xy 164.073579 -198.931593)
			(xy 164.0919 -198.882317) (xy 164.117029 -198.83614) (xy 164.148456 -198.793997) (xy 164.185546 -198.75674)
			(xy 164.227548 -198.725124) (xy 164.25037 -198.712074) (xy 164.258128 -198.707376) (xy 164.269974 -198.693658)
			(xy 164.276331 -198.676685) (xy 164.276786 -198.667624) (xy 164.276786 -197.703186) (xy 164.276423 -197.694107)
			(xy 164.270082 -197.677094) (xy 164.258175 -197.663386) (xy 164.25037 -197.658736) (xy 164.227563 -197.645662)
			(xy 164.185563 -197.614049) (xy 164.148474 -197.576794) (xy 164.117047 -197.534654) (xy 164.09192 -197.488479)
			(xy 164.073599 -197.439207) (xy 164.062456 -197.387833) (xy 164.058717 -197.335397) (xy 164.062457 -197.282962)
			(xy 164.0736 -197.231588) (xy 164.091922 -197.182315) (xy 164.117051 -197.136142) (xy 164.148478 -197.094001)
			(xy 164.185567 -197.056748) (xy 164.227568 -197.025135) (xy 164.25037 -197.012052) (xy 164.258137 -197.007358)
			(xy 164.270003 -196.993643) (xy 164.276385 -196.976668) (xy 164.276786 -196.967602) (xy 164.276786 -194.573652)
			(xy 164.276532 -194.573144) (xy 164.26561 -194.559174) (xy 164.252823 -194.542252) (xy 164.232475 -194.505039)
			(xy 164.218586 -194.464966) (xy 164.211541 -194.423144) (xy 164.211535 -194.380732) (xy 164.218568 -194.338907)
			(xy 164.232445 -194.29883) (xy 164.252781 -194.261611) (xy 164.26561 -194.244722) (xy 164.270641 -194.23784)
			(xy 164.276225 -194.221745) (xy 164.276532 -194.213226) (xy 164.276532 -183.226456) (xy 164.276102 -183.216389)
			(xy 164.26838 -183.197793) (xy 164.261546 -183.190388) (xy 149.383242 -168.312084) (xy 149.375819 -168.305301)
			(xy 149.357222 -168.297695) (xy 149.347174 -168.297352) (xy 140.431266 -168.297352) (xy 140.421469 -168.297734)
			(xy 140.403271 -168.304979) (xy 140.389142 -168.318544) (xy 140.384784 -168.327324) (xy 140.368021 -168.363475)
			(xy 140.328033 -168.432406) (xy 140.281071 -168.496789) (xy 140.22765 -168.555921) (xy 140.168351 -168.609158)
			(xy 140.103822 -168.655918) (xy 140.034767 -168.695691) (xy 139.961939 -168.728044) (xy 139.886134 -168.752622)
			(xy 139.808178 -168.769158) (xy 139.728923 -168.777471) (xy 139.649233 -168.777471) (xy 139.569978 -168.769158)
			(xy 139.492022 -168.752622) (xy 139.416217 -168.728044) (xy 139.343389 -168.695691) (xy 139.274334 -168.655918)
			(xy 139.209805 -168.609158) (xy 139.150506 -168.555921) (xy 139.097085 -168.496789) (xy 139.050123 -168.432406)
			(xy 139.010135 -168.363475) (xy 138.993372 -168.327324) (xy 138.988938 -168.318601) (xy 138.974811 -168.305086)
			(xy 138.956666 -168.297806) (xy 138.94689 -168.297352) (xy 136.143492 -168.297352) (xy 136.143492 -168.296844)
			(xy 130.011424 -168.296844) (xy 130.001361 -168.297282) (xy 129.982781 -168.305021) (xy 129.975356 -168.31183)
			(xy 128.64338 -169.643806) (xy 128.625341 -169.66107) (xy 128.583849 -169.688835) (xy 128.53773 -169.707955)
			(xy 128.488765 -169.717694) (xy 128.463802 -169.718228) (xy 126.55296 -169.718228) (xy 126.542894 -169.718659)
			(xy 126.524302 -169.726387) (xy 126.516892 -169.733214) (xy 113.757456 -182.49265) (xy 113.753138 -182.52694)
			(xy 113.762028 -182.54218) (xy 113.774752 -182.564367) (xy 113.794795 -182.611423) (xy 113.80836 -182.660738)
			(xy 113.815204 -182.711425) (xy 113.815622 -182.736998) (xy 113.815136 -182.76425) (xy 113.80738 -182.818198)
			(xy 113.792025 -182.870494) (xy 113.769385 -182.920073) (xy 113.739919 -182.965924) (xy 113.704227 -183.007116)
			(xy 113.663037 -183.042809) (xy 113.617187 -183.072277) (xy 113.567609 -183.09492) (xy 113.515314 -183.110277)
			(xy 113.461366 -183.118035) (xy 113.434114 -183.118506) (xy 113.408542 -183.118078) (xy 113.357859 -183.111217)
			(xy 113.308544 -183.097657) (xy 113.261479 -183.07764) (xy 113.239296 -183.064912) (xy 113.224056 -183.056022)
			(xy 113.189766 -183.06034) (xy 112.196372 -184.053734) (xy 112.189523 -184.061131) (xy 112.18179 -184.07973)
			(xy 112.181386 -184.089802) (xy 112.181386 -192.092326) (xy 112.181813 -192.102394) (xy 112.189533 -192.120993)
			(xy 112.196372 -192.128394) (xy 131.697476 -211.629498) (xy 131.714735 -211.647539) (xy 131.742491 -211.689032)
			(xy 131.7616 -211.735151) (xy 131.771324 -211.784115) (xy 131.771898 -211.809076) (xy 131.771898 -212.98027)
			(xy 140.011662 -212.98027) (xy 140.015692 -212.83792) (xy 140.027769 -212.696027) (xy 140.047854 -212.555044)
			(xy 140.075883 -212.415423) (xy 140.111767 -212.277611) (xy 140.155389 -212.14205) (xy 140.206611 -212.009175)
			(xy 140.265269 -211.87941) (xy 140.331174 -211.753171) (xy 140.404115 -211.630863) (xy 140.483859 -211.512878)
			(xy 140.570151 -211.399593) (xy 140.662713 -211.291372) (xy 140.76125 -211.18856) (xy 140.865445 -211.091488)
			(xy 140.974966 -211.000467) (xy 141.08946 -210.915787) (xy 141.208562 -210.837721) (xy 141.33189 -210.766517)
			(xy 141.459048 -210.702405) (xy 141.58963 -210.64559) (xy 141.723218 -210.596253) (xy 141.859382 -210.554553)
			(xy 141.997688 -210.520624) (xy 142.137691 -210.494573) (xy 142.278945 -210.476485) (xy 142.420995 -210.466417)
			(xy 142.563387 -210.464402) (xy 142.705666 -210.470446) (xy 142.847374 -210.484529) (xy 142.988059 -210.506608)
			(xy 143.127269 -210.53661) (xy 143.264559 -210.57444) (xy 143.399489 -210.619976) (xy 143.531627 -210.673074)
			(xy 143.660549 -210.733561) (xy 143.785842 -210.801246) (xy 143.907105 -210.875911) (xy 144.02395 -210.957317)
			(xy 144.136003 -211.045203) (xy 144.242903 -211.139287) (xy 144.34431 -211.239269) (xy 144.439898 -211.344827)
			(xy 144.529361 -211.455625) (xy 144.612412 -211.571306) (xy 144.688785 -211.691501) (xy 144.758236 -211.815824)
			(xy 144.820542 -211.943877) (xy 144.875504 -212.07525) (xy 144.922945 -212.209522) (xy 144.962714 -212.346263)
			(xy 144.994683 -212.485035) (xy 145.01875 -212.625393) (xy 145.034838 -212.766888) (xy 145.042894 -212.909067)
			(xy 145.043398 -212.98027) (xy 145.042894 -213.051473) (xy 145.034838 -213.193652) (xy 145.01875 -213.335147)
			(xy 144.994683 -213.475505) (xy 144.962714 -213.614277) (xy 144.922945 -213.751018) (xy 144.875504 -213.88529)
			(xy 144.820542 -214.016663) (xy 144.758236 -214.144716) (xy 144.688785 -214.269039) (xy 144.612412 -214.389234)
			(xy 144.529361 -214.504915) (xy 144.439898 -214.615713) (xy 144.34431 -214.721271) (xy 144.242903 -214.821253)
			(xy 144.136003 -214.915337) (xy 144.02395 -215.003223) (xy 143.907105 -215.084629) (xy 143.785842 -215.159294)
			(xy 143.660549 -215.226979) (xy 143.531627 -215.287466) (xy 143.399489 -215.340564) (xy 143.264559 -215.3861)
			(xy 143.127269 -215.42393) (xy 142.988059 -215.453932) (xy 142.847374 -215.476011) (xy 142.705666 -215.490094)
			(xy 142.563387 -215.496138) (xy 142.420995 -215.494123) (xy 142.278945 -215.484055) (xy 142.137691 -215.465967)
			(xy 141.997688 -215.439916) (xy 141.859382 -215.405987) (xy 141.723218 -215.364287) (xy 141.58963 -215.31495)
			(xy 141.459048 -215.258135) (xy 141.33189 -215.194023) (xy 141.208562 -215.122819) (xy 141.08946 -215.044753)
			(xy 140.974966 -214.960073) (xy 140.865445 -214.869052) (xy 140.76125 -214.77198) (xy 140.662713 -214.669168)
			(xy 140.570151 -214.560947) (xy 140.483859 -214.447662) (xy 140.404115 -214.329677) (xy 140.331174 -214.207369)
			(xy 140.265269 -214.08113) (xy 140.206611 -213.951365) (xy 140.155389 -213.81849) (xy 140.111767 -213.682929)
			(xy 140.075883 -213.545117) (xy 140.047854 -213.405496) (xy 140.027769 -213.264513) (xy 140.015692 -213.12262)
			(xy 140.011662 -212.98027) (xy 131.771898 -212.98027) (xy 131.771898 -221.579186) (xy 131.772268 -221.58722)
			(xy 131.777326 -221.602476) (xy 131.781804 -221.609158) (xy 131.796838 -221.630538) (xy 131.820676 -221.677047)
			(xy 131.836886 -221.726733) (xy 131.845063 -221.778352) (xy 131.845558 -221.804484) (xy 131.845093 -221.829922)
			(xy 131.837304 -221.880199) (xy 131.821909 -221.928691) (xy 131.799271 -221.974253) (xy 131.769922 -222.015811)
			(xy 131.734556 -222.052385) (xy 131.694006 -222.083112) (xy 131.671822 -222.095568) (xy 131.65963 -222.102172)
			(xy 131.645152 -222.126048) (xy 131.645152 -223.102932) (xy 131.65963 -223.126808) (xy 131.671822 -223.133412)
			(xy 131.693993 -223.145894) (xy 131.734551 -223.176611) (xy 131.769926 -223.213178) (xy 131.799283 -223.254731)
			(xy 131.82193 -223.30029) (xy 131.837331 -223.34878) (xy 131.845124 -223.399057) (xy 131.845558 -223.424496)
			(xy 131.845075 -223.450484) (xy 131.836944 -223.50182) (xy 131.820882 -223.551252) (xy 131.797283 -223.597562)
			(xy 131.76673 -223.63961) (xy 131.729975 -223.67636) (xy 131.687923 -223.706907) (xy 131.641609 -223.730499)
			(xy 131.592175 -223.746555) (xy 131.540838 -223.754679) (xy 131.51485 -223.755204) (xy 131.503166 -223.75495)
			(xy 131.488942 -223.754442) (xy 131.464558 -223.767904) (xy 131.318 -224.020634) (xy 131.318508 -224.04832)
			(xy 131.325874 -224.060512) (xy 131.337608 -224.080199) (xy 131.356127 -224.12212) (xy 131.368679 -224.166198)
			(xy 131.375022 -224.211587) (xy 131.375404 -224.234502) (xy 131.374921 -224.260491) (xy 131.366789 -224.311829)
			(xy 131.350727 -224.361263) (xy 131.327129 -224.407576) (xy 131.296577 -224.449627) (xy 131.259822 -224.48638)
			(xy 131.217771 -224.516932) (xy 131.171458 -224.540529) (xy 131.122023 -224.556591) (xy 131.070685 -224.564721)
			(xy 131.044696 -224.56521) (xy 131.033266 -224.564956) (xy 131.019042 -224.564448) (xy 130.994658 -224.57791)
			(xy 130.8481 -224.830386) (xy 130.848608 -224.858326) (xy 130.855974 -224.870518) (xy 130.867707 -224.890205)
			(xy 130.886226 -224.932127) (xy 130.898777 -224.976204) (xy 130.905119 -225.021593) (xy 130.905504 -225.044508)
			(xy 130.904994 -225.070495) (xy 130.896862 -225.121828) (xy 130.880801 -225.171257) (xy 130.857204 -225.217565)
			(xy 130.826654 -225.259612) (xy 130.789903 -225.296362) (xy 130.747855 -225.32691) (xy 130.701546 -225.350505)
			(xy 130.652116 -225.366565) (xy 130.600783 -225.374695) (xy 130.574796 -225.375216) (xy 130.563112 -225.374962)
			(xy 130.549142 -225.374454) (xy 130.524504 -225.387916) (xy 130.377946 -225.640646) (xy 130.378454 -225.668586)
			(xy 130.38582 -225.680524) (xy 130.397552 -225.700211) (xy 130.416067 -225.742134) (xy 130.428615 -225.786211)
			(xy 130.434956 -225.8316) (xy 130.43535 -225.854514) (xy 130.434839 -225.880502) (xy 130.426707 -225.931837)
			(xy 130.410646 -225.981268) (xy 130.38705 -226.027579) (xy 130.356501 -226.069629) (xy 130.31975 -226.106382)
			(xy 130.277703 -226.136935) (xy 130.231394 -226.160535) (xy 130.181964 -226.176601) (xy 130.13063 -226.184737)
			(xy 130.104642 -226.185222) (xy 130.093212 -226.184968) (xy 130.078988 -226.18446) (xy 130.054604 -226.197922)
			(xy 129.908046 -226.450652) (xy 129.908554 -226.478338) (xy 129.91592 -226.49053) (xy 129.927651 -226.510218)
			(xy 129.946166 -226.55214) (xy 129.958713 -226.596218) (xy 129.965053 -226.641606) (xy 129.96545 -226.66452)
			(xy 129.964939 -226.690507) (xy 129.956806 -226.741842) (xy 129.940744 -226.791272) (xy 129.917148 -226.837582)
			(xy 129.886598 -226.879631) (xy 129.849848 -226.916384) (xy 129.807801 -226.946936) (xy 129.761493 -226.970536)
			(xy 129.712063 -226.986601) (xy 129.660729 -226.994737) (xy 129.634742 -226.995228) (xy 129.623312 -226.994974)
			(xy 129.609088 -226.994466) (xy 129.584704 -227.007928) (xy 129.438146 -227.260404) (xy 129.438654 -227.288344)
			(xy 129.44602 -227.300536) (xy 129.457751 -227.320224) (xy 129.476265 -227.362146) (xy 129.488811 -227.406224)
			(xy 129.49515 -227.451612) (xy 129.49555 -227.474526) (xy 129.495039 -227.500513) (xy 129.486905 -227.551847)
			(xy 129.470842 -227.601277) (xy 129.447246 -227.647586) (xy 129.416696 -227.689634) (xy 129.379946 -227.726386)
			(xy 129.337899 -227.756937) (xy 129.291591 -227.780536) (xy 129.242162 -227.796601) (xy 129.190829 -227.804737)
			(xy 129.164842 -227.805234) (xy 129.153158 -227.80498) (xy 129.138934 -227.804472) (xy 129.11455 -227.817934)
			(xy 128.967992 -228.070664) (xy 128.9685 -228.09835) (xy 128.975866 -228.110542) (xy 128.987598 -228.130229)
			(xy 129.006114 -228.172151) (xy 129.018662 -228.216229) (xy 129.025002 -228.261618) (xy 129.025396 -228.284532)
			(xy 129.024884 -228.310517) (xy 129.016749 -228.361847) (xy 129.000685 -228.411273) (xy 128.977088 -228.457577)
			(xy 128.946537 -228.49962) (xy 128.909786 -228.536366) (xy 128.867739 -228.566911) (xy 128.821432 -228.590502)
			(xy 128.772004 -228.60656) (xy 128.720673 -228.614688) (xy 128.694688 -228.61524) (xy 128.668889 -228.614743)
			(xy 128.617919 -228.606724) (xy 128.568814 -228.590882) (xy 128.522767 -228.567603) (xy 128.480897 -228.537451)
			(xy 128.44422 -228.501159) (xy 128.413628 -228.459609) (xy 128.401318 -228.436932) (xy 128.394714 -228.424232)
			(xy 128.370584 -228.4095) (xy 128.078738 -228.4095) (xy 128.054608 -228.424232) (xy 128.048004 -228.436932)
			(xy 128.035686 -228.459606) (xy 128.0051 -228.501163) (xy 127.968427 -228.537461) (xy 127.926559 -228.567619)
			(xy 127.880512 -228.590902) (xy 127.831405 -228.606746) (xy 127.780433 -228.614766) (xy 127.728835 -228.614766)
			(xy 127.677863 -228.606746) (xy 127.628756 -228.590902) (xy 127.582709 -228.567619) (xy 127.540841 -228.537461)
			(xy 127.504168 -228.501163) (xy 127.473582 -228.459606) (xy 127.461264 -228.436932) (xy 127.45466 -228.424232)
			(xy 127.43053 -228.4095) (xy 127.138938 -228.4095) (xy 127.114808 -228.424232) (xy 127.108204 -228.436932)
			(xy 127.095885 -228.459604) (xy 127.065298 -228.501156) (xy 127.028624 -228.537448) (xy 126.986755 -228.567599)
			(xy 126.940708 -228.590875) (xy 126.891602 -228.60671) (xy 126.840632 -228.61472) (xy 126.814834 -228.61524)
			(xy 126.80315 -228.614986) (xy 126.78918 -228.614478) (xy 126.764542 -228.62794) (xy 126.617984 -228.88067)
			(xy 126.618492 -228.90861) (xy 126.625858 -228.920548) (xy 126.63759 -228.940235) (xy 126.656106 -228.982157)
			(xy 126.668653 -229.026235) (xy 126.674992 -229.071624) (xy 126.675388 -229.094538) (xy 126.675015 -229.117153)
			(xy 126.668842 -229.161961) (xy 126.656615 -229.205508) (xy 126.638564 -229.246981) (xy 126.627128 -229.266496)
			(xy 126.619762 -229.278688) (xy 126.619508 -229.30612) (xy 126.766828 -229.560628) (xy 126.791466 -229.57409)
			(xy 126.805436 -229.573836) (xy 126.814834 -229.573582) (xy 126.84082 -229.574094) (xy 126.892152 -229.582229)
			(xy 126.94158 -229.598294) (xy 126.987886 -229.621892) (xy 127.029931 -229.652443) (xy 127.066679 -229.689195)
			(xy 127.097226 -229.731243) (xy 127.120819 -229.777552) (xy 127.136879 -229.826981) (xy 127.145009 -229.878314)
			(xy 127.145009 -229.930286) (xy 127.136879 -229.981619) (xy 127.120819 -230.031048) (xy 127.097226 -230.077357)
			(xy 127.066679 -230.119405) (xy 127.029931 -230.156157) (xy 126.987886 -230.186708) (xy 126.94158 -230.210306)
			(xy 126.892152 -230.226371) (xy 126.84082 -230.234506) (xy 126.814834 -230.234998) (xy 126.803404 -230.234744)
			(xy 126.78918 -230.234236) (xy 126.764796 -230.247698) (xy 126.60376 -230.52532) (xy 126.603506 -230.552244)
			(xy 126.610364 -230.564182) (xy 126.622819 -230.587266) (xy 126.64049 -230.636649) (xy 126.649453 -230.688326)
			(xy 126.649988 -230.71455) (xy 126.649446 -230.740432) (xy 126.640722 -230.791454) (xy 126.623516 -230.840274)
			(xy 126.61138 -230.86314) (xy 126.604776 -230.874824) (xy 126.60503 -230.901494) (xy 126.766828 -231.18064)
			(xy 126.791466 -231.194102) (xy 126.805436 -231.193848) (xy 126.814834 -231.193594) (xy 126.840819 -231.194106)
			(xy 126.892149 -231.202241) (xy 126.941575 -231.218305) (xy 126.98788 -231.241902) (xy 127.029923 -231.272452)
			(xy 127.06667 -231.309203) (xy 127.097216 -231.351249) (xy 127.120808 -231.397556) (xy 127.136867 -231.446984)
			(xy 127.144997 -231.498315) (xy 127.144997 -231.550285) (xy 127.136867 -231.601616) (xy 127.120808 -231.651044)
			(xy 127.097216 -231.697351) (xy 127.06667 -231.739397) (xy 127.029923 -231.776148) (xy 126.98788 -231.806698)
			(xy 126.941575 -231.830295) (xy 126.892149 -231.846359) (xy 126.840819 -231.854494) (xy 126.814834 -231.85501)
			(xy 126.803404 -231.854756) (xy 126.78918 -231.854248) (xy 126.764796 -231.86771) (xy 126.618238 -232.12044)
			(xy 126.618492 -232.14838) (xy 126.626112 -232.160572) (xy 126.637786 -232.180244) (xy 126.656201 -232.222118)
			(xy 126.668676 -232.266128) (xy 126.674973 -232.311436) (xy 126.675388 -232.334308) (xy 126.675035 -232.356956)
			(xy 126.668885 -232.401833) (xy 126.65666 -232.445448) (xy 126.63859 -232.486983) (xy 126.627128 -232.50652)
			(xy 126.619762 -232.518458) (xy 126.619254 -232.546144) (xy 126.767082 -232.800652) (xy 126.791466 -232.814114)
			(xy 126.805436 -232.81386) (xy 126.814834 -232.813606) (xy 126.840819 -232.814118) (xy 126.892149 -232.822253)
			(xy 126.941574 -232.838317) (xy 126.987877 -232.861915) (xy 127.02992 -232.892466) (xy 127.066666 -232.929217)
			(xy 127.09721 -232.971264) (xy 127.120801 -233.017571) (xy 127.136858 -233.066998) (xy 127.144986 -233.118329)
			(xy 127.145542 -233.144314) (xy 127.145167 -233.167002) (xy 127.138966 -233.211953) (xy 127.126681 -233.255635)
			(xy 127.108544 -233.297228) (xy 127.097028 -233.31678) (xy 127.089916 -233.328718) (xy 127.089408 -233.356658)
			(xy 127.236728 -233.610658) (xy 127.261112 -233.62412) (xy 127.275336 -233.623866) (xy 127.284734 -233.623612)
			(xy 127.310718 -233.624124) (xy 127.362045 -233.632258) (xy 127.411468 -233.648321) (xy 127.45777 -233.671918)
			(xy 127.499811 -233.702466) (xy 127.536556 -233.739215) (xy 127.5671 -233.781259) (xy 127.590692 -233.827563)
			(xy 127.60675 -233.876988) (xy 127.614879 -233.928316) (xy 127.614879 -233.980284) (xy 127.60675 -234.031612)
			(xy 127.590692 -234.081037) (xy 127.5671 -234.127341) (xy 127.536556 -234.169385) (xy 127.499811 -234.206134)
			(xy 127.45777 -234.236682) (xy 127.411468 -234.260279) (xy 127.362045 -234.276342) (xy 127.310718 -234.284476)
			(xy 127.284734 -234.285028) (xy 127.273304 -234.284774) (xy 127.25908 -234.284266) (xy 127.234696 -234.297728)
			(xy 127.088138 -234.550204) (xy 127.088646 -234.578144) (xy 127.096012 -234.590336) (xy 127.107743 -234.610024)
			(xy 127.126257 -234.651946) (xy 127.138804 -234.696024) (xy 127.145143 -234.741412) (xy 127.145542 -234.764326)
			(xy 127.145031 -234.790313) (xy 127.136897 -234.841646) (xy 127.120834 -234.891075) (xy 127.097237 -234.937384)
			(xy 127.066688 -234.979431) (xy 127.029937 -235.016183) (xy 126.987891 -235.046733) (xy 126.941583 -235.070331)
			(xy 126.892154 -235.086395) (xy 126.840821 -235.09453) (xy 126.814834 -235.095034) (xy 126.803404 -235.09478)
			(xy 126.78918 -235.094272) (xy 126.764796 -235.107734) (xy 126.618238 -235.360464) (xy 126.618492 -235.388404)
			(xy 126.626112 -235.400596) (xy 126.637791 -235.420267) (xy 126.656216 -235.462139) (xy 126.6687 -235.506149)
			(xy 126.675008 -235.551459) (xy 126.675388 -235.574332) (xy 126.675033 -235.59698) (xy 126.66888 -235.641855)
			(xy 126.656653 -235.685468) (xy 126.63858 -235.727002) (xy 126.627128 -235.746544) (xy 126.619762 -235.758482)
			(xy 126.619254 -235.786168) (xy 126.766828 -236.040676) (xy 126.791466 -236.054138) (xy 126.805436 -236.053884)
			(xy 126.814834 -236.05363) (xy 126.840816 -236.054142) (xy 126.892141 -236.062276) (xy 126.941561 -236.078338)
			(xy 126.98786 -236.101933) (xy 127.029899 -236.13248) (xy 127.066642 -236.169227) (xy 127.097184 -236.211269)
			(xy 127.120775 -236.25757) (xy 127.136832 -236.306992) (xy 127.14496 -236.358318) (xy 127.14496 -236.410282)
			(xy 127.136832 -236.461608) (xy 127.120775 -236.51103) (xy 127.097184 -236.557331) (xy 127.066642 -236.599373)
			(xy 127.029899 -236.63612) (xy 126.98786 -236.666667) (xy 126.941561 -236.690262) (xy 126.892141 -236.706324)
			(xy 126.840816 -236.714458) (xy 126.814834 -236.715046) (xy 126.80315 -236.714792) (xy 126.78918 -236.714284)
			(xy 126.764796 -236.727746) (xy 126.617984 -236.980476) (xy 126.618492 -237.008416) (xy 126.625858 -237.020354)
			(xy 126.63759 -237.040041) (xy 126.656105 -237.081963) (xy 126.668651 -237.126041) (xy 126.674989 -237.17143)
			(xy 126.675388 -237.194344) (xy 126.674875 -237.220328) (xy 126.666739 -237.271656) (xy 126.650674 -237.32108)
			(xy 126.627075 -237.367382) (xy 126.596524 -237.409422) (xy 126.559773 -237.446166) (xy 126.517727 -237.476709)
			(xy 126.471421 -237.500298) (xy 126.421994 -237.516354) (xy 126.370664 -237.52448) (xy 126.34468 -237.525052)
			(xy 126.33325 -237.524798) (xy 126.319026 -237.52429) (xy 126.294642 -237.537752) (xy 126.148084 -237.790482)
			(xy 126.148592 -237.818422) (xy 126.155958 -237.83036) (xy 126.16769 -237.850047) (xy 126.186204 -237.89197)
			(xy 126.198749 -237.936048) (xy 126.205086 -237.981436) (xy 126.205488 -238.00435) (xy 126.205488 -238.012986)
			(xy 126.20498 -238.026956) (xy 126.218696 -238.05134) (xy 127.07112 -238.540798) (xy 127.09906 -238.54029)
			(xy 127.110998 -238.532924) (xy 127.130669 -238.521245) (xy 127.172541 -238.502818) (xy 127.216551 -238.490332)
			(xy 127.261861 -238.484024) (xy 127.284734 -238.483648) (xy 127.310723 -238.48416) (xy 127.36206 -238.492296)
			(xy 127.411493 -238.508362) (xy 127.457804 -238.531963) (xy 127.499853 -238.562517) (xy 127.536605 -238.599273)
			(xy 127.567155 -238.641325) (xy 127.590751 -238.687639) (xy 127.606812 -238.737073) (xy 127.614942 -238.788411)
			(xy 127.614942 -238.840389) (xy 127.606812 -238.891727) (xy 127.590751 -238.941161) (xy 127.567155 -238.987475)
			(xy 127.536605 -239.029527) (xy 127.499853 -239.066283) (xy 127.457804 -239.096837) (xy 127.411493 -239.120438)
			(xy 127.36206 -239.136504) (xy 127.310723 -239.14464) (xy 127.284734 -239.145064) (xy 127.273304 -239.14481)
			(xy 127.25908 -239.144302) (xy 127.234696 -239.157764) (xy 127.088138 -239.410494) (xy 127.088646 -239.43818)
			(xy 127.096012 -239.450372) (xy 127.107741 -239.47006) (xy 127.12625 -239.511983) (xy 127.138793 -239.556061)
			(xy 127.145127 -239.601448) (xy 127.145542 -239.624362) (xy 127.145062 -239.650354) (xy 127.136935 -239.701699)
			(xy 127.120877 -239.751141) (xy 127.097282 -239.797462) (xy 127.066731 -239.839522) (xy 127.029976 -239.876284)
			(xy 126.987924 -239.906844) (xy 126.941608 -239.930449) (xy 126.892169 -239.946519) (xy 126.840826 -239.954656)
			(xy 126.814834 -239.95507) (xy 126.803404 -239.954816) (xy 126.78918 -239.954308) (xy 126.764796 -239.96777)
			(xy 126.618238 -240.2205) (xy 126.618492 -240.24844) (xy 126.626112 -240.260632) (xy 126.637788 -240.280304)
			(xy 126.656208 -240.322176) (xy 126.668688 -240.366186) (xy 126.674991 -240.411495) (xy 126.675388 -240.434368)
			(xy 126.675038 -240.457017) (xy 126.668893 -240.501896) (xy 126.656672 -240.545513) (xy 126.638606 -240.587052)
			(xy 126.627128 -240.60658) (xy 126.619762 -240.618518) (xy 126.619254 -240.646204) (xy 126.767082 -240.900712)
			(xy 126.791466 -240.914174) (xy 126.805436 -240.91392) (xy 126.814834 -240.913666) (xy 126.84082 -240.914178)
			(xy 126.892152 -240.922313) (xy 126.94158 -240.938376) (xy 126.987886 -240.961974) (xy 127.029932 -240.992523)
			(xy 127.066682 -241.029274) (xy 127.097231 -241.07132) (xy 127.120827 -241.117628) (xy 127.136889 -241.167056)
			(xy 127.145023 -241.218388) (xy 127.145542 -241.244374) (xy 127.145163 -241.267061) (xy 127.138954 -241.312008)
			(xy 127.126663 -241.355686) (xy 127.10852 -241.397275) (xy 127.097028 -241.41684) (xy 127.089916 -241.428778)
			(xy 127.089408 -241.456718) (xy 127.236728 -241.710718) (xy 127.261112 -241.72418) (xy 127.275336 -241.723926)
			(xy 127.284734 -241.723672) (xy 127.310721 -241.724184) (xy 127.362054 -241.732319) (xy 127.411483 -241.748384)
			(xy 127.457791 -241.771983) (xy 127.499837 -241.802536) (xy 127.536586 -241.839289) (xy 127.567134 -241.881338)
			(xy 127.590729 -241.927648) (xy 127.606789 -241.977079) (xy 127.614919 -242.028413) (xy 127.614919 -242.080387)
			(xy 127.606789 -242.131721) (xy 127.590729 -242.181152) (xy 127.567134 -242.227462) (xy 127.536586 -242.269511)
			(xy 127.499837 -242.306264) (xy 127.457791 -242.336817) (xy 127.411483 -242.360416) (xy 127.362054 -242.376481)
			(xy 127.310721 -242.384616) (xy 127.284734 -242.385088) (xy 127.273304 -242.384834) (xy 127.25908 -242.384326)
			(xy 127.234696 -242.397788) (xy 127.088138 -242.650264) (xy 127.088646 -242.678204) (xy 127.096012 -242.690396)
			(xy 127.107746 -242.710083) (xy 127.126265 -242.752005) (xy 127.138817 -242.796082) (xy 127.145162 -242.841471)
			(xy 127.145542 -242.864386) (xy 127.145034 -242.890375) (xy 127.136905 -242.941713) (xy 127.120846 -242.991148)
			(xy 127.097251 -243.037462) (xy 127.066702 -243.079514) (xy 127.029951 -243.116271) (xy 126.987903 -243.146826)
			(xy 126.941592 -243.170427) (xy 126.89216 -243.186494) (xy 126.840823 -243.19463) (xy 126.814834 -243.195094)
			(xy 126.803404 -243.19484) (xy 126.78918 -243.194332) (xy 126.764796 -243.207794) (xy 126.618238 -243.460524)
			(xy 126.618492 -243.488464) (xy 126.626112 -243.500656) (xy 126.637787 -243.520328) (xy 126.656204 -243.562201)
			(xy 126.668681 -243.606211) (xy 126.67498 -243.65152) (xy 126.675388 -243.674392) (xy 126.675036 -243.697041)
			(xy 126.668888 -243.741918) (xy 126.656665 -243.785534) (xy 126.638596 -243.827071) (xy 126.627128 -243.846604)
			(xy 126.619762 -243.858542) (xy 126.619254 -243.886228) (xy 126.767082 -244.140736) (xy 126.791466 -244.154198)
			(xy 126.805436 -244.153944) (xy 126.814834 -244.15369) (xy 126.840819 -244.154202) (xy 126.89215 -244.162337)
			(xy 126.941576 -244.178401) (xy 126.987881 -244.201998) (xy 127.029925 -244.232549) (xy 127.066672 -244.2693)
			(xy 127.097218 -244.311346) (xy 127.120811 -244.357653) (xy 127.136871 -244.407081) (xy 127.145 -244.458412)
			(xy 127.145542 -244.484398) (xy 127.145168 -244.507086) (xy 127.138969 -244.552038) (xy 127.126686 -244.595721)
			(xy 127.10855 -244.637316) (xy 127.097028 -244.656864) (xy 127.089916 -244.668802) (xy 127.089408 -244.696742)
			(xy 127.236728 -244.950742) (xy 127.261112 -244.964204) (xy 127.275336 -244.96395) (xy 127.284734 -244.963696)
			(xy 127.310719 -244.964208) (xy 127.362049 -244.972343) (xy 127.411474 -244.988407) (xy 127.457778 -245.012004)
			(xy 127.499822 -245.042554) (xy 127.536568 -245.079304) (xy 127.567114 -245.121351) (xy 127.590706 -245.167657)
			(xy 127.606765 -245.217084) (xy 127.614895 -245.268415) (xy 127.614895 -245.320385) (xy 127.606765 -245.371716)
			(xy 127.590706 -245.421143) (xy 127.567114 -245.467449) (xy 127.536568 -245.509496) (xy 127.499822 -245.546246)
			(xy 127.457778 -245.576796) (xy 127.411474 -245.600393) (xy 127.362049 -245.616457) (xy 127.310719 -245.624592)
			(xy 127.284734 -245.625112) (xy 127.273304 -245.624858) (xy 127.25908 -245.62435) (xy 127.234696 -245.637812)
			(xy 127.088138 -245.890288) (xy 127.088646 -245.918228) (xy 127.096012 -245.93042) (xy 127.107744 -245.950107)
			(xy 127.12626 -245.992029) (xy 127.138809 -246.036107) (xy 127.145151 -246.081495) (xy 127.145542 -246.10441)
			(xy 127.145032 -246.130398) (xy 127.1369 -246.181733) (xy 127.120839 -246.231164) (xy 127.097243 -246.277475)
			(xy 127.066694 -246.319524) (xy 127.029943 -246.356278) (xy 126.987895 -246.38683) (xy 126.941587 -246.41043)
			(xy 126.892156 -246.426495) (xy 126.840822 -246.43463) (xy 126.814834 -246.435118) (xy 126.803404 -246.434864)
			(xy 126.78918 -246.434356) (xy 126.764796 -246.447818) (xy 126.618238 -246.700548) (xy 126.618492 -246.728488)
			(xy 126.626112 -246.74068) (xy 126.637792 -246.760351) (xy 126.656219 -246.802223) (xy 126.668706 -246.846233)
			(xy 126.675015 -246.891543) (xy 126.675388 -246.914416) (xy 126.675035 -246.937064) (xy 126.668883 -246.98194)
			(xy 126.656658 -247.025554) (xy 126.638587 -247.067089) (xy 126.627128 -247.086628) (xy 126.619762 -247.098566)
			(xy 126.619254 -247.126252) (xy 126.767082 -247.38076) (xy 126.791466 -247.394222) (xy 126.805436 -247.393968)
			(xy 126.814834 -247.393714) (xy 126.840819 -247.394226) (xy 126.892148 -247.402361) (xy 126.941572 -247.418425)
			(xy 126.987876 -247.442023) (xy 127.029917 -247.472574) (xy 127.066662 -247.509325) (xy 127.097206 -247.551372)
			(xy 127.120796 -247.597679) (xy 127.136852 -247.647107) (xy 127.144978 -247.698437) (xy 127.145542 -247.724422)
			(xy 127.145167 -247.74711) (xy 127.138964 -247.79206) (xy 127.126679 -247.835741) (xy 127.108541 -247.877335)
			(xy 127.097028 -247.896888) (xy 127.089916 -247.908826) (xy 127.089408 -247.936766) (xy 127.236728 -248.190766)
			(xy 127.261112 -248.204228) (xy 127.275336 -248.203974) (xy 127.284734 -248.20372) (xy 127.310717 -248.204232)
			(xy 127.362043 -248.212366) (xy 127.411465 -248.228429) (xy 127.457766 -248.252024) (xy 127.499806 -248.282572)
			(xy 127.53655 -248.31932) (xy 127.567093 -248.361363) (xy 127.590684 -248.407666) (xy 127.606742 -248.45709)
			(xy 127.614871 -248.508417) (xy 127.614871 -248.560383) (xy 127.606742 -248.61171) (xy 127.590684 -248.661134)
			(xy 127.567093 -248.707437) (xy 127.53655 -248.74948) (xy 127.499806 -248.786228) (xy 127.457766 -248.816776)
			(xy 127.411465 -248.840371) (xy 127.362043 -248.856434) (xy 127.310717 -248.864568) (xy 127.284734 -248.865136)
			(xy 127.273304 -248.864882) (xy 127.25908 -248.864374) (xy 127.234696 -248.877836) (xy 127.088138 -249.130312)
			(xy 127.088646 -249.158252) (xy 127.096012 -249.170444) (xy 127.107743 -249.190132) (xy 127.126256 -249.232054)
			(xy 127.138802 -249.276132) (xy 127.14514 -249.32152) (xy 127.145542 -249.344434) (xy 127.14503 -249.37042)
			(xy 127.136895 -249.421753) (xy 127.120832 -249.471181) (xy 127.097235 -249.517488) (xy 127.066685 -249.559535)
			(xy 127.029935 -249.596285) (xy 126.987888 -249.626835) (xy 126.941581 -249.650432) (xy 126.892153 -249.666495)
			(xy 126.84082 -249.67463) (xy 126.814834 -249.675142) (xy 126.803404 -249.674888) (xy 126.78918 -249.67438)
			(xy 126.764796 -249.687842) (xy 126.618238 -249.940572) (xy 126.618492 -249.968512) (xy 126.625858 -249.98045)
			(xy 126.63759 -250.000137) (xy 126.656105 -250.042059) (xy 126.668653 -250.086137) (xy 126.674991 -250.131526)
			(xy 126.675388 -250.15444) (xy 126.674875 -250.180425) (xy 126.66674 -250.231753) (xy 126.650675 -250.281177)
			(xy 126.627077 -250.327479) (xy 126.596526 -250.36952) (xy 126.559775 -250.406265) (xy 126.517728 -250.436808)
			(xy 126.471421 -250.460398) (xy 126.421995 -250.476454) (xy 126.370665 -250.48458) (xy 126.34468 -250.485148)
			(xy 126.321353 -250.484728) (xy 126.275165 -250.478141) (xy 126.230357 -250.465141) (xy 126.187815 -250.445987)
			(xy 126.167896 -250.43384) (xy 126.155704 -250.42622) (xy 126.128018 -250.425712) (xy 125.278134 -250.9139)
			(xy 125.264672 -250.93803) (xy 125.26518 -250.952508) (xy 125.265434 -250.964446) (xy 125.264921 -250.990432)
			(xy 125.256785 -251.041762) (xy 125.24072 -251.091188) (xy 125.217122 -251.137493) (xy 125.186572 -251.179537)
			(xy 125.149822 -251.216285) (xy 125.107776 -251.246833) (xy 125.06147 -251.270428) (xy 125.012043 -251.28649)
			(xy 124.960712 -251.294623) (xy 124.934726 -251.295154) (xy 124.923296 -251.2949) (xy 124.909072 -251.294392)
			(xy 124.884688 -251.307854) (xy 124.73813 -251.56033) (xy 124.738384 -251.58827) (xy 124.746004 -251.600462)
			(xy 124.757734 -251.62015) (xy 124.776245 -251.662073) (xy 124.788789 -251.70615) (xy 124.795125 -251.751538)
			(xy 124.795534 -251.774452) (xy 124.795024 -251.800439) (xy 124.786894 -251.851774) (xy 124.770833 -251.901204)
			(xy 124.747237 -251.947514) (xy 124.716687 -251.989562) (xy 124.679936 -252.026313) (xy 124.637888 -252.056863)
			(xy 124.591578 -252.080459) (xy 124.542148 -252.09652) (xy 124.490813 -252.10465) (xy 124.438839 -252.10465)
			(xy 124.387504 -252.09652) (xy 124.338074 -252.080459) (xy 124.291764 -252.056863) (xy 124.249716 -252.026313)
			(xy 124.212965 -251.989562) (xy 124.182415 -251.947514) (xy 124.158819 -251.901204) (xy 124.142758 -251.851774)
			(xy 124.134628 -251.800439) (xy 124.134118 -251.774452) (xy 124.134372 -251.759466) (xy 124.135134 -251.744988)
			(xy 124.121672 -251.72035) (xy 123.274328 -251.233686) (xy 123.246134 -251.234448) (xy 123.233942 -251.242322)
			(xy 123.213805 -251.254829) (xy 123.170711 -251.274575) (xy 123.125238 -251.287965) (xy 123.07832 -251.294723)
			(xy 123.054618 -251.295154) (xy 123.028629 -251.294646) (xy 122.977289 -251.286518) (xy 122.927853 -251.270459)
			(xy 122.881538 -251.246865) (xy 122.839484 -251.216316) (xy 122.802725 -251.179565) (xy 122.772169 -251.137517)
			(xy 122.748566 -251.091206) (xy 122.732497 -251.041773) (xy 122.724359 -250.990435) (xy 122.72391 -250.964446)
			(xy 122.724325 -250.940859) (xy 122.731023 -250.894162) (xy 122.744289 -250.848891) (xy 122.763853 -250.805965)
			(xy 122.776234 -250.785884) (xy 122.784108 -250.773692) (xy 122.78487 -250.745498) (xy 122.640852 -250.49734)
			(xy 122.61596 -250.483878) (xy 122.601482 -250.48464) (xy 122.584718 -250.485148) (xy 122.561392 -250.484724)
			(xy 122.515208 -250.478129) (xy 122.470404 -250.465122) (xy 122.427868 -250.445962) (xy 122.407934 -250.43384)
			(xy 122.395742 -250.42622) (xy 122.367802 -250.425712) (xy 121.518426 -250.913646) (xy 121.50471 -250.938284)
			(xy 121.505218 -250.952508) (xy 121.505472 -250.964446) (xy 121.504959 -250.99043) (xy 121.496822 -251.041757)
			(xy 121.480757 -251.091179) (xy 121.457158 -251.137479) (xy 121.426607 -251.179518) (xy 121.389856 -251.21626)
			(xy 121.347809 -251.246801) (xy 121.301503 -251.270388) (xy 121.252077 -251.286442) (xy 121.200748 -251.294565)
			(xy 121.174764 -251.295154) (xy 121.163334 -251.2949) (xy 121.14911 -251.294392) (xy 121.124726 -251.307854)
			(xy 120.977914 -251.560584) (xy 120.978422 -251.588524) (xy 120.985788 -251.600462) (xy 120.997518 -251.62015)
			(xy 121.01603 -251.662072) (xy 121.028575 -251.70615) (xy 121.034911 -251.751538) (xy 121.035318 -251.774452)
			(xy 121.034808 -251.800439) (xy 121.026678 -251.851774) (xy 121.010617 -251.901204) (xy 120.987021 -251.947514)
			(xy 120.956471 -251.989562) (xy 120.91972 -252.026313) (xy 120.877672 -252.056863) (xy 120.831362 -252.080459)
			(xy 120.781932 -252.09652) (xy 120.730597 -252.10465) (xy 120.678623 -252.10465) (xy 120.627288 -252.09652)
			(xy 120.577858 -252.080459) (xy 120.531548 -252.056863) (xy 120.4895 -252.026313) (xy 120.452749 -251.989562)
			(xy 120.422199 -251.947514) (xy 120.398603 -251.901204) (xy 120.382542 -251.851774) (xy 120.374412 -251.800439)
			(xy 120.373902 -251.774452) (xy 120.374156 -251.759212) (xy 120.374918 -251.744988) (xy 120.361456 -251.720096)
			(xy 119.514366 -251.233686) (xy 119.486172 -251.234448) (xy 119.47398 -251.242322) (xy 119.453844 -251.254831)
			(xy 119.41075 -251.274583) (xy 119.365278 -251.287977) (xy 119.318358 -251.294741) (xy 119.294656 -251.295154)
			(xy 119.26867 -251.294641) (xy 119.217338 -251.286505) (xy 119.16791 -251.270441) (xy 119.121604 -251.246844)
			(xy 119.079558 -251.216294) (xy 119.042807 -251.179544) (xy 119.012257 -251.137498) (xy 118.98866 -251.091192)
			(xy 118.972595 -251.041764) (xy 118.964459 -250.990432) (xy 118.963948 -250.964446) (xy 118.964363 -250.940858)
			(xy 118.97106 -250.894161) (xy 118.984323 -250.848889) (xy 119.003885 -250.805961) (xy 119.016272 -250.785884)
			(xy 119.024146 -250.773692) (xy 119.024654 -250.745498) (xy 118.880636 -250.49734) (xy 118.855998 -250.483878)
			(xy 118.84152 -250.48464) (xy 118.824756 -250.485148) (xy 118.801429 -250.484726) (xy 118.755243 -250.478136)
			(xy 118.710437 -250.465134) (xy 118.667897 -250.445977) (xy 118.647972 -250.43384) (xy 118.636034 -250.42622)
			(xy 118.607586 -250.425712) (xy 117.758464 -250.913646) (xy 117.744748 -250.938284) (xy 117.745256 -250.952254)
			(xy 117.74551 -250.964446) (xy 117.744997 -250.990431) (xy 117.736861 -251.04176) (xy 117.720796 -251.091184)
			(xy 117.697197 -251.137488) (xy 117.666647 -251.17953) (xy 117.629896 -251.216276) (xy 117.58785 -251.246821)
			(xy 117.541544 -251.270413) (xy 117.492117 -251.286471) (xy 117.440787 -251.2946) (xy 117.414802 -251.295154)
			(xy 117.403372 -251.2949) (xy 117.389148 -251.294392) (xy 117.364764 -251.307854) (xy 117.217952 -251.560584)
			(xy 117.21846 -251.588524) (xy 117.225826 -251.600462) (xy 117.237555 -251.62015) (xy 117.256065 -251.662073)
			(xy 117.268608 -251.706151) (xy 117.274944 -251.751538) (xy 117.275356 -251.774452) (xy 117.274846 -251.800439)
			(xy 117.266716 -251.851774) (xy 117.250655 -251.901204) (xy 117.227059 -251.947514) (xy 117.196509 -251.989562)
			(xy 117.159758 -252.026313) (xy 117.11771 -252.056863) (xy 117.0714 -252.080459) (xy 117.02197 -252.09652)
			(xy 116.970635 -252.10465) (xy 116.918661 -252.10465) (xy 116.867326 -252.09652) (xy 116.817896 -252.080459)
			(xy 116.771586 -252.056863) (xy 116.729538 -252.026313) (xy 116.692787 -251.989562) (xy 116.662237 -251.947514)
			(xy 116.638641 -251.901204) (xy 116.62258 -251.851774) (xy 116.61445 -251.800439) (xy 116.61394 -251.774452)
			(xy 116.614194 -251.759212) (xy 116.614956 -251.744988) (xy 116.601494 -251.720096) (xy 115.754404 -251.233686)
			(xy 115.72621 -251.234448) (xy 115.714018 -251.242322) (xy 115.693882 -251.254834) (xy 115.650789 -251.27459)
			(xy 115.605317 -251.28799) (xy 115.558397 -251.294759) (xy 115.534694 -251.295154) (xy 115.508706 -251.294644)
			(xy 115.457369 -251.286513) (xy 115.407937 -251.270452) (xy 115.361625 -251.246857) (xy 115.319574 -251.216308)
			(xy 115.282818 -251.179557) (xy 115.252264 -251.137509) (xy 115.228663 -251.0912) (xy 115.212596 -251.04177)
			(xy 115.204459 -250.990434) (xy 115.203986 -250.964446) (xy 115.204401 -250.940859) (xy 115.211098 -250.894162)
			(xy 115.224363 -250.84889) (xy 115.243926 -250.805963) (xy 115.25631 -250.785884) (xy 115.264184 -250.773692)
			(xy 115.264692 -250.745498) (xy 115.120674 -250.49734) (xy 115.096036 -250.483878) (xy 115.081558 -250.48464)
			(xy 115.064794 -250.485148) (xy 115.041469 -250.484722) (xy 114.995286 -250.478124) (xy 114.950484 -250.465115)
			(xy 114.907949 -250.445952) (xy 114.88801 -250.43384) (xy 114.876072 -250.42622) (xy 114.847624 -250.425712)
			(xy 113.998248 -250.9139) (xy 113.984786 -250.93803) (xy 113.985294 -250.952508) (xy 113.985548 -250.964446)
			(xy 113.985035 -250.990432) (xy 113.976899 -251.041763) (xy 113.960834 -251.09119) (xy 113.937237 -251.137496)
			(xy 113.906687 -251.179541) (xy 113.869937 -251.216291) (xy 113.827891 -251.24684) (xy 113.781585 -251.270437)
			(xy 113.732157 -251.2865) (xy 113.680826 -251.294636) (xy 113.65484 -251.295154) (xy 113.629052 -251.294663)
			(xy 113.578101 -251.286664) (xy 113.529009 -251.270853) (xy 113.482966 -251.247614) (xy 113.441089 -251.217509)
			(xy 113.404391 -251.181269) (xy 113.373764 -251.139773) (xy 113.36147 -251.1171) (xy 113.354866 -251.1044)
			(xy 113.330736 -251.089668) (xy 110.817406 -251.089668) (xy 110.810759 -251.089489) (xy 110.797891 -251.086157)
			(xy 110.792006 -251.083064) (xy 109.648244 -250.425712) (xy 109.619796 -250.42622) (xy 109.607858 -250.43384)
			(xy 109.58794 -250.445994) (xy 109.545409 -250.465183) (xy 109.500599 -250.478191) (xy 109.454404 -250.484758)
			(xy 109.431074 -250.485148) (xy 109.41431 -250.48464) (xy 109.399832 -250.483878) (xy 109.375194 -250.49734)
			(xy 109.231176 -250.745498) (xy 109.231684 -250.773692) (xy 109.239558 -250.785884) (xy 109.251928 -250.805969)
			(xy 109.271477 -250.848899) (xy 109.284736 -250.894168) (xy 109.291437 -250.940861) (xy 109.291882 -250.964446)
			(xy 109.291369 -250.99043) (xy 109.283233 -251.041757) (xy 109.267167 -251.09118) (xy 109.243568 -251.137481)
			(xy 109.213017 -251.179521) (xy 109.176266 -251.216264) (xy 109.13422 -251.246806) (xy 109.087914 -251.270395)
			(xy 109.038487 -251.286449) (xy 108.987158 -251.294575) (xy 108.961174 -251.295154) (xy 108.937472 -251.294745)
			(xy 108.890555 -251.287974) (xy 108.845084 -251.274575) (xy 108.801993 -251.254821) (xy 108.78185 -251.242322)
			(xy 108.769658 -251.234448) (xy 108.741464 -251.233686) (xy 107.89412 -251.72035) (xy 107.880658 -251.744988)
			(xy 107.88142 -251.759466) (xy 107.881674 -251.774452) (xy 107.881164 -251.800439) (xy 107.873034 -251.851774)
			(xy 107.856973 -251.901204) (xy 107.833377 -251.947514) (xy 107.802827 -251.989562) (xy 107.766076 -252.026313)
			(xy 107.724028 -252.056863) (xy 107.677718 -252.080459) (xy 107.628288 -252.09652) (xy 107.576953 -252.10465)
			(xy 107.524979 -252.10465) (xy 107.473644 -252.09652) (xy 107.424214 -252.080459) (xy 107.377904 -252.056863)
			(xy 107.335856 -252.026313) (xy 107.299105 -251.989562) (xy 107.268555 -251.947514) (xy 107.244959 -251.901204)
			(xy 107.228898 -251.851774) (xy 107.220768 -251.800439) (xy 107.220258 -251.774452) (xy 107.220628 -251.751504)
			(xy 107.226939 -251.706046) (xy 107.239486 -251.6619) (xy 107.25803 -251.619918) (xy 107.269788 -251.600208)
			(xy 107.277408 -251.58827) (xy 107.277662 -251.56033) (xy 107.131104 -251.307854) (xy 107.10672 -251.294392)
			(xy 107.092496 -251.2949) (xy 107.081066 -251.295154) (xy 107.057364 -251.294745) (xy 107.010447 -251.287973)
			(xy 106.964978 -251.274572) (xy 106.921887 -251.254817) (xy 106.901742 -251.242322) (xy 106.88955 -251.234448)
			(xy 106.861356 -251.233686) (xy 106.014266 -251.720096) (xy 106.000804 -251.744988) (xy 106.001566 -251.759466)
			(xy 106.00182 -251.774452) (xy 106.00131 -251.800439) (xy 105.99318 -251.851774) (xy 105.977119 -251.901204)
			(xy 105.953523 -251.947514) (xy 105.922973 -251.989562) (xy 105.886222 -252.026313) (xy 105.844174 -252.056863)
			(xy 105.797864 -252.080459) (xy 105.748434 -252.09652) (xy 105.697099 -252.10465) (xy 105.645125 -252.10465)
			(xy 105.59379 -252.09652) (xy 105.54436 -252.080459) (xy 105.49805 -252.056863) (xy 105.456002 -252.026313)
			(xy 105.419251 -251.989562) (xy 105.388701 -251.947514) (xy 105.365105 -251.901204) (xy 105.349044 -251.851774)
			(xy 105.340914 -251.800439) (xy 105.340404 -251.774452) (xy 105.340792 -251.751536) (xy 105.347121 -251.706144)
			(xy 105.359665 -251.662063) (xy 105.378184 -251.620139) (xy 105.389934 -251.600462) (xy 105.3973 -251.588524)
			(xy 105.397808 -251.560584) (xy 105.250996 -251.307854) (xy 105.226612 -251.294392) (xy 105.212388 -251.2949)
			(xy 105.200958 -251.295154) (xy 105.177257 -251.294744) (xy 105.13034 -251.287971) (xy 105.084871 -251.27457)
			(xy 105.041781 -251.254814) (xy 105.021634 -251.242322) (xy 105.009442 -251.234448) (xy 104.981248 -251.233686)
			(xy 104.134158 -251.72035) (xy 104.120696 -251.744988) (xy 104.121458 -251.759466) (xy 104.121712 -251.774452)
			(xy 104.121202 -251.800439) (xy 104.113072 -251.851774) (xy 104.097011 -251.901204) (xy 104.073415 -251.947514)
			(xy 104.042865 -251.989562) (xy 104.006114 -252.026313) (xy 103.964066 -252.056863) (xy 103.917756 -252.080459)
			(xy 103.868326 -252.09652) (xy 103.816991 -252.10465) (xy 103.765017 -252.10465) (xy 103.713682 -252.09652)
			(xy 103.664252 -252.080459) (xy 103.617942 -252.056863) (xy 103.575894 -252.026313) (xy 103.539143 -251.989562)
			(xy 103.508593 -251.947514) (xy 103.484997 -251.901204) (xy 103.468936 -251.851774) (xy 103.460806 -251.800439)
			(xy 103.460296 -251.774452) (xy 103.460684 -251.751536) (xy 103.467013 -251.706144) (xy 103.479557 -251.662063)
			(xy 103.498075 -251.620139) (xy 103.509826 -251.600462) (xy 103.517446 -251.58827) (xy 103.5177 -251.56033)
			(xy 103.371142 -251.307854) (xy 103.346758 -251.294392) (xy 103.332534 -251.2949) (xy 103.321104 -251.295154)
			(xy 103.297371 -251.29476) (xy 103.250388 -251.288003) (xy 103.204853 -251.274601) (xy 103.161703 -251.254826)
			(xy 103.141526 -251.242322) (xy 103.129334 -251.234448) (xy 103.101394 -251.233686) (xy 102.254304 -251.720096)
			(xy 102.240842 -251.744988) (xy 102.241604 -251.759212) (xy 102.241858 -251.774452) (xy 102.241378 -251.800442)
			(xy 102.233253 -251.851784) (xy 102.217194 -251.901221) (xy 102.193598 -251.947538) (xy 102.163046 -251.989592)
			(xy 102.12629 -252.026347) (xy 102.084236 -252.056899) (xy 102.03792 -252.080495) (xy 101.988482 -252.096553)
			(xy 101.93714 -252.104679) (xy 101.91115 -252.10516) (xy 101.894132 -252.104652) (xy 101.879654 -252.10389)
			(xy 101.855016 -252.117352) (xy 101.710998 -252.365764) (xy 101.711506 -252.393704) (xy 101.71938 -252.405896)
			(xy 101.731755 -252.42598) (xy 101.751314 -252.468909) (xy 101.764584 -252.514177) (xy 101.771297 -252.560871)
			(xy 101.771704 -252.584458) (xy 101.771224 -252.610449) (xy 101.763098 -252.661793) (xy 101.747039 -252.711233)
			(xy 101.723444 -252.757551) (xy 101.692892 -252.799608) (xy 101.656137 -252.836368) (xy 101.614084 -252.866924)
			(xy 101.567768 -252.890525) (xy 101.51833 -252.906589) (xy 101.466987 -252.914721) (xy 101.440996 -252.915166)
			(xy 101.417294 -252.914759) (xy 101.370375 -252.907991) (xy 101.324903 -252.894594) (xy 101.281809 -252.874843)
			(xy 101.261672 -252.862334) (xy 101.24948 -252.85446) (xy 101.221286 -252.853698) (xy 100.374196 -253.340362)
			(xy 100.360734 -253.365) (xy 100.361496 -253.379478) (xy 100.36175 -253.394464) (xy 100.361496 -253.406148)
			(xy 100.360988 -253.420372) (xy 100.37445 -253.444756) (xy 101.224588 -253.932944) (xy 101.252528 -253.932436)
			(xy 101.264466 -253.924816) (xy 101.284369 -253.912719) (xy 101.326852 -253.893625) (xy 101.371593 -253.880681)
			(xy 101.417708 -253.874145) (xy 101.440996 -253.873762) (xy 101.466988 -253.874245) (xy 101.518332 -253.882376)
			(xy 101.567771 -253.89844) (xy 101.614089 -253.922039) (xy 101.656145 -253.952594) (xy 101.692903 -253.989352)
			(xy 101.723458 -254.031408) (xy 101.747059 -254.077725) (xy 101.763123 -254.127165) (xy 101.771255 -254.178508)
			(xy 101.771255 -254.230492) (xy 101.763123 -254.281835) (xy 101.747059 -254.331275) (xy 101.723458 -254.377592)
			(xy 101.692903 -254.419648) (xy 101.656145 -254.456406) (xy 101.614089 -254.486961) (xy 101.567771 -254.51056)
			(xy 101.518332 -254.526624) (xy 101.466988 -254.534755) (xy 101.440996 -254.535178) (xy 101.417294 -254.534771)
			(xy 101.370375 -254.528003) (xy 101.324902 -254.514607) (xy 101.281808 -254.494856) (xy 101.261672 -254.482346)
			(xy 101.24948 -254.474472) (xy 101.221286 -254.47371) (xy 100.374196 -254.960374) (xy 100.360734 -254.985012)
			(xy 100.361496 -254.99949) (xy 100.36175 -255.014476) (xy 100.361366 -255.037795) (xy 100.354846 -255.083974)
			(xy 100.341904 -255.128779) (xy 100.322796 -255.171322) (xy 100.310696 -255.19126) (xy 100.303076 -255.203198)
			(xy 100.302314 -255.231392) (xy 100.447348 -255.481074) (xy 100.471986 -255.49479) (xy 100.48621 -255.494028)
			(xy 100.500942 -255.493774) (xy 100.526928 -255.494287) (xy 100.578258 -255.502422) (xy 100.627684 -255.518487)
			(xy 100.673989 -255.542085) (xy 100.716033 -255.572635) (xy 100.752781 -255.609385) (xy 100.783328 -255.651431)
			(xy 100.806922 -255.697738) (xy 100.822983 -255.747165) (xy 100.831115 -255.798496) (xy 100.83165 -255.824482)
			(xy 100.831245 -255.847841) (xy 100.824673 -255.894095) (xy 100.811671 -255.938967) (xy 100.792498 -255.981569)
			(xy 100.780342 -256.00152) (xy 100.772468 -256.013712) (xy 100.77196 -256.041906) (xy 100.91674 -256.291334)
			(xy 100.941378 -256.304796) (xy 100.955856 -256.304034) (xy 100.971096 -256.30378) (xy 100.997084 -256.304289)
			(xy 101.048419 -256.312419) (xy 101.097851 -256.32848) (xy 101.144162 -256.352075) (xy 101.186212 -256.382625)
			(xy 101.222965 -256.419376) (xy 101.253516 -256.461424) (xy 101.277114 -256.507734) (xy 101.293177 -256.557165)
			(xy 101.30131 -256.6085) (xy 101.301804 -256.634488) (xy 101.301739 -256.64429) (xy 101.300595 -256.663861)
			(xy 101.299518 -256.673604) (xy 101.29774 -256.687574) (xy 101.309424 -256.713482) (xy 102.625906 -257.618738)
			(xy 102.655624 -257.619754) (xy 102.668324 -257.612388) (xy 102.689639 -257.600344) (xy 102.734769 -257.581364)
			(xy 102.78201 -257.56851) (xy 102.830535 -257.562007) (xy 102.855014 -257.561588) (xy 102.881358 -257.562059)
			(xy 102.933508 -257.569559) (xy 102.98406 -257.584404) (xy 103.031986 -257.606292) (xy 103.076308 -257.634778)
			(xy 103.116126 -257.669281) (xy 103.150628 -257.7091) (xy 103.179113 -257.753423) (xy 103.201 -257.801349)
			(xy 103.215843 -257.851902) (xy 103.223342 -257.904052) (xy 103.223822 -257.930396) (xy 103.22336 -257.956528)
			(xy 103.215969 -258.008267) (xy 103.201347 -258.058445) (xy 103.179788 -258.106055) (xy 103.151724 -258.150146)
			(xy 103.117716 -258.189833) (xy 103.078447 -258.224322) (xy 103.034702 -258.252921) (xy 103.011224 -258.264406)
			(xy 102.997762 -258.270756) (xy 102.982014 -258.295648) (xy 102.982014 -258.465066) (xy 102.997762 -258.489958)
			(xy 103.011224 -258.496308) (xy 103.036271 -258.508566) (xy 103.082669 -258.539497) (xy 103.123878 -258.577063)
			(xy 103.158959 -258.620409) (xy 103.18711 -258.668544) (xy 103.20769 -258.72037) (xy 103.220228 -258.774704)
			(xy 103.224438 -258.830308) (xy 103.220646 -258.880356) (xy 151.51202 -258.880356) (xy 151.51605 -258.738021)
			(xy 151.528125 -258.596141) (xy 151.548208 -258.455173) (xy 151.576235 -258.315566) (xy 151.612115 -258.177768)
			(xy 151.655733 -258.042221) (xy 151.70695 -257.909359) (xy 151.765601 -257.779607) (xy 151.831499 -257.653381)
			(xy 151.904433 -257.531085) (xy 151.98417 -257.413112) (xy 152.070452 -257.299839) (xy 152.163005 -257.191628)
			(xy 152.261532 -257.088827) (xy 152.365717 -256.991765) (xy 152.475226 -256.900753) (xy 152.589709 -256.816081)
			(xy 152.708799 -256.738023) (xy 152.832114 -256.666827) (xy 152.95926 -256.602721) (xy 153.089829 -256.545912)
			(xy 153.223403 -256.49658) (xy 153.359554 -256.454884) (xy 153.497845 -256.420958) (xy 153.637835 -256.39491)
			(xy 153.779074 -256.376824) (xy 153.92111 -256.366757) (xy 154.063488 -256.364742) (xy 154.205752 -256.370785)
			(xy 154.347446 -256.384867) (xy 154.488116 -256.406943) (xy 154.627313 -256.436943) (xy 154.764589 -256.474769)
			(xy 154.899505 -256.520301) (xy 155.031629 -256.573392) (xy 155.160538 -256.633874) (xy 155.285819 -256.701552)
			(xy 155.40707 -256.776209) (xy 155.523903 -256.857607) (xy 155.635944 -256.945484) (xy 155.742834 -257.039559)
			(xy 155.844231 -257.139531) (xy 155.939809 -257.245079) (xy 156.029263 -257.355865) (xy 156.112305 -257.471534)
			(xy 156.188671 -257.591717) (xy 156.258115 -257.716027) (xy 156.320415 -257.844068) (xy 156.375371 -257.975427)
			(xy 156.422808 -258.109686) (xy 156.462572 -258.246413) (xy 156.494538 -258.385171) (xy 156.518603 -258.525515)
			(xy 156.534689 -258.666996) (xy 156.542744 -258.80916) (xy 156.543248 -258.880356) (xy 156.542744 -258.951552)
			(xy 156.534689 -259.093716) (xy 156.518603 -259.235197) (xy 156.494538 -259.375541) (xy 156.462572 -259.514299)
			(xy 156.422808 -259.651026) (xy 156.375371 -259.785285) (xy 156.320415 -259.916644) (xy 156.258115 -260.044685)
			(xy 156.188671 -260.168995) (xy 156.112305 -260.289178) (xy 156.029263 -260.404847) (xy 155.939809 -260.515633)
			(xy 155.844231 -260.621181) (xy 155.742834 -260.721153) (xy 155.635944 -260.815228) (xy 155.523903 -260.903105)
			(xy 155.40707 -260.984503) (xy 155.285819 -261.05916) (xy 155.160538 -261.126838) (xy 155.031629 -261.18732)
			(xy 154.899505 -261.240411) (xy 154.764589 -261.285943) (xy 154.627313 -261.323769) (xy 154.488116 -261.353769)
			(xy 154.347446 -261.375845) (xy 154.205752 -261.389927) (xy 154.063488 -261.39597) (xy 153.92111 -261.393955)
			(xy 153.779074 -261.383888) (xy 153.637835 -261.365802) (xy 153.497845 -261.339754) (xy 153.359554 -261.305828)
			(xy 153.223403 -261.264132) (xy 153.089829 -261.2148) (xy 152.95926 -261.157991) (xy 152.832114 -261.093885)
			(xy 152.708799 -261.022689) (xy 152.589709 -260.944631) (xy 152.475226 -260.859959) (xy 152.365717 -260.768947)
			(xy 152.261532 -260.671885) (xy 152.163005 -260.569084) (xy 152.070452 -260.460873) (xy 151.98417 -260.3476)
			(xy 151.904433 -260.229627) (xy 151.831499 -260.107331) (xy 151.765601 -259.981105) (xy 151.70695 -259.851353)
			(xy 151.655733 -259.718491) (xy 151.612115 -259.582944) (xy 151.576235 -259.445146) (xy 151.548208 -259.305539)
			(xy 151.528125 -259.164571) (xy 151.51605 -259.022691) (xy 151.51202 -258.880356) (xy 103.220646 -258.880356)
			(xy 103.220225 -258.885911) (xy 103.207685 -258.940245) (xy 103.187104 -258.99207) (xy 103.15895 -259.040204)
			(xy 103.123868 -259.083548) (xy 103.082657 -259.121113) (xy 103.036258 -259.152041) (xy 103.011224 -259.164328)
			(xy 102.997762 -259.170678) (xy 102.982014 -259.19557) (xy 102.982014 -259.364988) (xy 102.997762 -259.38988)
			(xy 103.011224 -259.39623) (xy 103.034715 -259.407697) (xy 103.078483 -259.436278) (xy 103.117771 -259.470758)
			(xy 103.151793 -259.510444) (xy 103.179863 -259.554541) (xy 103.201419 -259.602162) (xy 103.216028 -259.652352)
			(xy 103.223396 -259.704103) (xy 103.223822 -259.73024) (xy 103.223349 -259.756583) (xy 103.215847 -259.808731)
			(xy 103.200999 -259.859281) (xy 103.17911 -259.907203) (xy 103.150624 -259.951523) (xy 103.11612 -259.991339)
			(xy 103.076303 -260.025839) (xy 103.031981 -260.054322) (xy 102.984056 -260.076208) (xy 102.933505 -260.091052)
			(xy 102.881357 -260.098551) (xy 102.855014 -260.099048) (xy 102.829742 -260.098638) (xy 102.779673 -260.091737)
			(xy 102.731018 -260.07805) (xy 102.707694 -260.068314) (xy 102.694232 -260.062472) (xy 102.664768 -260.067044)
			(xy 101.59746 -261.007098) (xy 101.589078 -261.034276) (xy 101.59238 -261.047992) (xy 101.596775 -261.067251)
			(xy 101.601491 -261.106472) (xy 101.601778 -261.126224) (xy 101.601373 -261.149853) (xy 101.594633 -261.196629)
			(xy 101.581296 -261.241967) (xy 101.561632 -261.284941) (xy 101.5492 -261.30504) (xy 101.541326 -261.317232)
			(xy 101.540818 -261.345426) (xy 101.684582 -261.59333) (xy 101.70922 -261.606792) (xy 101.723698 -261.60603)
			(xy 101.74097 -261.605522) (xy 101.766958 -261.606003) (xy 101.818296 -261.61413) (xy 101.86773 -261.630188)
			(xy 101.914043 -261.653782) (xy 101.956095 -261.684331) (xy 101.99285 -261.721082) (xy 102.023403 -261.763131)
			(xy 102.047001 -261.809442) (xy 102.063063 -261.858875) (xy 102.071195 -261.910212) (xy 102.071195 -261.962188)
			(xy 102.063063 -262.013525) (xy 102.047001 -262.062958) (xy 102.023403 -262.109269) (xy 101.99285 -262.151318)
			(xy 101.956095 -262.188069) (xy 101.914043 -262.218618) (xy 101.86773 -262.242212) (xy 101.818296 -262.25827)
			(xy 101.766958 -262.266397) (xy 101.74097 -262.266938) (xy 101.72573 -262.266684) (xy 101.711506 -262.265922)
			(xy 101.686614 -262.279384) (xy 101.542088 -262.528812) (xy 101.542596 -262.557006) (xy 101.55047 -262.569198)
			(xy 101.562638 -262.589144) (xy 101.581842 -262.631737) (xy 101.594845 -262.676613) (xy 101.601389 -262.722875)
			(xy 101.601778 -262.746236) (xy 101.601379 -262.769867) (xy 101.594651 -262.816648) (xy 101.581323 -262.861993)
			(xy 101.561669 -262.904974) (xy 101.5492 -262.925052) (xy 101.541326 -262.937244) (xy 101.540818 -262.965438)
			(xy 101.684582 -263.213342) (xy 101.709474 -263.226804) (xy 101.723952 -263.226042) (xy 101.74097 -263.225534)
			(xy 101.76696 -263.226015) (xy 101.818299 -263.234143) (xy 101.867735 -263.250203) (xy 101.91405 -263.2738)
			(xy 101.956102 -263.304352) (xy 101.992856 -263.341108) (xy 102.023407 -263.383161) (xy 102.047002 -263.429476)
			(xy 102.06306 -263.478912) (xy 102.071186 -263.530252) (xy 102.071678 -263.556242) (xy 102.071276 -263.579862)
			(xy 102.064596 -263.626625) (xy 102.051335 -263.671964) (xy 102.031763 -263.714957) (xy 102.019354 -263.735058)
			(xy 102.01148 -263.74725) (xy 102.010718 -263.775444) (xy 102.154736 -264.023348) (xy 102.179374 -264.03681)
			(xy 102.193852 -264.036048) (xy 102.211124 -264.03554) (xy 102.234482 -264.035948) (xy 102.280733 -264.042525)
			(xy 102.325603 -264.055531) (xy 102.368202 -264.074709) (xy 102.388162 -264.086848) (xy 102.4001 -264.094468)
			(xy 102.428294 -264.094976) (xy 103.545894 -263.453372) (xy 103.55072 -263.45007) (xy 105.121202 -262.294624)
			(xy 105.13187 -262.266938) (xy 105.129076 -262.25246) (xy 105.125738 -262.234613) (xy 105.122177 -262.198479)
			(xy 105.121964 -262.180324) (xy 105.122432 -262.153978) (xy 105.129928 -262.101822) (xy 105.144769 -262.051264)
			(xy 105.166655 -262.003332) (xy 105.195139 -261.959003) (xy 105.229642 -261.919179) (xy 105.269461 -261.88467)
			(xy 105.313787 -261.85618) (xy 105.361715 -261.834287) (xy 105.412271 -261.819439) (xy 105.464426 -261.811936)
			(xy 105.490772 -261.811516) (xy 105.522869 -261.812207) (xy 105.586093 -261.823319) (xy 105.616502 -261.833614)
			(xy 105.630472 -261.838694) (xy 105.659174 -261.83209) (xy 106.06786 -261.423404) (xy 106.073702 -261.392924)
			(xy 106.067352 -261.378192) (xy 106.057551 -261.354793) (xy 106.043745 -261.305978) (xy 106.036779 -261.255729)
			(xy 106.036364 -261.230364) (xy 106.036836 -261.204021) (xy 106.044339 -261.151871) (xy 106.059185 -261.10132)
			(xy 106.081075 -261.053396) (xy 106.10956 -261.009075) (xy 106.144063 -260.969258) (xy 106.183881 -260.934756)
			(xy 106.228203 -260.906271) (xy 106.276128 -260.884383) (xy 106.326679 -260.869537) (xy 106.378829 -260.862036)
			(xy 106.405172 -260.861556) (xy 106.433196 -260.862076) (xy 106.488598 -260.870551) (xy 106.542081 -260.887311)
			(xy 106.592412 -260.911969) (xy 106.638433 -260.943958) (xy 106.679085 -260.982542) (xy 106.713431 -261.026832)
			(xy 106.740681 -261.075808) (xy 106.760208 -261.128344) (xy 106.76636 -261.155688) (xy 106.769916 -261.173468)
			(xy 106.797856 -261.196074) (xy 107.282742 -261.196074) (xy 107.307634 -261.180326) (xy 107.313984 -261.166864)
			(xy 107.326244 -261.141817) (xy 107.357177 -261.09542) (xy 107.394745 -261.054212) (xy 107.438092 -261.019132)
			(xy 107.486228 -260.990981) (xy 107.538055 -260.970402) (xy 107.59239 -260.957863) (xy 107.647994 -260.953652)
			(xy 107.703598 -260.957863) (xy 107.757933 -260.970402) (xy 107.80976 -260.990981) (xy 107.857896 -261.019132)
			(xy 107.901243 -261.054212) (xy 107.938811 -261.09542) (xy 107.969744 -261.141817) (xy 107.982004 -261.166864)
			(xy 107.988354 -261.180326) (xy 108.013246 -261.196074) (xy 108.232702 -261.196074) (xy 108.257594 -261.180326)
			(xy 108.263944 -261.166864) (xy 108.276204 -261.141817) (xy 108.307137 -261.09542) (xy 108.344705 -261.054212)
			(xy 108.388052 -261.019132) (xy 108.436188 -260.990981) (xy 108.488015 -260.970402) (xy 108.54235 -260.957863)
			(xy 108.597954 -260.953652) (xy 108.653558 -260.957863) (xy 108.707893 -260.970402) (xy 108.75972 -260.990981)
			(xy 108.807856 -261.019132) (xy 108.851203 -261.054212) (xy 108.888771 -261.09542) (xy 108.919704 -261.141817)
			(xy 108.931964 -261.166864) (xy 108.938314 -261.180326) (xy 108.963206 -261.196074) (xy 109.182662 -261.196074)
			(xy 109.207554 -261.180326) (xy 109.213904 -261.166864) (xy 109.226164 -261.141817) (xy 109.257097 -261.09542)
			(xy 109.294665 -261.054212) (xy 109.338012 -261.019132) (xy 109.386148 -260.990981) (xy 109.437975 -260.970402)
			(xy 109.49231 -260.957863) (xy 109.547914 -260.953652) (xy 109.603518 -260.957863) (xy 109.657853 -260.970402)
			(xy 109.70968 -260.990981) (xy 109.757816 -261.019132) (xy 109.801163 -261.054212) (xy 109.838731 -261.09542)
			(xy 109.869664 -261.141817) (xy 109.881924 -261.166864) (xy 109.888274 -261.180326) (xy 109.913166 -261.196074)
			(xy 110.132622 -261.196074) (xy 110.157514 -261.180326) (xy 110.163864 -261.166864) (xy 110.176124 -261.141817)
			(xy 110.207057 -261.09542) (xy 110.244625 -261.054212) (xy 110.287972 -261.019132) (xy 110.336108 -260.990981)
			(xy 110.387935 -260.970402) (xy 110.44227 -260.957863) (xy 110.497874 -260.953652) (xy 110.553478 -260.957863)
			(xy 110.607813 -260.970402) (xy 110.65964 -260.990981) (xy 110.707776 -261.019132) (xy 110.751123 -261.054212)
			(xy 110.788691 -261.09542) (xy 110.819624 -261.141817) (xy 110.831884 -261.166864) (xy 110.838234 -261.180326)
			(xy 110.863126 -261.196074) (xy 111.082582 -261.196074) (xy 111.107474 -261.180326) (xy 111.113824 -261.166864)
			(xy 111.126084 -261.141817) (xy 111.157017 -261.09542) (xy 111.194585 -261.054212) (xy 111.237932 -261.019132)
			(xy 111.286068 -260.990981) (xy 111.337895 -260.970402) (xy 111.39223 -260.957863) (xy 111.447834 -260.953652)
			(xy 111.503438 -260.957863) (xy 111.557773 -260.970402) (xy 111.6096 -260.990981) (xy 111.657736 -261.019132)
			(xy 111.701083 -261.054212) (xy 111.738651 -261.09542) (xy 111.769584 -261.141817) (xy 111.781844 -261.166864)
			(xy 111.788194 -261.180326) (xy 111.813086 -261.196074) (xy 112.032542 -261.196074) (xy 112.057434 -261.180326)
			(xy 112.063784 -261.166864) (xy 112.076044 -261.141817) (xy 112.106977 -261.09542) (xy 112.144545 -261.054212)
			(xy 112.187892 -261.019132) (xy 112.236028 -260.990981) (xy 112.287855 -260.970402) (xy 112.34219 -260.957863)
			(xy 112.397794 -260.953652) (xy 112.453398 -260.957863) (xy 112.507733 -260.970402) (xy 112.55956 -260.990981)
			(xy 112.607696 -261.019132) (xy 112.651043 -261.054212) (xy 112.688611 -261.09542) (xy 112.719544 -261.141817)
			(xy 112.731804 -261.166864) (xy 112.738154 -261.180326) (xy 112.763046 -261.196074) (xy 112.982756 -261.196074)
			(xy 113.007648 -261.180326) (xy 113.013998 -261.166864) (xy 113.026258 -261.141817) (xy 113.057191 -261.09542)
			(xy 113.094759 -261.054212) (xy 113.138106 -261.019132) (xy 113.186242 -260.990981) (xy 113.238069 -260.970402)
			(xy 113.292404 -260.957863) (xy 113.348008 -260.953652) (xy 113.403612 -260.957863) (xy 113.457947 -260.970402)
			(xy 113.509774 -260.990981) (xy 113.55791 -261.019132) (xy 113.601257 -261.054212) (xy 113.638825 -261.09542)
			(xy 113.669758 -261.141817) (xy 113.682018 -261.166864) (xy 113.688368 -261.180326) (xy 113.71326 -261.196074)
			(xy 113.932716 -261.196074) (xy 113.957608 -261.180326) (xy 113.963958 -261.166864) (xy 113.976218 -261.141817)
			(xy 114.007151 -261.09542) (xy 114.044719 -261.054212) (xy 114.088066 -261.019132) (xy 114.136202 -260.990981)
			(xy 114.188029 -260.970402) (xy 114.242364 -260.957863) (xy 114.297968 -260.953652) (xy 114.353572 -260.957863)
			(xy 114.407907 -260.970402) (xy 114.459734 -260.990981) (xy 114.50787 -261.019132) (xy 114.551217 -261.054212)
			(xy 114.588785 -261.09542) (xy 114.619718 -261.141817) (xy 114.631978 -261.166864) (xy 114.638328 -261.180326)
			(xy 114.66322 -261.196074) (xy 114.882676 -261.196074) (xy 114.907568 -261.180326) (xy 114.913918 -261.166864)
			(xy 114.926178 -261.141817) (xy 114.957111 -261.09542) (xy 114.994679 -261.054212) (xy 115.038026 -261.019132)
			(xy 115.086162 -260.990981) (xy 115.137989 -260.970402) (xy 115.192324 -260.957863) (xy 115.247928 -260.953652)
			(xy 115.303532 -260.957863) (xy 115.357867 -260.970402) (xy 115.409694 -260.990981) (xy 115.45783 -261.019132)
			(xy 115.501177 -261.054212) (xy 115.538745 -261.09542) (xy 115.569678 -261.141817) (xy 115.581938 -261.166864)
			(xy 115.588288 -261.180326) (xy 115.61318 -261.196074) (xy 115.832636 -261.196074) (xy 115.857528 -261.180326)
			(xy 115.863878 -261.166864) (xy 115.875347 -261.143376) (xy 115.903929 -261.099613) (xy 115.938411 -261.06033)
			(xy 115.978098 -261.026315) (xy 116.022195 -260.998251) (xy 116.069816 -260.976702) (xy 116.120004 -260.9621)
			(xy 116.171753 -260.954739) (xy 116.197888 -260.954266) (xy 116.224233 -260.954735) (xy 116.276388 -260.962232)
			(xy 116.326945 -260.977074) (xy 116.374875 -260.998961) (xy 116.419202 -261.027445) (xy 116.459025 -261.061948)
			(xy 116.493532 -261.101768) (xy 116.522021 -261.146092) (xy 116.543912 -261.19402) (xy 116.55876 -261.244575)
			(xy 116.566262 -261.296729) (xy 116.566696 -261.323074) (xy 116.566005 -261.355171) (xy 116.554893 -261.418395)
			(xy 116.544598 -261.448804) (xy 116.539518 -261.463028) (xy 116.545868 -261.491476) (xy 116.582698 -261.528306)
			(xy 116.590097 -261.535152) (xy 116.608695 -261.542886) (xy 116.618766 -261.543292) (xy 120.270524 -261.543292)
			(xy 120.2871 -261.543856) (xy 120.319116 -261.552463) (xy 120.34783 -261.569036) (xy 120.359932 -261.580376)
			(xy 120.611138 -261.831836) (xy 120.621806 -261.839964) (xy 121.727468 -262.474964) (xy 121.755662 -262.474456)
			(xy 121.7676 -262.466836) (xy 121.787546 -262.454668) (xy 121.830139 -262.435464) (xy 121.875015 -262.422461)
			(xy 121.921277 -262.415917) (xy 121.944638 -262.415528) (xy 121.96191 -262.416036) (xy 121.976388 -262.416798)
			(xy 122.001026 -262.403336) (xy 122.145044 -262.155432) (xy 122.144536 -262.127238) (xy 122.136662 -262.115046)
			(xy 122.124217 -262.094956) (xy 122.104572 -262.051975) (xy 122.091246 -262.006635) (xy 122.084513 -261.959859)
			(xy 122.084084 -261.93623) (xy 122.084594 -261.910243) (xy 122.092724 -261.858908) (xy 122.108785 -261.809478)
			(xy 122.132381 -261.763168) (xy 122.162931 -261.72112) (xy 122.199682 -261.684369) (xy 122.24173 -261.653819)
			(xy 122.28804 -261.630223) (xy 122.33747 -261.614162) (xy 122.388805 -261.606032) (xy 122.440779 -261.606032)
			(xy 122.492114 -261.614162) (xy 122.541544 -261.630223) (xy 122.587854 -261.653819) (xy 122.629902 -261.684369)
			(xy 122.666653 -261.72112) (xy 122.697203 -261.763168) (xy 122.720799 -261.809478) (xy 122.73686 -261.858908)
			(xy 122.74499 -261.910243) (xy 122.7455 -261.93623) (xy 122.745246 -261.948422) (xy 122.744738 -261.962646)
			(xy 122.758454 -261.987284) (xy 123.607576 -262.475218) (xy 123.63577 -262.474456) (xy 123.647708 -262.466836)
			(xy 123.667654 -262.454669) (xy 123.710247 -262.435466) (xy 123.755123 -262.422463) (xy 123.801385 -262.415921)
			(xy 123.824746 -262.415528) (xy 123.85073 -262.416041) (xy 123.902057 -262.424178) (xy 123.951479 -262.440243)
			(xy 123.997779 -262.463842) (xy 124.039818 -262.494393) (xy 124.07656 -262.531144) (xy 124.107101 -262.573191)
			(xy 124.130688 -262.619497) (xy 124.146742 -262.668923) (xy 124.154865 -262.720252) (xy 124.155454 -262.746236)
			(xy 124.1552 -262.758428) (xy 124.154692 -262.772652) (xy 124.168408 -262.79729) (xy 125.01753 -263.28497)
			(xy 125.045724 -263.284462) (xy 125.057662 -263.276842) (xy 125.077609 -263.264675) (xy 125.120202 -263.245472)
			(xy 125.165077 -263.232467) (xy 125.211339 -263.22592) (xy 125.2347 -263.225534) (xy 125.251972 -263.226042)
			(xy 125.26645 -263.226804) (xy 125.291088 -263.213342) (xy 125.435106 -262.965438) (xy 125.434598 -262.937244)
			(xy 125.426724 -262.925052) (xy 125.41428 -262.904961) (xy 125.394636 -262.86198) (xy 125.381311 -262.81664)
			(xy 125.374578 -262.769865) (xy 125.374146 -262.746236) (xy 125.374656 -262.720249) (xy 125.382786 -262.668914)
			(xy 125.398847 -262.619484) (xy 125.422443 -262.573174) (xy 125.452993 -262.531126) (xy 125.489744 -262.494375)
			(xy 125.531792 -262.463825) (xy 125.578102 -262.440229) (xy 125.627532 -262.424168) (xy 125.678867 -262.416038)
			(xy 125.730841 -262.416038) (xy 125.782176 -262.424168) (xy 125.831606 -262.440229) (xy 125.877916 -262.463825)
			(xy 125.919964 -262.494375) (xy 125.956715 -262.531126) (xy 125.987265 -262.573174) (xy 126.010861 -262.619484)
			(xy 126.026922 -262.668914) (xy 126.035052 -262.720249) (xy 126.035562 -262.746236) (xy 126.035308 -262.758428)
			(xy 126.0348 -262.772652) (xy 126.048516 -262.79729) (xy 126.897384 -263.285224) (xy 126.925832 -263.284462)
			(xy 126.93777 -263.276842) (xy 126.957717 -263.264676) (xy 127.00031 -263.245473) (xy 127.045186 -263.232469)
			(xy 127.091447 -263.225924) (xy 127.114808 -263.225534) (xy 127.131826 -263.226042) (xy 127.146304 -263.226804)
			(xy 127.171196 -263.213342) (xy 127.31496 -262.965692) (xy 127.314198 -262.937244) (xy 127.306578 -262.925052)
			(xy 127.294133 -262.904962) (xy 127.274485 -262.861981) (xy 127.261158 -262.816641) (xy 127.254423 -262.769865)
			(xy 127.254 -262.746236) (xy 127.25448 -262.720245) (xy 127.262607 -262.668903) (xy 127.278666 -262.619464)
			(xy 127.302262 -262.573146) (xy 127.332814 -262.53109) (xy 127.369569 -262.494332) (xy 127.411622 -262.463777)
			(xy 127.457938 -262.440177) (xy 127.507375 -262.424114) (xy 127.558717 -262.415983) (xy 127.584708 -262.415528)
			(xy 127.61052 -262.416024) (xy 127.661517 -262.424043) (xy 127.71065 -262.439885) (xy 127.756727 -262.463165)
			(xy 127.798629 -262.49332) (xy 127.835339 -262.529616) (xy 127.865966 -262.571173) (xy 127.878332 -262.593836)
			(xy 127.884936 -262.606536) (xy 127.909066 -262.621268) (xy 128.200404 -262.621268) (xy 128.224534 -262.606536)
			(xy 128.231138 -262.593836) (xy 128.243484 -262.571163) (xy 128.27412 -262.529613) (xy 128.310836 -262.493325)
			(xy 128.352742 -262.463178) (xy 128.39882 -262.439903) (xy 128.447954 -262.424066) (xy 128.498951 -262.41605)
			(xy 128.550573 -262.41605) (xy 128.60157 -262.424066) (xy 128.650704 -262.439903) (xy 128.696782 -262.463178)
			(xy 128.738688 -262.493325) (xy 128.775404 -262.529613) (xy 128.80604 -262.571163) (xy 128.818386 -262.593836)
			(xy 128.82499 -262.606536) (xy 128.84912 -262.621268) (xy 129.140458 -262.621268) (xy 129.164588 -262.606536)
			(xy 129.171192 -262.593836) (xy 129.183538 -262.571163) (xy 129.214174 -262.529613) (xy 129.25089 -262.493325)
			(xy 129.292796 -262.463178) (xy 129.338874 -262.439903) (xy 129.388008 -262.424066) (xy 129.439005 -262.41605)
			(xy 129.490627 -262.41605) (xy 129.541624 -262.424066) (xy 129.590758 -262.439903) (xy 129.636836 -262.463178)
			(xy 129.678742 -262.493325) (xy 129.715458 -262.529613) (xy 129.746094 -262.571163) (xy 129.75844 -262.593836)
			(xy 129.765044 -262.606536) (xy 129.789174 -262.621268) (xy 130.080512 -262.621268) (xy 130.104642 -262.606536)
			(xy 130.111246 -262.593836) (xy 130.123596 -262.571168) (xy 130.154238 -262.529627) (xy 130.190956 -262.493347)
			(xy 130.232862 -262.463207) (xy 130.278938 -262.439937) (xy 130.328068 -262.424101) (xy 130.379061 -262.416084)
			(xy 130.40487 -262.415528) (xy 130.43086 -262.416009) (xy 130.4822 -262.424137) (xy 130.531636 -262.440197)
			(xy 130.577951 -262.463793) (xy 130.620003 -262.494346) (xy 130.656758 -262.531101) (xy 130.68731 -262.573154)
			(xy 130.710906 -262.619469) (xy 130.726965 -262.668906) (xy 130.735092 -262.720246) (xy 130.735578 -262.746236)
			(xy 130.735324 -262.758428) (xy 130.734816 -262.772652) (xy 130.748532 -262.79729) (xy 131.5974 -263.285224)
			(xy 131.625594 -263.284462) (xy 131.637786 -263.277096) (xy 131.65773 -263.264909) (xy 131.700317 -263.245656)
			(xy 131.74519 -263.232585) (xy 131.791456 -263.225957) (xy 131.814824 -263.225534) (xy 131.840635 -263.226031)
			(xy 131.891631 -263.234052) (xy 131.940762 -263.249896) (xy 131.986836 -263.273178) (xy 132.028735 -263.303333)
			(xy 132.065443 -263.33963) (xy 132.096068 -263.381187) (xy 132.108448 -263.403842) (xy 132.115052 -263.416542)
			(xy 132.139182 -263.431274) (xy 132.43052 -263.431274) (xy 132.45465 -263.416542) (xy 132.461254 -263.403842)
			(xy 132.4736 -263.381169) (xy 132.504236 -263.339619) (xy 132.540952 -263.303331) (xy 132.582858 -263.273184)
			(xy 132.628936 -263.249909) (xy 132.67807 -263.234072) (xy 132.729067 -263.226056) (xy 132.780689 -263.226056)
			(xy 132.831686 -263.234072) (xy 132.88082 -263.249909) (xy 132.926898 -263.273184) (xy 132.968804 -263.303331)
			(xy 133.00552 -263.339619) (xy 133.036156 -263.381169) (xy 133.048502 -263.403842) (xy 133.055106 -263.416542)
			(xy 133.079236 -263.431274) (xy 133.37032 -263.431274) (xy 133.39445 -263.416542) (xy 133.401054 -263.403842)
			(xy 133.4134 -263.381169) (xy 133.444036 -263.339619) (xy 133.480752 -263.303331) (xy 133.522658 -263.273184)
			(xy 133.568736 -263.249909) (xy 133.61787 -263.234072) (xy 133.668867 -263.226056) (xy 133.720489 -263.226056)
			(xy 133.771486 -263.234072) (xy 133.82062 -263.249909) (xy 133.866698 -263.273184) (xy 133.908604 -263.303331)
			(xy 133.94532 -263.339619) (xy 133.975956 -263.381169) (xy 133.988302 -263.403842) (xy 133.994906 -263.416542)
			(xy 134.019036 -263.431274) (xy 134.310374 -263.431274) (xy 134.334504 -263.416542) (xy 134.341108 -263.403842)
			(xy 134.353454 -263.381169) (xy 134.38409 -263.339619) (xy 134.420806 -263.303331) (xy 134.462712 -263.273184)
			(xy 134.50879 -263.249909) (xy 134.557924 -263.234072) (xy 134.608921 -263.226056) (xy 134.660543 -263.226056)
			(xy 134.71154 -263.234072) (xy 134.760674 -263.249909) (xy 134.806752 -263.273184) (xy 134.848658 -263.303331)
			(xy 134.885374 -263.339619) (xy 134.91601 -263.381169) (xy 134.928356 -263.403842) (xy 134.93496 -263.416542)
			(xy 134.95909 -263.431274) (xy 135.250428 -263.431274) (xy 135.274558 -263.416542) (xy 135.281162 -263.403842)
			(xy 135.293508 -263.381169) (xy 135.324144 -263.339619) (xy 135.36086 -263.303331) (xy 135.402766 -263.273184)
			(xy 135.448844 -263.249909) (xy 135.497978 -263.234072) (xy 135.548975 -263.226056) (xy 135.600597 -263.226056)
			(xy 135.651594 -263.234072) (xy 135.700728 -263.249909) (xy 135.746806 -263.273184) (xy 135.788712 -263.303331)
			(xy 135.825428 -263.339619) (xy 135.856064 -263.381169) (xy 135.86841 -263.403842) (xy 135.875014 -263.416542)
			(xy 135.899144 -263.431274) (xy 136.190482 -263.431274) (xy 136.214612 -263.416542) (xy 136.221216 -263.403842)
			(xy 136.233565 -263.381172) (xy 136.264206 -263.339628) (xy 136.300923 -263.303344) (xy 136.342829 -263.273199)
			(xy 136.388905 -263.249925) (xy 136.438036 -263.234084) (xy 136.48903 -263.226062) (xy 136.51484 -263.225534)
			(xy 136.540826 -263.22602) (xy 136.592157 -263.234157) (xy 136.641584 -263.250223) (xy 136.687888 -263.273823)
			(xy 136.729931 -263.304377) (xy 136.766676 -263.341132) (xy 136.797219 -263.383182) (xy 136.820809 -263.429492)
			(xy 136.836863 -263.478923) (xy 136.844986 -263.530256) (xy 136.845548 -263.556242) (xy 136.84515 -263.579228)
			(xy 136.838778 -263.624757) (xy 136.826161 -263.668964) (xy 136.807544 -263.710998) (xy 136.795764 -263.73074)
			(xy 136.788398 -263.742678) (xy 136.78789 -263.770618) (xy 136.934448 -264.02284) (xy 136.958832 -264.036302)
			(xy 136.973056 -264.035794) (xy 136.98474 -264.03554) (xy 137.010554 -264.036031) (xy 137.061558 -264.044041)
			(xy 137.110698 -264.059877) (xy 137.156783 -264.083153) (xy 137.198692 -264.113305) (xy 137.235409 -264.1496)
			(xy 137.266043 -264.191159) (xy 137.278364 -264.213848) (xy 137.284968 -264.226548) (xy 137.309098 -264.24128)
			(xy 137.600436 -264.24128) (xy 137.624566 -264.226548) (xy 137.63117 -264.213848) (xy 137.643516 -264.191175)
			(xy 137.674152 -264.149625) (xy 137.710868 -264.113337) (xy 137.752774 -264.08319) (xy 137.798852 -264.059915)
			(xy 137.847986 -264.044078) (xy 137.898983 -264.036062) (xy 137.950605 -264.036062) (xy 138.001602 -264.044078)
			(xy 138.050736 -264.059915) (xy 138.096814 -264.08319) (xy 138.13872 -264.113337) (xy 138.175436 -264.149625)
			(xy 138.206072 -264.191175) (xy 138.218418 -264.213848) (xy 138.225022 -264.226548) (xy 138.249152 -264.24128)
			(xy 138.54049 -264.24128) (xy 138.56462 -264.226548) (xy 138.571224 -264.213848) (xy 138.58357 -264.191175)
			(xy 138.614206 -264.149625) (xy 138.650922 -264.113337) (xy 138.692828 -264.08319) (xy 138.738906 -264.059915)
			(xy 138.78804 -264.044078) (xy 138.839037 -264.036062) (xy 138.890659 -264.036062) (xy 138.941656 -264.044078)
			(xy 138.99079 -264.059915) (xy 139.036868 -264.08319) (xy 139.078774 -264.113337) (xy 139.11549 -264.149625)
			(xy 139.146126 -264.191175) (xy 139.158472 -264.213848) (xy 139.165076 -264.226548) (xy 139.189206 -264.24128)
			(xy 139.48029 -264.24128) (xy 139.50442 -264.226548) (xy 139.511024 -264.213848) (xy 139.52337 -264.191175)
			(xy 139.554006 -264.149625) (xy 139.590722 -264.113337) (xy 139.632628 -264.08319) (xy 139.678706 -264.059915)
			(xy 139.72784 -264.044078) (xy 139.778837 -264.036062) (xy 139.830459 -264.036062) (xy 139.881456 -264.044078)
			(xy 139.93059 -264.059915) (xy 139.976668 -264.08319) (xy 140.018574 -264.113337) (xy 140.05529 -264.149625)
			(xy 140.085926 -264.191175) (xy 140.098272 -264.213848) (xy 140.104876 -264.226548) (xy 140.129006 -264.24128)
			(xy 140.420344 -264.24128) (xy 140.444474 -264.226548) (xy 140.451078 -264.213848) (xy 140.463424 -264.191175)
			(xy 140.49406 -264.149625) (xy 140.530776 -264.113337) (xy 140.572682 -264.08319) (xy 140.61876 -264.059915)
			(xy 140.667894 -264.044078) (xy 140.718891 -264.036062) (xy 140.770513 -264.036062) (xy 140.82151 -264.044078)
			(xy 140.870644 -264.059915) (xy 140.916722 -264.08319) (xy 140.958628 -264.113337) (xy 140.995344 -264.149625)
			(xy 141.02598 -264.191175) (xy 141.038326 -264.213848) (xy 141.04493 -264.226548) (xy 141.06906 -264.24128)
			(xy 141.360398 -264.24128) (xy 141.384528 -264.226548) (xy 141.391132 -264.213848) (xy 141.403481 -264.191178)
			(xy 141.434122 -264.149635) (xy 141.47084 -264.113352) (xy 141.512745 -264.083209) (xy 141.558822 -264.059936)
			(xy 141.607952 -264.044098) (xy 141.658946 -264.036078) (xy 141.684756 -264.03554) (xy 141.710746 -264.03602)
			(xy 141.762087 -264.044146) (xy 141.811525 -264.060205) (xy 141.85784 -264.083801) (xy 141.899894 -264.114353)
			(xy 141.936649 -264.151109) (xy 141.967201 -264.193163) (xy 141.990797 -264.239479) (xy 142.006855 -264.288917)
			(xy 142.01498 -264.340258) (xy 142.015464 -264.366248) (xy 142.015072 -264.389236) (xy 142.00871 -264.434769)
			(xy 141.996102 -264.478981) (xy 141.97749 -264.52102) (xy 141.96568 -264.540746) (xy 141.958314 -264.552684)
			(xy 141.957806 -264.580624) (xy 142.10411 -264.832846) (xy 142.128494 -264.846308) (xy 142.142718 -264.8458)
			(xy 142.154656 -264.845546) (xy 142.180647 -264.846052) (xy 142.231989 -264.854177) (xy 142.281429 -264.870234)
			(xy 142.327748 -264.893826) (xy 142.369806 -264.924375) (xy 142.406567 -264.961126) (xy 142.437127 -265.003176)
			(xy 142.460732 -265.049488) (xy 142.476802 -265.098923) (xy 142.484941 -265.150263) (xy 142.485364 -265.176254)
			(xy 142.484993 -265.199202) (xy 142.478683 -265.24466) (xy 142.466135 -265.288806) (xy 142.447592 -265.330788)
			(xy 142.435834 -265.350498) (xy 142.428214 -265.36269) (xy 142.427706 -265.390376) (xy 142.588488 -265.66749)
			(xy 142.611856 -265.680952) (xy 142.625572 -265.680952) (xy 142.649525 -265.68148) (xy 142.696826 -265.689082)
			(xy 142.742359 -265.703977) (xy 142.785007 -265.7258) (xy 142.823724 -265.754017) (xy 142.85756 -265.787933)
			(xy 142.885683 -265.826718) (xy 142.907404 -265.869418) (xy 142.92219 -265.914987) (xy 142.929678 -265.962306)
			(xy 142.930118 -265.98626) (xy 142.929562 -266.012578) (xy 142.920532 -266.064433) (xy 142.902748 -266.113974)
			(xy 142.89024 -266.137136) (xy 142.883382 -266.149074) (xy 142.883636 -266.175744) (xy 143.044418 -266.452858)
			(xy 143.068802 -266.46632) (xy 143.083026 -266.465812) (xy 143.09471 -266.465558) (xy 143.120521 -266.466054)
			(xy 143.171518 -266.474074) (xy 143.220649 -266.489917) (xy 143.266724 -266.513199) (xy 143.308623 -266.543355)
			(xy 143.34533 -266.579652) (xy 143.375954 -266.621211) (xy 143.388334 -266.643866) (xy 143.394938 -266.656566)
			(xy 143.419068 -266.671298) (xy 143.710406 -266.671298)
		)
		(stroke
			(width 0)
			(type solid)
		)
		(fill yes)
		(layer "In8.Cu")
		(net "PVDDCR_SOC_P1")
	)
	(gr_poly
		(pts
			(xy 78.89113 -354.3046) (xy 78.901198 -354.304171) (xy 78.919794 -354.296449) (xy 78.927198 -354.289614)
			(xy 81.619344 -351.597468) (xy 81.637385 -351.580208) (xy 81.678878 -351.552449) (xy 81.724996 -351.533335)
			(xy 81.773961 -351.523602) (xy 81.798922 -351.523046) (xy 84.955634 -351.523046) (xy 84.9657 -351.522615)
			(xy 84.984291 -351.514886) (xy 84.991702 -351.50806) (xy 85.237828 -351.261934) (xy 85.245327 -351.253526)
			(xy 85.252867 -351.232324) (xy 85.250696 -351.209927) (xy 85.245448 -351.199958) (xy 85.186012 -351.100136)
			(xy 85.154008 -351.08769) (xy 85.13699 -351.09277) (xy 85.095849 -351.104454) (xy 85.011901 -351.120824)
			(xy 84.92677 -351.129076) (xy 84.884006 -351.1296) (xy 84.842891 -351.129125) (xy 84.761012 -351.121539)
			(xy 84.680181 -351.10643) (xy 84.60109 -351.083928) (xy 84.524412 -351.054224) (xy 84.450802 -351.017572)
			(xy 84.380888 -350.974285) (xy 84.315266 -350.924732) (xy 84.254496 -350.869335) (xy 84.199096 -350.808568)
			(xy 84.14954 -350.742948) (xy 84.106249 -350.673036) (xy 84.069594 -350.599428) (xy 84.039886 -350.522752)
			(xy 84.01738 -350.443661) (xy 84.002267 -350.362832) (xy 83.994677 -350.280953) (xy 83.994244 -350.239838)
			(xy 83.994756 -350.196891) (xy 84.003031 -350.111396) (xy 84.019518 -350.027098) (xy 84.044063 -349.944785)
			(xy 84.059776 -349.904812) (xy 84.063053 -349.895497) (xy 84.063065 -349.875768) (xy 84.059776 -349.866458)
			(xy 84.044087 -349.826477) (xy 84.019565 -349.744161) (xy 84.003079 -349.659867) (xy 83.994781 -349.574377)
			(xy 83.994244 -349.531432) (xy 83.994836 -349.485786) (xy 84.004216 -349.394977) (xy 84.02286 -349.305609)
			(xy 84.036154 -349.261938) (xy 84.038612 -349.252927) (xy 84.037578 -349.234293) (xy 84.034122 -349.225616)
			(xy 84.015452 -349.182532) (xy 83.986244 -349.093287) (xy 83.966602 -349.001462) (xy 83.956746 -348.908078)
			(xy 83.956144 -348.861126) (xy 83.956586 -348.820566) (xy 83.963951 -348.739782) (xy 83.978632 -348.660002)
			(xy 84.000507 -348.581887) (xy 84.029395 -348.506086) (xy 84.046822 -348.469458) (xy 84.050803 -348.46039)
			(xy 84.05223 -348.440657) (xy 84.049616 -348.431104) (xy 84.035432 -348.386079) (xy 84.015541 -348.293794)
			(xy 84.005527 -348.199922) (xy 84.004912 -348.15272) (xy 84.005416 -348.110372) (xy 84.013467 -348.026058)
			(xy 84.029496 -347.942892) (xy 84.053357 -347.861625) (xy 84.084836 -347.782995) (xy 84.123647 -347.707714)
			(xy 84.169437 -347.636462) (xy 84.221793 -347.569886) (xy 84.280241 -347.508588) (xy 84.344251 -347.453123)
			(xy 84.413243 -347.403994) (xy 84.486593 -347.361645) (xy 84.563636 -347.326461) (xy 84.643675 -347.298759)
			(xy 84.725984 -347.278791) (xy 84.809819 -347.266738) (xy 84.89442 -347.262708) (xy 84.979021 -347.266738)
			(xy 85.062856 -347.278791) (xy 85.145165 -347.298759) (xy 85.225204 -347.326461) (xy 85.302247 -347.361645)
			(xy 85.375597 -347.403994) (xy 85.444589 -347.453123) (xy 85.508599 -347.508588) (xy 85.567047 -347.569886)
			(xy 85.619403 -347.636462) (xy 85.665193 -347.707714) (xy 85.704004 -347.782995) (xy 85.735483 -347.861625)
			(xy 85.759344 -347.942892) (xy 85.775373 -348.026058) (xy 85.783424 -348.110372) (xy 85.783928 -348.15272)
			(xy 85.78347 -348.193279) (xy 85.776102 -348.274061) (xy 85.761418 -348.353839) (xy 85.739542 -348.431951)
			(xy 85.710654 -348.50775) (xy 85.69325 -348.544388) (xy 85.689254 -348.553455) (xy 85.687805 -348.573196)
			(xy 85.690456 -348.582742) (xy 85.704637 -348.627767) (xy 85.724522 -348.720053) (xy 85.73453 -348.813924)
			(xy 85.73516 -348.861126) (xy 85.734608 -348.906766) (xy 85.725314 -348.997571) (xy 85.706764 -349.086945)
			(xy 85.693504 -349.13062) (xy 85.691059 -349.139631) (xy 85.692111 -349.158255) (xy 85.695536 -349.166942)
			(xy 85.714229 -349.210023) (xy 85.74349 -349.299263) (xy 85.763197 -349.391087) (xy 85.773131 -349.484475)
			(xy 85.773768 -349.531432) (xy 85.773258 -349.57438) (xy 85.764985 -349.659876) (xy 85.748501 -349.744174)
			(xy 85.723959 -349.826489) (xy 85.708236 -349.866458) (xy 85.704913 -349.875763) (xy 85.704926 -349.895501)
			(xy 85.708236 -349.904812) (xy 85.723926 -349.944792) (xy 85.74845 -350.027109) (xy 85.764939 -350.111403)
			(xy 85.77324 -350.196892) (xy 85.773768 -350.239838) (xy 85.773252 -350.282603) (xy 85.765018 -350.367737)
			(xy 85.74864 -350.451686) (xy 85.736938 -350.492822) (xy 85.731858 -350.50984) (xy 85.744304 -350.541844)
			(xy 85.844126 -350.60128) (xy 85.854088 -350.606558) (xy 85.876495 -350.608763) (xy 85.897692 -350.601171)
			(xy 85.906102 -350.59366) (xy 86.871556 -349.628206) (xy 86.889596 -349.610945) (xy 86.931089 -349.583184)
			(xy 86.977207 -349.564069) (xy 87.026172 -349.554337) (xy 87.051134 -349.553784) (xy 108.266738 -349.553784)
			(xy 108.276805 -349.553354) (xy 108.295398 -349.545628) (xy 108.302806 -349.538798) (xy 115.78463 -342.056974)
			(xy 115.80267 -342.039712) (xy 115.844163 -342.011951) (xy 115.890281 -341.992834) (xy 115.939246 -341.983098)
			(xy 115.964208 -341.982552) (xy 131.294632 -341.982552) (xy 131.298442 -341.978742) (xy 131.54914 -341.728044)
			(xy 131.555984 -341.720645) (xy 131.563708 -341.702046) (xy 131.564126 -341.691976) (xy 131.564126 -327.905364)
			(xy 131.563632 -327.895359) (xy 131.555967 -327.876875) (xy 131.541816 -327.862727) (xy 131.523331 -327.855066)
			(xy 131.513326 -327.854564) (xy 111.260636 -327.854564) (xy 111.251353 -327.854961) (xy 111.234017 -327.8616)
			(xy 111.226854 -327.867518) (xy 111.205796 -327.885578) (xy 111.159436 -327.916044) (xy 111.109148 -327.939462)
			(xy 111.055994 -327.955339) (xy 111.001099 -327.963337) (xy 110.973362 -327.963784) (xy 110.94563 -327.96328)
			(xy 110.890752 -327.955245) (xy 110.83761 -327.939364) (xy 110.787321 -327.91597) (xy 110.740941 -327.885554)
			(xy 110.71987 -327.867518) (xy 110.712679 -327.861647) (xy 110.695361 -327.855001) (xy 110.686088 -327.854564)
			(xy 105.730548 -327.854564) (xy 105.720372 -327.855078) (xy 105.701653 -327.863081) (xy 105.694226 -327.870058)
			(xy 105.63606 -327.929748) (xy 105.628694 -327.948544) (xy 105.628948 -327.958958) (xy 105.629202 -327.969626)
			(xy 105.628714 -327.996876) (xy 105.620955 -328.05082) (xy 105.605597 -328.103112) (xy 105.582955 -328.152685)
			(xy 105.553488 -328.198532) (xy 105.517796 -328.239719) (xy 105.476606 -328.275407) (xy 105.430757 -328.30487)
			(xy 105.381182 -328.327509) (xy 105.328889 -328.342862) (xy 105.274944 -328.350617) (xy 105.247694 -328.351134)
			(xy 105.221417 -328.350713) (xy 105.169358 -328.343531) (xy 105.11878 -328.329263) (xy 105.094532 -328.31913)
			(xy 105.080054 -328.31278) (xy 105.049574 -328.318368) (xy 104.769412 -328.59853) (xy 104.75137 -328.615787)
			(xy 104.709875 -328.643538) (xy 104.663757 -328.662645) (xy 104.614794 -328.672369) (xy 104.589834 -328.672952)
			(xy 99.041712 -328.672952) (xy 99.014788 -328.693272) (xy 99.009962 -328.709528) (xy 99.001891 -328.73562)
			(xy 98.979325 -328.785357) (xy 98.949899 -328.831368) (xy 98.914214 -328.872715) (xy 98.873 -328.908552)
			(xy 98.827098 -328.938148) (xy 98.777445 -328.960898) (xy 98.725056 -328.976338) (xy 98.671002 -328.984151)
			(xy 98.643694 -328.98461) (xy 98.616443 -328.984124) (xy 98.562496 -328.976367) (xy 98.510202 -328.961011)
			(xy 98.460625 -328.93837) (xy 98.414775 -328.908903) (xy 98.373586 -328.873212) (xy 98.337894 -328.832022)
			(xy 98.308429 -328.786171) (xy 98.285788 -328.736595) (xy 98.270433 -328.6843) (xy 98.262676 -328.630353)
			(xy 98.262186 -328.603102) (xy 98.262692 -328.574637) (xy 98.271113 -328.518334) (xy 98.287814 -328.46391)
			(xy 98.312423 -328.412574) (xy 98.327972 -328.388726) (xy 98.338386 -328.373486) (xy 98.335084 -328.337418)
			(xy 96.216216 -326.21855) (xy 96.208816 -326.211711) (xy 96.190217 -326.203999) (xy 96.180148 -326.203564)
			(xy 74.588624 -326.203564) (xy 74.578561 -326.204003) (xy 74.559983 -326.211744) (xy 74.552556 -326.21855)
			(xy 70.958964 -329.812142) (xy 70.940923 -329.829402) (xy 70.89943 -329.857161) (xy 70.853312 -329.876276)
			(xy 70.804347 -329.88601) (xy 70.779386 -329.886564) (xy 65.825624 -329.886564) (xy 65.815561 -329.887003)
			(xy 65.796983 -329.894744) (xy 65.789556 -329.90155) (xy 65.216786 -330.47432) (xy 65.209933 -330.481715)
			(xy 65.202193 -330.500314) (xy 65.2018 -330.510388) (xy 65.2018 -334.98409) (xy 65.20118 -335.009043)
			(xy 65.191428 -335.057988) (xy 65.172315 -335.104089) (xy 65.144577 -335.145578) (xy 65.127378 -335.163668)
			(xy 64.624204 -335.666842) (xy 64.606161 -335.684097) (xy 64.564666 -335.711846) (xy 64.518548 -335.73095)
			(xy 64.469586 -335.740673) (xy 64.444626 -335.741264) (xy 59.559698 -335.741264) (xy 59.53379 -335.759044)
			(xy 59.528202 -335.773776) (xy 59.51738 -335.800363) (xy 59.488916 -335.850211) (xy 59.453313 -335.895236)
			(xy 59.41137 -335.934425) (xy 59.364035 -335.966895) (xy 59.312372 -335.991914) (xy 59.257547 -336.008917)
			(xy 59.200795 -336.017523) (xy 59.172094 -336.018124) (xy 59.145899 -336.017691) (xy 59.094002 -336.010525)
			(xy 59.043572 -335.99633) (xy 58.995557 -335.975371) (xy 58.950859 -335.948043) (xy 58.910319 -335.91486)
			(xy 58.892186 -335.89595) (xy 58.884712 -335.888621) (xy 58.865557 -335.880237) (xy 58.855102 -335.879694)
			(xy 58.780426 -335.879694) (xy 58.769982 -335.880263) (xy 58.750848 -335.888663) (xy 58.743342 -335.89595)
			(xy 58.725212 -335.914861) (xy 58.684668 -335.94804) (xy 58.639969 -335.975365) (xy 58.591954 -335.996322)
			(xy 58.541525 -336.010517) (xy 58.489629 -336.017684) (xy 58.463434 -336.018124) (xy 58.434727 -336.017608)
			(xy 58.377961 -336.009013) (xy 58.323123 -335.992011) (xy 58.271451 -335.966987) (xy 58.22411 -335.934504)
			(xy 58.18217 -335.895296) (xy 58.146576 -335.850248) (xy 58.118131 -335.800376) (xy 58.107326 -335.773776)
			(xy 58.101738 -335.759044) (xy 58.07583 -335.741264) (xy 57.407048 -335.741264) (xy 57.380886 -335.759298)
			(xy 57.375298 -335.774284) (xy 57.364636 -335.801152) (xy 57.33638 -335.851577) (xy 57.300842 -335.897163)
			(xy 57.258835 -335.936868) (xy 57.211319 -335.969783) (xy 57.159383 -335.995154) (xy 57.104214 -336.012402)
			(xy 57.047075 -336.021132) (xy 57.018174 -336.02168) (xy 56.989436 -336.021157) (xy 56.93261 -336.012531)
			(xy 56.877722 -335.995477) (xy 56.826013 -335.970382) (xy 56.778655 -335.937813) (xy 56.757316 -335.918556)
			(xy 56.750204 -335.911952) (xy 56.732678 -335.90484) (xy 56.64327 -335.90484) (xy 56.625744 -335.911952)
			(xy 56.618632 -335.918556) (xy 56.597303 -335.937822) (xy 56.549938 -335.970377) (xy 56.498225 -335.99546)
			(xy 56.443336 -336.012502) (xy 56.386511 -336.021119) (xy 56.357774 -336.02168) (xy 56.32887 -336.021151)
			(xy 56.271721 -336.012438) (xy 56.216543 -335.995199) (xy 56.164598 -335.969831) (xy 56.117077 -335.936913)
			(xy 56.075068 -335.897201) (xy 56.039533 -335.851603) (xy 56.011288 -335.801165) (xy 56.00065 -335.774284)
			(xy 55.995062 -335.759298) (xy 55.9689 -335.741264) (xy 23.700486 -335.741264) (xy 23.675526 -335.740691)
			(xy 23.626567 -335.730949) (xy 23.580449 -335.711841) (xy 23.538946 -335.684102) (xy 23.520908 -335.666842)
			(xy 23.495 -335.640934) (xy 23.487557 -335.63424) (xy 23.469059 -335.626642) (xy 23.449061 -335.626658)
			(xy 23.439628 -335.630012) (xy 23.425404 -335.635854) (xy 23.408386 -335.661254) (xy 23.408386 -336.9884)
			(xy 70.218517 -336.9884) (xy 70.222508 -336.904617) (xy 70.234446 -336.821593) (xy 70.254221 -336.74008)
			(xy 70.281655 -336.660815) (xy 70.3165 -336.584518) (xy 70.35844 -336.511878) (xy 70.407095 -336.443554)
			(xy 70.462025 -336.380164) (xy 70.522731 -336.322283) (xy 70.588664 -336.270435) (xy 70.659228 -336.225089)
			(xy 70.733783 -336.186656) (xy 70.811653 -336.155484) (xy 70.892134 -336.131855) (xy 70.974497 -336.115984)
			(xy 71.057995 -336.108014) (xy 71.099934 -336.107532) (xy 71.137123 -336.107938) (xy 71.211236 -336.114223)
			(xy 71.284556 -336.126727) (xy 71.356562 -336.145363) (xy 71.39178 -336.157316) (xy 71.399976 -336.159839)
			(xy 71.417112 -336.159839) (xy 71.425308 -336.157316) (xy 71.470669 -336.142069) (xy 71.563884 -336.120393)
			(xy 71.658899 -336.108952) (xy 71.70674 -336.107786) (xy 71.718176 -336.107007) (xy 71.738659 -336.096778)
			(xy 71.752714 -336.078706) (xy 71.755762 -336.067654) (xy 71.765272 -336.026636) (xy 71.791094 -335.946486)
			(xy 71.807324 -335.907634) (xy 71.810983 -335.897931) (xy 71.810971 -335.877211) (xy 71.807324 -335.867502)
			(xy 71.790169 -335.826159) (xy 71.763338 -335.74076) (xy 71.7453 -335.653081) (xy 71.736241 -335.564026)
			(xy 71.735696 -335.519268) (xy 71.736195 -335.477343) (xy 71.744165 -335.393872) (xy 71.760034 -335.311537)
			(xy 71.783657 -335.231083) (xy 71.814821 -335.153239) (xy 71.853244 -335.078709) (xy 71.898577 -335.00817)
			(xy 71.95041 -334.942259) (xy 72.008273 -334.881573) (xy 72.071643 -334.826663) (xy 72.139946 -334.778025)
			(xy 72.212563 -334.7361) (xy 72.288836 -334.701267) (xy 72.368075 -334.673842) (xy 72.449561 -334.654073)
			(xy 72.532558 -334.64214) (xy 72.616314 -334.638151) (xy 72.70007 -334.64214) (xy 72.783067 -334.654073)
			(xy 72.864553 -334.673842) (xy 72.943792 -334.701267) (xy 73.020065 -334.7361) (xy 73.092682 -334.778025)
			(xy 73.160985 -334.826663) (xy 73.224355 -334.881573) (xy 73.282218 -334.942259) (xy 73.334051 -335.00817)
			(xy 73.379384 -335.078709) (xy 73.417807 -335.153239) (xy 73.448971 -335.231083) (xy 73.472594 -335.311537)
			(xy 73.488463 -335.393872) (xy 73.496433 -335.477343) (xy 73.496932 -335.519268) (xy 73.496405 -335.564027)
			(xy 73.487367 -335.653088) (xy 73.469332 -335.740771) (xy 73.442485 -335.826168) (xy 73.425304 -335.867502)
			(xy 73.421681 -335.877216) (xy 73.421669 -335.897926) (xy 73.425304 -335.907634) (xy 73.441139 -335.945575)
			(xy 73.466487 -336.02379) (xy 73.484436 -336.104027) (xy 73.494829 -336.185587) (xy 73.496678 -336.226658)
			(xy 73.496932 -336.240374) (xy 73.511156 -336.263234) (xy 73.61301 -336.31759) (xy 73.639934 -336.316828)
			(xy 73.651618 -336.309462) (xy 73.686811 -336.288202) (xy 73.76042 -336.251553) (xy 73.837094 -336.221845)
			(xy 73.91618 -336.199333) (xy 73.997005 -336.184209) (xy 74.07888 -336.1766) (xy 74.119994 -336.176112)
			(xy 74.161107 -336.176619) (xy 74.242983 -336.184205) (xy 74.32381 -336.199313) (xy 74.402898 -336.221815)
			(xy 74.479573 -336.251518) (xy 74.553179 -336.288168) (xy 74.623091 -336.331454) (xy 74.68871 -336.381006)
			(xy 74.749477 -336.4364) (xy 74.804874 -336.497166) (xy 74.854428 -336.562783) (xy 74.897716 -336.632693)
			(xy 74.934369 -336.706298) (xy 74.964075 -336.782971) (xy 74.986579 -336.862059) (xy 75.001691 -336.942885)
			(xy 75.005252 -336.9813) (xy 78.574105 -336.9813) (xy 78.578096 -336.897517) (xy 78.590033 -336.814493)
			(xy 78.609809 -336.732979) (xy 78.637243 -336.653715) (xy 78.672087 -336.577417) (xy 78.714027 -336.504776)
			(xy 78.762681 -336.436452) (xy 78.81761 -336.373061) (xy 78.878316 -336.31518) (xy 78.94425 -336.26333)
			(xy 79.014813 -336.217984) (xy 79.089367 -336.179549) (xy 79.167237 -336.148376) (xy 79.247718 -336.124747)
			(xy 79.330081 -336.108874) (xy 79.413579 -336.100902) (xy 79.455518 -336.10042) (xy 79.492708 -336.100802)
			(xy 79.566821 -336.107094) (xy 79.640141 -336.119606) (xy 79.712146 -336.138248) (xy 79.747364 -336.150204)
			(xy 79.75556 -336.152727) (xy 79.772696 -336.152727) (xy 79.780892 -336.150204) (xy 79.82711 -336.134723)
			(xy 79.922101 -336.112853) (xy 80.018924 -336.101587) (xy 80.067658 -336.100674) (xy 80.079173 -336.100035)
			(xy 80.099844 -336.089868) (xy 80.113999 -336.071694) (xy 80.116934 -336.060542) (xy 80.12645 -336.018737)
			(xy 80.152526 -335.937055) (xy 80.169004 -335.897474) (xy 80.172641 -335.887764) (xy 80.172644 -335.86705)
			(xy 80.169004 -335.857342) (xy 80.151829 -335.816007) (xy 80.125003 -335.730605) (xy 80.10697 -335.642924)
			(xy 80.097917 -335.553866) (xy 80.097376 -335.509108) (xy 80.097875 -335.467183) (xy 80.105845 -335.383712)
			(xy 80.121714 -335.301377) (xy 80.145337 -335.220923) (xy 80.176501 -335.143079) (xy 80.214924 -335.068549)
			(xy 80.260257 -334.99801) (xy 80.31209 -334.932099) (xy 80.369953 -334.871413) (xy 80.433323 -334.816503)
			(xy 80.501626 -334.767865) (xy 80.574243 -334.72594) (xy 80.650516 -334.691107) (xy 80.729755 -334.663682)
			(xy 80.811241 -334.643913) (xy 80.894238 -334.63198) (xy 80.977994 -334.627991) (xy 81.06175 -334.63198)
			(xy 81.144747 -334.643913) (xy 81.226233 -334.663682) (xy 81.305472 -334.691107) (xy 81.381745 -334.72594)
			(xy 81.454362 -334.767865) (xy 81.522665 -334.816503) (xy 81.586035 -334.871413) (xy 81.643898 -334.932099)
			(xy 81.695731 -334.99801) (xy 81.741064 -335.068549) (xy 81.779487 -335.143079) (xy 81.810651 -335.220923)
			(xy 81.834274 -335.301377) (xy 81.850143 -335.383712) (xy 81.858113 -335.467183) (xy 81.858612 -335.509108)
			(xy 81.8581 -335.553868) (xy 81.849058 -335.642929) (xy 81.831019 -335.730611) (xy 81.804167 -335.816009)
			(xy 81.786984 -335.857342) (xy 81.783338 -335.867049) (xy 81.783341 -335.887765) (xy 81.786984 -335.897474)
			(xy 81.802748 -335.935334) (xy 81.827987 -336.013369) (xy 81.845871 -336.093411) (xy 81.856247 -336.174768)
			(xy 81.858104 -336.215736) (xy 81.858612 -336.229452) (xy 81.872836 -336.252312) (xy 81.974182 -336.306922)
			(xy 82.000852 -336.30616) (xy 82.012536 -336.299048) (xy 82.047432 -336.278305) (xy 82.120306 -336.242523)
			(xy 82.19614 -336.213534) (xy 82.2743 -336.191579) (xy 82.354137 -336.176843) (xy 82.434985 -336.169448)
			(xy 82.475578 -336.169) (xy 82.516691 -336.169534) (xy 82.598566 -336.177119) (xy 82.679391 -336.192225)
			(xy 82.758479 -336.214725) (xy 82.835153 -336.244426) (xy 82.908759 -336.281075) (xy 82.97867 -336.324359)
			(xy 83.044289 -336.373909) (xy 83.105056 -336.429302) (xy 83.160453 -336.490065) (xy 83.210007 -336.555681)
			(xy 83.253296 -336.625589) (xy 83.28995 -336.699193) (xy 83.319656 -336.775864) (xy 83.342161 -336.85495)
			(xy 83.357273 -336.935775) (xy 83.360149 -336.9668) (xy 86.931981 -336.9668) (xy 86.935971 -336.883042)
			(xy 86.947905 -336.800043) (xy 86.967674 -336.718554) (xy 86.9951 -336.639313) (xy 87.029935 -336.563039)
			(xy 87.071862 -336.490421) (xy 87.120503 -336.422117) (xy 87.175416 -336.358746) (xy 87.236104 -336.300883)
			(xy 87.302018 -336.24905) (xy 87.37256 -336.203717) (xy 87.447092 -336.165296) (xy 87.52494 -336.134133)
			(xy 87.605396 -336.110512) (xy 87.687734 -336.094645) (xy 87.771208 -336.086677) (xy 87.813134 -336.086196)
			(xy 87.850319 -336.08655) (xy 87.924427 -336.092775) (xy 87.997747 -336.105222) (xy 88.069757 -336.123801)
			(xy 88.10498 -336.135726) (xy 88.113176 -336.138249) (xy 88.130312 -336.138249) (xy 88.138508 -336.135726)
			(xy 88.183102 -336.120718) (xy 88.274708 -336.09922) (xy 88.368084 -336.087605) (xy 88.415114 -336.086196)
			(xy 88.426305 -336.085461) (xy 88.446408 -336.075565) (xy 88.460424 -336.058085) (xy 88.463628 -336.047334)
			(xy 88.472739 -336.011599) (xy 88.496138 -335.941658) (xy 88.510364 -335.907634) (xy 88.514021 -335.89793)
			(xy 88.514009 -335.877211) (xy 88.510364 -335.867502) (xy 88.493206 -335.82616) (xy 88.466376 -335.74076)
			(xy 88.448339 -335.653081) (xy 88.43928 -335.564026) (xy 88.438736 -335.519268) (xy 88.439235 -335.477343)
			(xy 88.447205 -335.393872) (xy 88.463074 -335.311537) (xy 88.486697 -335.231083) (xy 88.517861 -335.153239)
			(xy 88.556284 -335.078709) (xy 88.601617 -335.00817) (xy 88.65345 -334.942259) (xy 88.711313 -334.881573)
			(xy 88.774683 -334.826663) (xy 88.842986 -334.778025) (xy 88.915603 -334.7361) (xy 88.991876 -334.701267)
			(xy 89.071115 -334.673842) (xy 89.152601 -334.654073) (xy 89.235598 -334.64214) (xy 89.319354 -334.638151)
			(xy 89.40311 -334.64214) (xy 89.486107 -334.654073) (xy 89.567593 -334.673842) (xy 89.646832 -334.701267)
			(xy 89.723105 -334.7361) (xy 89.795722 -334.778025) (xy 89.864025 -334.826663) (xy 89.927395 -334.881573)
			(xy 89.985258 -334.942259) (xy 90.037091 -335.00817) (xy 90.082424 -335.078709) (xy 90.120847 -335.153239)
			(xy 90.152011 -335.231083) (xy 90.175634 -335.311537) (xy 90.191503 -335.393872) (xy 90.199473 -335.477343)
			(xy 90.199972 -335.519268) (xy 90.199441 -335.564027) (xy 90.190404 -335.653088) (xy 90.17237 -335.74077)
			(xy 90.145524 -335.826168) (xy 90.128344 -335.867502) (xy 90.124724 -335.877216) (xy 90.124712 -335.897925)
			(xy 90.128344 -335.907634) (xy 90.14352 -335.944017) (xy 90.168055 -336.018939) (xy 90.185802 -336.095753)
			(xy 90.196619 -336.173844) (xy 90.198956 -336.213196) (xy 90.199718 -336.226912) (xy 90.214196 -336.249518)
			(xy 90.316812 -336.302604) (xy 90.343482 -336.301334) (xy 90.355166 -336.293968) (xy 90.390919 -336.271811)
			(xy 90.465823 -336.23353) (xy 90.544005 -336.202491) (xy 90.624768 -336.178971) (xy 90.70739 -336.163179)
			(xy 90.791135 -336.155257) (xy 90.833194 -336.154776) (xy 90.874302 -336.155218) (xy 90.956167 -336.162803)
			(xy 91.036983 -336.177907) (xy 91.116061 -336.200402) (xy 91.192727 -336.230097) (xy 91.266326 -336.266738)
			(xy 91.336231 -336.310013) (xy 91.401845 -336.359552) (xy 91.46261 -336.414933) (xy 91.518006 -336.475684)
			(xy 91.567562 -336.541286) (xy 91.610854 -336.61118) (xy 91.647513 -336.68477) (xy 91.677227 -336.761428)
			(xy 91.699742 -336.840501) (xy 91.714867 -336.921313) (xy 91.722471 -337.003176) (xy 91.722641 -337.0176)
			(xy 95.263181 -337.0176) (xy 95.267171 -336.933842) (xy 95.279105 -336.850843) (xy 95.298874 -336.769354)
			(xy 95.3263 -336.690113) (xy 95.361135 -336.613839) (xy 95.403062 -336.541221) (xy 95.451703 -336.472917)
			(xy 95.506616 -336.409546) (xy 95.567304 -336.351683) (xy 95.633218 -336.29985) (xy 95.70376 -336.254517)
			(xy 95.778292 -336.216096) (xy 95.85614 -336.184933) (xy 95.936596 -336.161312) (xy 96.018934 -336.145445)
			(xy 96.102408 -336.137477) (xy 96.144334 -336.136996) (xy 96.181519 -336.13735) (xy 96.255627 -336.143575)
			(xy 96.328947 -336.156022) (xy 96.400957 -336.174601) (xy 96.43618 -336.186526) (xy 96.444376 -336.189049)
			(xy 96.461512 -336.189049) (xy 96.469708 -336.186526) (xy 96.515925 -336.171041) (xy 96.610917 -336.149172)
			(xy 96.70774 -336.137908) (xy 96.756474 -336.136996) (xy 96.767661 -336.136387) (xy 96.787899 -336.126839)
			(xy 96.802151 -336.109589) (xy 96.805496 -336.098896) (xy 96.81425 -336.066254) (xy 96.836121 -336.002303)
			(xy 96.849184 -335.971134) (xy 96.852845 -335.961431) (xy 96.852833 -335.940711) (xy 96.849184 -335.931002)
			(xy 96.832027 -335.88966) (xy 96.805196 -335.80426) (xy 96.787159 -335.716581) (xy 96.7781 -335.627526)
			(xy 96.777556 -335.582768) (xy 96.778055 -335.540843) (xy 96.786025 -335.457372) (xy 96.801894 -335.375037)
			(xy 96.825517 -335.294583) (xy 96.856681 -335.216739) (xy 96.895104 -335.142209) (xy 96.940437 -335.07167)
			(xy 96.99227 -335.005759) (xy 97.050133 -334.945073) (xy 97.113503 -334.890163) (xy 97.181806 -334.841525)
			(xy 97.254423 -334.7996) (xy 97.330696 -334.764767) (xy 97.409935 -334.737342) (xy 97.491421 -334.717573)
			(xy 97.574418 -334.70564) (xy 97.658174 -334.701651) (xy 97.74193 -334.70564) (xy 97.824927 -334.717573)
			(xy 97.906413 -334.737342) (xy 97.985652 -334.764767) (xy 98.061925 -334.7996) (xy 98.134542 -334.841525)
			(xy 98.202845 -334.890163) (xy 98.266215 -334.945073) (xy 98.324078 -335.005759) (xy 98.375911 -335.07167)
			(xy 98.421244 -335.142209) (xy 98.459667 -335.216739) (xy 98.490831 -335.294583) (xy 98.514454 -335.375037)
			(xy 98.530323 -335.457372) (xy 98.538293 -335.540843) (xy 98.538792 -335.582768) (xy 98.538268 -335.627527)
			(xy 98.52923 -335.716588) (xy 98.511194 -335.804271) (xy 98.484346 -335.889668) (xy 98.467164 -335.931002)
			(xy 98.463542 -335.940716) (xy 98.463531 -335.961426) (xy 98.467164 -335.971134) (xy 98.48433 -336.012473)
			(xy 98.511159 -336.097874) (xy 98.529194 -336.185554) (xy 98.538249 -336.27461) (xy 98.538792 -336.319368)
			(xy 98.538552 -336.350973) (xy 98.534101 -336.414026) (xy 98.529902 -336.445352) (xy 98.528378 -336.456274)
			(xy 98.53422 -336.476848) (xy 98.597466 -336.551778) (xy 98.61677 -336.561176) (xy 98.627946 -336.56143)
			(xy 98.670902 -336.563008) (xy 98.756231 -336.573428) (xy 98.840158 -336.592031) (xy 98.921898 -336.618644)
			(xy 99.00069 -336.653018) (xy 99.075799 -336.694832) (xy 99.146523 -336.743697) (xy 99.212204 -336.799156)
			(xy 99.272228 -336.860693) (xy 99.326037 -336.927733) (xy 99.373127 -336.999651) (xy 99.413059 -337.075777)
			(xy 99.445462 -337.155399) (xy 99.470033 -337.237777) (xy 99.486543 -337.32214) (xy 99.494837 -337.407702)
			(xy 99.495356 -337.450684) (xy 99.494799 -337.493394) (xy 99.486541 -337.578416) (xy 99.470184 -337.662257)
			(xy 99.44588 -337.744149) (xy 99.430332 -337.783932) (xy 99.426798 -337.793999) (xy 99.427585 -337.815303)
			(xy 99.431856 -337.82508) (xy 99.448927 -337.861382) (xy 99.477247 -337.936442) (xy 99.498691 -338.013749)
			(xy 99.513085 -338.092672) (xy 99.520312 -338.172571) (xy 99.520756 -338.212684) (xy 99.520272 -338.252763)
			(xy 99.512982 -338.33259) (xy 99.498549 -338.411439) (xy 99.488244 -338.450174) (xy 99.485843 -338.460698)
			(xy 99.489132 -338.482012) (xy 99.494594 -338.491322) (xy 99.517345 -338.52734) (xy 99.556637 -338.602937)
			(xy 99.588514 -338.681946) (xy 99.612684 -338.763644) (xy 99.628925 -338.847279) (xy 99.637089 -338.932085)
			(xy 99.637596 -338.974684) (xy 99.637001 -339.021087) (xy 99.627302 -339.113385) (xy 99.608039 -339.204171)
			(xy 99.579422 -339.292455) (xy 99.561142 -339.33511) (xy 99.557344 -339.345055) (xy 99.557338 -339.366316)
			(xy 99.561142 -339.376258) (xy 99.579397 -339.418922) (xy 99.607993 -339.507209) (xy 99.627252 -339.597991)
			(xy 99.636966 -339.690283) (xy 99.637596 -339.736684) (xy 99.637132 -339.777795) (xy 99.629546 -339.859665)
			(xy 99.614436 -339.940487) (xy 99.591932 -340.019568) (xy 99.562226 -340.096236) (xy 99.525571 -340.169835)
			(xy 99.482281 -340.239737) (xy 99.432724 -340.305345) (xy 99.377324 -340.3661) (xy 99.316553 -340.421484)
			(xy 99.25093 -340.471022) (xy 99.181016 -340.514293) (xy 99.107407 -340.550927) (xy 99.030731 -340.580612)
			(xy 98.951643 -340.603093) (xy 98.870818 -340.61818) (xy 98.788945 -340.625744) (xy 98.747834 -340.626192)
			(xy 98.704859 -340.625663) (xy 98.619309 -340.617375) (xy 98.534957 -340.600874) (xy 98.45259 -340.576313)
			(xy 98.372977 -340.543922) (xy 98.296859 -340.504001) (xy 98.224947 -340.456925) (xy 98.157912 -340.403131)
			(xy 98.096378 -340.343122) (xy 98.040919 -340.277458) (xy 98.01606 -340.242398) (xy 98.010455 -340.235056)
			(xy 97.995216 -340.224641) (xy 97.986342 -340.222078) (xy 97.94544 -340.211492) (xy 97.865683 -340.183605)
			(xy 97.788928 -340.148281) (xy 97.715869 -340.105839) (xy 97.647164 -340.05666) (xy 97.583432 -340.001188)
			(xy 97.525246 -339.939922) (xy 97.473132 -339.873416) (xy 97.427559 -339.802268) (xy 97.388937 -339.727119)
			(xy 97.357615 -339.648646) (xy 97.333875 -339.567557) (xy 97.317931 -339.484583) (xy 97.309927 -339.40047)
			(xy 97.309432 -339.358224) (xy 97.309829 -339.321956) (xy 97.315809 -339.249667) (xy 97.327648 -339.178103)
			(xy 97.336102 -339.142832) (xy 97.338139 -339.132668) (xy 97.334873 -339.11222) (xy 97.329752 -339.103208)
			(xy 97.307698 -339.067555) (xy 97.269607 -338.992868) (xy 97.238709 -338.91493) (xy 97.215277 -338.834431)
			(xy 97.199521 -338.752086) (xy 97.191579 -338.668623) (xy 97.191068 -338.626704) (xy 97.191648 -338.581935)
			(xy 97.200654 -338.49285) (xy 97.218554 -338.405119) (xy 97.245168 -338.319627) (xy 97.262188 -338.278216)
			(xy 97.265753 -338.268625) (xy 97.265754 -338.248182) (xy 97.262188 -338.238592) (xy 97.246411 -338.200279)
			(xy 97.221196 -338.121347) (xy 97.203435 -338.04041) (xy 97.193281 -337.958173) (xy 97.191576 -337.916774)
			(xy 97.190731 -337.905855) (xy 97.181081 -337.886218) (xy 97.164168 -337.872338) (xy 97.15373 -337.869022)
			(xy 97.136858 -337.864524) (xy 97.103447 -337.854361) (xy 97.086928 -337.848702) (xy 97.078732 -337.846179)
			(xy 97.061596 -337.846179) (xy 97.0534 -337.848702) (xy 97.01818 -337.860638) (xy 96.946171 -337.879227)
			(xy 96.87285 -337.89167) (xy 96.798739 -337.897878) (xy 96.761554 -337.898232) (xy 96.724369 -337.89788)
			(xy 96.650261 -337.891654) (xy 96.576941 -337.879206) (xy 96.504931 -337.860627) (xy 96.469708 -337.848702)
			(xy 96.461512 -337.846179) (xy 96.444376 -337.846179) (xy 96.43618 -337.848702) (xy 96.400962 -337.860643)
			(xy 96.328952 -337.879231) (xy 96.25563 -337.891673) (xy 96.181519 -337.897879) (xy 96.144334 -337.898232)
			(xy 96.102408 -337.897723) (xy 96.018934 -337.889755) (xy 95.936596 -337.873888) (xy 95.85614 -337.850267)
			(xy 95.778292 -337.819104) (xy 95.70376 -337.780683) (xy 95.633218 -337.73535) (xy 95.567304 -337.683517)
			(xy 95.506616 -337.625654) (xy 95.451703 -337.562283) (xy 95.403062 -337.493979) (xy 95.361135 -337.421361)
			(xy 95.3263 -337.345087) (xy 95.298874 -337.265846) (xy 95.279105 -337.184357) (xy 95.267171 -337.101358)
			(xy 95.263181 -337.0176) (xy 91.722641 -337.0176) (xy 91.722956 -337.044284) (xy 91.722404 -337.089054)
			(xy 91.71339 -337.178139) (xy 91.695482 -337.26587) (xy 91.668861 -337.351361) (xy 91.651836 -337.392772)
			(xy 91.648282 -337.402366) (xy 91.648276 -337.422805) (xy 91.651836 -337.432396) (xy 91.668872 -337.473803)
			(xy 91.695506 -337.559291) (xy 91.71341 -337.647024) (xy 91.722404 -337.736113) (xy 91.722956 -337.780884)
			(xy 91.722404 -337.825654) (xy 91.71339 -337.914739) (xy 91.695482 -338.00247) (xy 91.668861 -338.087961)
			(xy 91.651836 -338.129372) (xy 91.648282 -338.138966) (xy 91.648276 -338.159405) (xy 91.651836 -338.168996)
			(xy 91.668872 -338.210403) (xy 91.695506 -338.295891) (xy 91.71341 -338.383624) (xy 91.722404 -338.472713)
			(xy 91.722956 -338.517484) (xy 91.722432 -338.558593) (xy 91.714846 -338.64046) (xy 91.699738 -338.721278)
			(xy 91.677236 -338.800357) (xy 91.647532 -338.877021) (xy 91.610881 -338.950618) (xy 91.567594 -339.020518)
			(xy 91.518041 -339.086125) (xy 91.462645 -339.146879) (xy 91.401879 -339.202262) (xy 91.336261 -339.251801)
			(xy 91.266352 -339.295073) (xy 91.192747 -339.331709) (xy 91.116076 -339.361396) (xy 91.036993 -339.383882)
			(xy 90.956172 -339.398973) (xy 90.874303 -339.406541) (xy 90.833194 -339.406992) (xy 90.791582 -339.406536)
			(xy 90.708719 -339.398784) (xy 90.626944 -339.383319) (xy 90.546973 -339.360277) (xy 90.469506 -339.329861)
			(xy 90.395222 -339.292336) (xy 90.359738 -339.270594) (xy 90.350613 -339.265518) (xy 90.329977 -339.262466)
			(xy 90.309819 -339.267832) (xy 90.301318 -339.273896) (xy 90.267632 -339.299829) (xy 90.196195 -339.345924)
			(xy 90.120687 -339.384993) (xy 90.041797 -339.416682) (xy 89.960243 -339.440701) (xy 89.87677 -339.456831)
			(xy 89.792139 -339.464925) (xy 89.74963 -339.465412) (xy 89.708522 -339.464959) (xy 89.626657 -339.457377)
			(xy 89.545841 -339.442274) (xy 89.466762 -339.41978) (xy 89.390096 -339.390087) (xy 89.316497 -339.353447)
			(xy 89.246591 -339.310173) (xy 89.180976 -339.260635) (xy 89.120211 -339.205254) (xy 89.064815 -339.144504)
			(xy 89.015259 -339.078902) (xy 88.971967 -339.009008) (xy 88.935308 -338.935418) (xy 88.905594 -338.85876)
			(xy 88.883079 -338.779687) (xy 88.867956 -338.698875) (xy 88.860352 -338.617012) (xy 88.859868 -338.575904)
			(xy 88.860448 -338.531135) (xy 88.869454 -338.44205) (xy 88.887354 -338.354319) (xy 88.913968 -338.268827)
			(xy 88.930988 -338.227416) (xy 88.934553 -338.217825) (xy 88.934554 -338.197382) (xy 88.930988 -338.187792)
			(xy 88.915211 -338.149479) (xy 88.889996 -338.070547) (xy 88.872235 -337.98961) (xy 88.862081 -337.907373)
			(xy 88.860376 -337.865974) (xy 88.859531 -337.855055) (xy 88.849881 -337.835418) (xy 88.832968 -337.821538)
			(xy 88.82253 -337.818222) (xy 88.805658 -337.813724) (xy 88.772247 -337.803561) (xy 88.755728 -337.797902)
			(xy 88.747532 -337.795379) (xy 88.730396 -337.795379) (xy 88.7222 -337.797902) (xy 88.68698 -337.809838)
			(xy 88.614971 -337.828427) (xy 88.54165 -337.84087) (xy 88.467539 -337.847078) (xy 88.430354 -337.847432)
			(xy 88.393169 -337.84708) (xy 88.319061 -337.840854) (xy 88.245741 -337.828406) (xy 88.173731 -337.809827)
			(xy 88.138508 -337.797902) (xy 88.130312 -337.795379) (xy 88.113176 -337.795379) (xy 88.10498 -337.797902)
			(xy 88.069762 -337.809843) (xy 87.997752 -337.828431) (xy 87.92443 -337.840873) (xy 87.850319 -337.847079)
			(xy 87.813134 -337.847432) (xy 87.771208 -337.846923) (xy 87.687734 -337.838955) (xy 87.605396 -337.823088)
			(xy 87.52494 -337.799467) (xy 87.447092 -337.768304) (xy 87.37256 -337.729883) (xy 87.302018 -337.68455)
			(xy 87.236104 -337.632717) (xy 87.175416 -337.574854) (xy 87.120503 -337.511483) (xy 87.071862 -337.443179)
			(xy 87.029935 -337.370561) (xy 86.9951 -337.294287) (xy 86.967674 -337.215046) (xy 86.947905 -337.133557)
			(xy 86.935971 -337.050558) (xy 86.931981 -336.9668) (xy 83.360149 -336.9668) (xy 83.364863 -337.017649)
			(xy 83.36534 -337.058762) (xy 83.364781 -337.103532) (xy 83.35577 -337.192617) (xy 83.337863 -337.280348)
			(xy 83.311243 -337.365839) (xy 83.29422 -337.40725) (xy 83.290679 -337.416847) (xy 83.290665 -337.437283)
			(xy 83.29422 -337.446874) (xy 83.311248 -337.488284) (xy 83.337884 -337.573771) (xy 83.355791 -337.661503)
			(xy 83.364787 -337.750591) (xy 83.36534 -337.795362) (xy 83.364781 -337.840132) (xy 83.35577 -337.929217)
			(xy 83.337863 -338.016948) (xy 83.311243 -338.102439) (xy 83.29422 -338.14385) (xy 83.290679 -338.153447)
			(xy 83.290665 -338.173883) (xy 83.29422 -338.183474) (xy 83.311248 -338.224884) (xy 83.337884 -338.310371)
			(xy 83.355791 -338.398103) (xy 83.364787 -338.487191) (xy 83.36534 -338.531962) (xy 83.364865 -338.573077)
			(xy 83.357281 -338.654956) (xy 83.342174 -338.735786) (xy 83.319674 -338.814878) (xy 83.289971 -338.891556)
			(xy 83.253319 -338.965166) (xy 83.210032 -339.03508) (xy 83.160479 -339.100701) (xy 83.105082 -339.16147)
			(xy 83.044313 -339.216869) (xy 82.978693 -339.266423) (xy 82.90878 -339.309712) (xy 82.83517 -339.346364)
			(xy 82.758493 -339.376068) (xy 82.679402 -339.398571) (xy 82.598572 -339.413679) (xy 82.516693 -339.421265)
			(xy 82.475578 -339.421724) (xy 82.433963 -339.421201) (xy 82.351099 -339.413386) (xy 82.269327 -339.397871)
			(xy 82.189359 -339.374793) (xy 82.111894 -339.344353) (xy 82.037608 -339.306816) (xy 82.002122 -339.285072)
			(xy 81.993008 -339.279971) (xy 81.972363 -339.276919) (xy 81.9522 -339.282299) (xy 81.943702 -339.288374)
			(xy 81.910029 -339.314336) (xy 81.838605 -339.360476) (xy 81.763103 -339.399589) (xy 81.684213 -339.431317)
			(xy 81.602655 -339.455371) (xy 81.519173 -339.47153) (xy 81.43453 -339.479647) (xy 81.392014 -339.480144)
			(xy 81.350899 -339.479688) (xy 81.269019 -339.472102) (xy 81.188189 -339.456993) (xy 81.109097 -339.434491)
			(xy 81.032419 -339.404786) (xy 80.95881 -339.368133) (xy 80.888896 -339.324845) (xy 80.823275 -339.27529)
			(xy 80.762506 -339.219892) (xy 80.707108 -339.159122) (xy 80.657553 -339.093501) (xy 80.614265 -339.023587)
			(xy 80.577612 -338.949977) (xy 80.547908 -338.873299) (xy 80.525406 -338.794207) (xy 80.510297 -338.713377)
			(xy 80.502712 -338.631497) (xy 80.502252 -338.590382) (xy 80.502826 -338.545613) (xy 80.511834 -338.456528)
			(xy 80.529735 -338.368797) (xy 80.556351 -338.283305) (xy 80.573372 -338.241894) (xy 80.576945 -338.232306)
			(xy 80.576939 -338.211861) (xy 80.573372 -338.20227) (xy 80.557588 -338.16396) (xy 80.532375 -338.085027)
			(xy 80.514616 -338.004089) (xy 80.504464 -337.921851) (xy 80.50276 -337.880452) (xy 80.501943 -337.869528)
			(xy 80.492281 -337.84989) (xy 80.475357 -337.836012) (xy 80.464914 -337.8327) (xy 80.448042 -337.828201)
			(xy 80.414631 -337.818039) (xy 80.398112 -337.81238) (xy 80.389916 -337.809857) (xy 80.37278 -337.809857)
			(xy 80.364584 -337.81238) (xy 80.329366 -337.824336) (xy 80.257364 -337.842992) (xy 80.184043 -337.855502)
			(xy 80.109928 -337.861777) (xy 80.072738 -337.862164) (xy 80.035549 -337.861761) (xy 79.961436 -337.855475)
			(xy 79.888116 -337.842969) (xy 79.81611 -337.824332) (xy 79.780892 -337.81238) (xy 79.772696 -337.809857)
			(xy 79.75556 -337.809857) (xy 79.747364 -337.81238) (xy 79.712148 -337.824342) (xy 79.640145 -337.842996)
			(xy 79.566824 -337.855505) (xy 79.492708 -337.861778) (xy 79.455518 -337.862164) (xy 79.413579 -337.861698)
			(xy 79.330081 -337.853726) (xy 79.247718 -337.837853) (xy 79.167237 -337.814224) (xy 79.089367 -337.783051)
			(xy 79.014813 -337.744616) (xy 78.94425 -337.69927) (xy 78.878316 -337.64742) (xy 78.81761 -337.589539)
			(xy 78.762681 -337.526148) (xy 78.714027 -337.457824) (xy 78.672087 -337.385183) (xy 78.637243 -337.308885)
			(xy 78.609809 -337.229621) (xy 78.590033 -337.148107) (xy 78.578096 -337.065083) (xy 78.574105 -336.9813)
			(xy 75.005252 -336.9813) (xy 75.00928 -337.024761) (xy 75.009756 -337.065874) (xy 75.009201 -337.110644)
			(xy 75.000188 -337.199729) (xy 74.982281 -337.28746) (xy 74.95566 -337.372951) (xy 74.938636 -337.414362)
			(xy 74.935088 -337.423957) (xy 74.935078 -337.444395) (xy 74.938636 -337.453986) (xy 74.955669 -337.495394)
			(xy 74.982303 -337.580882) (xy 75.000209 -337.668615) (xy 75.009203 -337.757703) (xy 75.009756 -337.802474)
			(xy 75.009201 -337.847244) (xy 75.000188 -337.936329) (xy 74.982281 -338.02406) (xy 74.95566 -338.109551)
			(xy 74.938636 -338.150962) (xy 74.935088 -338.160557) (xy 74.935078 -338.180995) (xy 74.938636 -338.190586)
			(xy 74.955669 -338.231994) (xy 74.982303 -338.317482) (xy 75.000209 -338.405215) (xy 75.009203 -338.494303)
			(xy 75.009756 -338.539074) (xy 75.009277 -338.580189) (xy 75.001692 -338.662067) (xy 74.986584 -338.742897)
			(xy 74.964083 -338.821988) (xy 74.93438 -338.898665) (xy 74.897729 -338.972274) (xy 74.854442 -339.042187)
			(xy 74.804888 -339.107809) (xy 74.749492 -339.168577) (xy 74.688724 -339.223976) (xy 74.623104 -339.27353)
			(xy 74.553192 -339.316819) (xy 74.479583 -339.353472) (xy 74.402907 -339.383177) (xy 74.323816 -339.40568)
			(xy 74.242987 -339.420789) (xy 74.161109 -339.428376) (xy 74.119994 -339.428836) (xy 74.078379 -339.428304)
			(xy 73.995516 -339.42049) (xy 73.913744 -339.404977) (xy 73.833776 -339.3819) (xy 73.756311 -339.351462)
			(xy 73.682025 -339.313927) (xy 73.646538 -339.292184) (xy 73.637413 -339.287109) (xy 73.616777 -339.284058)
			(xy 73.596619 -339.289422) (xy 73.588118 -339.295486) (xy 73.554476 -339.321488) (xy 73.483046 -339.367625)
			(xy 73.407538 -339.406732) (xy 73.328643 -339.438455) (xy 73.24708 -339.462501) (xy 73.163594 -339.478653)
			(xy 73.078947 -339.486763) (xy 73.03643 -339.487256) (xy 72.995315 -339.486773) (xy 72.913437 -339.479188)
			(xy 72.832607 -339.464081) (xy 72.753517 -339.44158) (xy 72.67684 -339.411877) (xy 72.60323 -339.375226)
			(xy 72.533317 -339.33194) (xy 72.467696 -339.282387) (xy 72.406927 -339.22699) (xy 72.351529 -339.166223)
			(xy 72.301974 -339.100603) (xy 72.258685 -339.030691) (xy 72.222032 -338.957082) (xy 72.192327 -338.880406)
			(xy 72.169824 -338.801316) (xy 72.154715 -338.720487) (xy 72.147128 -338.638609) (xy 72.146668 -338.597494)
			(xy 72.147245 -338.552725) (xy 72.156251 -338.46364) (xy 72.174152 -338.375909) (xy 72.200767 -338.290417)
			(xy 72.217788 -338.249006) (xy 72.221359 -338.239417) (xy 72.221356 -338.218972) (xy 72.217788 -338.209382)
			(xy 72.202008 -338.17107) (xy 72.176794 -338.092137) (xy 72.159033 -338.011201) (xy 72.148881 -337.928963)
			(xy 72.147176 -337.887564) (xy 72.146339 -337.876644) (xy 72.136685 -337.857006) (xy 72.119769 -337.843127)
			(xy 72.10933 -337.839812) (xy 72.092458 -337.835314) (xy 72.059047 -337.825151) (xy 72.042528 -337.819492)
			(xy 72.034332 -337.816969) (xy 72.017196 -337.816969) (xy 72.009 -337.819492) (xy 71.973781 -337.831444)
			(xy 71.901779 -337.850101) (xy 71.828459 -337.862612) (xy 71.754344 -337.868888) (xy 71.717154 -337.869276)
			(xy 71.679965 -337.868873) (xy 71.605852 -337.862587) (xy 71.532532 -337.850082) (xy 71.460526 -337.831445)
			(xy 71.425308 -337.819492) (xy 71.417112 -337.816969) (xy 71.399976 -337.816969) (xy 71.39178 -337.819492)
			(xy 71.356562 -337.83145) (xy 71.28456 -337.850105) (xy 71.211239 -337.862615) (xy 71.137124 -337.868889)
			(xy 71.099934 -337.869276) (xy 71.057995 -337.868786) (xy 70.974497 -337.860816) (xy 70.892134 -337.844945)
			(xy 70.811653 -337.821316) (xy 70.733783 -337.790144) (xy 70.659228 -337.751711) (xy 70.588664 -337.706365)
			(xy 70.522731 -337.654517) (xy 70.462025 -337.596636) (xy 70.407095 -337.533246) (xy 70.35844 -337.464922)
			(xy 70.3165 -337.392282) (xy 70.281655 -337.315985) (xy 70.254221 -337.23672) (xy 70.234446 -337.155207)
			(xy 70.222508 -337.072183) (xy 70.218517 -336.9884) (xy 23.408386 -336.9884) (xy 23.408386 -341.9277)
			(xy 103.538816 -341.9277) (xy 103.542807 -341.843921) (xy 103.554743 -341.760902) (xy 103.574517 -341.679392)
			(xy 103.601948 -341.600131) (xy 103.63679 -341.523837) (xy 103.678726 -341.4512) (xy 103.727376 -341.382878)
			(xy 103.7823 -341.319489) (xy 103.843001 -341.261608) (xy 103.908929 -341.20976) (xy 103.979486 -341.164412)
			(xy 104.054035 -341.125977) (xy 104.131899 -341.094802) (xy 104.212375 -341.071169) (xy 104.294732 -341.055293)
			(xy 104.378225 -341.047317) (xy 104.420162 -341.046816) (xy 104.457351 -341.047215) (xy 104.531464 -341.053502)
			(xy 104.604784 -341.066008) (xy 104.67679 -341.084646) (xy 104.712008 -341.0966) (xy 104.720204 -341.099123)
			(xy 104.73734 -341.099123) (xy 104.745536 -341.0966) (xy 104.791751 -341.081107) (xy 104.886744 -341.059242)
			(xy 104.983568 -341.047981) (xy 105.032302 -341.04707) (xy 105.043494 -341.046501) (xy 105.063736 -341.036937)
			(xy 105.077985 -341.01967) (xy 105.081324 -341.00897) (xy 105.090084 -340.97633) (xy 105.111951 -340.912377)
			(xy 105.125012 -340.881208) (xy 105.128629 -340.871492) (xy 105.128644 -340.850784) (xy 105.125012 -340.841076)
			(xy 105.107848 -340.799736) (xy 105.081019 -340.714336) (xy 105.062984 -340.626656) (xy 105.053927 -340.5376)
			(xy 105.053384 -340.492842) (xy 105.053883 -340.450917) (xy 105.061853 -340.367446) (xy 105.077722 -340.285111)
			(xy 105.101345 -340.204657) (xy 105.132509 -340.126813) (xy 105.170932 -340.052283) (xy 105.216265 -339.981744)
			(xy 105.268098 -339.915833) (xy 105.325961 -339.855147) (xy 105.389331 -339.800237) (xy 105.457634 -339.751599)
			(xy 105.530251 -339.709674) (xy 105.606524 -339.674841) (xy 105.685763 -339.647416) (xy 105.767249 -339.627647)
			(xy 105.850246 -339.615714) (xy 105.934002 -339.611725) (xy 106.017758 -339.615714) (xy 106.100755 -339.627647)
			(xy 106.182241 -339.647416) (xy 106.26148 -339.674841) (xy 106.337753 -339.709674) (xy 106.41037 -339.751599)
			(xy 106.478673 -339.800237) (xy 106.542043 -339.855147) (xy 106.599906 -339.915833) (xy 106.651739 -339.981744)
			(xy 106.697072 -340.052283) (xy 106.735495 -340.126813) (xy 106.766659 -340.204657) (xy 106.790282 -340.285111)
			(xy 106.806151 -340.367446) (xy 106.814121 -340.450917) (xy 106.81462 -340.492842) (xy 106.814084 -340.537601)
			(xy 106.80505 -340.626662) (xy 106.787017 -340.714344) (xy 106.760172 -340.799742) (xy 106.742992 -340.841076)
			(xy 106.739326 -340.850777) (xy 106.739342 -340.871499) (xy 106.742992 -340.881208) (xy 106.751374 -340.901528)
			(xy 106.755013 -340.909633) (xy 106.76682 -340.92289) (xy 106.782442 -340.931323) (xy 106.800005 -340.933918)
			(xy 106.808778 -340.932516) (xy 106.852626 -340.924181) (xy 106.94144 -340.915273) (xy 106.98607 -340.914736)
			(xy 107.027176 -340.915241) (xy 107.109038 -340.922823) (xy 107.189852 -340.937924) (xy 107.268928 -340.960416)
			(xy 107.345591 -340.990108) (xy 107.419189 -341.026745) (xy 107.489092 -341.070016) (xy 107.554706 -341.119551)
			(xy 107.61547 -341.174927) (xy 107.670867 -341.235674) (xy 107.720423 -341.301272) (xy 107.763716 -341.371161)
			(xy 107.800377 -341.444747) (xy 107.830093 -341.521401) (xy 107.85261 -341.60047) (xy 107.867738 -341.681278)
			(xy 107.875346 -341.763138) (xy 107.875832 -341.804244) (xy 107.875268 -341.849014) (xy 107.866258 -341.938099)
			(xy 107.848353 -342.02583) (xy 107.821735 -342.111321) (xy 107.804712 -342.152732) (xy 107.80112 -342.162315)
			(xy 107.801136 -342.182765) (xy 107.804712 -342.192356) (xy 107.821734 -342.233768) (xy 107.848372 -342.319255)
			(xy 107.86628 -342.406986) (xy 107.875278 -342.496074) (xy 107.875832 -342.540844) (xy 107.875381 -342.579473)
			(xy 107.868636 -342.656436) (xy 107.855235 -342.732523) (xy 107.83528 -342.807159) (xy 107.822492 -342.843612)
			(xy 107.819539 -342.853049) (xy 107.820333 -342.872788) (xy 107.824016 -342.881966) (xy 107.843087 -342.925345)
			(xy 107.872921 -343.015291) (xy 107.893015 -343.1079) (xy 107.90314 -343.202122) (xy 107.903772 -343.249504)
			(xy 107.903199 -343.294273) (xy 107.894192 -343.383358) (xy 107.87629 -343.471089) (xy 107.849674 -343.556581)
			(xy 107.832652 -343.597992) (xy 107.829086 -343.607582) (xy 107.829087 -343.628025) (xy 107.832652 -343.637616)
			(xy 107.849695 -343.67902) (xy 107.876327 -343.76451) (xy 107.894229 -343.852244) (xy 107.903221 -343.941333)
			(xy 107.903772 -343.986104) (xy 107.903351 -344.027216) (xy 107.895763 -344.109088) (xy 107.880651 -344.189911)
			(xy 107.858144 -344.268995) (xy 107.828436 -344.345663) (xy 107.791778 -344.419263) (xy 107.748485 -344.489166)
			(xy 107.698925 -344.554775) (xy 107.643522 -344.61553) (xy 107.582749 -344.670913) (xy 107.517123 -344.720451)
			(xy 107.447206 -344.763721) (xy 107.373594 -344.800355) (xy 107.296916 -344.830038) (xy 107.217825 -344.852518)
			(xy 107.136997 -344.867603) (xy 107.055122 -344.875165) (xy 107.01401 -344.875612) (xy 106.971444 -344.875093)
			(xy 106.8867 -344.86696) (xy 106.803121 -344.850767) (xy 106.721472 -344.826663) (xy 106.642499 -344.794868)
			(xy 106.566926 -344.755674) (xy 106.495442 -344.709437) (xy 106.428704 -344.656583) (xy 106.367321 -344.597594)
			(xy 106.311854 -344.53301) (xy 106.262812 -344.463422) (xy 106.220644 -344.389467) (xy 106.202734 -344.350848)
			(xy 106.197093 -344.340103) (xy 106.178145 -344.324993) (xy 106.166412 -344.321892) (xy 106.123833 -344.312714)
			(xy 106.040563 -344.287147) (xy 105.960191 -344.253561) (xy 105.883487 -344.212279) (xy 105.811187 -344.163696)
			(xy 105.743982 -344.108278) (xy 105.682517 -344.046555) (xy 105.627381 -343.979119) (xy 105.579102 -343.906615)
			(xy 105.538141 -343.829739) (xy 105.504893 -343.749227) (xy 105.479675 -343.665851) (xy 105.462728 -343.580408)
			(xy 105.454216 -343.493718) (xy 105.453688 -343.450164) (xy 105.454253 -343.405394) (xy 105.463263 -343.316309)
			(xy 105.481167 -343.228578) (xy 105.507785 -343.143087) (xy 105.524808 -343.101676) (xy 105.528395 -343.092092)
			(xy 105.528382 -343.071643) (xy 105.524808 -343.062052) (xy 105.508891 -343.02338) (xy 105.483531 -342.943684)
			(xy 105.46577 -342.861957) (xy 105.460292 -342.820498) (xy 105.458698 -342.810528) (xy 105.448788 -342.792957)
			(xy 105.432839 -342.780603) (xy 105.423208 -342.777572) (xy 105.40795 -342.773353) (xy 105.377717 -342.763951)
			(xy 105.362756 -342.758776) (xy 105.35456 -342.756253) (xy 105.337424 -342.756253) (xy 105.329228 -342.758776)
			(xy 105.294015 -342.770747) (xy 105.222011 -342.789399) (xy 105.148689 -342.801905) (xy 105.074572 -342.808175)
			(xy 105.037382 -342.80856) (xy 105.000192 -342.808173) (xy 104.926079 -342.801882) (xy 104.85276 -342.789372)
			(xy 104.780754 -342.770731) (xy 104.745536 -342.758776) (xy 104.73734 -342.756253) (xy 104.720204 -342.756253)
			(xy 104.712008 -342.758776) (xy 104.676797 -342.770753) (xy 104.604792 -342.789403) (xy 104.531469 -342.801908)
			(xy 104.457353 -342.808176) (xy 104.420162 -342.80856) (xy 104.378225 -342.808083) (xy 104.294732 -342.800107)
			(xy 104.212375 -342.784231) (xy 104.131899 -342.760598) (xy 104.054035 -342.729423) (xy 103.979486 -342.690988)
			(xy 103.908929 -342.64564) (xy 103.843001 -342.593792) (xy 103.7823 -342.535911) (xy 103.727376 -342.472522)
			(xy 103.678726 -342.4042) (xy 103.63679 -342.331563) (xy 103.601948 -342.255269) (xy 103.574517 -342.176008)
			(xy 103.554743 -342.094498) (xy 103.542807 -342.011479) (xy 103.538816 -341.9277) (xy 23.408386 -341.9277)
			(xy 23.408386 -342.73109) (xy 23.408712 -342.738897) (xy 23.413502 -342.753763) (xy 23.417784 -342.7603)
			(xy 23.434038 -342.784081) (xy 23.459792 -342.835604) (xy 23.477295 -342.89048) (xy 23.486128 -342.947399)
			(xy 23.486618 -342.9762) (xy 23.486078 -343.004996) (xy 23.47722 -343.061904) (xy 23.45973 -343.116776)
			(xy 23.434022 -343.168313) (xy 23.417784 -343.1921) (xy 23.413481 -343.198627) (xy 23.40869 -343.213499)
			(xy 23.408386 -343.22131) (xy 23.408386 -345.237562) (xy 88.42502 -345.237562) (xy 88.425476 -345.196455)
			(xy 88.433064 -345.114592) (xy 88.448171 -345.033778) (xy 88.470668 -344.954703) (xy 88.500364 -344.87804)
			(xy 88.537005 -344.804443) (xy 88.58028 -344.73454) (xy 88.629818 -344.668927) (xy 88.685198 -344.608163)
			(xy 88.745947 -344.552768) (xy 88.811546 -344.503212) (xy 88.881438 -344.459919) (xy 88.955025 -344.423259)
			(xy 89.031681 -344.393542) (xy 89.110751 -344.371024) (xy 89.19156 -344.355896) (xy 89.273421 -344.348287)
			(xy 89.314528 -344.3478) (xy 89.358923 -344.348358) (xy 89.447268 -344.357247) (xy 89.534288 -344.374894)
			(xy 89.619117 -344.401123) (xy 89.660222 -344.417904) (xy 89.668919 -344.421068) (xy 89.687398 -344.421734)
			(xy 89.69629 -344.419174) (xy 89.742575 -344.404089) (xy 89.837607 -344.382956) (xy 89.934379 -344.372329)
			(xy 89.983056 -344.371676) (xy 90.021341 -344.372048) (xy 90.09763 -344.378592) (xy 90.173072 -344.391678)
			(xy 90.247108 -344.411209) (xy 90.283284 -344.423746) (xy 90.291721 -344.426397) (xy 90.309391 -344.426397)
			(xy 90.317828 -344.423746) (xy 90.35401 -344.411232) (xy 90.428049 -344.391722) (xy 90.503488 -344.378639)
			(xy 90.579773 -344.372079) (xy 90.618056 -344.371676) (xy 90.664451 -344.372276) (xy 90.756739 -344.381916)
			(xy 90.847523 -344.401107) (xy 90.935817 -344.429641) (xy 90.978482 -344.447876) (xy 90.988424 -344.451682)
			(xy 91.009688 -344.451682) (xy 91.01963 -344.447876) (xy 91.062298 -344.429645) (xy 91.150588 -344.401097)
			(xy 91.241371 -344.381901) (xy 91.33366 -344.372263) (xy 91.380056 -344.371676) (xy 91.418341 -344.372048)
			(xy 91.49463 -344.378592) (xy 91.570072 -344.391678) (xy 91.644108 -344.411209) (xy 91.680284 -344.423746)
			(xy 91.688721 -344.426397) (xy 91.706391 -344.426397) (xy 91.714828 -344.423746) (xy 91.75101 -344.411232)
			(xy 91.825049 -344.391722) (xy 91.900488 -344.378639) (xy 91.976773 -344.372079) (xy 92.015056 -344.371676)
			(xy 92.053341 -344.372048) (xy 92.12963 -344.378592) (xy 92.205072 -344.391678) (xy 92.279108 -344.411209)
			(xy 92.315284 -344.423746) (xy 92.323721 -344.426397) (xy 92.341391 -344.426397) (xy 92.349828 -344.423746)
			(xy 92.38601 -344.411232) (xy 92.460049 -344.391722) (xy 92.535488 -344.378639) (xy 92.611773 -344.372079)
			(xy 92.650056 -344.371676) (xy 92.691158 -344.372194) (xy 92.773012 -344.379775) (xy 92.853817 -344.394876)
			(xy 92.932883 -344.417369) (xy 93.009537 -344.447061) (xy 93.083125 -344.4837) (xy 93.153018 -344.526972)
			(xy 93.21862 -344.576508) (xy 93.279371 -344.631887) (xy 93.334753 -344.692634) (xy 93.384294 -344.758233)
			(xy 93.427571 -344.828123) (xy 93.464215 -344.901708) (xy 93.493912 -344.97836) (xy 93.51641 -345.057425)
			(xy 93.531517 -345.138229) (xy 93.539103 -345.220082) (xy 93.539564 -345.261184) (xy 93.53916 -345.301746)
			(xy 93.531819 -345.382537) (xy 93.517144 -345.462323) (xy 93.495255 -345.540438) (xy 93.466335 -345.616232)
			(xy 93.448886 -345.652852) (xy 93.444878 -345.661912) (xy 93.443456 -345.681655) (xy 93.446092 -345.691206)
			(xy 93.460291 -345.736227) (xy 93.480181 -345.828513) (xy 93.490178 -345.922387) (xy 93.490796 -345.96959)
			(xy 93.490238 -346.015229) (xy 93.480936 -346.106032) (xy 93.462388 -346.195406) (xy 93.44914 -346.239084)
			(xy 93.446675 -346.248093) (xy 93.44772 -346.266727) (xy 93.451172 -346.275406) (xy 93.469867 -346.318487)
			(xy 93.49915 -346.407722) (xy 93.518862 -346.499547) (xy 93.528784 -346.592938) (xy 93.529404 -346.639896)
			(xy 93.528944 -346.681007) (xy 93.521356 -346.762877) (xy 93.506246 -346.843698) (xy 93.483741 -346.92278)
			(xy 93.454034 -346.999447) (xy 93.417379 -347.073045) (xy 93.374088 -347.142947) (xy 93.324531 -347.208555)
			(xy 93.269131 -347.26931) (xy 93.20836 -347.324693) (xy 93.142737 -347.374232) (xy 93.072823 -347.417503)
			(xy 92.999214 -347.454137) (xy 92.922539 -347.483822) (xy 92.843451 -347.506304) (xy 92.762626 -347.521391)
			(xy 92.680753 -347.528955) (xy 92.639642 -347.529404) (xy 92.601357 -347.529034) (xy 92.525068 -347.52249)
			(xy 92.449626 -347.509403) (xy 92.37559 -347.489871) (xy 92.339414 -347.477334) (xy 92.330977 -347.474683)
			(xy 92.313307 -347.474683) (xy 92.30487 -347.477334) (xy 92.268688 -347.489847) (xy 92.194649 -347.509358)
			(xy 92.119209 -347.522442) (xy 92.042925 -347.529001) (xy 92.004642 -347.529404) (xy 91.961524 -347.528886)
			(xy 91.875691 -347.520542) (xy 91.79107 -347.503927) (xy 91.708455 -347.479198) (xy 91.668346 -347.463364)
			(xy 91.658975 -347.460038) (xy 91.639109 -347.460038) (xy 91.629738 -347.463364) (xy 91.589624 -347.479187)
			(xy 91.507011 -347.50392) (xy 91.422391 -347.520541) (xy 91.33656 -347.528893) (xy 91.293442 -347.529404)
			(xy 91.255157 -347.529034) (xy 91.178868 -347.52249) (xy 91.103426 -347.509403) (xy 91.02939 -347.489871)
			(xy 90.993214 -347.477334) (xy 90.984777 -347.474683) (xy 90.967107 -347.474683) (xy 90.95867 -347.477334)
			(xy 90.922488 -347.489847) (xy 90.848449 -347.509358) (xy 90.773009 -347.522442) (xy 90.696725 -347.529001)
			(xy 90.658442 -347.529404) (xy 90.620157 -347.529034) (xy 90.543868 -347.52249) (xy 90.468426 -347.509403)
			(xy 90.39439 -347.489871) (xy 90.358214 -347.477334) (xy 90.349777 -347.474683) (xy 90.332107 -347.474683)
			(xy 90.32367 -347.477334) (xy 90.287488 -347.489847) (xy 90.213449 -347.509358) (xy 90.138009 -347.522442)
			(xy 90.061725 -347.529001) (xy 90.023442 -347.529404) (xy 89.985157 -347.529034) (xy 89.908868 -347.52249)
			(xy 89.833426 -347.509403) (xy 89.75939 -347.489871) (xy 89.723214 -347.477334) (xy 89.714777 -347.474683)
			(xy 89.697107 -347.474683) (xy 89.68867 -347.477334) (xy 89.652488 -347.489847) (xy 89.578449 -347.509358)
			(xy 89.503009 -347.522442) (xy 89.426725 -347.529001) (xy 89.388442 -347.529404) (xy 89.347337 -347.528847)
			(xy 89.265478 -347.521267) (xy 89.184667 -347.506168) (xy 89.105593 -347.483678) (xy 89.028932 -347.453989)
			(xy 88.955336 -347.417355) (xy 88.885433 -347.374087) (xy 88.81982 -347.324556) (xy 88.759057 -347.269183)
			(xy 88.70366 -347.20844) (xy 88.654104 -347.142846) (xy 88.61081 -347.07296) (xy 88.574148 -346.999378)
			(xy 88.54443 -346.922728) (xy 88.52191 -346.843663) (xy 88.506779 -346.762857) (xy 88.499168 -346.681001)
			(xy 88.49868 -346.639896) (xy 88.49928 -346.594251) (xy 88.508675 -346.503445) (xy 88.527305 -346.414075)
			(xy 88.54059 -346.370402) (xy 88.543068 -346.361395) (xy 88.542016 -346.342759) (xy 88.538558 -346.33408)
			(xy 88.519895 -346.290993) (xy 88.490688 -346.201748) (xy 88.471043 -346.109924) (xy 88.461176 -346.016541)
			(xy 88.46058 -345.96959) (xy 88.460997 -345.930463) (xy 88.467845 -345.852508) (xy 88.481506 -345.775455)
			(xy 88.501874 -345.699897) (xy 88.514936 -345.663012) (xy 88.517951 -345.653293) (xy 88.516917 -345.632991)
			(xy 88.512904 -345.623642) (xy 88.496009 -345.587453) (xy 88.467989 -345.512656) (xy 88.446785 -345.43565)
			(xy 88.432566 -345.357053) (xy 88.425448 -345.277498) (xy 88.42502 -345.237562) (xy 23.408386 -345.237562)
			(xy 23.408386 -345.319096) (xy 23.408808 -345.329167) (xy 23.41652 -345.347774) (xy 23.423372 -345.355164)
			(xy 24.055578 -345.98737) (xy 24.072839 -346.00541) (xy 24.100599 -346.046903) (xy 24.119713 -346.093021)
			(xy 24.129443 -346.141986) (xy 24.13 -346.166948) (xy 24.13 -348.70949) (xy 28.410141 -348.70949)
			(xy 28.414132 -348.625708) (xy 28.426069 -348.542686) (xy 28.445844 -348.461173) (xy 28.473277 -348.38191)
			(xy 28.508121 -348.305613) (xy 28.550059 -348.232974) (xy 28.598712 -348.16465) (xy 28.65364 -348.101261)
			(xy 28.714345 -348.043379) (xy 28.780276 -347.99153) (xy 28.850838 -347.946183) (xy 28.92539 -347.907749)
			(xy 29.003259 -347.876576) (xy 29.083738 -347.852945) (xy 29.166099 -347.837072) (xy 29.249596 -347.829099)
			(xy 29.291534 -347.828616) (xy 29.328723 -347.829023) (xy 29.402836 -347.835307) (xy 29.476156 -347.847812)
			(xy 29.548162 -347.866448) (xy 29.58338 -347.8784) (xy 29.591576 -347.880923) (xy 29.608712 -347.880923)
			(xy 29.616908 -347.8784) (xy 29.658685 -347.864329) (xy 29.744376 -347.84362) (xy 29.831705 -347.831558)
			(xy 29.875734 -347.829378) (xy 29.88701 -347.828307) (xy 29.907032 -347.817779) (xy 29.920624 -347.799697)
			(xy 29.923486 -347.788738) (xy 29.932967 -347.744976) (xy 29.959558 -347.659468) (xy 29.976572 -347.61805)
			(xy 29.980113 -347.608453) (xy 29.980127 -347.588017) (xy 29.976572 -347.578426) (xy 29.959544 -347.537016)
			(xy 29.932908 -347.451529) (xy 29.915001 -347.363797) (xy 29.906005 -347.274709) (xy 29.905452 -347.229938)
			(xy 29.905888 -347.189346) (xy 29.913291 -347.108501) (xy 29.928029 -347.028666) (xy 29.949981 -346.950507)
			(xy 29.978963 -346.874673) (xy 30.014735 -346.801795) (xy 30.056998 -346.73248) (xy 30.105401 -346.667304)
			(xy 30.159542 -346.60681) (xy 30.218969 -346.5515) (xy 30.283189 -346.501836) (xy 30.351667 -346.45823)
			(xy 30.387544 -346.439236) (xy 30.396074 -346.434297) (xy 30.408824 -346.419289) (xy 30.414958 -346.400576)
			(xy 30.414722 -346.390722) (xy 30.41396 -346.365322) (xy 30.414481 -346.337437) (xy 30.422793 -346.28229)
			(xy 30.439231 -346.228998) (xy 30.463429 -346.178752) (xy 30.494845 -346.132673) (xy 30.532778 -346.091791)
			(xy 30.57638 -346.057019) (xy 30.624678 -346.029134) (xy 30.676593 -346.008759) (xy 30.730964 -345.996349)
			(xy 30.786578 -345.992182) (xy 30.842192 -345.996349) (xy 30.896563 -346.008759) (xy 30.948478 -346.029134)
			(xy 30.996776 -346.057019) (xy 31.040378 -346.091791) (xy 31.078311 -346.132673) (xy 31.109727 -346.178752)
			(xy 31.133925 -346.228998) (xy 31.150363 -346.28229) (xy 31.158675 -346.337437) (xy 31.159196 -346.365322)
			(xy 31.158688 -346.383356) (xy 31.15866 -346.393249) (xy 31.165282 -346.411875) (xy 31.178455 -346.426614)
			(xy 31.187136 -346.431362) (xy 31.224041 -346.449965) (xy 31.294555 -346.49308) (xy 31.360766 -346.542551)
			(xy 31.4221 -346.597952) (xy 31.47803 -346.658805) (xy 31.528073 -346.724585) (xy 31.571797 -346.794724)
			(xy 31.608825 -346.868616) (xy 31.638837 -346.945626) (xy 31.661575 -347.025088) (xy 31.676842 -347.106317)
			(xy 31.684507 -347.188612) (xy 31.684976 -347.229938) (xy 31.684414 -347.274708) (xy 31.675404 -347.363793)
			(xy 31.657499 -347.451524) (xy 31.630879 -347.537015) (xy 31.613856 -347.578426) (xy 31.61027 -347.58801)
			(xy 31.610284 -347.608459) (xy 31.613856 -347.61805) (xy 31.630031 -347.657368) (xy 31.655701 -347.738424)
			(xy 31.673532 -347.821557) (xy 31.68336 -347.906011) (xy 31.684722 -347.948504) (xy 31.684976 -347.96222)
			(xy 31.6992 -347.985588) (xy 31.801054 -348.040706) (xy 31.828232 -348.039944) (xy 31.84017 -348.032578)
			(xy 31.875522 -348.010993) (xy 31.949529 -347.973778) (xy 32.026677 -347.943609) (xy 32.106297 -347.920748)
			(xy 32.187699 -347.905393) (xy 32.270176 -347.897677) (xy 32.311594 -347.897196) (xy 32.352707 -347.897719)
			(xy 32.434582 -347.905305) (xy 32.515408 -347.920413) (xy 32.594495 -347.942914) (xy 32.671169 -347.972616)
			(xy 32.744775 -348.009266) (xy 32.814686 -348.05255) (xy 32.880304 -348.102101) (xy 32.941071 -348.157495)
			(xy 32.996468 -348.218259) (xy 33.046022 -348.283875) (xy 33.089311 -348.353783) (xy 33.125965 -348.427387)
			(xy 33.155671 -348.504059) (xy 33.178176 -348.583145) (xy 33.193289 -348.66397) (xy 33.197509 -348.70949)
			(xy 36.690541 -348.70949) (xy 36.694532 -348.625708) (xy 36.706469 -348.542686) (xy 36.726244 -348.461173)
			(xy 36.753677 -348.38191) (xy 36.788521 -348.305613) (xy 36.830459 -348.232974) (xy 36.879112 -348.16465)
			(xy 36.93404 -348.101261) (xy 36.994745 -348.043379) (xy 37.060676 -347.99153) (xy 37.131238 -347.946183)
			(xy 37.20579 -347.907749) (xy 37.283659 -347.876576) (xy 37.364138 -347.852945) (xy 37.446499 -347.837072)
			(xy 37.529996 -347.829099) (xy 37.571934 -347.828616) (xy 37.609123 -347.829023) (xy 37.683236 -347.835307)
			(xy 37.756556 -347.847812) (xy 37.828562 -347.866448) (xy 37.86378 -347.8784) (xy 37.871976 -347.880923)
			(xy 37.889112 -347.880923) (xy 37.897308 -347.8784) (xy 37.935448 -347.865479) (xy 38.013548 -347.845826)
			(xy 38.093117 -347.833397) (xy 38.133274 -347.830394) (xy 38.144263 -347.829135) (xy 38.163705 -347.818647)
			(xy 38.176935 -347.800955) (xy 38.179756 -347.790262) (xy 38.189168 -347.74808) (xy 38.215125 -347.665638)
			(xy 38.231572 -347.62567) (xy 38.235159 -347.616086) (xy 38.235144 -347.595637) (xy 38.231572 -347.586046)
			(xy 38.21455 -347.544634) (xy 38.187912 -347.459147) (xy 38.170004 -347.371416) (xy 38.161006 -347.282328)
			(xy 38.160452 -347.237558) (xy 38.160956 -347.195197) (xy 38.169009 -347.11086) (xy 38.185043 -347.02767)
			(xy 38.208911 -346.94638) (xy 38.240399 -346.867728) (xy 38.279221 -346.792425) (xy 38.325024 -346.721153)
			(xy 38.377395 -346.654557) (xy 38.43586 -346.593242) (xy 38.499888 -346.537761) (xy 38.5689 -346.488618)
			(xy 38.64227 -346.446258) (xy 38.719335 -346.411063) (xy 38.799397 -346.383354) (xy 38.88173 -346.36338)
			(xy 38.965589 -346.351323) (xy 39.050214 -346.347292) (xy 39.134839 -346.351323) (xy 39.218698 -346.36338)
			(xy 39.301031 -346.383354) (xy 39.381093 -346.411063) (xy 39.458158 -346.446258) (xy 39.531528 -346.488618)
			(xy 39.60054 -346.537761) (xy 39.664568 -346.593242) (xy 39.723033 -346.654557) (xy 39.775404 -346.721153)
			(xy 39.821207 -346.792425) (xy 39.860029 -346.867728) (xy 39.891517 -346.94638) (xy 39.915385 -347.02767)
			(xy 39.931419 -347.11086) (xy 39.939472 -347.195197) (xy 39.939976 -347.237558) (xy 39.939421 -347.282328)
			(xy 39.930409 -347.371413) (xy 39.912502 -347.459144) (xy 39.88588 -347.544635) (xy 39.868856 -347.586046)
			(xy 39.865315 -347.595644) (xy 39.8653 -347.61608) (xy 39.868856 -347.62567) (xy 39.885384 -347.665905)
			(xy 39.911453 -347.748896) (xy 39.92929 -347.834036) (xy 39.938724 -347.920512) (xy 39.939722 -347.963998)
			(xy 39.939976 -347.977968) (xy 39.954454 -348.001844) (xy 40.05834 -348.056454) (xy 40.08628 -348.05493)
			(xy 40.09771 -348.04731) (xy 40.134305 -348.023444) (xy 40.211348 -347.98223) (xy 40.292061 -347.948768)
			(xy 40.375665 -347.923381) (xy 40.461356 -347.906311) (xy 40.548307 -347.897725) (xy 40.591994 -347.897196)
			(xy 40.633107 -347.897719) (xy 40.714982 -347.905305) (xy 40.795808 -347.920413) (xy 40.874895 -347.942914)
			(xy 40.951569 -347.972616) (xy 41.025175 -348.009266) (xy 41.095086 -348.05255) (xy 41.160704 -348.102101)
			(xy 41.221471 -348.157495) (xy 41.276868 -348.218259) (xy 41.326422 -348.283875) (xy 41.369711 -348.353783)
			(xy 41.406365 -348.427387) (xy 41.436071 -348.504059) (xy 41.458576 -348.583145) (xy 41.473689 -348.66397)
			(xy 41.47791 -348.7095) (xy 44.996301 -348.7095) (xy 45.000292 -348.625716) (xy 45.01223 -348.54269)
			(xy 45.032006 -348.461175) (xy 45.05944 -348.381909) (xy 45.094286 -348.30561) (xy 45.136227 -348.232969)
			(xy 45.184883 -348.164644) (xy 45.239813 -348.101253) (xy 45.30052 -348.043371) (xy 45.366455 -347.991522)
			(xy 45.43702 -347.946175) (xy 45.511576 -347.907741) (xy 45.589448 -347.876568) (xy 45.66993 -347.852939)
			(xy 45.752294 -347.837068) (xy 45.835794 -347.829098) (xy 45.877734 -347.828616) (xy 45.914923 -347.829023)
			(xy 45.989036 -347.835307) (xy 46.062356 -347.847812) (xy 46.134362 -347.866448) (xy 46.16958 -347.8784)
			(xy 46.177776 -347.880923) (xy 46.194912 -347.880923) (xy 46.203108 -347.8784) (xy 46.244357 -347.864476)
			(xy 46.328947 -347.843861) (xy 46.415158 -347.831701) (xy 46.458632 -347.829378) (xy 46.469417 -347.828405)
			(xy 46.488732 -347.818658) (xy 46.502367 -347.80186) (xy 46.505622 -347.791532) (xy 46.514117 -347.760219)
			(xy 46.535095 -347.698817) (xy 46.547532 -347.66885) (xy 46.551076 -347.659253) (xy 46.55109 -347.638816)
			(xy 46.547532 -347.629226) (xy 46.530501 -347.587817) (xy 46.503866 -347.502329) (xy 46.485961 -347.414597)
			(xy 46.476965 -347.325509) (xy 46.476412 -347.280738) (xy 46.476916 -347.238377) (xy 46.484969 -347.15404)
			(xy 46.501003 -347.07085) (xy 46.524871 -346.98956) (xy 46.556359 -346.910908) (xy 46.595181 -346.835605)
			(xy 46.640984 -346.764333) (xy 46.693355 -346.697737) (xy 46.75182 -346.636422) (xy 46.815848 -346.580941)
			(xy 46.88486 -346.531798) (xy 46.95823 -346.489438) (xy 47.035295 -346.454243) (xy 47.115357 -346.426534)
			(xy 47.19769 -346.40656) (xy 47.281549 -346.394503) (xy 47.366174 -346.390472) (xy 47.450799 -346.394503)
			(xy 47.534658 -346.40656) (xy 47.616991 -346.426534) (xy 47.697053 -346.454243) (xy 47.774118 -346.489438)
			(xy 47.847488 -346.531798) (xy 47.9165 -346.580941) (xy 47.980528 -346.636422) (xy 48.038993 -346.697737)
			(xy 48.091364 -346.764333) (xy 48.137167 -346.835605) (xy 48.175989 -346.910908) (xy 48.207477 -346.98956)
			(xy 48.231345 -347.07085) (xy 48.247379 -347.15404) (xy 48.255432 -347.238377) (xy 48.255936 -347.280738)
			(xy 48.25537 -347.325508) (xy 48.24636 -347.414592) (xy 48.228456 -347.502324) (xy 48.201838 -347.587815)
			(xy 48.184816 -347.629226) (xy 48.181232 -347.638811) (xy 48.181246 -347.659259) (xy 48.184816 -347.66885)
			(xy 48.199304 -347.703977) (xy 48.222973 -347.776187) (xy 48.2404 -347.850153) (xy 48.251457 -347.925335)
			(xy 48.254158 -347.963236) (xy 48.25492 -347.976952) (xy 48.269906 -347.999558) (xy 48.372776 -348.051374)
			(xy 48.3997 -348.04985) (xy 48.41113 -348.04223) (xy 48.447343 -348.019182) (xy 48.523387 -347.979349)
			(xy 48.602912 -347.947022) (xy 48.685181 -347.922504) (xy 48.769429 -347.90602) (xy 48.854872 -347.897725)
			(xy 48.897794 -347.897196) (xy 48.938907 -347.897719) (xy 49.020782 -347.905305) (xy 49.101608 -347.920413)
			(xy 49.180695 -347.942914) (xy 49.257369 -347.972616) (xy 49.330975 -348.009266) (xy 49.400886 -348.05255)
			(xy 49.466504 -348.102101) (xy 49.527271 -348.157495) (xy 49.582668 -348.218259) (xy 49.632222 -348.283875)
			(xy 49.675511 -348.353783) (xy 49.712165 -348.427387) (xy 49.741871 -348.504059) (xy 49.764376 -348.583145)
			(xy 49.779489 -348.66397) (xy 49.78371 -348.7095) (xy 53.352901 -348.7095) (xy 53.356892 -348.625716)
			(xy 53.36883 -348.54269) (xy 53.388606 -348.461175) (xy 53.41604 -348.381909) (xy 53.450886 -348.30561)
			(xy 53.492827 -348.232969) (xy 53.541483 -348.164644) (xy 53.596413 -348.101253) (xy 53.65712 -348.043371)
			(xy 53.723055 -347.991522) (xy 53.79362 -347.946175) (xy 53.868176 -347.907741) (xy 53.946048 -347.876568)
			(xy 54.02653 -347.852939) (xy 54.108894 -347.837068) (xy 54.192394 -347.829098) (xy 54.234334 -347.828616)
			(xy 54.271523 -347.829023) (xy 54.345636 -347.835307) (xy 54.418956 -347.847812) (xy 54.490962 -347.866448)
			(xy 54.52618 -347.8784) (xy 54.534376 -347.880923) (xy 54.551512 -347.880923) (xy 54.559708 -347.8784)
			(xy 54.600957 -347.864476) (xy 54.685547 -347.843861) (xy 54.771758 -347.831701) (xy 54.815232 -347.829378)
			(xy 54.826186 -347.828354) (xy 54.84574 -347.818319) (xy 54.859356 -347.801066) (xy 54.862476 -347.790516)
			(xy 54.871519 -347.754203) (xy 54.894919 -347.683115) (xy 54.909212 -347.64853) (xy 54.912768 -347.638937)
			(xy 54.912774 -347.618496) (xy 54.909212 -347.608906) (xy 54.892173 -347.5675) (xy 54.865541 -347.482011)
			(xy 54.847637 -347.394278) (xy 54.838644 -347.305189) (xy 54.838092 -347.260418) (xy 54.838596 -347.218057)
			(xy 54.846649 -347.13372) (xy 54.862683 -347.05053) (xy 54.886551 -346.96924) (xy 54.918039 -346.890588)
			(xy 54.956861 -346.815285) (xy 55.002664 -346.744013) (xy 55.055035 -346.677417) (xy 55.1135 -346.616102)
			(xy 55.177528 -346.560621) (xy 55.24654 -346.511478) (xy 55.31991 -346.469118) (xy 55.396975 -346.433923)
			(xy 55.477037 -346.406214) (xy 55.55937 -346.38624) (xy 55.643229 -346.374183) (xy 55.727854 -346.370152)
			(xy 55.812479 -346.374183) (xy 55.896338 -346.38624) (xy 55.978671 -346.406214) (xy 56.058733 -346.433923)
			(xy 56.135798 -346.469118) (xy 56.209168 -346.511478) (xy 56.27818 -346.560621) (xy 56.342208 -346.616102)
			(xy 56.400673 -346.677417) (xy 56.453044 -346.744013) (xy 56.498847 -346.815285) (xy 56.537669 -346.890588)
			(xy 56.569157 -346.96924) (xy 56.593025 -347.05053) (xy 56.609059 -347.13372) (xy 56.617112 -347.218057)
			(xy 56.617616 -347.260418) (xy 56.617044 -347.305187) (xy 56.608037 -347.394272) (xy 56.590134 -347.482003)
			(xy 56.563518 -347.567495) (xy 56.546496 -347.608906) (xy 56.542919 -347.618493) (xy 56.542926 -347.63894)
			(xy 56.546496 -347.64853) (xy 56.561684 -347.685398) (xy 56.586189 -347.761282) (xy 56.603812 -347.839053)
			(xy 56.614411 -347.918088) (xy 56.6166 -347.957902) (xy 56.617108 -347.971364) (xy 56.63184 -347.994478)
			(xy 56.734456 -348.04731) (xy 56.761634 -348.04604) (xy 56.773064 -348.038674) (xy 56.808981 -348.016152)
			(xy 56.88432 -347.977266) (xy 56.963017 -347.945725) (xy 57.044358 -347.921816) (xy 57.127605 -347.905754)
			(xy 57.212003 -347.897686) (xy 57.254394 -347.897196) (xy 57.295507 -347.897719) (xy 57.377382 -347.905305)
			(xy 57.458208 -347.920413) (xy 57.537295 -347.942914) (xy 57.613969 -347.972616) (xy 57.687575 -348.009266)
			(xy 57.757486 -348.05255) (xy 57.823104 -348.102101) (xy 57.883871 -348.157495) (xy 57.939268 -348.218259)
			(xy 57.988822 -348.283875) (xy 58.032111 -348.353783) (xy 58.068765 -348.427387) (xy 58.098471 -348.504059)
			(xy 58.120976 -348.583145) (xy 58.136089 -348.66397) (xy 58.14031 -348.7095) (xy 61.684101 -348.7095)
			(xy 61.688092 -348.625716) (xy 61.70003 -348.54269) (xy 61.719806 -348.461175) (xy 61.74724 -348.381909)
			(xy 61.782086 -348.30561) (xy 61.824027 -348.232969) (xy 61.872683 -348.164644) (xy 61.927613 -348.101253)
			(xy 61.98832 -348.043371) (xy 62.054255 -347.991522) (xy 62.12482 -347.946175) (xy 62.199376 -347.907741)
			(xy 62.277248 -347.876568) (xy 62.35773 -347.852939) (xy 62.440094 -347.837068) (xy 62.523594 -347.829098)
			(xy 62.565534 -347.828616) (xy 62.602723 -347.829023) (xy 62.676836 -347.835307) (xy 62.750156 -347.847812)
			(xy 62.822162 -347.866448) (xy 62.85738 -347.8784) (xy 62.865576 -347.880923) (xy 62.882712 -347.880923)
			(xy 62.890908 -347.8784) (xy 62.93563 -347.863377) (xy 63.027487 -347.841848) (xy 63.121119 -347.830251)
			(xy 63.168276 -347.82887) (xy 63.179057 -347.82822) (xy 63.198555 -347.818959) (xy 63.212545 -347.802521)
			(xy 63.216028 -347.792294) (xy 63.223799 -347.76642) (xy 63.242101 -347.715585) (xy 63.252604 -347.690694)
			(xy 63.256229 -347.680981) (xy 63.25624 -347.66027) (xy 63.252604 -347.650562) (xy 63.235435 -347.609224)
			(xy 63.208608 -347.523823) (xy 63.190573 -347.436143) (xy 63.181518 -347.347086) (xy 63.180976 -347.302328)
			(xy 63.181475 -347.260403) (xy 63.189445 -347.176932) (xy 63.205314 -347.094597) (xy 63.228937 -347.014143)
			(xy 63.260101 -346.936299) (xy 63.298524 -346.861769) (xy 63.343857 -346.79123) (xy 63.39569 -346.725319)
			(xy 63.453553 -346.664633) (xy 63.516923 -346.609723) (xy 63.585226 -346.561085) (xy 63.657843 -346.51916)
			(xy 63.734116 -346.484327) (xy 63.813355 -346.456902) (xy 63.894841 -346.437133) (xy 63.977838 -346.4252)
			(xy 64.061594 -346.421211) (xy 64.14535 -346.4252) (xy 64.228347 -346.437133) (xy 64.309833 -346.456902)
			(xy 64.389072 -346.484327) (xy 64.465345 -346.51916) (xy 64.537962 -346.561085) (xy 64.606265 -346.609723)
			(xy 64.669635 -346.664633) (xy 64.727498 -346.725319) (xy 64.779331 -346.79123) (xy 64.824664 -346.861769)
			(xy 64.863087 -346.936299) (xy 64.894251 -347.014143) (xy 64.917874 -347.094597) (xy 64.933743 -347.176932)
			(xy 64.941713 -347.260403) (xy 64.942212 -347.302328) (xy 64.941672 -347.347087) (xy 64.932639 -347.436147)
			(xy 64.914607 -347.52383) (xy 64.887763 -347.609228) (xy 64.870584 -347.650562) (xy 64.866927 -347.660266)
			(xy 64.866937 -347.680985) (xy 64.870584 -347.690694) (xy 64.888862 -347.734789) (xy 64.91689 -347.826038)
			(xy 64.934892 -347.919782) (xy 64.939418 -347.9673) (xy 64.940434 -347.980762) (xy 64.95542 -348.00286)
			(xy 65.058544 -348.053152) (xy 65.08496 -348.051374) (xy 65.096644 -348.043754) (xy 65.132959 -348.020439)
			(xy 65.209305 -347.980191) (xy 65.289189 -347.947525) (xy 65.371861 -347.922748) (xy 65.456544 -347.906093)
			(xy 65.542442 -347.897716) (xy 65.585594 -347.897196) (xy 65.626707 -347.897719) (xy 65.708582 -347.905305)
			(xy 65.789408 -347.920413) (xy 65.868495 -347.942914) (xy 65.945169 -347.972616) (xy 66.018775 -348.009266)
			(xy 66.088686 -348.05255) (xy 66.154304 -348.102101) (xy 66.215071 -348.157495) (xy 66.270468 -348.218259)
			(xy 66.320022 -348.283875) (xy 66.363311 -348.353783) (xy 66.399965 -348.427387) (xy 66.429671 -348.504059)
			(xy 66.452176 -348.583145) (xy 66.467289 -348.66397) (xy 66.474879 -348.745845) (xy 66.475356 -348.786958)
			(xy 66.474795 -348.831728) (xy 66.467942 -348.89948) (xy 81.294224 -348.89948) (xy 81.294687 -348.858913)
			(xy 81.30208 -348.778118) (xy 81.316804 -348.698332) (xy 81.338734 -348.620219) (xy 81.36769 -348.544429)
			(xy 81.385156 -348.507812) (xy 81.389129 -348.49874) (xy 81.390571 -348.479008) (xy 81.38795 -348.469458)
			(xy 81.37371 -348.424443) (xy 81.353732 -348.332162) (xy 81.343651 -348.238283) (xy 81.342992 -348.191074)
			(xy 81.343496 -348.148713) (xy 81.351549 -348.064376) (xy 81.367583 -347.981186) (xy 81.391451 -347.899896)
			(xy 81.422939 -347.821244) (xy 81.461761 -347.745941) (xy 81.507564 -347.674669) (xy 81.559935 -347.608073)
			(xy 81.6184 -347.546758) (xy 81.682428 -347.491277) (xy 81.75144 -347.442134) (xy 81.82481 -347.399774)
			(xy 81.901875 -347.364579) (xy 81.981937 -347.33687) (xy 82.06427 -347.316896) (xy 82.148129 -347.304839)
			(xy 82.232754 -347.300808) (xy 82.317379 -347.304839) (xy 82.401238 -347.316896) (xy 82.483571 -347.33687)
			(xy 82.563633 -347.364579) (xy 82.640698 -347.399774) (xy 82.714068 -347.442134) (xy 82.78308 -347.491277)
			(xy 82.847108 -347.546758) (xy 82.905573 -347.608073) (xy 82.957944 -347.674669) (xy 83.003747 -347.745941)
			(xy 83.042569 -347.821244) (xy 83.074057 -347.899896) (xy 83.097925 -347.981186) (xy 83.113959 -348.064376)
			(xy 83.122012 -348.148713) (xy 83.122516 -348.191074) (xy 83.12207 -348.231641) (xy 83.114672 -348.312437)
			(xy 83.099945 -348.392223) (xy 83.07801 -348.470336) (xy 83.049051 -348.546125) (xy 83.031584 -348.582742)
			(xy 83.027581 -348.591804) (xy 83.026156 -348.611545) (xy 83.02879 -348.621096) (xy 83.043017 -348.666115)
			(xy 83.063 -348.758394) (xy 83.073086 -348.852272) (xy 83.073748 -348.89948) (xy 83.073141 -348.945125)
			(xy 83.063748 -349.035931) (xy 83.045121 -349.1253) (xy 83.031838 -349.168974) (xy 83.029379 -349.177985)
			(xy 83.03042 -349.196616) (xy 83.03387 -349.205296) (xy 83.052527 -349.248385) (xy 83.081735 -349.337629)
			(xy 83.101382 -349.429453) (xy 83.111251 -349.522835) (xy 83.111848 -349.569786) (xy 83.111412 -349.610119)
			(xy 83.104141 -349.690457) (xy 83.08963 -349.769807) (xy 83.067997 -349.847519) (xy 83.039422 -349.922954)
			(xy 83.022186 -349.959422) (xy 83.017736 -349.970094) (xy 83.017755 -349.993189) (xy 83.022186 -350.003872)
			(xy 83.039408 -350.040291) (xy 83.067973 -350.115623) (xy 83.089602 -350.193232) (xy 83.104117 -350.27248)
			(xy 83.111401 -350.352717) (xy 83.111848 -350.393) (xy 83.111344 -350.435361) (xy 83.103291 -350.519698)
			(xy 83.087257 -350.602888) (xy 83.063389 -350.684178) (xy 83.031901 -350.76283) (xy 82.993079 -350.838133)
			(xy 82.947276 -350.909405) (xy 82.894905 -350.976001) (xy 82.83644 -351.037316) (xy 82.772412 -351.092797)
			(xy 82.7034 -351.14194) (xy 82.63003 -351.1843) (xy 82.552965 -351.219495) (xy 82.472903 -351.247204)
			(xy 82.39057 -351.267178) (xy 82.306711 -351.279235) (xy 82.222086 -351.283267) (xy 82.137461 -351.279235)
			(xy 82.053602 -351.267178) (xy 81.971269 -351.247204) (xy 81.891207 -351.219495) (xy 81.814142 -351.1843)
			(xy 81.740772 -351.14194) (xy 81.67176 -351.092797) (xy 81.607732 -351.037316) (xy 81.549267 -350.976001)
			(xy 81.496896 -350.909405) (xy 81.451093 -350.838133) (xy 81.412271 -350.76283) (xy 81.380783 -350.684178)
			(xy 81.356915 -350.602888) (xy 81.340881 -350.519698) (xy 81.332828 -350.435361) (xy 81.332324 -350.393)
			(xy 81.332778 -350.35266) (xy 81.340081 -350.272312) (xy 81.354637 -350.192956) (xy 81.376326 -350.115246)
			(xy 81.404968 -350.039822) (xy 81.42224 -350.003364) (xy 81.426812 -349.992711) (xy 81.426828 -349.969558)
			(xy 81.42224 -349.958914) (xy 81.405059 -349.922483) (xy 81.376548 -349.847143) (xy 81.35497 -349.769534)
			(xy 81.340501 -349.69029) (xy 81.33326 -349.610063) (xy 81.332832 -349.569786) (xy 81.333382 -349.524146)
			(xy 81.342687 -349.433343) (xy 81.361239 -349.34397) (xy 81.374488 -349.300292) (xy 81.376971 -349.291286)
			(xy 81.375916 -349.272649) (xy 81.372456 -349.26397) (xy 81.353748 -349.220894) (xy 81.32447 -349.131657)
			(xy 81.304762 -349.039831) (xy 81.294843 -348.946439) (xy 81.294224 -348.89948) (xy 66.467942 -348.89948)
			(xy 66.465784 -348.920813) (xy 66.447878 -349.008544) (xy 66.421259 -349.094035) (xy 66.404236 -349.135446)
			(xy 66.400697 -349.145044) (xy 66.400681 -349.16548) (xy 66.404236 -349.17507) (xy 66.421263 -349.21648)
			(xy 66.4479 -349.301967) (xy 66.465806 -349.3897) (xy 66.474803 -349.478787) (xy 66.475356 -349.523558)
			(xy 66.474795 -349.568328) (xy 66.465784 -349.657413) (xy 66.447878 -349.745144) (xy 66.421259 -349.830635)
			(xy 66.404236 -349.872046) (xy 66.400697 -349.881644) (xy 66.400681 -349.90208) (xy 66.404236 -349.91167)
			(xy 66.421263 -349.95308) (xy 66.4479 -350.038567) (xy 66.465806 -350.1263) (xy 66.474803 -350.215387)
			(xy 66.475356 -350.260158) (xy 66.474861 -350.301272) (xy 66.467278 -350.383151) (xy 66.452172 -350.46398)
			(xy 66.429672 -350.54307) (xy 66.39997 -350.619748) (xy 66.36332 -350.693357) (xy 66.320034 -350.76327)
			(xy 66.270482 -350.828891) (xy 66.215086 -350.88966) (xy 66.154319 -350.945059) (xy 66.0887 -350.994614)
			(xy 66.018788 -351.037902) (xy 65.94518 -351.074555) (xy 65.868505 -351.10426) (xy 65.789415 -351.126764)
			(xy 65.708586 -351.141873) (xy 65.626708 -351.14946) (xy 65.585594 -351.14992) (xy 65.543979 -351.14939)
			(xy 65.461116 -351.141576) (xy 65.379344 -351.126063) (xy 65.299376 -351.102986) (xy 65.221911 -351.072547)
			(xy 65.147624 -351.035012) (xy 65.112138 -351.013268) (xy 65.103017 -351.008182) (xy 65.082377 -351.005125)
			(xy 65.062216 -351.010498) (xy 65.053718 -351.01657) (xy 65.020074 -351.04257) (xy 64.948645 -351.088707)
			(xy 64.873137 -351.127815) (xy 64.794242 -351.159538) (xy 64.712679 -351.183585) (xy 64.629193 -351.199737)
			(xy 64.544547 -351.207847) (xy 64.50203 -351.20834) (xy 64.460915 -351.207873) (xy 64.379035 -351.200288)
			(xy 64.298205 -351.185181) (xy 64.219114 -351.162679) (xy 64.142436 -351.132976) (xy 64.068826 -351.096324)
			(xy 63.998912 -351.053036) (xy 63.93329 -351.003482) (xy 63.872521 -350.948084) (xy 63.817123 -350.887316)
			(xy 63.767568 -350.821695) (xy 63.72428 -350.751781) (xy 63.687628 -350.678172) (xy 63.657923 -350.601494)
			(xy 63.635421 -350.522403) (xy 63.620313 -350.441573) (xy 63.612727 -350.359693) (xy 63.612268 -350.318578)
			(xy 63.61284 -350.273809) (xy 63.621847 -350.184724) (xy 63.63975 -350.096993) (xy 63.666366 -350.011501)
			(xy 63.683388 -349.97009) (xy 63.686968 -349.960503) (xy 63.68696 -349.940056) (xy 63.683388 -349.930466)
			(xy 63.667603 -349.892156) (xy 63.642391 -349.813223) (xy 63.624631 -349.732285) (xy 63.61448 -349.650047)
			(xy 63.612776 -349.608648) (xy 63.61195 -349.597726) (xy 63.602291 -349.578089) (xy 63.585371 -349.56421)
			(xy 63.57493 -349.560896) (xy 63.558058 -349.556397) (xy 63.524647 -349.546235) (xy 63.508128 -349.540576)
			(xy 63.499932 -349.538053) (xy 63.482796 -349.538053) (xy 63.4746 -349.540576) (xy 63.43938 -349.552528)
			(xy 63.367379 -349.571185) (xy 63.294059 -349.583696) (xy 63.219944 -349.589972) (xy 63.182754 -349.59036)
			(xy 63.145565 -349.589952) (xy 63.071452 -349.583667) (xy 62.998133 -349.571163) (xy 62.926126 -349.552528)
			(xy 62.890908 -349.540576) (xy 62.882712 -349.538053) (xy 62.865576 -349.538053) (xy 62.85738 -349.540576)
			(xy 62.822162 -349.552533) (xy 62.75016 -349.571189) (xy 62.676839 -349.583699) (xy 62.602724 -349.589973)
			(xy 62.565534 -349.59036) (xy 62.523594 -349.589902) (xy 62.440094 -349.581932) (xy 62.35773 -349.566061)
			(xy 62.277248 -349.542432) (xy 62.199376 -349.511259) (xy 62.12482 -349.472825) (xy 62.054255 -349.427478)
			(xy 61.98832 -349.375629) (xy 61.927613 -349.317747) (xy 61.872683 -349.254356) (xy 61.824027 -349.186031)
			(xy 61.782086 -349.11339) (xy 61.74724 -349.037091) (xy 61.719806 -348.957825) (xy 61.70003 -348.87631)
			(xy 61.688092 -348.793284) (xy 61.684101 -348.7095) (xy 58.14031 -348.7095) (xy 58.143679 -348.745845)
			(xy 58.144156 -348.786958) (xy 58.143595 -348.831728) (xy 58.134584 -348.920813) (xy 58.116678 -349.008544)
			(xy 58.090059 -349.094035) (xy 58.073036 -349.135446) (xy 58.069497 -349.145044) (xy 58.069481 -349.16548)
			(xy 58.073036 -349.17507) (xy 58.090063 -349.21648) (xy 58.1167 -349.301967) (xy 58.134606 -349.3897)
			(xy 58.143603 -349.478787) (xy 58.144156 -349.523558) (xy 58.143595 -349.568328) (xy 58.134584 -349.657413)
			(xy 58.116678 -349.745144) (xy 58.090059 -349.830635) (xy 58.073036 -349.872046) (xy 58.069497 -349.881644)
			(xy 58.069481 -349.90208) (xy 58.073036 -349.91167) (xy 58.090063 -349.95308) (xy 58.1167 -350.038567)
			(xy 58.134606 -350.1263) (xy 58.143603 -350.215387) (xy 58.144156 -350.260158) (xy 58.143661 -350.301272)
			(xy 58.136078 -350.383151) (xy 58.120972 -350.46398) (xy 58.098472 -350.54307) (xy 58.06877 -350.619748)
			(xy 58.03212 -350.693357) (xy 57.988834 -350.76327) (xy 57.939282 -350.828891) (xy 57.883886 -350.88966)
			(xy 57.823119 -350.945059) (xy 57.7575 -350.994614) (xy 57.687588 -351.037902) (xy 57.61398 -351.074555)
			(xy 57.537305 -351.10426) (xy 57.458215 -351.126764) (xy 57.377386 -351.141873) (xy 57.295508 -351.14946)
			(xy 57.254394 -351.14992) (xy 57.212779 -351.14939) (xy 57.129916 -351.141576) (xy 57.048144 -351.126063)
			(xy 56.968176 -351.102986) (xy 56.890711 -351.072547) (xy 56.816424 -351.035012) (xy 56.780938 -351.013268)
			(xy 56.771817 -351.008182) (xy 56.751177 -351.005125) (xy 56.731016 -351.010498) (xy 56.722518 -351.01657)
			(xy 56.688874 -351.04257) (xy 56.617445 -351.088707) (xy 56.541937 -351.127815) (xy 56.463042 -351.159538)
			(xy 56.381479 -351.183585) (xy 56.297993 -351.199737) (xy 56.213347 -351.207847) (xy 56.17083 -351.20834)
			(xy 56.129715 -351.207873) (xy 56.047835 -351.200288) (xy 55.967005 -351.185181) (xy 55.887914 -351.162679)
			(xy 55.811236 -351.132976) (xy 55.737626 -351.096324) (xy 55.667712 -351.053036) (xy 55.60209 -351.003482)
			(xy 55.541321 -350.948084) (xy 55.485923 -350.887316) (xy 55.436368 -350.821695) (xy 55.39308 -350.751781)
			(xy 55.356428 -350.678172) (xy 55.326723 -350.601494) (xy 55.304221 -350.522403) (xy 55.289113 -350.441573)
			(xy 55.281527 -350.359693) (xy 55.281068 -350.318578) (xy 55.28164 -350.273809) (xy 55.290647 -350.184724)
			(xy 55.30855 -350.096993) (xy 55.335166 -350.011501) (xy 55.352188 -349.97009) (xy 55.355768 -349.960503)
			(xy 55.35576 -349.940056) (xy 55.352188 -349.930466) (xy 55.336403 -349.892156) (xy 55.311191 -349.813223)
			(xy 55.293431 -349.732285) (xy 55.28328 -349.650047) (xy 55.281576 -349.608648) (xy 55.28075 -349.597726)
			(xy 55.271091 -349.578089) (xy 55.254171 -349.56421) (xy 55.24373 -349.560896) (xy 55.226858 -349.556397)
			(xy 55.193447 -349.546235) (xy 55.176928 -349.540576) (xy 55.168732 -349.538053) (xy 55.151596 -349.538053)
			(xy 55.1434 -349.540576) (xy 55.10818 -349.552528) (xy 55.036179 -349.571185) (xy 54.962859 -349.583696)
			(xy 54.888744 -349.589972) (xy 54.851554 -349.59036) (xy 54.814365 -349.589952) (xy 54.740252 -349.583667)
			(xy 54.666933 -349.571163) (xy 54.594926 -349.552528) (xy 54.559708 -349.540576) (xy 54.551512 -349.538053)
			(xy 54.534376 -349.538053) (xy 54.52618 -349.540576) (xy 54.490962 -349.552533) (xy 54.41896 -349.571189)
			(xy 54.345639 -349.583699) (xy 54.271524 -349.589973) (xy 54.234334 -349.59036) (xy 54.192394 -349.589902)
			(xy 54.108894 -349.581932) (xy 54.02653 -349.566061) (xy 53.946048 -349.542432) (xy 53.868176 -349.511259)
			(xy 53.79362 -349.472825) (xy 53.723055 -349.427478) (xy 53.65712 -349.375629) (xy 53.596413 -349.317747)
			(xy 53.541483 -349.254356) (xy 53.492827 -349.186031) (xy 53.450886 -349.11339) (xy 53.41604 -349.037091)
			(xy 53.388606 -348.957825) (xy 53.36883 -348.87631) (xy 53.356892 -348.793284) (xy 53.352901 -348.7095)
			(xy 49.78371 -348.7095) (xy 49.787079 -348.745845) (xy 49.787556 -348.786958) (xy 49.786995 -348.831728)
			(xy 49.777984 -348.920813) (xy 49.760078 -349.008544) (xy 49.733459 -349.094035) (xy 49.716436 -349.135446)
			(xy 49.712897 -349.145044) (xy 49.712881 -349.16548) (xy 49.716436 -349.17507) (xy 49.733463 -349.21648)
			(xy 49.7601 -349.301967) (xy 49.778006 -349.3897) (xy 49.787003 -349.478787) (xy 49.787556 -349.523558)
			(xy 49.786995 -349.568328) (xy 49.777984 -349.657413) (xy 49.760078 -349.745144) (xy 49.733459 -349.830635)
			(xy 49.716436 -349.872046) (xy 49.712897 -349.881644) (xy 49.712881 -349.90208) (xy 49.716436 -349.91167)
			(xy 49.733463 -349.95308) (xy 49.7601 -350.038567) (xy 49.778006 -350.1263) (xy 49.787003 -350.215387)
			(xy 49.787556 -350.260158) (xy 49.787061 -350.301272) (xy 49.779478 -350.383151) (xy 49.764372 -350.46398)
			(xy 49.741872 -350.54307) (xy 49.71217 -350.619748) (xy 49.67552 -350.693357) (xy 49.632234 -350.76327)
			(xy 49.582682 -350.828891) (xy 49.527286 -350.88966) (xy 49.466519 -350.945059) (xy 49.4009 -350.994614)
			(xy 49.330988 -351.037902) (xy 49.25738 -351.074555) (xy 49.180705 -351.10426) (xy 49.101615 -351.126764)
			(xy 49.020786 -351.141873) (xy 48.938908 -351.14946) (xy 48.897794 -351.14992) (xy 48.856179 -351.14939)
			(xy 48.773316 -351.141576) (xy 48.691544 -351.126063) (xy 48.611576 -351.102986) (xy 48.534111 -351.072547)
			(xy 48.459824 -351.035012) (xy 48.424338 -351.013268) (xy 48.415217 -351.008182) (xy 48.394577 -351.005125)
			(xy 48.374416 -351.010498) (xy 48.365918 -351.01657) (xy 48.332274 -351.04257) (xy 48.260845 -351.088707)
			(xy 48.185337 -351.127815) (xy 48.106442 -351.159538) (xy 48.024879 -351.183585) (xy 47.941393 -351.199737)
			(xy 47.856747 -351.207847) (xy 47.81423 -351.20834) (xy 47.773115 -351.207873) (xy 47.691235 -351.200288)
			(xy 47.610405 -351.185181) (xy 47.531314 -351.162679) (xy 47.454636 -351.132976) (xy 47.381026 -351.096324)
			(xy 47.311112 -351.053036) (xy 47.24549 -351.003482) (xy 47.184721 -350.948084) (xy 47.129323 -350.887316)
			(xy 47.079768 -350.821695) (xy 47.03648 -350.751781) (xy 46.999828 -350.678172) (xy 46.970123 -350.601494)
			(xy 46.947621 -350.522403) (xy 46.932513 -350.441573) (xy 46.924927 -350.359693) (xy 46.924468 -350.318578)
			(xy 46.92504 -350.273809) (xy 46.934047 -350.184724) (xy 46.95195 -350.096993) (xy 46.978566 -350.011501)
			(xy 46.995588 -349.97009) (xy 46.999168 -349.960503) (xy 46.99916 -349.940056) (xy 46.995588 -349.930466)
			(xy 46.979803 -349.892156) (xy 46.954591 -349.813223) (xy 46.936831 -349.732285) (xy 46.92668 -349.650047)
			(xy 46.924976 -349.608648) (xy 46.92415 -349.597726) (xy 46.914491 -349.578089) (xy 46.897571 -349.56421)
			(xy 46.88713 -349.560896) (xy 46.870258 -349.556397) (xy 46.836847 -349.546235) (xy 46.820328 -349.540576)
			(xy 46.812132 -349.538053) (xy 46.794996 -349.538053) (xy 46.7868 -349.540576) (xy 46.75158 -349.552528)
			(xy 46.679579 -349.571185) (xy 46.606259 -349.583696) (xy 46.532144 -349.589972) (xy 46.494954 -349.59036)
			(xy 46.457765 -349.589952) (xy 46.383652 -349.583667) (xy 46.310333 -349.571163) (xy 46.238326 -349.552528)
			(xy 46.203108 -349.540576) (xy 46.194912 -349.538053) (xy 46.177776 -349.538053) (xy 46.16958 -349.540576)
			(xy 46.134362 -349.552533) (xy 46.06236 -349.571189) (xy 45.989039 -349.583699) (xy 45.914924 -349.589973)
			(xy 45.877734 -349.59036) (xy 45.835794 -349.589902) (xy 45.752294 -349.581932) (xy 45.66993 -349.566061)
			(xy 45.589448 -349.542432) (xy 45.511576 -349.511259) (xy 45.43702 -349.472825) (xy 45.366455 -349.427478)
			(xy 45.30052 -349.375629) (xy 45.239813 -349.317747) (xy 45.184883 -349.254356) (xy 45.136227 -349.186031)
			(xy 45.094286 -349.11339) (xy 45.05944 -349.037091) (xy 45.032006 -348.957825) (xy 45.01223 -348.87631)
			(xy 45.000292 -348.793284) (xy 44.996301 -348.7095) (xy 41.47791 -348.7095) (xy 41.481279 -348.745845)
			(xy 41.481756 -348.786958) (xy 41.481195 -348.831728) (xy 41.472184 -348.920813) (xy 41.454278 -349.008544)
			(xy 41.427659 -349.094035) (xy 41.410636 -349.135446) (xy 41.407097 -349.145044) (xy 41.407081 -349.16548)
			(xy 41.410636 -349.17507) (xy 41.427663 -349.21648) (xy 41.4543 -349.301967) (xy 41.472206 -349.3897)
			(xy 41.481203 -349.478787) (xy 41.481756 -349.523558) (xy 41.481195 -349.568328) (xy 41.472184 -349.657413)
			(xy 41.454278 -349.745144) (xy 41.427659 -349.830635) (xy 41.410636 -349.872046) (xy 41.407097 -349.881644)
			(xy 41.407081 -349.90208) (xy 41.410636 -349.91167) (xy 41.427663 -349.95308) (xy 41.4543 -350.038567)
			(xy 41.472206 -350.1263) (xy 41.481203 -350.215387) (xy 41.481756 -350.260158) (xy 41.481261 -350.301272)
			(xy 41.473678 -350.383151) (xy 41.458572 -350.46398) (xy 41.436072 -350.54307) (xy 41.40637 -350.619748)
			(xy 41.36972 -350.693357) (xy 41.326434 -350.76327) (xy 41.276882 -350.828891) (xy 41.221486 -350.88966)
			(xy 41.160719 -350.945059) (xy 41.0951 -350.994614) (xy 41.025188 -351.037902) (xy 40.95158 -351.074555)
			(xy 40.874905 -351.10426) (xy 40.795815 -351.126764) (xy 40.714986 -351.141873) (xy 40.633108 -351.14946)
			(xy 40.591994 -351.14992) (xy 40.550379 -351.14939) (xy 40.467516 -351.141576) (xy 40.385744 -351.126063)
			(xy 40.305776 -351.102986) (xy 40.228311 -351.072547) (xy 40.154024 -351.035012) (xy 40.118538 -351.013268)
			(xy 40.109417 -351.008182) (xy 40.088777 -351.005125) (xy 40.068616 -351.010498) (xy 40.060118 -351.01657)
			(xy 40.026474 -351.04257) (xy 39.955045 -351.088707) (xy 39.879537 -351.127815) (xy 39.800642 -351.159538)
			(xy 39.719079 -351.183585) (xy 39.635593 -351.199737) (xy 39.550947 -351.207847) (xy 39.50843 -351.20834)
			(xy 39.467315 -351.207873) (xy 39.385435 -351.200288) (xy 39.304605 -351.185181) (xy 39.225514 -351.162679)
			(xy 39.148836 -351.132976) (xy 39.075226 -351.096324) (xy 39.005312 -351.053036) (xy 38.93969 -351.003482)
			(xy 38.878921 -350.948084) (xy 38.823523 -350.887316) (xy 38.773968 -350.821695) (xy 38.73068 -350.751781)
			(xy 38.694028 -350.678172) (xy 38.664323 -350.601494) (xy 38.641821 -350.522403) (xy 38.626713 -350.441573)
			(xy 38.619127 -350.359693) (xy 38.618668 -350.318578) (xy 38.61924 -350.273809) (xy 38.628247 -350.184724)
			(xy 38.64615 -350.096993) (xy 38.672766 -350.011501) (xy 38.689788 -349.97009) (xy 38.693368 -349.960503)
			(xy 38.69336 -349.940056) (xy 38.689788 -349.930466) (xy 38.674003 -349.892156) (xy 38.648791 -349.813223)
			(xy 38.631031 -349.732285) (xy 38.62088 -349.650047) (xy 38.619176 -349.608648) (xy 38.61835 -349.597726)
			(xy 38.608691 -349.578089) (xy 38.591771 -349.56421) (xy 38.58133 -349.560896) (xy 38.564458 -349.556397)
			(xy 38.531047 -349.546235) (xy 38.514528 -349.540576) (xy 38.506332 -349.538053) (xy 38.489196 -349.538053)
			(xy 38.481 -349.540576) (xy 38.44578 -349.552528) (xy 38.373779 -349.571185) (xy 38.300459 -349.583696)
			(xy 38.226344 -349.589972) (xy 38.189154 -349.59036) (xy 38.151965 -349.589952) (xy 38.077852 -349.583667)
			(xy 38.004533 -349.571163) (xy 37.932526 -349.552528) (xy 37.897308 -349.540576) (xy 37.889112 -349.538053)
			(xy 37.871976 -349.538053) (xy 37.86378 -349.540576) (xy 37.828562 -349.552533) (xy 37.75656 -349.571189)
			(xy 37.683239 -349.583699) (xy 37.609124 -349.589973) (xy 37.571934 -349.59036) (xy 37.529996 -349.589881)
			(xy 37.446499 -349.581908) (xy 37.364138 -349.566035) (xy 37.283659 -349.542404) (xy 37.20579 -349.511231)
			(xy 37.131238 -349.472797) (xy 37.060676 -349.42745) (xy 36.994745 -349.375601) (xy 36.93404 -349.317719)
			(xy 36.879112 -349.25433) (xy 36.830459 -349.186006) (xy 36.788521 -349.113367) (xy 36.753677 -349.03707)
			(xy 36.726244 -348.957807) (xy 36.706469 -348.876294) (xy 36.694532 -348.793272) (xy 36.690541 -348.70949)
			(xy 33.197509 -348.70949) (xy 33.200879 -348.745845) (xy 33.201356 -348.786958) (xy 33.200795 -348.831728)
			(xy 33.191784 -348.920813) (xy 33.173878 -349.008544) (xy 33.147259 -349.094035) (xy 33.130236 -349.135446)
			(xy 33.126697 -349.145044) (xy 33.126681 -349.16548) (xy 33.130236 -349.17507) (xy 33.147263 -349.21648)
			(xy 33.1739 -349.301967) (xy 33.191806 -349.3897) (xy 33.200803 -349.478787) (xy 33.201356 -349.523558)
			(xy 33.200795 -349.568328) (xy 33.191784 -349.657413) (xy 33.173878 -349.745144) (xy 33.147259 -349.830635)
			(xy 33.130236 -349.872046) (xy 33.126697 -349.881644) (xy 33.126681 -349.90208) (xy 33.130236 -349.91167)
			(xy 33.147263 -349.95308) (xy 33.1739 -350.038567) (xy 33.191806 -350.1263) (xy 33.200803 -350.215387)
			(xy 33.201356 -350.260158) (xy 33.200861 -350.301272) (xy 33.193278 -350.383151) (xy 33.178172 -350.46398)
			(xy 33.155672 -350.54307) (xy 33.12597 -350.619748) (xy 33.08932 -350.693357) (xy 33.046034 -350.76327)
			(xy 32.996482 -350.828891) (xy 32.941086 -350.88966) (xy 32.880319 -350.945059) (xy 32.8147 -350.994614)
			(xy 32.744788 -351.037902) (xy 32.67118 -351.074555) (xy 32.594505 -351.10426) (xy 32.515415 -351.126764)
			(xy 32.434586 -351.141873) (xy 32.352708 -351.14946) (xy 32.311594 -351.14992) (xy 32.269979 -351.14939)
			(xy 32.187116 -351.141576) (xy 32.105344 -351.126063) (xy 32.025376 -351.102986) (xy 31.947911 -351.072547)
			(xy 31.873624 -351.035012) (xy 31.838138 -351.013268) (xy 31.829017 -351.008182) (xy 31.808377 -351.005125)
			(xy 31.788216 -351.010498) (xy 31.779718 -351.01657) (xy 31.746074 -351.04257) (xy 31.674645 -351.088707)
			(xy 31.599137 -351.127815) (xy 31.520242 -351.159538) (xy 31.438679 -351.183585) (xy 31.355193 -351.199737)
			(xy 31.270547 -351.207847) (xy 31.22803 -351.20834) (xy 31.186915 -351.207873) (xy 31.105035 -351.200288)
			(xy 31.024205 -351.185181) (xy 30.945114 -351.162679) (xy 30.868436 -351.132976) (xy 30.794826 -351.096324)
			(xy 30.724912 -351.053036) (xy 30.65929 -351.003482) (xy 30.598521 -350.948084) (xy 30.543123 -350.887316)
			(xy 30.493568 -350.821695) (xy 30.45028 -350.751781) (xy 30.413628 -350.678172) (xy 30.383923 -350.601494)
			(xy 30.361421 -350.522403) (xy 30.346313 -350.441573) (xy 30.338727 -350.359693) (xy 30.338268 -350.318578)
			(xy 30.33884 -350.273809) (xy 30.347847 -350.184724) (xy 30.36575 -350.096993) (xy 30.392366 -350.011501)
			(xy 30.409388 -349.97009) (xy 30.412968 -349.960503) (xy 30.41296 -349.940056) (xy 30.409388 -349.930466)
			(xy 30.393603 -349.892156) (xy 30.368391 -349.813223) (xy 30.350631 -349.732285) (xy 30.34048 -349.650047)
			(xy 30.338776 -349.608648) (xy 30.33795 -349.597726) (xy 30.328291 -349.578089) (xy 30.311371 -349.56421)
			(xy 30.30093 -349.560896) (xy 30.284058 -349.556397) (xy 30.250647 -349.546235) (xy 30.234128 -349.540576)
			(xy 30.225932 -349.538053) (xy 30.208796 -349.538053) (xy 30.2006 -349.540576) (xy 30.16538 -349.552528)
			(xy 30.093379 -349.571185) (xy 30.020059 -349.583696) (xy 29.945944 -349.589972) (xy 29.908754 -349.59036)
			(xy 29.871565 -349.589952) (xy 29.797452 -349.583667) (xy 29.724133 -349.571163) (xy 29.652126 -349.552528)
			(xy 29.616908 -349.540576) (xy 29.608712 -349.538053) (xy 29.591576 -349.538053) (xy 29.58338 -349.540576)
			(xy 29.548162 -349.552533) (xy 29.47616 -349.571189) (xy 29.402839 -349.583699) (xy 29.328724 -349.589973)
			(xy 29.291534 -349.59036) (xy 29.249596 -349.589881) (xy 29.166099 -349.581908) (xy 29.083738 -349.566035)
			(xy 29.003259 -349.542404) (xy 28.92539 -349.511231) (xy 28.850838 -349.472797) (xy 28.780276 -349.42745)
			(xy 28.714345 -349.375601) (xy 28.65364 -349.317719) (xy 28.598712 -349.25433) (xy 28.550059 -349.186006)
			(xy 28.508121 -349.113367) (xy 28.473277 -349.03707) (xy 28.445844 -348.957807) (xy 28.426069 -348.876294)
			(xy 28.414132 -348.793272) (xy 28.410141 -348.70949) (xy 24.13 -348.70949) (xy 24.13 -351.12071)
			(xy 24.130425 -351.130779) (xy 24.138142 -351.149381) (xy 24.144986 -351.156778) (xy 24.626062 -351.637854)
			(xy 73.92162 -351.637854) (xy 73.922073 -351.597287) (xy 73.929469 -351.516491) (xy 73.944194 -351.436705)
			(xy 73.966127 -351.358593) (xy 73.995085 -351.282803) (xy 74.012552 -351.246186) (xy 74.016539 -351.237119)
			(xy 74.017973 -351.217383) (xy 74.015346 -351.207832) (xy 74.001124 -351.162812) (xy 73.98114 -351.070533)
			(xy 73.971051 -350.976656) (xy 73.970388 -350.929448) (xy 73.970892 -350.887087) (xy 73.978945 -350.80275)
			(xy 73.994979 -350.71956) (xy 74.018847 -350.63827) (xy 74.050335 -350.559618) (xy 74.089157 -350.484315)
			(xy 74.13496 -350.413043) (xy 74.187331 -350.346447) (xy 74.245796 -350.285132) (xy 74.309824 -350.229651)
			(xy 74.378836 -350.180508) (xy 74.452206 -350.138148) (xy 74.529271 -350.102953) (xy 74.609333 -350.075244)
			(xy 74.691666 -350.05527) (xy 74.775525 -350.043213) (xy 74.86015 -350.039182) (xy 74.944775 -350.043213)
			(xy 75.028634 -350.05527) (xy 75.110967 -350.075244) (xy 75.191029 -350.102953) (xy 75.268094 -350.138148)
			(xy 75.341464 -350.180508) (xy 75.410476 -350.229651) (xy 75.474504 -350.285132) (xy 75.532969 -350.346447)
			(xy 75.58534 -350.413043) (xy 75.631143 -350.484315) (xy 75.669965 -350.559618) (xy 75.701453 -350.63827)
			(xy 75.725321 -350.71956) (xy 75.741355 -350.80275) (xy 75.749408 -350.887087) (xy 75.749912 -350.929448)
			(xy 75.749456 -350.970015) (xy 75.742061 -351.05081) (xy 75.727336 -351.130596) (xy 75.705403 -351.208709)
			(xy 75.676446 -351.284499) (xy 75.65898 -351.321116) (xy 75.654992 -351.330183) (xy 75.653558 -351.34992)
			(xy 75.656186 -351.35947) (xy 75.670409 -351.40449) (xy 75.690393 -351.496768) (xy 75.700481 -351.590646)
			(xy 75.700605 -351.5995) (xy 76.58354 -351.5995) (xy 76.583977 -351.558938) (xy 76.59131 -351.478148)
			(xy 76.605978 -351.398363) (xy 76.62786 -351.320247) (xy 76.656772 -351.244452) (xy 76.674218 -351.207832)
			(xy 76.67818 -351.198756) (xy 76.679631 -351.179027) (xy 76.677012 -351.169478) (xy 76.662834 -351.124451)
			(xy 76.642936 -351.032168) (xy 76.632931 -350.938296) (xy 76.632308 -350.891094) (xy 76.632812 -350.848746)
			(xy 76.640863 -350.764432) (xy 76.656892 -350.681266) (xy 76.680753 -350.599999) (xy 76.712232 -350.521369)
			(xy 76.751043 -350.446088) (xy 76.796833 -350.374836) (xy 76.849189 -350.30826) (xy 76.907637 -350.246962)
			(xy 76.971647 -350.191497) (xy 77.040639 -350.142368) (xy 77.113989 -350.100019) (xy 77.191032 -350.064835)
			(xy 77.271071 -350.037133) (xy 77.35338 -350.017165) (xy 77.437215 -350.005112) (xy 77.521816 -350.001082)
			(xy 77.606417 -350.005112) (xy 77.690252 -350.017165) (xy 77.772561 -350.037133) (xy 77.8526 -350.064835)
			(xy 77.929643 -350.100019) (xy 78.002993 -350.142368) (xy 78.071985 -350.191497) (xy 78.135995 -350.246962)
			(xy 78.194443 -350.30826) (xy 78.246799 -350.374836) (xy 78.292589 -350.446088) (xy 78.3314 -350.521369)
			(xy 78.362879 -350.599999) (xy 78.38674 -350.681266) (xy 78.402769 -350.764432) (xy 78.41082 -350.848746)
			(xy 78.411324 -350.891094) (xy 78.410888 -350.931656) (xy 78.403556 -351.012446) (xy 78.388887 -351.092231)
			(xy 78.367006 -351.170347) (xy 78.338092 -351.246142) (xy 78.320646 -351.282762) (xy 78.316687 -351.291839)
			(xy 78.315236 -351.311567) (xy 78.317852 -351.321116) (xy 78.332052 -351.366136) (xy 78.351942 -351.458423)
			(xy 78.361938 -351.552297) (xy 78.362556 -351.5995) (xy 78.362003 -351.645139) (xy 78.352699 -351.735943)
			(xy 78.334149 -351.825316) (xy 78.3209 -351.868994) (xy 78.318425 -351.878002) (xy 78.319475 -351.896637)
			(xy 78.322932 -351.905316) (xy 78.341634 -351.948394) (xy 78.370914 -352.03763) (xy 78.390624 -352.129456)
			(xy 78.400545 -352.222848) (xy 78.401164 -352.269806) (xy 78.400618 -352.312751) (xy 78.392322 -352.39824)
			(xy 78.375839 -352.482535) (xy 78.351319 -352.564851) (xy 78.335632 -352.604832) (xy 78.332357 -352.614145)
			(xy 78.33236 -352.633871) (xy 78.335632 -352.643186) (xy 78.351338 -352.683162) (xy 78.375884 -352.765474)
			(xy 78.392373 -352.84977) (xy 78.400651 -352.935265) (xy 78.401164 -352.978212) (xy 78.40066 -353.020573)
			(xy 78.392607 -353.10491) (xy 78.376573 -353.1881) (xy 78.352705 -353.26939) (xy 78.321217 -353.348042)
			(xy 78.282395 -353.423345) (xy 78.236592 -353.494617) (xy 78.184221 -353.561213) (xy 78.125756 -353.622528)
			(xy 78.061728 -353.678009) (xy 77.992716 -353.727152) (xy 77.919346 -353.769512) (xy 77.842281 -353.804707)
			(xy 77.762219 -353.832416) (xy 77.679886 -353.85239) (xy 77.596027 -353.864447) (xy 77.511402 -353.868479)
			(xy 77.426777 -353.864447) (xy 77.342918 -353.85239) (xy 77.260585 -353.832416) (xy 77.180523 -353.804707)
			(xy 77.103458 -353.769512) (xy 77.030088 -353.727152) (xy 76.961076 -353.678009) (xy 76.897048 -353.622528)
			(xy 76.838583 -353.561213) (xy 76.786212 -353.494617) (xy 76.740409 -353.423345) (xy 76.701587 -353.348042)
			(xy 76.670099 -353.26939) (xy 76.646231 -353.1881) (xy 76.630197 -353.10491) (xy 76.622144 -353.020573)
			(xy 76.62164 -352.978212) (xy 76.622159 -352.935266) (xy 76.630462 -352.849776) (xy 76.646954 -352.765482)
			(xy 76.671481 -352.683166) (xy 76.687172 -352.643186) (xy 76.690497 -352.633879) (xy 76.6905 -352.614137)
			(xy 76.687172 -352.604832) (xy 76.671472 -352.564854) (xy 76.646924 -352.482543) (xy 76.630433 -352.398247)
			(xy 76.622154 -352.312753) (xy 76.62164 -352.269806) (xy 76.622244 -352.224161) (xy 76.631638 -352.133355)
			(xy 76.650266 -352.043985) (xy 76.66355 -352.000312) (xy 76.666018 -351.991303) (xy 76.664971 -351.972669)
			(xy 76.661518 -351.96399) (xy 76.642856 -351.920903) (xy 76.61365 -351.831658) (xy 76.594004 -351.739834)
			(xy 76.584137 -351.646451) (xy 76.58354 -351.5995) (xy 75.700605 -351.5995) (xy 75.701144 -351.637854)
			(xy 75.70053 -351.683499) (xy 75.691141 -351.774304) (xy 75.672516 -351.863674) (xy 75.659234 -351.907348)
			(xy 75.656789 -351.916361) (xy 75.657821 -351.93499) (xy 75.661266 -351.94367) (xy 75.679947 -351.986749)
			(xy 75.709149 -352.075997) (xy 75.728789 -352.167824) (xy 75.738651 -352.261208) (xy 75.739244 -352.30816)
			(xy 75.738798 -352.348493) (xy 75.731529 -352.428831) (xy 75.71702 -352.508181) (xy 75.69539 -352.585893)
			(xy 75.666817 -352.661328) (xy 75.649582 -352.697796) (xy 75.645149 -352.708474) (xy 75.645157 -352.731564)
			(xy 75.649582 -352.742246) (xy 75.666795 -352.778669) (xy 75.695361 -352.854001) (xy 75.716992 -352.931608)
			(xy 75.73151 -353.010855) (xy 75.738795 -353.091091) (xy 75.739244 -353.131374) (xy 75.73874 -353.173735)
			(xy 75.730687 -353.258072) (xy 75.714653 -353.341262) (xy 75.690785 -353.422552) (xy 75.659297 -353.501204)
			(xy 75.620475 -353.576507) (xy 75.574672 -353.647779) (xy 75.522301 -353.714375) (xy 75.463836 -353.77569)
			(xy 75.399808 -353.831171) (xy 75.330796 -353.880314) (xy 75.257426 -353.922674) (xy 75.180361 -353.957869)
			(xy 75.100299 -353.985578) (xy 75.017966 -354.005552) (xy 74.934107 -354.017609) (xy 74.849482 -354.021641)
			(xy 74.764857 -354.017609) (xy 74.680998 -354.005552) (xy 74.598665 -353.985578) (xy 74.518603 -353.957869)
			(xy 74.441538 -353.922674) (xy 74.368168 -353.880314) (xy 74.299156 -353.831171) (xy 74.235128 -353.77569)
			(xy 74.176663 -353.714375) (xy 74.124292 -353.647779) (xy 74.078489 -353.576507) (xy 74.039667 -353.501204)
			(xy 74.008179 -353.422552) (xy 73.984311 -353.341262) (xy 73.968277 -353.258072) (xy 73.960224 -353.173735)
			(xy 73.95972 -353.131374) (xy 73.960164 -353.091034) (xy 73.96747 -353.010685) (xy 73.982028 -352.931329)
			(xy 74.003719 -352.85362) (xy 74.032363 -352.778196) (xy 74.049636 -352.741738) (xy 74.054225 -352.731091)
			(xy 74.054231 -352.707932) (xy 74.049636 -352.697288) (xy 74.032445 -352.660861) (xy 74.003936 -352.58552)
			(xy 73.98236 -352.50791) (xy 73.967893 -352.428665) (xy 73.960655 -352.348437) (xy 73.960228 -352.30816)
			(xy 73.960797 -352.262521) (xy 73.970094 -352.171718) (xy 73.988639 -352.082344) (xy 74.001884 -352.038666)
			(xy 74.004328 -352.029652) (xy 74.003299 -352.011023) (xy 73.999852 -352.002344) (xy 73.981136 -351.959272)
			(xy 73.95186 -351.870033) (xy 73.932154 -351.778206) (xy 73.922237 -351.684813) (xy 73.92162 -351.637854)
			(xy 24.626062 -351.637854) (xy 24.638254 -351.650046) (xy 24.664162 -351.656904) (xy 24.67737 -351.653348)
			(xy 24.701733 -351.647175) (xy 24.751554 -351.640547) (xy 24.776684 -351.64014) (xy 24.803936 -351.640602)
			(xy 24.857886 -351.648358) (xy 24.910183 -351.663713) (xy 24.959763 -351.686355) (xy 25.005614 -351.715823)
			(xy 25.046805 -351.751518) (xy 25.082496 -351.792711) (xy 25.11196 -351.838566) (xy 25.134598 -351.888147)
			(xy 25.149949 -351.940445) (xy 25.1577 -351.994396) (xy 25.158192 -352.021648) (xy 25.157771 -352.046777)
			(xy 25.15114 -352.096595) (xy 25.144984 -352.120962) (xy 25.141428 -352.13417) (xy 25.148286 -352.160078)
			(xy 27.277822 -354.289614) (xy 27.285218 -354.296466) (xy 27.303817 -354.304206) (xy 27.31389 -354.3046)
		)
		(stroke
			(width 0)
			(type solid)
		)
		(fill yes)
		(layer "In8.Cu")
		(net "GND")
	)
	(gr_poly
		(pts
			(xy 295.90746 -399.579084) (xy 295.917525 -399.578649) (xy 295.936112 -399.570918) (xy 295.943528 -399.564098)
			(xy 301.013368 -394.494258) (xy 301.03141 -394.477) (xy 301.072904 -394.449247) (xy 301.119022 -394.430138)
			(xy 301.167986 -394.42041) (xy 301.192946 -394.419836) (xy 303.770792 -394.419836) (xy 303.779681 -394.419496)
			(xy 303.796383 -394.413406) (xy 303.809985 -394.401959) (xy 303.814734 -394.394436) (xy 303.821592 -394.382498)
			(xy 303.821592 -394.355574) (xy 303.52365 -393.839954) (xy 303.511756 -393.817285) (xy 303.494889 -393.768953)
			(xy 303.486337 -393.718483) (xy 303.485804 -393.692888) (xy 303.485804 -393.69238) (xy 303.486276 -393.66839)
			(xy 303.493785 -393.621002) (xy 303.508614 -393.575371) (xy 303.530399 -393.532622) (xy 303.558603 -393.493807)
			(xy 303.592531 -393.459882) (xy 303.631349 -393.431682) (xy 303.674101 -393.409902) (xy 303.719733 -393.395077)
			(xy 303.767122 -393.387574) (xy 303.791112 -393.387072) (xy 303.815046 -393.387538) (xy 303.862329 -393.395002)
			(xy 303.907869 -393.409747) (xy 303.950555 -393.431411) (xy 303.98934 -393.459466) (xy 304.023278 -393.493223)
			(xy 304.051538 -393.531859) (xy 304.062892 -393.552934) (xy 304.0634 -393.55395) (xy 304.45583 -394.232892)
			(xy 304.467531 -394.254168) (xy 304.484783 -394.299552) (xy 304.494644 -394.347092) (xy 304.496216 -394.371322)
			(xy 304.497232 -394.391896) (xy 304.526442 -394.419836) (xy 304.970688 -394.419836) (xy 304.979577 -394.419497)
			(xy 304.99628 -394.413407) (xy 305.009883 -394.401961) (xy 305.01463 -394.394436) (xy 305.021488 -394.382498)
			(xy 305.021488 -394.355574) (xy 304.723546 -393.839954) (xy 304.711652 -393.817285) (xy 304.694786 -393.768953)
			(xy 304.686233 -393.718483) (xy 304.6857 -393.692888) (xy 304.6857 -393.69238) (xy 304.686172 -393.66839)
			(xy 304.693681 -393.621001) (xy 304.70851 -393.57537) (xy 304.730295 -393.532621) (xy 304.758499 -393.493806)
			(xy 304.792427 -393.45988) (xy 304.831245 -393.43168) (xy 304.873996 -393.409899) (xy 304.919628 -393.395074)
			(xy 304.967018 -393.38757) (xy 304.991008 -393.387072) (xy 305.014942 -393.387537) (xy 305.062225 -393.395001)
			(xy 305.107766 -393.409746) (xy 305.150452 -393.43141) (xy 305.189238 -393.459464) (xy 305.223176 -393.493222)
			(xy 305.251437 -393.531858) (xy 305.262788 -393.552934) (xy 305.263296 -393.55395) (xy 305.655726 -394.232892)
			(xy 305.667427 -394.254168) (xy 305.68468 -394.299551) (xy 305.69454 -394.347092) (xy 305.696112 -394.371322)
			(xy 305.697128 -394.391896) (xy 305.726338 -394.419836) (xy 306.170584 -394.419836) (xy 306.179474 -394.419498)
			(xy 306.196177 -394.413409) (xy 306.209782 -394.401963) (xy 306.214526 -394.394436) (xy 306.221384 -394.382498)
			(xy 306.221384 -394.355574) (xy 305.923442 -393.839954) (xy 305.911548 -393.817285) (xy 305.894682 -393.768953)
			(xy 305.88613 -393.718483) (xy 305.885596 -393.692888) (xy 305.885596 -393.69238) (xy 305.886068 -393.66839)
			(xy 305.893577 -393.621001) (xy 305.908406 -393.57537) (xy 305.930191 -393.53262) (xy 305.958394 -393.493805)
			(xy 305.992323 -393.459879) (xy 306.031141 -393.431678) (xy 306.073892 -393.409897) (xy 306.119524 -393.395071)
			(xy 306.166914 -393.387566) (xy 306.190904 -393.387072) (xy 306.191158 -393.387072) (xy 306.21509 -393.387541)
			(xy 306.262368 -393.395012) (xy 306.307904 -393.409761) (xy 306.350583 -393.431429) (xy 306.389363 -393.459485)
			(xy 306.423295 -393.493243) (xy 306.45155 -393.531879) (xy 306.462938 -393.552934) (xy 306.463446 -393.55395)
			(xy 306.855876 -394.232892) (xy 306.867578 -394.254167) (xy 306.884834 -394.299551) (xy 306.894697 -394.347092)
			(xy 306.896262 -394.371322) (xy 306.897278 -394.391896) (xy 306.926488 -394.419836) (xy 307.370734 -394.419836)
			(xy 307.379628 -394.419506) (xy 307.396345 -394.413428) (xy 307.409963 -394.401985) (xy 307.414676 -394.394436)
			(xy 307.421534 -394.382498) (xy 307.421534 -394.355574) (xy 307.123592 -393.839954) (xy 307.111655 -393.817294)
			(xy 307.094696 -393.768971) (xy 307.086046 -393.718493) (xy 307.085492 -393.692888) (xy 307.085492 -393.69238)
			(xy 307.085941 -393.668375) (xy 307.093458 -393.620958) (xy 307.108304 -393.575301) (xy 307.130112 -393.532531)
			(xy 307.158346 -393.4937) (xy 307.192309 -393.459768) (xy 307.231165 -393.431569) (xy 307.273955 -393.409799)
			(xy 307.319625 -393.394994) (xy 307.367049 -393.387519) (xy 307.391054 -393.387072) (xy 307.414986 -393.387541)
			(xy 307.462265 -393.395011) (xy 307.507801 -393.40976) (xy 307.550481 -393.431427) (xy 307.589261 -393.459483)
			(xy 307.623194 -393.493242) (xy 307.651449 -393.531877) (xy 307.662834 -393.552934) (xy 307.663342 -393.55395)
			(xy 308.055772 -394.232892) (xy 308.067475 -394.254167) (xy 308.084731 -394.29955) (xy 308.094593 -394.347092)
			(xy 308.096158 -394.371322) (xy 308.097174 -394.391896) (xy 308.126384 -394.419836) (xy 308.57063 -394.419836)
			(xy 308.579524 -394.419506) (xy 308.596242 -394.413429) (xy 308.609862 -394.401987) (xy 308.614572 -394.394436)
			(xy 308.62143 -394.382498) (xy 308.62143 -394.355574) (xy 308.323488 -393.839954) (xy 308.311551 -393.817294)
			(xy 308.294592 -393.768971) (xy 308.285942 -393.718493) (xy 308.285388 -393.692888) (xy 308.285388 -393.69238)
			(xy 308.285837 -393.668375) (xy 308.293354 -393.620957) (xy 308.308199 -393.5753) (xy 308.330008 -393.53253)
			(xy 308.358242 -393.493699) (xy 308.392205 -393.459766) (xy 308.43106 -393.431567) (xy 308.47385 -393.409796)
			(xy 308.51952 -393.394991) (xy 308.566945 -393.387516) (xy 308.59095 -393.387072) (xy 308.614883 -393.38754)
			(xy 308.662161 -393.39501) (xy 308.707698 -393.409759) (xy 308.750378 -393.431426) (xy 308.789159 -393.459482)
			(xy 308.823092 -393.49324) (xy 308.851348 -393.531876) (xy 308.86273 -393.552934) (xy 308.863238 -393.55395)
			(xy 309.255668 -394.232892) (xy 309.267371 -394.254167) (xy 309.284627 -394.29955) (xy 309.29449 -394.347091)
			(xy 309.296054 -394.371322) (xy 309.29707 -394.391896) (xy 309.32628 -394.419836) (xy 309.77078 -394.419836)
			(xy 309.77967 -394.419498) (xy 309.796375 -394.41341) (xy 309.80998 -394.401964) (xy 309.814722 -394.394436)
			(xy 309.82158 -394.382498) (xy 309.82158 -394.355574) (xy 309.523638 -393.839954) (xy 309.511744 -393.817284)
			(xy 309.494878 -393.768953) (xy 309.486326 -393.718483) (xy 309.485792 -393.692888) (xy 309.485792 -393.69238)
			(xy 309.486264 -393.66839) (xy 309.493773 -393.621001) (xy 309.508602 -393.575369) (xy 309.530386 -393.532619)
			(xy 309.55859 -393.493803) (xy 309.592519 -393.459877) (xy 309.631336 -393.431676) (xy 309.674088 -393.409894)
			(xy 309.71972 -393.395068) (xy 309.76711 -393.387563) (xy 309.7911 -393.387072) (xy 309.796688 -393.387072)
			(xy 309.806407 -393.38679) (xy 309.824565 -393.379881) (xy 309.831994 -393.37361) (xy 309.854854 -393.352528)
			(xy 309.862306 -393.345038) (xy 309.870854 -393.325742) (xy 309.871364 -393.31519) (xy 309.871364 -392.47064)
			(xy 309.871981 -392.445685) (xy 309.881727 -392.396737) (xy 309.900834 -392.350629) (xy 309.928567 -392.309134)
			(xy 309.945786 -392.291062) (xy 310.284114 -391.952734) (xy 310.300857 -391.936689) (xy 310.339027 -391.910362)
			(xy 310.381341 -391.8914) (xy 310.403748 -391.885424) (xy 310.410606 -391.8839) (xy 310.422544 -391.877042)
			(xy 310.564784 -391.734802) (xy 310.582825 -391.717543) (xy 310.624319 -391.689787) (xy 310.670437 -391.670678)
			(xy 310.719401 -391.660951) (xy 310.744362 -391.66038) (xy 325.613522 -391.66038) (xy 325.638478 -391.660994)
			(xy 325.68743 -391.670734) (xy 325.733542 -391.689837) (xy 325.775042 -391.717567) (xy 325.7931 -391.734802)
			(xy 326.137524 -392.079226) (xy 326.154786 -392.097266) (xy 326.182548 -392.138759) (xy 326.201666 -392.184877)
			(xy 326.211403 -392.233842) (xy 326.211946 -392.258804) (xy 326.211946 -393.057634) (xy 326.211382 -393.081676)
			(xy 326.202332 -393.128902) (xy 326.184562 -393.173582) (xy 326.158705 -393.214123) (xy 326.125685 -393.249078)
			(xy 326.106536 -393.263628) (xy 326.097019 -393.27124) (xy 326.085858 -393.292863) (xy 326.0852 -393.30503)
			(xy 326.0852 -394.611352) (xy 326.084762 -394.621384) (xy 326.077188 -394.63996) (xy 326.070468 -394.64742)
			(xy 325.922386 -394.795248) (xy 325.915573 -394.802592) (xy 325.907845 -394.821055) (xy 325.9074 -394.831062)
			(xy 325.9074 -394.878814) (xy 325.908094 -394.890976) (xy 325.91923 -394.9126) (xy 325.928736 -394.920216)
			(xy 325.949126 -394.935706) (xy 325.983808 -394.973366) (xy 326.010238 -395.017214) (xy 326.019414 -395.04112)
			(xy 326.022716 -395.050518) (xy 326.035924 -395.06525) (xy 326.117458 -395.105128) (xy 326.13727 -395.106652)
			(xy 326.146668 -395.103604) (xy 326.175578 -395.094708) (xy 326.235298 -395.085134) (xy 326.26554 -395.084554)
			(xy 326.293176 -395.085047) (xy 326.347868 -395.093026) (xy 326.400837 -395.10881) (xy 326.450975 -395.132071)
			(xy 326.497234 -395.16232) (xy 326.538645 -395.198926) (xy 326.574343 -395.241123) (xy 326.60358 -395.288028)
			(xy 326.625746 -395.33866) (xy 326.640376 -395.39196) (xy 326.644254 -395.419326) (xy 326.64654 -395.438376)
			(xy 326.675242 -395.463776) (xy 327.600818 -395.463776) (xy 327.610886 -395.463349) (xy 327.629484 -395.455627)
			(xy 327.636886 -395.44879) (xy 329.033886 -394.05179) (xy 329.040732 -394.044391) (xy 329.048465 -394.025793)
			(xy 329.048872 -394.015722) (xy 329.048872 -392.849354) (xy 329.049488 -392.824399) (xy 329.059232 -392.775449)
			(xy 329.078337 -392.72934) (xy 329.106069 -392.687843) (xy 329.123294 -392.669776) (xy 329.823826 -391.969244)
			(xy 329.841867 -391.951984) (xy 329.883361 -391.924225) (xy 329.929478 -391.905109) (xy 329.978443 -391.895374)
			(xy 330.003404 -391.894822) (xy 332.26502 -391.894822) (xy 332.276037 -391.894278) (xy 332.296049 -391.885057)
			(xy 332.303628 -391.877042) (xy 332.321838 -391.856507) (xy 332.36314 -391.820363) (xy 332.409195 -391.79051)
			(xy 332.459052 -391.767564) (xy 332.511682 -391.751998) (xy 332.566 -391.744134) (xy 332.620884 -391.744134)
			(xy 332.675202 -391.751998) (xy 332.727832 -391.767564) (xy 332.777689 -391.79051) (xy 332.823744 -391.820363)
			(xy 332.865046 -391.856507) (xy 332.883256 -391.877042) (xy 332.890828 -391.885068) (xy 332.910844 -391.894297)
			(xy 332.921864 -391.894822) (xy 342.252808 -391.894822) (xy 342.277768 -391.895394) (xy 342.326728 -391.905135)
			(xy 342.372848 -391.924241) (xy 342.414353 -391.951978) (xy 342.432386 -391.969244) (xy 342.547194 -392.083798)
			(xy 342.554606 -392.090482) (xy 342.573039 -392.098079) (xy 342.592977 -392.098079) (xy 342.61141 -392.090482)
			(xy 342.618822 -392.083798) (xy 342.910414 -391.792206) (xy 342.928453 -391.774941) (xy 342.969944 -391.747174)
			(xy 343.016063 -391.728051) (xy 343.065029 -391.718311) (xy 343.089992 -391.717784) (xy 358.205532 -391.717784)
			(xy 358.230487 -391.718399) (xy 358.279439 -391.728141) (xy 358.325549 -391.747245) (xy 358.367047 -391.774977)
			(xy 358.38511 -391.792206) (xy 358.665272 -392.072368) (xy 358.682534 -392.090408) (xy 358.710295 -392.1319)
			(xy 358.729409 -392.178019) (xy 358.73914 -392.226984) (xy 358.739694 -392.251946) (xy 358.739694 -393.057634)
			(xy 358.73913 -393.081677) (xy 358.730082 -393.128904) (xy 358.712314 -393.173587) (xy 358.68646 -393.214131)
			(xy 358.653443 -393.249091) (xy 358.634284 -393.263628) (xy 358.624775 -393.271244) (xy 358.613626 -393.292866)
			(xy 358.612948 -393.30503) (xy 358.612948 -394.611352) (xy 358.612509 -394.621383) (xy 358.604929 -394.639954)
			(xy 358.598216 -394.64742) (xy 358.450134 -394.795248) (xy 358.443327 -394.802594) (xy 358.435607 -394.821057)
			(xy 358.435148 -394.831062) (xy 358.435148 -394.878814) (xy 358.435843 -394.890974) (xy 358.446986 -394.912591)
			(xy 358.456484 -394.920216) (xy 358.475656 -394.934737) (xy 358.508669 -394.969701) (xy 358.534518 -395.01025)
			(xy 358.55228 -395.054937) (xy 358.561322 -395.102166) (xy 358.561894 -395.12621) (xy 358.561894 -395.635734)
			(xy 358.562323 -395.645802) (xy 358.570045 -395.664398) (xy 358.57688 -395.671802) (xy 358.58323 -395.678152)
			(xy 358.590628 -395.684999) (xy 358.609226 -395.69273) (xy 358.619298 -395.693138) (xy 363.950504 -395.693138)
			(xy 363.960514 -395.69265) (xy 363.979011 -395.684991) (xy 363.993172 -395.670839) (xy 364.000843 -395.652348)
			(xy 364.001304 -395.642338) (xy 364.001304 -395.308074) (xy 364.00179 -395.280823) (xy 364.009546 -395.226875)
			(xy 364.024901 -395.17458) (xy 364.047543 -395.125003) (xy 364.077009 -395.079153) (xy 364.1127 -395.037962)
			(xy 364.153891 -395.002271) (xy 364.199741 -394.972805) (xy 364.249318 -394.950163) (xy 364.301613 -394.934808)
			(xy 364.355561 -394.927052) (xy 364.410063 -394.927052) (xy 364.464011 -394.934808) (xy 364.516306 -394.950163)
			(xy 364.565883 -394.972805) (xy 364.611733 -395.002271) (xy 364.652924 -395.037962) (xy 364.688615 -395.079153)
			(xy 364.718081 -395.125003) (xy 364.740723 -395.17458) (xy 364.756078 -395.226875) (xy 364.763834 -395.280823)
			(xy 364.76432 -395.308074) (xy 364.76432 -395.642338) (xy 364.764815 -395.652339) (xy 364.772482 -395.670814)
			(xy 364.786634 -395.684951) (xy 364.805118 -395.692597) (xy 364.81512 -395.693138) (xy 365.657384 -395.693138)
			(xy 365.667446 -395.692698) (xy 365.686022 -395.684955) (xy 365.693452 -395.678152) (xy 366.090708 -395.280896)
			(xy 366.097553 -395.273497) (xy 366.105285 -395.254899) (xy 366.105694 -395.244828) (xy 366.105694 -392.52779)
			(xy 366.106306 -392.502834) (xy 366.116046 -392.453881) (xy 366.135147 -392.407768) (xy 366.162878 -392.366268)
			(xy 366.180116 -392.348212) (xy 366.593628 -391.9347) (xy 366.611667 -391.917437) (xy 366.653159 -391.889672)
			(xy 366.699278 -391.870552) (xy 366.748244 -391.860815) (xy 366.773206 -391.860278) (xy 366.870488 -391.860278)
			(xy 366.880096 -391.859862) (xy 366.897973 -391.852809) (xy 366.905286 -391.846562) (xy 366.926604 -391.827334)
			(xy 366.973933 -391.794844) (xy 367.025596 -391.769813) (xy 367.080426 -391.752804) (xy 367.137186 -391.744203)
			(xy 367.194594 -391.744203) (xy 367.251354 -391.752804) (xy 367.306184 -391.769813) (xy 367.357847 -391.794844)
			(xy 367.405176 -391.827334) (xy 367.426494 -391.846562) (xy 367.433784 -391.852847) (xy 367.451675 -391.859903)
			(xy 367.461292 -391.860278) (xy 376.818906 -391.860278) (xy 376.843863 -391.86089) (xy 376.892817 -391.870628)
			(xy 376.938931 -391.889728) (xy 376.980433 -391.917458) (xy 376.998484 -391.9347) (xy 377.183904 -392.12012)
			(xy 377.191316 -392.126804) (xy 377.209749 -392.134401) (xy 377.229687 -392.134401) (xy 377.24812 -392.126804)
			(xy 377.255532 -392.12012) (xy 377.64085 -391.734802) (xy 377.65889 -391.71754) (xy 377.700383 -391.689779)
			(xy 377.746501 -391.670664) (xy 377.795466 -391.660931) (xy 377.820428 -391.66038) (xy 392.713464 -391.66038)
			(xy 392.738418 -391.660998) (xy 392.787366 -391.670745) (xy 392.833472 -391.689853) (xy 392.874966 -391.717587)
			(xy 392.893042 -391.734802) (xy 393.237466 -392.079226) (xy 393.254726 -392.097267) (xy 393.282483 -392.138761)
			(xy 393.301598 -392.184879) (xy 393.311333 -392.233843) (xy 393.311888 -392.258804) (xy 393.311888 -393.057634)
			(xy 393.311324 -393.081677) (xy 393.302275 -393.128904) (xy 393.284507 -393.173586) (xy 393.258653 -393.21413)
			(xy 393.225636 -393.249089) (xy 393.206478 -393.263628) (xy 393.19706 -393.271292) (xy 393.186069 -393.292905)
			(xy 393.185396 -393.30503) (xy 393.185396 -394.611352) (xy 393.184963 -394.621418) (xy 393.177235 -394.640008)
			(xy 393.17041 -394.64742) (xy 393.022328 -394.795248) (xy 393.015633 -394.802654) (xy 393.008027 -394.82109)
			(xy 393.007596 -394.831062) (xy 393.007596 -394.878814) (xy 393.008223 -394.890948) (xy 393.019237 -394.912566)
			(xy 393.028678 -394.920216) (xy 393.04785 -394.934736) (xy 393.080865 -394.9697) (xy 393.106714 -395.010249)
			(xy 393.124477 -395.054936) (xy 393.133518 -395.102166) (xy 393.134088 -395.12621) (xy 393.134088 -395.757654)
			(xy 393.1345 -395.767682) (xy 393.142161 -395.786217) (xy 393.156334 -395.800407) (xy 393.17486 -395.808089)
			(xy 393.184888 -395.808454) (xy 394.486384 -395.808454) (xy 394.496446 -395.808014) (xy 394.515024 -395.800273)
			(xy 394.522452 -395.793468) (xy 395.977364 -394.338556) (xy 395.984207 -394.331157) (xy 395.991931 -394.312558)
			(xy 395.99235 -394.302488) (xy 395.99235 -392.573764) (xy 395.992925 -392.548805) (xy 396.002671 -392.499849)
			(xy 396.021783 -392.453734) (xy 396.049524 -392.412236) (xy 396.066772 -392.394186) (xy 396.864078 -391.59688)
			(xy 396.88212 -391.579622) (xy 396.923614 -391.551868) (xy 396.969732 -391.532759) (xy 397.018695 -391.523032)
			(xy 397.043656 -391.522458) (xy 425.075604 -391.522458) (xy 425.100564 -391.52303) (xy 425.149524 -391.532771)
			(xy 425.195642 -391.551879) (xy 425.237145 -391.579619) (xy 425.255182 -391.59688) (xy 425.749466 -392.091164)
			(xy 425.766723 -392.109206) (xy 425.794474 -392.150701) (xy 425.813582 -392.196819) (xy 425.82331 -392.245782)
			(xy 425.823888 -392.270742) (xy 425.823888 -396.813786) (xy 425.824326 -396.82385) (xy 425.832061 -396.842433)
			(xy 425.838874 -396.849854) (xy 426.461936 -397.472916) (xy 426.469332 -397.479766) (xy 426.487931 -397.487501)
			(xy 426.498004 -397.487902) (xy 429.173132 -397.487902) (xy 429.1832 -397.487473) (xy 429.201796 -397.479751)
			(xy 429.2092 -397.472916) (xy 429.257206 -397.42491) (xy 429.263278 -397.418302) (xy 429.270749 -397.401999)
			(xy 429.272126 -397.384119) (xy 429.267237 -397.366865) (xy 429.262286 -397.359378) (xy 429.245243 -397.334805)
			(xy 429.2182 -397.281471) (xy 429.1998 -397.224573) (xy 429.190495 -397.165503) (xy 429.189896 -397.135604)
			(xy 429.190359 -397.108351) (xy 429.198116 -397.0544) (xy 429.213471 -397.002102) (xy 429.236114 -396.952521)
			(xy 429.265582 -396.906668) (xy 429.301275 -396.865475) (xy 429.342468 -396.829782) (xy 429.388321 -396.800314)
			(xy 429.437902 -396.777671) (xy 429.4902 -396.762316) (xy 429.544151 -396.754559) (xy 429.571404 -396.754096)
			(xy 429.597523 -396.754522) (xy 429.64927 -396.761656) (xy 429.674528 -396.76832) (xy 429.686212 -396.771622)
			(xy 429.709326 -396.76705) (xy 429.783494 -396.710916) (xy 429.792479 -396.703323) (xy 429.802931 -396.682277)
			(xy 429.80356 -396.67053) (xy 429.80356 -387.132322) (xy 429.803301 -387.125433) (xy 429.799575 -387.112167)
			(xy 429.796194 -387.10616) (xy 429.75016 -387.028798) (xy 429.663806 -386.870817) (xy 429.584111 -386.709374)
			(xy 429.511215 -386.54475) (xy 429.445244 -386.377231) (xy 429.386312 -386.207107) (xy 429.334522 -386.034675)
			(xy 429.289965 -385.860234) (xy 429.252717 -385.684087) (xy 429.222843 -385.506541) (xy 429.200396 -385.327904)
			(xy 429.185414 -385.148487) (xy 429.177923 -384.968601) (xy 429.17745 -384.87858) (xy 429.177965 -384.784031)
			(xy 429.186244 -384.595114) (xy 429.202785 -384.406741) (xy 429.227558 -384.219273) (xy 429.260513 -384.033069)
			(xy 429.301588 -383.848486) (xy 429.350705 -383.665878) (xy 429.407769 -383.485596) (xy 429.47267 -383.307984)
			(xy 429.545284 -383.133384) (xy 429.625473 -382.96213) (xy 429.713082 -382.794551) (xy 429.807943 -382.630968)
			(xy 429.909874 -382.471694) (xy 430.01868 -382.317036) (xy 430.134153 -382.167289) (xy 430.25607 -382.022741)
			(xy 430.384198 -381.883668) (xy 430.518292 -381.750338) (xy 430.658095 -381.623006) (xy 430.803337 -381.501917)
			(xy 430.953741 -381.387302) (xy 431.109019 -381.279381) (xy 431.268872 -381.178361) (xy 431.432995 -381.084437)
			(xy 431.51679 -381.04064) (xy 431.527712 -381.035052) (xy 431.541682 -381.015494) (xy 431.55616 -380.922276)
			(xy 431.557372 -380.910331) (xy 431.549943 -380.887535) (xy 431.541936 -380.878588) (xy 426.107606 -375.444258)
			(xy 426.100211 -375.437404) (xy 426.081612 -375.429658) (xy 426.071538 -375.429272) (xy 289.817556 -375.429272)
			(xy 289.807489 -375.429702) (xy 289.788893 -375.437425) (xy 289.781488 -375.444258) (xy 288.43224 -376.793506)
			(xy 288.425128 -376.81916) (xy 288.428176 -376.832114) (xy 288.433041 -376.853049) (xy 288.438262 -376.895713)
			(xy 288.43859 -376.917204) (xy 288.438128 -376.943373) (xy 288.43047 -376.995149) (xy 288.41532 -377.045247)
			(xy 288.393004 -377.09259) (xy 288.364002 -377.136159) (xy 288.328937 -377.175016) (xy 288.30905 -377.192032)
			(xy 288.300761 -377.199631) (xy 288.291128 -377.219921) (xy 288.290508 -377.231148) (xy 288.290508 -377.444567)
			(xy 300.335454 -377.444567) (xy 300.335454 -377.390033) (xy 300.343215 -377.336054) (xy 300.358579 -377.283729)
			(xy 300.381233 -377.234123) (xy 300.410717 -377.188246) (xy 300.446429 -377.147031) (xy 300.487642 -377.111319)
			(xy 300.533519 -377.081835) (xy 300.583125 -377.059181) (xy 300.63545 -377.043816) (xy 300.689429 -377.036055)
			(xy 300.716696 -377.035568) (xy 301.580296 -377.035568) (xy 301.607569 -377.035971) (xy 301.661561 -377.043734)
			(xy 301.713898 -377.059101) (xy 301.763516 -377.08176) (xy 301.809403 -377.11125) (xy 301.850627 -377.14697)
			(xy 301.886348 -377.188193) (xy 301.915838 -377.234081) (xy 301.938498 -377.283698) (xy 301.953866 -377.336035)
			(xy 301.961628 -377.390027) (xy 301.961628 -377.444567) (xy 307.142654 -377.444567) (xy 307.142654 -377.390033)
			(xy 307.150415 -377.336054) (xy 307.165779 -377.283729) (xy 307.188433 -377.234123) (xy 307.217917 -377.188246)
			(xy 307.253629 -377.147031) (xy 307.294842 -377.111319) (xy 307.340719 -377.081835) (xy 307.390325 -377.059181)
			(xy 307.44265 -377.043816) (xy 307.496629 -377.036055) (xy 307.523896 -377.035568) (xy 308.387496 -377.035568)
			(xy 308.414769 -377.035971) (xy 308.468761 -377.043734) (xy 308.521098 -377.059101) (xy 308.570716 -377.08176)
			(xy 308.616603 -377.11125) (xy 308.657827 -377.14697) (xy 308.693548 -377.188193) (xy 308.723038 -377.234081)
			(xy 308.745698 -377.283698) (xy 308.761066 -377.336035) (xy 308.768828 -377.390027) (xy 308.768828 -377.444567)
			(xy 313.949854 -377.444567) (xy 313.949854 -377.390033) (xy 313.957615 -377.336054) (xy 313.972979 -377.283729)
			(xy 313.995633 -377.234123) (xy 314.025117 -377.188246) (xy 314.060829 -377.147031) (xy 314.102042 -377.111319)
			(xy 314.147919 -377.081835) (xy 314.197525 -377.059181) (xy 314.24985 -377.043816) (xy 314.303829 -377.036055)
			(xy 314.331096 -377.035568) (xy 315.194696 -377.035568) (xy 315.221969 -377.035971) (xy 315.275961 -377.043734)
			(xy 315.328298 -377.059101) (xy 315.377916 -377.08176) (xy 315.423803 -377.11125) (xy 315.465027 -377.14697)
			(xy 315.500748 -377.188193) (xy 315.530238 -377.234081) (xy 315.552898 -377.283698) (xy 315.568266 -377.336035)
			(xy 315.576028 -377.390027) (xy 315.576028 -377.444567) (xy 320.757054 -377.444567) (xy 320.757054 -377.390033)
			(xy 320.764815 -377.336054) (xy 320.780179 -377.283729) (xy 320.802833 -377.234123) (xy 320.832317 -377.188246)
			(xy 320.868029 -377.147031) (xy 320.909242 -377.111319) (xy 320.955119 -377.081835) (xy 321.004725 -377.059181)
			(xy 321.05705 -377.043816) (xy 321.111029 -377.036055) (xy 321.138296 -377.035568) (xy 322.001896 -377.035568)
			(xy 322.029169 -377.035971) (xy 322.083161 -377.043734) (xy 322.135498 -377.059101) (xy 322.185116 -377.08176)
			(xy 322.231003 -377.11125) (xy 322.272227 -377.14697) (xy 322.307948 -377.188193) (xy 322.337438 -377.234081)
			(xy 322.360098 -377.283698) (xy 322.375466 -377.336035) (xy 322.383228 -377.390027) (xy 322.383228 -377.444567)
			(xy 324.160654 -377.444567) (xy 324.160654 -377.390033) (xy 324.168415 -377.336054) (xy 324.183779 -377.283729)
			(xy 324.206433 -377.234123) (xy 324.235917 -377.188246) (xy 324.271629 -377.147031) (xy 324.312842 -377.111319)
			(xy 324.358719 -377.081835) (xy 324.408325 -377.059181) (xy 324.46065 -377.043816) (xy 324.514629 -377.036055)
			(xy 324.541896 -377.035568) (xy 325.405496 -377.035568) (xy 325.432769 -377.035971) (xy 325.486761 -377.043734)
			(xy 325.539098 -377.059101) (xy 325.588716 -377.08176) (xy 325.634603 -377.11125) (xy 325.675827 -377.14697)
			(xy 325.711548 -377.188193) (xy 325.741038 -377.234081) (xy 325.763698 -377.283698) (xy 325.779066 -377.336035)
			(xy 325.786828 -377.390027) (xy 325.786828 -377.444571) (xy 332.863132 -377.444571) (xy 332.863132 -377.390029)
			(xy 332.870894 -377.336043) (xy 332.886261 -377.283711) (xy 332.908921 -377.234098) (xy 332.93841 -377.188216)
			(xy 332.974129 -377.146998) (xy 333.015351 -377.111284) (xy 333.061237 -377.081799) (xy 333.110852 -377.059146)
			(xy 333.163186 -377.043785) (xy 333.217173 -377.036028) (xy 333.244444 -377.035568) (xy 334.108044 -377.035568)
			(xy 334.135313 -377.035998) (xy 334.189297 -377.043765) (xy 334.241625 -377.059135) (xy 334.291233 -377.081796)
			(xy 334.337112 -377.111285) (xy 334.378328 -377.147003) (xy 334.414041 -377.188223) (xy 334.443525 -377.234105)
			(xy 334.46618 -377.283716) (xy 334.481544 -377.336047) (xy 334.489306 -377.39003) (xy 334.489306 -377.44457)
			(xy 334.489306 -377.444571) (xy 339.670332 -377.444571) (xy 339.670332 -377.390029) (xy 339.678094 -377.336043)
			(xy 339.693461 -377.283711) (xy 339.716121 -377.234098) (xy 339.74561 -377.188216) (xy 339.781329 -377.146998)
			(xy 339.822551 -377.111284) (xy 339.868437 -377.081799) (xy 339.918052 -377.059146) (xy 339.970386 -377.043785)
			(xy 340.024373 -377.036028) (xy 340.051644 -377.035568) (xy 340.915244 -377.035568) (xy 340.942513 -377.035998)
			(xy 340.996497 -377.043765) (xy 341.048825 -377.059135) (xy 341.098433 -377.081796) (xy 341.144312 -377.111285)
			(xy 341.185528 -377.147003) (xy 341.221241 -377.188223) (xy 341.250725 -377.234105) (xy 341.27338 -377.283716)
			(xy 341.288744 -377.336047) (xy 341.296506 -377.39003) (xy 341.296506 -377.44457) (xy 341.296506 -377.444571)
			(xy 346.477532 -377.444571) (xy 346.477532 -377.390029) (xy 346.485294 -377.336043) (xy 346.500661 -377.283711)
			(xy 346.523321 -377.234098) (xy 346.55281 -377.188216) (xy 346.588529 -377.146998) (xy 346.629751 -377.111284)
			(xy 346.675637 -377.081799) (xy 346.725252 -377.059146) (xy 346.777586 -377.043785) (xy 346.831573 -377.036028)
			(xy 346.858844 -377.035568) (xy 347.722444 -377.035568) (xy 347.749713 -377.035998) (xy 347.803697 -377.043765)
			(xy 347.856025 -377.059135) (xy 347.905633 -377.081796) (xy 347.951512 -377.111285) (xy 347.992728 -377.147003)
			(xy 348.028441 -377.188223) (xy 348.057925 -377.234105) (xy 348.08058 -377.283716) (xy 348.095944 -377.336047)
			(xy 348.103706 -377.39003) (xy 348.103706 -377.44457) (xy 348.103706 -377.444571) (xy 353.284732 -377.444571)
			(xy 353.284732 -377.390029) (xy 353.292494 -377.336043) (xy 353.307861 -377.283711) (xy 353.330521 -377.234098)
			(xy 353.36001 -377.188216) (xy 353.395729 -377.146998) (xy 353.436951 -377.111284) (xy 353.482837 -377.081799)
			(xy 353.532452 -377.059146) (xy 353.584786 -377.043785) (xy 353.638773 -377.036028) (xy 353.666044 -377.035568)
			(xy 354.529644 -377.035568) (xy 354.556913 -377.035998) (xy 354.610897 -377.043765) (xy 354.663225 -377.059135)
			(xy 354.712833 -377.081796) (xy 354.758712 -377.111285) (xy 354.799928 -377.147003) (xy 354.835641 -377.188223)
			(xy 354.865125 -377.234105) (xy 354.88778 -377.283716) (xy 354.903144 -377.336047) (xy 354.910906 -377.39003)
			(xy 354.910906 -377.44457) (xy 354.910906 -377.444571) (xy 356.688332 -377.444571) (xy 356.688332 -377.390029)
			(xy 356.696094 -377.336043) (xy 356.711461 -377.283711) (xy 356.734121 -377.234098) (xy 356.76361 -377.188216)
			(xy 356.799329 -377.146998) (xy 356.840551 -377.111284) (xy 356.886437 -377.081799) (xy 356.936052 -377.059146)
			(xy 356.988386 -377.043785) (xy 357.042373 -377.036028) (xy 357.069644 -377.035568) (xy 357.933244 -377.035568)
			(xy 357.960513 -377.035998) (xy 358.014497 -377.043765) (xy 358.066825 -377.059135) (xy 358.116433 -377.081796)
			(xy 358.162312 -377.111285) (xy 358.203528 -377.147003) (xy 358.239241 -377.188223) (xy 358.268725 -377.234105)
			(xy 358.29138 -377.283716) (xy 358.306744 -377.336047) (xy 358.314506 -377.39003) (xy 358.314506 -377.444567)
			(xy 367.435654 -377.444567) (xy 367.435654 -377.390033) (xy 367.443415 -377.336054) (xy 367.458779 -377.28373)
			(xy 367.481433 -377.234124) (xy 367.510916 -377.188247) (xy 367.546627 -377.147033) (xy 367.587841 -377.11132)
			(xy 367.633717 -377.081837) (xy 367.683322 -377.059182) (xy 367.735647 -377.043817) (xy 367.789625 -377.036055)
			(xy 367.816892 -377.035568) (xy 368.680492 -377.035568) (xy 368.707766 -377.035971) (xy 368.761757 -377.043733)
			(xy 368.814095 -377.0591) (xy 368.863713 -377.081759) (xy 368.909602 -377.111248) (xy 368.950826 -377.146968)
			(xy 368.986547 -377.188192) (xy 369.016038 -377.23408) (xy 369.038698 -377.283697) (xy 369.054065 -377.336035)
			(xy 369.061828 -377.390026) (xy 369.061828 -377.444567) (xy 374.242854 -377.444567) (xy 374.242854 -377.390033)
			(xy 374.250615 -377.336054) (xy 374.265979 -377.28373) (xy 374.288633 -377.234124) (xy 374.318116 -377.188247)
			(xy 374.353827 -377.147033) (xy 374.395041 -377.11132) (xy 374.440917 -377.081837) (xy 374.490522 -377.059182)
			(xy 374.542847 -377.043817) (xy 374.596825 -377.036055) (xy 374.624092 -377.035568) (xy 375.487692 -377.035568)
			(xy 375.514966 -377.035971) (xy 375.568957 -377.043733) (xy 375.621295 -377.0591) (xy 375.670913 -377.081759)
			(xy 375.716802 -377.111248) (xy 375.758026 -377.146968) (xy 375.793747 -377.188192) (xy 375.823238 -377.23408)
			(xy 375.845898 -377.283697) (xy 375.861265 -377.336035) (xy 375.869028 -377.390026) (xy 375.869028 -377.444567)
			(xy 381.050054 -377.444567) (xy 381.050054 -377.390033) (xy 381.057815 -377.336054) (xy 381.073179 -377.28373)
			(xy 381.095833 -377.234124) (xy 381.125316 -377.188247) (xy 381.161027 -377.147033) (xy 381.202241 -377.11132)
			(xy 381.248117 -377.081837) (xy 381.297722 -377.059182) (xy 381.350047 -377.043817) (xy 381.404025 -377.036055)
			(xy 381.431292 -377.035568) (xy 382.294892 -377.035568) (xy 382.322166 -377.035971) (xy 382.376157 -377.043733)
			(xy 382.428495 -377.0591) (xy 382.478113 -377.081759) (xy 382.524002 -377.111248) (xy 382.565226 -377.146968)
			(xy 382.600947 -377.188192) (xy 382.630438 -377.23408) (xy 382.653098 -377.283697) (xy 382.668465 -377.336035)
			(xy 382.676228 -377.390026) (xy 382.676228 -377.444567) (xy 387.857254 -377.444567) (xy 387.857254 -377.390033)
			(xy 387.865015 -377.336054) (xy 387.880379 -377.28373) (xy 387.903033 -377.234124) (xy 387.932516 -377.188247)
			(xy 387.968227 -377.147033) (xy 388.009441 -377.11132) (xy 388.055317 -377.081837) (xy 388.104922 -377.059182)
			(xy 388.157247 -377.043817) (xy 388.211225 -377.036055) (xy 388.238492 -377.035568) (xy 389.102092 -377.035568)
			(xy 389.129366 -377.035971) (xy 389.183357 -377.043733) (xy 389.235695 -377.0591) (xy 389.285313 -377.081759)
			(xy 389.331202 -377.111248) (xy 389.372426 -377.146968) (xy 389.408147 -377.188192) (xy 389.437638 -377.23408)
			(xy 389.460298 -377.283697) (xy 389.475665 -377.336035) (xy 389.483428 -377.390026) (xy 389.483428 -377.444567)
			(xy 391.260854 -377.444567) (xy 391.260854 -377.390033) (xy 391.268615 -377.336054) (xy 391.283979 -377.28373)
			(xy 391.306633 -377.234124) (xy 391.336116 -377.188247) (xy 391.371827 -377.147033) (xy 391.413041 -377.11132)
			(xy 391.458917 -377.081837) (xy 391.508522 -377.059182) (xy 391.560847 -377.043817) (xy 391.614825 -377.036055)
			(xy 391.642092 -377.035568) (xy 392.505692 -377.035568) (xy 392.532966 -377.035971) (xy 392.586957 -377.043733)
			(xy 392.639295 -377.0591) (xy 392.688913 -377.081759) (xy 392.734802 -377.111248) (xy 392.776026 -377.146968)
			(xy 392.811747 -377.188192) (xy 392.841238 -377.23408) (xy 392.863898 -377.283697) (xy 392.879265 -377.336035)
			(xy 392.887028 -377.390026) (xy 392.887028 -377.444571) (xy 399.963332 -377.444571) (xy 399.963332 -377.390029)
			(xy 399.971094 -377.336043) (xy 399.986461 -377.283711) (xy 400.00912 -377.234099) (xy 400.038609 -377.188217)
			(xy 400.074328 -377.147) (xy 400.11555 -377.111285) (xy 400.161435 -377.081801) (xy 400.211049 -377.059147)
			(xy 400.263382 -377.043786) (xy 400.317369 -377.036029) (xy 400.34464 -377.035568) (xy 401.20824 -377.035568)
			(xy 401.23551 -377.035997) (xy 401.289493 -377.043764) (xy 401.341822 -377.059134) (xy 401.391431 -377.081794)
			(xy 401.437311 -377.111284) (xy 401.478527 -377.147002) (xy 401.51424 -377.188222) (xy 401.543725 -377.234104)
			(xy 401.56638 -377.283716) (xy 401.581744 -377.336046) (xy 401.589506 -377.39003) (xy 401.589506 -377.44457)
			(xy 401.589506 -377.444571) (xy 406.770532 -377.444571) (xy 406.770532 -377.390029) (xy 406.778294 -377.336043)
			(xy 406.793661 -377.283711) (xy 406.81632 -377.234099) (xy 406.845809 -377.188217) (xy 406.881528 -377.147)
			(xy 406.92275 -377.111285) (xy 406.968635 -377.081801) (xy 407.018249 -377.059147) (xy 407.070582 -377.043786)
			(xy 407.124569 -377.036029) (xy 407.15184 -377.035568) (xy 408.01544 -377.035568) (xy 408.04271 -377.035997)
			(xy 408.096693 -377.043764) (xy 408.149022 -377.059134) (xy 408.198631 -377.081794) (xy 408.244511 -377.111284)
			(xy 408.285727 -377.147002) (xy 408.32144 -377.188222) (xy 408.350925 -377.234104) (xy 408.37358 -377.283716)
			(xy 408.388944 -377.336046) (xy 408.396706 -377.39003) (xy 408.396706 -377.44457) (xy 408.396706 -377.444571)
			(xy 413.577732 -377.444571) (xy 413.577732 -377.390029) (xy 413.585494 -377.336043) (xy 413.600861 -377.283711)
			(xy 413.62352 -377.234099) (xy 413.653009 -377.188217) (xy 413.688728 -377.147) (xy 413.72995 -377.111285)
			(xy 413.775835 -377.081801) (xy 413.825449 -377.059147) (xy 413.877782 -377.043786) (xy 413.931769 -377.036029)
			(xy 413.95904 -377.035568) (xy 414.82264 -377.035568) (xy 414.84991 -377.035997) (xy 414.903893 -377.043764)
			(xy 414.956222 -377.059134) (xy 415.005831 -377.081794) (xy 415.051711 -377.111284) (xy 415.092927 -377.147002)
			(xy 415.12864 -377.188222) (xy 415.158125 -377.234104) (xy 415.18078 -377.283716) (xy 415.196144 -377.336046)
			(xy 415.203906 -377.39003) (xy 415.203906 -377.44457) (xy 415.203906 -377.444571) (xy 420.384932 -377.444571)
			(xy 420.384932 -377.390029) (xy 420.392694 -377.336043) (xy 420.408061 -377.283711) (xy 420.43072 -377.234099)
			(xy 420.460209 -377.188217) (xy 420.495928 -377.147) (xy 420.53715 -377.111285) (xy 420.583035 -377.081801)
			(xy 420.632649 -377.059147) (xy 420.684982 -377.043786) (xy 420.738969 -377.036029) (xy 420.76624 -377.035568)
			(xy 421.62984 -377.035568) (xy 421.65711 -377.035997) (xy 421.711093 -377.043764) (xy 421.763422 -377.059134)
			(xy 421.813031 -377.081794) (xy 421.858911 -377.111284) (xy 421.900127 -377.147002) (xy 421.93584 -377.188222)
			(xy 421.965325 -377.234104) (xy 421.98798 -377.283716) (xy 422.003344 -377.336046) (xy 422.011106 -377.39003)
			(xy 422.011106 -377.44457) (xy 422.011106 -377.444571) (xy 423.788532 -377.444571) (xy 423.788532 -377.390029)
			(xy 423.796294 -377.336043) (xy 423.811661 -377.283711) (xy 423.83432 -377.234099) (xy 423.863809 -377.188217)
			(xy 423.899528 -377.147) (xy 423.94075 -377.111285) (xy 423.986635 -377.081801) (xy 424.036249 -377.059147)
			(xy 424.088582 -377.043786) (xy 424.142569 -377.036029) (xy 424.16984 -377.035568) (xy 425.03344 -377.035568)
			(xy 425.06071 -377.035997) (xy 425.114693 -377.043764) (xy 425.167022 -377.059134) (xy 425.216631 -377.081794)
			(xy 425.262511 -377.111284) (xy 425.303727 -377.147002) (xy 425.33944 -377.188222) (xy 425.368925 -377.234104)
			(xy 425.39158 -377.283716) (xy 425.406944 -377.336046) (xy 425.414706 -377.39003) (xy 425.414706 -377.44457)
			(xy 425.406944 -377.498554) (xy 425.39158 -377.550884) (xy 425.368925 -377.600496) (xy 425.33944 -377.646378)
			(xy 425.303727 -377.687598) (xy 425.262511 -377.723316) (xy 425.216631 -377.752806) (xy 425.167022 -377.775466)
			(xy 425.114693 -377.790836) (xy 425.06071 -377.798603) (xy 425.03344 -377.799092) (xy 424.16984 -377.799092)
			(xy 424.142569 -377.798571) (xy 424.088582 -377.790814) (xy 424.036249 -377.775453) (xy 423.986635 -377.752799)
			(xy 423.94075 -377.723315) (xy 423.899528 -377.6876) (xy 423.863809 -377.646383) (xy 423.83432 -377.600501)
			(xy 423.811661 -377.550889) (xy 423.796294 -377.498557) (xy 423.788532 -377.444571) (xy 422.011106 -377.444571)
			(xy 422.003344 -377.498554) (xy 421.98798 -377.550884) (xy 421.965325 -377.600496) (xy 421.93584 -377.646378)
			(xy 421.900127 -377.687598) (xy 421.858911 -377.723316) (xy 421.813031 -377.752806) (xy 421.763422 -377.775466)
			(xy 421.711093 -377.790836) (xy 421.65711 -377.798603) (xy 421.62984 -377.799092) (xy 420.76624 -377.799092)
			(xy 420.738969 -377.798571) (xy 420.684982 -377.790814) (xy 420.632649 -377.775453) (xy 420.583035 -377.752799)
			(xy 420.53715 -377.723315) (xy 420.495928 -377.6876) (xy 420.460209 -377.646383) (xy 420.43072 -377.600501)
			(xy 420.408061 -377.550889) (xy 420.392694 -377.498557) (xy 420.384932 -377.444571) (xy 415.203906 -377.444571)
			(xy 415.196144 -377.498554) (xy 415.18078 -377.550884) (xy 415.158125 -377.600496) (xy 415.12864 -377.646378)
			(xy 415.092927 -377.687598) (xy 415.051711 -377.723316) (xy 415.005831 -377.752806) (xy 414.956222 -377.775466)
			(xy 414.903893 -377.790836) (xy 414.84991 -377.798603) (xy 414.82264 -377.799092) (xy 413.95904 -377.799092)
			(xy 413.931769 -377.798571) (xy 413.877782 -377.790814) (xy 413.825449 -377.775453) (xy 413.775835 -377.752799)
			(xy 413.72995 -377.723315) (xy 413.688728 -377.6876) (xy 413.653009 -377.646383) (xy 413.62352 -377.600501)
			(xy 413.600861 -377.550889) (xy 413.585494 -377.498557) (xy 413.577732 -377.444571) (xy 408.396706 -377.444571)
			(xy 408.388944 -377.498554) (xy 408.37358 -377.550884) (xy 408.350925 -377.600496) (xy 408.32144 -377.646378)
			(xy 408.285727 -377.687598) (xy 408.244511 -377.723316) (xy 408.198631 -377.752806) (xy 408.149022 -377.775466)
			(xy 408.096693 -377.790836) (xy 408.04271 -377.798603) (xy 408.01544 -377.799092) (xy 407.15184 -377.799092)
			(xy 407.124569 -377.798571) (xy 407.070582 -377.790814) (xy 407.018249 -377.775453) (xy 406.968635 -377.752799)
			(xy 406.92275 -377.723315) (xy 406.881528 -377.6876) (xy 406.845809 -377.646383) (xy 406.81632 -377.600501)
			(xy 406.793661 -377.550889) (xy 406.778294 -377.498557) (xy 406.770532 -377.444571) (xy 401.589506 -377.444571)
			(xy 401.581744 -377.498554) (xy 401.56638 -377.550884) (xy 401.543725 -377.600496) (xy 401.51424 -377.646378)
			(xy 401.478527 -377.687598) (xy 401.437311 -377.723316) (xy 401.391431 -377.752806) (xy 401.341822 -377.775466)
			(xy 401.289493 -377.790836) (xy 401.23551 -377.798603) (xy 401.20824 -377.799092) (xy 400.34464 -377.799092)
			(xy 400.317369 -377.798571) (xy 400.263382 -377.790814) (xy 400.211049 -377.775453) (xy 400.161435 -377.752799)
			(xy 400.11555 -377.723315) (xy 400.074328 -377.6876) (xy 400.038609 -377.646383) (xy 400.00912 -377.600501)
			(xy 399.986461 -377.550889) (xy 399.971094 -377.498557) (xy 399.963332 -377.444571) (xy 392.887028 -377.444571)
			(xy 392.887028 -377.444574) (xy 392.879265 -377.498565) (xy 392.863898 -377.550903) (xy 392.841238 -377.60052)
			(xy 392.811747 -377.646408) (xy 392.776026 -377.687632) (xy 392.734802 -377.723352) (xy 392.688913 -377.752841)
			(xy 392.639295 -377.7755) (xy 392.586957 -377.790867) (xy 392.532966 -377.798629) (xy 392.505692 -377.799092)
			(xy 391.642092 -377.799092) (xy 391.614825 -377.798545) (xy 391.560847 -377.790783) (xy 391.508522 -377.775418)
			(xy 391.458917 -377.752763) (xy 391.413041 -377.72328) (xy 391.371827 -377.687567) (xy 391.336116 -377.646353)
			(xy 391.306633 -377.600476) (xy 391.283979 -377.55087) (xy 391.268615 -377.498546) (xy 391.260854 -377.444567)
			(xy 389.483428 -377.444567) (xy 389.483428 -377.444574) (xy 389.475665 -377.498565) (xy 389.460298 -377.550903)
			(xy 389.437638 -377.60052) (xy 389.408147 -377.646408) (xy 389.372426 -377.687632) (xy 389.331202 -377.723352)
			(xy 389.285313 -377.752841) (xy 389.235695 -377.7755) (xy 389.183357 -377.790867) (xy 389.129366 -377.798629)
			(xy 389.102092 -377.799092) (xy 388.238492 -377.799092) (xy 388.211225 -377.798545) (xy 388.157247 -377.790783)
			(xy 388.104922 -377.775418) (xy 388.055317 -377.752763) (xy 388.009441 -377.72328) (xy 387.968227 -377.687567)
			(xy 387.932516 -377.646353) (xy 387.903033 -377.600476) (xy 387.880379 -377.55087) (xy 387.865015 -377.498546)
			(xy 387.857254 -377.444567) (xy 382.676228 -377.444567) (xy 382.676228 -377.444574) (xy 382.668465 -377.498565)
			(xy 382.653098 -377.550903) (xy 382.630438 -377.60052) (xy 382.600947 -377.646408) (xy 382.565226 -377.687632)
			(xy 382.524002 -377.723352) (xy 382.478113 -377.752841) (xy 382.428495 -377.7755) (xy 382.376157 -377.790867)
			(xy 382.322166 -377.798629) (xy 382.294892 -377.799092) (xy 381.431292 -377.799092) (xy 381.404025 -377.798545)
			(xy 381.350047 -377.790783) (xy 381.297722 -377.775418) (xy 381.248117 -377.752763) (xy 381.202241 -377.72328)
			(xy 381.161027 -377.687567) (xy 381.125316 -377.646353) (xy 381.095833 -377.600476) (xy 381.073179 -377.55087)
			(xy 381.057815 -377.498546) (xy 381.050054 -377.444567) (xy 375.869028 -377.444567) (xy 375.869028 -377.444574)
			(xy 375.861265 -377.498565) (xy 375.845898 -377.550903) (xy 375.823238 -377.60052) (xy 375.793747 -377.646408)
			(xy 375.758026 -377.687632) (xy 375.716802 -377.723352) (xy 375.670913 -377.752841) (xy 375.621295 -377.7755)
			(xy 375.568957 -377.790867) (xy 375.514966 -377.798629) (xy 375.487692 -377.799092) (xy 374.624092 -377.799092)
			(xy 374.596825 -377.798545) (xy 374.542847 -377.790783) (xy 374.490522 -377.775418) (xy 374.440917 -377.752763)
			(xy 374.395041 -377.72328) (xy 374.353827 -377.687567) (xy 374.318116 -377.646353) (xy 374.288633 -377.600476)
			(xy 374.265979 -377.55087) (xy 374.250615 -377.498546) (xy 374.242854 -377.444567) (xy 369.061828 -377.444567)
			(xy 369.061828 -377.444574) (xy 369.054065 -377.498565) (xy 369.038698 -377.550903) (xy 369.016038 -377.60052)
			(xy 368.986547 -377.646408) (xy 368.950826 -377.687632) (xy 368.909602 -377.723352) (xy 368.863713 -377.752841)
			(xy 368.814095 -377.7755) (xy 368.761757 -377.790867) (xy 368.707766 -377.798629) (xy 368.680492 -377.799092)
			(xy 367.816892 -377.799092) (xy 367.789625 -377.798545) (xy 367.735647 -377.790783) (xy 367.683322 -377.775418)
			(xy 367.633717 -377.752763) (xy 367.587841 -377.72328) (xy 367.546627 -377.687567) (xy 367.510916 -377.646353)
			(xy 367.481433 -377.600476) (xy 367.458779 -377.55087) (xy 367.443415 -377.498546) (xy 367.435654 -377.444567)
			(xy 358.314506 -377.444567) (xy 358.314506 -377.44457) (xy 358.306744 -377.498553) (xy 358.29138 -377.550884)
			(xy 358.268725 -377.600495) (xy 358.239241 -377.646377) (xy 358.203528 -377.687597) (xy 358.162312 -377.723315)
			(xy 358.116433 -377.752804) (xy 358.066825 -377.775465) (xy 358.014497 -377.790835) (xy 357.960513 -377.798602)
			(xy 357.933244 -377.799092) (xy 357.069644 -377.799092) (xy 357.042373 -377.798572) (xy 356.988386 -377.790815)
			(xy 356.936052 -377.775454) (xy 356.886437 -377.752801) (xy 356.840551 -377.723316) (xy 356.799329 -377.687602)
			(xy 356.76361 -377.646384) (xy 356.734121 -377.600502) (xy 356.711461 -377.550889) (xy 356.696094 -377.498557)
			(xy 356.688332 -377.444571) (xy 354.910906 -377.444571) (xy 354.903144 -377.498553) (xy 354.88778 -377.550884)
			(xy 354.865125 -377.600495) (xy 354.835641 -377.646377) (xy 354.799928 -377.687597) (xy 354.758712 -377.723315)
			(xy 354.712833 -377.752804) (xy 354.663225 -377.775465) (xy 354.610897 -377.790835) (xy 354.556913 -377.798602)
			(xy 354.529644 -377.799092) (xy 353.666044 -377.799092) (xy 353.638773 -377.798572) (xy 353.584786 -377.790815)
			(xy 353.532452 -377.775454) (xy 353.482837 -377.752801) (xy 353.436951 -377.723316) (xy 353.395729 -377.687602)
			(xy 353.36001 -377.646384) (xy 353.330521 -377.600502) (xy 353.307861 -377.550889) (xy 353.292494 -377.498557)
			(xy 353.284732 -377.444571) (xy 348.103706 -377.444571) (xy 348.095944 -377.498553) (xy 348.08058 -377.550884)
			(xy 348.057925 -377.600495) (xy 348.028441 -377.646377) (xy 347.992728 -377.687597) (xy 347.951512 -377.723315)
			(xy 347.905633 -377.752804) (xy 347.856025 -377.775465) (xy 347.803697 -377.790835) (xy 347.749713 -377.798602)
			(xy 347.722444 -377.799092) (xy 346.858844 -377.799092) (xy 346.831573 -377.798572) (xy 346.777586 -377.790815)
			(xy 346.725252 -377.775454) (xy 346.675637 -377.752801) (xy 346.629751 -377.723316) (xy 346.588529 -377.687602)
			(xy 346.55281 -377.646384) (xy 346.523321 -377.600502) (xy 346.500661 -377.550889) (xy 346.485294 -377.498557)
			(xy 346.477532 -377.444571) (xy 341.296506 -377.444571) (xy 341.288744 -377.498553) (xy 341.27338 -377.550884)
			(xy 341.250725 -377.600495) (xy 341.221241 -377.646377) (xy 341.185528 -377.687597) (xy 341.144312 -377.723315)
			(xy 341.098433 -377.752804) (xy 341.048825 -377.775465) (xy 340.996497 -377.790835) (xy 340.942513 -377.798602)
			(xy 340.915244 -377.799092) (xy 340.051644 -377.799092) (xy 340.024373 -377.798572) (xy 339.970386 -377.790815)
			(xy 339.918052 -377.775454) (xy 339.868437 -377.752801) (xy 339.822551 -377.723316) (xy 339.781329 -377.687602)
			(xy 339.74561 -377.646384) (xy 339.716121 -377.600502) (xy 339.693461 -377.550889) (xy 339.678094 -377.498557)
			(xy 339.670332 -377.444571) (xy 334.489306 -377.444571) (xy 334.481544 -377.498553) (xy 334.46618 -377.550884)
			(xy 334.443525 -377.600495) (xy 334.414041 -377.646377) (xy 334.378328 -377.687597) (xy 334.337112 -377.723315)
			(xy 334.291233 -377.752804) (xy 334.241625 -377.775465) (xy 334.189297 -377.790835) (xy 334.135313 -377.798602)
			(xy 334.108044 -377.799092) (xy 333.244444 -377.799092) (xy 333.217173 -377.798572) (xy 333.163186 -377.790815)
			(xy 333.110852 -377.775454) (xy 333.061237 -377.752801) (xy 333.015351 -377.723316) (xy 332.974129 -377.687602)
			(xy 332.93841 -377.646384) (xy 332.908921 -377.600502) (xy 332.886261 -377.550889) (xy 332.870894 -377.498557)
			(xy 332.863132 -377.444571) (xy 325.786828 -377.444571) (xy 325.786828 -377.444573) (xy 325.779066 -377.498565)
			(xy 325.763698 -377.550902) (xy 325.741038 -377.600519) (xy 325.711548 -377.646407) (xy 325.675827 -377.68763)
			(xy 325.634603 -377.72335) (xy 325.588716 -377.75284) (xy 325.539098 -377.775499) (xy 325.486761 -377.790866)
			(xy 325.432769 -377.798629) (xy 325.405496 -377.799092) (xy 324.541896 -377.799092) (xy 324.514629 -377.798545)
			(xy 324.46065 -377.790784) (xy 324.408325 -377.775419) (xy 324.358719 -377.752765) (xy 324.312842 -377.723281)
			(xy 324.271629 -377.687569) (xy 324.235917 -377.646354) (xy 324.206433 -377.600477) (xy 324.183779 -377.550871)
			(xy 324.168415 -377.498546) (xy 324.160654 -377.444567) (xy 322.383228 -377.444567) (xy 322.383228 -377.444573)
			(xy 322.375466 -377.498565) (xy 322.360098 -377.550902) (xy 322.337438 -377.600519) (xy 322.307948 -377.646407)
			(xy 322.272227 -377.68763) (xy 322.231003 -377.72335) (xy 322.185116 -377.75284) (xy 322.135498 -377.775499)
			(xy 322.083161 -377.790866) (xy 322.029169 -377.798629) (xy 322.001896 -377.799092) (xy 321.138296 -377.799092)
			(xy 321.111029 -377.798545) (xy 321.05705 -377.790784) (xy 321.004725 -377.775419) (xy 320.955119 -377.752765)
			(xy 320.909242 -377.723281) (xy 320.868029 -377.687569) (xy 320.832317 -377.646354) (xy 320.802833 -377.600477)
			(xy 320.780179 -377.550871) (xy 320.764815 -377.498546) (xy 320.757054 -377.444567) (xy 315.576028 -377.444567)
			(xy 315.576028 -377.444573) (xy 315.568266 -377.498565) (xy 315.552898 -377.550902) (xy 315.530238 -377.600519)
			(xy 315.500748 -377.646407) (xy 315.465027 -377.68763) (xy 315.423803 -377.72335) (xy 315.377916 -377.75284)
			(xy 315.328298 -377.775499) (xy 315.275961 -377.790866) (xy 315.221969 -377.798629) (xy 315.194696 -377.799092)
			(xy 314.331096 -377.799092) (xy 314.303829 -377.798545) (xy 314.24985 -377.790784) (xy 314.197525 -377.775419)
			(xy 314.147919 -377.752765) (xy 314.102042 -377.723281) (xy 314.060829 -377.687569) (xy 314.025117 -377.646354)
			(xy 313.995633 -377.600477) (xy 313.972979 -377.550871) (xy 313.957615 -377.498546) (xy 313.949854 -377.444567)
			(xy 308.768828 -377.444567) (xy 308.768828 -377.444573) (xy 308.761066 -377.498565) (xy 308.745698 -377.550902)
			(xy 308.723038 -377.600519) (xy 308.693548 -377.646407) (xy 308.657827 -377.68763) (xy 308.616603 -377.72335)
			(xy 308.570716 -377.75284) (xy 308.521098 -377.775499) (xy 308.468761 -377.790866) (xy 308.414769 -377.798629)
			(xy 308.387496 -377.799092) (xy 307.523896 -377.799092) (xy 307.496629 -377.798545) (xy 307.44265 -377.790784)
			(xy 307.390325 -377.775419) (xy 307.340719 -377.752765) (xy 307.294842 -377.723281) (xy 307.253629 -377.687569)
			(xy 307.217917 -377.646354) (xy 307.188433 -377.600477) (xy 307.165779 -377.550871) (xy 307.150415 -377.498546)
			(xy 307.142654 -377.444567) (xy 301.961628 -377.444567) (xy 301.961628 -377.444573) (xy 301.953866 -377.498565)
			(xy 301.938498 -377.550902) (xy 301.915838 -377.600519) (xy 301.886348 -377.646407) (xy 301.850627 -377.68763)
			(xy 301.809403 -377.72335) (xy 301.763516 -377.75284) (xy 301.713898 -377.775499) (xy 301.661561 -377.790866)
			(xy 301.607569 -377.798629) (xy 301.580296 -377.799092) (xy 300.716696 -377.799092) (xy 300.689429 -377.798545)
			(xy 300.63545 -377.790784) (xy 300.583125 -377.775419) (xy 300.533519 -377.752765) (xy 300.487642 -377.723281)
			(xy 300.446429 -377.687569) (xy 300.410717 -377.646354) (xy 300.381233 -377.600477) (xy 300.358579 -377.550871)
			(xy 300.343215 -377.498546) (xy 300.335454 -377.444567) (xy 288.290508 -377.444567) (xy 288.290508 -379.908367)
			(xy 298.633654 -379.908367) (xy 298.633654 -379.853833) (xy 298.641415 -379.799854) (xy 298.656779 -379.747529)
			(xy 298.679433 -379.697923) (xy 298.708917 -379.652046) (xy 298.744629 -379.610831) (xy 298.785842 -379.575119)
			(xy 298.831719 -379.545635) (xy 298.881325 -379.522981) (xy 298.93365 -379.507616) (xy 298.987629 -379.499855)
			(xy 299.014896 -379.499368) (xy 299.878496 -379.499368) (xy 299.905769 -379.499771) (xy 299.959761 -379.507534)
			(xy 300.012098 -379.522901) (xy 300.061716 -379.54556) (xy 300.107603 -379.57505) (xy 300.148827 -379.61077)
			(xy 300.184548 -379.651993) (xy 300.214038 -379.697881) (xy 300.236698 -379.747498) (xy 300.252066 -379.799835)
			(xy 300.259828 -379.853827) (xy 300.259828 -379.908367) (xy 305.440854 -379.908367) (xy 305.440854 -379.853833)
			(xy 305.448615 -379.799854) (xy 305.463979 -379.747529) (xy 305.486633 -379.697923) (xy 305.516117 -379.652046)
			(xy 305.551829 -379.610831) (xy 305.593042 -379.575119) (xy 305.638919 -379.545635) (xy 305.688525 -379.522981)
			(xy 305.74085 -379.507616) (xy 305.794829 -379.499855) (xy 305.822096 -379.499368) (xy 306.685696 -379.499368)
			(xy 306.712969 -379.499771) (xy 306.766961 -379.507534) (xy 306.819298 -379.522901) (xy 306.868916 -379.54556)
			(xy 306.914803 -379.57505) (xy 306.956027 -379.61077) (xy 306.991748 -379.651993) (xy 307.021238 -379.697881)
			(xy 307.043898 -379.747498) (xy 307.059266 -379.799835) (xy 307.067028 -379.853827) (xy 307.067028 -379.908367)
			(xy 312.248054 -379.908367) (xy 312.248054 -379.853833) (xy 312.255815 -379.799854) (xy 312.271179 -379.747529)
			(xy 312.293833 -379.697923) (xy 312.323317 -379.652046) (xy 312.359029 -379.610831) (xy 312.400242 -379.575119)
			(xy 312.446119 -379.545635) (xy 312.495725 -379.522981) (xy 312.54805 -379.507616) (xy 312.602029 -379.499855)
			(xy 312.629296 -379.499368) (xy 313.492896 -379.499368) (xy 313.520169 -379.499771) (xy 313.574161 -379.507534)
			(xy 313.626498 -379.522901) (xy 313.676116 -379.54556) (xy 313.722003 -379.57505) (xy 313.763227 -379.61077)
			(xy 313.798948 -379.651993) (xy 313.828438 -379.697881) (xy 313.851098 -379.747498) (xy 313.866466 -379.799835)
			(xy 313.874228 -379.853827) (xy 313.874228 -379.908367) (xy 319.055254 -379.908367) (xy 319.055254 -379.853833)
			(xy 319.063015 -379.799854) (xy 319.078379 -379.747529) (xy 319.101033 -379.697923) (xy 319.130517 -379.652046)
			(xy 319.166229 -379.610831) (xy 319.207442 -379.575119) (xy 319.253319 -379.545635) (xy 319.302925 -379.522981)
			(xy 319.35525 -379.507616) (xy 319.409229 -379.499855) (xy 319.436496 -379.499368) (xy 320.300096 -379.499368)
			(xy 320.327369 -379.499771) (xy 320.381361 -379.507534) (xy 320.433698 -379.522901) (xy 320.483316 -379.54556)
			(xy 320.529203 -379.57505) (xy 320.570427 -379.61077) (xy 320.606148 -379.651993) (xy 320.635638 -379.697881)
			(xy 320.658298 -379.747498) (xy 320.673666 -379.799835) (xy 320.681428 -379.853827) (xy 320.681428 -379.908371)
			(xy 331.161332 -379.908371) (xy 331.161332 -379.853829) (xy 331.169094 -379.799843) (xy 331.184461 -379.747511)
			(xy 331.207121 -379.697898) (xy 331.23661 -379.652016) (xy 331.272329 -379.610798) (xy 331.313551 -379.575084)
			(xy 331.359437 -379.545599) (xy 331.409052 -379.522946) (xy 331.461386 -379.507585) (xy 331.515373 -379.499828)
			(xy 331.542644 -379.499368) (xy 332.406244 -379.499368) (xy 332.433513 -379.499798) (xy 332.487497 -379.507565)
			(xy 332.539825 -379.522935) (xy 332.589433 -379.545596) (xy 332.635312 -379.575085) (xy 332.676528 -379.610803)
			(xy 332.712241 -379.652023) (xy 332.741725 -379.697905) (xy 332.76438 -379.747516) (xy 332.779744 -379.799847)
			(xy 332.787506 -379.85383) (xy 332.787506 -379.90837) (xy 332.787506 -379.908371) (xy 337.968532 -379.908371)
			(xy 337.968532 -379.853829) (xy 337.976294 -379.799843) (xy 337.991661 -379.747511) (xy 338.014321 -379.697898)
			(xy 338.04381 -379.652016) (xy 338.079529 -379.610798) (xy 338.120751 -379.575084) (xy 338.166637 -379.545599)
			(xy 338.216252 -379.522946) (xy 338.268586 -379.507585) (xy 338.322573 -379.499828) (xy 338.349844 -379.499368)
			(xy 339.213444 -379.499368) (xy 339.240713 -379.499798) (xy 339.294697 -379.507565) (xy 339.347025 -379.522935)
			(xy 339.396633 -379.545596) (xy 339.442512 -379.575085) (xy 339.483728 -379.610803) (xy 339.519441 -379.652023)
			(xy 339.548925 -379.697905) (xy 339.57158 -379.747516) (xy 339.586944 -379.799847) (xy 339.594706 -379.85383)
			(xy 339.594706 -379.90837) (xy 339.594706 -379.908371) (xy 344.775732 -379.908371) (xy 344.775732 -379.853829)
			(xy 344.783494 -379.799843) (xy 344.798861 -379.747511) (xy 344.821521 -379.697898) (xy 344.85101 -379.652016)
			(xy 344.886729 -379.610798) (xy 344.927951 -379.575084) (xy 344.973837 -379.545599) (xy 345.023452 -379.522946)
			(xy 345.075786 -379.507585) (xy 345.129773 -379.499828) (xy 345.157044 -379.499368) (xy 346.020644 -379.499368)
			(xy 346.047913 -379.499798) (xy 346.101897 -379.507565) (xy 346.154225 -379.522935) (xy 346.203833 -379.545596)
			(xy 346.249712 -379.575085) (xy 346.290928 -379.610803) (xy 346.326641 -379.652023) (xy 346.356125 -379.697905)
			(xy 346.37878 -379.747516) (xy 346.394144 -379.799847) (xy 346.401906 -379.85383) (xy 346.401906 -379.90837)
			(xy 346.401906 -379.908371) (xy 351.582932 -379.908371) (xy 351.582932 -379.853829) (xy 351.590694 -379.799843)
			(xy 351.606061 -379.747511) (xy 351.628721 -379.697898) (xy 351.65821 -379.652016) (xy 351.693929 -379.610798)
			(xy 351.735151 -379.575084) (xy 351.781037 -379.545599) (xy 351.830652 -379.522946) (xy 351.882986 -379.507585)
			(xy 351.936973 -379.499828) (xy 351.964244 -379.499368) (xy 352.827844 -379.499368) (xy 352.855113 -379.499798)
			(xy 352.909097 -379.507565) (xy 352.961425 -379.522935) (xy 353.011033 -379.545596) (xy 353.056912 -379.575085)
			(xy 353.098128 -379.610803) (xy 353.133841 -379.652023) (xy 353.163325 -379.697905) (xy 353.18598 -379.747516)
			(xy 353.201344 -379.799847) (xy 353.209106 -379.85383) (xy 353.209106 -379.908367) (xy 365.733854 -379.908367)
			(xy 365.733854 -379.853833) (xy 365.741615 -379.799854) (xy 365.756979 -379.74753) (xy 365.779633 -379.697924)
			(xy 365.809116 -379.652047) (xy 365.844827 -379.610833) (xy 365.886041 -379.57512) (xy 365.931917 -379.545637)
			(xy 365.981522 -379.522982) (xy 366.033847 -379.507617) (xy 366.087825 -379.499855) (xy 366.115092 -379.499368)
			(xy 366.978692 -379.499368) (xy 367.005966 -379.499771) (xy 367.059957 -379.507533) (xy 367.112295 -379.5229)
			(xy 367.161913 -379.545559) (xy 367.207802 -379.575048) (xy 367.249026 -379.610768) (xy 367.284747 -379.651992)
			(xy 367.314238 -379.69788) (xy 367.336898 -379.747497) (xy 367.352265 -379.799835) (xy 367.360028 -379.853826)
			(xy 367.360028 -379.908367) (xy 372.541054 -379.908367) (xy 372.541054 -379.853833) (xy 372.548815 -379.799854)
			(xy 372.564179 -379.74753) (xy 372.586833 -379.697924) (xy 372.616316 -379.652047) (xy 372.652027 -379.610833)
			(xy 372.693241 -379.57512) (xy 372.739117 -379.545637) (xy 372.788722 -379.522982) (xy 372.841047 -379.507617)
			(xy 372.895025 -379.499855) (xy 372.922292 -379.499368) (xy 373.785892 -379.499368) (xy 373.813166 -379.499771)
			(xy 373.867157 -379.507533) (xy 373.919495 -379.5229) (xy 373.969113 -379.545559) (xy 374.015002 -379.575048)
			(xy 374.056226 -379.610768) (xy 374.091947 -379.651992) (xy 374.121438 -379.69788) (xy 374.144098 -379.747497)
			(xy 374.159465 -379.799835) (xy 374.167228 -379.853826) (xy 374.167228 -379.908367) (xy 379.348254 -379.908367)
			(xy 379.348254 -379.853833) (xy 379.356015 -379.799854) (xy 379.371379 -379.74753) (xy 379.394033 -379.697924)
			(xy 379.423516 -379.652047) (xy 379.459227 -379.610833) (xy 379.500441 -379.57512) (xy 379.546317 -379.545637)
			(xy 379.595922 -379.522982) (xy 379.648247 -379.507617) (xy 379.702225 -379.499855) (xy 379.729492 -379.499368)
			(xy 380.593092 -379.499368) (xy 380.620366 -379.499771) (xy 380.674357 -379.507533) (xy 380.726695 -379.5229)
			(xy 380.776313 -379.545559) (xy 380.822202 -379.575048) (xy 380.863426 -379.610768) (xy 380.899147 -379.651992)
			(xy 380.928638 -379.69788) (xy 380.951298 -379.747497) (xy 380.966665 -379.799835) (xy 380.974428 -379.853826)
			(xy 380.974428 -379.908367) (xy 386.155454 -379.908367) (xy 386.155454 -379.853833) (xy 386.163215 -379.799854)
			(xy 386.178579 -379.74753) (xy 386.201233 -379.697924) (xy 386.230716 -379.652047) (xy 386.266427 -379.610833)
			(xy 386.307641 -379.57512) (xy 386.353517 -379.545637) (xy 386.403122 -379.522982) (xy 386.455447 -379.507617)
			(xy 386.509425 -379.499855) (xy 386.536692 -379.499368) (xy 387.400292 -379.499368) (xy 387.427566 -379.499771)
			(xy 387.481557 -379.507533) (xy 387.533895 -379.5229) (xy 387.583513 -379.545559) (xy 387.629402 -379.575048)
			(xy 387.670626 -379.610768) (xy 387.706347 -379.651992) (xy 387.735838 -379.69788) (xy 387.758498 -379.747497)
			(xy 387.773865 -379.799835) (xy 387.781628 -379.853826) (xy 387.781628 -379.908371) (xy 398.261532 -379.908371)
			(xy 398.261532 -379.853829) (xy 398.269294 -379.799843) (xy 398.284661 -379.747511) (xy 398.30732 -379.697899)
			(xy 398.336809 -379.652017) (xy 398.372528 -379.6108) (xy 398.41375 -379.575085) (xy 398.459635 -379.545601)
			(xy 398.509249 -379.522947) (xy 398.561582 -379.507586) (xy 398.615569 -379.499829) (xy 398.64284 -379.499368)
			(xy 399.50644 -379.499368) (xy 399.53371 -379.499797) (xy 399.587693 -379.507564) (xy 399.640022 -379.522934)
			(xy 399.689631 -379.545594) (xy 399.735511 -379.575084) (xy 399.776727 -379.610802) (xy 399.81244 -379.652022)
			(xy 399.841925 -379.697904) (xy 399.86458 -379.747516) (xy 399.879944 -379.799846) (xy 399.887706 -379.85383)
			(xy 399.887706 -379.90837) (xy 399.887706 -379.908371) (xy 405.068732 -379.908371) (xy 405.068732 -379.853829)
			(xy 405.076494 -379.799843) (xy 405.091861 -379.747511) (xy 405.11452 -379.697899) (xy 405.144009 -379.652017)
			(xy 405.179728 -379.6108) (xy 405.22095 -379.575085) (xy 405.266835 -379.545601) (xy 405.316449 -379.522947)
			(xy 405.368782 -379.507586) (xy 405.422769 -379.499829) (xy 405.45004 -379.499368) (xy 406.31364 -379.499368)
			(xy 406.34091 -379.499797) (xy 406.394893 -379.507564) (xy 406.447222 -379.522934) (xy 406.496831 -379.545594)
			(xy 406.542711 -379.575084) (xy 406.583927 -379.610802) (xy 406.61964 -379.652022) (xy 406.649125 -379.697904)
			(xy 406.67178 -379.747516) (xy 406.687144 -379.799846) (xy 406.694906 -379.85383) (xy 406.694906 -379.90837)
			(xy 406.694906 -379.908371) (xy 411.875932 -379.908371) (xy 411.875932 -379.853829) (xy 411.883694 -379.799843)
			(xy 411.899061 -379.747511) (xy 411.92172 -379.697899) (xy 411.951209 -379.652017) (xy 411.986928 -379.6108)
			(xy 412.02815 -379.575085) (xy 412.074035 -379.545601) (xy 412.123649 -379.522947) (xy 412.175982 -379.507586)
			(xy 412.229969 -379.499829) (xy 412.25724 -379.499368) (xy 413.12084 -379.499368) (xy 413.14811 -379.499797)
			(xy 413.202093 -379.507564) (xy 413.254422 -379.522934) (xy 413.304031 -379.545594) (xy 413.349911 -379.575084)
			(xy 413.391127 -379.610802) (xy 413.42684 -379.652022) (xy 413.456325 -379.697904) (xy 413.47898 -379.747516)
			(xy 413.494344 -379.799846) (xy 413.502106 -379.85383) (xy 413.502106 -379.90837) (xy 413.502106 -379.908371)
			(xy 418.683132 -379.908371) (xy 418.683132 -379.853829) (xy 418.690894 -379.799843) (xy 418.706261 -379.747511)
			(xy 418.72892 -379.697899) (xy 418.758409 -379.652017) (xy 418.794128 -379.6108) (xy 418.83535 -379.575085)
			(xy 418.881235 -379.545601) (xy 418.930849 -379.522947) (xy 418.983182 -379.507586) (xy 419.037169 -379.499829)
			(xy 419.06444 -379.499368) (xy 419.92804 -379.499368) (xy 419.95531 -379.499797) (xy 420.009293 -379.507564)
			(xy 420.061622 -379.522934) (xy 420.111231 -379.545594) (xy 420.157111 -379.575084) (xy 420.198327 -379.610802)
			(xy 420.23404 -379.652022) (xy 420.263525 -379.697904) (xy 420.28618 -379.747516) (xy 420.301544 -379.799846)
			(xy 420.309306 -379.85383) (xy 420.309306 -379.90837) (xy 420.301544 -379.962354) (xy 420.28618 -380.014684)
			(xy 420.263525 -380.064296) (xy 420.23404 -380.110178) (xy 420.198327 -380.151398) (xy 420.157111 -380.187116)
			(xy 420.111231 -380.216606) (xy 420.061622 -380.239266) (xy 420.009293 -380.254636) (xy 419.95531 -380.262403)
			(xy 419.92804 -380.262892) (xy 419.06444 -380.262892) (xy 419.037169 -380.262371) (xy 418.983182 -380.254614)
			(xy 418.930849 -380.239253) (xy 418.881235 -380.216599) (xy 418.83535 -380.187115) (xy 418.794128 -380.1514)
			(xy 418.758409 -380.110183) (xy 418.72892 -380.064301) (xy 418.706261 -380.014689) (xy 418.690894 -379.962357)
			(xy 418.683132 -379.908371) (xy 413.502106 -379.908371) (xy 413.494344 -379.962354) (xy 413.47898 -380.014684)
			(xy 413.456325 -380.064296) (xy 413.42684 -380.110178) (xy 413.391127 -380.151398) (xy 413.349911 -380.187116)
			(xy 413.304031 -380.216606) (xy 413.254422 -380.239266) (xy 413.202093 -380.254636) (xy 413.14811 -380.262403)
			(xy 413.12084 -380.262892) (xy 412.25724 -380.262892) (xy 412.229969 -380.262371) (xy 412.175982 -380.254614)
			(xy 412.123649 -380.239253) (xy 412.074035 -380.216599) (xy 412.02815 -380.187115) (xy 411.986928 -380.1514)
			(xy 411.951209 -380.110183) (xy 411.92172 -380.064301) (xy 411.899061 -380.014689) (xy 411.883694 -379.962357)
			(xy 411.875932 -379.908371) (xy 406.694906 -379.908371) (xy 406.687144 -379.962354) (xy 406.67178 -380.014684)
			(xy 406.649125 -380.064296) (xy 406.61964 -380.110178) (xy 406.583927 -380.151398) (xy 406.542711 -380.187116)
			(xy 406.496831 -380.216606) (xy 406.447222 -380.239266) (xy 406.394893 -380.254636) (xy 406.34091 -380.262403)
			(xy 406.31364 -380.262892) (xy 405.45004 -380.262892) (xy 405.422769 -380.262371) (xy 405.368782 -380.254614)
			(xy 405.316449 -380.239253) (xy 405.266835 -380.216599) (xy 405.22095 -380.187115) (xy 405.179728 -380.1514)
			(xy 405.144009 -380.110183) (xy 405.11452 -380.064301) (xy 405.091861 -380.014689) (xy 405.076494 -379.962357)
			(xy 405.068732 -379.908371) (xy 399.887706 -379.908371) (xy 399.879944 -379.962354) (xy 399.86458 -380.014684)
			(xy 399.841925 -380.064296) (xy 399.81244 -380.110178) (xy 399.776727 -380.151398) (xy 399.735511 -380.187116)
			(xy 399.689631 -380.216606) (xy 399.640022 -380.239266) (xy 399.587693 -380.254636) (xy 399.53371 -380.262403)
			(xy 399.50644 -380.262892) (xy 398.64284 -380.262892) (xy 398.615569 -380.262371) (xy 398.561582 -380.254614)
			(xy 398.509249 -380.239253) (xy 398.459635 -380.216599) (xy 398.41375 -380.187115) (xy 398.372528 -380.1514)
			(xy 398.336809 -380.110183) (xy 398.30732 -380.064301) (xy 398.284661 -380.014689) (xy 398.269294 -379.962357)
			(xy 398.261532 -379.908371) (xy 387.781628 -379.908371) (xy 387.781628 -379.908374) (xy 387.773865 -379.962365)
			(xy 387.758498 -380.014703) (xy 387.735838 -380.06432) (xy 387.706347 -380.110208) (xy 387.670626 -380.151432)
			(xy 387.629402 -380.187152) (xy 387.583513 -380.216641) (xy 387.533895 -380.2393) (xy 387.481557 -380.254667)
			(xy 387.427566 -380.262429) (xy 387.400292 -380.262892) (xy 386.536692 -380.262892) (xy 386.509425 -380.262345)
			(xy 386.455447 -380.254583) (xy 386.403122 -380.239218) (xy 386.353517 -380.216563) (xy 386.307641 -380.18708)
			(xy 386.266427 -380.151367) (xy 386.230716 -380.110153) (xy 386.201233 -380.064276) (xy 386.178579 -380.01467)
			(xy 386.163215 -379.962346) (xy 386.155454 -379.908367) (xy 380.974428 -379.908367) (xy 380.974428 -379.908374)
			(xy 380.966665 -379.962365) (xy 380.951298 -380.014703) (xy 380.928638 -380.06432) (xy 380.899147 -380.110208)
			(xy 380.863426 -380.151432) (xy 380.822202 -380.187152) (xy 380.776313 -380.216641) (xy 380.726695 -380.2393)
			(xy 380.674357 -380.254667) (xy 380.620366 -380.262429) (xy 380.593092 -380.262892) (xy 379.729492 -380.262892)
			(xy 379.702225 -380.262345) (xy 379.648247 -380.254583) (xy 379.595922 -380.239218) (xy 379.546317 -380.216563)
			(xy 379.500441 -380.18708) (xy 379.459227 -380.151367) (xy 379.423516 -380.110153) (xy 379.394033 -380.064276)
			(xy 379.371379 -380.01467) (xy 379.356015 -379.962346) (xy 379.348254 -379.908367) (xy 374.167228 -379.908367)
			(xy 374.167228 -379.908374) (xy 374.159465 -379.962365) (xy 374.144098 -380.014703) (xy 374.121438 -380.06432)
			(xy 374.091947 -380.110208) (xy 374.056226 -380.151432) (xy 374.015002 -380.187152) (xy 373.969113 -380.216641)
			(xy 373.919495 -380.2393) (xy 373.867157 -380.254667) (xy 373.813166 -380.262429) (xy 373.785892 -380.262892)
			(xy 372.922292 -380.262892) (xy 372.895025 -380.262345) (xy 372.841047 -380.254583) (xy 372.788722 -380.239218)
			(xy 372.739117 -380.216563) (xy 372.693241 -380.18708) (xy 372.652027 -380.151367) (xy 372.616316 -380.110153)
			(xy 372.586833 -380.064276) (xy 372.564179 -380.01467) (xy 372.548815 -379.962346) (xy 372.541054 -379.908367)
			(xy 367.360028 -379.908367) (xy 367.360028 -379.908374) (xy 367.352265 -379.962365) (xy 367.336898 -380.014703)
			(xy 367.314238 -380.06432) (xy 367.284747 -380.110208) (xy 367.249026 -380.151432) (xy 367.207802 -380.187152)
			(xy 367.161913 -380.216641) (xy 367.112295 -380.2393) (xy 367.059957 -380.254667) (xy 367.005966 -380.262429)
			(xy 366.978692 -380.262892) (xy 366.115092 -380.262892) (xy 366.087825 -380.262345) (xy 366.033847 -380.254583)
			(xy 365.981522 -380.239218) (xy 365.931917 -380.216563) (xy 365.886041 -380.18708) (xy 365.844827 -380.151367)
			(xy 365.809116 -380.110153) (xy 365.779633 -380.064276) (xy 365.756979 -380.01467) (xy 365.741615 -379.962346)
			(xy 365.733854 -379.908367) (xy 353.209106 -379.908367) (xy 353.209106 -379.90837) (xy 353.201344 -379.962353)
			(xy 353.18598 -380.014684) (xy 353.163325 -380.064295) (xy 353.133841 -380.110177) (xy 353.098128 -380.151397)
			(xy 353.056912 -380.187115) (xy 353.011033 -380.216604) (xy 352.961425 -380.239265) (xy 352.909097 -380.254635)
			(xy 352.855113 -380.262402) (xy 352.827844 -380.262892) (xy 351.964244 -380.262892) (xy 351.936973 -380.262372)
			(xy 351.882986 -380.254615) (xy 351.830652 -380.239254) (xy 351.781037 -380.216601) (xy 351.735151 -380.187116)
			(xy 351.693929 -380.151402) (xy 351.65821 -380.110184) (xy 351.628721 -380.064302) (xy 351.606061 -380.014689)
			(xy 351.590694 -379.962357) (xy 351.582932 -379.908371) (xy 346.401906 -379.908371) (xy 346.394144 -379.962353)
			(xy 346.37878 -380.014684) (xy 346.356125 -380.064295) (xy 346.326641 -380.110177) (xy 346.290928 -380.151397)
			(xy 346.249712 -380.187115) (xy 346.203833 -380.216604) (xy 346.154225 -380.239265) (xy 346.101897 -380.254635)
			(xy 346.047913 -380.262402) (xy 346.020644 -380.262892) (xy 345.157044 -380.262892) (xy 345.129773 -380.262372)
			(xy 345.075786 -380.254615) (xy 345.023452 -380.239254) (xy 344.973837 -380.216601) (xy 344.927951 -380.187116)
			(xy 344.886729 -380.151402) (xy 344.85101 -380.110184) (xy 344.821521 -380.064302) (xy 344.798861 -380.014689)
			(xy 344.783494 -379.962357) (xy 344.775732 -379.908371) (xy 339.594706 -379.908371) (xy 339.586944 -379.962353)
			(xy 339.57158 -380.014684) (xy 339.548925 -380.064295) (xy 339.519441 -380.110177) (xy 339.483728 -380.151397)
			(xy 339.442512 -380.187115) (xy 339.396633 -380.216604) (xy 339.347025 -380.239265) (xy 339.294697 -380.254635)
			(xy 339.240713 -380.262402) (xy 339.213444 -380.262892) (xy 338.349844 -380.262892) (xy 338.322573 -380.262372)
			(xy 338.268586 -380.254615) (xy 338.216252 -380.239254) (xy 338.166637 -380.216601) (xy 338.120751 -380.187116)
			(xy 338.079529 -380.151402) (xy 338.04381 -380.110184) (xy 338.014321 -380.064302) (xy 337.991661 -380.014689)
			(xy 337.976294 -379.962357) (xy 337.968532 -379.908371) (xy 332.787506 -379.908371) (xy 332.779744 -379.962353)
			(xy 332.76438 -380.014684) (xy 332.741725 -380.064295) (xy 332.712241 -380.110177) (xy 332.676528 -380.151397)
			(xy 332.635312 -380.187115) (xy 332.589433 -380.216604) (xy 332.539825 -380.239265) (xy 332.487497 -380.254635)
			(xy 332.433513 -380.262402) (xy 332.406244 -380.262892) (xy 331.542644 -380.262892) (xy 331.515373 -380.262372)
			(xy 331.461386 -380.254615) (xy 331.409052 -380.239254) (xy 331.359437 -380.216601) (xy 331.313551 -380.187116)
			(xy 331.272329 -380.151402) (xy 331.23661 -380.110184) (xy 331.207121 -380.064302) (xy 331.184461 -380.014689)
			(xy 331.169094 -379.962357) (xy 331.161332 -379.908371) (xy 320.681428 -379.908371) (xy 320.681428 -379.908373)
			(xy 320.673666 -379.962365) (xy 320.658298 -380.014702) (xy 320.635638 -380.064319) (xy 320.606148 -380.110207)
			(xy 320.570427 -380.15143) (xy 320.529203 -380.18715) (xy 320.483316 -380.21664) (xy 320.433698 -380.239299)
			(xy 320.381361 -380.254666) (xy 320.327369 -380.262429) (xy 320.300096 -380.262892) (xy 319.436496 -380.262892)
			(xy 319.409229 -380.262345) (xy 319.35525 -380.254584) (xy 319.302925 -380.239219) (xy 319.253319 -380.216565)
			(xy 319.207442 -380.187081) (xy 319.166229 -380.151369) (xy 319.130517 -380.110154) (xy 319.101033 -380.064277)
			(xy 319.078379 -380.014671) (xy 319.063015 -379.962346) (xy 319.055254 -379.908367) (xy 313.874228 -379.908367)
			(xy 313.874228 -379.908373) (xy 313.866466 -379.962365) (xy 313.851098 -380.014702) (xy 313.828438 -380.064319)
			(xy 313.798948 -380.110207) (xy 313.763227 -380.15143) (xy 313.722003 -380.18715) (xy 313.676116 -380.21664)
			(xy 313.626498 -380.239299) (xy 313.574161 -380.254666) (xy 313.520169 -380.262429) (xy 313.492896 -380.262892)
			(xy 312.629296 -380.262892) (xy 312.602029 -380.262345) (xy 312.54805 -380.254584) (xy 312.495725 -380.239219)
			(xy 312.446119 -380.216565) (xy 312.400242 -380.187081) (xy 312.359029 -380.151369) (xy 312.323317 -380.110154)
			(xy 312.293833 -380.064277) (xy 312.271179 -380.014671) (xy 312.255815 -379.962346) (xy 312.248054 -379.908367)
			(xy 307.067028 -379.908367) (xy 307.067028 -379.908373) (xy 307.059266 -379.962365) (xy 307.043898 -380.014702)
			(xy 307.021238 -380.064319) (xy 306.991748 -380.110207) (xy 306.956027 -380.15143) (xy 306.914803 -380.18715)
			(xy 306.868916 -380.21664) (xy 306.819298 -380.239299) (xy 306.766961 -380.254666) (xy 306.712969 -380.262429)
			(xy 306.685696 -380.262892) (xy 305.822096 -380.262892) (xy 305.794829 -380.262345) (xy 305.74085 -380.254584)
			(xy 305.688525 -380.239219) (xy 305.638919 -380.216565) (xy 305.593042 -380.187081) (xy 305.551829 -380.151369)
			(xy 305.516117 -380.110154) (xy 305.486633 -380.064277) (xy 305.463979 -380.014671) (xy 305.448615 -379.962346)
			(xy 305.440854 -379.908367) (xy 300.259828 -379.908367) (xy 300.259828 -379.908373) (xy 300.252066 -379.962365)
			(xy 300.236698 -380.014702) (xy 300.214038 -380.064319) (xy 300.184548 -380.110207) (xy 300.148827 -380.15143)
			(xy 300.107603 -380.18715) (xy 300.061716 -380.21664) (xy 300.012098 -380.239299) (xy 299.959761 -380.254666)
			(xy 299.905769 -380.262429) (xy 299.878496 -380.262892) (xy 299.014896 -380.262892) (xy 298.987629 -380.262345)
			(xy 298.93365 -380.254584) (xy 298.881325 -380.239219) (xy 298.831719 -380.216565) (xy 298.785842 -380.187081)
			(xy 298.744629 -380.151369) (xy 298.708917 -380.110154) (xy 298.679433 -380.064277) (xy 298.656779 -380.014671)
			(xy 298.641415 -379.962346) (xy 298.633654 -379.908367) (xy 288.290508 -379.908367) (xy 288.290508 -381.36068)
			(xy 288.290836 -381.370157) (xy 288.297619 -381.387852) (xy 288.310374 -381.401867) (xy 288.318702 -381.4064)
			(xy 288.41319 -381.453136) (xy 288.442146 -381.450342) (xy 288.453576 -381.441706) (xy 288.528371 -381.385444)
			(xy 288.682126 -381.278688) (xy 288.840363 -381.178695) (xy 289.002785 -381.085653) (xy 289.169087 -380.999738)
			(xy 289.338955 -380.92111) (xy 289.512072 -380.849918) (xy 289.688111 -380.786295) (xy 289.866741 -380.730361)
			(xy 290.047629 -380.682221) (xy 290.230432 -380.641965) (xy 290.414808 -380.609669) (xy 290.600411 -380.585394)
			(xy 290.786891 -380.569185) (xy 290.973898 -380.561072) (xy 291.06749 -380.56058) (xy 291.160408 -380.561073)
			(xy 291.346072 -380.569067) (xy 291.53122 -380.585042) (xy 291.715509 -380.608968) (xy 291.898599 -380.6408)
			(xy 292.080149 -380.680479) (xy 292.259824 -380.727933) (xy 292.437292 -380.783072) (xy 292.612222 -380.845796)
			(xy 292.784293 -380.915987) (xy 292.953184 -380.993517) (xy 293.118583 -381.07824) (xy 293.280184 -381.170001)
			(xy 293.437688 -381.26863) (xy 293.590803 -381.373943) (xy 293.739245 -381.485746) (xy 293.882739 -381.603832)
			(xy 294.021021 -381.727982) (xy 294.153833 -381.857967) (xy 294.28093 -381.993545) (xy 294.402076 -382.134465)
			(xy 294.517048 -382.280467) (xy 294.583071 -382.372167) (xy 303.739054 -382.372167) (xy 303.739054 -382.317633)
			(xy 303.746815 -382.263654) (xy 303.762179 -382.211329) (xy 303.784833 -382.161723) (xy 303.814317 -382.115846)
			(xy 303.850029 -382.074631) (xy 303.891242 -382.038919) (xy 303.937119 -382.009435) (xy 303.986725 -381.986781)
			(xy 304.03905 -381.971416) (xy 304.093029 -381.963655) (xy 304.120296 -381.963168) (xy 304.983896 -381.963168)
			(xy 305.011169 -381.963571) (xy 305.065161 -381.971334) (xy 305.117498 -381.986701) (xy 305.167116 -382.00936)
			(xy 305.213003 -382.03885) (xy 305.254227 -382.07457) (xy 305.289948 -382.115793) (xy 305.319438 -382.161681)
			(xy 305.342098 -382.211298) (xy 305.357466 -382.263635) (xy 305.365228 -382.317627) (xy 305.365228 -382.372167)
			(xy 310.546254 -382.372167) (xy 310.546254 -382.317633) (xy 310.554015 -382.263654) (xy 310.569379 -382.211329)
			(xy 310.592033 -382.161723) (xy 310.621517 -382.115846) (xy 310.657229 -382.074631) (xy 310.698442 -382.038919)
			(xy 310.744319 -382.009435) (xy 310.793925 -381.986781) (xy 310.84625 -381.971416) (xy 310.900229 -381.963655)
			(xy 310.927496 -381.963168) (xy 311.791096 -381.963168) (xy 311.818369 -381.963571) (xy 311.872361 -381.971334)
			(xy 311.924698 -381.986701) (xy 311.974316 -382.00936) (xy 312.020203 -382.03885) (xy 312.061427 -382.07457)
			(xy 312.097148 -382.115793) (xy 312.126638 -382.161681) (xy 312.149298 -382.211298) (xy 312.164666 -382.263635)
			(xy 312.172428 -382.317627) (xy 312.172428 -382.372167) (xy 317.353454 -382.372167) (xy 317.353454 -382.317633)
			(xy 317.361215 -382.263654) (xy 317.376579 -382.211329) (xy 317.399233 -382.161723) (xy 317.428717 -382.115846)
			(xy 317.464429 -382.074631) (xy 317.505642 -382.038919) (xy 317.551519 -382.009435) (xy 317.601125 -381.986781)
			(xy 317.65345 -381.971416) (xy 317.707429 -381.963655) (xy 317.734696 -381.963168) (xy 318.598296 -381.963168)
			(xy 318.625569 -381.963571) (xy 318.679561 -381.971334) (xy 318.731898 -381.986701) (xy 318.781516 -382.00936)
			(xy 318.827403 -382.03885) (xy 318.868627 -382.07457) (xy 318.904348 -382.115793) (xy 318.933838 -382.161681)
			(xy 318.956498 -382.211298) (xy 318.971866 -382.263635) (xy 318.979628 -382.317627) (xy 318.979628 -382.372171)
			(xy 336.266732 -382.372171) (xy 336.266732 -382.317629) (xy 336.274494 -382.263643) (xy 336.289861 -382.211311)
			(xy 336.312521 -382.161698) (xy 336.34201 -382.115816) (xy 336.377729 -382.074598) (xy 336.418951 -382.038884)
			(xy 336.464837 -382.009399) (xy 336.514452 -381.986746) (xy 336.566786 -381.971385) (xy 336.620773 -381.963628)
			(xy 336.648044 -381.963168) (xy 337.511644 -381.963168) (xy 337.538913 -381.963598) (xy 337.592897 -381.971365)
			(xy 337.645225 -381.986735) (xy 337.694833 -382.009396) (xy 337.740712 -382.038885) (xy 337.781928 -382.074603)
			(xy 337.817641 -382.115823) (xy 337.847125 -382.161705) (xy 337.86978 -382.211316) (xy 337.885144 -382.263647)
			(xy 337.892906 -382.31763) (xy 337.892906 -382.37217) (xy 337.892906 -382.372171) (xy 343.073932 -382.372171)
			(xy 343.073932 -382.317629) (xy 343.081694 -382.263643) (xy 343.097061 -382.211311) (xy 343.119721 -382.161698)
			(xy 343.14921 -382.115816) (xy 343.184929 -382.074598) (xy 343.226151 -382.038884) (xy 343.272037 -382.009399)
			(xy 343.321652 -381.986746) (xy 343.373986 -381.971385) (xy 343.427973 -381.963628) (xy 343.455244 -381.963168)
			(xy 344.318844 -381.963168) (xy 344.346113 -381.963598) (xy 344.400097 -381.971365) (xy 344.452425 -381.986735)
			(xy 344.502033 -382.009396) (xy 344.547912 -382.038885) (xy 344.589128 -382.074603) (xy 344.624841 -382.115823)
			(xy 344.654325 -382.161705) (xy 344.67698 -382.211316) (xy 344.692344 -382.263647) (xy 344.700106 -382.31763)
			(xy 344.700106 -382.37217) (xy 344.700106 -382.372171) (xy 349.881132 -382.372171) (xy 349.881132 -382.317629)
			(xy 349.888894 -382.263643) (xy 349.904261 -382.211311) (xy 349.926921 -382.161698) (xy 349.95641 -382.115816)
			(xy 349.992129 -382.074598) (xy 350.033351 -382.038884) (xy 350.079237 -382.009399) (xy 350.128852 -381.986746)
			(xy 350.181186 -381.971385) (xy 350.235173 -381.963628) (xy 350.262444 -381.963168) (xy 351.126044 -381.963168)
			(xy 351.153313 -381.963598) (xy 351.207297 -381.971365) (xy 351.259625 -381.986735) (xy 351.309233 -382.009396)
			(xy 351.355112 -382.038885) (xy 351.396328 -382.074603) (xy 351.432041 -382.115823) (xy 351.461525 -382.161705)
			(xy 351.48418 -382.211316) (xy 351.499544 -382.263647) (xy 351.507306 -382.31763) (xy 351.507306 -382.372167)
			(xy 370.839254 -382.372167) (xy 370.839254 -382.317633) (xy 370.847015 -382.263654) (xy 370.862379 -382.21133)
			(xy 370.885033 -382.161724) (xy 370.914516 -382.115847) (xy 370.950227 -382.074633) (xy 370.991441 -382.03892)
			(xy 371.037317 -382.009437) (xy 371.086922 -381.986782) (xy 371.139247 -381.971417) (xy 371.193225 -381.963655)
			(xy 371.220492 -381.963168) (xy 372.084092 -381.963168) (xy 372.111366 -381.963571) (xy 372.165357 -381.971333)
			(xy 372.217695 -381.9867) (xy 372.267313 -382.009359) (xy 372.313202 -382.038848) (xy 372.354426 -382.074568)
			(xy 372.390147 -382.115792) (xy 372.419638 -382.16168) (xy 372.442298 -382.211297) (xy 372.457665 -382.263635)
			(xy 372.465428 -382.317626) (xy 372.465428 -382.372167) (xy 377.646454 -382.372167) (xy 377.646454 -382.317633)
			(xy 377.654215 -382.263654) (xy 377.669579 -382.21133) (xy 377.692233 -382.161724) (xy 377.721716 -382.115847)
			(xy 377.757427 -382.074633) (xy 377.798641 -382.03892) (xy 377.844517 -382.009437) (xy 377.894122 -381.986782)
			(xy 377.946447 -381.971417) (xy 378.000425 -381.963655) (xy 378.027692 -381.963168) (xy 378.891292 -381.963168)
			(xy 378.918566 -381.963571) (xy 378.972557 -381.971333) (xy 379.024895 -381.9867) (xy 379.074513 -382.009359)
			(xy 379.120402 -382.038848) (xy 379.161626 -382.074568) (xy 379.197347 -382.115792) (xy 379.226838 -382.16168)
			(xy 379.249498 -382.211297) (xy 379.264865 -382.263635) (xy 379.272628 -382.317626) (xy 379.272628 -382.372167)
			(xy 384.453654 -382.372167) (xy 384.453654 -382.317633) (xy 384.461415 -382.263654) (xy 384.476779 -382.21133)
			(xy 384.499433 -382.161724) (xy 384.528916 -382.115847) (xy 384.564627 -382.074633) (xy 384.605841 -382.03892)
			(xy 384.651717 -382.009437) (xy 384.701322 -381.986782) (xy 384.753647 -381.971417) (xy 384.807625 -381.963655)
			(xy 384.834892 -381.963168) (xy 385.698492 -381.963168) (xy 385.725766 -381.963571) (xy 385.779757 -381.971333)
			(xy 385.832095 -381.9867) (xy 385.881713 -382.009359) (xy 385.927602 -382.038848) (xy 385.968826 -382.074568)
			(xy 386.004547 -382.115792) (xy 386.034038 -382.16168) (xy 386.056698 -382.211297) (xy 386.072065 -382.263635)
			(xy 386.079828 -382.317626) (xy 386.079828 -382.372171) (xy 403.366932 -382.372171) (xy 403.366932 -382.317629)
			(xy 403.374694 -382.263643) (xy 403.390061 -382.211311) (xy 403.41272 -382.161699) (xy 403.442209 -382.115817)
			(xy 403.477928 -382.0746) (xy 403.51915 -382.038885) (xy 403.565035 -382.009401) (xy 403.614649 -381.986747)
			(xy 403.666982 -381.971386) (xy 403.720969 -381.963629) (xy 403.74824 -381.963168) (xy 404.61184 -381.963168)
			(xy 404.63911 -381.963597) (xy 404.693093 -381.971364) (xy 404.745422 -381.986734) (xy 404.795031 -382.009394)
			(xy 404.840911 -382.038884) (xy 404.882127 -382.074602) (xy 404.91784 -382.115822) (xy 404.947325 -382.161704)
			(xy 404.96998 -382.211316) (xy 404.985344 -382.263646) (xy 404.993106 -382.31763) (xy 404.993106 -382.37217)
			(xy 404.993106 -382.372171) (xy 410.174132 -382.372171) (xy 410.174132 -382.317629) (xy 410.181894 -382.263643)
			(xy 410.197261 -382.211311) (xy 410.21992 -382.161699) (xy 410.249409 -382.115817) (xy 410.285128 -382.0746)
			(xy 410.32635 -382.038885) (xy 410.372235 -382.009401) (xy 410.421849 -381.986747) (xy 410.474182 -381.971386)
			(xy 410.528169 -381.963629) (xy 410.55544 -381.963168) (xy 411.41904 -381.963168) (xy 411.44631 -381.963597)
			(xy 411.500293 -381.971364) (xy 411.552622 -381.986734) (xy 411.602231 -382.009394) (xy 411.648111 -382.038884)
			(xy 411.689327 -382.074602) (xy 411.72504 -382.115822) (xy 411.754525 -382.161704) (xy 411.77718 -382.211316)
			(xy 411.792544 -382.263646) (xy 411.800306 -382.31763) (xy 411.800306 -382.37217) (xy 411.800306 -382.372171)
			(xy 416.981332 -382.372171) (xy 416.981332 -382.317629) (xy 416.989094 -382.263643) (xy 417.004461 -382.211311)
			(xy 417.02712 -382.161699) (xy 417.056609 -382.115817) (xy 417.092328 -382.0746) (xy 417.13355 -382.038885)
			(xy 417.179435 -382.009401) (xy 417.229049 -381.986747) (xy 417.281382 -381.971386) (xy 417.335369 -381.963629)
			(xy 417.36264 -381.963168) (xy 418.22624 -381.963168) (xy 418.25351 -381.963597) (xy 418.307493 -381.971364)
			(xy 418.359822 -381.986734) (xy 418.409431 -382.009394) (xy 418.455311 -382.038884) (xy 418.496527 -382.074602)
			(xy 418.53224 -382.115822) (xy 418.561725 -382.161704) (xy 418.58438 -382.211316) (xy 418.599744 -382.263646)
			(xy 418.607506 -382.31763) (xy 418.607506 -382.37217) (xy 418.599744 -382.426154) (xy 418.58438 -382.478484)
			(xy 418.561725 -382.528096) (xy 418.53224 -382.573978) (xy 418.496527 -382.615198) (xy 418.455311 -382.650916)
			(xy 418.409431 -382.680406) (xy 418.359822 -382.703066) (xy 418.307493 -382.718436) (xy 418.25351 -382.726203)
			(xy 418.22624 -382.726692) (xy 417.36264 -382.726692) (xy 417.335369 -382.726171) (xy 417.281382 -382.718414)
			(xy 417.229049 -382.703053) (xy 417.179435 -382.680399) (xy 417.13355 -382.650915) (xy 417.092328 -382.6152)
			(xy 417.056609 -382.573983) (xy 417.02712 -382.528101) (xy 417.004461 -382.478489) (xy 416.989094 -382.426157)
			(xy 416.981332 -382.372171) (xy 411.800306 -382.372171) (xy 411.792544 -382.426154) (xy 411.77718 -382.478484)
			(xy 411.754525 -382.528096) (xy 411.72504 -382.573978) (xy 411.689327 -382.615198) (xy 411.648111 -382.650916)
			(xy 411.602231 -382.680406) (xy 411.552622 -382.703066) (xy 411.500293 -382.718436) (xy 411.44631 -382.726203)
			(xy 411.41904 -382.726692) (xy 410.55544 -382.726692) (xy 410.528169 -382.726171) (xy 410.474182 -382.718414)
			(xy 410.421849 -382.703053) (xy 410.372235 -382.680399) (xy 410.32635 -382.650915) (xy 410.285128 -382.6152)
			(xy 410.249409 -382.573983) (xy 410.21992 -382.528101) (xy 410.197261 -382.478489) (xy 410.181894 -382.426157)
			(xy 410.174132 -382.372171) (xy 404.993106 -382.372171) (xy 404.985344 -382.426154) (xy 404.96998 -382.478484)
			(xy 404.947325 -382.528096) (xy 404.91784 -382.573978) (xy 404.882127 -382.615198) (xy 404.840911 -382.650916)
			(xy 404.795031 -382.680406) (xy 404.745422 -382.703066) (xy 404.693093 -382.718436) (xy 404.63911 -382.726203)
			(xy 404.61184 -382.726692) (xy 403.74824 -382.726692) (xy 403.720969 -382.726171) (xy 403.666982 -382.718414)
			(xy 403.614649 -382.703053) (xy 403.565035 -382.680399) (xy 403.51915 -382.650915) (xy 403.477928 -382.6152)
			(xy 403.442209 -382.573983) (xy 403.41272 -382.528101) (xy 403.390061 -382.478489) (xy 403.374694 -382.426157)
			(xy 403.366932 -382.372171) (xy 386.079828 -382.372171) (xy 386.079828 -382.372174) (xy 386.072065 -382.426165)
			(xy 386.056698 -382.478503) (xy 386.034038 -382.52812) (xy 386.004547 -382.574008) (xy 385.968826 -382.615232)
			(xy 385.927602 -382.650952) (xy 385.881713 -382.680441) (xy 385.832095 -382.7031) (xy 385.779757 -382.718467)
			(xy 385.725766 -382.726229) (xy 385.698492 -382.726692) (xy 384.834892 -382.726692) (xy 384.807625 -382.726145)
			(xy 384.753647 -382.718383) (xy 384.701322 -382.703018) (xy 384.651717 -382.680363) (xy 384.605841 -382.65088)
			(xy 384.564627 -382.615167) (xy 384.528916 -382.573953) (xy 384.499433 -382.528076) (xy 384.476779 -382.47847)
			(xy 384.461415 -382.426146) (xy 384.453654 -382.372167) (xy 379.272628 -382.372167) (xy 379.272628 -382.372174)
			(xy 379.264865 -382.426165) (xy 379.249498 -382.478503) (xy 379.226838 -382.52812) (xy 379.197347 -382.574008)
			(xy 379.161626 -382.615232) (xy 379.120402 -382.650952) (xy 379.074513 -382.680441) (xy 379.024895 -382.7031)
			(xy 378.972557 -382.718467) (xy 378.918566 -382.726229) (xy 378.891292 -382.726692) (xy 378.027692 -382.726692)
			(xy 378.000425 -382.726145) (xy 377.946447 -382.718383) (xy 377.894122 -382.703018) (xy 377.844517 -382.680363)
			(xy 377.798641 -382.65088) (xy 377.757427 -382.615167) (xy 377.721716 -382.573953) (xy 377.692233 -382.528076)
			(xy 377.669579 -382.47847) (xy 377.654215 -382.426146) (xy 377.646454 -382.372167) (xy 372.465428 -382.372167)
			(xy 372.465428 -382.372174) (xy 372.457665 -382.426165) (xy 372.442298 -382.478503) (xy 372.419638 -382.52812)
			(xy 372.390147 -382.574008) (xy 372.354426 -382.615232) (xy 372.313202 -382.650952) (xy 372.267313 -382.680441)
			(xy 372.217695 -382.7031) (xy 372.165357 -382.718467) (xy 372.111366 -382.726229) (xy 372.084092 -382.726692)
			(xy 371.220492 -382.726692) (xy 371.193225 -382.726145) (xy 371.139247 -382.718383) (xy 371.086922 -382.703018)
			(xy 371.037317 -382.680363) (xy 370.991441 -382.65088) (xy 370.950227 -382.615167) (xy 370.914516 -382.573953)
			(xy 370.885033 -382.528076) (xy 370.862379 -382.47847) (xy 370.847015 -382.426146) (xy 370.839254 -382.372167)
			(xy 351.507306 -382.372167) (xy 351.507306 -382.37217) (xy 351.499544 -382.426153) (xy 351.48418 -382.478484)
			(xy 351.461525 -382.528095) (xy 351.432041 -382.573977) (xy 351.396328 -382.615197) (xy 351.355112 -382.650915)
			(xy 351.309233 -382.680404) (xy 351.259625 -382.703065) (xy 351.207297 -382.718435) (xy 351.153313 -382.726202)
			(xy 351.126044 -382.726692) (xy 350.262444 -382.726692) (xy 350.235173 -382.726172) (xy 350.181186 -382.718415)
			(xy 350.128852 -382.703054) (xy 350.079237 -382.680401) (xy 350.033351 -382.650916) (xy 349.992129 -382.615202)
			(xy 349.95641 -382.573984) (xy 349.926921 -382.528102) (xy 349.904261 -382.478489) (xy 349.888894 -382.426157)
			(xy 349.881132 -382.372171) (xy 344.700106 -382.372171) (xy 344.692344 -382.426153) (xy 344.67698 -382.478484)
			(xy 344.654325 -382.528095) (xy 344.624841 -382.573977) (xy 344.589128 -382.615197) (xy 344.547912 -382.650915)
			(xy 344.502033 -382.680404) (xy 344.452425 -382.703065) (xy 344.400097 -382.718435) (xy 344.346113 -382.726202)
			(xy 344.318844 -382.726692) (xy 343.455244 -382.726692) (xy 343.427973 -382.726172) (xy 343.373986 -382.718415)
			(xy 343.321652 -382.703054) (xy 343.272037 -382.680401) (xy 343.226151 -382.650916) (xy 343.184929 -382.615202)
			(xy 343.14921 -382.573984) (xy 343.119721 -382.528102) (xy 343.097061 -382.478489) (xy 343.081694 -382.426157)
			(xy 343.073932 -382.372171) (xy 337.892906 -382.372171) (xy 337.885144 -382.426153) (xy 337.86978 -382.478484)
			(xy 337.847125 -382.528095) (xy 337.817641 -382.573977) (xy 337.781928 -382.615197) (xy 337.740712 -382.650915)
			(xy 337.694833 -382.680404) (xy 337.645225 -382.703065) (xy 337.592897 -382.718435) (xy 337.538913 -382.726202)
			(xy 337.511644 -382.726692) (xy 336.648044 -382.726692) (xy 336.620773 -382.726172) (xy 336.566786 -382.718415)
			(xy 336.514452 -382.703054) (xy 336.464837 -382.680401) (xy 336.418951 -382.650916) (xy 336.377729 -382.615202)
			(xy 336.34201 -382.573984) (xy 336.312521 -382.528102) (xy 336.289861 -382.478489) (xy 336.274494 -382.426157)
			(xy 336.266732 -382.372171) (xy 318.979628 -382.372171) (xy 318.979628 -382.372173) (xy 318.971866 -382.426165)
			(xy 318.956498 -382.478502) (xy 318.933838 -382.528119) (xy 318.904348 -382.574007) (xy 318.868627 -382.61523)
			(xy 318.827403 -382.65095) (xy 318.781516 -382.68044) (xy 318.731898 -382.703099) (xy 318.679561 -382.718466)
			(xy 318.625569 -382.726229) (xy 318.598296 -382.726692) (xy 317.734696 -382.726692) (xy 317.707429 -382.726145)
			(xy 317.65345 -382.718384) (xy 317.601125 -382.703019) (xy 317.551519 -382.680365) (xy 317.505642 -382.650881)
			(xy 317.464429 -382.615169) (xy 317.428717 -382.573954) (xy 317.399233 -382.528077) (xy 317.376579 -382.478471)
			(xy 317.361215 -382.426146) (xy 317.353454 -382.372167) (xy 312.172428 -382.372167) (xy 312.172428 -382.372173)
			(xy 312.164666 -382.426165) (xy 312.149298 -382.478502) (xy 312.126638 -382.528119) (xy 312.097148 -382.574007)
			(xy 312.061427 -382.61523) (xy 312.020203 -382.65095) (xy 311.974316 -382.68044) (xy 311.924698 -382.703099)
			(xy 311.872361 -382.718466) (xy 311.818369 -382.726229) (xy 311.791096 -382.726692) (xy 310.927496 -382.726692)
			(xy 310.900229 -382.726145) (xy 310.84625 -382.718384) (xy 310.793925 -382.703019) (xy 310.744319 -382.680365)
			(xy 310.698442 -382.650881) (xy 310.657229 -382.615169) (xy 310.621517 -382.573954) (xy 310.592033 -382.528077)
			(xy 310.569379 -382.478471) (xy 310.554015 -382.426146) (xy 310.546254 -382.372167) (xy 305.365228 -382.372167)
			(xy 305.365228 -382.372173) (xy 305.357466 -382.426165) (xy 305.342098 -382.478502) (xy 305.319438 -382.528119)
			(xy 305.289948 -382.574007) (xy 305.254227 -382.61523) (xy 305.213003 -382.65095) (xy 305.167116 -382.68044)
			(xy 305.117498 -382.703099) (xy 305.065161 -382.718466) (xy 305.011169 -382.726229) (xy 304.983896 -382.726692)
			(xy 304.120296 -382.726692) (xy 304.093029 -382.726145) (xy 304.03905 -382.718384) (xy 303.986725 -382.703019)
			(xy 303.937119 -382.680365) (xy 303.891242 -382.650881) (xy 303.850029 -382.615169) (xy 303.814317 -382.573954)
			(xy 303.784833 -382.528077) (xy 303.762179 -382.478471) (xy 303.746815 -382.426146) (xy 303.739054 -382.372167)
			(xy 294.583071 -382.372167) (xy 294.625632 -382.43128) (xy 294.727626 -382.586625) (xy 294.822844 -382.746214)
			(xy 294.911107 -382.909752) (xy 294.992252 -383.076936) (xy 295.06613 -383.247456) (xy 295.132604 -383.420996)
			(xy 295.191549 -383.597236) (xy 295.242858 -383.775848) (xy 295.286435 -383.956503) (xy 295.322199 -384.138865)
			(xy 295.350085 -384.322597) (xy 295.370041 -384.507358) (xy 295.382029 -384.692807) (xy 295.386027 -384.8786)
			(xy 295.382029 -385.064393) (xy 295.372367 -385.21386) (xy 297.048936 -385.21386) (xy 297.048936 -384.35026)
			(xy 297.049422 -384.323009) (xy 297.057178 -384.269061) (xy 297.072533 -384.216766) (xy 297.095175 -384.167189)
			(xy 297.124641 -384.121339) (xy 297.160332 -384.080148) (xy 297.201523 -384.044457) (xy 297.247373 -384.014991)
			(xy 297.29695 -383.992349) (xy 297.349245 -383.976994) (xy 297.403193 -383.969238) (xy 297.457695 -383.969238)
			(xy 297.511643 -383.976994) (xy 297.563938 -383.992349) (xy 297.613515 -384.014991) (xy 297.659365 -384.044457)
			(xy 297.700556 -384.080148) (xy 297.736247 -384.121339) (xy 297.765713 -384.167189) (xy 297.788355 -384.216766)
			(xy 297.80371 -384.269061) (xy 297.811466 -384.323009) (xy 297.811952 -384.35026) (xy 297.811952 -385.21386)
			(xy 297.811466 -385.241111) (xy 297.80371 -385.295059) (xy 297.790858 -385.338828) (xy 326.895968 -385.338828)
			(xy 326.895968 -384.475228) (xy 326.896454 -384.447977) (xy 326.90421 -384.394029) (xy 326.919565 -384.341734)
			(xy 326.942207 -384.292157) (xy 326.971673 -384.246307) (xy 327.007364 -384.205116) (xy 327.048555 -384.169425)
			(xy 327.094405 -384.139959) (xy 327.143982 -384.117317) (xy 327.196277 -384.101962) (xy 327.250225 -384.094206)
			(xy 327.304727 -384.094206) (xy 327.358675 -384.101962) (xy 327.41097 -384.117317) (xy 327.460547 -384.139959)
			(xy 327.506397 -384.169425) (xy 327.547588 -384.205116) (xy 327.583279 -384.246307) (xy 327.612745 -384.292157)
			(xy 327.635387 -384.341734) (xy 327.650742 -384.394029) (xy 327.658498 -384.447977) (xy 327.658984 -384.475228)
			(xy 327.658984 -385.21386) (xy 329.576684 -385.21386) (xy 329.576684 -384.35026) (xy 329.57717 -384.323009)
			(xy 329.584926 -384.269061) (xy 329.600281 -384.216766) (xy 329.622923 -384.167189) (xy 329.652389 -384.121339)
			(xy 329.68808 -384.080148) (xy 329.729271 -384.044457) (xy 329.775121 -384.014991) (xy 329.824698 -383.992349)
			(xy 329.876993 -383.976994) (xy 329.930941 -383.969238) (xy 329.985443 -383.969238) (xy 330.039391 -383.976994)
			(xy 330.091686 -383.992349) (xy 330.141263 -384.014991) (xy 330.187113 -384.044457) (xy 330.228304 -384.080148)
			(xy 330.263995 -384.121339) (xy 330.293461 -384.167189) (xy 330.316103 -384.216766) (xy 330.331458 -384.269061)
			(xy 330.339214 -384.323009) (xy 330.3397 -384.35026) (xy 330.3397 -385.21386) (xy 330.339214 -385.241111)
			(xy 330.331458 -385.295059) (xy 330.318606 -385.338828) (xy 359.423716 -385.338828) (xy 359.423716 -384.475228)
			(xy 359.424202 -384.447977) (xy 359.431958 -384.394029) (xy 359.447313 -384.341734) (xy 359.469955 -384.292157)
			(xy 359.499421 -384.246307) (xy 359.535112 -384.205116) (xy 359.576303 -384.169425) (xy 359.622153 -384.139959)
			(xy 359.67173 -384.117317) (xy 359.724025 -384.101962) (xy 359.777973 -384.094206) (xy 359.832475 -384.094206)
			(xy 359.886423 -384.101962) (xy 359.938718 -384.117317) (xy 359.988295 -384.139959) (xy 360.034145 -384.169425)
			(xy 360.075336 -384.205116) (xy 360.111027 -384.246307) (xy 360.140493 -384.292157) (xy 360.163135 -384.341734)
			(xy 360.17849 -384.394029) (xy 360.186246 -384.447977) (xy 360.186732 -384.475228) (xy 360.186732 -385.21386)
			(xy 364.149132 -385.21386) (xy 364.149132 -384.35026) (xy 364.149618 -384.323009) (xy 364.157374 -384.269061)
			(xy 364.172729 -384.216766) (xy 364.195371 -384.167189) (xy 364.224837 -384.121339) (xy 364.260528 -384.080148)
			(xy 364.301719 -384.044457) (xy 364.347569 -384.014991) (xy 364.397146 -383.992349) (xy 364.449441 -383.976994)
			(xy 364.503389 -383.969238) (xy 364.557891 -383.969238) (xy 364.611839 -383.976994) (xy 364.664134 -383.992349)
			(xy 364.713711 -384.014991) (xy 364.759561 -384.044457) (xy 364.800752 -384.080148) (xy 364.836443 -384.121339)
			(xy 364.865909 -384.167189) (xy 364.888551 -384.216766) (xy 364.903906 -384.269061) (xy 364.911662 -384.323009)
			(xy 364.912148 -384.35026) (xy 364.912148 -385.21386) (xy 364.911662 -385.241111) (xy 364.903906 -385.295059)
			(xy 364.891054 -385.338828) (xy 393.996164 -385.338828) (xy 393.996164 -384.475228) (xy 393.99665 -384.447977)
			(xy 394.004406 -384.394029) (xy 394.019761 -384.341734) (xy 394.042403 -384.292157) (xy 394.071869 -384.246307)
			(xy 394.10756 -384.205116) (xy 394.148751 -384.169425) (xy 394.194601 -384.139959) (xy 394.244178 -384.117317)
			(xy 394.296473 -384.101962) (xy 394.350421 -384.094206) (xy 394.404923 -384.094206) (xy 394.458871 -384.101962)
			(xy 394.511166 -384.117317) (xy 394.560743 -384.139959) (xy 394.606593 -384.169425) (xy 394.647784 -384.205116)
			(xy 394.683475 -384.246307) (xy 394.712941 -384.292157) (xy 394.735583 -384.341734) (xy 394.750938 -384.394029)
			(xy 394.758694 -384.447977) (xy 394.75918 -384.475228) (xy 394.75918 -385.21386) (xy 396.67688 -385.21386)
			(xy 396.67688 -384.35026) (xy 396.677366 -384.323009) (xy 396.685122 -384.269061) (xy 396.700477 -384.216766)
			(xy 396.723119 -384.167189) (xy 396.752585 -384.121339) (xy 396.788276 -384.080148) (xy 396.829467 -384.044457)
			(xy 396.875317 -384.014991) (xy 396.924894 -383.992349) (xy 396.977189 -383.976994) (xy 397.031137 -383.969238)
			(xy 397.085639 -383.969238) (xy 397.139587 -383.976994) (xy 397.191882 -383.992349) (xy 397.241459 -384.014991)
			(xy 397.287309 -384.044457) (xy 397.3285 -384.080148) (xy 397.364191 -384.121339) (xy 397.393657 -384.167189)
			(xy 397.416299 -384.216766) (xy 397.431654 -384.269061) (xy 397.43941 -384.323009) (xy 397.439896 -384.35026)
			(xy 397.439896 -385.21386) (xy 397.43941 -385.241111) (xy 397.431654 -385.295059) (xy 397.418802 -385.338828)
			(xy 426.523912 -385.338828) (xy 426.523912 -384.475228) (xy 426.524398 -384.447977) (xy 426.532154 -384.394029)
			(xy 426.547509 -384.341734) (xy 426.570151 -384.292157) (xy 426.599617 -384.246307) (xy 426.635308 -384.205116)
			(xy 426.676499 -384.169425) (xy 426.722349 -384.139959) (xy 426.771926 -384.117317) (xy 426.824221 -384.101962)
			(xy 426.878169 -384.094206) (xy 426.932671 -384.094206) (xy 426.986619 -384.101962) (xy 427.038914 -384.117317)
			(xy 427.088491 -384.139959) (xy 427.134341 -384.169425) (xy 427.175532 -384.205116) (xy 427.211223 -384.246307)
			(xy 427.240689 -384.292157) (xy 427.263331 -384.341734) (xy 427.278686 -384.394029) (xy 427.286442 -384.447977)
			(xy 427.286928 -384.475228) (xy 427.286928 -385.338828) (xy 427.286442 -385.366079) (xy 427.278686 -385.420027)
			(xy 427.263331 -385.472322) (xy 427.240689 -385.521899) (xy 427.211223 -385.567749) (xy 427.175532 -385.60894)
			(xy 427.134341 -385.644631) (xy 427.088491 -385.674097) (xy 427.038914 -385.696739) (xy 426.986619 -385.712094)
			(xy 426.932671 -385.71985) (xy 426.878169 -385.71985) (xy 426.824221 -385.712094) (xy 426.771926 -385.696739)
			(xy 426.722349 -385.674097) (xy 426.676499 -385.644631) (xy 426.635308 -385.60894) (xy 426.599617 -385.567749)
			(xy 426.570151 -385.521899) (xy 426.547509 -385.472322) (xy 426.532154 -385.420027) (xy 426.524398 -385.366079)
			(xy 426.523912 -385.338828) (xy 397.418802 -385.338828) (xy 397.416299 -385.347354) (xy 397.393657 -385.396931)
			(xy 397.364191 -385.442781) (xy 397.3285 -385.483972) (xy 397.287309 -385.519663) (xy 397.241459 -385.549129)
			(xy 397.191882 -385.571771) (xy 397.139587 -385.587126) (xy 397.085639 -385.594882) (xy 397.031137 -385.594882)
			(xy 396.977189 -385.587126) (xy 396.924894 -385.571771) (xy 396.875317 -385.549129) (xy 396.829467 -385.519663)
			(xy 396.788276 -385.483972) (xy 396.752585 -385.442781) (xy 396.723119 -385.396931) (xy 396.700477 -385.347354)
			(xy 396.685122 -385.295059) (xy 396.677366 -385.241111) (xy 396.67688 -385.21386) (xy 394.75918 -385.21386)
			(xy 394.75918 -385.338828) (xy 394.758694 -385.366079) (xy 394.750938 -385.420027) (xy 394.735583 -385.472322)
			(xy 394.712941 -385.521899) (xy 394.683475 -385.567749) (xy 394.647784 -385.60894) (xy 394.606593 -385.644631)
			(xy 394.560743 -385.674097) (xy 394.511166 -385.696739) (xy 394.458871 -385.712094) (xy 394.404923 -385.71985)
			(xy 394.350421 -385.71985) (xy 394.296473 -385.712094) (xy 394.244178 -385.696739) (xy 394.194601 -385.674097)
			(xy 394.148751 -385.644631) (xy 394.10756 -385.60894) (xy 394.071869 -385.567749) (xy 394.042403 -385.521899)
			(xy 394.019761 -385.472322) (xy 394.004406 -385.420027) (xy 393.99665 -385.366079) (xy 393.996164 -385.338828)
			(xy 364.891054 -385.338828) (xy 364.888551 -385.347354) (xy 364.865909 -385.396931) (xy 364.836443 -385.442781)
			(xy 364.800752 -385.483972) (xy 364.759561 -385.519663) (xy 364.713711 -385.549129) (xy 364.664134 -385.571771)
			(xy 364.611839 -385.587126) (xy 364.557891 -385.594882) (xy 364.503389 -385.594882) (xy 364.449441 -385.587126)
			(xy 364.397146 -385.571771) (xy 364.347569 -385.549129) (xy 364.301719 -385.519663) (xy 364.260528 -385.483972)
			(xy 364.224837 -385.442781) (xy 364.195371 -385.396931) (xy 364.172729 -385.347354) (xy 364.157374 -385.295059)
			(xy 364.149618 -385.241111) (xy 364.149132 -385.21386) (xy 360.186732 -385.21386) (xy 360.186732 -385.338828)
			(xy 360.186246 -385.366079) (xy 360.17849 -385.420027) (xy 360.163135 -385.472322) (xy 360.140493 -385.521899)
			(xy 360.111027 -385.567749) (xy 360.075336 -385.60894) (xy 360.034145 -385.644631) (xy 359.988295 -385.674097)
			(xy 359.938718 -385.696739) (xy 359.886423 -385.712094) (xy 359.832475 -385.71985) (xy 359.777973 -385.71985)
			(xy 359.724025 -385.712094) (xy 359.67173 -385.696739) (xy 359.622153 -385.674097) (xy 359.576303 -385.644631)
			(xy 359.535112 -385.60894) (xy 359.499421 -385.567749) (xy 359.469955 -385.521899) (xy 359.447313 -385.472322)
			(xy 359.431958 -385.420027) (xy 359.424202 -385.366079) (xy 359.423716 -385.338828) (xy 330.318606 -385.338828)
			(xy 330.316103 -385.347354) (xy 330.293461 -385.396931) (xy 330.263995 -385.442781) (xy 330.228304 -385.483972)
			(xy 330.187113 -385.519663) (xy 330.141263 -385.549129) (xy 330.091686 -385.571771) (xy 330.039391 -385.587126)
			(xy 329.985443 -385.594882) (xy 329.930941 -385.594882) (xy 329.876993 -385.587126) (xy 329.824698 -385.571771)
			(xy 329.775121 -385.549129) (xy 329.729271 -385.519663) (xy 329.68808 -385.483972) (xy 329.652389 -385.442781)
			(xy 329.622923 -385.396931) (xy 329.600281 -385.347354) (xy 329.584926 -385.295059) (xy 329.57717 -385.241111)
			(xy 329.576684 -385.21386) (xy 327.658984 -385.21386) (xy 327.658984 -385.338828) (xy 327.658498 -385.366079)
			(xy 327.650742 -385.420027) (xy 327.635387 -385.472322) (xy 327.612745 -385.521899) (xy 327.583279 -385.567749)
			(xy 327.547588 -385.60894) (xy 327.506397 -385.644631) (xy 327.460547 -385.674097) (xy 327.41097 -385.696739)
			(xy 327.358675 -385.712094) (xy 327.304727 -385.71985) (xy 327.250225 -385.71985) (xy 327.196277 -385.712094)
			(xy 327.143982 -385.696739) (xy 327.094405 -385.674097) (xy 327.048555 -385.644631) (xy 327.007364 -385.60894)
			(xy 326.971673 -385.567749) (xy 326.942207 -385.521899) (xy 326.919565 -385.472322) (xy 326.90421 -385.420027)
			(xy 326.896454 -385.366079) (xy 326.895968 -385.338828) (xy 297.790858 -385.338828) (xy 297.788355 -385.347354)
			(xy 297.765713 -385.396931) (xy 297.736247 -385.442781) (xy 297.700556 -385.483972) (xy 297.659365 -385.519663)
			(xy 297.613515 -385.549129) (xy 297.563938 -385.571771) (xy 297.511643 -385.587126) (xy 297.457695 -385.594882)
			(xy 297.403193 -385.594882) (xy 297.349245 -385.587126) (xy 297.29695 -385.571771) (xy 297.247373 -385.549129)
			(xy 297.201523 -385.519663) (xy 297.160332 -385.483972) (xy 297.124641 -385.442781) (xy 297.095175 -385.396931)
			(xy 297.072533 -385.347354) (xy 297.057178 -385.295059) (xy 297.049422 -385.241111) (xy 297.048936 -385.21386)
			(xy 295.372367 -385.21386) (xy 295.370041 -385.249842) (xy 295.350085 -385.434603) (xy 295.322199 -385.618335)
			(xy 295.286435 -385.800697) (xy 295.242858 -385.981352) (xy 295.191549 -386.159964) (xy 295.132604 -386.336204)
			(xy 295.06613 -386.509744) (xy 294.992252 -386.680264) (xy 294.911107 -386.847448) (xy 294.822844 -387.010986)
			(xy 294.727626 -387.170575) (xy 294.625632 -387.32592) (xy 294.517048 -387.476733) (xy 294.402076 -387.622735)
			(xy 294.28093 -387.763655) (xy 294.153833 -387.899233) (xy 294.021021 -388.029218) (xy 293.882739 -388.153368)
			(xy 293.739245 -388.271454) (xy 293.590803 -388.383257) (xy 293.437688 -388.48857) (xy 293.280184 -388.587199)
			(xy 293.118583 -388.67896) (xy 292.994679 -388.742428) (xy 326.895968 -388.742428) (xy 326.895968 -387.878828)
			(xy 326.896454 -387.851577) (xy 326.90421 -387.797629) (xy 326.919565 -387.745334) (xy 326.942207 -387.695757)
			(xy 326.971673 -387.649907) (xy 327.007364 -387.608716) (xy 327.048555 -387.573025) (xy 327.094405 -387.543559)
			(xy 327.143982 -387.520917) (xy 327.196277 -387.505562) (xy 327.250225 -387.497806) (xy 327.304727 -387.497806)
			(xy 327.358675 -387.505562) (xy 327.41097 -387.520917) (xy 327.460547 -387.543559) (xy 327.506397 -387.573025)
			(xy 327.547588 -387.608716) (xy 327.583279 -387.649907) (xy 327.612745 -387.695757) (xy 327.635387 -387.745334)
			(xy 327.650742 -387.797629) (xy 327.658498 -387.851577) (xy 327.658984 -387.878828) (xy 327.658984 -388.742428)
			(xy 359.423716 -388.742428) (xy 359.423716 -387.878828) (xy 359.424202 -387.851577) (xy 359.431958 -387.797629)
			(xy 359.447313 -387.745334) (xy 359.469955 -387.695757) (xy 359.499421 -387.649907) (xy 359.535112 -387.608716)
			(xy 359.576303 -387.573025) (xy 359.622153 -387.543559) (xy 359.67173 -387.520917) (xy 359.724025 -387.505562)
			(xy 359.777973 -387.497806) (xy 359.832475 -387.497806) (xy 359.886423 -387.505562) (xy 359.938718 -387.520917)
			(xy 359.988295 -387.543559) (xy 360.034145 -387.573025) (xy 360.075336 -387.608716) (xy 360.111027 -387.649907)
			(xy 360.140493 -387.695757) (xy 360.163135 -387.745334) (xy 360.17849 -387.797629) (xy 360.186246 -387.851577)
			(xy 360.186732 -387.878828) (xy 360.186732 -388.742428) (xy 393.996164 -388.742428) (xy 393.996164 -387.878828)
			(xy 393.99665 -387.851577) (xy 394.004406 -387.797629) (xy 394.019761 -387.745334) (xy 394.042403 -387.695757)
			(xy 394.071869 -387.649907) (xy 394.10756 -387.608716) (xy 394.148751 -387.573025) (xy 394.194601 -387.543559)
			(xy 394.244178 -387.520917) (xy 394.296473 -387.505562) (xy 394.350421 -387.497806) (xy 394.404923 -387.497806)
			(xy 394.458871 -387.505562) (xy 394.511166 -387.520917) (xy 394.560743 -387.543559) (xy 394.606593 -387.573025)
			(xy 394.647784 -387.608716) (xy 394.683475 -387.649907) (xy 394.712941 -387.695757) (xy 394.735583 -387.745334)
			(xy 394.750938 -387.797629) (xy 394.758694 -387.851577) (xy 394.75918 -387.878828) (xy 394.75918 -388.742428)
			(xy 426.523912 -388.742428) (xy 426.523912 -387.878828) (xy 426.524398 -387.851577) (xy 426.532154 -387.797629)
			(xy 426.547509 -387.745334) (xy 426.570151 -387.695757) (xy 426.599617 -387.649907) (xy 426.635308 -387.608716)
			(xy 426.676499 -387.573025) (xy 426.722349 -387.543559) (xy 426.771926 -387.520917) (xy 426.824221 -387.505562)
			(xy 426.878169 -387.497806) (xy 426.932671 -387.497806) (xy 426.986619 -387.505562) (xy 427.038914 -387.520917)
			(xy 427.088491 -387.543559) (xy 427.134341 -387.573025) (xy 427.175532 -387.608716) (xy 427.211223 -387.649907)
			(xy 427.240689 -387.695757) (xy 427.263331 -387.745334) (xy 427.278686 -387.797629) (xy 427.286442 -387.851577)
			(xy 427.286928 -387.878828) (xy 427.286928 -388.742428) (xy 427.286442 -388.769679) (xy 427.278686 -388.823627)
			(xy 427.263331 -388.875922) (xy 427.240689 -388.925499) (xy 427.211223 -388.971349) (xy 427.175532 -389.01254)
			(xy 427.134341 -389.048231) (xy 427.088491 -389.077697) (xy 427.038914 -389.100339) (xy 426.986619 -389.115694)
			(xy 426.932671 -389.12345) (xy 426.878169 -389.12345) (xy 426.824221 -389.115694) (xy 426.771926 -389.100339)
			(xy 426.722349 -389.077697) (xy 426.676499 -389.048231) (xy 426.635308 -389.01254) (xy 426.599617 -388.971349)
			(xy 426.570151 -388.925499) (xy 426.547509 -388.875922) (xy 426.532154 -388.823627) (xy 426.524398 -388.769679)
			(xy 426.523912 -388.742428) (xy 394.75918 -388.742428) (xy 394.758694 -388.769679) (xy 394.750938 -388.823627)
			(xy 394.735583 -388.875922) (xy 394.712941 -388.925499) (xy 394.683475 -388.971349) (xy 394.647784 -389.01254)
			(xy 394.606593 -389.048231) (xy 394.560743 -389.077697) (xy 394.511166 -389.100339) (xy 394.458871 -389.115694)
			(xy 394.404923 -389.12345) (xy 394.350421 -389.12345) (xy 394.296473 -389.115694) (xy 394.244178 -389.100339)
			(xy 394.194601 -389.077697) (xy 394.148751 -389.048231) (xy 394.10756 -389.01254) (xy 394.071869 -388.971349)
			(xy 394.042403 -388.925499) (xy 394.019761 -388.875922) (xy 394.004406 -388.823627) (xy 393.99665 -388.769679)
			(xy 393.996164 -388.742428) (xy 360.186732 -388.742428) (xy 360.186246 -388.769679) (xy 360.17849 -388.823627)
			(xy 360.163135 -388.875922) (xy 360.140493 -388.925499) (xy 360.111027 -388.971349) (xy 360.075336 -389.01254)
			(xy 360.034145 -389.048231) (xy 359.988295 -389.077697) (xy 359.938718 -389.100339) (xy 359.886423 -389.115694)
			(xy 359.832475 -389.12345) (xy 359.777973 -389.12345) (xy 359.724025 -389.115694) (xy 359.67173 -389.100339)
			(xy 359.622153 -389.077697) (xy 359.576303 -389.048231) (xy 359.535112 -389.01254) (xy 359.499421 -388.971349)
			(xy 359.469955 -388.925499) (xy 359.447313 -388.875922) (xy 359.431958 -388.823627) (xy 359.424202 -388.769679)
			(xy 359.423716 -388.742428) (xy 327.658984 -388.742428) (xy 327.658498 -388.769679) (xy 327.650742 -388.823627)
			(xy 327.635387 -388.875922) (xy 327.612745 -388.925499) (xy 327.583279 -388.971349) (xy 327.547588 -389.01254)
			(xy 327.506397 -389.048231) (xy 327.460547 -389.077697) (xy 327.41097 -389.100339) (xy 327.358675 -389.115694)
			(xy 327.304727 -389.12345) (xy 327.250225 -389.12345) (xy 327.196277 -389.115694) (xy 327.143982 -389.100339)
			(xy 327.094405 -389.077697) (xy 327.048555 -389.048231) (xy 327.007364 -389.01254) (xy 326.971673 -388.971349)
			(xy 326.942207 -388.925499) (xy 326.919565 -388.875922) (xy 326.90421 -388.823627) (xy 326.896454 -388.769679)
			(xy 326.895968 -388.742428) (xy 292.994679 -388.742428) (xy 292.953184 -388.763683) (xy 292.784293 -388.841213)
			(xy 292.612222 -388.911404) (xy 292.437292 -388.974128) (xy 292.259824 -389.029267) (xy 292.080149 -389.076721)
			(xy 291.898599 -389.1164) (xy 291.715509 -389.148232) (xy 291.53122 -389.172158) (xy 291.346072 -389.188133)
			(xy 291.160408 -389.196127) (xy 291.06749 -389.19658) (xy 290.973899 -389.196079) (xy 290.786892 -389.187967)
			(xy 290.600412 -389.171758) (xy 290.41481 -389.147482) (xy 290.230434 -389.115186) (xy 290.047631 -389.07493)
			(xy 289.866745 -389.026789) (xy 289.688115 -388.970855) (xy 289.512076 -388.907232) (xy 289.33896 -388.836039)
			(xy 289.169093 -388.757411) (xy 289.002792 -388.671495) (xy 288.840371 -388.578453) (xy 288.682135 -388.47846)
			(xy 288.52838 -388.371703) (xy 288.453576 -388.315454) (xy 288.442146 -388.306818) (xy 288.41319 -388.304024)
			(xy 288.318702 -388.35076) (xy 288.310398 -388.355325) (xy 288.297662 -388.369337) (xy 288.290865 -388.387011)
			(xy 288.290508 -388.39648) (xy 288.290508 -390.75106) (xy 297.048936 -390.75106) (xy 297.048936 -389.88746)
			(xy 297.049422 -389.860209) (xy 297.057178 -389.806261) (xy 297.072533 -389.753966) (xy 297.095175 -389.704389)
			(xy 297.124641 -389.658539) (xy 297.160332 -389.617348) (xy 297.201523 -389.581657) (xy 297.247373 -389.552191)
			(xy 297.29695 -389.529549) (xy 297.349245 -389.514194) (xy 297.403193 -389.506438) (xy 297.457695 -389.506438)
			(xy 297.511643 -389.514194) (xy 297.563938 -389.529549) (xy 297.613515 -389.552191) (xy 297.659365 -389.581657)
			(xy 297.700556 -389.617348) (xy 297.736247 -389.658539) (xy 297.765713 -389.704389) (xy 297.788355 -389.753966)
			(xy 297.80371 -389.806261) (xy 297.811466 -389.860209) (xy 297.811952 -389.88746) (xy 297.811952 -390.75106)
			(xy 329.576684 -390.75106) (xy 329.576684 -389.88746) (xy 329.57717 -389.860209) (xy 329.584926 -389.806261)
			(xy 329.600281 -389.753966) (xy 329.622923 -389.704389) (xy 329.652389 -389.658539) (xy 329.68808 -389.617348)
			(xy 329.729271 -389.581657) (xy 329.775121 -389.552191) (xy 329.824698 -389.529549) (xy 329.876993 -389.514194)
			(xy 329.930941 -389.506438) (xy 329.985443 -389.506438) (xy 330.039391 -389.514194) (xy 330.091686 -389.529549)
			(xy 330.141263 -389.552191) (xy 330.187113 -389.581657) (xy 330.228304 -389.617348) (xy 330.263995 -389.658539)
			(xy 330.293461 -389.704389) (xy 330.316103 -389.753966) (xy 330.331458 -389.806261) (xy 330.339214 -389.860209)
			(xy 330.3397 -389.88746) (xy 330.3397 -390.75106) (xy 364.149132 -390.75106) (xy 364.149132 -389.88746)
			(xy 364.149618 -389.860209) (xy 364.157374 -389.806261) (xy 364.172729 -389.753966) (xy 364.195371 -389.704389)
			(xy 364.224837 -389.658539) (xy 364.260528 -389.617348) (xy 364.301719 -389.581657) (xy 364.347569 -389.552191)
			(xy 364.397146 -389.529549) (xy 364.449441 -389.514194) (xy 364.503389 -389.506438) (xy 364.557891 -389.506438)
			(xy 364.611839 -389.514194) (xy 364.664134 -389.529549) (xy 364.713711 -389.552191) (xy 364.759561 -389.581657)
			(xy 364.800752 -389.617348) (xy 364.836443 -389.658539) (xy 364.865909 -389.704389) (xy 364.888551 -389.753966)
			(xy 364.903906 -389.806261) (xy 364.911662 -389.860209) (xy 364.912148 -389.88746) (xy 364.912148 -390.75106)
			(xy 396.67688 -390.75106) (xy 396.67688 -389.88746) (xy 396.677366 -389.860209) (xy 396.685122 -389.806261)
			(xy 396.700477 -389.753966) (xy 396.723119 -389.704389) (xy 396.752585 -389.658539) (xy 396.788276 -389.617348)
			(xy 396.829467 -389.581657) (xy 396.875317 -389.552191) (xy 396.924894 -389.529549) (xy 396.977189 -389.514194)
			(xy 397.031137 -389.506438) (xy 397.085639 -389.506438) (xy 397.139587 -389.514194) (xy 397.191882 -389.529549)
			(xy 397.241459 -389.552191) (xy 397.287309 -389.581657) (xy 397.3285 -389.617348) (xy 397.364191 -389.658539)
			(xy 397.393657 -389.704389) (xy 397.416299 -389.753966) (xy 397.431654 -389.806261) (xy 397.43941 -389.860209)
			(xy 397.439896 -389.88746) (xy 397.439896 -390.75106) (xy 397.43941 -390.778311) (xy 397.431654 -390.832259)
			(xy 397.416299 -390.884554) (xy 397.393657 -390.934131) (xy 397.364191 -390.979981) (xy 397.3285 -391.021172)
			(xy 397.287309 -391.056863) (xy 397.241459 -391.086329) (xy 397.191882 -391.108971) (xy 397.139587 -391.124326)
			(xy 397.085639 -391.132082) (xy 397.031137 -391.132082) (xy 396.977189 -391.124326) (xy 396.924894 -391.108971)
			(xy 396.875317 -391.086329) (xy 396.829467 -391.056863) (xy 396.788276 -391.021172) (xy 396.752585 -390.979981)
			(xy 396.723119 -390.934131) (xy 396.700477 -390.884554) (xy 396.685122 -390.832259) (xy 396.677366 -390.778311)
			(xy 396.67688 -390.75106) (xy 364.912148 -390.75106) (xy 364.911662 -390.778311) (xy 364.903906 -390.832259)
			(xy 364.888551 -390.884554) (xy 364.865909 -390.934131) (xy 364.836443 -390.979981) (xy 364.800752 -391.021172)
			(xy 364.759561 -391.056863) (xy 364.713711 -391.086329) (xy 364.664134 -391.108971) (xy 364.611839 -391.124326)
			(xy 364.557891 -391.132082) (xy 364.503389 -391.132082) (xy 364.449441 -391.124326) (xy 364.397146 -391.108971)
			(xy 364.347569 -391.086329) (xy 364.301719 -391.056863) (xy 364.260528 -391.021172) (xy 364.224837 -390.979981)
			(xy 364.195371 -390.934131) (xy 364.172729 -390.884554) (xy 364.157374 -390.832259) (xy 364.149618 -390.778311)
			(xy 364.149132 -390.75106) (xy 330.3397 -390.75106) (xy 330.339214 -390.778311) (xy 330.331458 -390.832259)
			(xy 330.316103 -390.884554) (xy 330.293461 -390.934131) (xy 330.263995 -390.979981) (xy 330.228304 -391.021172)
			(xy 330.187113 -391.056863) (xy 330.141263 -391.086329) (xy 330.091686 -391.108971) (xy 330.039391 -391.124326)
			(xy 329.985443 -391.132082) (xy 329.930941 -391.132082) (xy 329.876993 -391.124326) (xy 329.824698 -391.108971)
			(xy 329.775121 -391.086329) (xy 329.729271 -391.056863) (xy 329.68808 -391.021172) (xy 329.652389 -390.979981)
			(xy 329.622923 -390.934131) (xy 329.600281 -390.884554) (xy 329.584926 -390.832259) (xy 329.57717 -390.778311)
			(xy 329.576684 -390.75106) (xy 297.811952 -390.75106) (xy 297.811466 -390.778311) (xy 297.80371 -390.832259)
			(xy 297.788355 -390.884554) (xy 297.765713 -390.934131) (xy 297.736247 -390.979981) (xy 297.700556 -391.021172)
			(xy 297.659365 -391.056863) (xy 297.613515 -391.086329) (xy 297.563938 -391.108971) (xy 297.511643 -391.124326)
			(xy 297.457695 -391.132082) (xy 297.403193 -391.132082) (xy 297.349245 -391.124326) (xy 297.29695 -391.108971)
			(xy 297.247373 -391.086329) (xy 297.201523 -391.056863) (xy 297.160332 -391.021172) (xy 297.124641 -390.979981)
			(xy 297.095175 -390.934131) (xy 297.072533 -390.884554) (xy 297.057178 -390.832259) (xy 297.049422 -390.778311)
			(xy 297.048936 -390.75106) (xy 288.290508 -390.75106) (xy 288.290508 -396.171674) (xy 296.901108 -396.171674)
			(xy 296.901108 -395.308074) (xy 296.901594 -395.280823) (xy 296.90935 -395.226875) (xy 296.924705 -395.17458)
			(xy 296.947347 -395.125003) (xy 296.976813 -395.079153) (xy 297.012504 -395.037962) (xy 297.053695 -395.002271)
			(xy 297.099545 -394.972805) (xy 297.149122 -394.950163) (xy 297.201417 -394.934808) (xy 297.255365 -394.927052)
			(xy 297.309867 -394.927052) (xy 297.363815 -394.934808) (xy 297.41611 -394.950163) (xy 297.465687 -394.972805)
			(xy 297.511537 -395.002271) (xy 297.552728 -395.037962) (xy 297.588419 -395.079153) (xy 297.617885 -395.125003)
			(xy 297.640527 -395.17458) (xy 297.655882 -395.226875) (xy 297.663638 -395.280823) (xy 297.664124 -395.308074)
			(xy 297.664124 -396.171674) (xy 297.663638 -396.198925) (xy 297.655882 -396.252873) (xy 297.640527 -396.305168)
			(xy 297.617885 -396.354745) (xy 297.588419 -396.400595) (xy 297.552728 -396.441786) (xy 297.511537 -396.477477)
			(xy 297.465687 -396.506943) (xy 297.41611 -396.529585) (xy 297.363815 -396.54494) (xy 297.309867 -396.552696)
			(xy 297.255365 -396.552696) (xy 297.201417 -396.54494) (xy 297.149122 -396.529585) (xy 297.099545 -396.506943)
			(xy 297.053695 -396.477477) (xy 297.012504 -396.441786) (xy 296.976813 -396.400595) (xy 296.947347 -396.354745)
			(xy 296.924705 -396.305168) (xy 296.90935 -396.252873) (xy 296.901594 -396.198925) (xy 296.901108 -396.171674)
			(xy 288.290508 -396.171674) (xy 288.290508 -398.339818) (xy 288.293048 -398.350994) (xy 288.295842 -398.356328)
			(xy 288.307389 -398.380957) (xy 288.323703 -398.432845) (xy 288.331933 -398.486611) (xy 288.332418 -398.513808)
			(xy 288.332302 -398.526937) (xy 288.330392 -398.553125) (xy 288.328608 -398.566132) (xy 288.32683 -398.57807)
			(xy 288.334196 -398.60093) (xy 289.297364 -399.564098) (xy 289.304766 -399.570935) (xy 289.323364 -399.578646)
			(xy 289.333432 -399.579084)
		)
		(stroke
			(width 0)
			(type solid)
		)
		(fill yes)
		(layer "In8.Cu")
		(net "P1V8_CPU0_RT_1D")
	)
	(gr_poly
		(pts
			(xy 285.486856 -355.918262) (xy 285.487872 -355.898196) (xy 285.4909 -355.855081) (xy 285.504276 -355.769685)
			(xy 285.525868 -355.685989) (xy 285.540196 -355.645212) (xy 285.543022 -355.636325) (xy 285.542766 -355.617693)
			(xy 285.539688 -355.60889) (xy 285.524477 -355.569491) (xy 285.50071 -355.488443) (xy 285.484739 -355.405506)
			(xy 285.476708 -355.321428) (xy 285.476188 -355.279198) (xy 285.476649 -355.238084) (xy 285.484236 -355.156207)
			(xy 285.499346 -355.075379) (xy 285.52185 -354.99629) (xy 285.551555 -354.919615) (xy 285.588209 -354.846009)
			(xy 285.631498 -354.776098) (xy 285.681053 -354.71048) (xy 285.736451 -354.649714) (xy 285.79722 -354.594319)
			(xy 285.862841 -354.544768) (xy 285.932754 -354.501483) (xy 286.006363 -354.464834) (xy 286.08304 -354.435133)
			(xy 286.16213 -354.412634) (xy 286.242958 -354.397529) (xy 286.324836 -354.389946) (xy 286.36595 -354.389436)
			(xy 286.404238 -354.389874) (xy 286.480527 -354.396501) (xy 286.555965 -354.409651) (xy 286.629997 -354.429226)
			(xy 286.666178 -354.44176) (xy 286.674615 -354.444411) (xy 286.692285 -354.444411) (xy 286.700722 -354.44176)
			(xy 286.736893 -354.429194) (xy 286.810924 -354.409605) (xy 286.886367 -354.39646) (xy 286.962661 -354.389856)
			(xy 287.00095 -354.389436) (xy 287.039238 -354.389874) (xy 287.115527 -354.396501) (xy 287.190965 -354.409651)
			(xy 287.264997 -354.429226) (xy 287.301178 -354.44176) (xy 287.309615 -354.444411) (xy 287.327285 -354.444411)
			(xy 287.335722 -354.44176) (xy 287.371893 -354.429194) (xy 287.445924 -354.409605) (xy 287.521367 -354.39646)
			(xy 287.597661 -354.389856) (xy 287.63595 -354.389436) (xy 287.674238 -354.389874) (xy 287.750527 -354.396501)
			(xy 287.825965 -354.409651) (xy 287.899997 -354.429226) (xy 287.936178 -354.44176) (xy 287.944615 -354.444411)
			(xy 287.962285 -354.444411) (xy 287.970722 -354.44176) (xy 288.006893 -354.429194) (xy 288.080924 -354.409605)
			(xy 288.156367 -354.39646) (xy 288.232661 -354.389856) (xy 288.27095 -354.389436) (xy 288.309238 -354.389874)
			(xy 288.385527 -354.396501) (xy 288.460965 -354.409651) (xy 288.534997 -354.429226) (xy 288.571178 -354.44176)
			(xy 288.579615 -354.444411) (xy 288.597285 -354.444411) (xy 288.605722 -354.44176) (xy 288.641893 -354.429194)
			(xy 288.715924 -354.409605) (xy 288.791367 -354.39646) (xy 288.867661 -354.389856) (xy 288.90595 -354.389436)
			(xy 288.947066 -354.389894) (xy 289.028949 -354.397477) (xy 289.109782 -354.412584) (xy 289.188877 -354.435084)
			(xy 289.265558 -354.464786) (xy 289.339171 -354.501438) (xy 289.409089 -354.544725) (xy 289.474713 -354.594279)
			(xy 289.535486 -354.649677) (xy 289.590887 -354.710447) (xy 289.640445 -354.776069) (xy 289.683737 -354.845983)
			(xy 289.720393 -354.919594) (xy 289.7501 -354.996274) (xy 289.772605 -355.075367) (xy 289.787715 -355.1562)
			(xy 289.795303 -355.238082) (xy 289.795712 -355.279198) (xy 289.79529 -355.318061) (xy 289.78849 -355.395489)
			(xy 289.774959 -355.472028) (xy 289.754801 -355.547095) (xy 289.741864 -355.583744) (xy 289.739049 -355.592631)
			(xy 289.739324 -355.611255) (xy 289.742372 -355.620066) (xy 289.75948 -355.664606) (xy 289.785183 -355.756496)
			(xy 289.800924 -355.850606) (xy 289.804348 -355.898196) (xy 289.805364 -355.918262) (xy 289.834828 -355.945948)
			(xy 305.153314 -355.945948) (xy 305.162236 -355.945559) (xy 305.179005 -355.939459) (xy 305.18608 -355.93401)
			(xy 305.206777 -355.917305) (xy 305.251922 -355.889185) (xy 305.300534 -355.867604) (xy 305.351671 -355.85298)
			(xy 305.404343 -355.845596) (xy 305.457529 -355.845596) (xy 305.510201 -355.85298) (xy 305.561338 -355.867604)
			(xy 305.60995 -355.889185) (xy 305.655095 -355.917305) (xy 305.675792 -355.93401) (xy 305.682842 -355.939504)
			(xy 305.699626 -355.945614) (xy 305.708558 -355.945948) (xy 420.089076 -355.945948) (xy 420.096027 -355.945707)
			(xy 420.109417 -355.941968) (xy 420.115492 -355.938582) (xy 420.141129 -355.923764) (xy 420.195945 -355.901373)
			(xy 420.253562 -355.887719) (xy 420.312596 -355.883131) (xy 420.37163 -355.887719) (xy 420.429247 -355.901373)
			(xy 420.484063 -355.923764) (xy 420.5097 -355.938582) (xy 420.515755 -355.942014) (xy 420.529159 -355.945746)
			(xy 420.536116 -355.945948) (xy 423.16019 -355.945948) (xy 423.167603 -355.945695) (xy 423.181803 -355.941437)
			(xy 423.18813 -355.937566) (xy 423.21157 -355.922792) (xy 423.26181 -355.899434) (xy 423.3149 -355.883585)
			(xy 423.369723 -355.875576) (xy 423.425129 -355.875576) (xy 423.479952 -355.883585) (xy 423.533042 -355.899434)
			(xy 423.583282 -355.922792) (xy 423.606722 -355.937566) (xy 423.613051 -355.941433) (xy 423.62725 -355.945695)
			(xy 423.634662 -355.945948) (xy 427.889416 -355.945948) (xy 427.901262 -355.945327) (xy 427.922455 -355.934734)
			(xy 427.930056 -355.925628) (xy 427.946795 -355.904267) (xy 427.985314 -355.86604) (xy 428.028859 -355.833653)
			(xy 428.076552 -355.807761) (xy 428.127431 -355.788884) (xy 428.180471 -355.777403) (xy 428.234602 -355.77355)
			(xy 428.288733 -355.777403) (xy 428.341773 -355.788884) (xy 428.392652 -355.807761) (xy 428.440345 -355.833653)
			(xy 428.48389 -355.86604) (xy 428.522409 -355.904267) (xy 428.539148 -355.925628) (xy 428.546754 -355.934728)
			(xy 428.567944 -355.945318) (xy 428.579788 -355.945948) (xy 431.53711 -355.945948) (xy 431.548286 -355.943408)
			(xy 431.55362 -355.940614) (xy 431.580223 -355.927942) (xy 431.636364 -355.910049) (xy 431.694592 -355.901022)
			(xy 431.724054 -355.900482) (xy 431.753513 -355.901037) (xy 431.811731 -355.910097) (xy 431.86787 -355.927979)
			(xy 431.894488 -355.940614) (xy 431.899822 -355.943408) (xy 431.910998 -355.945948) (xy 439.547762 -355.945948)
			(xy 439.557826 -355.945512) (xy 439.576409 -355.937776) (xy 439.58383 -355.930962) (xy 440.567572 -354.94722)
			(xy 440.574409 -354.939819) (xy 440.582119 -354.92122) (xy 440.582558 -354.911152) (xy 440.582558 -353.998022)
			(xy 440.5822 -353.988941) (xy 440.575865 -353.971921) (xy 440.563957 -353.958208) (xy 440.556142 -353.953572)
			(xy 440.490276 -353.916785) (xy 440.362042 -353.837277) (xy 440.238121 -353.751201) (xy 440.11885 -353.658789)
			(xy 440.004553 -353.560292) (xy 439.89554 -353.455977) (xy 439.792105 -353.346127) (xy 439.694531 -353.231041)
			(xy 439.603082 -353.111031) (xy 439.518005 -352.986421) (xy 439.439532 -352.857551) (xy 439.367876 -352.72477)
			(xy 439.30323 -352.588438) (xy 439.245771 -352.448924) (xy 439.195654 -352.306608) (xy 439.153016 -352.161876)
			(xy 439.117971 -352.01512) (xy 439.090615 -351.866738) (xy 439.071022 -351.717133) (xy 439.059245 -351.566711)
			(xy 439.055317 -351.41588) (xy 439.059247 -351.265048) (xy 439.071026 -351.114626) (xy 439.090621 -350.965022)
			(xy 439.117979 -350.81664) (xy 439.153026 -350.669885) (xy 439.195667 -350.525153) (xy 439.245786 -350.382838)
			(xy 439.303247 -350.243325) (xy 439.367894 -350.106994) (xy 439.439553 -349.974214) (xy 439.518027 -349.845345)
			(xy 439.603106 -349.720736) (xy 439.694557 -349.600727) (xy 439.792132 -349.485642) (xy 439.895568 -349.375795)
			(xy 440.004583 -349.271481) (xy 440.118882 -349.172986) (xy 440.238154 -349.080575) (xy 440.362075 -348.9945)
			(xy 440.490311 -348.914995) (xy 440.556142 -348.878144) (xy 440.563911 -348.873452) (xy 440.575783 -348.859738)
			(xy 440.582166 -348.842761) (xy 440.582558 -348.833694) (xy 440.582558 -347.921072) (xy 440.58219 -347.912028)
			(xy 440.575902 -347.895068) (xy 440.564119 -347.881344) (xy 440.556396 -347.876622) (xy 440.531261 -347.862077)
			(xy 440.485316 -347.826563) (xy 440.445286 -347.784494) (xy 440.412096 -347.736843) (xy 440.386514 -347.684711)
			(xy 440.36913 -347.629304) (xy 440.360347 -347.571901) (xy 440.3598 -347.542866) (xy 440.360323 -347.514128)
			(xy 440.368951 -347.457303) (xy 440.386005 -347.402415) (xy 440.411099 -347.350706) (xy 440.443667 -347.303347)
			(xy 440.462924 -347.282008) (xy 440.469528 -347.274896) (xy 440.47664 -347.25737) (xy 440.47664 -347.167962)
			(xy 440.469528 -347.150436) (xy 440.462924 -347.143324) (xy 440.443649 -347.121998) (xy 440.411076 -347.074638)
			(xy 440.385975 -347.022927) (xy 440.368916 -346.968036) (xy 440.360284 -346.911206) (xy 440.3598 -346.882466)
			(xy 440.360274 -346.855097) (xy 440.368102 -346.800921) (xy 440.383593 -346.74842) (xy 440.406428 -346.698672)
			(xy 440.436139 -346.652699) (xy 440.45378 -346.631768) (xy 440.459876 -346.624656) (xy 440.466226 -346.607638)
			(xy 440.466226 -346.522294) (xy 440.459876 -346.505276) (xy 440.45378 -346.498164) (xy 440.436141 -346.477232)
			(xy 440.406421 -346.431264) (xy 440.383583 -346.381517) (xy 440.368099 -346.329014) (xy 440.360286 -346.274836)
			(xy 440.3598 -346.247466) (xy 440.360345 -346.218432) (xy 440.369146 -346.161034) (xy 440.386539 -346.105632)
			(xy 440.412123 -346.053504) (xy 440.445308 -346.005852) (xy 440.485327 -345.963776) (xy 440.531258 -345.928247)
			(xy 440.556396 -345.91371) (xy 440.564134 -345.909006) (xy 440.575926 -345.895279) (xy 440.582207 -345.878308)
			(xy 440.582558 -345.86926) (xy 440.582558 -341.09406) (xy 440.582071 -341.08406) (xy 440.574445 -341.065569)
			(xy 440.560355 -341.051373) (xy 440.551316 -341.04707) (xy 440.536838 -341.040974) (xy 440.506866 -341.04707)
			(xy 439.52922 -342.024716) (xy 439.511179 -342.041974) (xy 439.469685 -342.069728) (xy 439.423566 -342.088837)
			(xy 439.374603 -342.098564) (xy 439.349642 -342.099138) (xy 416.31235 -342.099138) (xy 416.287395 -342.098522)
			(xy 416.238445 -342.088777) (xy 416.192336 -342.069672) (xy 416.15084 -342.04194) (xy 416.132772 -342.024716)
			(xy 413.210248 -339.102192) (xy 413.202846 -339.095355) (xy 413.184248 -339.08764) (xy 413.17418 -339.087206)
			(xy 408.676602 -339.087206) (xy 408.66822 -339.090254) (xy 408.643103 -339.09888) (xy 408.59115 -339.10989)
			(xy 408.538172 -339.113584) (xy 408.485194 -339.10989) (xy 408.433241 -339.09888) (xy 408.408124 -339.090254)
			(xy 408.399742 -339.087206) (xy 390.99109 -339.087206) (xy 390.966134 -339.086594) (xy 390.917181 -339.076854)
			(xy 390.871068 -339.057753) (xy 390.829568 -339.030022) (xy 390.811512 -339.012784) (xy 379.668532 -327.869804)
			(xy 379.66113 -327.862968) (xy 379.642532 -327.855257) (xy 379.632464 -327.854818) (xy 359.442766 -327.854818)
			(xy 359.435056 -327.855046) (xy 359.420317 -327.859567) (xy 359.41381 -327.863708) (xy 359.389849 -327.879519)
			(xy 359.338187 -327.904545) (xy 359.283364 -327.921565) (xy 359.226612 -327.930196) (xy 359.19791 -327.930764)
			(xy 359.169203 -327.93025) (xy 359.112439 -327.921644) (xy 359.057611 -327.904612) (xy 359.005962 -327.879539)
			(xy 358.98201 -327.863708) (xy 358.975498 -327.859578) (xy 358.960762 -327.855061) (xy 358.953054 -327.854818)
			(xy 353.638104 -327.854818) (xy 353.627856 -327.855277) (xy 353.608979 -327.863262) (xy 353.601528 -327.870312)
			(xy 353.543616 -327.930764) (xy 353.53625 -327.950068) (xy 353.536758 -327.960482) (xy 353.537012 -327.975722)
			(xy 353.536525 -328.002972) (xy 353.528766 -328.056918) (xy 353.513409 -328.10921) (xy 353.490766 -328.158785)
			(xy 353.4613 -328.204633) (xy 353.425608 -328.245821) (xy 353.384418 -328.28151) (xy 353.338569 -328.310975)
			(xy 353.288993 -328.333615) (xy 353.2367 -328.34897) (xy 353.182754 -328.356726) (xy 353.155504 -328.35723)
			(xy 353.132292 -328.35689) (xy 353.086212 -328.351258) (xy 353.041159 -328.340065) (xy 353.01936 -328.332084)
			(xy 353.005136 -328.32675) (xy 352.975926 -328.332846) (xy 352.709988 -328.598784) (xy 352.69195 -328.61605)
			(xy 352.650458 -328.643818) (xy 352.60434 -328.662942) (xy 352.555373 -328.672683) (xy 352.53041 -328.673206)
			(xy 346.977208 -328.673206) (xy 346.950284 -328.693018) (xy 346.945458 -328.709274) (xy 346.93714 -328.735017)
			(xy 346.914252 -328.784036) (xy 346.884669 -328.829331) (xy 346.848985 -328.869993) (xy 346.807915 -328.905207)
			(xy 346.762283 -328.934266) (xy 346.713004 -328.956589) (xy 346.661065 -328.971727) (xy 346.60751 -328.979377)
			(xy 346.58046 -328.979784) (xy 346.553211 -328.979295) (xy 346.499269 -328.971534) (xy 346.446981 -328.956175)
			(xy 346.39741 -328.933531) (xy 346.351566 -328.904063) (xy 346.310383 -328.868372) (xy 346.274698 -328.827182)
			(xy 346.245238 -328.781334) (xy 346.222603 -328.731759) (xy 346.207253 -328.679468) (xy 346.1995 -328.625525)
			(xy 346.198952 -328.598276) (xy 346.199493 -328.569919) (xy 346.207928 -328.513833) (xy 346.224563 -328.459612)
			(xy 346.249033 -328.408447) (xy 346.264484 -328.384662) (xy 346.270588 -328.374553) (xy 346.27372 -328.351175)
			(xy 346.266113 -328.328849) (xy 346.258134 -328.320146) (xy 344.156792 -326.218804) (xy 344.149393 -326.211959)
			(xy 344.130795 -326.204226) (xy 344.120724 -326.203818) (xy 322.5292 -326.203818) (xy 322.51913 -326.204242)
			(xy 322.500527 -326.211958) (xy 322.493132 -326.218804) (xy 318.89954 -329.812396) (xy 318.8815 -329.829657)
			(xy 318.840007 -329.857417) (xy 318.793888 -329.876531) (xy 318.744924 -329.886262) (xy 318.719962 -329.886818)
			(xy 313.0042 -329.886818) (xy 312.99413 -329.887242) (xy 312.975527 -329.894958) (xy 312.968132 -329.901804)
			(xy 312.384948 -330.484988) (xy 312.378095 -330.492384) (xy 312.370348 -330.510982) (xy 312.369962 -330.521056)
			(xy 312.369962 -334.994758) (xy 312.369385 -335.019716) (xy 312.359635 -335.068671) (xy 312.340522 -335.114782)
			(xy 312.312779 -335.156279) (xy 312.29554 -335.174336) (xy 311.80278 -335.667096) (xy 311.784741 -335.68436)
			(xy 311.743249 -335.712127) (xy 311.697131 -335.731248) (xy 311.648165 -335.740987) (xy 311.623202 -335.741518)
			(xy 306.512722 -335.741518) (xy 306.486052 -335.760822) (xy 306.480972 -335.77657) (xy 306.47233 -335.8018)
			(xy 306.448986 -335.849749) (xy 306.41919 -335.893979) (xy 306.383524 -335.933628) (xy 306.342684 -335.967922)
			(xy 306.297464 -335.996193) (xy 306.248747 -336.01789) (xy 306.197483 -336.032589) (xy 306.144671 -336.040005)
			(xy 306.118006 -336.040476) (xy 306.090636 -336.040005) (xy 306.036458 -336.032181) (xy 305.983954 -336.016694)
			(xy 305.934203 -335.993861) (xy 305.888227 -335.964152) (xy 305.867308 -335.946496) (xy 305.860196 -335.9404)
			(xy 305.843178 -335.93405) (xy 305.757834 -335.93405) (xy 305.740816 -335.9404) (xy 305.733704 -335.946496)
			(xy 305.712773 -335.964138) (xy 305.666807 -335.993865) (xy 305.61706 -336.016709) (xy 305.564556 -336.0322)
			(xy 305.510377 -336.040019) (xy 305.483006 -336.040476) (xy 305.45634 -336.040032) (xy 305.403529 -336.032607)
			(xy 305.352265 -336.0179) (xy 305.303549 -335.996198) (xy 305.25833 -335.967924) (xy 305.217488 -335.933629)
			(xy 305.18182 -335.893981) (xy 305.15202 -335.849752) (xy 305.128669 -335.801805) (xy 305.12004 -335.77657)
			(xy 305.11496 -335.760822) (xy 305.08829 -335.741518) (xy 304.248312 -335.741518) (xy 304.221388 -335.761838)
			(xy 304.216562 -335.778348) (xy 304.208571 -335.804562) (xy 304.186116 -335.854552) (xy 304.156741 -335.900815)
			(xy 304.12105 -335.9424) (xy 304.079776 -335.978452) (xy 304.03377 -336.008228) (xy 303.983978 -336.031117)
			(xy 303.931423 -336.046647) (xy 303.877187 -336.054499) (xy 303.849786 -336.054954) (xy 303.821048 -336.054432)
			(xy 303.764222 -336.045807) (xy 303.709333 -336.028753) (xy 303.657624 -336.003658) (xy 303.610265 -335.971089)
			(xy 303.588928 -335.95183) (xy 303.581816 -335.945226) (xy 303.56429 -335.938114) (xy 303.474882 -335.938114)
			(xy 303.457356 -335.945226) (xy 303.450244 -335.95183) (xy 303.428916 -335.971098) (xy 303.381552 -336.003657)
			(xy 303.329839 -336.028743) (xy 303.27495 -336.045788) (xy 303.218124 -336.054407) (xy 303.189386 -336.054954)
			(xy 303.161986 -336.054479) (xy 303.10775 -336.046635) (xy 303.055195 -336.031111) (xy 303.005402 -336.008226)
			(xy 302.959397 -335.978451) (xy 302.918126 -335.942399) (xy 302.882438 -335.900813) (xy 302.853069 -335.854547)
			(xy 302.830623 -335.804555) (xy 302.82261 -335.778348) (xy 302.817784 -335.761838) (xy 302.79086 -335.741518)
			(xy 271.536668 -335.741518) (xy 271.526601 -335.741947) (xy 271.508006 -335.749672) (xy 271.5006 -335.756504)
			(xy 271.363948 -335.893156) (xy 271.357105 -335.900555) (xy 271.349384 -335.919154) (xy 271.348962 -335.929224)
			(xy 271.348962 -336.9836) (xy 318.155561 -336.9836) (xy 318.15955 -336.899842) (xy 318.171484 -336.816843)
			(xy 318.191253 -336.735354) (xy 318.218678 -336.656114) (xy 318.253512 -336.579839) (xy 318.295438 -336.50722)
			(xy 318.344078 -336.438916) (xy 318.398989 -336.375544) (xy 318.459676 -336.317679) (xy 318.525589 -336.265845)
			(xy 318.59613 -336.220511) (xy 318.670661 -336.182087) (xy 318.748507 -336.150922) (xy 318.828963 -336.127298)
			(xy 318.911301 -336.111429) (xy 318.994774 -336.103459) (xy 319.0367 -336.10296) (xy 319.073884 -336.103325)
			(xy 319.147992 -336.109548) (xy 319.221312 -336.121992) (xy 319.293323 -336.140567) (xy 319.328546 -336.15249)
			(xy 319.336742 -336.155013) (xy 319.353878 -336.155013) (xy 319.362074 -336.15249) (xy 319.406878 -336.137448)
			(xy 319.498905 -336.115902) (xy 319.592708 -336.104321) (xy 319.63995 -336.10296) (xy 319.651488 -336.102265)
			(xy 319.672113 -336.091876) (xy 319.686133 -336.073526) (xy 319.688972 -336.06232) (xy 319.698432 -336.018429)
			(xy 319.725027 -335.932667) (xy 319.742058 -335.891124) (xy 319.745615 -335.881531) (xy 319.745619 -335.861091)
			(xy 319.742058 -335.8515) (xy 319.72505 -335.810089) (xy 319.698496 -335.72459) (xy 319.68066 -335.636857)
			(xy 319.671721 -335.547776) (xy 319.671192 -335.503012) (xy 319.671696 -335.460664) (xy 319.679747 -335.37635)
			(xy 319.695776 -335.293184) (xy 319.719637 -335.211917) (xy 319.751116 -335.133287) (xy 319.789927 -335.058006)
			(xy 319.835717 -334.986754) (xy 319.888073 -334.920178) (xy 319.946521 -334.85888) (xy 320.010531 -334.803415)
			(xy 320.079523 -334.754286) (xy 320.152873 -334.711937) (xy 320.229916 -334.676753) (xy 320.309955 -334.649051)
			(xy 320.392264 -334.629083) (xy 320.476099 -334.61703) (xy 320.5607 -334.613) (xy 320.645301 -334.61703)
			(xy 320.729136 -334.629083) (xy 320.811445 -334.649051) (xy 320.891484 -334.676753) (xy 320.968527 -334.711937)
			(xy 321.041877 -334.754286) (xy 321.110869 -334.803415) (xy 321.174879 -334.85888) (xy 321.233327 -334.920178)
			(xy 321.285683 -334.986754) (xy 321.331473 -335.058006) (xy 321.370284 -335.133287) (xy 321.401763 -335.211917)
			(xy 321.425624 -335.293184) (xy 321.441653 -335.37635) (xy 321.449704 -335.460664) (xy 321.450208 -335.503012)
			(xy 321.449678 -335.547776) (xy 321.440749 -335.636858) (xy 321.42291 -335.724591) (xy 321.396343 -335.810086)
			(xy 321.379342 -335.8515) (xy 321.375771 -335.861089) (xy 321.375776 -335.881533) (xy 321.379342 -335.891124)
			(xy 321.395061 -335.929255) (xy 321.42019 -336.007817) (xy 321.437947 -336.088366) (xy 321.448179 -336.170212)
			(xy 321.449954 -336.211418) (xy 321.450208 -336.22488) (xy 321.464432 -336.247994) (xy 321.564762 -336.303112)
			(xy 321.591686 -336.302604) (xy 321.603116 -336.295746) (xy 321.637462 -336.275884) (xy 321.709064 -336.241691)
			(xy 321.783427 -336.214009) (xy 321.859958 -336.193059) (xy 321.938052 -336.179007) (xy 322.017086 -336.171964)
			(xy 322.05676 -336.17154) (xy 322.097864 -336.17199) (xy 322.179721 -336.179572) (xy 322.26053 -336.194675)
			(xy 322.3396 -336.21717) (xy 322.416257 -336.246866) (xy 322.489847 -336.283508) (xy 322.559742 -336.326784)
			(xy 322.625346 -336.376325) (xy 322.686098 -336.431708) (xy 322.74148 -336.492461) (xy 322.791021 -336.558064)
			(xy 322.834296 -336.62796) (xy 322.870938 -336.70155) (xy 322.900632 -336.778207) (xy 322.923127 -336.857278)
			(xy 322.938229 -336.938087) (xy 322.941787 -336.9765) (xy 326.511148 -336.9765) (xy 326.515138 -336.892742)
			(xy 326.527072 -336.809743) (xy 326.546841 -336.728254) (xy 326.574266 -336.649013) (xy 326.609099 -336.572737)
			(xy 326.651025 -336.500118) (xy 326.699664 -336.431814) (xy 326.754575 -336.368441) (xy 326.815262 -336.310576)
			(xy 326.881174 -336.258741) (xy 326.951715 -336.213406) (xy 327.026246 -336.174981) (xy 327.104092 -336.143815)
			(xy 327.184547 -336.12019) (xy 327.266885 -336.104319) (xy 327.350358 -336.096347) (xy 327.392284 -336.095848)
			(xy 327.429468 -336.096219) (xy 327.503576 -336.10244) (xy 327.576896 -336.114882) (xy 327.648907 -336.133456)
			(xy 327.68413 -336.145378) (xy 327.692326 -336.147901) (xy 327.709462 -336.147901) (xy 327.717658 -336.145378)
			(xy 327.763554 -336.130002) (xy 327.857867 -336.108208) (xy 327.953999 -336.096874) (xy 328.002392 -336.095848)
			(xy 328.013767 -336.095113) (xy 328.034196 -336.085063) (xy 328.048298 -336.06719) (xy 328.051414 -336.056224)
			(xy 328.060633 -336.017607) (xy 328.085057 -335.942056) (xy 328.100182 -335.905348) (xy 328.103724 -335.895751)
			(xy 328.103738 -335.875315) (xy 328.100182 -335.865724) (xy 328.083183 -335.82431) (xy 328.056627 -335.738812)
			(xy 328.038788 -335.65108) (xy 328.029846 -335.562) (xy 328.029316 -335.517236) (xy 328.02982 -335.474888)
			(xy 328.037871 -335.390574) (xy 328.0539 -335.307408) (xy 328.077761 -335.226141) (xy 328.10924 -335.147511)
			(xy 328.148051 -335.07223) (xy 328.193841 -335.000978) (xy 328.246197 -334.934402) (xy 328.304645 -334.873104)
			(xy 328.368655 -334.817639) (xy 328.437647 -334.76851) (xy 328.510997 -334.726161) (xy 328.58804 -334.690977)
			(xy 328.668079 -334.663275) (xy 328.750388 -334.643307) (xy 328.834223 -334.631254) (xy 328.918824 -334.627224)
			(xy 329.003425 -334.631254) (xy 329.08726 -334.643307) (xy 329.169569 -334.663275) (xy 329.249608 -334.690977)
			(xy 329.326651 -334.726161) (xy 329.400001 -334.76851) (xy 329.468993 -334.817639) (xy 329.533003 -334.873104)
			(xy 329.591451 -334.934402) (xy 329.643807 -335.000978) (xy 329.689597 -335.07223) (xy 329.728408 -335.147511)
			(xy 329.759887 -335.226141) (xy 329.783748 -335.307408) (xy 329.799777 -335.390574) (xy 329.807828 -335.474888)
			(xy 329.808332 -335.517236) (xy 329.807817 -335.562001) (xy 329.798884 -335.651083) (xy 329.781041 -335.738816)
			(xy 329.75447 -335.824311) (xy 329.737466 -335.865724) (xy 329.733881 -335.875309) (xy 329.733894 -335.895757)
			(xy 329.737466 -335.905348) (xy 329.752245 -335.941179) (xy 329.776235 -336.014886) (xy 329.793723 -336.090401)
			(xy 329.804575 -336.167151) (xy 329.807062 -336.20583) (xy 329.807824 -336.219038) (xy 329.822048 -336.24139)
			(xy 329.922124 -336.294984) (xy 329.948794 -336.294476) (xy 329.960224 -336.287872) (xy 329.994483 -336.268147)
			(xy 330.065868 -336.23417) (xy 330.139986 -336.206662) (xy 330.216254 -336.18584) (xy 330.294068 -336.171868)
			(xy 330.372815 -336.164856) (xy 330.412344 -336.164428) (xy 330.453448 -336.164825) (xy 330.535306 -336.172414)
			(xy 330.616114 -336.187524) (xy 330.695183 -336.210025) (xy 330.771839 -336.239726) (xy 330.845427 -336.276373)
			(xy 330.91532 -336.319653) (xy 330.980922 -336.369198) (xy 331.041672 -336.424584) (xy 331.097053 -336.48534)
			(xy 331.146592 -336.550946) (xy 331.189866 -336.620843) (xy 331.226507 -336.694434) (xy 331.256201 -336.771093)
			(xy 331.278695 -336.850164) (xy 331.293797 -336.930973) (xy 331.296671 -336.962) (xy 334.868517 -336.962)
			(xy 334.872507 -336.878219) (xy 334.884444 -336.795197) (xy 334.904219 -336.713686) (xy 334.931652 -336.634423)
			(xy 334.966495 -336.558127) (xy 335.008433 -336.485488) (xy 335.057086 -336.417165) (xy 335.112013 -336.353776)
			(xy 335.172717 -336.295895) (xy 335.238647 -336.244046) (xy 335.309208 -336.198699) (xy 335.38376 -336.160265)
			(xy 335.461628 -336.129092) (xy 335.542106 -336.105461) (xy 335.624466 -336.089588) (xy 335.707962 -336.081615)
			(xy 335.7499 -336.081116) (xy 335.78709 -336.081504) (xy 335.861203 -336.087794) (xy 335.934522 -336.100304)
			(xy 336.006528 -336.118945) (xy 336.041746 -336.1309) (xy 336.049942 -336.133423) (xy 336.067078 -336.133423)
			(xy 336.075274 -336.1309) (xy 336.110496 -336.118972) (xy 336.182504 -336.10038) (xy 336.255825 -336.087935)
			(xy 336.329935 -336.081725) (xy 336.36712 -336.08137) (xy 336.378455 -336.080768) (xy 336.398918 -336.071018)
			(xy 336.413169 -336.05339) (xy 336.416396 -336.042508) (xy 336.425304 -336.007451) (xy 336.448069 -335.938786)
			(xy 336.461862 -335.905348) (xy 336.465405 -335.895751) (xy 336.465418 -335.875315) (xy 336.461862 -335.865724)
			(xy 336.444862 -335.82431) (xy 336.418306 -335.738812) (xy 336.400467 -335.65108) (xy 336.391526 -335.562)
			(xy 336.390996 -335.517236) (xy 336.3915 -335.474888) (xy 336.399551 -335.390574) (xy 336.41558 -335.307408)
			(xy 336.439441 -335.226141) (xy 336.47092 -335.147511) (xy 336.509731 -335.07223) (xy 336.555521 -335.000978)
			(xy 336.607877 -334.934402) (xy 336.666325 -334.873104) (xy 336.730335 -334.817639) (xy 336.799327 -334.76851)
			(xy 336.872677 -334.726161) (xy 336.94972 -334.690977) (xy 337.029759 -334.663275) (xy 337.112068 -334.643307)
			(xy 337.195903 -334.631254) (xy 337.280504 -334.627224) (xy 337.365105 -334.631254) (xy 337.44894 -334.643307)
			(xy 337.531249 -334.663275) (xy 337.611288 -334.690977) (xy 337.688331 -334.726161) (xy 337.761681 -334.76851)
			(xy 337.830673 -334.817639) (xy 337.894683 -334.873104) (xy 337.953131 -334.934402) (xy 338.005487 -335.000978)
			(xy 338.051277 -335.07223) (xy 338.090088 -335.147511) (xy 338.121567 -335.226141) (xy 338.145428 -335.307408)
			(xy 338.161457 -335.390574) (xy 338.169508 -335.474888) (xy 338.170012 -335.517236) (xy 338.169491 -335.562001)
			(xy 338.160559 -335.651083) (xy 338.142718 -335.738815) (xy 338.116149 -335.824311) (xy 338.099146 -335.865724)
			(xy 338.095561 -335.875309) (xy 338.095575 -335.895757) (xy 338.099146 -335.905348) (xy 338.117792 -335.95091)
			(xy 338.146101 -336.045203) (xy 338.163844 -336.142042) (xy 338.16798 -336.191098) (xy 338.168742 -336.204306)
			(xy 338.18322 -336.226404) (xy 338.283042 -336.278982) (xy 338.309204 -336.278474) (xy 338.320634 -336.271616)
			(xy 338.354723 -336.252133) (xy 338.425722 -336.218592) (xy 338.499399 -336.191437) (xy 338.575183 -336.170878)
			(xy 338.652483 -336.157075) (xy 338.730699 -336.150137) (xy 338.76996 -336.149696) (xy 338.81107 -336.150191)
			(xy 338.89294 -336.157775) (xy 338.97376 -336.172882) (xy 339.052841 -336.195384) (xy 339.129508 -336.225088)
			(xy 339.203107 -336.261741) (xy 339.273008 -336.305029) (xy 339.338617 -336.354584) (xy 339.399372 -336.409982)
			(xy 339.454755 -336.470751) (xy 339.504294 -336.536372) (xy 339.547565 -336.606284) (xy 339.5842 -336.679891)
			(xy 339.613885 -336.756566) (xy 339.636368 -336.835652) (xy 339.651455 -336.916476) (xy 339.659019 -336.998348)
			(xy 339.659177 -337.0128) (xy 343.199717 -337.0128) (xy 343.203707 -336.929019) (xy 343.215644 -336.845997)
			(xy 343.235419 -336.764486) (xy 343.262852 -336.685223) (xy 343.297695 -336.608927) (xy 343.339633 -336.536288)
			(xy 343.388286 -336.467965) (xy 343.443213 -336.404576) (xy 343.503917 -336.346695) (xy 343.569847 -336.294846)
			(xy 343.640408 -336.249499) (xy 343.71496 -336.211065) (xy 343.792828 -336.179892) (xy 343.873306 -336.156261)
			(xy 343.955666 -336.140388) (xy 344.039162 -336.132415) (xy 344.0811 -336.131916) (xy 344.11829 -336.132304)
			(xy 344.192403 -336.138594) (xy 344.265722 -336.151104) (xy 344.337728 -336.169745) (xy 344.372946 -336.1817)
			(xy 344.381142 -336.184223) (xy 344.398278 -336.184223) (xy 344.406474 -336.1817) (xy 344.441687 -336.169727)
			(xy 344.513691 -336.151076) (xy 344.587013 -336.13857) (xy 344.661129 -336.1323) (xy 344.69832 -336.131916)
			(xy 344.712798 -336.13217) (xy 344.724169 -336.131792) (xy 344.744841 -336.122355) (xy 344.759419 -336.104924)
			(xy 344.762836 -336.09407) (xy 344.771394 -336.062107) (xy 344.792623 -335.999431) (xy 344.805254 -335.968848)
			(xy 344.808797 -335.959251) (xy 344.808811 -335.938814) (xy 344.805254 -335.929224) (xy 344.788254 -335.887811)
			(xy 344.761698 -335.802312) (xy 344.743859 -335.71458) (xy 344.734918 -335.6255) (xy 344.734388 -335.580736)
			(xy 344.734892 -335.538388) (xy 344.742943 -335.454074) (xy 344.758972 -335.370908) (xy 344.782833 -335.289641)
			(xy 344.814312 -335.211011) (xy 344.853123 -335.13573) (xy 344.898913 -335.064478) (xy 344.951269 -334.997902)
			(xy 345.009717 -334.936604) (xy 345.073727 -334.881139) (xy 345.142719 -334.83201) (xy 345.216069 -334.789661)
			(xy 345.293112 -334.754477) (xy 345.373151 -334.726775) (xy 345.45546 -334.706807) (xy 345.539295 -334.694754)
			(xy 345.623896 -334.690724) (xy 345.708497 -334.694754) (xy 345.792332 -334.706807) (xy 345.874641 -334.726775)
			(xy 345.95468 -334.754477) (xy 346.031723 -334.789661) (xy 346.105073 -334.83201) (xy 346.174065 -334.881139)
			(xy 346.238075 -334.936604) (xy 346.296523 -334.997902) (xy 346.348879 -335.064478) (xy 346.394669 -335.13573)
			(xy 346.43348 -335.211011) (xy 346.464959 -335.289641) (xy 346.48882 -335.370908) (xy 346.504849 -335.454074)
			(xy 346.5129 -335.538388) (xy 346.513404 -335.580736) (xy 346.512883 -335.625501) (xy 346.503951 -335.714582)
			(xy 346.48611 -335.802315) (xy 346.45954 -335.887811) (xy 346.442538 -335.929224) (xy 346.438954 -335.938809)
			(xy 346.438967 -335.959257) (xy 346.442538 -335.968848) (xy 346.459529 -336.010265) (xy 346.486087 -336.095762)
			(xy 346.503929 -336.183493) (xy 346.512872 -336.272572) (xy 346.513404 -336.317336) (xy 346.513182 -336.348682)
			(xy 346.508857 -336.411225) (xy 346.504768 -336.442304) (xy 346.503244 -336.452972) (xy 346.508832 -336.473292)
			(xy 346.569538 -336.547714) (xy 346.58808 -336.557366) (xy 346.598748 -336.558128) (xy 346.640541 -336.561266)
			(xy 346.723318 -336.574429) (xy 346.804489 -336.59532) (xy 346.883336 -336.623754) (xy 346.959158 -336.659479)
			(xy 347.031283 -336.702177) (xy 347.099073 -336.75147) (xy 347.161925 -336.806921) (xy 347.219283 -336.868039)
			(xy 347.270637 -336.93428) (xy 347.315532 -337.005059) (xy 347.353571 -337.079747) (xy 347.384416 -337.157682)
			(xy 347.407793 -337.238172) (xy 347.423495 -337.320505) (xy 347.431383 -337.40395) (xy 347.431868 -337.445858)
			(xy 347.431361 -337.488564) (xy 347.423173 -337.573582) (xy 347.406877 -337.657424) (xy 347.382624 -337.739319)
			(xy 347.367098 -337.779106) (xy 347.363667 -337.789193) (xy 347.364442 -337.810456) (xy 347.368622 -337.820254)
			(xy 347.385657 -337.856566) (xy 347.413925 -337.931633) (xy 347.435319 -338.008941) (xy 347.449664 -338.08786)
			(xy 347.456846 -338.167751) (xy 347.457268 -338.207858) (xy 347.456674 -338.254253) (xy 347.447033 -338.346541)
			(xy 347.42784 -338.437325) (xy 347.399305 -338.525619) (xy 347.381068 -338.568284) (xy 347.377284 -338.578233)
			(xy 347.377268 -338.599491) (xy 347.381068 -338.609432) (xy 347.399296 -338.652101) (xy 347.427845 -338.740391)
			(xy 347.447043 -338.831174) (xy 347.456681 -338.923462) (xy 347.457268 -338.969858) (xy 347.456674 -339.016253)
			(xy 347.447033 -339.108541) (xy 347.42784 -339.199325) (xy 347.399305 -339.287619) (xy 347.381068 -339.330284)
			(xy 347.377284 -339.340233) (xy 347.377268 -339.361491) (xy 347.381068 -339.371432) (xy 347.399296 -339.414101)
			(xy 347.427845 -339.502391) (xy 347.447043 -339.593174) (xy 347.456681 -339.685462) (xy 347.457268 -339.731858)
			(xy 347.456747 -339.772964) (xy 347.449167 -339.854825) (xy 347.434067 -339.935639) (xy 347.411576 -340.014714)
			(xy 347.381885 -340.091377) (xy 347.345249 -340.164975) (xy 347.30198 -340.234878) (xy 347.252446 -340.300492)
			(xy 347.19707 -340.361256) (xy 347.136324 -340.416653) (xy 347.070727 -340.466209) (xy 347.000838 -340.509502)
			(xy 346.927254 -340.546163) (xy 346.8506 -340.575879) (xy 346.771533 -340.598397) (xy 346.690725 -340.613525)
			(xy 346.608866 -340.621133) (xy 346.56776 -340.62162) (xy 346.525159 -340.621134) (xy 346.440349 -340.612975)
			(xy 346.356708 -340.596745) (xy 346.275001 -340.572593) (xy 346.195978 -340.540739) (xy 346.120362 -340.501477)
			(xy 346.048846 -340.455165) (xy 345.982085 -340.402229) (xy 345.920691 -340.343152) (xy 345.865226 -340.278476)
			(xy 345.840304 -340.243922) (xy 345.834716 -340.236562) (xy 345.819472 -340.226142) (xy 345.810586 -340.223602)
			(xy 345.769427 -340.213207) (xy 345.689122 -340.185668) (xy 345.611806 -340.150603) (xy 345.538183 -340.108332)
			(xy 345.468921 -340.05924) (xy 345.40465 -340.003772) (xy 345.345957 -339.942434) (xy 345.293373 -339.875784)
			(xy 345.247379 -339.804427) (xy 345.208391 -339.729013) (xy 345.176765 -339.650228) (xy 345.152789 -339.568788)
			(xy 345.136679 -339.485435) (xy 345.128584 -339.400926) (xy 345.128088 -339.358478) (xy 345.128614 -339.313713)
			(xy 345.137545 -339.224632) (xy 345.155384 -339.136899) (xy 345.181952 -339.051403) (xy 345.198954 -339.00999)
			(xy 345.202531 -339.000403) (xy 345.202523 -338.979957) (xy 345.198954 -338.970366) (xy 345.181967 -338.928947)
			(xy 345.155408 -338.843451) (xy 345.137565 -338.75572) (xy 345.12862 -338.666642) (xy 345.128088 -338.621878)
			(xy 345.128614 -338.577113) (xy 345.137545 -338.488032) (xy 345.155384 -338.400299) (xy 345.181952 -338.314803)
			(xy 345.198954 -338.27339) (xy 345.202531 -338.263803) (xy 345.202523 -338.243357) (xy 345.198954 -338.233766)
			(xy 345.183168 -338.195457) (xy 345.157955 -338.116523) (xy 345.140197 -338.035586) (xy 345.130046 -337.953347)
			(xy 345.128342 -337.911948) (xy 345.12754 -337.901022) (xy 345.117874 -337.881381) (xy 345.100942 -337.867505)
			(xy 345.090496 -337.864196) (xy 345.073624 -337.859698) (xy 345.040213 -337.849535) (xy 345.023694 -337.843876)
			(xy 345.015498 -337.841353) (xy 344.998362 -337.841353) (xy 344.990166 -337.843876) (xy 344.95495 -337.855837)
			(xy 344.882946 -337.874492) (xy 344.809626 -337.887) (xy 344.73551 -337.893274) (xy 344.69832 -337.89366)
			(xy 344.661131 -337.893262) (xy 344.587018 -337.886974) (xy 344.513698 -337.874467) (xy 344.441692 -337.855829)
			(xy 344.406474 -337.843876) (xy 344.398278 -337.841353) (xy 344.381142 -337.841353) (xy 344.372946 -337.843876)
			(xy 344.337731 -337.855842) (xy 344.265728 -337.874496) (xy 344.192406 -337.887003) (xy 344.11829 -337.893275)
			(xy 344.0811 -337.89366) (xy 344.039162 -337.893185) (xy 343.955666 -337.885212) (xy 343.873306 -337.869339)
			(xy 343.792828 -337.845708) (xy 343.71496 -337.814535) (xy 343.640408 -337.776101) (xy 343.569847 -337.730754)
			(xy 343.503917 -337.678905) (xy 343.443213 -337.621024) (xy 343.388286 -337.557635) (xy 343.339633 -337.489312)
			(xy 343.297695 -337.416673) (xy 343.262852 -337.340377) (xy 343.235419 -337.261114) (xy 343.215644 -337.179603)
			(xy 343.203707 -337.096581) (xy 343.199717 -337.0128) (xy 339.659177 -337.0128) (xy 339.659468 -337.039458)
			(xy 339.658957 -337.084223) (xy 339.650022 -337.173305) (xy 339.632178 -337.261038) (xy 339.605606 -337.346533)
			(xy 339.588602 -337.387946) (xy 339.585059 -337.397543) (xy 339.585044 -337.41798) (xy 339.588602 -337.42757)
			(xy 339.605598 -337.468985) (xy 339.632155 -337.554483) (xy 339.649995 -337.642215) (xy 339.658937 -337.731294)
			(xy 339.659468 -337.776058) (xy 339.658957 -337.820823) (xy 339.650022 -337.909905) (xy 339.632178 -337.997638)
			(xy 339.605606 -338.083133) (xy 339.588602 -338.124546) (xy 339.585059 -338.134143) (xy 339.585044 -338.15458)
			(xy 339.588602 -338.16417) (xy 339.605598 -338.205585) (xy 339.632155 -338.291083) (xy 339.649995 -338.378815)
			(xy 339.658937 -338.467894) (xy 339.659468 -338.512658) (xy 339.658947 -338.553764) (xy 339.651367 -338.635625)
			(xy 339.636267 -338.716439) (xy 339.613776 -338.795514) (xy 339.584085 -338.872177) (xy 339.547449 -338.945775)
			(xy 339.50418 -339.015678) (xy 339.454646 -339.081292) (xy 339.39927 -339.142056) (xy 339.338524 -339.197453)
			(xy 339.272927 -339.247009) (xy 339.203038 -339.290302) (xy 339.129454 -339.326963) (xy 339.0528 -339.356679)
			(xy 338.973733 -339.379197) (xy 338.892925 -339.394325) (xy 338.811066 -339.401933) (xy 338.76996 -339.40242)
			(xy 338.728345 -339.401907) (xy 338.645481 -339.394089) (xy 338.563708 -339.378573) (xy 338.483741 -339.355493)
			(xy 338.406276 -339.325051) (xy 338.33199 -339.287513) (xy 338.296504 -339.265768) (xy 338.287397 -339.260652)
			(xy 338.266748 -339.257605) (xy 338.246582 -339.262991) (xy 338.238084 -339.26907) (xy 338.204417 -339.295039)
			(xy 338.132992 -339.341179) (xy 338.057489 -339.380291) (xy 337.978598 -339.412018) (xy 337.897038 -339.436071)
			(xy 337.813556 -339.452228) (xy 337.728912 -339.460344) (xy 337.686396 -339.46084) (xy 337.645286 -339.460351)
			(xy 337.563418 -339.452764) (xy 337.482599 -339.437653) (xy 337.403519 -339.415149) (xy 337.326853 -339.385443)
			(xy 337.253256 -339.348789) (xy 337.183356 -339.3055) (xy 337.117748 -339.255944) (xy 337.056994 -339.200546)
			(xy 337.001611 -339.139778) (xy 336.952073 -339.074158) (xy 336.908801 -339.004246) (xy 336.872166 -338.93064)
			(xy 336.842479 -338.853967) (xy 336.819995 -338.774881) (xy 336.804905 -338.694058) (xy 336.797338 -338.612188)
			(xy 336.796888 -338.571078) (xy 336.797414 -338.526313) (xy 336.806345 -338.437232) (xy 336.824184 -338.349499)
			(xy 336.850752 -338.264003) (xy 336.867754 -338.22259) (xy 336.871331 -338.213003) (xy 336.871323 -338.192557)
			(xy 336.867754 -338.182966) (xy 336.851968 -338.144657) (xy 336.826755 -338.065723) (xy 336.808997 -337.984786)
			(xy 336.798846 -337.902547) (xy 336.797142 -337.861148) (xy 336.79634 -337.850222) (xy 336.786674 -337.830581)
			(xy 336.769742 -337.816705) (xy 336.759296 -337.813396) (xy 336.742424 -337.808898) (xy 336.709013 -337.798735)
			(xy 336.692494 -337.793076) (xy 336.684298 -337.790553) (xy 336.667162 -337.790553) (xy 336.658966 -337.793076)
			(xy 336.62375 -337.805037) (xy 336.551746 -337.823692) (xy 336.478426 -337.8362) (xy 336.40431 -337.842474)
			(xy 336.36712 -337.84286) (xy 336.329931 -337.842462) (xy 336.255818 -337.836174) (xy 336.182498 -337.823667)
			(xy 336.110492 -337.805029) (xy 336.075274 -337.793076) (xy 336.067078 -337.790553) (xy 336.049942 -337.790553)
			(xy 336.041746 -337.793076) (xy 336.006531 -337.805042) (xy 335.934528 -337.823696) (xy 335.861206 -337.836203)
			(xy 335.78709 -337.842475) (xy 335.7499 -337.84286) (xy 335.707962 -337.842385) (xy 335.624466 -337.834412)
			(xy 335.542106 -337.818539) (xy 335.461628 -337.794908) (xy 335.38376 -337.763735) (xy 335.309208 -337.725301)
			(xy 335.238647 -337.679954) (xy 335.172717 -337.628105) (xy 335.112013 -337.570224) (xy 335.057086 -337.506835)
			(xy 335.008433 -337.438512) (xy 334.966495 -337.365873) (xy 334.931652 -337.289577) (xy 334.904219 -337.210314)
			(xy 334.884444 -337.128803) (xy 334.872507 -337.045781) (xy 334.868517 -336.962) (xy 331.296671 -336.962)
			(xy 331.301379 -337.012832) (xy 331.301852 -337.053936) (xy 331.301335 -337.098701) (xy 331.292402 -337.187783)
			(xy 331.27456 -337.275516) (xy 331.247989 -337.361011) (xy 331.230986 -337.402424) (xy 331.227399 -337.412008)
			(xy 331.227413 -337.432457) (xy 331.230986 -337.442048) (xy 331.247974 -337.483466) (xy 331.274534 -337.568963)
			(xy 331.292376 -337.656694) (xy 331.30132 -337.745772) (xy 331.301852 -337.790536) (xy 331.301335 -337.835301)
			(xy 331.292402 -337.924383) (xy 331.27456 -338.012116) (xy 331.247989 -338.097611) (xy 331.230986 -338.139024)
			(xy 331.227399 -338.148608) (xy 331.227413 -338.169057) (xy 331.230986 -338.178648) (xy 331.247974 -338.220066)
			(xy 331.274534 -338.305563) (xy 331.292376 -338.393294) (xy 331.30132 -338.482372) (xy 331.301852 -338.527136)
			(xy 331.301368 -338.568238) (xy 331.29378 -338.65009) (xy 331.278673 -338.730894) (xy 331.256175 -338.809959)
			(xy 331.226478 -338.886611) (xy 331.189836 -338.960196) (xy 331.14656 -339.030087) (xy 331.097021 -339.095686)
			(xy 331.041641 -339.156436) (xy 330.980892 -339.211816) (xy 330.915293 -339.261356) (xy 330.845403 -339.304632)
			(xy 330.771818 -339.341275) (xy 330.695167 -339.370972) (xy 330.616102 -339.393471) (xy 330.535298 -339.408579)
			(xy 330.453446 -339.416167) (xy 330.412344 -339.416644) (xy 330.370732 -339.416171) (xy 330.28787 -339.408423)
			(xy 330.206095 -339.392962) (xy 330.126124 -339.369924) (xy 330.048657 -339.33951) (xy 329.974372 -339.301987)
			(xy 329.938888 -339.280246) (xy 329.929745 -339.275207) (xy 329.90912 -339.272136) (xy 329.888967 -339.277488)
			(xy 329.880468 -339.283548) (xy 329.846805 -339.309512) (xy 329.775363 -339.355602) (xy 329.699851 -339.394667)
			(xy 329.620956 -339.426351) (xy 329.539399 -339.450365) (xy 329.455923 -339.46649) (xy 329.37129 -339.474579)
			(xy 329.32878 -339.475064) (xy 329.287675 -339.474667) (xy 329.205817 -339.46708) (xy 329.125007 -339.451972)
			(xy 329.045936 -339.429472) (xy 328.969279 -339.399772) (xy 328.895689 -339.363126) (xy 328.825795 -339.319846)
			(xy 328.760192 -339.270301) (xy 328.69944 -339.214915) (xy 328.644058 -339.154159) (xy 328.594518 -339.088553)
			(xy 328.551243 -339.018655) (xy 328.514602 -338.945062) (xy 328.484908 -338.868403) (xy 328.462414 -338.789331)
			(xy 328.447312 -338.70852) (xy 328.43973 -338.626661) (xy 328.439272 -338.585556) (xy 328.439784 -338.540791)
			(xy 328.448718 -338.451709) (xy 328.466562 -338.363976) (xy 328.493134 -338.278481) (xy 328.510138 -338.237068)
			(xy 328.513728 -338.227485) (xy 328.513711 -338.207035) (xy 328.510138 -338.197444) (xy 328.494344 -338.159138)
			(xy 328.469134 -338.080203) (xy 328.451378 -337.999265) (xy 328.441229 -337.917025) (xy 328.439526 -337.875626)
			(xy 328.438678 -337.864706) (xy 328.429036 -337.845063) (xy 328.41212 -337.831185) (xy 328.40168 -337.827874)
			(xy 328.384807 -337.823378) (xy 328.351397 -337.813214) (xy 328.334878 -337.807554) (xy 328.326682 -337.805031)
			(xy 328.309546 -337.805031) (xy 328.30135 -337.807554) (xy 328.266125 -337.819474) (xy 328.194118 -337.838068)
			(xy 328.120798 -337.850516) (xy 328.046689 -337.856728) (xy 328.009504 -337.857084) (xy 327.97232 -337.856715)
			(xy 327.898212 -337.850493) (xy 327.824892 -337.838051) (xy 327.752881 -337.819476) (xy 327.717658 -337.807554)
			(xy 327.709462 -337.805031) (xy 327.692326 -337.805031) (xy 327.68413 -337.807554) (xy 327.648907 -337.819479)
			(xy 327.576899 -337.838072) (xy 327.503579 -337.850518) (xy 327.429469 -337.856729) (xy 327.392284 -337.857084)
			(xy 327.350358 -337.856653) (xy 327.266885 -337.848681) (xy 327.184547 -337.83281) (xy 327.104092 -337.809185)
			(xy 327.026246 -337.778019) (xy 326.951715 -337.739594) (xy 326.881174 -337.694259) (xy 326.815262 -337.642424)
			(xy 326.754575 -337.584559) (xy 326.699664 -337.521186) (xy 326.651025 -337.452882) (xy 326.609099 -337.380263)
			(xy 326.574266 -337.303987) (xy 326.546841 -337.224746) (xy 326.527072 -337.143257) (xy 326.515138 -337.060258)
			(xy 326.511148 -336.9765) (xy 322.941787 -336.9765) (xy 322.94581 -337.019944) (xy 322.946268 -337.061048)
			(xy 322.945754 -337.105813) (xy 322.93682 -337.194895) (xy 322.918977 -337.282628) (xy 322.892406 -337.368123)
			(xy 322.875402 -337.409536) (xy 322.871808 -337.419118) (xy 322.871825 -337.439569) (xy 322.875402 -337.44916)
			(xy 322.892395 -337.490576) (xy 322.918953 -337.576074) (xy 322.936794 -337.663805) (xy 322.945737 -337.752884)
			(xy 322.946268 -337.797648) (xy 322.945754 -337.842413) (xy 322.93682 -337.931495) (xy 322.918977 -338.019228)
			(xy 322.892406 -338.104723) (xy 322.875402 -338.146136) (xy 322.871808 -338.155718) (xy 322.871825 -338.176169)
			(xy 322.875402 -338.18576) (xy 322.892395 -338.227176) (xy 322.918953 -338.312674) (xy 322.936794 -338.400405)
			(xy 322.945737 -338.489484) (xy 322.946268 -338.534248) (xy 322.945879 -338.575352) (xy 322.938289 -338.65721)
			(xy 322.923179 -338.738019) (xy 322.900678 -338.817088) (xy 322.870976 -338.893744) (xy 322.834329 -338.967333)
			(xy 322.791048 -339.037226) (xy 322.741503 -339.102828) (xy 322.686116 -339.163578) (xy 322.62536 -339.218959)
			(xy 322.559753 -339.268498) (xy 322.489856 -339.311772) (xy 322.416264 -339.348412) (xy 322.339605 -339.378106)
			(xy 322.260533 -339.400599) (xy 322.179723 -339.415702) (xy 322.097864 -339.423283) (xy 322.05676 -339.423756)
			(xy 322.015148 -339.423274) (xy 321.932286 -339.415527) (xy 321.850512 -339.400068) (xy 321.770541 -339.377031)
			(xy 321.693073 -339.346619) (xy 321.618788 -339.309098) (xy 321.583304 -339.287358) (xy 321.574197 -339.282243)
			(xy 321.553548 -339.279197) (xy 321.533382 -339.284582) (xy 321.524884 -339.29066) (xy 321.491217 -339.316618)
			(xy 321.419776 -339.362709) (xy 321.344264 -339.401774) (xy 321.26537 -339.433459) (xy 321.183814 -339.457474)
			(xy 321.100338 -339.4736) (xy 321.015705 -339.48169) (xy 320.973196 -339.482176) (xy 320.932092 -339.481752)
			(xy 320.850234 -339.474166) (xy 320.769426 -339.459059) (xy 320.690356 -339.436561) (xy 320.613699 -339.406863)
			(xy 320.54011 -339.370219) (xy 320.470216 -339.326941) (xy 320.404613 -339.277398) (xy 320.343861 -339.222013)
			(xy 320.288479 -339.161259) (xy 320.238939 -339.095655) (xy 320.195664 -339.025759) (xy 320.159022 -338.952168)
			(xy 320.129327 -338.87551) (xy 320.106832 -338.796439) (xy 320.091729 -338.71563) (xy 320.084147 -338.633772)
			(xy 320.083688 -338.592668) (xy 320.084211 -338.547903) (xy 320.093142 -338.458822) (xy 320.110983 -338.371089)
			(xy 320.137551 -338.285593) (xy 320.154554 -338.24418) (xy 320.158136 -338.234595) (xy 320.158125 -338.214147)
			(xy 320.154554 -338.204556) (xy 320.138765 -338.166248) (xy 320.113553 -338.087314) (xy 320.095796 -338.006376)
			(xy 320.085645 -337.924137) (xy 320.083942 -337.882738) (xy 320.083148 -337.871811) (xy 320.073477 -337.85217)
			(xy 320.056543 -337.838295) (xy 320.046096 -337.834986) (xy 320.029224 -337.830489) (xy 319.995813 -337.820325)
			(xy 319.979294 -337.814666) (xy 319.971098 -337.812143) (xy 319.953962 -337.812143) (xy 319.945766 -337.814666)
			(xy 319.910549 -337.82661) (xy 319.838539 -337.845197) (xy 319.765217 -337.857638) (xy 319.691106 -337.863844)
			(xy 319.65392 -337.864196) (xy 319.616736 -337.863827) (xy 319.542628 -337.857606) (xy 319.469308 -337.845164)
			(xy 319.397297 -337.826589) (xy 319.362074 -337.814666) (xy 319.353878 -337.812143) (xy 319.336742 -337.812143)
			(xy 319.328546 -337.814666) (xy 319.293322 -337.826587) (xy 319.221314 -337.845181) (xy 319.147994 -337.857628)
			(xy 319.073885 -337.86384) (xy 319.0367 -337.864196) (xy 318.994774 -337.863741) (xy 318.911301 -337.855771)
			(xy 318.828963 -337.839902) (xy 318.748507 -337.816278) (xy 318.670661 -337.785113) (xy 318.59613 -337.746689)
			(xy 318.525589 -337.701355) (xy 318.459676 -337.649521) (xy 318.398989 -337.591656) (xy 318.344078 -337.528284)
			(xy 318.295438 -337.45998) (xy 318.253512 -337.387361) (xy 318.218678 -337.311086) (xy 318.191253 -337.231846)
			(xy 318.171484 -337.150357) (xy 318.15955 -337.067358) (xy 318.155561 -336.9836) (xy 271.348962 -336.9836)
			(xy 271.348962 -339.385656) (xy 271.36725 -339.411564) (xy 271.382744 -339.417152) (xy 271.408507 -339.426901)
			(xy 271.457146 -339.452751) (xy 271.501563 -339.485328) (xy 271.540833 -339.523953) (xy 271.574141 -339.567825)
			(xy 271.600793 -339.61603) (xy 271.620236 -339.667566) (xy 271.632066 -339.721364) (xy 271.636037 -339.776303)
			(xy 271.632065 -339.831242) (xy 271.620235 -339.885039) (xy 271.600791 -339.936575) (xy 271.574138 -339.98478)
			(xy 271.54083 -340.028651) (xy 271.501559 -340.067275) (xy 271.457142 -340.099851) (xy 271.408502 -340.125701)
			(xy 271.382744 -340.135464) (xy 271.36725 -340.141052) (xy 271.348962 -340.16696) (xy 271.348962 -341.9229)
			(xy 351.475729 -341.9229) (xy 351.479719 -341.839138) (xy 351.491654 -341.756134) (xy 351.511424 -341.674641)
			(xy 351.538852 -341.595396) (xy 351.573688 -341.519117) (xy 351.615617 -341.446494) (xy 351.66426 -341.378187)
			(xy 351.719176 -341.314813) (xy 351.779867 -341.256945) (xy 351.845785 -341.205109) (xy 351.916331 -341.159774)
			(xy 351.990867 -341.12135) (xy 352.068718 -341.090185) (xy 352.149179 -341.066562) (xy 352.231522 -341.050694)
			(xy 352.314999 -341.042726) (xy 352.356928 -341.042244) (xy 352.394113 -341.042602) (xy 352.46822 -341.048827)
			(xy 352.54154 -341.061273) (xy 352.613551 -341.07985) (xy 352.648774 -341.091774) (xy 352.65697 -341.094297)
			(xy 352.674106 -341.094297) (xy 352.682302 -341.091774) (xy 352.717522 -341.079841) (xy 352.789531 -341.06125)
			(xy 352.862852 -341.048806) (xy 352.936963 -341.042598) (xy 352.974148 -341.042244) (xy 352.988626 -341.042244)
			(xy 352.999994 -341.041829) (xy 353.020668 -341.032414) (xy 353.035248 -341.014994) (xy 353.038664 -341.004144)
			(xy 353.047218 -340.97218) (xy 353.068449 -340.909504) (xy 353.081082 -340.878922) (xy 353.084639 -340.869329)
			(xy 353.084643 -340.848889) (xy 353.081082 -340.839298) (xy 353.064075 -340.797887) (xy 353.03752 -340.712388)
			(xy 353.019684 -340.624655) (xy 353.010745 -340.535574) (xy 353.010216 -340.49081) (xy 353.01072 -340.448462)
			(xy 353.018771 -340.364148) (xy 353.0348 -340.280982) (xy 353.058661 -340.199715) (xy 353.09014 -340.121085)
			(xy 353.128951 -340.045804) (xy 353.174741 -339.974552) (xy 353.227097 -339.907976) (xy 353.285545 -339.846678)
			(xy 353.349555 -339.791213) (xy 353.418547 -339.742084) (xy 353.491897 -339.699735) (xy 353.56894 -339.664551)
			(xy 353.648979 -339.636849) (xy 353.731288 -339.616881) (xy 353.815123 -339.604828) (xy 353.899724 -339.600798)
			(xy 353.984325 -339.604828) (xy 354.06816 -339.616881) (xy 354.150469 -339.636849) (xy 354.230508 -339.664551)
			(xy 354.307551 -339.699735) (xy 354.380901 -339.742084) (xy 354.449893 -339.791213) (xy 354.513903 -339.846678)
			(xy 354.572351 -339.907976) (xy 354.624707 -339.974552) (xy 354.670497 -340.045804) (xy 354.709308 -340.121085)
			(xy 354.740787 -340.199715) (xy 354.764648 -340.280982) (xy 354.780677 -340.364148) (xy 354.788728 -340.448462)
			(xy 354.789232 -340.49081) (xy 354.788708 -340.535575) (xy 354.779777 -340.624657) (xy 354.761937 -340.712389)
			(xy 354.735368 -340.797885) (xy 354.718366 -340.839298) (xy 354.714795 -340.848887) (xy 354.714799 -340.869331)
			(xy 354.718366 -340.878922) (xy 354.735345 -340.920344) (xy 354.761907 -341.005839) (xy 354.779752 -341.093569)
			(xy 354.788699 -341.182647) (xy 354.789232 -341.22741) (xy 354.789232 -341.228172) (xy 354.789643 -341.238195)
			(xy 354.79731 -341.256718) (xy 354.811486 -341.270892) (xy 354.830009 -341.278557) (xy 354.840032 -341.278972)
			(xy 354.847906 -341.278972) (xy 354.862638 -341.2744) (xy 354.869242 -341.269828) (xy 354.906551 -341.244594)
			(xy 354.985338 -341.200935) (xy 355.068135 -341.165465) (xy 355.154094 -341.138546) (xy 355.242334 -341.120456)
			(xy 355.33195 -341.111378) (xy 355.376988 -341.110824) (xy 355.418092 -341.111264) (xy 355.499949 -341.118848)
			(xy 355.580757 -341.133953) (xy 355.659827 -341.15645) (xy 355.736484 -341.186147) (xy 355.810073 -341.22279)
			(xy 355.879967 -341.266067) (xy 355.94557 -341.315609) (xy 356.006322 -341.370992) (xy 356.061704 -341.431745)
			(xy 356.111244 -341.497349) (xy 356.15452 -341.567245) (xy 356.191162 -341.640835) (xy 356.220857 -341.717492)
			(xy 356.243352 -341.796562) (xy 356.258455 -341.877371) (xy 356.266037 -341.959228) (xy 356.266496 -342.000332)
			(xy 356.265974 -342.045097) (xy 356.257042 -342.134178) (xy 356.239201 -342.221911) (xy 356.212632 -342.307407)
			(xy 356.19563 -342.34882) (xy 356.192048 -342.358406) (xy 356.19206 -342.378853) (xy 356.19563 -342.388444)
			(xy 356.212619 -342.429862) (xy 356.239178 -342.515358) (xy 356.25702 -342.603089) (xy 356.265964 -342.692168)
			(xy 356.266496 -342.736932) (xy 356.265974 -342.781697) (xy 356.257042 -342.870778) (xy 356.239201 -342.958511)
			(xy 356.212632 -343.044007) (xy 356.19563 -343.08542) (xy 356.192048 -343.095006) (xy 356.19206 -343.115453)
			(xy 356.19563 -343.125044) (xy 356.212619 -343.166462) (xy 356.239178 -343.251958) (xy 356.25702 -343.339689)
			(xy 356.265964 -343.428768) (xy 356.266496 -343.473532) (xy 356.266064 -343.514635) (xy 356.258476 -343.596491)
			(xy 356.243368 -343.677298) (xy 356.220868 -343.756366) (xy 356.191169 -343.83302) (xy 356.154525 -343.906608)
			(xy 356.111246 -343.9765) (xy 356.061704 -344.042101) (xy 356.00632 -344.102851) (xy 355.945567 -344.158232)
			(xy 355.879964 -344.207771) (xy 355.810069 -344.251046) (xy 355.73648 -344.287687) (xy 355.659824 -344.317382)
			(xy 355.580755 -344.339878) (xy 355.499948 -344.354982) (xy 355.418091 -344.362566) (xy 355.376988 -344.36304)
			(xy 355.335375 -344.362595) (xy 355.252512 -344.354841) (xy 355.170737 -344.339375) (xy 355.090766 -344.316332)
			(xy 355.013299 -344.285913) (xy 354.939015 -344.248385) (xy 354.903532 -344.226642) (xy 354.894412 -344.221554)
			(xy 354.873772 -344.218501) (xy 354.853611 -344.223873) (xy 354.845112 -344.229944) (xy 354.811434 -344.255887)
			(xy 354.739995 -344.301979) (xy 354.664485 -344.341047) (xy 354.585593 -344.372734) (xy 354.504038 -344.396752)
			(xy 354.420565 -344.41288) (xy 354.335933 -344.420973) (xy 354.293424 -344.42146) (xy 354.25232 -344.421025)
			(xy 354.170462 -344.413441) (xy 354.089653 -344.398337) (xy 354.010583 -344.375841) (xy 353.933926 -344.346144)
			(xy 353.860336 -344.309501) (xy 353.790441 -344.266224) (xy 353.724837 -344.216682) (xy 353.664085 -344.161298)
			(xy 353.608703 -344.100544) (xy 353.559163 -344.03494) (xy 353.515887 -343.965043) (xy 353.479246 -343.891453)
			(xy 353.449552 -343.814794) (xy 353.427057 -343.735723) (xy 353.411955 -343.654914) (xy 353.404374 -343.573056)
			(xy 353.403916 -343.531952) (xy 353.404431 -343.487187) (xy 353.413365 -343.398105) (xy 353.431208 -343.310372)
			(xy 353.457779 -343.224877) (xy 353.474782 -343.183464) (xy 353.478372 -343.173881) (xy 353.478354 -343.153431)
			(xy 353.474782 -343.14384) (xy 353.458989 -343.105534) (xy 353.433779 -343.026599) (xy 353.416022 -342.945661)
			(xy 353.405873 -342.863421) (xy 353.40417 -342.822022) (xy 353.403294 -342.811106) (xy 353.39366 -342.791469)
			(xy 353.376758 -342.777587) (xy 353.366324 -342.77427) (xy 353.349452 -342.769771) (xy 353.316041 -342.759609)
			(xy 353.299522 -342.75395) (xy 353.291326 -342.751427) (xy 353.27419 -342.751427) (xy 353.265994 -342.75395)
			(xy 353.230774 -342.765885) (xy 353.158765 -342.784475) (xy 353.085444 -342.796919) (xy 353.011333 -342.803127)
			(xy 352.974148 -342.80348) (xy 352.936964 -342.803098) (xy 352.862857 -342.79688) (xy 352.789537 -342.784441)
			(xy 352.717525 -342.76587) (xy 352.682302 -342.75395) (xy 352.674106 -342.751427) (xy 352.65697 -342.751427)
			(xy 352.648774 -342.75395) (xy 352.613556 -342.765891) (xy 352.541546 -342.784479) (xy 352.468224 -342.796921)
			(xy 352.394113 -342.803127) (xy 352.356928 -342.80348) (xy 352.314999 -342.803074) (xy 352.231522 -342.795106)
			(xy 352.149179 -342.779238) (xy 352.068718 -342.755615) (xy 351.990867 -342.72445) (xy 351.916331 -342.686026)
			(xy 351.845785 -342.640691) (xy 351.779867 -342.588855) (xy 351.719176 -342.530987) (xy 351.66426 -342.467613)
			(xy 351.615617 -342.399306) (xy 351.573688 -342.326683) (xy 351.538852 -342.250404) (xy 351.511424 -342.171159)
			(xy 351.491654 -342.089666) (xy 351.479719 -342.006662) (xy 351.475729 -341.9229) (xy 271.348962 -341.9229)
			(xy 271.348962 -348.7047) (xy 275.231844 -348.7047) (xy 275.235834 -348.620942) (xy 275.247768 -348.537942)
			(xy 275.267537 -348.456452) (xy 275.294962 -348.377211) (xy 275.329796 -348.300935) (xy 275.371722 -348.228316)
			(xy 275.420361 -348.16001) (xy 275.475273 -348.096638) (xy 275.53596 -348.038772) (xy 275.601873 -347.986937)
			(xy 275.672414 -347.941602) (xy 275.746946 -347.903177) (xy 275.824792 -347.872011) (xy 275.905248 -347.848386)
			(xy 275.987586 -347.832515) (xy 276.071059 -347.824543) (xy 276.112986 -347.824044) (xy 276.15017 -347.824414)
			(xy 276.224278 -347.830636) (xy 276.297598 -347.843078) (xy 276.369609 -347.861652) (xy 276.404832 -347.873574)
			(xy 276.413028 -347.876097) (xy 276.430164 -347.876097) (xy 276.43836 -347.873574) (xy 276.478965 -347.859871)
			(xy 276.562206 -347.839476) (xy 276.647036 -347.82727) (xy 276.68982 -347.824806) (xy 276.700474 -347.823858)
			(xy 276.719614 -347.814355) (xy 276.733232 -347.797887) (xy 276.736556 -347.787722) (xy 276.744588 -347.759435)
			(xy 276.763907 -347.703889) (xy 276.775164 -347.676724) (xy 276.778721 -347.667131) (xy 276.778725 -347.646691)
			(xy 276.775164 -347.6371) (xy 276.758127 -347.595694) (xy 276.731493 -347.510205) (xy 276.713589 -347.422472)
			(xy 276.704596 -347.333383) (xy 276.704044 -347.288612) (xy 276.704548 -347.246251) (xy 276.712601 -347.161914)
			(xy 276.728635 -347.078724) (xy 276.752503 -346.997434) (xy 276.783991 -346.918782) (xy 276.822813 -346.843479)
			(xy 276.868616 -346.772207) (xy 276.920987 -346.705611) (xy 276.979452 -346.644296) (xy 277.04348 -346.588815)
			(xy 277.112492 -346.539672) (xy 277.185862 -346.497312) (xy 277.262927 -346.462117) (xy 277.342989 -346.434408)
			(xy 277.425322 -346.414434) (xy 277.509181 -346.402377) (xy 277.593806 -346.398346) (xy 277.678431 -346.402377)
			(xy 277.76229 -346.414434) (xy 277.844623 -346.434408) (xy 277.924685 -346.462117) (xy 278.00175 -346.497312)
			(xy 278.07512 -346.539672) (xy 278.144132 -346.588815) (xy 278.20816 -346.644296) (xy 278.266625 -346.705611)
			(xy 278.318996 -346.772207) (xy 278.364799 -346.843479) (xy 278.403621 -346.918782) (xy 278.435109 -346.997434)
			(xy 278.458977 -347.078724) (xy 278.475011 -347.161914) (xy 278.483064 -347.246251) (xy 278.483568 -347.288612)
			(xy 278.482998 -347.333381) (xy 278.47399 -347.422466) (xy 278.456088 -347.510198) (xy 278.42947 -347.595689)
			(xy 278.412448 -347.6371) (xy 278.408877 -347.646689) (xy 278.408882 -347.667133) (xy 278.412448 -347.676724)
			(xy 278.426621 -347.711083) (xy 278.449883 -347.78168) (xy 278.467176 -347.853971) (xy 278.47838 -347.927452)
			(xy 278.481282 -347.964506) (xy 278.482298 -347.978476) (xy 278.497284 -348.000574) (xy 278.600916 -348.051628)
			(xy 278.627586 -348.04985) (xy 278.639016 -348.04223) (xy 278.675617 -348.018437) (xy 278.752639 -347.977332)
			(xy 278.833317 -347.943969) (xy 278.916874 -347.918668) (xy 279.002507 -347.901673) (xy 279.089394 -347.893146)
			(xy 279.133046 -347.892624) (xy 279.174153 -347.893069) (xy 279.256016 -347.900657) (xy 279.336831 -347.915765)
			(xy 279.415907 -347.938263) (xy 279.49257 -347.96796) (xy 279.566167 -348.004602) (xy 279.63607 -348.047877)
			(xy 279.701683 -348.097416) (xy 279.762447 -348.152796) (xy 279.817842 -348.213546) (xy 279.867398 -348.279147)
			(xy 279.91069 -348.349039) (xy 279.947351 -348.422627) (xy 279.977067 -348.499283) (xy 279.999585 -348.578353)
			(xy 280.014712 -348.659164) (xy 280.018945 -348.7047) (xy 283.512244 -348.7047) (xy 283.516234 -348.620942)
			(xy 283.528168 -348.537942) (xy 283.547937 -348.456452) (xy 283.575362 -348.377211) (xy 283.610196 -348.300935)
			(xy 283.652122 -348.228316) (xy 283.700761 -348.16001) (xy 283.755673 -348.096638) (xy 283.81636 -348.038772)
			(xy 283.882273 -347.986937) (xy 283.952814 -347.941602) (xy 284.027346 -347.903177) (xy 284.105192 -347.872011)
			(xy 284.185648 -347.848386) (xy 284.267986 -347.832515) (xy 284.351459 -347.824543) (xy 284.393386 -347.824044)
			(xy 284.43057 -347.824414) (xy 284.504678 -347.830636) (xy 284.577998 -347.843078) (xy 284.650009 -347.861652)
			(xy 284.685232 -347.873574) (xy 284.693428 -347.876097) (xy 284.710564 -347.876097) (xy 284.71876 -347.873574)
			(xy 284.756938 -347.860634) (xy 284.835124 -347.840982) (xy 284.91478 -347.828562) (xy 284.95498 -347.825568)
			(xy 284.965838 -347.82436) (xy 284.985096 -347.814096) (xy 284.99831 -347.79673) (xy 285.001208 -347.786198)
			(xy 285.010486 -347.747118) (xy 285.035162 -347.670674) (xy 285.050484 -347.633544) (xy 285.054028 -347.623948)
			(xy 285.05404 -347.603511) (xy 285.050484 -347.59392) (xy 285.033454 -347.552511) (xy 285.006819 -347.467023)
			(xy 284.988912 -347.379291) (xy 284.979917 -347.290203) (xy 284.979364 -347.245432) (xy 284.979868 -347.203071)
			(xy 284.987921 -347.118734) (xy 285.003955 -347.035544) (xy 285.027823 -346.954254) (xy 285.059311 -346.875602)
			(xy 285.098133 -346.800299) (xy 285.143936 -346.729027) (xy 285.196307 -346.662431) (xy 285.254772 -346.601116)
			(xy 285.3188 -346.545635) (xy 285.387812 -346.496492) (xy 285.461182 -346.454132) (xy 285.538247 -346.418937)
			(xy 285.618309 -346.391228) (xy 285.700642 -346.371254) (xy 285.784501 -346.359197) (xy 285.869126 -346.355166)
			(xy 285.953751 -346.359197) (xy 286.03761 -346.371254) (xy 286.119943 -346.391228) (xy 286.200005 -346.418937)
			(xy 286.27707 -346.454132) (xy 286.35044 -346.496492) (xy 286.419452 -346.545635) (xy 286.48348 -346.601116)
			(xy 286.541945 -346.662431) (xy 286.594316 -346.729027) (xy 286.640119 -346.800299) (xy 286.678941 -346.875602)
			(xy 286.710429 -346.954254) (xy 286.734297 -347.035544) (xy 286.750331 -347.118734) (xy 286.758384 -347.203071)
			(xy 286.758888 -347.245432) (xy 286.758323 -347.290202) (xy 286.749314 -347.379287) (xy 286.73141 -347.467018)
			(xy 286.704791 -347.552509) (xy 286.687768 -347.59392) (xy 286.684185 -347.603505) (xy 286.684197 -347.623953)
			(xy 286.687768 -347.633544) (xy 286.703871 -347.672618) (xy 286.72945 -347.753174) (xy 286.747275 -347.835792)
			(xy 286.757183 -347.919728) (xy 286.758634 -347.961966) (xy 286.758888 -347.97619) (xy 286.773366 -347.999558)
			(xy 286.877506 -348.053406) (xy 286.905192 -348.051882) (xy 286.916876 -348.044008) (xy 286.953598 -348.019927)
			(xy 287.030944 -347.978334) (xy 287.112015 -347.944569) (xy 287.196019 -347.918962) (xy 287.282139 -347.901762)
			(xy 287.369535 -347.893138) (xy 287.413446 -347.892624) (xy 287.454553 -347.893069) (xy 287.536416 -347.900657)
			(xy 287.617231 -347.915765) (xy 287.696307 -347.938263) (xy 287.77297 -347.96796) (xy 287.846567 -348.004602)
			(xy 287.91647 -348.047877) (xy 287.982083 -348.097416) (xy 288.042847 -348.152796) (xy 288.098242 -348.213546)
			(xy 288.147798 -348.279147) (xy 288.19109 -348.349039) (xy 288.227751 -348.422627) (xy 288.257467 -348.499283)
			(xy 288.279985 -348.578353) (xy 288.295112 -348.659164) (xy 288.299345 -348.7047) (xy 291.818044 -348.7047)
			(xy 291.822034 -348.620942) (xy 291.833968 -348.537942) (xy 291.853737 -348.456452) (xy 291.881162 -348.377211)
			(xy 291.915996 -348.300935) (xy 291.957922 -348.228316) (xy 292.006561 -348.16001) (xy 292.061473 -348.096638)
			(xy 292.12216 -348.038772) (xy 292.188073 -347.986937) (xy 292.258614 -347.941602) (xy 292.333146 -347.903177)
			(xy 292.410992 -347.872011) (xy 292.491448 -347.848386) (xy 292.573786 -347.832515) (xy 292.657259 -347.824543)
			(xy 292.699186 -347.824044) (xy 292.73637 -347.824414) (xy 292.810478 -347.830636) (xy 292.883798 -347.843078)
			(xy 292.955809 -347.861652) (xy 292.991032 -347.873574) (xy 292.999228 -347.876097) (xy 293.016364 -347.876097)
			(xy 293.02456 -347.873574) (xy 293.057737 -347.862322) (xy 293.125493 -347.844496) (xy 293.194454 -347.832123)
			(xy 293.229284 -347.828362) (xy 293.240044 -347.82673) (xy 293.258819 -347.815766) (xy 293.271409 -347.798041)
			(xy 293.273988 -347.787468) (xy 293.28351 -347.742121) (xy 293.310744 -347.653548) (xy 293.328344 -347.610684)
			(xy 293.331924 -347.601098) (xy 293.331914 -347.580651) (xy 293.328344 -347.57106) (xy 293.311293 -347.529659)
			(xy 293.284663 -347.444168) (xy 293.266763 -347.356433) (xy 293.257774 -347.267343) (xy 293.257224 -347.222572)
			(xy 293.257728 -347.180211) (xy 293.265781 -347.095874) (xy 293.281815 -347.012684) (xy 293.305683 -346.931394)
			(xy 293.337171 -346.852742) (xy 293.375993 -346.777439) (xy 293.421796 -346.706167) (xy 293.474167 -346.639571)
			(xy 293.532632 -346.578256) (xy 293.59666 -346.522775) (xy 293.665672 -346.473632) (xy 293.739042 -346.431272)
			(xy 293.816107 -346.396077) (xy 293.896169 -346.368368) (xy 293.978502 -346.348394) (xy 294.062361 -346.336337)
			(xy 294.146986 -346.332306) (xy 294.231611 -346.336337) (xy 294.31547 -346.348394) (xy 294.397803 -346.368368)
			(xy 294.477865 -346.396077) (xy 294.55493 -346.431272) (xy 294.6283 -346.473632) (xy 294.697312 -346.522775)
			(xy 294.76134 -346.578256) (xy 294.819805 -346.639571) (xy 294.872176 -346.706167) (xy 294.917979 -346.777439)
			(xy 294.956801 -346.852742) (xy 294.988289 -346.931394) (xy 295.012157 -347.012684) (xy 295.028191 -347.095874)
			(xy 295.036244 -347.180211) (xy 295.036748 -347.222572) (xy 295.036192 -347.267342) (xy 295.027179 -347.356427)
			(xy 295.009272 -347.444158) (xy 294.982652 -347.529649) (xy 294.965628 -347.57106) (xy 294.962081 -347.580656)
			(xy 294.96207 -347.601093) (xy 294.965628 -347.610684) (xy 294.982659 -347.652092) (xy 295.009295 -347.73758)
			(xy 295.0272 -347.825313) (xy 295.036195 -347.914401) (xy 295.036748 -347.959172) (xy 295.036494 -347.977206)
			(xy 295.03624 -347.991938) (xy 295.050718 -348.016322) (xy 295.157144 -348.072202) (xy 295.185592 -348.07017)
			(xy 295.19753 -348.061534) (xy 295.230065 -348.038562) (xy 295.298502 -347.997814) (xy 295.370309 -347.96335)
			(xy 295.444911 -347.935446) (xy 295.521709 -347.914326) (xy 295.600089 -347.900158) (xy 295.679421 -347.893057)
			(xy 295.719246 -347.892624) (xy 295.760353 -347.893069) (xy 295.842216 -347.900657) (xy 295.923031 -347.915765)
			(xy 296.002107 -347.938263) (xy 296.07877 -347.96796) (xy 296.152367 -348.004602) (xy 296.22227 -348.047877)
			(xy 296.287883 -348.097416) (xy 296.348647 -348.152796) (xy 296.404042 -348.213546) (xy 296.453598 -348.279147)
			(xy 296.49689 -348.349039) (xy 296.533551 -348.422627) (xy 296.563267 -348.499283) (xy 296.585785 -348.578353)
			(xy 296.600912 -348.659164) (xy 296.605145 -348.7047) (xy 300.174644 -348.7047) (xy 300.178634 -348.620942)
			(xy 300.190568 -348.537942) (xy 300.210337 -348.456452) (xy 300.237762 -348.377211) (xy 300.272596 -348.300935)
			(xy 300.314522 -348.228316) (xy 300.363161 -348.16001) (xy 300.418073 -348.096638) (xy 300.47876 -348.038772)
			(xy 300.544673 -347.986937) (xy 300.615214 -347.941602) (xy 300.689746 -347.903177) (xy 300.767592 -347.872011)
			(xy 300.848048 -347.848386) (xy 300.930386 -347.832515) (xy 301.013859 -347.824543) (xy 301.055786 -347.824044)
			(xy 301.09297 -347.824414) (xy 301.167078 -347.830636) (xy 301.240398 -347.843078) (xy 301.312409 -347.861652)
			(xy 301.347632 -347.873574) (xy 301.355828 -347.876097) (xy 301.372964 -347.876097) (xy 301.38116 -347.873574)
			(xy 301.419296 -347.860641) (xy 301.497398 -347.840993) (xy 301.576968 -347.828568) (xy 301.617126 -347.825568)
			(xy 301.627815 -347.824425) (xy 301.646831 -347.814441) (xy 301.660064 -347.797526) (xy 301.6631 -347.787214)
			(xy 301.671959 -347.753143) (xy 301.694335 -347.686389) (xy 301.707804 -347.653864) (xy 301.711398 -347.644282)
			(xy 301.71138 -347.623831) (xy 301.707804 -347.61424) (xy 301.690776 -347.57283) (xy 301.66414 -347.487343)
			(xy 301.646234 -347.39961) (xy 301.637237 -347.310523) (xy 301.636684 -347.265752) (xy 301.637188 -347.223391)
			(xy 301.645241 -347.139054) (xy 301.661275 -347.055864) (xy 301.685143 -346.974574) (xy 301.716631 -346.895922)
			(xy 301.755453 -346.820619) (xy 301.801256 -346.749347) (xy 301.853627 -346.682751) (xy 301.912092 -346.621436)
			(xy 301.97612 -346.565955) (xy 302.045132 -346.516812) (xy 302.118502 -346.474452) (xy 302.195567 -346.439257)
			(xy 302.275629 -346.411548) (xy 302.357962 -346.391574) (xy 302.441821 -346.379517) (xy 302.526446 -346.375486)
			(xy 302.611071 -346.379517) (xy 302.69493 -346.391574) (xy 302.777263 -346.411548) (xy 302.857325 -346.439257)
			(xy 302.93439 -346.474452) (xy 303.00776 -346.516812) (xy 303.076772 -346.565955) (xy 303.1408 -346.621436)
			(xy 303.199265 -346.682751) (xy 303.251636 -346.749347) (xy 303.297439 -346.820619) (xy 303.336261 -346.895922)
			(xy 303.367749 -346.974574) (xy 303.391617 -347.055864) (xy 303.407651 -347.139054) (xy 303.415704 -347.223391)
			(xy 303.416208 -347.265752) (xy 303.415649 -347.310522) (xy 303.406637 -347.399607) (xy 303.388731 -347.487338)
			(xy 303.362111 -347.572829) (xy 303.345088 -347.61424) (xy 303.341549 -347.623838) (xy 303.341532 -347.644274)
			(xy 303.345088 -347.653864) (xy 303.36051 -347.691224) (xy 303.385289 -347.768163) (xy 303.402976 -347.847034)
			(xy 303.413426 -347.927187) (xy 303.415446 -347.967554) (xy 303.415954 -347.981524) (xy 303.43094 -348.004638)
			(xy 303.53508 -348.057216) (xy 303.562766 -348.055184) (xy 303.574196 -348.04731) (xy 303.611191 -348.022724)
			(xy 303.68921 -347.980246) (xy 303.771072 -347.945749) (xy 303.855962 -347.919575) (xy 303.943036 -347.901984)
			(xy 304.031429 -347.893153) (xy 304.075846 -347.892624) (xy 304.116953 -347.893069) (xy 304.198816 -347.900657)
			(xy 304.279631 -347.915765) (xy 304.358707 -347.938263) (xy 304.43537 -347.96796) (xy 304.508967 -348.004602)
			(xy 304.57887 -348.047877) (xy 304.644483 -348.097416) (xy 304.705247 -348.152796) (xy 304.760642 -348.213546)
			(xy 304.810198 -348.279147) (xy 304.85349 -348.349039) (xy 304.890151 -348.422627) (xy 304.919867 -348.499283)
			(xy 304.942385 -348.578353) (xy 304.957512 -348.659164) (xy 304.961745 -348.7047) (xy 308.505844 -348.7047)
			(xy 308.509834 -348.620942) (xy 308.521768 -348.537942) (xy 308.541537 -348.456452) (xy 308.568962 -348.377211)
			(xy 308.603796 -348.300935) (xy 308.645722 -348.228316) (xy 308.694361 -348.16001) (xy 308.749273 -348.096638)
			(xy 308.80996 -348.038772) (xy 308.875873 -347.986937) (xy 308.946414 -347.941602) (xy 309.020946 -347.903177)
			(xy 309.098792 -347.872011) (xy 309.179248 -347.848386) (xy 309.261586 -347.832515) (xy 309.345059 -347.824543)
			(xy 309.386986 -347.824044) (xy 309.42417 -347.824414) (xy 309.498278 -347.830636) (xy 309.571598 -347.843078)
			(xy 309.643609 -347.861652) (xy 309.678832 -347.873574) (xy 309.687028 -347.876097) (xy 309.704164 -347.876097)
			(xy 309.71236 -347.873574) (xy 309.752042 -347.860186) (xy 309.833344 -347.840073) (xy 309.916186 -347.827757)
			(xy 309.957978 -347.82506) (xy 309.968788 -347.824034) (xy 309.988074 -347.814091) (xy 310.00157 -347.797101)
			(xy 310.004714 -347.786706) (xy 310.013526 -347.752769) (xy 310.03578 -347.686272) (xy 310.049164 -347.653864)
			(xy 310.052755 -347.644281) (xy 310.052737 -347.623831) (xy 310.049164 -347.61424) (xy 310.03214 -347.572829)
			(xy 310.005503 -347.487342) (xy 309.987595 -347.39961) (xy 309.978598 -347.310522) (xy 309.978044 -347.265752)
			(xy 309.978548 -347.223391) (xy 309.986601 -347.139054) (xy 310.002635 -347.055864) (xy 310.026503 -346.974574)
			(xy 310.057991 -346.895922) (xy 310.096813 -346.820619) (xy 310.142616 -346.749347) (xy 310.194987 -346.682751)
			(xy 310.253452 -346.621436) (xy 310.31748 -346.565955) (xy 310.386492 -346.516812) (xy 310.459862 -346.474452)
			(xy 310.536927 -346.439257) (xy 310.616989 -346.411548) (xy 310.699322 -346.391574) (xy 310.783181 -346.379517)
			(xy 310.867806 -346.375486) (xy 310.952431 -346.379517) (xy 311.03629 -346.391574) (xy 311.118623 -346.411548)
			(xy 311.198685 -346.439257) (xy 311.27575 -346.474452) (xy 311.34912 -346.516812) (xy 311.418132 -346.565955)
			(xy 311.48216 -346.621436) (xy 311.540625 -346.682751) (xy 311.592996 -346.749347) (xy 311.638799 -346.820619)
			(xy 311.677621 -346.895922) (xy 311.709109 -346.974574) (xy 311.732977 -347.055864) (xy 311.749011 -347.139054)
			(xy 311.757064 -347.223391) (xy 311.757568 -347.265752) (xy 311.757012 -347.310522) (xy 311.748 -347.399607)
			(xy 311.730093 -347.487338) (xy 311.703472 -347.572829) (xy 311.686448 -347.61424) (xy 311.682911 -347.623839)
			(xy 311.682894 -347.644274) (xy 311.686448 -347.653864) (xy 311.701578 -347.690518) (xy 311.725997 -347.765967)
			(xy 311.743615 -347.843288) (xy 311.754293 -347.921869) (xy 311.756552 -347.961458) (xy 311.75706 -347.975428)
			(xy 311.771792 -347.998288) (xy 311.875424 -348.050866) (xy 311.902602 -348.049088) (xy 311.914286 -348.041468)
			(xy 311.950816 -348.017793) (xy 312.027663 -347.976887) (xy 312.10814 -347.94369) (xy 312.191477 -347.918518)
			(xy 312.276876 -347.901613) (xy 312.363518 -347.893137) (xy 312.407046 -347.892624) (xy 312.448153 -347.893069)
			(xy 312.530016 -347.900657) (xy 312.610831 -347.915765) (xy 312.689907 -347.938263) (xy 312.76657 -347.96796)
			(xy 312.840167 -348.004602) (xy 312.91007 -348.047877) (xy 312.975683 -348.097416) (xy 313.036447 -348.152796)
			(xy 313.091842 -348.213546) (xy 313.141398 -348.279147) (xy 313.18469 -348.349039) (xy 313.221351 -348.422627)
			(xy 313.251067 -348.499283) (xy 313.273585 -348.578353) (xy 313.288712 -348.659164) (xy 313.296321 -348.741025)
			(xy 313.296808 -348.782132) (xy 313.296242 -348.826902) (xy 313.287233 -348.915987) (xy 313.269329 -349.003718)
			(xy 313.242711 -349.089209) (xy 313.225688 -349.13062) (xy 313.222104 -349.140205) (xy 313.222115 -349.160653)
			(xy 313.225688 -349.170244) (xy 313.242711 -349.211656) (xy 313.269347 -349.297143) (xy 313.287256 -349.384874)
			(xy 313.291976 -349.43161) (xy 326.552821 -349.43161) (xy 326.556826 -349.325861) (xy 326.568816 -349.220718)
			(xy 326.588725 -349.116783) (xy 326.616436 -349.014651) (xy 326.651793 -348.914907) (xy 326.694591 -348.818123)
			(xy 326.744587 -348.724853) (xy 326.801494 -348.635632) (xy 326.864985 -348.550969) (xy 326.934697 -348.471351)
			(xy 327.010231 -348.397233) (xy 327.091154 -348.32904) (xy 327.177003 -348.267162) (xy 327.267286 -348.211955)
			(xy 327.361485 -348.163733) (xy 327.459062 -348.122773) (xy 327.559457 -348.089311) (xy 327.662095 -348.063537)
			(xy 327.766388 -348.045599) (xy 327.871739 -348.0356) (xy 327.977545 -348.033597) (xy 328.083199 -348.039602)
			(xy 328.188096 -348.053581) (xy 328.291636 -348.075452) (xy 328.393225 -348.105092) (xy 328.492282 -348.14233)
			(xy 328.588239 -348.186952) (xy 328.680546 -348.238704) (xy 328.768675 -348.297289) (xy 328.852121 -348.362371)
			(xy 328.930405 -348.433577) (xy 329.00308 -348.5105) (xy 329.06973 -348.5927) (xy 329.129972 -348.679704)
			(xy 329.183461 -348.771015) (xy 329.229892 -348.86611) (xy 329.268997 -348.964444) (xy 329.300554 -349.065455)
			(xy 329.324381 -349.168562) (xy 329.340342 -349.273176) (xy 329.348346 -349.378698) (xy 329.348846 -349.43161)
			(xy 334.012801 -349.43161) (xy 334.016806 -349.325861) (xy 334.028796 -349.220718) (xy 334.048705 -349.116783)
			(xy 334.076416 -349.014651) (xy 334.111773 -348.914907) (xy 334.154571 -348.818123) (xy 334.204567 -348.724853)
			(xy 334.261474 -348.635632) (xy 334.324965 -348.550969) (xy 334.394677 -348.471351) (xy 334.470211 -348.397233)
			(xy 334.551134 -348.32904) (xy 334.636983 -348.267162) (xy 334.727266 -348.211955) (xy 334.821465 -348.163733)
			(xy 334.919042 -348.122773) (xy 335.019437 -348.089311) (xy 335.122075 -348.063537) (xy 335.226368 -348.045599)
			(xy 335.331719 -348.0356) (xy 335.437525 -348.033597) (xy 335.543179 -348.039602) (xy 335.648076 -348.053581)
			(xy 335.751616 -348.075452) (xy 335.853205 -348.105092) (xy 335.952262 -348.14233) (xy 336.048219 -348.186952)
			(xy 336.140526 -348.238704) (xy 336.228655 -348.297289) (xy 336.312101 -348.362371) (xy 336.390385 -348.433577)
			(xy 336.46306 -348.5105) (xy 336.52971 -348.5927) (xy 336.589952 -348.679704) (xy 336.643441 -348.771015)
			(xy 336.689872 -348.86611) (xy 336.728977 -348.964444) (xy 336.760534 -349.065455) (xy 336.784361 -349.168562)
			(xy 336.800322 -349.273176) (xy 336.808326 -349.378698) (xy 336.808826 -349.43161) (xy 336.808326 -349.484522)
			(xy 336.800322 -349.590044) (xy 336.784361 -349.694658) (xy 336.760534 -349.797765) (xy 336.728977 -349.898776)
			(xy 336.689872 -349.99711) (xy 336.643441 -350.092205) (xy 336.589952 -350.183516) (xy 336.52971 -350.27052)
			(xy 336.46306 -350.35272) (xy 336.390385 -350.429643) (xy 336.312101 -350.500849) (xy 336.228655 -350.565931)
			(xy 336.140526 -350.624516) (xy 336.048219 -350.676268) (xy 335.952262 -350.72089) (xy 335.853205 -350.758128)
			(xy 335.751616 -350.787768) (xy 335.648076 -350.809639) (xy 335.543179 -350.823618) (xy 335.437525 -350.829623)
			(xy 335.331719 -350.82762) (xy 335.226368 -350.817621) (xy 335.122075 -350.799683) (xy 335.019437 -350.773909)
			(xy 334.919042 -350.740447) (xy 334.821465 -350.699487) (xy 334.727266 -350.651265) (xy 334.636983 -350.596058)
			(xy 334.551134 -350.53418) (xy 334.470211 -350.465987) (xy 334.394677 -350.391869) (xy 334.324965 -350.312251)
			(xy 334.261474 -350.227588) (xy 334.204567 -350.138367) (xy 334.154571 -350.045097) (xy 334.111773 -349.948313)
			(xy 334.076416 -349.848569) (xy 334.048705 -349.746437) (xy 334.028796 -349.642502) (xy 334.016806 -349.537359)
			(xy 334.012801 -349.43161) (xy 329.348846 -349.43161) (xy 329.348346 -349.484522) (xy 329.340342 -349.590044)
			(xy 329.324381 -349.694658) (xy 329.300554 -349.797765) (xy 329.268997 -349.898776) (xy 329.229892 -349.99711)
			(xy 329.183461 -350.092205) (xy 329.129972 -350.183516) (xy 329.06973 -350.27052) (xy 329.00308 -350.35272)
			(xy 328.930405 -350.429643) (xy 328.852121 -350.500849) (xy 328.768675 -350.565931) (xy 328.680546 -350.624516)
			(xy 328.588239 -350.676268) (xy 328.492282 -350.72089) (xy 328.393225 -350.758128) (xy 328.291636 -350.787768)
			(xy 328.188096 -350.809639) (xy 328.083199 -350.823618) (xy 327.977545 -350.829623) (xy 327.871739 -350.82762)
			(xy 327.766388 -350.817621) (xy 327.662095 -350.799683) (xy 327.559457 -350.773909) (xy 327.459062 -350.740447)
			(xy 327.361485 -350.699487) (xy 327.267286 -350.651265) (xy 327.177003 -350.596058) (xy 327.091154 -350.53418)
			(xy 327.010231 -350.465987) (xy 326.934697 -350.391869) (xy 326.864985 -350.312251) (xy 326.801494 -350.227588)
			(xy 326.744587 -350.138367) (xy 326.694591 -350.045097) (xy 326.651793 -349.948313) (xy 326.616436 -349.848569)
			(xy 326.588725 -349.746437) (xy 326.568816 -349.642502) (xy 326.556826 -349.537359) (xy 326.552821 -349.43161)
			(xy 313.291976 -349.43161) (xy 313.296254 -349.473962) (xy 313.296808 -349.518732) (xy 313.296242 -349.563502)
			(xy 313.287233 -349.652587) (xy 313.269329 -349.740318) (xy 313.242711 -349.825809) (xy 313.225688 -349.86722)
			(xy 313.222104 -349.876805) (xy 313.222115 -349.897253) (xy 313.225688 -349.906844) (xy 313.242711 -349.948256)
			(xy 313.269347 -350.033743) (xy 313.287256 -350.121474) (xy 313.296254 -350.210562) (xy 313.296808 -350.255332)
			(xy 313.296378 -350.296443) (xy 313.288787 -350.378314) (xy 313.273674 -350.459136) (xy 313.251166 -350.538217)
			(xy 313.221457 -350.614885) (xy 313.184799 -350.688483) (xy 313.141506 -350.758385) (xy 313.091947 -350.823993)
			(xy 313.036545 -350.884747) (xy 312.975772 -350.94013) (xy 312.910148 -350.989668) (xy 312.840233 -351.032938)
			(xy 312.766623 -351.069572) (xy 312.689946 -351.099257) (xy 312.610857 -351.121739) (xy 312.530031 -351.136827)
			(xy 312.448157 -351.144391) (xy 312.407046 -351.14484) (xy 312.365434 -351.144367) (xy 312.282572 -351.136619)
			(xy 312.200797 -351.121158) (xy 312.120826 -351.09812) (xy 312.043359 -351.067706) (xy 311.969074 -351.030183)
			(xy 311.93359 -351.008442) (xy 311.924446 -351.003405) (xy 311.903822 -351.000334) (xy 311.883669 -351.005685)
			(xy 311.87517 -351.011744) (xy 311.841506 -351.037707) (xy 311.770065 -351.083797) (xy 311.694552 -351.122862)
			(xy 311.615658 -351.154546) (xy 311.534101 -351.178561) (xy 311.450625 -351.194686) (xy 311.365992 -351.202775)
			(xy 311.323482 -351.20326) (xy 311.282375 -351.202805) (xy 311.200511 -351.195219) (xy 311.119697 -351.180113)
			(xy 311.04062 -351.157617) (xy 310.963956 -351.127921) (xy 310.890359 -351.09128) (xy 310.820455 -351.048006)
			(xy 310.754841 -350.998468) (xy 310.694077 -350.943088) (xy 310.638682 -350.882339) (xy 310.589126 -350.816738)
			(xy 310.545833 -350.746846) (xy 310.509173 -350.673258) (xy 310.479458 -350.596602) (xy 310.456941 -350.517531)
			(xy 310.441814 -350.43672) (xy 310.434206 -350.354859) (xy 310.43372 -350.313752) (xy 310.434279 -350.268982)
			(xy 310.44329 -350.179897) (xy 310.461196 -350.092166) (xy 310.487816 -350.006675) (xy 310.50484 -349.965264)
			(xy 310.508432 -349.955681) (xy 310.508415 -349.935231) (xy 310.50484 -349.92564) (xy 310.489045 -349.887334)
			(xy 310.463835 -349.808399) (xy 310.446079 -349.727461) (xy 310.435931 -349.645221) (xy 310.434228 -349.603822)
			(xy 310.433382 -349.592901) (xy 310.423739 -349.57326) (xy 310.406823 -349.559381) (xy 310.396382 -349.55607)
			(xy 310.379509 -349.551574) (xy 310.346099 -349.54141) (xy 310.32958 -349.53575) (xy 310.321384 -349.533227)
			(xy 310.304248 -349.533227) (xy 310.296052 -349.53575) (xy 310.260836 -349.547697) (xy 310.188826 -349.566284)
			(xy 310.115503 -349.578724) (xy 310.041392 -349.584928) (xy 310.004206 -349.58528) (xy 309.967022 -349.584911)
			(xy 309.892914 -349.578689) (xy 309.819594 -349.566246) (xy 309.747583 -349.547672) (xy 309.71236 -349.53575)
			(xy 309.704164 -349.533227) (xy 309.687028 -349.533227) (xy 309.678832 -349.53575) (xy 309.643609 -349.547675)
			(xy 309.571601 -349.566268) (xy 309.498281 -349.578714) (xy 309.424171 -349.584925) (xy 309.386986 -349.58528)
			(xy 309.345059 -349.584857) (xy 309.261586 -349.576885) (xy 309.179248 -349.561014) (xy 309.098792 -349.537389)
			(xy 309.020946 -349.506223) (xy 308.946414 -349.467798) (xy 308.875873 -349.422463) (xy 308.80996 -349.370628)
			(xy 308.749273 -349.312762) (xy 308.694361 -349.24939) (xy 308.645722 -349.181084) (xy 308.603796 -349.108465)
			(xy 308.568962 -349.032189) (xy 308.541537 -348.952948) (xy 308.521768 -348.871458) (xy 308.509834 -348.788458)
			(xy 308.505844 -348.7047) (xy 304.961745 -348.7047) (xy 304.965121 -348.741025) (xy 304.965608 -348.782132)
			(xy 304.965042 -348.826902) (xy 304.956033 -348.915987) (xy 304.938129 -349.003718) (xy 304.911511 -349.089209)
			(xy 304.894488 -349.13062) (xy 304.890904 -349.140205) (xy 304.890915 -349.160653) (xy 304.894488 -349.170244)
			(xy 304.911511 -349.211656) (xy 304.938147 -349.297143) (xy 304.956056 -349.384874) (xy 304.965054 -349.473962)
			(xy 304.965608 -349.518732) (xy 304.965042 -349.563502) (xy 304.956033 -349.652587) (xy 304.938129 -349.740318)
			(xy 304.911511 -349.825809) (xy 304.894488 -349.86722) (xy 304.890904 -349.876805) (xy 304.890915 -349.897253)
			(xy 304.894488 -349.906844) (xy 304.911511 -349.948256) (xy 304.938147 -350.033743) (xy 304.956056 -350.121474)
			(xy 304.965054 -350.210562) (xy 304.965608 -350.255332) (xy 304.965178 -350.296443) (xy 304.957587 -350.378314)
			(xy 304.942474 -350.459136) (xy 304.919966 -350.538217) (xy 304.890257 -350.614885) (xy 304.853599 -350.688483)
			(xy 304.810306 -350.758385) (xy 304.760747 -350.823993) (xy 304.705345 -350.884747) (xy 304.644572 -350.94013)
			(xy 304.578948 -350.989668) (xy 304.509033 -351.032938) (xy 304.435423 -351.069572) (xy 304.358746 -351.099257)
			(xy 304.279657 -351.121739) (xy 304.198831 -351.136827) (xy 304.116957 -351.144391) (xy 304.075846 -351.14484)
			(xy 304.034234 -351.144367) (xy 303.951372 -351.136619) (xy 303.869597 -351.121158) (xy 303.789626 -351.09812)
			(xy 303.712159 -351.067706) (xy 303.637874 -351.030183) (xy 303.60239 -351.008442) (xy 303.593246 -351.003405)
			(xy 303.572622 -351.000334) (xy 303.552469 -351.005685) (xy 303.54397 -351.011744) (xy 303.510306 -351.037707)
			(xy 303.438865 -351.083797) (xy 303.363352 -351.122862) (xy 303.284458 -351.154546) (xy 303.202901 -351.178561)
			(xy 303.119425 -351.194686) (xy 303.034792 -351.202775) (xy 302.992282 -351.20326) (xy 302.951175 -351.202805)
			(xy 302.869311 -351.195219) (xy 302.788497 -351.180113) (xy 302.70942 -351.157617) (xy 302.632756 -351.127921)
			(xy 302.559159 -351.09128) (xy 302.489255 -351.048006) (xy 302.423641 -350.998468) (xy 302.362877 -350.943088)
			(xy 302.307482 -350.882339) (xy 302.257926 -350.816738) (xy 302.214633 -350.746846) (xy 302.177973 -350.673258)
			(xy 302.148258 -350.596602) (xy 302.125741 -350.517531) (xy 302.110614 -350.43672) (xy 302.103006 -350.354859)
			(xy 302.10252 -350.313752) (xy 302.103079 -350.268982) (xy 302.11209 -350.179897) (xy 302.129996 -350.092166)
			(xy 302.156616 -350.006675) (xy 302.17364 -349.965264) (xy 302.177232 -349.955681) (xy 302.177215 -349.935231)
			(xy 302.17364 -349.92564) (xy 302.157845 -349.887334) (xy 302.132635 -349.808399) (xy 302.114879 -349.727461)
			(xy 302.104731 -349.645221) (xy 302.103028 -349.603822) (xy 302.102182 -349.592901) (xy 302.092539 -349.57326)
			(xy 302.075623 -349.559381) (xy 302.065182 -349.55607) (xy 302.048309 -349.551574) (xy 302.014899 -349.54141)
			(xy 301.99838 -349.53575) (xy 301.990184 -349.533227) (xy 301.973048 -349.533227) (xy 301.964852 -349.53575)
			(xy 301.929636 -349.547697) (xy 301.857626 -349.566284) (xy 301.784303 -349.578724) (xy 301.710192 -349.584928)
			(xy 301.673006 -349.58528) (xy 301.635822 -349.584911) (xy 301.561714 -349.578689) (xy 301.488394 -349.566246)
			(xy 301.416383 -349.547672) (xy 301.38116 -349.53575) (xy 301.372964 -349.533227) (xy 301.355828 -349.533227)
			(xy 301.347632 -349.53575) (xy 301.312409 -349.547675) (xy 301.240401 -349.566268) (xy 301.167081 -349.578714)
			(xy 301.092971 -349.584925) (xy 301.055786 -349.58528) (xy 301.013859 -349.584857) (xy 300.930386 -349.576885)
			(xy 300.848048 -349.561014) (xy 300.767592 -349.537389) (xy 300.689746 -349.506223) (xy 300.615214 -349.467798)
			(xy 300.544673 -349.422463) (xy 300.47876 -349.370628) (xy 300.418073 -349.312762) (xy 300.363161 -349.24939)
			(xy 300.314522 -349.181084) (xy 300.272596 -349.108465) (xy 300.237762 -349.032189) (xy 300.210337 -348.952948)
			(xy 300.190568 -348.871458) (xy 300.178634 -348.788458) (xy 300.174644 -348.7047) (xy 296.605145 -348.7047)
			(xy 296.608521 -348.741025) (xy 296.609008 -348.782132) (xy 296.608442 -348.826902) (xy 296.599433 -348.915987)
			(xy 296.581529 -349.003718) (xy 296.554911 -349.089209) (xy 296.537888 -349.13062) (xy 296.534304 -349.140205)
			(xy 296.534315 -349.160653) (xy 296.537888 -349.170244) (xy 296.554911 -349.211656) (xy 296.581547 -349.297143)
			(xy 296.599456 -349.384874) (xy 296.608454 -349.473962) (xy 296.609008 -349.518732) (xy 296.608442 -349.563502)
			(xy 296.599433 -349.652587) (xy 296.581529 -349.740318) (xy 296.554911 -349.825809) (xy 296.537888 -349.86722)
			(xy 296.534304 -349.876805) (xy 296.534315 -349.897253) (xy 296.537888 -349.906844) (xy 296.554911 -349.948256)
			(xy 296.581547 -350.033743) (xy 296.599456 -350.121474) (xy 296.608454 -350.210562) (xy 296.609008 -350.255332)
			(xy 296.608578 -350.296443) (xy 296.600987 -350.378314) (xy 296.585874 -350.459136) (xy 296.563366 -350.538217)
			(xy 296.533657 -350.614885) (xy 296.496999 -350.688483) (xy 296.453706 -350.758385) (xy 296.404147 -350.823993)
			(xy 296.348745 -350.884747) (xy 296.287972 -350.94013) (xy 296.222348 -350.989668) (xy 296.152433 -351.032938)
			(xy 296.078823 -351.069572) (xy 296.002146 -351.099257) (xy 295.923057 -351.121739) (xy 295.842231 -351.136827)
			(xy 295.760357 -351.144391) (xy 295.719246 -351.14484) (xy 295.677634 -351.144367) (xy 295.594772 -351.136619)
			(xy 295.512997 -351.121158) (xy 295.433026 -351.09812) (xy 295.355559 -351.067706) (xy 295.281274 -351.030183)
			(xy 295.24579 -351.008442) (xy 295.236646 -351.003405) (xy 295.216022 -351.000334) (xy 295.195869 -351.005685)
			(xy 295.18737 -351.011744) (xy 295.153706 -351.037707) (xy 295.082265 -351.083797) (xy 295.006752 -351.122862)
			(xy 294.927858 -351.154546) (xy 294.846301 -351.178561) (xy 294.762825 -351.194686) (xy 294.678192 -351.202775)
			(xy 294.635682 -351.20326) (xy 294.594575 -351.202805) (xy 294.512711 -351.195219) (xy 294.431897 -351.180113)
			(xy 294.35282 -351.157617) (xy 294.276156 -351.127921) (xy 294.202559 -351.09128) (xy 294.132655 -351.048006)
			(xy 294.067041 -350.998468) (xy 294.006277 -350.943088) (xy 293.950882 -350.882339) (xy 293.901326 -350.816738)
			(xy 293.858033 -350.746846) (xy 293.821373 -350.673258) (xy 293.791658 -350.596602) (xy 293.769141 -350.517531)
			(xy 293.754014 -350.43672) (xy 293.746406 -350.354859) (xy 293.74592 -350.313752) (xy 293.746479 -350.268982)
			(xy 293.75549 -350.179897) (xy 293.773396 -350.092166) (xy 293.800016 -350.006675) (xy 293.81704 -349.965264)
			(xy 293.820632 -349.955681) (xy 293.820615 -349.935231) (xy 293.81704 -349.92564) (xy 293.801245 -349.887334)
			(xy 293.776035 -349.808399) (xy 293.758279 -349.727461) (xy 293.748131 -349.645221) (xy 293.746428 -349.603822)
			(xy 293.745582 -349.592901) (xy 293.735939 -349.57326) (xy 293.719023 -349.559381) (xy 293.708582 -349.55607)
			(xy 293.691709 -349.551574) (xy 293.658299 -349.54141) (xy 293.64178 -349.53575) (xy 293.633584 -349.533227)
			(xy 293.616448 -349.533227) (xy 293.608252 -349.53575) (xy 293.573036 -349.547697) (xy 293.501026 -349.566284)
			(xy 293.427703 -349.578724) (xy 293.353592 -349.584928) (xy 293.316406 -349.58528) (xy 293.279222 -349.584911)
			(xy 293.205114 -349.578689) (xy 293.131794 -349.566246) (xy 293.059783 -349.547672) (xy 293.02456 -349.53575)
			(xy 293.016364 -349.533227) (xy 292.999228 -349.533227) (xy 292.991032 -349.53575) (xy 292.955809 -349.547675)
			(xy 292.883801 -349.566268) (xy 292.810481 -349.578714) (xy 292.736371 -349.584925) (xy 292.699186 -349.58528)
			(xy 292.657259 -349.584857) (xy 292.573786 -349.576885) (xy 292.491448 -349.561014) (xy 292.410992 -349.537389)
			(xy 292.333146 -349.506223) (xy 292.258614 -349.467798) (xy 292.188073 -349.422463) (xy 292.12216 -349.370628)
			(xy 292.061473 -349.312762) (xy 292.006561 -349.24939) (xy 291.957922 -349.181084) (xy 291.915996 -349.108465)
			(xy 291.881162 -349.032189) (xy 291.853737 -348.952948) (xy 291.833968 -348.871458) (xy 291.822034 -348.788458)
			(xy 291.818044 -348.7047) (xy 288.299345 -348.7047) (xy 288.302721 -348.741025) (xy 288.303208 -348.782132)
			(xy 288.302642 -348.826902) (xy 288.293633 -348.915987) (xy 288.275729 -349.003718) (xy 288.249111 -349.089209)
			(xy 288.232088 -349.13062) (xy 288.228504 -349.140205) (xy 288.228515 -349.160653) (xy 288.232088 -349.170244)
			(xy 288.249111 -349.211656) (xy 288.275747 -349.297143) (xy 288.293656 -349.384874) (xy 288.302654 -349.473962)
			(xy 288.303208 -349.518732) (xy 288.302642 -349.563502) (xy 288.293633 -349.652587) (xy 288.275729 -349.740318)
			(xy 288.249111 -349.825809) (xy 288.232088 -349.86722) (xy 288.228504 -349.876805) (xy 288.228515 -349.897253)
			(xy 288.232088 -349.906844) (xy 288.249111 -349.948256) (xy 288.275747 -350.033743) (xy 288.293656 -350.121474)
			(xy 288.302654 -350.210562) (xy 288.303208 -350.255332) (xy 288.302778 -350.296443) (xy 288.295187 -350.378314)
			(xy 288.280074 -350.459136) (xy 288.257566 -350.538217) (xy 288.227857 -350.614885) (xy 288.191199 -350.688483)
			(xy 288.147906 -350.758385) (xy 288.098347 -350.823993) (xy 288.042945 -350.884747) (xy 287.982172 -350.94013)
			(xy 287.916548 -350.989668) (xy 287.846633 -351.032938) (xy 287.773023 -351.069572) (xy 287.696346 -351.099257)
			(xy 287.617257 -351.121739) (xy 287.536431 -351.136827) (xy 287.454557 -351.144391) (xy 287.413446 -351.14484)
			(xy 287.371834 -351.144367) (xy 287.288972 -351.136619) (xy 287.207197 -351.121158) (xy 287.127226 -351.09812)
			(xy 287.049759 -351.067706) (xy 286.975474 -351.030183) (xy 286.93999 -351.008442) (xy 286.930846 -351.003405)
			(xy 286.910222 -351.000334) (xy 286.890069 -351.005685) (xy 286.88157 -351.011744) (xy 286.847906 -351.037707)
			(xy 286.776465 -351.083797) (xy 286.700952 -351.122862) (xy 286.622058 -351.154546) (xy 286.540501 -351.178561)
			(xy 286.457025 -351.194686) (xy 286.372392 -351.202775) (xy 286.329882 -351.20326) (xy 286.288775 -351.202805)
			(xy 286.206911 -351.195219) (xy 286.126097 -351.180113) (xy 286.04702 -351.157617) (xy 285.970356 -351.127921)
			(xy 285.896759 -351.09128) (xy 285.826855 -351.048006) (xy 285.761241 -350.998468) (xy 285.700477 -350.943088)
			(xy 285.645082 -350.882339) (xy 285.595526 -350.816738) (xy 285.552233 -350.746846) (xy 285.515573 -350.673258)
			(xy 285.485858 -350.596602) (xy 285.463341 -350.517531) (xy 285.448214 -350.43672) (xy 285.440606 -350.354859)
			(xy 285.44012 -350.313752) (xy 285.440679 -350.268982) (xy 285.44969 -350.179897) (xy 285.467596 -350.092166)
			(xy 285.494216 -350.006675) (xy 285.51124 -349.965264) (xy 285.514832 -349.955681) (xy 285.514815 -349.935231)
			(xy 285.51124 -349.92564) (xy 285.495445 -349.887334) (xy 285.470235 -349.808399) (xy 285.452479 -349.727461)
			(xy 285.442331 -349.645221) (xy 285.440628 -349.603822) (xy 285.439782 -349.592901) (xy 285.430139 -349.57326)
			(xy 285.413223 -349.559381) (xy 285.402782 -349.55607) (xy 285.385909 -349.551574) (xy 285.352499 -349.54141)
			(xy 285.33598 -349.53575) (xy 285.327784 -349.533227) (xy 285.310648 -349.533227) (xy 285.302452 -349.53575)
			(xy 285.267236 -349.547697) (xy 285.195226 -349.566284) (xy 285.121903 -349.578724) (xy 285.047792 -349.584928)
			(xy 285.010606 -349.58528) (xy 284.973422 -349.584911) (xy 284.899314 -349.578689) (xy 284.825994 -349.566246)
			(xy 284.753983 -349.547672) (xy 284.71876 -349.53575) (xy 284.710564 -349.533227) (xy 284.693428 -349.533227)
			(xy 284.685232 -349.53575) (xy 284.650009 -349.547675) (xy 284.578001 -349.566268) (xy 284.504681 -349.578714)
			(xy 284.430571 -349.584925) (xy 284.393386 -349.58528) (xy 284.351459 -349.584857) (xy 284.267986 -349.576885)
			(xy 284.185648 -349.561014) (xy 284.105192 -349.537389) (xy 284.027346 -349.506223) (xy 283.952814 -349.467798)
			(xy 283.882273 -349.422463) (xy 283.81636 -349.370628) (xy 283.755673 -349.312762) (xy 283.700761 -349.24939)
			(xy 283.652122 -349.181084) (xy 283.610196 -349.108465) (xy 283.575362 -349.032189) (xy 283.547937 -348.952948)
			(xy 283.528168 -348.871458) (xy 283.516234 -348.788458) (xy 283.512244 -348.7047) (xy 280.018945 -348.7047)
			(xy 280.022321 -348.741025) (xy 280.022808 -348.782132) (xy 280.022242 -348.826902) (xy 280.013233 -348.915987)
			(xy 279.995329 -349.003718) (xy 279.968711 -349.089209) (xy 279.951688 -349.13062) (xy 279.948104 -349.140205)
			(xy 279.948115 -349.160653) (xy 279.951688 -349.170244) (xy 279.968711 -349.211656) (xy 279.995347 -349.297143)
			(xy 280.013256 -349.384874) (xy 280.022254 -349.473962) (xy 280.022808 -349.518732) (xy 280.022242 -349.563502)
			(xy 280.013233 -349.652587) (xy 279.995329 -349.740318) (xy 279.968711 -349.825809) (xy 279.951688 -349.86722)
			(xy 279.948104 -349.876805) (xy 279.948115 -349.897253) (xy 279.951688 -349.906844) (xy 279.968711 -349.948256)
			(xy 279.995347 -350.033743) (xy 280.013256 -350.121474) (xy 280.022254 -350.210562) (xy 280.022808 -350.255332)
			(xy 280.022378 -350.296443) (xy 280.014787 -350.378314) (xy 279.999674 -350.459136) (xy 279.977166 -350.538217)
			(xy 279.947457 -350.614885) (xy 279.910799 -350.688483) (xy 279.867506 -350.758385) (xy 279.817947 -350.823993)
			(xy 279.762545 -350.884747) (xy 279.701772 -350.94013) (xy 279.636148 -350.989668) (xy 279.566233 -351.032938)
			(xy 279.492623 -351.069572) (xy 279.415946 -351.099257) (xy 279.336857 -351.121739) (xy 279.256031 -351.136827)
			(xy 279.174157 -351.144391) (xy 279.133046 -351.14484) (xy 279.091434 -351.144367) (xy 279.008572 -351.136619)
			(xy 278.926797 -351.121158) (xy 278.846826 -351.09812) (xy 278.769359 -351.067706) (xy 278.695074 -351.030183)
			(xy 278.65959 -351.008442) (xy 278.650446 -351.003405) (xy 278.629822 -351.000334) (xy 278.609669 -351.005685)
			(xy 278.60117 -351.011744) (xy 278.567506 -351.037707) (xy 278.496065 -351.083797) (xy 278.420552 -351.122862)
			(xy 278.341658 -351.154546) (xy 278.260101 -351.178561) (xy 278.176625 -351.194686) (xy 278.091992 -351.202775)
			(xy 278.049482 -351.20326) (xy 278.008375 -351.202805) (xy 277.926511 -351.195219) (xy 277.845697 -351.180113)
			(xy 277.76662 -351.157617) (xy 277.689956 -351.127921) (xy 277.616359 -351.09128) (xy 277.546455 -351.048006)
			(xy 277.480841 -350.998468) (xy 277.420077 -350.943088) (xy 277.364682 -350.882339) (xy 277.315126 -350.816738)
			(xy 277.271833 -350.746846) (xy 277.235173 -350.673258) (xy 277.205458 -350.596602) (xy 277.182941 -350.517531)
			(xy 277.167814 -350.43672) (xy 277.160206 -350.354859) (xy 277.15972 -350.313752) (xy 277.160279 -350.268982)
			(xy 277.16929 -350.179897) (xy 277.187196 -350.092166) (xy 277.213816 -350.006675) (xy 277.23084 -349.965264)
			(xy 277.234432 -349.955681) (xy 277.234415 -349.935231) (xy 277.23084 -349.92564) (xy 277.215045 -349.887334)
			(xy 277.189835 -349.808399) (xy 277.172079 -349.727461) (xy 277.161931 -349.645221) (xy 277.160228 -349.603822)
			(xy 277.159382 -349.592901) (xy 277.149739 -349.57326) (xy 277.132823 -349.559381) (xy 277.122382 -349.55607)
			(xy 277.105509 -349.551574) (xy 277.072099 -349.54141) (xy 277.05558 -349.53575) (xy 277.047384 -349.533227)
			(xy 277.030248 -349.533227) (xy 277.022052 -349.53575) (xy 276.986836 -349.547697) (xy 276.914826 -349.566284)
			(xy 276.841503 -349.578724) (xy 276.767392 -349.584928) (xy 276.730206 -349.58528) (xy 276.693022 -349.584911)
			(xy 276.618914 -349.578689) (xy 276.545594 -349.566246) (xy 276.473583 -349.547672) (xy 276.43836 -349.53575)
			(xy 276.430164 -349.533227) (xy 276.413028 -349.533227) (xy 276.404832 -349.53575) (xy 276.369609 -349.547675)
			(xy 276.297601 -349.566268) (xy 276.224281 -349.578714) (xy 276.150171 -349.584925) (xy 276.112986 -349.58528)
			(xy 276.071059 -349.584857) (xy 275.987586 -349.576885) (xy 275.905248 -349.561014) (xy 275.824792 -349.537389)
			(xy 275.746946 -349.506223) (xy 275.672414 -349.467798) (xy 275.601873 -349.422463) (xy 275.53596 -349.370628)
			(xy 275.475273 -349.312762) (xy 275.420361 -349.24939) (xy 275.371722 -349.181084) (xy 275.329796 -349.108465)
			(xy 275.294962 -349.032189) (xy 275.267537 -348.952948) (xy 275.247768 -348.871458) (xy 275.235834 -348.788458)
			(xy 275.231844 -348.7047) (xy 271.348962 -348.7047) (xy 271.348962 -352.973132) (xy 338.849208 -352.973132)
			(xy 338.849825 -352.926972) (xy 338.859426 -352.835153) (xy 338.878488 -352.744823) (xy 338.906804 -352.656953)
			(xy 338.9249 -352.614484) (xy 338.928699 -352.60454) (xy 338.928703 -352.583278) (xy 338.9249 -352.573336)
			(xy 338.90688 -352.530918) (xy 338.878719 -352.443158) (xy 338.859786 -352.352956) (xy 338.850284 -352.26128)
			(xy 338.849716 -352.215196) (xy 338.850295 -352.1688) (xy 338.859941 -352.076512) (xy 338.879138 -351.985728)
			(xy 338.907678 -351.897435) (xy 338.925916 -351.85477) (xy 338.929722 -351.844828) (xy 338.929721 -351.823565)
			(xy 338.925916 -351.813622) (xy 338.907671 -351.77096) (xy 338.879127 -351.682667) (xy 338.859934 -351.591882)
			(xy 338.850301 -351.499592) (xy 338.849716 -351.453196) (xy 338.850148 -351.412092) (xy 338.857734 -351.330235)
			(xy 338.87284 -351.249427) (xy 338.895338 -351.170357) (xy 338.925036 -351.093701) (xy 338.96168 -351.020112)
			(xy 339.004958 -350.950218) (xy 339.0545 -350.884616) (xy 339.109884 -350.823864) (xy 339.170637 -350.768482)
			(xy 339.236241 -350.718942) (xy 339.306137 -350.675666) (xy 339.379727 -350.639025) (xy 339.456384 -350.609329)
			(xy 339.535454 -350.586834) (xy 339.616263 -350.57173) (xy 339.69812 -350.564147) (xy 339.739224 -350.563688)
			(xy 339.785619 -350.564298) (xy 339.877906 -350.573935) (xy 339.96869 -350.593123) (xy 340.056984 -350.621654)
			(xy 340.09965 -350.639888) (xy 340.109592 -350.643694) (xy 340.130856 -350.643694) (xy 340.140798 -350.639888)
			(xy 340.183457 -350.621635) (xy 340.27175 -350.593093) (xy 340.362537 -350.573902) (xy 340.454828 -350.564272)
			(xy 340.501224 -350.563688) (xy 340.547619 -350.564298) (xy 340.639906 -350.573935) (xy 340.73069 -350.593123)
			(xy 340.818984 -350.621654) (xy 340.86165 -350.639888) (xy 340.871592 -350.643694) (xy 340.892856 -350.643694)
			(xy 340.902798 -350.639888) (xy 340.945457 -350.621635) (xy 341.03375 -350.593093) (xy 341.124537 -350.573902)
			(xy 341.216828 -350.564272) (xy 341.263224 -350.563688) (xy 341.309619 -350.564298) (xy 341.401906 -350.573935)
			(xy 341.49269 -350.593123) (xy 341.580984 -350.621654) (xy 341.62365 -350.639888) (xy 341.633592 -350.643694)
			(xy 341.654856 -350.643694) (xy 341.664798 -350.639888) (xy 341.707457 -350.621635) (xy 341.79575 -350.593093)
			(xy 341.886537 -350.573902) (xy 341.978828 -350.564272) (xy 342.025224 -350.563688) (xy 342.071619 -350.564298)
			(xy 342.163906 -350.573935) (xy 342.25469 -350.593123) (xy 342.342984 -350.621654) (xy 342.38565 -350.639888)
			(xy 342.395592 -350.643694) (xy 342.416856 -350.643694) (xy 342.426798 -350.639888) (xy 342.469457 -350.621635)
			(xy 342.55775 -350.593093) (xy 342.648537 -350.573902) (xy 342.740828 -350.564272) (xy 342.787224 -350.563688)
			(xy 342.833721 -350.564268) (xy 342.926211 -350.573942) (xy 343.017189 -350.593203) (xy 343.105663 -350.621842)
			(xy 343.148412 -350.640142) (xy 343.157173 -350.643559) (xy 343.175938 -350.644473) (xy 343.184988 -350.64192)
			(xy 343.230317 -350.627524) (xy 343.323273 -350.607389) (xy 343.417848 -350.597296) (xy 343.465404 -350.596708)
			(xy 343.506508 -350.597148) (xy 343.588364 -350.604734) (xy 343.669172 -350.61984) (xy 343.748241 -350.642338)
			(xy 343.824897 -350.672035) (xy 343.898486 -350.708679) (xy 343.968379 -350.751956) (xy 344.033982 -350.801498)
			(xy 344.094733 -350.856881) (xy 344.150115 -350.917634) (xy 344.199655 -350.983237) (xy 344.242931 -351.053132)
			(xy 344.279573 -351.126721) (xy 344.309269 -351.203378) (xy 344.331765 -351.282448) (xy 344.346869 -351.363255)
			(xy 344.354453 -351.445112) (xy 344.354912 -351.486216) (xy 344.354334 -351.532612) (xy 344.344688 -351.6249)
			(xy 344.32549 -351.715684) (xy 344.296951 -351.803977) (xy 344.278712 -351.846642) (xy 344.274897 -351.856581)
			(xy 344.274903 -351.877848) (xy 344.278712 -351.88779) (xy 344.296962 -351.93045) (xy 344.325505 -352.018743)
			(xy 344.344696 -352.109529) (xy 344.354328 -352.20182) (xy 344.354912 -352.248216) (xy 344.354328 -352.294369)
			(xy 344.344776 -352.386179) (xy 344.325776 -352.476508) (xy 344.297531 -352.564386) (xy 344.279474 -352.606864)
			(xy 344.275648 -352.6168) (xy 344.275662 -352.638069) (xy 344.279474 -352.648012) (xy 344.29749 -352.690438)
			(xy 344.325707 -352.77819) (xy 344.344711 -352.868387) (xy 344.354297 -352.960064) (xy 344.354912 -353.006152)
			(xy 344.354402 -353.047262) (xy 344.34922 -353.1032) (xy 423.453493 -353.1032) (xy 423.457484 -353.019415)
			(xy 423.469422 -352.936388) (xy 423.489198 -352.854872) (xy 423.516634 -352.775605) (xy 423.55148 -352.699305)
			(xy 423.593421 -352.626663) (xy 423.642078 -352.558337) (xy 423.697009 -352.494945) (xy 423.757718 -352.437063)
			(xy 423.823654 -352.385213) (xy 423.89422 -352.339866) (xy 423.968777 -352.301432) (xy 424.04665 -352.270259)
			(xy 424.127133 -352.24663) (xy 424.209499 -352.230759) (xy 424.293 -352.222789) (xy 424.33494 -352.222308)
			(xy 424.372129 -352.222714) (xy 424.446242 -352.228999) (xy 424.519562 -352.241503) (xy 424.591568 -352.260139)
			(xy 424.626786 -352.272092) (xy 424.634982 -352.274615) (xy 424.652118 -352.274615) (xy 424.660314 -352.272092)
			(xy 424.687596 -352.262757) (xy 424.74314 -352.24725) (xy 424.771312 -352.241104) (xy 424.781089 -352.238609)
			(xy 424.797722 -352.227214) (xy 424.808697 -352.210302) (xy 424.810936 -352.200464) (xy 424.820391 -352.151355)
			(xy 424.84891 -352.055495) (xy 424.867832 -352.009202) (xy 424.871403 -351.999613) (xy 424.871399 -351.979169)
			(xy 424.867832 -351.969578) (xy 424.850786 -351.928175) (xy 424.824155 -351.842685) (xy 424.806254 -351.754951)
			(xy 424.797263 -351.665861) (xy 424.796712 -351.62109) (xy 424.797216 -351.578729) (xy 424.805269 -351.494392)
			(xy 424.821303 -351.411202) (xy 424.845171 -351.329912) (xy 424.876659 -351.25126) (xy 424.915481 -351.175957)
			(xy 424.961284 -351.104685) (xy 425.013655 -351.038089) (xy 425.07212 -350.976774) (xy 425.136148 -350.921293)
			(xy 425.20516 -350.87215) (xy 425.27853 -350.82979) (xy 425.355595 -350.794595) (xy 425.435657 -350.766886)
			(xy 425.51799 -350.746912) (xy 425.601849 -350.734855) (xy 425.686474 -350.730824) (xy 425.771099 -350.734855)
			(xy 425.854958 -350.746912) (xy 425.937291 -350.766886) (xy 426.017353 -350.794595) (xy 426.094418 -350.82979)
			(xy 426.167788 -350.87215) (xy 426.2368 -350.921293) (xy 426.300828 -350.976774) (xy 426.359293 -351.038089)
			(xy 426.411664 -351.104685) (xy 426.457467 -351.175957) (xy 426.496289 -351.25126) (xy 426.527777 -351.329912)
			(xy 426.551645 -351.411202) (xy 426.567679 -351.494392) (xy 426.575732 -351.578729) (xy 426.576236 -351.62109)
			(xy 426.575653 -351.665859) (xy 426.566649 -351.754944) (xy 426.548749 -351.842675) (xy 426.522136 -351.928167)
			(xy 426.505116 -351.969578) (xy 426.501559 -351.979171) (xy 426.501555 -351.999611) (xy 426.505116 -352.009202)
			(xy 426.522153 -352.050608) (xy 426.548787 -352.136097) (xy 426.566691 -352.22383) (xy 426.575684 -352.312919)
			(xy 426.576236 -352.35769) (xy 426.575815 -352.394789) (xy 426.569551 -352.468723) (xy 426.557151 -352.541879)
			(xy 426.548296 -352.577908) (xy 426.546514 -352.586294) (xy 426.548018 -352.603361) (xy 426.555074 -352.618974)
			(xy 426.560742 -352.625406) (xy 426.601128 -352.668332) (xy 426.613574 -352.665538) (xy 426.622391 -352.663274)
			(xy 426.637739 -352.653501) (xy 426.643546 -352.646488) (xy 426.66867 -352.613784) (xy 426.724067 -352.552685)
			(xy 426.784882 -352.496976) (xy 426.850593 -352.447136) (xy 426.920635 -352.403592) (xy 426.994408 -352.366719)
			(xy 427.071277 -352.336834) (xy 427.150582 -352.314192) (xy 427.231643 -352.298989) (xy 427.313763 -352.291354)
			(xy 427.355 -352.290888) (xy 427.396111 -352.291352) (xy 427.477981 -352.29894) (xy 427.558801 -352.314051)
			(xy 427.637882 -352.336556) (xy 427.714549 -352.366262) (xy 427.788147 -352.402918) (xy 427.858049 -352.446208)
			(xy 427.923657 -352.495765) (xy 427.984412 -352.551165) (xy 428.039795 -352.611935) (xy 428.089333 -352.677557)
			(xy 428.132604 -352.747471) (xy 428.169239 -352.82108) (xy 428.198924 -352.897755) (xy 428.221406 -352.976842)
			(xy 428.236494 -353.057667) (xy 428.243048 -353.1286) (xy 431.780208 -353.1286) (xy 431.784199 -353.04482)
			(xy 431.796136 -352.961799) (xy 431.815909 -352.880289) (xy 431.843342 -352.801027) (xy 431.878184 -352.724732)
			(xy 431.92012 -352.652094) (xy 431.968771 -352.583771) (xy 432.023696 -352.520381) (xy 432.084398 -352.4625)
			(xy 432.150327 -352.410651) (xy 432.220886 -352.365303) (xy 432.295436 -352.326868) (xy 432.373301 -352.295693)
			(xy 432.453778 -352.27206) (xy 432.536136 -352.256184) (xy 432.619631 -352.248208) (xy 432.661568 -352.247708)
			(xy 432.698757 -352.248106) (xy 432.77287 -352.254393) (xy 432.84619 -352.2669) (xy 432.918196 -352.285538)
			(xy 432.953414 -352.297492) (xy 432.96161 -352.300015) (xy 432.978746 -352.300015) (xy 432.986942 -352.297492)
			(xy 433.014223 -352.288155) (xy 433.069768 -352.27265) (xy 433.09794 -352.266504) (xy 433.107722 -352.264025)
			(xy 433.124353 -352.252622) (xy 433.135327 -352.235704) (xy 433.137564 -352.225864) (xy 433.147017 -352.176755)
			(xy 433.175537 -352.080895) (xy 433.19446 -352.034602) (xy 433.19803 -352.025013) (xy 433.198026 -352.004569)
			(xy 433.19446 -351.994978) (xy 433.177416 -351.953575) (xy 433.150784 -351.868085) (xy 433.132882 -351.780351)
			(xy 433.123891 -351.691261) (xy 433.12334 -351.64649) (xy 433.123844 -351.604129) (xy 433.131897 -351.519792)
			(xy 433.147931 -351.436602) (xy 433.171799 -351.355312) (xy 433.203287 -351.27666) (xy 433.242109 -351.201357)
			(xy 433.287912 -351.130085) (xy 433.340283 -351.063489) (xy 433.398748 -351.002174) (xy 433.462776 -350.946693)
			(xy 433.531788 -350.89755) (xy 433.605158 -350.85519) (xy 433.682223 -350.819995) (xy 433.762285 -350.792286)
			(xy 433.844618 -350.772312) (xy 433.928477 -350.760255) (xy 434.013102 -350.756224) (xy 434.097727 -350.760255)
			(xy 434.181586 -350.772312) (xy 434.263919 -350.792286) (xy 434.343981 -350.819995) (xy 434.421046 -350.85519)
			(xy 434.494416 -350.89755) (xy 434.563428 -350.946693) (xy 434.627456 -351.002174) (xy 434.685921 -351.063489)
			(xy 434.738292 -351.130085) (xy 434.784095 -351.201357) (xy 434.822917 -351.27666) (xy 434.854405 -351.355312)
			(xy 434.878273 -351.436602) (xy 434.894307 -351.519792) (xy 434.90236 -351.604129) (xy 434.902864 -351.64649)
			(xy 434.902279 -351.691259) (xy 434.893275 -351.780343) (xy 434.875376 -351.868074) (xy 434.848764 -351.953566)
			(xy 434.831744 -351.994978) (xy 434.828186 -352.00457) (xy 434.828182 -352.025011) (xy 434.831744 -352.034602)
			(xy 434.848782 -352.076008) (xy 434.875415 -352.161497) (xy 434.893319 -352.24923) (xy 434.902312 -352.338319)
			(xy 434.902864 -352.38309) (xy 434.902442 -352.420189) (xy 434.896179 -352.494123) (xy 434.883778 -352.567279)
			(xy 434.874924 -352.603308) (xy 434.873134 -352.611693) (xy 434.874639 -352.628762) (xy 434.881699 -352.644375)
			(xy 434.88737 -352.650806) (xy 434.927756 -352.693732) (xy 434.940202 -352.690938) (xy 434.94901 -352.688645)
			(xy 434.964363 -352.678893) (xy 434.970174 -352.671888) (xy 434.995281 -352.639171) (xy 435.05068 -352.578072)
			(xy 435.111497 -352.522364) (xy 435.17721 -352.472524) (xy 435.247255 -352.428982) (xy 435.321029 -352.39211)
			(xy 435.3979 -352.362226) (xy 435.477207 -352.339586) (xy 435.558269 -352.324385) (xy 435.64039 -352.316753)
			(xy 435.681628 -352.316288) (xy 435.722739 -352.316726) (xy 435.80461 -352.324316) (xy 435.885431 -352.339429)
			(xy 435.964512 -352.361936) (xy 436.041179 -352.391645) (xy 436.114778 -352.428302) (xy 436.184679 -352.471595)
			(xy 436.250287 -352.521154) (xy 436.311041 -352.576555) (xy 436.366424 -352.637327) (xy 436.415962 -352.70295)
			(xy 436.459233 -352.772865) (xy 436.495867 -352.846475) (xy 436.525552 -352.923151) (xy 436.548034 -353.00224)
			(xy 436.563122 -353.083066) (xy 436.570687 -353.164939) (xy 436.571136 -353.20605) (xy 436.570625 -353.250815)
			(xy 436.561691 -353.339897) (xy 436.543847 -353.42763) (xy 436.517274 -353.513125) (xy 436.50027 -353.554538)
			(xy 436.496676 -353.56412) (xy 436.496695 -353.584571) (xy 436.50027 -353.594162) (xy 436.517262 -353.635579)
			(xy 436.543821 -353.721076) (xy 436.561662 -353.808807) (xy 436.570605 -353.897886) (xy 436.571136 -353.94265)
			(xy 436.570625 -353.987415) (xy 436.561691 -354.076497) (xy 436.543847 -354.16423) (xy 436.517274 -354.249725)
			(xy 436.50027 -354.291138) (xy 436.496676 -354.30072) (xy 436.496695 -354.321171) (xy 436.50027 -354.330762)
			(xy 436.517262 -354.372179) (xy 436.543821 -354.457676) (xy 436.561662 -354.545407) (xy 436.570605 -354.634486)
			(xy 436.571136 -354.67925) (xy 436.57064 -354.720357) (xy 436.56306 -354.80222) (xy 436.547959 -354.883035)
			(xy 436.525468 -354.962112) (xy 436.495777 -355.038776) (xy 436.45914 -355.112375) (xy 436.415869 -355.18228)
			(xy 436.366333 -355.247894) (xy 436.310956 -355.308659) (xy 436.250208 -355.364056) (xy 436.184609 -355.413612)
			(xy 436.114718 -355.456904) (xy 436.041131 -355.493565) (xy 435.964475 -355.523279) (xy 435.885405 -355.545796)
			(xy 435.804595 -355.560921) (xy 435.722735 -355.568527) (xy 435.681628 -355.569012) (xy 435.640012 -355.568516)
			(xy 435.557148 -355.560695) (xy 435.475375 -355.545175) (xy 435.395407 -355.522092) (xy 435.317943 -355.491648)
			(xy 435.243658 -355.454106) (xy 435.208172 -355.43236) (xy 435.199036 -355.427305) (xy 435.178406 -355.424238)
			(xy 435.15825 -355.429598) (xy 435.149752 -355.435662) (xy 435.116095 -355.461645) (xy 435.044668 -355.507784)
			(xy 434.969164 -355.546894) (xy 434.890271 -355.578619) (xy 434.80871 -355.602669) (xy 434.725225 -355.618825)
			(xy 434.64058 -355.626937) (xy 434.598064 -355.627432) (xy 434.556953 -355.626982) (xy 434.475084 -355.619391)
			(xy 434.394263 -355.604278) (xy 434.315183 -355.581771) (xy 434.238517 -355.552062) (xy 434.164919 -355.515405)
			(xy 434.095019 -355.472113) (xy 434.029411 -355.422555) (xy 433.968657 -355.367155) (xy 433.913275 -355.306384)
			(xy 433.863736 -355.240762) (xy 433.820465 -355.170848) (xy 433.783831 -355.09724) (xy 433.754145 -355.020565)
			(xy 433.731661 -354.941477) (xy 433.716572 -354.860653) (xy 433.709006 -354.778781) (xy 433.708556 -354.73767)
			(xy 433.709074 -354.692905) (xy 433.718007 -354.603823) (xy 433.735848 -354.51609) (xy 433.762419 -354.430595)
			(xy 433.779422 -354.389182) (xy 433.783005 -354.379596) (xy 433.782994 -354.359149) (xy 433.779422 -354.349558)
			(xy 433.763631 -354.311251) (xy 433.738421 -354.232316) (xy 433.720663 -354.151378) (xy 433.710513 -354.069139)
			(xy 433.70881 -354.02774) (xy 433.707967 -354.016821) (xy 433.698312 -353.997188) (xy 433.681401 -353.983306)
			(xy 433.670964 -353.979988) (xy 433.654091 -353.975492) (xy 433.620681 -353.965328) (xy 433.604162 -353.959668)
			(xy 433.595966 -353.957145) (xy 433.57883 -353.957145) (xy 433.570634 -353.959668) (xy 433.535422 -353.971642)
			(xy 433.463417 -353.990292) (xy 433.390095 -354.002797) (xy 433.315979 -354.009067) (xy 433.278788 -354.009452)
			(xy 433.241598 -354.009064) (xy 433.167486 -354.002773) (xy 433.094166 -353.990263) (xy 433.02216 -353.971623)
			(xy 432.986942 -353.959668) (xy 432.978746 -353.957145) (xy 432.96161 -353.957145) (xy 432.953414 -353.959668)
			(xy 432.918203 -353.971647) (xy 432.846198 -353.990296) (xy 432.772875 -354.0028) (xy 432.698759 -354.009068)
			(xy 432.661568 -354.009452) (xy 432.619631 -354.008992) (xy 432.536136 -354.001016) (xy 432.453778 -353.98514)
			(xy 432.373301 -353.961507) (xy 432.295436 -353.930332) (xy 432.220886 -353.891897) (xy 432.150327 -353.846549)
			(xy 432.084398 -353.7947) (xy 432.023696 -353.736819) (xy 431.968771 -353.673429) (xy 431.92012 -353.605106)
			(xy 431.878184 -353.532468) (xy 431.843342 -353.456173) (xy 431.815909 -353.376911) (xy 431.796136 -353.295401)
			(xy 431.784199 -353.21238) (xy 431.780208 -353.1286) (xy 428.243048 -353.1286) (xy 428.244059 -353.139539)
			(xy 428.244508 -353.18065) (xy 428.243992 -353.225415) (xy 428.235058 -353.314497) (xy 428.217216 -353.40223)
			(xy 428.190645 -353.487725) (xy 428.173642 -353.529138) (xy 428.17005 -353.538721) (xy 428.170068 -353.559171)
			(xy 428.173642 -353.568762) (xy 428.190638 -353.610177) (xy 428.217195 -353.695675) (xy 428.235035 -353.783407)
			(xy 428.243977 -353.872486) (xy 428.244508 -353.91725) (xy 428.243992 -353.962015) (xy 428.235058 -354.051097)
			(xy 428.217216 -354.13883) (xy 428.190645 -354.224325) (xy 428.173642 -354.265738) (xy 428.17005 -354.275321)
			(xy 428.170068 -354.295771) (xy 428.173642 -354.305362) (xy 428.190638 -354.346777) (xy 428.217195 -354.432275)
			(xy 428.235035 -354.520007) (xy 428.243977 -354.609086) (xy 428.244508 -354.65385) (xy 428.24394 -354.694955)
			(xy 428.23636 -354.776814) (xy 428.221262 -354.857624) (xy 428.198773 -354.936698) (xy 428.169085 -355.013359)
			(xy 428.132451 -355.086955) (xy 428.089184 -355.156857) (xy 428.039654 -355.22247) (xy 427.984281 -355.283233)
			(xy 427.923539 -355.33863) (xy 427.857946 -355.388186) (xy 427.788061 -355.431481) (xy 427.714479 -355.468143)
			(xy 427.63783 -355.497861) (xy 427.558765 -355.520382) (xy 427.47796 -355.535512) (xy 427.396104 -355.543124)
			(xy 427.355 -355.543612) (xy 427.313384 -355.543129) (xy 427.230519 -355.535306) (xy 427.148746 -355.519784)
			(xy 427.068779 -355.496698) (xy 426.991314 -355.466251) (xy 426.917029 -355.428708) (xy 426.881544 -355.40696)
			(xy 426.87242 -355.40188) (xy 426.851782 -355.398822) (xy 426.831622 -355.404192) (xy 426.823124 -355.410262)
			(xy 426.789477 -355.436258) (xy 426.718048 -355.482396) (xy 426.642542 -355.521504) (xy 426.563647 -355.553228)
			(xy 426.482084 -355.577275) (xy 426.398599 -355.593428) (xy 426.313953 -355.601539) (xy 426.271436 -355.602032)
			(xy 426.230327 -355.601513) (xy 426.148459 -355.593929) (xy 426.06764 -355.578822) (xy 425.98856 -355.556321)
			(xy 425.911894 -355.526617) (xy 425.838297 -355.489966) (xy 425.768396 -355.446679) (xy 425.702788 -355.397126)
			(xy 425.642034 -355.341729) (xy 425.58665 -355.280962) (xy 425.537111 -355.215344) (xy 425.49384 -355.145433)
			(xy 425.457204 -355.071828) (xy 425.427518 -354.995156) (xy 425.405034 -354.916071) (xy 425.389944 -354.835249)
			(xy 425.382378 -354.753379) (xy 425.381928 -354.71227) (xy 425.382449 -354.667505) (xy 425.391381 -354.578423)
			(xy 425.409222 -354.49069) (xy 425.435791 -354.405195) (xy 425.452794 -354.363782) (xy 425.456378 -354.354197)
			(xy 425.456367 -354.333749) (xy 425.452794 -354.324158) (xy 425.437002 -354.285851) (xy 425.411792 -354.206916)
			(xy 425.394035 -354.125978) (xy 425.383885 -354.043739) (xy 425.382182 -354.00234) (xy 425.381358 -353.991418)
			(xy 425.371697 -353.971782) (xy 425.354777 -353.957903) (xy 425.344336 -353.954588) (xy 425.327464 -353.950088)
			(xy 425.294053 -353.939926) (xy 425.277534 -353.934268) (xy 425.269338 -353.931745) (xy 425.252202 -353.931745)
			(xy 425.244006 -353.934268) (xy 425.208787 -353.946222) (xy 425.136785 -353.964878) (xy 425.063465 -353.977388)
			(xy 424.98935 -353.983664) (xy 424.95216 -353.984052) (xy 424.914971 -353.983643) (xy 424.840858 -353.977359)
			(xy 424.767539 -353.964855) (xy 424.695532 -353.94622) (xy 424.660314 -353.934268) (xy 424.652118 -353.931745)
			(xy 424.634982 -353.931745) (xy 424.626786 -353.934268) (xy 424.591569 -353.946227) (xy 424.519566 -353.964882)
			(xy 424.446245 -353.977391) (xy 424.37213 -353.983665) (xy 424.33494 -353.984052) (xy 424.293 -353.983611)
			(xy 424.209499 -353.975641) (xy 424.127133 -353.95977) (xy 424.04665 -353.936141) (xy 423.968777 -353.904968)
			(xy 423.89422 -353.866534) (xy 423.823654 -353.821187) (xy 423.757718 -353.769337) (xy 423.697009 -353.711455)
			(xy 423.642078 -353.648063) (xy 423.593421 -353.579737) (xy 423.55148 -353.507095) (xy 423.516634 -353.430795)
			(xy 423.489198 -353.351528) (xy 423.469422 -353.270012) (xy 423.457484 -353.186985) (xy 423.453493 -353.1032)
			(xy 344.34922 -353.1032) (xy 344.346818 -353.129131) (xy 344.331712 -353.20995) (xy 344.309211 -353.289031)
			(xy 344.279508 -353.365698) (xy 344.242856 -353.439296) (xy 344.199569 -353.509197) (xy 344.150015 -353.574806)
			(xy 344.094618 -353.635561) (xy 344.03385 -353.690944) (xy 343.968231 -353.740483) (xy 343.898319 -353.783755)
			(xy 343.824713 -353.82039) (xy 343.748039 -353.850075) (xy 343.668954 -353.872558) (xy 343.58813 -353.887646)
			(xy 343.50626 -353.895211) (xy 343.46515 -353.89566) (xy 343.421566 -353.895134) (xy 343.334811 -353.886653)
			(xy 343.249302 -353.869729) (xy 343.165858 -353.844524) (xy 343.085279 -353.81128) (xy 343.046558 -353.791266)
			(xy 343.035117 -353.785971) (xy 343.009938 -353.786108) (xy 342.998552 -353.79152) (xy 342.959312 -353.812286)
			(xy 342.877483 -353.846743) (xy 342.792629 -353.872876) (xy 342.705593 -353.890425) (xy 342.617242 -353.899215)
			(xy 342.572848 -353.899724) (xy 342.534563 -353.899351) (xy 342.458274 -353.892807) (xy 342.382832 -353.879722)
			(xy 342.308796 -353.860191) (xy 342.27262 -353.847654) (xy 342.264183 -353.845003) (xy 342.246513 -353.845003)
			(xy 342.238076 -353.847654) (xy 342.201893 -353.860167) (xy 342.127855 -353.879678) (xy 342.052415 -353.892761)
			(xy 341.976131 -353.89932) (xy 341.937848 -353.899724) (xy 341.899563 -353.899351) (xy 341.823274 -353.892807)
			(xy 341.747832 -353.879722) (xy 341.673796 -353.860191) (xy 341.63762 -353.847654) (xy 341.629183 -353.845003)
			(xy 341.611513 -353.845003) (xy 341.603076 -353.847654) (xy 341.566893 -353.860167) (xy 341.492855 -353.879678)
			(xy 341.417415 -353.892761) (xy 341.341131 -353.89932) (xy 341.302848 -353.899724) (xy 341.264563 -353.899351)
			(xy 341.188274 -353.892807) (xy 341.112832 -353.879722) (xy 341.038796 -353.860191) (xy 341.00262 -353.847654)
			(xy 340.994183 -353.845003) (xy 340.976513 -353.845003) (xy 340.968076 -353.847654) (xy 340.931893 -353.860167)
			(xy 340.857855 -353.879678) (xy 340.782415 -353.892761) (xy 340.706131 -353.89932) (xy 340.667848 -353.899724)
			(xy 340.626561 -353.899267) (xy 340.544342 -353.891612) (xy 340.463186 -353.876372) (xy 340.383791 -353.853679)
			(xy 340.306839 -353.823729) (xy 340.232994 -353.786777) (xy 340.197694 -353.765358) (xy 340.190048 -353.760984)
			(xy 340.172838 -353.757274) (xy 340.155388 -353.759605) (xy 340.147402 -353.763326) (xy 340.109478 -353.782391)
			(xy 340.030697 -353.814004) (xy 339.949262 -353.837968) (xy 339.865915 -353.854065) (xy 339.781414 -353.862149)
			(xy 339.73897 -353.86264) (xy 339.697862 -353.862216) (xy 339.615997 -353.854629) (xy 339.535181 -353.839522)
			(xy 339.456103 -353.817024) (xy 339.379438 -353.787327) (xy 339.30584 -353.750684) (xy 339.235936 -353.707408)
			(xy 339.170322 -353.657867) (xy 339.109558 -353.602485) (xy 339.054162 -353.541734) (xy 339.004606 -353.476131)
			(xy 338.961314 -353.406237) (xy 338.924655 -353.332646) (xy 338.89494 -353.255988) (xy 338.872425 -353.176916)
			(xy 338.857299 -353.096103) (xy 338.849693 -353.01424) (xy 338.849208 -352.973132) (xy 271.348962 -352.973132)
			(xy 271.348962 -354.118672) (xy 271.3494 -354.128735) (xy 271.35714 -354.147315) (xy 271.363948 -354.15474)
			(xy 273.14017 -355.930962) (xy 273.14757 -355.937802) (xy 273.166169 -355.945516) (xy 273.176238 -355.945948)
			(xy 285.457392 -355.945948)
		)
		(stroke
			(width 0)
			(type solid)
		)
		(fill yes)
		(layer "In8.Cu")
		(net "GND")
	)
	(gr_poly
		(pts
			(xy 64.318388 -335.233264) (xy 64.328458 -335.232842) (xy 64.347063 -335.225127) (xy 64.354456 -335.218278)
			(xy 64.678814 -334.89392) (xy 64.685657 -334.886521) (xy 64.693376 -334.867922) (xy 64.6938 -334.857852)
			(xy 64.6938 -330.38415) (xy 64.694416 -330.359195) (xy 64.704162 -330.310247) (xy 64.723269 -330.264139)
			(xy 64.751004 -330.222645) (xy 64.768222 -330.204572) (xy 65.519808 -329.452986) (xy 65.537847 -329.435722)
			(xy 65.579339 -329.407956) (xy 65.625457 -329.388834) (xy 65.674423 -329.379093) (xy 65.699386 -329.378564)
			(xy 70.653148 -329.378564) (xy 70.663214 -329.378131) (xy 70.681802 -329.370401) (xy 70.689216 -329.363578)
			(xy 71.76262 -328.290174) (xy 71.768462 -328.260456) (xy 71.76262 -328.245978) (xy 71.75368 -328.223033)
			(xy 71.741115 -328.175419) (xy 71.734796 -328.126582) (xy 71.734426 -328.10196) (xy 71.734915 -328.074712)
			(xy 71.742676 -328.02077) (xy 71.758035 -327.968482) (xy 71.780679 -327.918912) (xy 71.810147 -327.873069)
			(xy 71.845839 -327.831887) (xy 71.887029 -327.796203) (xy 71.932877 -327.766744) (xy 71.982451 -327.744109)
			(xy 72.034742 -327.728761) (xy 72.088685 -327.72101) (xy 72.115934 -327.720452) (xy 72.140555 -327.720837)
			(xy 72.18939 -327.727163) (xy 72.237008 -327.739707) (xy 72.259952 -327.748646) (xy 72.27443 -327.754488)
			(xy 72.304148 -327.748646) (xy 74.282808 -325.769986) (xy 74.300847 -325.752722) (xy 74.342339 -325.724956)
			(xy 74.388457 -325.705834) (xy 74.437423 -325.696093) (xy 74.462386 -325.695564) (xy 96.306386 -325.695564)
			(xy 96.33134 -325.696184) (xy 96.380285 -325.705934) (xy 96.426389 -325.725044) (xy 96.467881 -325.752779)
			(xy 96.485964 -325.769986) (xy 98.865944 -328.149966) (xy 98.873343 -328.156809) (xy 98.891942 -328.164533)
			(xy 98.902012 -328.164952) (xy 104.463596 -328.164952) (xy 104.473665 -328.164528) (xy 104.492266 -328.156809)
			(xy 104.499664 -328.149966) (xy 105.228644 -327.420986) (xy 105.246684 -327.403725) (xy 105.288177 -327.375964)
			(xy 105.334295 -327.356849) (xy 105.38326 -327.347115) (xy 105.408222 -327.346564) (xy 110.212124 -327.346564)
			(xy 110.222432 -327.346095) (xy 110.241384 -327.337982) (xy 110.255592 -327.323043) (xy 110.259622 -327.313544)
			(xy 110.27364 -327.27771) (xy 110.307891 -327.208801) (xy 110.348905 -327.143691) (xy 110.396268 -327.083042)
			(xy 110.449497 -327.02747) (xy 110.508051 -326.977541) (xy 110.571336 -326.933761) (xy 110.638707 -326.896577)
			(xy 110.70948 -326.866365) (xy 110.782935 -326.843434) (xy 110.858326 -326.828015) (xy 110.934886 -326.820267)
			(xy 111.011838 -326.820267) (xy 111.088398 -326.828015) (xy 111.163789 -326.843434) (xy 111.237244 -326.866365)
			(xy 111.308017 -326.896577) (xy 111.375388 -326.933761) (xy 111.438673 -326.977541) (xy 111.497227 -327.02747)
			(xy 111.550456 -327.083042) (xy 111.597819 -327.143691) (xy 111.638833 -327.208801) (xy 111.673084 -327.27771)
			(xy 111.687102 -327.313544) (xy 111.691168 -327.323016) (xy 111.705388 -327.337912) (xy 111.724305 -327.346051)
			(xy 111.7346 -327.346564) (xy 131.105148 -327.346564) (xy 131.115214 -327.346131) (xy 131.133802 -327.338401)
			(xy 131.141216 -327.331578) (xy 131.54914 -326.923654) (xy 131.555986 -326.916256) (xy 131.563713 -326.897657)
			(xy 131.564126 -326.887586) (xy 131.564126 -296.213022) (xy 131.563821 -296.204827) (xy 131.558646 -296.189275)
			(xy 131.553966 -296.182542) (xy 131.538313 -296.160915) (xy 131.513463 -296.113669) (xy 131.49653 -296.063042)
			(xy 131.487955 -296.010352) (xy 131.487418 -295.98366) (xy 131.487875 -295.958927) (xy 131.495237 -295.910011)
			(xy 131.509806 -295.862738) (xy 131.531256 -295.818164) (xy 131.544822 -295.797478) (xy 131.55295 -295.78554)
			(xy 131.553966 -295.75633) (xy 131.39928 -295.489376) (xy 131.374388 -295.475914) (xy 131.360164 -295.476676)
			(xy 131.34467 -295.47693) (xy 131.318684 -295.476418) (xy 131.267352 -295.468284) (xy 131.217924 -295.452221)
			(xy 131.171617 -295.428624) (xy 131.129571 -295.398074) (xy 131.092821 -295.361323) (xy 131.062272 -295.319276)
			(xy 131.038676 -295.272969) (xy 131.022614 -295.223541) (xy 131.014481 -295.172208) (xy 131.013962 -295.146222)
			(xy 131.014367 -295.122821) (xy 131.020968 -295.076487) (xy 131.03404 -295.031548) (xy 131.053323 -294.988903)
			(xy 131.065524 -294.96893) (xy 131.073144 -294.956738) (xy 131.073652 -294.928544) (xy 130.929126 -294.67937)
			(xy 130.904488 -294.665908) (xy 130.89001 -294.66667) (xy 130.87477 -294.666924) (xy 130.848784 -294.666412)
			(xy 130.797452 -294.658278) (xy 130.748025 -294.642215) (xy 130.701718 -294.618617) (xy 130.659673 -294.588067)
			(xy 130.622923 -294.551317) (xy 130.592375 -294.50927) (xy 130.56878 -294.462963) (xy 130.552719 -294.413534)
			(xy 130.544587 -294.362202) (xy 130.544062 -294.336216) (xy 130.544479 -294.312846) (xy 130.551092 -294.266576)
			(xy 130.564158 -294.221699) (xy 130.583418 -294.179111) (xy 130.595624 -294.159178) (xy 130.603244 -294.146986)
			(xy 130.603752 -294.118792) (xy 130.458972 -293.869364) (xy 130.434334 -293.855902) (xy 130.42011 -293.856664)
			(xy 130.40487 -293.856918) (xy 130.379351 -293.85645) (xy 130.328917 -293.848617) (xy 130.280285 -293.833127)
			(xy 130.234613 -293.810347) (xy 130.192983 -293.780819) (xy 130.156385 -293.745244) (xy 130.12569 -293.704468)
			(xy 130.113278 -293.682166) (xy 130.10642 -293.669466) (xy 130.082544 -293.655242) (xy 129.787142 -293.655242)
			(xy 129.763266 -293.669466) (xy 129.756408 -293.682166) (xy 129.743954 -293.704442) (xy 129.713256 -293.745209)
			(xy 129.676662 -293.780778) (xy 129.63504 -293.810306) (xy 129.589377 -293.833093) (xy 129.540757 -293.848597)
			(xy 129.490332 -293.856451) (xy 129.464816 -293.856918) (xy 129.438826 -293.856436) (xy 129.387485 -293.848307)
			(xy 129.338047 -293.832246) (xy 129.291731 -293.808649) (xy 129.249677 -293.778098) (xy 129.212919 -293.741343)
			(xy 129.182364 -293.699291) (xy 129.158764 -293.652977) (xy 129.142699 -293.603541) (xy 129.134566 -293.5522)
			(xy 129.134108 -293.52621) (xy 129.134526 -293.50284) (xy 129.141138 -293.456569) (xy 129.154203 -293.411692)
			(xy 129.173461 -293.369103) (xy 129.18567 -293.349172) (xy 129.19329 -293.33698) (xy 129.193798 -293.308786)
			(xy 129.049018 -293.059358) (xy 129.02438 -293.045896) (xy 129.009902 -293.046658) (xy 128.994662 -293.046912)
			(xy 128.968677 -293.0464) (xy 128.917347 -293.038264) (xy 128.867921 -293.0222) (xy 128.821616 -292.998602)
			(xy 128.779573 -292.968052) (xy 128.742826 -292.931301) (xy 128.71228 -292.889255) (xy 128.688687 -292.842948)
			(xy 128.672628 -292.79352) (xy 128.664498 -292.742189) (xy 128.663954 -292.716204) (xy 128.66436 -292.692803)
			(xy 128.670963 -292.64647) (xy 128.684037 -292.601532) (xy 128.703321 -292.558889) (xy 128.715516 -292.538912)
			(xy 128.723136 -292.526974) (xy 128.723644 -292.498526) (xy 128.579118 -292.249352) (xy 128.554226 -292.23589)
			(xy 128.540002 -292.236652) (xy 128.524762 -292.236906) (xy 128.498777 -292.236394) (xy 128.447447 -292.228258)
			(xy 128.398022 -292.212194) (xy 128.351718 -292.188596) (xy 128.309675 -292.158046) (xy 128.272928 -292.121295)
			(xy 128.242383 -292.079248) (xy 128.218791 -292.032941) (xy 128.202732 -291.983514) (xy 128.194603 -291.932183)
			(xy 128.194054 -291.906198) (xy 128.194461 -291.882797) (xy 128.201064 -291.836465) (xy 128.214139 -291.791527)
			(xy 128.233424 -291.748884) (xy 128.245616 -291.728906) (xy 128.253236 -291.716968) (xy 128.253744 -291.688774)
			(xy 128.109218 -291.439346) (xy 128.084326 -291.425884) (xy 128.070102 -291.426646) (xy 128.054862 -291.4269)
			(xy 128.028877 -291.426388) (xy 127.977548 -291.418252) (xy 127.928123 -291.402188) (xy 127.881819 -291.37859)
			(xy 127.839777 -291.348039) (xy 127.803031 -291.311288) (xy 127.772486 -291.269242) (xy 127.748895 -291.222935)
			(xy 127.732837 -291.173508) (xy 127.724709 -291.122177) (xy 127.724154 -291.096192) (xy 127.724561 -291.072834)
			(xy 127.731136 -291.026582) (xy 127.744141 -290.981711) (xy 127.763317 -290.939111) (xy 127.775462 -290.919154)
			(xy 127.783336 -290.906962) (xy 127.783844 -290.878768) (xy 127.639064 -290.62934) (xy 127.614172 -290.615878)
			(xy 127.599948 -290.61664) (xy 127.584708 -290.616894) (xy 127.558719 -290.616411) (xy 127.50738 -290.608281)
			(xy 127.457945 -290.592219) (xy 127.411632 -290.568622) (xy 127.369581 -290.53807) (xy 127.332827 -290.501315)
			(xy 127.302275 -290.459263) (xy 127.278678 -290.412949) (xy 127.262617 -290.363514) (xy 127.254488 -290.312175)
			(xy 127.254 -290.286186) (xy 127.254407 -290.262786) (xy 127.261012 -290.216453) (xy 127.274086 -290.171515)
			(xy 127.293369 -290.128872) (xy 127.305562 -290.108894) (xy 127.313182 -290.096956) (xy 127.31369 -290.068762)
			(xy 127.169164 -289.819334) (xy 127.144272 -289.805872) (xy 127.130048 -289.806634) (xy 127.114808 -289.806888)
			(xy 127.088819 -289.806405) (xy 127.037481 -289.798275) (xy 126.988046 -289.782213) (xy 126.941733 -289.758616)
			(xy 126.899682 -289.728063) (xy 126.862929 -289.691308) (xy 126.832378 -289.649256) (xy 126.808782 -289.602943)
			(xy 126.792722 -289.553508) (xy 126.784594 -289.502169) (xy 126.7841 -289.47618) (xy 126.784508 -289.452822)
			(xy 126.791084 -289.40657) (xy 126.804088 -289.361699) (xy 126.823263 -289.319099) (xy 126.835408 -289.299142)
			(xy 126.843282 -289.28695) (xy 126.84379 -289.258756) (xy 126.69901 -289.009328) (xy 126.674372 -288.995866)
			(xy 126.659894 -288.996628) (xy 126.644654 -288.996882) (xy 126.618671 -288.996369) (xy 126.567346 -288.988233)
			(xy 126.517926 -288.97217) (xy 126.471626 -288.948573) (xy 126.429588 -288.918025) (xy 126.392845 -288.881277)
			(xy 126.362303 -288.839234) (xy 126.338713 -288.792932) (xy 126.322656 -288.743509) (xy 126.314527 -288.692183)
			(xy 126.314527 -288.640217) (xy 126.322656 -288.588891) (xy 126.338713 -288.539468) (xy 126.362303 -288.493166)
			(xy 126.392845 -288.451123) (xy 126.429588 -288.414375) (xy 126.471626 -288.383827) (xy 126.517926 -288.36023)
			(xy 126.567346 -288.344167) (xy 126.618671 -288.336031) (xy 126.644654 -288.335466) (xy 126.66218 -288.335974)
			(xy 126.676404 -288.336736) (xy 126.70155 -288.32302) (xy 126.84506 -288.075624) (xy 126.844552 -288.04743)
			(xy 126.836678 -288.035238) (xy 126.824227 -288.015149) (xy 126.804568 -287.97217) (xy 126.79123 -287.92683)
			(xy 126.784483 -287.880053) (xy 126.7841 -287.856422) (xy 126.784581 -287.830432) (xy 126.79271 -287.779091)
			(xy 126.80877 -287.729654) (xy 126.832367 -287.683338) (xy 126.862919 -287.641285) (xy 126.899674 -287.604528)
			(xy 126.941726 -287.573974) (xy 126.988041 -287.550376) (xy 127.037477 -287.534313) (xy 127.088818 -287.526183)
			(xy 127.114808 -287.525714) (xy 127.13208 -287.526222) (xy 127.146558 -287.526984) (xy 127.17145 -287.513522)
			(xy 127.31496 -287.265872) (xy 127.314452 -287.23717) (xy 127.306578 -287.225232) (xy 127.294141 -287.205101)
			(xy 127.274481 -287.162059) (xy 127.261145 -287.116658) (xy 127.254404 -287.069821) (xy 127.254 -287.046162)
			(xy 127.254421 -287.022793) (xy 127.261039 -286.976525) (xy 127.27411 -286.931651) (xy 127.293372 -286.889066)
			(xy 127.305562 -286.869124) (xy 127.313182 -286.856932) (xy 127.31369 -286.828738) (xy 127.169164 -286.579564)
			(xy 127.144272 -286.566102) (xy 127.130048 -286.566864) (xy 127.114808 -286.567118) (xy 127.08882 -286.566609)
			(xy 127.037484 -286.55848) (xy 126.988052 -286.542419) (xy 126.94174 -286.518824) (xy 126.89969 -286.488275)
			(xy 126.862937 -286.451523) (xy 126.832385 -286.409475) (xy 126.808787 -286.363165) (xy 126.792725 -286.313733)
			(xy 126.784592 -286.262398) (xy 126.7841 -286.23641) (xy 126.784506 -286.213009) (xy 126.791107 -286.166675)
			(xy 126.804179 -286.121736) (xy 126.823459 -286.07909) (xy 126.835662 -286.059118) (xy 126.843282 -286.04718)
			(xy 126.84379 -286.018986) (xy 126.699264 -285.769558) (xy 126.674372 -285.756096) (xy 126.660148 -285.756858)
			(xy 126.644654 -285.757112) (xy 126.618669 -285.756599) (xy 126.567339 -285.748463) (xy 126.517914 -285.732397)
			(xy 126.471611 -285.708799) (xy 126.429568 -285.678248) (xy 126.392822 -285.641497) (xy 126.362277 -285.59945)
			(xy 126.338685 -285.553143) (xy 126.322627 -285.503716) (xy 126.314497 -285.452385) (xy 126.314497 -285.400415)
			(xy 126.322627 -285.349084) (xy 126.338685 -285.299657) (xy 126.362277 -285.25335) (xy 126.392822 -285.211303)
			(xy 126.429568 -285.174552) (xy 126.471611 -285.144001) (xy 126.517914 -285.120403) (xy 126.567339 -285.104337)
			(xy 126.618669 -285.096201) (xy 126.644654 -285.095696) (xy 126.66218 -285.096204) (xy 126.676404 -285.096966)
			(xy 126.70155 -285.08325) (xy 126.84506 -284.8356) (xy 126.844552 -284.807406) (xy 126.836678 -284.795214)
			(xy 126.824229 -284.775125) (xy 126.804573 -284.732146) (xy 126.791238 -284.686805) (xy 126.784494 -284.640028)
			(xy 126.7841 -284.616398) (xy 126.784583 -284.590409) (xy 126.792715 -284.539071) (xy 126.808777 -284.489637)
			(xy 126.832375 -284.443325) (xy 126.862928 -284.401275) (xy 126.899682 -284.364521) (xy 126.941734 -284.33397)
			(xy 126.988047 -284.310374) (xy 127.037481 -284.294312) (xy 127.088819 -284.286182) (xy 127.114808 -284.28569)
			(xy 127.13208 -284.286198) (xy 127.146558 -284.28696) (xy 127.17145 -284.273498) (xy 127.315214 -284.025848)
			(xy 127.314452 -283.997654) (xy 127.306578 -283.985208) (xy 127.294129 -283.965119) (xy 127.274474 -283.922139)
			(xy 127.26114 -283.876799) (xy 127.254397 -283.830022) (xy 127.254 -283.806392) (xy 127.254407 -283.782991)
			(xy 127.26101 -283.736658) (xy 127.274084 -283.69172) (xy 127.293367 -283.649076) (xy 127.305562 -283.6291)
			(xy 127.313182 -283.616908) (xy 127.31369 -283.588714) (xy 127.169164 -283.33954) (xy 127.144272 -283.326078)
			(xy 127.130048 -283.32684) (xy 127.114808 -283.327094) (xy 127.088819 -283.326611) (xy 127.03748 -283.318481)
			(xy 126.988045 -283.302419) (xy 126.941732 -283.278822) (xy 126.899681 -283.24827) (xy 126.862927 -283.211515)
			(xy 126.832375 -283.169463) (xy 126.808778 -283.123149) (xy 126.792717 -283.073714) (xy 126.784588 -283.022375)
			(xy 126.7841 -282.996386) (xy 126.784507 -282.972986) (xy 126.791112 -282.926653) (xy 126.804186 -282.881715)
			(xy 126.823469 -282.839072) (xy 126.835662 -282.819094) (xy 126.843282 -282.807156) (xy 126.84379 -282.778962)
			(xy 126.699264 -282.529534) (xy 126.674372 -282.516072) (xy 126.660148 -282.516834) (xy 126.644654 -282.517088)
			(xy 126.618671 -282.516575) (xy 126.567345 -282.508439) (xy 126.517924 -282.492375) (xy 126.471623 -282.468778)
			(xy 126.429584 -282.43823) (xy 126.39284 -282.401481) (xy 126.362298 -282.359438) (xy 126.338707 -282.313134)
			(xy 126.32265 -282.26371) (xy 126.314521 -282.212383) (xy 126.314521 -282.160417) (xy 126.32265 -282.10909)
			(xy 126.338707 -282.059666) (xy 126.362298 -282.013362) (xy 126.39284 -281.971319) (xy 126.429584 -281.93457)
			(xy 126.471623 -281.904022) (xy 126.517924 -281.880425) (xy 126.567345 -281.864361) (xy 126.618671 -281.856225)
			(xy 126.644654 -281.855672) (xy 126.661926 -281.85618) (xy 126.676404 -281.856942) (xy 126.70155 -281.843226)
			(xy 126.84506 -281.595576) (xy 126.844552 -281.567382) (xy 126.836678 -281.55519) (xy 126.82423 -281.535101)
			(xy 126.804578 -281.492121) (xy 126.791245 -281.44678) (xy 126.784505 -281.400004) (xy 126.7841 -281.376374)
			(xy 126.784508 -281.353016) (xy 126.791085 -281.306764) (xy 126.80409 -281.261894) (xy 126.823265 -281.219294)
			(xy 126.835408 -281.199336) (xy 126.843282 -281.187144) (xy 126.84379 -281.15895) (xy 126.69901 -280.909522)
			(xy 126.674118 -280.89606) (xy 126.659894 -280.896822) (xy 126.644654 -280.897076) (xy 126.61867 -280.896563)
			(xy 126.567343 -280.888426) (xy 126.517921 -280.872361) (xy 126.47162 -280.848762) (xy 126.429581 -280.818211)
			(xy 126.392838 -280.78146) (xy 126.362297 -280.739413) (xy 126.338709 -280.693107) (xy 126.322655 -280.643681)
			(xy 126.314531 -280.592352) (xy 126.313946 -280.566368) (xy 126.314348 -280.542966) (xy 126.320942 -280.496629)
			(xy 126.334009 -280.451686) (xy 126.353286 -280.409037) (xy 126.365508 -280.389076) (xy 126.373128 -280.377138)
			(xy 126.373636 -280.348944) (xy 126.22911 -280.099516) (xy 126.204218 -280.086054) (xy 126.189994 -280.086816)
			(xy 126.174754 -280.08707) (xy 126.148772 -280.086557) (xy 126.097449 -280.078421) (xy 126.048031 -280.062358)
			(xy 126.001733 -280.038763) (xy 125.959696 -280.008216) (xy 125.922955 -279.971469) (xy 125.892413 -279.929428)
			(xy 125.868824 -279.883127) (xy 125.852768 -279.833706) (xy 125.84464 -279.782382) (xy 125.84464 -279.730418)
			(xy 125.852768 -279.679094) (xy 125.868824 -279.629673) (xy 125.892413 -279.583372) (xy 125.922955 -279.541331)
			(xy 125.959696 -279.504584) (xy 126.001733 -279.474037) (xy 126.048031 -279.450442) (xy 126.097449 -279.434379)
			(xy 126.148772 -279.426243) (xy 126.174754 -279.425654) (xy 126.1985 -279.426057) (xy 126.245503 -279.432847)
			(xy 126.291046 -279.446308) (xy 126.334188 -279.466161) (xy 126.354332 -279.47874) (xy 126.366524 -279.486614)
			(xy 126.394718 -279.487376) (xy 127.241554 -279.000966) (xy 127.255016 -278.976328) (xy 127.254254 -278.96185)
			(xy 127.254 -278.946356) (xy 127.254421 -278.922987) (xy 127.26104 -278.87672) (xy 127.274112 -278.831846)
			(xy 127.293374 -278.789262) (xy 127.305562 -278.769318) (xy 127.313182 -278.757126) (xy 127.31369 -278.728932)
			(xy 127.16891 -278.479504) (xy 127.144272 -278.466042) (xy 127.130048 -278.466804) (xy 127.114808 -278.467058)
			(xy 127.08882 -278.466575) (xy 127.037483 -278.458445) (xy 126.988051 -278.442383) (xy 126.94174 -278.418785)
			(xy 126.899692 -278.388232) (xy 126.862941 -278.351476) (xy 126.832393 -278.309424) (xy 126.808801 -278.26311)
			(xy 126.792745 -278.213676) (xy 126.784621 -278.162338) (xy 126.7841 -278.13635) (xy 126.784522 -278.112981)
			(xy 126.791142 -278.066714) (xy 126.804213 -278.021841) (xy 126.823477 -277.979257) (xy 126.835662 -277.959312)
			(xy 126.843282 -277.94712) (xy 126.84379 -277.918926) (xy 126.699264 -277.669498) (xy 126.674372 -277.656036)
			(xy 126.660148 -277.656798) (xy 126.644654 -277.657052) (xy 126.618666 -277.656539) (xy 126.56733 -277.648402)
			(xy 126.517899 -277.632334) (xy 126.47159 -277.608733) (xy 126.429542 -277.578178) (xy 126.392792 -277.541423)
			(xy 126.362243 -277.499371) (xy 126.338648 -277.453058) (xy 126.322588 -277.403625) (xy 126.314457 -277.352288)
			(xy 126.314457 -277.300312) (xy 126.322588 -277.248975) (xy 126.338648 -277.199542) (xy 126.362243 -277.153229)
			(xy 126.392792 -277.111177) (xy 126.429542 -277.074422) (xy 126.47159 -277.043867) (xy 126.517899 -277.020266)
			(xy 126.56733 -277.004198) (xy 126.618666 -276.996061) (xy 126.644654 -276.995636) (xy 126.66218 -276.996144)
			(xy 126.676404 -276.996906) (xy 126.70155 -276.98319) (xy 126.84506 -276.73554) (xy 126.844552 -276.707346)
			(xy 126.836678 -276.695154) (xy 126.824232 -276.675064) (xy 126.804585 -276.632084) (xy 126.791257 -276.586743)
			(xy 126.784522 -276.539967) (xy 126.7841 -276.516338) (xy 126.78458 -276.490347) (xy 126.792707 -276.439004)
			(xy 126.808766 -276.389565) (xy 126.832362 -276.343247) (xy 126.862913 -276.301191) (xy 126.899668 -276.264433)
			(xy 126.941722 -276.233877) (xy 126.988037 -276.210277) (xy 127.037475 -276.194214) (xy 127.088817 -276.186083)
			(xy 127.114808 -276.18563) (xy 127.13208 -276.186138) (xy 127.146558 -276.1869) (xy 127.17145 -276.173438)
			(xy 127.315214 -275.925788) (xy 127.314452 -275.897594) (xy 127.306578 -275.885148) (xy 127.294133 -275.865058)
			(xy 127.274486 -275.822077) (xy 127.261159 -275.776737) (xy 127.254425 -275.729961) (xy 127.254 -275.706332)
			(xy 127.254404 -275.682931) (xy 127.261003 -275.636595) (xy 127.274072 -275.591654) (xy 127.29335 -275.549007)
			(xy 127.305562 -275.52904) (xy 127.313182 -275.516848) (xy 127.31369 -275.488654) (xy 127.169164 -275.23948)
			(xy 127.144272 -275.226018) (xy 127.130048 -275.22678) (xy 127.114808 -275.227034) (xy 127.08882 -275.226525)
			(xy 127.037483 -275.218396) (xy 126.988049 -275.202336) (xy 126.941737 -275.178741) (xy 126.899686 -275.148192)
			(xy 126.862931 -275.11144) (xy 126.832377 -275.069392) (xy 126.808777 -275.023082) (xy 126.792712 -274.97365)
			(xy 126.784578 -274.922314) (xy 126.7841 -274.896326) (xy 126.784505 -274.872925) (xy 126.791104 -274.82659)
			(xy 126.804174 -274.781649) (xy 126.823453 -274.739002) (xy 126.835662 -274.719034) (xy 126.843282 -274.707096)
			(xy 126.84379 -274.678902) (xy 126.699264 -274.429474) (xy 126.674372 -274.416012) (xy 126.660148 -274.416774)
			(xy 126.644654 -274.417028) (xy 126.618668 -274.416515) (xy 126.567336 -274.408378) (xy 126.517908 -274.392312)
			(xy 126.471602 -274.368712) (xy 126.429558 -274.33816) (xy 126.39281 -274.301407) (xy 126.362263 -274.259358)
			(xy 126.33867 -274.213049) (xy 126.322611 -274.16362) (xy 126.314481 -274.112286) (xy 126.314481 -274.060314)
			(xy 126.322611 -274.00898) (xy 126.33867 -273.959551) (xy 126.362263 -273.913242) (xy 126.39281 -273.871193)
			(xy 126.429558 -273.83444) (xy 126.471602 -273.803888) (xy 126.517908 -273.780288) (xy 126.567336 -273.764222)
			(xy 126.618668 -273.756085) (xy 126.644654 -273.755612) (xy 126.66218 -273.75612) (xy 126.676404 -273.756882)
			(xy 126.70155 -273.743166) (xy 126.84506 -273.495516) (xy 126.844552 -273.467322) (xy 126.836678 -273.45513)
			(xy 126.824228 -273.435041) (xy 126.80457 -273.392062) (xy 126.791232 -273.346722) (xy 126.784487 -273.299945)
			(xy 126.7841 -273.276314) (xy 126.784582 -273.250324) (xy 126.792712 -273.198984) (xy 126.808773 -273.149549)
			(xy 126.83237 -273.103234) (xy 126.862922 -273.061181) (xy 126.899677 -273.024426) (xy 126.941729 -272.993873)
			(xy 126.988043 -272.970275) (xy 127.037479 -272.954213) (xy 127.088818 -272.946083) (xy 127.114808 -272.945606)
			(xy 127.13208 -272.946114) (xy 127.146558 -272.946876) (xy 127.17145 -272.933414) (xy 127.315214 -272.685764)
			(xy 127.314452 -272.65757) (xy 127.306578 -272.645124) (xy 127.294128 -272.625035) (xy 127.274471 -272.582056)
			(xy 127.261134 -272.536716) (xy 127.254389 -272.489938) (xy 127.254 -272.466308) (xy 127.254406 -272.442907)
			(xy 127.261007 -272.396573) (xy 127.274079 -272.351634) (xy 127.29336 -272.308988) (xy 127.305562 -272.289016)
			(xy 127.313182 -272.276824) (xy 127.31369 -272.24863) (xy 127.169164 -271.999456) (xy 127.144272 -271.985994)
			(xy 127.130048 -271.986756) (xy 127.114808 -271.98701) (xy 127.088818 -271.986527) (xy 127.037479 -271.978397)
			(xy 126.988043 -271.962336) (xy 126.941728 -271.938738) (xy 126.899676 -271.908186) (xy 126.86292 -271.871432)
			(xy 126.832367 -271.82938) (xy 126.808768 -271.783066) (xy 126.792705 -271.733631) (xy 126.784573 -271.682292)
			(xy 126.7841 -271.656302) (xy 126.784506 -271.632901) (xy 126.791108 -271.586568) (xy 126.804181 -271.541629)
			(xy 126.823463 -271.498984) (xy 126.835662 -271.47901) (xy 126.843282 -271.467072) (xy 126.84379 -271.438878)
			(xy 126.699264 -271.18945) (xy 126.674372 -271.175988) (xy 126.660148 -271.17675) (xy 126.644654 -271.177004)
			(xy 126.618669 -271.176491) (xy 126.567341 -271.168355) (xy 126.517917 -271.15229) (xy 126.471615 -271.128692)
			(xy 126.429573 -271.098142) (xy 126.392828 -271.061391) (xy 126.362284 -271.019346) (xy 126.338692 -270.97304)
			(xy 126.322634 -270.923614) (xy 126.314505 -270.872285) (xy 126.314505 -270.820315) (xy 126.322634 -270.768986)
			(xy 126.338692 -270.71956) (xy 126.362284 -270.673254) (xy 126.392828 -270.631209) (xy 126.429573 -270.594458)
			(xy 126.471615 -270.563908) (xy 126.517917 -270.54031) (xy 126.567341 -270.524245) (xy 126.618669 -270.516109)
			(xy 126.644654 -270.515588) (xy 126.66218 -270.516096) (xy 126.676404 -270.516858) (xy 126.70155 -270.503142)
			(xy 126.84506 -270.255492) (xy 126.844552 -270.227298) (xy 126.836678 -270.215106) (xy 126.824229 -270.195017)
			(xy 126.804575 -270.152037) (xy 126.79124 -270.106697) (xy 126.784498 -270.05992) (xy 126.7841 -270.03629)
			(xy 126.78461 -270.010304) (xy 126.792742 -269.958971) (xy 126.808804 -269.909542) (xy 126.832401 -269.863235)
			(xy 126.862951 -269.821188) (xy 126.899702 -269.784439) (xy 126.94175 -269.753891) (xy 126.988059 -269.730297)
			(xy 127.037488 -269.714238) (xy 127.088822 -269.706109) (xy 127.114808 -269.705582) (xy 127.13208 -269.70609)
			(xy 127.146558 -269.706852) (xy 127.17145 -269.69339) (xy 127.315214 -269.44574) (xy 127.314452 -269.417546)
			(xy 127.306578 -269.4051) (xy 127.29413 -269.385011) (xy 127.274476 -269.342031) (xy 127.261142 -269.296691)
			(xy 127.254401 -269.249914) (xy 127.254 -269.226284) (xy 127.254408 -269.202884) (xy 127.261012 -269.156551)
			(xy 127.274087 -269.111614) (xy 127.29337 -269.06897) (xy 127.305562 -269.048992) (xy 127.313182 -269.037054)
			(xy 127.31369 -269.008606) (xy 127.169164 -268.759432) (xy 127.144272 -268.74597) (xy 127.130048 -268.746732)
			(xy 127.114808 -268.746986) (xy 127.088819 -268.746503) (xy 127.037481 -268.738373) (xy 126.988047 -268.722311)
			(xy 126.941734 -268.698714) (xy 126.899683 -268.668161) (xy 126.86293 -268.631406) (xy 126.832379 -268.589354)
			(xy 126.808783 -268.543041) (xy 126.792724 -268.493606) (xy 126.784595 -268.442267) (xy 126.7841 -268.416278)
			(xy 126.784508 -268.39292) (xy 126.791084 -268.346668) (xy 126.804088 -268.301797) (xy 126.823264 -268.259197)
			(xy 126.835408 -268.23924) (xy 126.843282 -268.227048) (xy 126.84379 -268.198854) (xy 126.69901 -267.949426)
			(xy 126.674372 -267.935964) (xy 126.659894 -267.936726) (xy 126.644654 -267.93698) (xy 126.61867 -267.936467)
			(xy 126.567343 -267.928331) (xy 126.51792 -267.912265) (xy 126.471619 -267.888666) (xy 126.429579 -267.858115)
			(xy 126.392837 -267.821364) (xy 126.362295 -267.779318) (xy 126.338706 -267.733011) (xy 126.322652 -267.683585)
			(xy 126.314527 -267.632256) (xy 126.313946 -267.606272) (xy 126.314366 -267.582903) (xy 126.320984 -267.536635)
			(xy 126.334055 -267.491761) (xy 126.353319 -267.449177) (xy 126.365508 -267.429234) (xy 126.373128 -267.417042)
			(xy 126.373636 -267.388848) (xy 126.214632 -267.115036) (xy 126.19101 -267.101574) (xy 126.177294 -267.101574)
			(xy 126.174754 -267.101574) (xy 126.14825 -267.101002) (xy 126.096038 -267.091839) (xy 126.046195 -267.073795)
			(xy 126.000216 -267.047414) (xy 125.959486 -267.013488) (xy 125.925227 -266.973037) (xy 125.911356 -266.950444)
			(xy 125.904244 -266.93876) (xy 125.88113 -266.925298) (xy 125.557026 -266.925298) (xy 125.53315 -266.939522)
			(xy 125.526292 -266.952222) (xy 125.51384 -266.9745) (xy 125.483144 -267.01527) (xy 125.446551 -267.050842)
			(xy 125.404928 -267.080372) (xy 125.359265 -267.10316) (xy 125.310643 -267.118664) (xy 125.260217 -267.126517)
			(xy 125.2347 -267.126974) (xy 125.224794 -267.12672) (xy 125.210824 -267.126466) (xy 125.18644 -267.139928)
			(xy 125.03912 -267.393674) (xy 125.039628 -267.421614) (xy 125.04674 -267.433552) (xy 125.058285 -267.453132)
			(xy 125.076493 -267.494779) (xy 125.088841 -267.538524) (xy 125.095096 -267.583545) (xy 125.095508 -267.606272)
			(xy 125.094998 -267.632259) (xy 125.086868 -267.683594) (xy 125.070807 -267.733024) (xy 125.047211 -267.779334)
			(xy 125.016661 -267.821382) (xy 124.97991 -267.858133) (xy 124.937862 -267.888683) (xy 124.891552 -267.912279)
			(xy 124.842122 -267.92834) (xy 124.790787 -267.93647) (xy 124.738813 -267.93647) (xy 124.687478 -267.92834)
			(xy 124.638048 -267.912279) (xy 124.591738 -267.888683) (xy 124.54969 -267.858133) (xy 124.512939 -267.821382)
			(xy 124.482389 -267.779334) (xy 124.458793 -267.733024) (xy 124.442732 -267.683594) (xy 124.434602 -267.632259)
			(xy 124.434092 -267.606272) (xy 124.434346 -267.594588) (xy 124.434854 -267.58011) (xy 124.421392 -267.555726)
			(xy 123.571508 -267.067538) (xy 123.543568 -267.068046) (xy 123.53163 -267.07592) (xy 123.511698 -267.088031)
			(xy 123.469154 -267.10714) (xy 123.424347 -267.120082) (xy 123.378166 -267.1266) (xy 123.354846 -267.126974)
			(xy 123.328855 -267.126494) (xy 123.277513 -267.118369) (xy 123.228075 -267.10231) (xy 123.181758 -267.078714)
			(xy 123.139703 -267.048162) (xy 123.102946 -267.011407) (xy 123.072392 -266.969353) (xy 123.048795 -266.923036)
			(xy 123.032734 -266.873598) (xy 123.024607 -266.822257) (xy 123.024138 -266.796266) (xy 123.024547 -266.772908)
			(xy 123.031125 -266.726657) (xy 123.044132 -266.681788) (xy 123.06331 -266.63919) (xy 123.075446 -266.619228)
			(xy 123.08332 -266.607036) (xy 123.083828 -266.578842) (xy 122.939048 -266.329414) (xy 122.914156 -266.315952)
			(xy 122.899932 -266.316714) (xy 122.884692 -266.316968) (xy 122.861778 -266.316576) (xy 122.816389 -266.310238)
			(xy 122.772313 -266.297686) (xy 122.730395 -266.279161) (xy 122.710702 -266.267438) (xy 122.698764 -266.260072)
			(xy 122.670824 -266.259564) (xy 121.818654 -266.749022) (xy 121.804938 -266.773406) (xy 121.805446 -266.787376)
			(xy 121.805446 -266.796266) (xy 121.804939 -266.822256) (xy 121.796813 -266.873597) (xy 121.780755 -266.923034)
			(xy 121.757162 -266.969351) (xy 121.726613 -267.011407) (xy 121.689862 -267.048167) (xy 121.647813 -267.078724)
			(xy 121.601501 -267.102328) (xy 121.552067 -267.118396) (xy 121.500728 -267.126533) (xy 121.474738 -267.126974)
			(xy 121.464832 -267.12672) (xy 121.450862 -267.126466) (xy 121.426224 -267.139928) (xy 121.279158 -267.393674)
			(xy 121.279412 -267.421614) (xy 121.286778 -267.433552) (xy 121.298322 -267.453132) (xy 121.316528 -267.49478)
			(xy 121.328875 -267.538525) (xy 121.335129 -267.583546) (xy 121.335546 -267.606272) (xy 121.335036 -267.632259)
			(xy 121.326906 -267.683594) (xy 121.310845 -267.733024) (xy 121.287249 -267.779334) (xy 121.256699 -267.821382)
			(xy 121.219948 -267.858133) (xy 121.1779 -267.888683) (xy 121.13159 -267.912279) (xy 121.08216 -267.92834)
			(xy 121.030825 -267.93647) (xy 120.978851 -267.93647) (xy 120.927516 -267.92834) (xy 120.878086 -267.912279)
			(xy 120.831776 -267.888683) (xy 120.789728 -267.858133) (xy 120.752977 -267.821382) (xy 120.722427 -267.779334)
			(xy 120.698831 -267.733024) (xy 120.68277 -267.683594) (xy 120.67464 -267.632259) (xy 120.67413 -267.606272)
			(xy 120.674384 -267.594588) (xy 120.674892 -267.58011) (xy 120.66143 -267.555726) (xy 119.811292 -267.067538)
			(xy 119.783606 -267.068046) (xy 119.771414 -267.075666) (xy 119.751495 -267.087816) (xy 119.708963 -267.106998)
			(xy 119.664153 -267.119999) (xy 119.617959 -267.12656) (xy 119.59463 -267.126974) (xy 119.56864 -267.126493)
			(xy 119.5173 -267.118365) (xy 119.467864 -267.102305) (xy 119.421549 -267.078709) (xy 119.379496 -267.048156)
			(xy 119.342741 -267.011401) (xy 119.312189 -266.969348) (xy 119.288593 -266.923033) (xy 119.272534 -266.873596)
			(xy 119.264407 -266.822256) (xy 119.263922 -266.796266) (xy 119.264324 -266.772864) (xy 119.270918 -266.726527)
			(xy 119.283984 -266.681584) (xy 119.303261 -266.638934) (xy 119.315484 -266.618974) (xy 119.323104 -266.607036)
			(xy 119.323612 -266.578842) (xy 119.178832 -266.329414) (xy 119.154194 -266.315952) (xy 119.139716 -266.316714)
			(xy 119.12473 -266.316968) (xy 119.101783 -266.316596) (xy 119.056325 -266.310284) (xy 119.01218 -266.297734)
			(xy 118.970199 -266.27919) (xy 118.950486 -266.267438) (xy 118.938548 -266.260072) (xy 118.910608 -266.259564)
			(xy 118.058692 -266.749022) (xy 118.044976 -266.773406) (xy 118.045484 -266.787376) (xy 118.045484 -266.796266)
			(xy 118.045003 -266.822256) (xy 118.036876 -266.873598) (xy 118.020817 -266.923035) (xy 117.99722 -266.969351)
			(xy 117.966668 -267.011405) (xy 117.929913 -267.048162) (xy 117.88786 -267.078715) (xy 117.841544 -267.102313)
			(xy 117.792107 -267.118374) (xy 117.740766 -267.126503) (xy 117.714776 -267.126974) (xy 117.70487 -267.12672)
			(xy 117.6909 -267.126466) (xy 117.666262 -267.139928) (xy 117.519196 -267.393928) (xy 117.51945 -267.421868)
			(xy 117.526816 -267.433806) (xy 117.538329 -267.45336) (xy 117.556478 -267.49495) (xy 117.568766 -267.538631)
			(xy 117.574964 -267.583583) (xy 117.57533 -267.606272) (xy 117.57482 -267.632259) (xy 117.56669 -267.683594)
			(xy 117.550629 -267.733024) (xy 117.527033 -267.779334) (xy 117.496483 -267.821382) (xy 117.459732 -267.858133)
			(xy 117.417684 -267.888683) (xy 117.371374 -267.912279) (xy 117.321944 -267.92834) (xy 117.270609 -267.93647)
			(xy 117.218635 -267.93647) (xy 117.1673 -267.92834) (xy 117.11787 -267.912279) (xy 117.07156 -267.888683)
			(xy 117.029512 -267.858133) (xy 116.992761 -267.821382) (xy 116.962211 -267.779334) (xy 116.938615 -267.733024)
			(xy 116.922554 -267.683594) (xy 116.914424 -267.632259) (xy 116.913914 -267.606272) (xy 116.914168 -267.594334)
			(xy 116.914676 -267.58011) (xy 116.901214 -267.555726) (xy 116.05133 -267.067538) (xy 116.023644 -267.068046)
			(xy 116.011452 -267.075666) (xy 115.991533 -267.087818) (xy 115.949002 -267.107005) (xy 115.904192 -267.120011)
			(xy 115.857998 -267.126578) (xy 115.834668 -267.126974) (xy 115.808681 -267.126488) (xy 115.757349 -267.118353)
			(xy 115.707921 -267.102288) (xy 115.661614 -267.078688) (xy 115.61957 -267.048134) (xy 115.582823 -267.01138)
			(xy 115.552278 -266.969329) (xy 115.528687 -266.923018) (xy 115.512632 -266.873587) (xy 115.504506 -266.822253)
			(xy 115.50396 -266.796266) (xy 115.504362 -266.772864) (xy 115.510957 -266.726527) (xy 115.524024 -266.681585)
			(xy 115.543303 -266.638936) (xy 115.555522 -266.618974) (xy 115.563142 -266.607036) (xy 115.56365 -266.578842)
			(xy 115.41887 -266.329414) (xy 115.394232 -266.315952) (xy 115.379754 -266.316714) (xy 115.364768 -266.316968)
			(xy 115.34182 -266.316599) (xy 115.29636 -266.310291) (xy 115.252212 -266.297746) (xy 115.210229 -266.279205)
			(xy 115.190524 -266.267438) (xy 115.178586 -266.260072) (xy 115.150646 -266.259564) (xy 114.29873 -266.749022)
			(xy 114.285014 -266.773406) (xy 114.285522 -266.787376) (xy 114.285522 -266.796266) (xy 114.285041 -266.822257)
			(xy 114.276915 -266.873601) (xy 114.260855 -266.923041) (xy 114.23726 -266.96936) (xy 114.206708 -267.011417)
			(xy 114.169954 -267.048177) (xy 114.127901 -267.078735) (xy 114.081585 -267.102337) (xy 114.032148 -267.118403)
			(xy 113.980805 -267.126538) (xy 113.954814 -267.126974) (xy 113.929297 -267.126501) (xy 113.87887 -267.118661)
			(xy 113.830247 -267.103163) (xy 113.784583 -267.080378) (xy 113.742963 -267.050845) (xy 113.706376 -267.015268)
			(xy 113.675692 -266.97449) (xy 113.663222 -266.952222) (xy 113.656364 -266.939522) (xy 113.632488 -266.925298)
			(xy 111.185198 -266.925298) (xy 111.178597 -266.925524) (xy 111.16586 -266.929009) (xy 111.160052 -266.932156)
			(xy 110.074456 -267.555726) (xy 110.060994 -267.58011) (xy 110.061502 -267.594334) (xy 110.061756 -267.606272)
			(xy 110.061246 -267.632259) (xy 110.053116 -267.683594) (xy 110.037055 -267.733024) (xy 110.013459 -267.779334)
			(xy 109.982909 -267.821382) (xy 109.946158 -267.858133) (xy 109.90411 -267.888683) (xy 109.8578 -267.912279)
			(xy 109.80837 -267.92834) (xy 109.757035 -267.93647) (xy 109.705061 -267.93647) (xy 109.653726 -267.92834)
			(xy 109.604296 -267.912279) (xy 109.557986 -267.888683) (xy 109.515938 -267.858133) (xy 109.479187 -267.821382)
			(xy 109.448637 -267.779334) (xy 109.425041 -267.733024) (xy 109.40898 -267.683594) (xy 109.40085 -267.632259)
			(xy 109.40034 -267.606272) (xy 109.400709 -267.583541) (xy 109.406931 -267.538506) (xy 109.41928 -267.494754)
			(xy 109.437522 -267.453112) (xy 109.449108 -267.433552) (xy 109.45622 -267.421614) (xy 109.456728 -267.393674)
			(xy 109.309408 -267.139928) (xy 109.285024 -267.126466) (xy 109.271054 -267.12672) (xy 109.261148 -267.126974)
			(xy 109.235157 -267.126494) (xy 109.183815 -267.118369) (xy 109.134376 -267.102311) (xy 109.088059 -267.078715)
			(xy 109.046003 -267.048163) (xy 109.009246 -267.011407) (xy 108.978693 -266.969353) (xy 108.955095 -266.923037)
			(xy 108.939034 -266.873599) (xy 108.930907 -266.822257) (xy 108.93044 -266.796266) (xy 108.93044 -266.78763)
			(xy 108.930948 -266.773406) (xy 108.917232 -266.749022) (xy 108.065062 -266.259564) (xy 108.037122 -266.260072)
			(xy 108.025184 -266.267438) (xy 108.005464 -266.279174) (xy 107.963476 -266.297694) (xy 107.919335 -266.310242)
			(xy 107.873885 -266.31658) (xy 107.85094 -266.316968) (xy 107.835954 -266.316714) (xy 107.82173 -266.315952)
			(xy 107.796838 -266.329414) (xy 107.652058 -266.578842) (xy 107.652566 -266.607036) (xy 107.66044 -266.619228)
			(xy 107.67261 -266.639174) (xy 107.691818 -266.681766) (xy 107.704829 -266.726642) (xy 107.711381 -266.772904)
			(xy 107.711748 -266.796266) (xy 107.711241 -266.822256) (xy 107.703115 -266.873597) (xy 107.687057 -266.923035)
			(xy 107.663464 -266.969352) (xy 107.632916 -267.011408) (xy 107.596164 -267.048167) (xy 107.554115 -267.078725)
			(xy 107.507803 -267.102329) (xy 107.458369 -267.118398) (xy 107.40703 -267.126535) (xy 107.38104 -267.126974)
			(xy 107.357721 -267.126591) (xy 107.311541 -267.120074) (xy 107.266734 -267.107134) (xy 107.224189 -267.088029)
			(xy 107.204256 -267.07592) (xy 107.192318 -267.068046) (xy 107.164378 -267.067538) (xy 106.314494 -267.555726)
			(xy 106.301032 -267.58011) (xy 106.30154 -267.594588) (xy 106.301794 -267.606272) (xy 106.301284 -267.632259)
			(xy 106.293154 -267.683594) (xy 106.277093 -267.733024) (xy 106.253497 -267.779334) (xy 106.222947 -267.821382)
			(xy 106.186196 -267.858133) (xy 106.144148 -267.888683) (xy 106.097838 -267.912279) (xy 106.048408 -267.92834)
			(xy 105.997073 -267.93647) (xy 105.945099 -267.93647) (xy 105.893764 -267.92834) (xy 105.844334 -267.912279)
			(xy 105.798024 -267.888683) (xy 105.755976 -267.858133) (xy 105.719225 -267.821382) (xy 105.688675 -267.779334)
			(xy 105.665079 -267.733024) (xy 105.649018 -267.683594) (xy 105.640888 -267.632259) (xy 105.640378 -267.606272)
			(xy 105.640747 -267.583541) (xy 105.646968 -267.538506) (xy 105.659314 -267.494752) (xy 105.677554 -267.453108)
			(xy 105.689146 -267.433552) (xy 105.696258 -267.421614) (xy 105.696766 -267.393674) (xy 105.549446 -267.139928)
			(xy 105.525062 -267.126466) (xy 105.511092 -267.12672) (xy 105.500932 -267.126974) (xy 105.474942 -267.126493)
			(xy 105.423602 -267.118366) (xy 105.374165 -267.102306) (xy 105.32785 -267.078709) (xy 105.285797 -267.048157)
			(xy 105.249042 -267.011402) (xy 105.21849 -266.969348) (xy 105.194893 -266.923033) (xy 105.178834 -266.873596)
			(xy 105.170707 -266.822256) (xy 105.170224 -266.796266) (xy 105.170224 -266.787376) (xy 105.170732 -266.773406)
			(xy 105.157016 -266.749022) (xy 104.3051 -266.259564) (xy 104.27716 -266.260072) (xy 104.265222 -266.267438)
			(xy 104.245501 -266.279171) (xy 104.203512 -266.297682) (xy 104.159371 -266.310222) (xy 104.113922 -266.316551)
			(xy 104.090978 -266.316968) (xy 104.075992 -266.316714) (xy 104.061768 -266.315952) (xy 104.036876 -266.329414)
			(xy 103.892096 -266.578842) (xy 103.892604 -266.607036) (xy 103.900478 -266.619228) (xy 103.91265 -266.639173)
			(xy 103.931862 -266.681765) (xy 103.944875 -266.726641) (xy 103.951428 -266.772903) (xy 103.951786 -266.796266)
			(xy 103.951305 -266.822256) (xy 103.943178 -266.873598) (xy 103.927119 -266.923035) (xy 103.903522 -266.969352)
			(xy 103.87297 -267.011406) (xy 103.836215 -267.048163) (xy 103.794162 -267.078716) (xy 103.747847 -267.102314)
			(xy 103.698409 -267.118375) (xy 103.647068 -267.126504) (xy 103.621078 -267.126974) (xy 103.597829 -267.126603)
			(xy 103.551785 -267.120131) (xy 103.507105 -267.10726) (xy 103.464673 -267.088247) (xy 103.444802 -267.076174)
			(xy 103.43261 -267.0683) (xy 103.40467 -267.067792) (xy 102.741476 -267.450316) (xy 102.726785 -267.458165)
			(xy 102.694623 -267.466775) (xy 102.677976 -267.467334) (xy 102.27945 -267.467334) (xy 102.262877 -267.466765)
			(xy 102.230868 -267.458149) (xy 102.202165 -267.441566) (xy 102.190042 -267.43025) (xy 101.876098 -267.116052)
			(xy 101.84892 -267.109194) (xy 101.835458 -267.113258) (xy 101.812365 -267.119675) (xy 101.764934 -267.126556)
			(xy 101.74097 -267.126974) (xy 101.714983 -267.126489) (xy 101.66365 -267.118353) (xy 101.614222 -267.102288)
			(xy 101.567915 -267.078688) (xy 101.525871 -267.048135) (xy 101.489123 -267.01138) (xy 101.458578 -266.96933)
			(xy 101.434987 -266.923019) (xy 101.418932 -266.873587) (xy 101.410806 -266.822253) (xy 101.410262 -266.796266)
			(xy 101.410262 -266.787376) (xy 101.41077 -266.773152) (xy 101.397054 -266.749022) (xy 100.545138 -266.259564)
			(xy 100.517198 -266.260072) (xy 100.50526 -266.267438) (xy 100.485539 -266.279173) (xy 100.443552 -266.297689)
			(xy 100.399411 -266.310234) (xy 100.353961 -266.316569) (xy 100.331016 -266.316968) (xy 100.316284 -266.316714)
			(xy 100.30206 -266.315952) (xy 100.277168 -266.329668) (xy 100.132388 -266.579096) (xy 100.132896 -266.60729)
			(xy 100.140516 -266.619482) (xy 100.152668 -266.639401) (xy 100.171853 -266.681932) (xy 100.184857 -266.726742)
			(xy 100.19142 -266.772937) (xy 100.191824 -266.796266) (xy 100.191343 -266.822257) (xy 100.183217 -266.873601)
			(xy 100.167157 -266.923041) (xy 100.143562 -266.96936) (xy 100.11301 -267.011418) (xy 100.076256 -267.048178)
			(xy 100.034203 -267.078736) (xy 99.987887 -267.102338) (xy 99.93845 -267.118405) (xy 99.887107 -267.12654)
			(xy 99.861116 -267.126974) (xy 99.84613 -267.12672) (xy 99.831906 -267.125958) (xy 99.807268 -267.13942)
			(xy 99.64801 -267.41374) (xy 99.64801 -267.440918) (xy 99.654868 -267.452856) (xy 99.667859 -267.476317)
			(xy 99.686312 -267.526667) (xy 99.695711 -267.579461) (xy 99.69627 -267.606272) (xy 99.695826 -267.630265)
			(xy 99.688322 -267.677662) (xy 99.673496 -267.723301) (xy 99.651711 -267.766058) (xy 99.623506 -267.804881)
			(xy 99.589573 -267.838812) (xy 99.55075 -267.867017) (xy 99.507992 -267.8888) (xy 99.462352 -267.903625)
			(xy 99.414956 -267.911127) (xy 99.390962 -267.91158) (xy 99.364472 -267.911011) (xy 99.312288 -267.901866)
			(xy 99.262464 -267.883855) (xy 99.216494 -267.857519) (xy 99.175756 -267.823648) (xy 99.141471 -267.783257)
			(xy 99.127564 -267.760704) (xy 99.120706 -267.74902) (xy 99.097338 -267.735812) (xy 98.773234 -267.735812)
			(xy 98.749358 -267.750036) (xy 98.742754 -267.762482) (xy 98.730281 -267.784731) (xy 98.699555 -267.825441)
			(xy 98.662946 -267.860956) (xy 98.621322 -267.890432) (xy 98.575668 -267.913173) (xy 98.527065 -267.928639)
			(xy 98.476664 -267.936465) (xy 98.42566 -267.936465) (xy 98.375259 -267.928639) (xy 98.326656 -267.913173)
			(xy 98.281002 -267.890432) (xy 98.239378 -267.860956) (xy 98.202769 -267.825441) (xy 98.172043 -267.784731)
			(xy 98.15957 -267.762482) (xy 98.152966 -267.750036) (xy 98.12909 -267.735812) (xy 97.804732 -267.735812)
			(xy 97.781364 -267.74902) (xy 97.774506 -267.760704) (xy 97.760626 -267.783257) (xy 97.726373 -267.82364)
			(xy 97.685682 -267.857525) (xy 97.663 -267.871194) (xy 97.653856 -267.876528) (xy 97.641156 -267.893292)
			(xy 97.61982 -267.986764) (xy 97.62363 -268.007338) (xy 97.629726 -268.016228) (xy 97.649255 -268.045766)
			(xy 97.683023 -268.10801) (xy 97.710445 -268.173298) (xy 97.731251 -268.240987) (xy 97.745234 -268.310406)
			(xy 97.752256 -268.380871) (xy 97.752662 -268.416278) (xy 97.752192 -268.453552) (xy 97.744401 -268.527692)
			(xy 97.728903 -268.600612) (xy 97.705867 -268.671512) (xy 97.675546 -268.739616) (xy 97.638272 -268.804176)
			(xy 97.594453 -268.864487) (xy 97.54457 -268.919887) (xy 97.489168 -268.969768) (xy 97.428856 -269.013585)
			(xy 97.364294 -269.050857) (xy 97.29619 -269.081176) (xy 97.225289 -269.104209) (xy 97.152369 -269.119705)
			(xy 97.078228 -269.127493) (xy 97.040954 -269.127986) (xy 97.007934 -269.127224) (xy 96.99752 -269.126716)
			(xy 96.978216 -269.133828) (xy 96.90989 -269.198852) (xy 96.901762 -269.217648) (xy 96.901762 -269.228062)
			(xy 96.901217 -269.251393) (xy 96.894373 -269.297555) (xy 96.881114 -269.342299) (xy 96.8617 -269.384736)
			(xy 96.849438 -269.404592) (xy 96.841818 -269.416784) (xy 96.841056 -269.444978) (xy 96.985074 -269.69339)
			(xy 97.009966 -269.706852) (xy 97.02419 -269.70609) (xy 97.040954 -269.705582) (xy 97.066946 -269.706062)
			(xy 97.118291 -269.714187) (xy 97.167732 -269.730245) (xy 97.214052 -269.75384) (xy 97.256111 -269.784392)
			(xy 97.292872 -269.821146) (xy 97.32343 -269.8632) (xy 97.347033 -269.909516) (xy 97.3631 -269.958955)
			(xy 97.371234 -270.010298) (xy 97.371662 -270.03629) (xy 97.371226 -270.059845) (xy 97.364505 -270.106473)
			(xy 97.351239 -270.151676) (xy 97.331698 -270.194542) (xy 97.319338 -270.214598) (xy 97.311464 -270.22679)
			(xy 97.310956 -270.254984) (xy 97.454974 -270.503396) (xy 97.479612 -270.516858) (xy 97.49409 -270.516096)
			(xy 97.511108 -270.515588) (xy 97.537095 -270.516098) (xy 97.588429 -270.52423) (xy 97.637859 -270.540292)
			(xy 97.684168 -270.563888) (xy 97.726216 -270.594439) (xy 97.762967 -270.63119) (xy 97.793516 -270.673239)
			(xy 97.817111 -270.719548) (xy 97.833172 -270.768979) (xy 97.841302 -270.820313) (xy 97.841302 -270.872287)
			(xy 97.833172 -270.923621) (xy 97.817111 -270.973052) (xy 97.793516 -271.019361) (xy 97.762967 -271.06141)
			(xy 97.726216 -271.098161) (xy 97.684168 -271.128712) (xy 97.637859 -271.152308) (xy 97.588429 -271.16837)
			(xy 97.537095 -271.176502) (xy 97.511108 -271.177004) (xy 97.496122 -271.17675) (xy 97.481898 -271.175988)
			(xy 97.45726 -271.18945) (xy 97.312226 -271.439132) (xy 97.312734 -271.46758) (xy 97.320354 -271.479518)
			(xy 97.332502 -271.499438) (xy 97.351681 -271.54197) (xy 97.364678 -271.58678) (xy 97.371235 -271.632974)
			(xy 97.371662 -271.656302) (xy 97.371179 -271.68229) (xy 97.363047 -271.733625) (xy 97.346984 -271.783057)
			(xy 97.323385 -271.829366) (xy 97.292832 -271.871414) (xy 97.256077 -271.908163) (xy 97.214025 -271.93871)
			(xy 97.167712 -271.962302) (xy 97.118279 -271.978358) (xy 97.066942 -271.986482) (xy 97.040954 -271.98701)
			(xy 97.026222 -271.986756) (xy 97.011998 -271.985994) (xy 96.98736 -271.99971) (xy 96.842326 -272.249392)
			(xy 96.843088 -272.277586) (xy 96.850708 -272.289524) (xy 96.862816 -272.309457) (xy 96.881919 -272.352002)
			(xy 96.894854 -272.396809) (xy 96.901364 -272.442989) (xy 96.901762 -272.466308) (xy 96.901324 -272.489862)
			(xy 96.894601 -272.536489) (xy 96.881334 -272.581692) (xy 96.861791 -272.624556) (xy 96.849438 -272.644616)
			(xy 96.841818 -272.656808) (xy 96.841056 -272.685002) (xy 96.985074 -272.933414) (xy 97.009966 -272.946876)
			(xy 97.02419 -272.946114) (xy 97.040954 -272.945606) (xy 97.066945 -272.946086) (xy 97.118289 -272.954211)
			(xy 97.167728 -272.97027) (xy 97.214047 -272.993865) (xy 97.256104 -273.024417) (xy 97.292862 -273.061172)
			(xy 97.323418 -273.103226) (xy 97.347018 -273.149542) (xy 97.363081 -273.19898) (xy 97.371212 -273.250323)
			(xy 97.371662 -273.276314) (xy 97.371224 -273.299868) (xy 97.3645 -273.346495) (xy 97.351232 -273.391697)
			(xy 97.331689 -273.434561) (xy 97.319338 -273.454622) (xy 97.311464 -273.466814) (xy 97.310956 -273.495008)
			(xy 97.454974 -273.74342) (xy 97.479612 -273.756882) (xy 97.49409 -273.75612) (xy 97.511108 -273.755612)
			(xy 97.537093 -273.756122) (xy 97.588424 -273.764253) (xy 97.63785 -273.780314) (xy 97.684156 -273.803909)
			(xy 97.7262 -273.834457) (xy 97.762948 -273.871206) (xy 97.793495 -273.913251) (xy 97.817089 -273.959557)
			(xy 97.833149 -274.008984) (xy 97.841279 -274.060315) (xy 97.841279 -274.112285) (xy 97.833149 -274.163616)
			(xy 97.817089 -274.213043) (xy 97.793495 -274.259349) (xy 97.762948 -274.301394) (xy 97.7262 -274.338143)
			(xy 97.684156 -274.368691) (xy 97.63785 -274.392286) (xy 97.588424 -274.408347) (xy 97.537093 -274.416478)
			(xy 97.511108 -274.417028) (xy 97.496122 -274.416774) (xy 97.481898 -274.416012) (xy 97.45726 -274.429474)
			(xy 97.312226 -274.679156) (xy 97.312734 -274.707604) (xy 97.320354 -274.719542) (xy 97.332507 -274.73946)
			(xy 97.351695 -274.781992) (xy 97.364703 -274.826801) (xy 97.37127 -274.872996) (xy 97.371662 -274.896326)
			(xy 97.371177 -274.922313) (xy 97.363042 -274.973645) (xy 97.346977 -275.023073) (xy 97.323377 -275.06938)
			(xy 97.292824 -275.111424) (xy 97.256069 -275.148171) (xy 97.214018 -275.178715) (xy 97.167707 -275.202305)
			(xy 97.118275 -275.218359) (xy 97.066941 -275.226483) (xy 97.040954 -275.227034) (xy 97.026222 -275.22678)
			(xy 97.011998 -275.226018) (xy 96.98736 -275.239734) (xy 96.842326 -275.489416) (xy 96.843088 -275.51761)
			(xy 96.850708 -275.529548) (xy 96.862821 -275.549479) (xy 96.881933 -275.592023) (xy 96.894879 -275.63683)
			(xy 96.9014 -275.683012) (xy 96.901762 -275.706332) (xy 96.901323 -275.729886) (xy 96.894596 -275.776511)
			(xy 96.881326 -275.821712) (xy 96.861781 -275.864574) (xy 96.849438 -275.88464) (xy 96.841818 -275.896832)
			(xy 96.841056 -275.925026) (xy 96.985074 -276.173438) (xy 97.009966 -276.1869) (xy 97.02419 -276.186138)
			(xy 97.040954 -276.18563) (xy 97.066945 -276.18611) (xy 97.118286 -276.194235) (xy 97.167725 -276.210294)
			(xy 97.214042 -276.23389) (xy 97.256096 -276.264442) (xy 97.292853 -276.301198) (xy 97.323406 -276.343252)
			(xy 97.347003 -276.389568) (xy 97.363063 -276.439006) (xy 97.37119 -276.490347) (xy 97.371662 -276.516338)
			(xy 97.371222 -276.539892) (xy 97.364495 -276.586517) (xy 97.351224 -276.631717) (xy 97.331679 -276.674579)
			(xy 97.319338 -276.694646) (xy 97.311464 -276.706838) (xy 97.310956 -276.735032) (xy 97.454974 -276.983444)
			(xy 97.479612 -276.996906) (xy 97.49409 -276.996144) (xy 97.511108 -276.995636) (xy 97.537091 -276.996146)
			(xy 97.588418 -277.004277) (xy 97.637841 -277.020336) (xy 97.684143 -277.04393) (xy 97.726184 -277.074475)
			(xy 97.76293 -277.111222) (xy 97.793475 -277.153264) (xy 97.817067 -277.199567) (xy 97.833125 -277.24899)
			(xy 97.841254 -277.300317) (xy 97.841254 -277.352283) (xy 97.833125 -277.40361) (xy 97.817067 -277.453033)
			(xy 97.793475 -277.499336) (xy 97.76293 -277.541378) (xy 97.726184 -277.578125) (xy 97.684143 -277.60867)
			(xy 97.637841 -277.632264) (xy 97.588418 -277.648323) (xy 97.537091 -277.656454) (xy 97.511108 -277.657052)
			(xy 97.496122 -277.656798) (xy 97.481898 -277.656036) (xy 97.45726 -277.669498) (xy 97.312226 -277.91918)
			(xy 97.312734 -277.947628) (xy 97.320354 -277.959566) (xy 97.332506 -277.979485) (xy 97.351691 -278.022016)
			(xy 97.364695 -278.066826) (xy 97.371259 -278.113021) (xy 97.371662 -278.13635) (xy 97.371183 -278.162341)
			(xy 97.363057 -278.213682) (xy 97.346999 -278.263121) (xy 97.323403 -278.309438) (xy 97.292851 -278.351492)
			(xy 97.256095 -278.388248) (xy 97.214041 -278.418801) (xy 97.167724 -278.442397) (xy 97.118286 -278.458456)
			(xy 97.066945 -278.466582) (xy 97.040954 -278.467058) (xy 97.026222 -278.466804) (xy 97.011998 -278.466042)
			(xy 96.98736 -278.479758) (xy 96.842326 -278.72944) (xy 96.843088 -278.757634) (xy 96.850708 -278.769572)
			(xy 96.862819 -278.789504) (xy 96.881929 -278.832048) (xy 96.894871 -278.876855) (xy 96.901388 -278.923036)
			(xy 96.901762 -278.946356) (xy 96.901508 -278.961342) (xy 96.900746 -278.97582) (xy 96.914208 -279.000458)
			(xy 97.761298 -279.487122) (xy 97.789492 -279.48636) (xy 97.801684 -279.478486) (xy 97.82182 -279.465974)
			(xy 97.864913 -279.446218) (xy 97.910385 -279.432818) (xy 97.957305 -279.426049) (xy 97.981008 -279.425654)
			(xy 98.006998 -279.426164) (xy 98.058337 -279.434297) (xy 98.107772 -279.45036) (xy 98.154086 -279.473959)
			(xy 98.196138 -279.504513) (xy 98.232893 -279.541268) (xy 98.263445 -279.583321) (xy 98.287043 -279.629635)
			(xy 98.303105 -279.679071) (xy 98.311236 -279.73041) (xy 98.311236 -279.78239) (xy 98.303105 -279.833729)
			(xy 98.287043 -279.883165) (xy 98.263445 -279.929479) (xy 98.232893 -279.971532) (xy 98.196138 -280.008287)
			(xy 98.154086 -280.038841) (xy 98.107772 -280.06244) (xy 98.058337 -280.078503) (xy 98.006998 -280.086636)
			(xy 97.981008 -280.08707) (xy 97.966022 -280.086816) (xy 97.951798 -280.086054) (xy 97.92716 -280.099516)
			(xy 97.78238 -280.349198) (xy 97.782888 -280.377392) (xy 97.790508 -280.389584) (xy 97.80266 -280.409502)
			(xy 97.821846 -280.452034) (xy 97.834849 -280.496844) (xy 97.841412 -280.543039) (xy 97.841816 -280.566368)
			(xy 97.841335 -280.592359) (xy 97.833208 -280.643702) (xy 97.817149 -280.693141) (xy 97.793553 -280.73946)
			(xy 97.763001 -280.781516) (xy 97.726247 -280.818275) (xy 97.684194 -280.848832) (xy 97.637878 -280.872433)
			(xy 97.588441 -280.888499) (xy 97.537099 -280.896632) (xy 97.511108 -280.897076) (xy 97.496376 -280.896822)
			(xy 97.481898 -280.89606) (xy 97.45726 -280.909522) (xy 97.312226 -281.159458) (xy 97.312988 -281.187652)
			(xy 97.320608 -281.19959) (xy 97.332718 -281.219522) (xy 97.351825 -281.262067) (xy 97.364765 -281.306874)
			(xy 97.37128 -281.353055) (xy 97.371662 -281.376374) (xy 97.371662 -281.3764) (xy 97.674859 -281.3764)
			(xy 97.679035 -281.32601) (xy 97.691448 -281.276995) (xy 97.711759 -281.230691) (xy 97.739414 -281.188362)
			(xy 97.77366 -281.151162) (xy 97.813561 -281.120107) (xy 97.85803 -281.096042) (xy 97.905853 -281.079626)
			(xy 97.955727 -281.071304) (xy 97.981008 -281.070812) (xy 98.921062 -281.070812) (xy 98.946341 -281.071354)
			(xy 98.996209 -281.07967) (xy 99.044029 -281.096081) (xy 99.088494 -281.12014) (xy 99.128393 -281.15119)
			(xy 99.162637 -281.188384) (xy 99.190291 -281.230707) (xy 99.210601 -281.277006) (xy 99.223013 -281.326016)
			(xy 99.227189 -281.3764) (xy 100.495088 -281.3764) (xy 100.499263 -281.326019) (xy 100.511672 -281.277012)
			(xy 100.531978 -281.230715) (xy 100.559627 -281.188392) (xy 100.593865 -281.151197) (xy 100.633757 -281.120144)
			(xy 100.678216 -281.09608) (xy 100.72603 -281.079662) (xy 100.775893 -281.071336) (xy 100.80117 -281.070812)
			(xy 101.741224 -281.070812) (xy 101.766497 -281.071388) (xy 101.816353 -281.079711) (xy 101.864159 -281.096126)
			(xy 101.908611 -281.120186) (xy 101.948498 -281.151233) (xy 101.98273 -281.188422) (xy 102.010375 -281.230738)
			(xy 102.030678 -281.277027) (xy 102.043086 -281.326027) (xy 102.04726 -281.3764) (xy 122.108688 -281.3764)
			(xy 122.112863 -281.326017) (xy 122.125274 -281.277007) (xy 122.145582 -281.230709) (xy 122.173233 -281.188385)
			(xy 122.207473 -281.151189) (xy 122.247369 -281.120136) (xy 122.291831 -281.096074) (xy 122.339648 -281.079657)
			(xy 122.389514 -281.071335) (xy 122.414792 -281.070812) (xy 123.354846 -281.070812) (xy 123.380118 -281.071389)
			(xy 123.429971 -281.079715) (xy 123.477774 -281.096133) (xy 123.522223 -281.120193) (xy 123.562106 -281.151241)
			(xy 123.596336 -281.18843) (xy 123.623978 -281.230745) (xy 123.64428 -281.277032) (xy 123.656686 -281.326029)
			(xy 123.66086 -281.3764) (xy 124.928589 -281.3764) (xy 124.932763 -281.326016) (xy 124.945174 -281.277006)
			(xy 124.965483 -281.230707) (xy 124.993135 -281.188382) (xy 125.027376 -281.151186) (xy 125.067273 -281.120134)
			(xy 125.111736 -281.096071) (xy 125.159554 -281.079655) (xy 125.209422 -281.071334) (xy 125.2347 -281.070812)
			(xy 126.174754 -281.070812) (xy 126.200033 -281.071353) (xy 126.249903 -281.079668) (xy 126.297723 -281.096079)
			(xy 126.34219 -281.120137) (xy 126.38209 -281.151187) (xy 126.416335 -281.188381) (xy 126.44399 -281.230705)
			(xy 126.464301 -281.277004) (xy 126.476713 -281.326015) (xy 126.480889 -281.3764) (xy 126.476713 -281.426785)
			(xy 126.464301 -281.475796) (xy 126.44399 -281.522095) (xy 126.416335 -281.564419) (xy 126.38209 -281.601613)
			(xy 126.34219 -281.632663) (xy 126.297723 -281.656721) (xy 126.249903 -281.673132) (xy 126.200033 -281.681447)
			(xy 126.174754 -281.681936) (xy 125.2347 -281.681936) (xy 125.209422 -281.681466) (xy 125.159554 -281.673145)
			(xy 125.111736 -281.656729) (xy 125.067273 -281.632666) (xy 125.027376 -281.601614) (xy 124.993135 -281.564418)
			(xy 124.965483 -281.522093) (xy 124.945174 -281.475794) (xy 124.932763 -281.426784) (xy 124.928589 -281.3764)
			(xy 123.66086 -281.3764) (xy 123.656686 -281.426771) (xy 123.64428 -281.475768) (xy 123.623978 -281.522055)
			(xy 123.596336 -281.56437) (xy 123.562106 -281.601559) (xy 123.522223 -281.632607) (xy 123.477774 -281.656667)
			(xy 123.429971 -281.673085) (xy 123.380118 -281.681411) (xy 123.354846 -281.681936) (xy 122.414792 -281.681936)
			(xy 122.389514 -281.681465) (xy 122.339648 -281.673143) (xy 122.291831 -281.656726) (xy 122.247369 -281.632664)
			(xy 122.207473 -281.601611) (xy 122.173233 -281.564415) (xy 122.145582 -281.522091) (xy 122.125274 -281.475793)
			(xy 122.112863 -281.426783) (xy 122.108688 -281.3764) (xy 102.04726 -281.3764) (xy 102.043086 -281.426773)
			(xy 102.030678 -281.475773) (xy 102.010375 -281.522062) (xy 101.98273 -281.564378) (xy 101.948498 -281.601567)
			(xy 101.908611 -281.632614) (xy 101.864159 -281.656674) (xy 101.816353 -281.673089) (xy 101.766497 -281.681412)
			(xy 101.741224 -281.681936) (xy 100.80117 -281.681936) (xy 100.775893 -281.681464) (xy 100.72603 -281.673138)
			(xy 100.678216 -281.65672) (xy 100.633757 -281.632656) (xy 100.593865 -281.601603) (xy 100.559627 -281.564408)
			(xy 100.531978 -281.522085) (xy 100.511672 -281.475788) (xy 100.499263 -281.426781) (xy 100.495088 -281.3764)
			(xy 99.227189 -281.3764) (xy 99.223013 -281.426784) (xy 99.210601 -281.475794) (xy 99.190291 -281.522093)
			(xy 99.162637 -281.564416) (xy 99.128393 -281.60161) (xy 99.088494 -281.63266) (xy 99.044029 -281.656719)
			(xy 98.996209 -281.67313) (xy 98.946341 -281.681446) (xy 98.921062 -281.681936) (xy 97.981008 -281.681936)
			(xy 97.955727 -281.681496) (xy 97.905853 -281.673174) (xy 97.85803 -281.656758) (xy 97.813561 -281.632693)
			(xy 97.77366 -281.601638) (xy 97.739414 -281.564438) (xy 97.711759 -281.522109) (xy 97.691448 -281.475805)
			(xy 97.679035 -281.42679) (xy 97.674859 -281.3764) (xy 97.371662 -281.3764) (xy 97.371227 -281.399929)
			(xy 97.364508 -281.446558) (xy 97.351244 -281.491763) (xy 97.331705 -281.53463) (xy 97.319338 -281.554682)
			(xy 97.311718 -281.566874) (xy 97.310956 -281.595068) (xy 97.454974 -281.84348) (xy 97.479612 -281.856942)
			(xy 97.494344 -281.85618) (xy 97.511108 -281.855672) (xy 97.537096 -281.856182) (xy 97.588433 -281.864314)
			(xy 97.637865 -281.880377) (xy 97.684177 -281.903975) (xy 97.726226 -281.934526) (xy 97.762979 -281.97128)
			(xy 97.79353 -282.01333) (xy 97.817126 -282.059642) (xy 97.833188 -282.109075) (xy 97.841318 -282.160412)
			(xy 97.841318 -282.1864) (xy 108.485149 -282.1864) (xy 108.48932 -282.136059) (xy 108.50172 -282.087092)
			(xy 108.522011 -282.040833) (xy 108.549639 -281.998544) (xy 108.58385 -281.96138) (xy 108.623712 -281.930354)
			(xy 108.668137 -281.906312) (xy 108.715913 -281.889909) (xy 108.765737 -281.881594) (xy 108.790994 -281.881072)
			(xy 109.731048 -281.881072) (xy 109.756299 -281.881637) (xy 109.806111 -281.889957) (xy 109.853875 -281.906361)
			(xy 109.898288 -281.930402) (xy 109.938139 -281.961425) (xy 109.97234 -281.998583) (xy 109.99996 -282.040863)
			(xy 110.020245 -282.087113) (xy 110.032641 -282.13607) (xy 110.036811 -282.1864) (xy 114.11882 -282.1864)
			(xy 114.122992 -282.136052) (xy 114.135394 -282.087078) (xy 114.155689 -282.040813) (xy 114.183321 -281.99852)
			(xy 114.217539 -281.961352) (xy 114.257407 -281.930323) (xy 114.301839 -281.906279) (xy 114.349622 -281.889877)
			(xy 114.399454 -281.881564) (xy 114.424714 -281.881072) (xy 115.364768 -281.881072) (xy 115.390026 -281.881602)
			(xy 115.439853 -281.889912) (xy 115.487633 -281.90631) (xy 115.532062 -281.93035) (xy 115.571927 -281.961375)
			(xy 115.606142 -281.998539) (xy 115.633773 -282.040827) (xy 115.654067 -282.087088) (xy 115.666468 -282.136057)
			(xy 115.67064 -282.1864) (xy 115.666468 -282.236743) (xy 115.654067 -282.285712) (xy 115.633773 -282.331973)
			(xy 115.606142 -282.374261) (xy 115.571927 -282.411425) (xy 115.532062 -282.44245) (xy 115.487633 -282.46649)
			(xy 115.439853 -282.482888) (xy 115.390026 -282.491198) (xy 115.364768 -282.491688) (xy 114.424714 -282.491688)
			(xy 114.399454 -282.491236) (xy 114.349622 -282.482923) (xy 114.301839 -282.466521) (xy 114.257407 -282.442477)
			(xy 114.217539 -282.411448) (xy 114.183321 -282.37428) (xy 114.155689 -282.331987) (xy 114.135394 -282.285722)
			(xy 114.122992 -282.236748) (xy 114.11882 -282.1864) (xy 110.036811 -282.1864) (xy 110.032641 -282.23673)
			(xy 110.020245 -282.285687) (xy 109.99996 -282.331937) (xy 109.97234 -282.374217) (xy 109.938139 -282.411375)
			(xy 109.898288 -282.442398) (xy 109.853875 -282.466439) (xy 109.806111 -282.482843) (xy 109.756299 -282.491163)
			(xy 109.731048 -282.491688) (xy 108.790994 -282.491688) (xy 108.765737 -282.491206) (xy 108.715913 -282.482891)
			(xy 108.668137 -282.466488) (xy 108.623712 -282.442446) (xy 108.58385 -282.41142) (xy 108.549639 -282.374256)
			(xy 108.522011 -282.331967) (xy 108.50172 -282.285708) (xy 108.48932 -282.236741) (xy 108.485149 -282.1864)
			(xy 97.841318 -282.1864) (xy 97.841318 -282.212388) (xy 97.833188 -282.263725) (xy 97.817126 -282.313158)
			(xy 97.79353 -282.35947) (xy 97.762979 -282.40152) (xy 97.726226 -282.438274) (xy 97.684177 -282.468825)
			(xy 97.637865 -282.492423) (xy 97.588433 -282.508486) (xy 97.537096 -282.516618) (xy 97.511108 -282.517088)
			(xy 97.496122 -282.516834) (xy 97.481898 -282.516072) (xy 97.45726 -282.529534) (xy 97.312226 -282.779216)
			(xy 97.312734 -282.807664) (xy 97.320354 -282.819602) (xy 97.332503 -282.839521) (xy 97.351684 -282.882054)
			(xy 97.364683 -282.926863) (xy 97.371242 -282.973057) (xy 97.371662 -282.996386) (xy 97.371662 -282.9964)
			(xy 97.674871 -282.9964) (xy 97.679047 -282.946012) (xy 97.691459 -282.896999) (xy 97.711769 -282.850697)
			(xy 97.739424 -282.808369) (xy 97.773668 -282.771171) (xy 97.813568 -282.740117) (xy 97.858035 -282.716053)
			(xy 97.905856 -282.699637) (xy 97.955728 -282.691316) (xy 97.981008 -282.690824) (xy 98.921062 -282.690824)
			(xy 98.946342 -282.691342) (xy 98.996212 -282.699658) (xy 99.044033 -282.71607) (xy 99.088501 -282.74013)
			(xy 99.128401 -282.771181) (xy 99.162646 -282.808377) (xy 99.190302 -282.850702) (xy 99.210613 -282.897002)
			(xy 99.223025 -282.946014) (xy 99.227201 -282.9964) (xy 100.4951 -282.9964) (xy 100.499275 -282.946021)
			(xy 100.511684 -282.897016) (xy 100.531989 -282.850721) (xy 100.559637 -282.8084) (xy 100.593873 -282.771206)
			(xy 100.633764 -282.740154) (xy 100.678221 -282.716091) (xy 100.726032 -282.699673) (xy 100.775894 -282.691348)
			(xy 100.80117 -282.690824) (xy 101.741224 -282.690824) (xy 101.766498 -282.691376) (xy 101.816356 -282.699699)
			(xy 101.864164 -282.716115) (xy 101.908618 -282.740176) (xy 101.948506 -282.771224) (xy 101.98274 -282.808415)
			(xy 102.010385 -282.850733) (xy 102.030689 -282.897024) (xy 102.043098 -282.946025) (xy 102.047272 -282.9964)
			(xy 103.315 -282.9964) (xy 103.319175 -282.94602) (xy 103.331584 -282.897014) (xy 103.35189 -282.850719)
			(xy 103.379539 -282.808397) (xy 103.413776 -282.771203) (xy 103.453668 -282.740151) (xy 103.498126 -282.716089)
			(xy 103.545939 -282.699672) (xy 103.595802 -282.691348) (xy 103.621078 -282.690824) (xy 104.561132 -282.690824)
			(xy 104.586405 -282.691376) (xy 104.636262 -282.699701) (xy 104.684069 -282.716117) (xy 104.728522 -282.740178)
			(xy 104.768409 -282.771227) (xy 104.802642 -282.808418) (xy 104.830287 -282.850735) (xy 104.85059 -282.897025)
			(xy 104.862998 -282.946026) (xy 104.867172 -282.9964) (xy 106.1349 -282.9964) (xy 106.139075 -282.946019)
			(xy 106.151485 -282.897012) (xy 106.171791 -282.850717) (xy 106.199441 -282.808394) (xy 106.233679 -282.7712)
			(xy 106.273572 -282.740149) (xy 106.318032 -282.716086) (xy 106.365846 -282.69967) (xy 106.415709 -282.691347)
			(xy 106.440986 -282.690824) (xy 107.38104 -282.690824) (xy 107.406313 -282.691377) (xy 107.456169 -282.699702)
			(xy 107.503975 -282.71612) (xy 107.548426 -282.740181) (xy 107.588312 -282.77123) (xy 107.622544 -282.80842)
			(xy 107.650188 -282.850737) (xy 107.67049 -282.897027) (xy 107.682898 -282.946026) (xy 107.687072 -282.9964)
			(xy 116.468571 -282.9964) (xy 116.472747 -282.946011) (xy 116.48516 -282.896996) (xy 116.505471 -282.850693)
			(xy 116.533127 -282.808365) (xy 116.567373 -282.771166) (xy 116.607275 -282.740112) (xy 116.651744 -282.716049)
			(xy 116.699568 -282.699634) (xy 116.749441 -282.691315) (xy 116.774722 -282.690824) (xy 117.714776 -282.690824)
			(xy 117.740055 -282.691343) (xy 117.789924 -282.699661) (xy 117.837743 -282.716074) (xy 117.882208 -282.740135)
			(xy 117.922107 -282.771186) (xy 117.95635 -282.808381) (xy 117.984004 -282.850706) (xy 118.004313 -282.897005)
			(xy 118.016725 -282.946015) (xy 118.020901 -282.9964) (xy 119.288471 -282.9964) (xy 119.292647 -282.94601)
			(xy 119.30506 -282.896994) (xy 119.325373 -282.850691) (xy 119.353029 -282.808362) (xy 119.387276 -282.771163)
			(xy 119.427179 -282.740109) (xy 119.47165 -282.716047) (xy 119.519474 -282.699633) (xy 119.569348 -282.691315)
			(xy 119.59463 -282.690824) (xy 120.534684 -282.690824) (xy 120.559962 -282.691344) (xy 120.60983 -282.699663)
			(xy 120.657648 -282.716077) (xy 120.702113 -282.740137) (xy 120.74201 -282.771189) (xy 120.776252 -282.808384)
			(xy 120.803905 -282.850708) (xy 120.824214 -282.897006) (xy 120.836625 -282.946016) (xy 120.840801 -282.9964)
			(xy 122.1087 -282.9964) (xy 122.112875 -282.946019) (xy 122.125285 -282.897011) (xy 122.145592 -282.850715)
			(xy 122.173242 -282.808392) (xy 122.207481 -282.771198) (xy 122.247375 -282.740147) (xy 122.291836 -282.716085)
			(xy 122.33965 -282.699669) (xy 122.389515 -282.691347) (xy 122.414792 -282.690824) (xy 123.354846 -282.690824)
			(xy 123.380119 -282.691377) (xy 123.429974 -282.699704) (xy 123.477779 -282.716122) (xy 123.52223 -282.740183)
			(xy 123.562114 -282.771232) (xy 123.596345 -282.808422) (xy 123.623989 -282.850739) (xy 123.644291 -282.897028)
			(xy 123.656698 -282.946027) (xy 123.660872 -282.9964) (xy 124.928601 -282.9964) (xy 124.932775 -282.946018)
			(xy 124.945186 -282.89701) (xy 124.965494 -282.850713) (xy 124.993144 -282.80839) (xy 125.027384 -282.771195)
			(xy 125.067279 -282.740144) (xy 125.111741 -282.716082) (xy 125.159557 -282.699667) (xy 125.209423 -282.691346)
			(xy 125.2347 -282.690824) (xy 126.174754 -282.690824) (xy 126.200034 -282.691341) (xy 126.249906 -282.699657)
			(xy 126.297728 -282.716068) (xy 126.342197 -282.740127) (xy 126.382098 -282.771178) (xy 126.416344 -282.808374)
			(xy 126.444 -282.850699) (xy 126.464312 -282.897) (xy 126.476725 -282.946013) (xy 126.480901 -282.9964)
			(xy 126.476725 -283.046787) (xy 126.464312 -283.0958) (xy 126.444 -283.142101) (xy 126.416344 -283.184426)
			(xy 126.382098 -283.221622) (xy 126.342197 -283.252673) (xy 126.297728 -283.276732) (xy 126.249906 -283.293143)
			(xy 126.200034 -283.301459) (xy 126.174754 -283.301948) (xy 125.2347 -283.301948) (xy 125.209423 -283.301454)
			(xy 125.159557 -283.293133) (xy 125.111741 -283.276718) (xy 125.067279 -283.252656) (xy 125.027384 -283.221605)
			(xy 124.993144 -283.18441) (xy 124.965494 -283.142087) (xy 124.945186 -283.09579) (xy 124.932775 -283.046782)
			(xy 124.928601 -282.9964) (xy 123.660872 -282.9964) (xy 123.656698 -283.046773) (xy 123.644291 -283.095772)
			(xy 123.623989 -283.142061) (xy 123.596345 -283.184378) (xy 123.562114 -283.221568) (xy 123.52223 -283.252617)
			(xy 123.477779 -283.276678) (xy 123.429974 -283.293096) (xy 123.380119 -283.301423) (xy 123.354846 -283.301948)
			(xy 122.414792 -283.301948) (xy 122.389515 -283.301453) (xy 122.33965 -283.293131) (xy 122.291836 -283.276715)
			(xy 122.247375 -283.252653) (xy 122.207481 -283.221602) (xy 122.173242 -283.184408) (xy 122.145592 -283.142085)
			(xy 122.125285 -283.095789) (xy 122.112875 -283.046781) (xy 122.1087 -282.9964) (xy 120.840801 -282.9964)
			(xy 120.836625 -283.046784) (xy 120.824214 -283.095794) (xy 120.803905 -283.142092) (xy 120.776252 -283.184416)
			(xy 120.74201 -283.221611) (xy 120.702113 -283.252663) (xy 120.657648 -283.276723) (xy 120.60983 -283.293137)
			(xy 120.559962 -283.301456) (xy 120.534684 -283.301948) (xy 119.59463 -283.301948) (xy 119.569348 -283.301485)
			(xy 119.519474 -283.293167) (xy 119.47165 -283.276753) (xy 119.427179 -283.252691) (xy 119.387276 -283.221637)
			(xy 119.353029 -283.184438) (xy 119.325373 -283.142109) (xy 119.30506 -283.095806) (xy 119.292647 -283.04679)
			(xy 119.288471 -282.9964) (xy 118.020901 -282.9964) (xy 118.016725 -283.046785) (xy 118.004313 -283.095795)
			(xy 117.984004 -283.142094) (xy 117.95635 -283.184419) (xy 117.922107 -283.221614) (xy 117.882208 -283.252665)
			(xy 117.837743 -283.276726) (xy 117.789924 -283.293139) (xy 117.740055 -283.301457) (xy 117.714776 -283.301948)
			(xy 116.774722 -283.301948) (xy 116.749441 -283.301485) (xy 116.699568 -283.293166) (xy 116.651744 -283.276751)
			(xy 116.607275 -283.252688) (xy 116.567373 -283.221634) (xy 116.533127 -283.184435) (xy 116.505471 -283.142107)
			(xy 116.48516 -283.095804) (xy 116.472747 -283.046789) (xy 116.468571 -282.9964) (xy 107.687072 -282.9964)
			(xy 107.682898 -283.046774) (xy 107.67049 -283.095773) (xy 107.650188 -283.142063) (xy 107.622544 -283.18438)
			(xy 107.588312 -283.22157) (xy 107.548426 -283.252619) (xy 107.503975 -283.27668) (xy 107.456169 -283.293098)
			(xy 107.406313 -283.301423) (xy 107.38104 -283.301948) (xy 106.440986 -283.301948) (xy 106.415709 -283.301453)
			(xy 106.365846 -283.29313) (xy 106.318032 -283.276714) (xy 106.273572 -283.252651) (xy 106.233679 -283.2216)
			(xy 106.199441 -283.184406) (xy 106.171791 -283.142083) (xy 106.151485 -283.095788) (xy 106.139075 -283.046781)
			(xy 106.1349 -282.9964) (xy 104.867172 -282.9964) (xy 104.862998 -283.046774) (xy 104.85059 -283.095775)
			(xy 104.830287 -283.142065) (xy 104.802642 -283.184382) (xy 104.768409 -283.221573) (xy 104.728522 -283.252622)
			(xy 104.684069 -283.276683) (xy 104.636262 -283.293099) (xy 104.586405 -283.301424) (xy 104.561132 -283.301948)
			(xy 103.621078 -283.301948) (xy 103.595802 -283.301452) (xy 103.545939 -283.293128) (xy 103.498126 -283.276711)
			(xy 103.453668 -283.252649) (xy 103.413776 -283.221597) (xy 103.379539 -283.184403) (xy 103.35189 -283.142081)
			(xy 103.331584 -283.095786) (xy 103.319175 -283.04678) (xy 103.315 -282.9964) (xy 102.047272 -282.9964)
			(xy 102.043098 -283.046775) (xy 102.030689 -283.095776) (xy 102.010385 -283.142067) (xy 101.98274 -283.184385)
			(xy 101.948506 -283.221576) (xy 101.908618 -283.252624) (xy 101.864164 -283.276685) (xy 101.816356 -283.293101)
			(xy 101.766498 -283.301424) (xy 101.741224 -283.301948) (xy 100.80117 -283.301948) (xy 100.775894 -283.301452)
			(xy 100.726032 -283.293127) (xy 100.678221 -283.276709) (xy 100.633764 -283.252646) (xy 100.593873 -283.221594)
			(xy 100.559637 -283.1844) (xy 100.531989 -283.142079) (xy 100.511684 -283.095784) (xy 100.499275 -283.046779)
			(xy 100.4951 -282.9964) (xy 99.227201 -282.9964) (xy 99.223025 -283.046786) (xy 99.210613 -283.095798)
			(xy 99.190302 -283.142098) (xy 99.162646 -283.184423) (xy 99.128401 -283.221619) (xy 99.088501 -283.25267)
			(xy 99.044033 -283.27673) (xy 98.996212 -283.293142) (xy 98.946342 -283.301458) (xy 98.921062 -283.301948)
			(xy 97.981008 -283.301948) (xy 97.955728 -283.301484) (xy 97.905856 -283.293163) (xy 97.858035 -283.276747)
			(xy 97.813568 -283.252683) (xy 97.773668 -283.221629) (xy 97.739424 -283.184431) (xy 97.711769 -283.142103)
			(xy 97.691459 -283.095801) (xy 97.679047 -283.046788) (xy 97.674871 -282.9964) (xy 97.371662 -282.9964)
			(xy 97.37118 -283.022375) (xy 97.36305 -283.073712) (xy 97.346989 -283.123146) (xy 97.323391 -283.169458)
			(xy 97.292838 -283.211507) (xy 97.256083 -283.248259) (xy 97.21403 -283.278808) (xy 97.167716 -283.302401)
			(xy 97.118281 -283.318458) (xy 97.066943 -283.326582) (xy 97.040954 -283.327094) (xy 97.026222 -283.32684)
			(xy 97.011998 -283.326078) (xy 96.98736 -283.339794) (xy 96.842326 -283.589476) (xy 96.843088 -283.61767)
			(xy 96.850708 -283.629608) (xy 96.862817 -283.64954) (xy 96.881922 -283.692085) (xy 96.894859 -283.736892)
			(xy 96.901372 -283.783073) (xy 96.901762 -283.806392) (xy 96.901762 -283.8064) (xy 108.485161 -283.8064)
			(xy 108.489332 -283.756061) (xy 108.501732 -283.707095) (xy 108.522022 -283.660838) (xy 108.549649 -283.618552)
			(xy 108.583859 -283.581389) (xy 108.623719 -283.550364) (xy 108.668142 -283.526323) (xy 108.715916 -283.509921)
			(xy 108.765738 -283.501606) (xy 108.790994 -283.501084) (xy 109.731048 -283.501084) (xy 109.7563 -283.501625)
			(xy 109.806114 -283.509945) (xy 109.85388 -283.52635) (xy 109.898295 -283.550392) (xy 109.938147 -283.581416)
			(xy 109.97235 -283.618576) (xy 109.999971 -283.660858) (xy 110.020256 -283.707109) (xy 110.032653 -283.756068)
			(xy 110.036823 -283.8064) (xy 114.118832 -283.8064) (xy 114.123004 -283.756054) (xy 114.135406 -283.707082)
			(xy 114.155699 -283.660819) (xy 114.183331 -283.618527) (xy 114.217547 -283.581361) (xy 114.257413 -283.550333)
			(xy 114.301844 -283.52629) (xy 114.349625 -283.509889) (xy 114.399455 -283.501576) (xy 114.424714 -283.501084)
			(xy 115.364768 -283.501084) (xy 115.390027 -283.50159) (xy 115.439856 -283.5099) (xy 115.487638 -283.526299)
			(xy 115.532068 -283.55034) (xy 115.571936 -283.581366) (xy 115.606152 -283.618531) (xy 115.633784 -283.660822)
			(xy 115.654078 -283.707084) (xy 115.66648 -283.756055) (xy 115.670652 -283.8064) (xy 115.66648 -283.856745)
			(xy 115.654078 -283.905716) (xy 115.633784 -283.951978) (xy 115.606152 -283.994269) (xy 115.571936 -284.031434)
			(xy 115.532068 -284.06246) (xy 115.487638 -284.086501) (xy 115.439856 -284.1029) (xy 115.390027 -284.11121)
			(xy 115.364768 -284.1117) (xy 114.424714 -284.1117) (xy 114.399455 -284.111224) (xy 114.349625 -284.102911)
			(xy 114.301844 -284.08651) (xy 114.257413 -284.062467) (xy 114.217547 -284.031439) (xy 114.183331 -283.994273)
			(xy 114.155699 -283.951981) (xy 114.135406 -283.905718) (xy 114.123004 -283.856746) (xy 114.118832 -283.8064)
			(xy 110.036823 -283.8064) (xy 110.032653 -283.856732) (xy 110.020256 -283.905691) (xy 109.999971 -283.951942)
			(xy 109.97235 -283.994224) (xy 109.938147 -284.031384) (xy 109.898295 -284.062408) (xy 109.85388 -284.08645)
			(xy 109.806114 -284.102855) (xy 109.7563 -284.111175) (xy 109.731048 -284.1117) (xy 108.790994 -284.1117)
			(xy 108.765738 -284.111194) (xy 108.715916 -284.102879) (xy 108.668142 -284.086477) (xy 108.623719 -284.062436)
			(xy 108.583859 -284.031411) (xy 108.549649 -283.994248) (xy 108.522022 -283.951962) (xy 108.501732 -283.905705)
			(xy 108.489332 -283.856739) (xy 108.485161 -283.8064) (xy 96.901762 -283.8064) (xy 96.901326 -283.829947)
			(xy 96.894604 -283.876574) (xy 96.881339 -283.921778) (xy 96.861798 -283.964644) (xy 96.849438 -283.9847)
			(xy 96.841818 -283.996892) (xy 96.841056 -284.025086) (xy 96.985074 -284.273498) (xy 97.009966 -284.28696)
			(xy 97.02419 -284.286198) (xy 97.040954 -284.28569) (xy 97.066946 -284.28617) (xy 97.11829 -284.294295)
			(xy 97.167731 -284.310353) (xy 97.21405 -284.333949) (xy 97.256108 -284.3645) (xy 97.292869 -284.401255)
			(xy 97.323426 -284.443309) (xy 97.347028 -284.489625) (xy 97.363094 -284.539063) (xy 97.371227 -284.590406)
			(xy 97.371662 -284.616398) (xy 97.371662 -284.6164) (xy 97.674883 -284.6164) (xy 97.679059 -284.566014)
			(xy 97.69147 -284.517003) (xy 97.71178 -284.470702) (xy 97.739433 -284.428377) (xy 97.773676 -284.39118)
			(xy 97.813574 -284.360127) (xy 97.85804 -284.336064) (xy 97.905859 -284.319649) (xy 97.955729 -284.311328)
			(xy 97.981008 -284.310836) (xy 98.921062 -284.310836) (xy 98.946343 -284.31133) (xy 98.996215 -284.319647)
			(xy 99.044038 -284.336059) (xy 99.088508 -284.36012) (xy 99.12841 -284.391172) (xy 99.162656 -284.428369)
			(xy 99.190312 -284.470696) (xy 99.210624 -284.516998) (xy 99.223037 -284.566012) (xy 99.227213 -284.6164)
			(xy 100.495112 -284.6164) (xy 100.499287 -284.566023) (xy 100.511695 -284.51702) (xy 100.532 -284.470727)
			(xy 100.559646 -284.428407) (xy 100.593881 -284.391215) (xy 100.63377 -284.360164) (xy 100.678226 -284.336102)
			(xy 100.726035 -284.319685) (xy 100.775895 -284.31136) (xy 100.80117 -284.310836) (xy 101.741224 -284.310836)
			(xy 101.766499 -284.311364) (xy 101.816359 -284.319688) (xy 101.864169 -284.336104) (xy 101.908625 -284.360165)
			(xy 101.948514 -284.391216) (xy 101.982749 -284.428408) (xy 102.010396 -284.470727) (xy 102.030701 -284.51702)
			(xy 102.043109 -284.566023) (xy 102.047284 -284.6164) (xy 103.315012 -284.6164) (xy 103.319187 -284.566022)
			(xy 103.331596 -284.517018) (xy 103.351901 -284.470725) (xy 103.379548 -284.428404) (xy 103.413784 -284.391212)
			(xy 103.453674 -284.360161) (xy 103.498131 -284.3361) (xy 103.545942 -284.319683) (xy 103.595803 -284.31136)
			(xy 103.621078 -284.310836) (xy 104.561132 -284.310836) (xy 104.586406 -284.311364) (xy 104.636265 -284.319689)
			(xy 104.684074 -284.336106) (xy 104.728529 -284.360168) (xy 104.768417 -284.391218) (xy 104.802651 -284.42841)
			(xy 104.830297 -284.470729) (xy 104.850601 -284.517021) (xy 104.863009 -284.566024) (xy 104.867184 -284.6164)
			(xy 106.134912 -284.6164) (xy 106.139087 -284.566021) (xy 106.151496 -284.517016) (xy 106.171802 -284.470722)
			(xy 106.19945 -284.428402) (xy 106.233687 -284.391209) (xy 106.273579 -284.360159) (xy 106.318037 -284.336097)
			(xy 106.365849 -284.319682) (xy 106.41571 -284.311359) (xy 106.440986 -284.310836) (xy 107.38104 -284.310836)
			(xy 107.406314 -284.311365) (xy 107.456172 -284.319691) (xy 107.503979 -284.336109) (xy 107.548433 -284.360171)
			(xy 107.58832 -284.391221) (xy 107.622553 -284.428413) (xy 107.650198 -284.470731) (xy 107.670502 -284.517023)
			(xy 107.68291 -284.566024) (xy 107.687084 -284.6164) (xy 116.468583 -284.6164) (xy 116.472759 -284.566013)
			(xy 116.485171 -284.517) (xy 116.505482 -284.470699) (xy 116.533137 -284.428372) (xy 116.567381 -284.391175)
			(xy 116.607282 -284.360122) (xy 116.651749 -284.33606) (xy 116.699571 -284.319646) (xy 116.749442 -284.311327)
			(xy 116.774722 -284.310836) (xy 117.714776 -284.310836) (xy 117.740056 -284.311331) (xy 117.789927 -284.319649)
			(xy 117.837748 -284.336063) (xy 117.882215 -284.360125) (xy 117.922115 -284.391177) (xy 117.95636 -284.428374)
			(xy 117.984014 -284.4707) (xy 118.004325 -284.517001) (xy 118.016737 -284.566013) (xy 118.020913 -284.6164)
			(xy 119.288483 -284.6164) (xy 119.292659 -284.566012) (xy 119.305072 -284.516998) (xy 119.325383 -284.470696)
			(xy 119.353039 -284.428369) (xy 119.387285 -284.391172) (xy 119.427186 -284.360119) (xy 119.471655 -284.336058)
			(xy 119.519477 -284.319644) (xy 119.569349 -284.311327) (xy 119.59463 -284.310836) (xy 120.534684 -284.310836)
			(xy 120.559963 -284.311332) (xy 120.609833 -284.319651) (xy 120.657653 -284.336066) (xy 120.702119 -284.360127)
			(xy 120.742018 -284.39118) (xy 120.776262 -284.428376) (xy 120.803915 -284.470702) (xy 120.824225 -284.517002)
			(xy 120.836637 -284.566014) (xy 120.840813 -284.6164) (xy 122.108712 -284.6164) (xy 122.112887 -284.56602)
			(xy 122.125297 -284.517015) (xy 122.145603 -284.470721) (xy 122.173252 -284.4284) (xy 122.207489 -284.391207)
			(xy 122.247382 -284.360157) (xy 122.291841 -284.336096) (xy 122.339653 -284.31968) (xy 122.389516 -284.311359)
			(xy 122.414792 -284.310836) (xy 123.354846 -284.310836) (xy 123.38012 -284.311366) (xy 123.429977 -284.319692)
			(xy 123.477783 -284.336111) (xy 123.522236 -284.360173) (xy 123.562123 -284.391223) (xy 123.596355 -284.428415)
			(xy 123.623999 -284.470733) (xy 123.644302 -284.517024) (xy 123.65671 -284.566025) (xy 123.660884 -284.6164)
			(xy 124.928613 -284.6164) (xy 124.932787 -284.56602) (xy 124.945197 -284.517014) (xy 124.965504 -284.470718)
			(xy 124.993154 -284.428397) (xy 125.027393 -284.391204) (xy 125.067286 -284.360154) (xy 125.111746 -284.336093)
			(xy 125.15956 -284.319679) (xy 125.209423 -284.311358) (xy 125.2347 -284.310836) (xy 126.174754 -284.310836)
			(xy 126.200035 -284.311329) (xy 126.249909 -284.319645) (xy 126.297733 -284.336057) (xy 126.342203 -284.360117)
			(xy 126.382107 -284.391169) (xy 126.416354 -284.428366) (xy 126.444011 -284.470694) (xy 126.464323 -284.516996)
			(xy 126.476737 -284.566011) (xy 126.480913 -284.6164) (xy 126.476737 -284.666789) (xy 126.464323 -284.715804)
			(xy 126.444011 -284.762106) (xy 126.416354 -284.804434) (xy 126.382107 -284.841631) (xy 126.342203 -284.872683)
			(xy 126.297733 -284.896743) (xy 126.249909 -284.913155) (xy 126.200035 -284.921471) (xy 126.174754 -284.92196)
			(xy 125.2347 -284.92196) (xy 125.209423 -284.921442) (xy 125.15956 -284.913121) (xy 125.111746 -284.896707)
			(xy 125.067286 -284.872646) (xy 125.027393 -284.841596) (xy 124.993154 -284.804403) (xy 124.965504 -284.762082)
			(xy 124.945197 -284.715786) (xy 124.932787 -284.66678) (xy 124.928613 -284.6164) (xy 123.660884 -284.6164)
			(xy 123.65671 -284.666775) (xy 123.644302 -284.715776) (xy 123.623999 -284.762067) (xy 123.596355 -284.804385)
			(xy 123.562123 -284.841577) (xy 123.522236 -284.872627) (xy 123.477783 -284.896689) (xy 123.429977 -284.913108)
			(xy 123.38012 -284.921434) (xy 123.354846 -284.92196) (xy 122.414792 -284.92196) (xy 122.389516 -284.921441)
			(xy 122.339653 -284.91312) (xy 122.291841 -284.896704) (xy 122.247382 -284.872643) (xy 122.207489 -284.841593)
			(xy 122.173252 -284.8044) (xy 122.145603 -284.762079) (xy 122.125297 -284.715785) (xy 122.112887 -284.66678)
			(xy 122.108712 -284.6164) (xy 120.840813 -284.6164) (xy 120.836637 -284.666786) (xy 120.824225 -284.715798)
			(xy 120.803915 -284.762098) (xy 120.776262 -284.804424) (xy 120.742018 -284.84162) (xy 120.702119 -284.872673)
			(xy 120.657653 -284.896734) (xy 120.609833 -284.913149) (xy 120.559963 -284.921468) (xy 120.534684 -284.92196)
			(xy 119.59463 -284.92196) (xy 119.569349 -284.921473) (xy 119.519477 -284.913156) (xy 119.471655 -284.896742)
			(xy 119.427186 -284.872681) (xy 119.387285 -284.841628) (xy 119.353039 -284.804431) (xy 119.325383 -284.762104)
			(xy 119.305072 -284.715802) (xy 119.292659 -284.666788) (xy 119.288483 -284.6164) (xy 118.020913 -284.6164)
			(xy 118.016737 -284.666787) (xy 118.004325 -284.715799) (xy 117.984014 -284.7621) (xy 117.95636 -284.804426)
			(xy 117.922115 -284.841623) (xy 117.882215 -284.872675) (xy 117.837748 -284.896737) (xy 117.789927 -284.913151)
			(xy 117.740056 -284.921469) (xy 117.714776 -284.92196) (xy 116.774722 -284.92196) (xy 116.749442 -284.921473)
			(xy 116.699571 -284.913154) (xy 116.651749 -284.89674) (xy 116.607282 -284.872678) (xy 116.567381 -284.841625)
			(xy 116.533137 -284.804428) (xy 116.505482 -284.762101) (xy 116.485171 -284.7158) (xy 116.472759 -284.666787)
			(xy 116.468583 -284.6164) (xy 107.687084 -284.6164) (xy 107.68291 -284.666776) (xy 107.670502 -284.715777)
			(xy 107.650198 -284.762069) (xy 107.622553 -284.804387) (xy 107.58832 -284.841579) (xy 107.548433 -284.872629)
			(xy 107.503979 -284.896691) (xy 107.456172 -284.913109) (xy 107.406314 -284.921435) (xy 107.38104 -284.92196)
			(xy 106.440986 -284.92196) (xy 106.41571 -284.921441) (xy 106.365849 -284.913118) (xy 106.318037 -284.896703)
			(xy 106.273579 -284.872641) (xy 106.233687 -284.841591) (xy 106.19945 -284.804398) (xy 106.171802 -284.762078)
			(xy 106.151496 -284.715784) (xy 106.139087 -284.666779) (xy 106.134912 -284.6164) (xy 104.867184 -284.6164)
			(xy 104.863009 -284.666776) (xy 104.850601 -284.715779) (xy 104.830297 -284.762071) (xy 104.802651 -284.80439)
			(xy 104.768417 -284.841582) (xy 104.728529 -284.872632) (xy 104.684074 -284.896694) (xy 104.636265 -284.913111)
			(xy 104.586406 -284.921436) (xy 104.561132 -284.92196) (xy 103.621078 -284.92196) (xy 103.595803 -284.92144)
			(xy 103.545942 -284.913117) (xy 103.498131 -284.8967) (xy 103.453674 -284.872639) (xy 103.413784 -284.841588)
			(xy 103.379548 -284.804396) (xy 103.351901 -284.762075) (xy 103.331596 -284.715782) (xy 103.319187 -284.666778)
			(xy 103.315012 -284.6164) (xy 102.047284 -284.6164) (xy 102.043109 -284.666777) (xy 102.030701 -284.71578)
			(xy 102.010396 -284.762073) (xy 101.982749 -284.804392) (xy 101.948514 -284.841584) (xy 101.908625 -284.872635)
			(xy 101.864169 -284.896696) (xy 101.816359 -284.913112) (xy 101.766499 -284.921436) (xy 101.741224 -284.92196)
			(xy 100.80117 -284.92196) (xy 100.775895 -284.92144) (xy 100.726035 -284.913115) (xy 100.678226 -284.896698)
			(xy 100.63377 -284.872636) (xy 100.593881 -284.841585) (xy 100.559646 -284.804393) (xy 100.532 -284.762073)
			(xy 100.511695 -284.71578) (xy 100.499287 -284.666777) (xy 100.495112 -284.6164) (xy 99.227213 -284.6164)
			(xy 99.223037 -284.666788) (xy 99.210624 -284.715802) (xy 99.190312 -284.762104) (xy 99.162656 -284.804431)
			(xy 99.12841 -284.841628) (xy 99.088508 -284.87268) (xy 99.044038 -284.896741) (xy 98.996215 -284.913153)
			(xy 98.946343 -284.92147) (xy 98.921062 -284.92196) (xy 97.981008 -284.92196) (xy 97.955729 -284.921472)
			(xy 97.905859 -284.913151) (xy 97.85804 -284.896736) (xy 97.813574 -284.872673) (xy 97.773676 -284.84162)
			(xy 97.739433 -284.804423) (xy 97.71178 -284.762098) (xy 97.69147 -284.715797) (xy 97.679059 -284.666786)
			(xy 97.674883 -284.6164) (xy 97.371662 -284.6164) (xy 97.371225 -284.639952) (xy 97.364503 -284.68658)
			(xy 97.351237 -284.731783) (xy 97.331695 -284.774648) (xy 97.319338 -284.794706) (xy 97.311464 -284.806898)
			(xy 97.310956 -284.835092) (xy 97.454974 -285.083504) (xy 97.479612 -285.096966) (xy 97.49409 -285.096204)
			(xy 97.511108 -285.095696) (xy 97.537094 -285.096206) (xy 97.588427 -285.104338) (xy 97.637856 -285.120399)
			(xy 97.684164 -285.143995) (xy 97.726211 -285.174545) (xy 97.762961 -285.211295) (xy 97.793509 -285.253343)
			(xy 97.817104 -285.299651) (xy 97.833164 -285.34908) (xy 97.841295 -285.400414) (xy 97.841295 -285.4264)
			(xy 108.485173 -285.4264) (xy 108.489344 -285.376063) (xy 108.501743 -285.327099) (xy 108.522032 -285.280844)
			(xy 108.549658 -285.238559) (xy 108.583867 -285.201398) (xy 108.623725 -285.170374) (xy 108.668147 -285.146334)
			(xy 108.715919 -285.129932) (xy 108.765739 -285.121618) (xy 108.790994 -285.121096) (xy 109.731048 -285.121096)
			(xy 109.756301 -285.121613) (xy 109.806117 -285.129933) (xy 109.853885 -285.146339) (xy 109.898301 -285.170382)
			(xy 109.938155 -285.201407) (xy 109.972359 -285.238568) (xy 109.999981 -285.280852) (xy 110.020267 -285.327105)
			(xy 110.032665 -285.376066) (xy 110.036835 -285.4264) (xy 114.118844 -285.4264) (xy 114.123016 -285.376056)
			(xy 114.135417 -285.327086) (xy 114.15571 -285.280825) (xy 114.18334 -285.238535) (xy 114.217555 -285.201369)
			(xy 114.25742 -285.170343) (xy 114.301849 -285.146301) (xy 114.349628 -285.1299) (xy 114.399456 -285.121588)
			(xy 114.424714 -285.121096) (xy 115.364768 -285.121096) (xy 115.390028 -285.121578) (xy 115.439859 -285.129889)
			(xy 115.487643 -285.146288) (xy 115.532075 -285.17033) (xy 115.571944 -285.201357) (xy 115.606161 -285.238524)
			(xy 115.633795 -285.280816) (xy 115.654089 -285.32708) (xy 115.666492 -285.376053) (xy 115.670664 -285.4264)
			(xy 115.666492 -285.476747) (xy 115.654089 -285.52572) (xy 115.633795 -285.571984) (xy 115.606161 -285.614276)
			(xy 115.571944 -285.651443) (xy 115.532075 -285.68247) (xy 115.487643 -285.706512) (xy 115.439859 -285.722911)
			(xy 115.390028 -285.731222) (xy 115.364768 -285.731712) (xy 114.424714 -285.731712) (xy 114.399456 -285.731212)
			(xy 114.349628 -285.7229) (xy 114.301849 -285.706499) (xy 114.25742 -285.682457) (xy 114.217555 -285.651431)
			(xy 114.18334 -285.614265) (xy 114.15571 -285.571975) (xy 114.135417 -285.525714) (xy 114.123016 -285.476744)
			(xy 114.118844 -285.4264) (xy 110.036835 -285.4264) (xy 110.032665 -285.476734) (xy 110.020267 -285.525695)
			(xy 109.999981 -285.571948) (xy 109.972359 -285.614232) (xy 109.938155 -285.651393) (xy 109.898301 -285.682418)
			(xy 109.853885 -285.706461) (xy 109.806117 -285.722867) (xy 109.756301 -285.731187) (xy 109.731048 -285.731712)
			(xy 108.790994 -285.731712) (xy 108.765739 -285.731182) (xy 108.715919 -285.722868) (xy 108.668147 -285.706466)
			(xy 108.623725 -285.682426) (xy 108.583867 -285.651402) (xy 108.549658 -285.614241) (xy 108.522032 -285.571956)
			(xy 108.501743 -285.525701) (xy 108.489344 -285.476737) (xy 108.485173 -285.4264) (xy 97.841295 -285.4264)
			(xy 97.841295 -285.452386) (xy 97.833164 -285.50372) (xy 97.817104 -285.553149) (xy 97.793509 -285.599457)
			(xy 97.762961 -285.641505) (xy 97.726211 -285.678255) (xy 97.684164 -285.708805) (xy 97.637856 -285.732401)
			(xy 97.588427 -285.748462) (xy 97.537094 -285.756594) (xy 97.511108 -285.757112) (xy 97.496122 -285.756858)
			(xy 97.481898 -285.756096) (xy 97.45726 -285.769558) (xy 97.312226 -286.01924) (xy 97.312734 -286.047688)
			(xy 97.320354 -286.059626) (xy 97.332508 -286.079544) (xy 97.351699 -286.122075) (xy 97.364708 -286.166885)
			(xy 97.371278 -286.21308) (xy 97.371662 -286.2364) (xy 97.675659 -286.2364) (xy 97.679824 -286.186142)
			(xy 97.692204 -286.137254) (xy 97.712462 -286.091072) (xy 97.740045 -286.048853) (xy 97.774201 -286.01175)
			(xy 97.813999 -285.980776) (xy 97.858351 -285.956774) (xy 97.90605 -285.940401) (xy 97.955793 -285.932101)
			(xy 97.981008 -285.93161) (xy 98.921062 -285.93161) (xy 98.946281 -285.932079) (xy 98.996031 -285.940375)
			(xy 99.043736 -285.956747) (xy 99.088097 -285.980749) (xy 99.127901 -286.011725) (xy 99.162063 -286.048831)
			(xy 99.189651 -286.091054) (xy 99.209913 -286.137242) (xy 99.222296 -286.186135) (xy 99.226461 -286.2364)
			(xy 100.495124 -286.2364) (xy 100.499298 -286.186025) (xy 100.511706 -286.137023) (xy 100.53201 -286.090733)
			(xy 100.559656 -286.048415) (xy 100.593889 -286.011224) (xy 100.633777 -285.980174) (xy 100.678231 -285.956113)
			(xy 100.726038 -285.939697) (xy 100.775896 -285.931372) (xy 100.80117 -285.930848) (xy 101.741224 -285.930848)
			(xy 101.7665 -285.931352) (xy 101.816362 -285.939676) (xy 101.864173 -285.956093) (xy 101.908631 -285.980155)
			(xy 101.948522 -286.011207) (xy 101.982759 -286.0484) (xy 102.010407 -286.090721) (xy 102.030712 -286.137016)
			(xy 102.043121 -286.186021) (xy 102.047296 -286.2364) (xy 103.315024 -286.2364) (xy 103.319199 -286.186024)
			(xy 103.331607 -286.137022) (xy 103.351911 -286.09073) (xy 103.379558 -286.048412) (xy 103.413792 -286.011221)
			(xy 103.453681 -285.980171) (xy 103.498136 -285.956111) (xy 103.545945 -285.939695) (xy 103.595804 -285.931372)
			(xy 103.621078 -285.930848) (xy 104.561132 -285.930848) (xy 104.586407 -285.931352) (xy 104.636268 -285.939678)
			(xy 104.684079 -285.956095) (xy 104.728535 -285.980158) (xy 104.768425 -286.01121) (xy 104.802661 -286.048403)
			(xy 104.830308 -286.090724) (xy 104.850613 -286.137017) (xy 104.863021 -286.186022) (xy 104.867196 -286.2364)
			(xy 106.134924 -286.2364) (xy 106.139099 -286.186023) (xy 106.151508 -286.13702) (xy 106.171813 -286.090728)
			(xy 106.19946 -286.048409) (xy 106.233695 -286.011218) (xy 106.273585 -285.980169) (xy 106.318041 -285.956108)
			(xy 106.365851 -285.939693) (xy 106.415711 -285.931371) (xy 106.440986 -285.930848) (xy 107.38104 -285.930848)
			(xy 107.406315 -285.931353) (xy 107.456175 -285.939679) (xy 107.503984 -285.956098) (xy 107.54844 -285.980161)
			(xy 107.588328 -286.011213) (xy 107.622563 -286.048406) (xy 107.650209 -286.090726) (xy 107.670513 -286.137019)
			(xy 107.682921 -286.186022) (xy 107.687096 -286.2364) (xy 116.468595 -286.2364) (xy 116.472771 -286.186015)
			(xy 116.485183 -286.137004) (xy 116.505492 -286.090704) (xy 116.533146 -286.048379) (xy 116.56739 -286.011184)
			(xy 116.607288 -285.980132) (xy 116.651754 -285.956071) (xy 116.699574 -285.939658) (xy 116.749443 -285.931339)
			(xy 116.774722 -285.930848) (xy 117.714776 -285.930848) (xy 117.740057 -285.931319) (xy 117.789929 -285.939638)
			(xy 117.837753 -285.956052) (xy 117.882222 -285.980115) (xy 117.922123 -286.011168) (xy 117.956369 -286.048366)
			(xy 117.984025 -286.090694) (xy 118.004336 -286.136997) (xy 118.016749 -286.186011) (xy 118.020925 -286.2364)
			(xy 119.288495 -286.2364) (xy 119.292671 -286.186014) (xy 119.305083 -286.137002) (xy 119.325394 -286.090702)
			(xy 119.353048 -286.048377) (xy 119.387293 -286.011181) (xy 119.427193 -285.980129) (xy 119.47166 -285.956069)
			(xy 119.51948 -285.939656) (xy 119.56935 -285.931339) (xy 119.59463 -285.930848) (xy 120.534684 -285.930848)
			(xy 120.559964 -285.93132) (xy 120.609836 -285.93964) (xy 120.657658 -285.956055) (xy 120.702126 -285.980117)
			(xy 120.742026 -286.011171) (xy 120.776271 -286.048369) (xy 120.803926 -286.090696) (xy 120.824237 -286.136998)
			(xy 120.836649 -286.186012) (xy 120.840825 -286.2364) (xy 122.108724 -286.2364) (xy 122.112899 -286.186022)
			(xy 122.125308 -286.137019) (xy 122.145613 -286.090726) (xy 122.173261 -286.048407) (xy 122.207498 -286.011216)
			(xy 122.247388 -285.980167) (xy 122.291845 -285.956107) (xy 122.339656 -285.939692) (xy 122.389517 -285.931371)
			(xy 122.414792 -285.930848) (xy 123.354846 -285.930848) (xy 123.380121 -285.931354) (xy 123.42998 -285.93968)
			(xy 123.477788 -285.9561) (xy 123.522243 -285.980163) (xy 123.562131 -286.011215) (xy 123.596364 -286.048408)
			(xy 123.62401 -286.090727) (xy 123.644314 -286.13702) (xy 123.656722 -286.186023) (xy 123.660896 -286.2364)
			(xy 123.656722 -286.286777) (xy 123.644314 -286.33578) (xy 123.62401 -286.382073) (xy 123.596364 -286.424392)
			(xy 123.562131 -286.461585) (xy 123.522243 -286.492637) (xy 123.477788 -286.5167) (xy 123.42998 -286.53312)
			(xy 123.380121 -286.541446) (xy 123.354846 -286.541972) (xy 122.414792 -286.541972) (xy 122.389517 -286.541429)
			(xy 122.339656 -286.533108) (xy 122.291845 -286.516693) (xy 122.247388 -286.492633) (xy 122.207498 -286.461584)
			(xy 122.173261 -286.424393) (xy 122.145613 -286.382074) (xy 122.125308 -286.335781) (xy 122.112899 -286.286778)
			(xy 122.108724 -286.2364) (xy 120.840825 -286.2364) (xy 120.836649 -286.286788) (xy 120.824237 -286.335802)
			(xy 120.803926 -286.382104) (xy 120.776271 -286.424431) (xy 120.742026 -286.461629) (xy 120.702126 -286.492683)
			(xy 120.657658 -286.516745) (xy 120.609836 -286.53316) (xy 120.559964 -286.54148) (xy 120.534684 -286.541972)
			(xy 119.59463 -286.541972) (xy 119.56935 -286.541461) (xy 119.51948 -286.533144) (xy 119.47166 -286.516731)
			(xy 119.427193 -286.492671) (xy 119.387293 -286.461619) (xy 119.353048 -286.424423) (xy 119.325394 -286.382098)
			(xy 119.305083 -286.335798) (xy 119.292671 -286.286786) (xy 119.288495 -286.2364) (xy 118.020925 -286.2364)
			(xy 118.016749 -286.286789) (xy 118.004336 -286.335803) (xy 117.984025 -286.382106) (xy 117.956369 -286.424434)
			(xy 117.922123 -286.461632) (xy 117.882222 -286.492685) (xy 117.837753 -286.516748) (xy 117.789929 -286.533162)
			(xy 117.740057 -286.541481) (xy 117.714776 -286.541972) (xy 116.774722 -286.541972) (xy 116.749443 -286.541461)
			(xy 116.699574 -286.533142) (xy 116.651754 -286.516729) (xy 116.607288 -286.492668) (xy 116.56739 -286.461616)
			(xy 116.533146 -286.424421) (xy 116.505492 -286.382096) (xy 116.485183 -286.335796) (xy 116.472771 -286.286785)
			(xy 116.468595 -286.2364) (xy 107.687096 -286.2364) (xy 107.682921 -286.286778) (xy 107.670513 -286.335781)
			(xy 107.650209 -286.382074) (xy 107.622563 -286.424394) (xy 107.588328 -286.461587) (xy 107.54844 -286.492639)
			(xy 107.503984 -286.516702) (xy 107.456175 -286.533121) (xy 107.406315 -286.541447) (xy 107.38104 -286.541972)
			(xy 106.440986 -286.541972) (xy 106.415711 -286.541429) (xy 106.365851 -286.533107) (xy 106.318041 -286.516692)
			(xy 106.273585 -286.492631) (xy 106.233695 -286.461582) (xy 106.19946 -286.424391) (xy 106.171813 -286.382072)
			(xy 106.151508 -286.33578) (xy 106.139099 -286.286777) (xy 106.134924 -286.2364) (xy 104.867196 -286.2364)
			(xy 104.863021 -286.286778) (xy 104.850613 -286.335783) (xy 104.830308 -286.382076) (xy 104.802661 -286.424397)
			(xy 104.768425 -286.46159) (xy 104.728535 -286.492642) (xy 104.684079 -286.516705) (xy 104.636268 -286.533122)
			(xy 104.586407 -286.541448) (xy 104.561132 -286.541972) (xy 103.621078 -286.541972) (xy 103.595804 -286.541428)
			(xy 103.545945 -286.533105) (xy 103.498136 -286.516689) (xy 103.453681 -286.492629) (xy 103.413792 -286.461579)
			(xy 103.379558 -286.424388) (xy 103.351911 -286.38207) (xy 103.331607 -286.335778) (xy 103.319199 -286.286776)
			(xy 103.315024 -286.2364) (xy 102.047296 -286.2364) (xy 102.043121 -286.286779) (xy 102.030712 -286.335784)
			(xy 102.010407 -286.382079) (xy 101.982759 -286.4244) (xy 101.948522 -286.461593) (xy 101.908631 -286.492645)
			(xy 101.864173 -286.516707) (xy 101.816362 -286.533124) (xy 101.7665 -286.541448) (xy 101.741224 -286.541972)
			(xy 100.80117 -286.541972) (xy 100.775896 -286.541428) (xy 100.726038 -286.533103) (xy 100.678231 -286.516687)
			(xy 100.633777 -286.492626) (xy 100.593889 -286.461576) (xy 100.559656 -286.424385) (xy 100.53201 -286.382067)
			(xy 100.511706 -286.335777) (xy 100.499298 -286.286775) (xy 100.495124 -286.2364) (xy 99.226461 -286.2364)
			(xy 99.222296 -286.286665) (xy 99.209913 -286.335558) (xy 99.189651 -286.381746) (xy 99.162063 -286.423969)
			(xy 99.127901 -286.461075) (xy 99.088097 -286.492051) (xy 99.043736 -286.516053) (xy 98.996031 -286.532425)
			(xy 98.946281 -286.540721) (xy 98.921062 -286.54121) (xy 97.981008 -286.54121) (xy 97.955793 -286.540699)
			(xy 97.90605 -286.532399) (xy 97.858351 -286.516026) (xy 97.813999 -286.492024) (xy 97.774201 -286.46105)
			(xy 97.740045 -286.423947) (xy 97.712462 -286.381728) (xy 97.692204 -286.335546) (xy 97.679824 -286.286658)
			(xy 97.675659 -286.2364) (xy 97.371662 -286.2364) (xy 97.371662 -286.23641) (xy 97.371178 -286.262397)
			(xy 97.363045 -286.313732) (xy 97.346982 -286.363162) (xy 97.323383 -286.409471) (xy 97.292829 -286.451517)
			(xy 97.256074 -286.488266) (xy 97.214023 -286.518812) (xy 97.167711 -286.542403) (xy 97.118278 -286.558458)
			(xy 97.066942 -286.566582) (xy 97.040954 -286.567118) (xy 97.026222 -286.566864) (xy 97.011998 -286.566102)
			(xy 96.98736 -286.579818) (xy 96.84258 -286.829246) (xy 96.843088 -286.85744) (xy 96.850708 -286.869632)
			(xy 96.862806 -286.889535) (xy 96.881903 -286.932017) (xy 96.89485 -286.976758) (xy 96.901391 -287.022874)
			(xy 96.901762 -287.046162) (xy 96.901761 -287.0462) (xy 108.485639 -287.0462) (xy 108.489804 -286.99594)
			(xy 108.502184 -286.947051) (xy 108.522443 -286.900866) (xy 108.550026 -286.858646) (xy 108.584183 -286.821541)
			(xy 108.62398 -286.790565) (xy 108.668334 -286.766561) (xy 108.716034 -286.750185) (xy 108.765778 -286.741883)
			(xy 108.790994 -286.741362) (xy 109.731048 -286.741362) (xy 109.756256 -286.741962) (xy 109.805982 -286.750268)
			(xy 109.853664 -286.766643) (xy 109.898 -286.790643) (xy 109.937782 -286.821612) (xy 109.971924 -286.858707)
			(xy 109.999496 -286.900914) (xy 110.019746 -286.947084) (xy 110.032121 -286.995957) (xy 110.036284 -287.0462)
			(xy 110.032121 -287.096443) (xy 110.019746 -287.145316) (xy 109.999496 -287.191486) (xy 109.971924 -287.233693)
			(xy 109.937782 -287.270788) (xy 109.898 -287.301757) (xy 109.853664 -287.325757) (xy 109.805982 -287.342132)
			(xy 109.756256 -287.350438) (xy 109.731048 -287.350962) (xy 108.790994 -287.350962) (xy 108.765778 -287.350517)
			(xy 108.716034 -287.342215) (xy 108.668334 -287.325839) (xy 108.62398 -287.301835) (xy 108.584183 -287.270859)
			(xy 108.550026 -287.233754) (xy 108.522443 -287.191534) (xy 108.502184 -287.145349) (xy 108.489804 -287.09646)
			(xy 108.485639 -287.0462) (xy 96.901761 -287.0462) (xy 96.901346 -287.069749) (xy 96.894649 -287.116446)
			(xy 96.881385 -287.161718) (xy 96.861823 -287.204646) (xy 96.849438 -287.224724) (xy 96.841564 -287.236916)
			(xy 96.841056 -287.26511) (xy 96.985074 -287.513522) (xy 97.009966 -287.526984) (xy 97.02419 -287.526222)
			(xy 97.040954 -287.525714) (xy 97.066945 -287.526194) (xy 97.118288 -287.534319) (xy 97.167727 -287.550378)
			(xy 97.214045 -287.573973) (xy 97.256101 -287.604525) (xy 97.292859 -287.641281) (xy 97.323414 -287.683334)
			(xy 97.347013 -287.729651) (xy 97.363075 -287.779089) (xy 97.371204 -287.830431) (xy 97.371662 -287.8564)
			(xy 97.675671 -287.8564) (xy 97.679835 -287.806144) (xy 97.692215 -287.757258) (xy 97.712472 -287.711077)
			(xy 97.740055 -287.66886) (xy 97.774209 -287.631759) (xy 97.814005 -287.600786) (xy 97.858356 -287.576785)
			(xy 97.906053 -287.560412) (xy 97.955794 -287.552113) (xy 97.981008 -287.551622) (xy 98.921062 -287.551622)
			(xy 98.946282 -287.552067) (xy 98.996034 -287.560363) (xy 99.043741 -287.576736) (xy 99.088103 -287.600739)
			(xy 99.127909 -287.631716) (xy 99.162072 -287.668823) (xy 99.189662 -287.711048) (xy 99.209924 -287.757238)
			(xy 99.222307 -287.806133) (xy 99.226473 -287.8564) (xy 100.495899 -287.8564) (xy 100.500063 -287.806152)
			(xy 100.512439 -287.757275) (xy 100.532692 -287.711101) (xy 100.560267 -287.668891) (xy 100.594414 -287.631794)
			(xy 100.634201 -287.600823) (xy 100.678542 -287.576823) (xy 100.726229 -287.560448) (xy 100.77596 -287.552145)
			(xy 100.80117 -287.551622) (xy 101.741224 -287.551622) (xy 101.766438 -287.5521) (xy 101.816177 -287.560404)
			(xy 101.863872 -287.576781) (xy 101.90822 -287.600784) (xy 101.948014 -287.631759) (xy 101.982166 -287.668862)
			(xy 102.009746 -287.711079) (xy 102.030002 -287.75726) (xy 102.04238 -287.806144) (xy 102.046545 -287.8564)
			(xy 103.315799 -287.8564) (xy 103.319963 -287.806151) (xy 103.33234 -287.757273) (xy 103.352593 -287.711099)
			(xy 103.380169 -287.668888) (xy 103.414317 -287.631791) (xy 103.454105 -287.60082) (xy 103.498447 -287.57682)
			(xy 103.546135 -287.560446) (xy 103.595868 -287.552144) (xy 103.621078 -287.551622) (xy 104.561132 -287.551622)
			(xy 104.586345 -287.552101) (xy 104.636084 -287.560406) (xy 104.683777 -287.576783) (xy 104.728125 -287.600787)
			(xy 104.767917 -287.631762) (xy 104.802068 -287.668864) (xy 104.829647 -287.711081) (xy 104.849902 -287.757261)
			(xy 104.862281 -287.806145) (xy 104.866445 -287.8564) (xy 106.135699 -287.8564) (xy 106.139863 -287.806151)
			(xy 106.152241 -287.757272) (xy 106.172494 -287.711097) (xy 106.200071 -287.668885) (xy 106.23422 -287.631788)
			(xy 106.274009 -287.600818) (xy 106.318353 -287.576818) (xy 106.366042 -287.560445) (xy 106.415775 -287.552143)
			(xy 106.440986 -287.551622) (xy 107.38104 -287.551622) (xy 107.406253 -287.552102) (xy 107.45599 -287.560407)
			(xy 107.503683 -287.576786) (xy 107.548029 -287.60079) (xy 107.58782 -287.631765) (xy 107.62197 -287.668867)
			(xy 107.649548 -287.711083) (xy 107.669803 -287.757263) (xy 107.682181 -287.806146) (xy 107.686345 -287.8564)
			(xy 107.682181 -287.906654) (xy 107.669803 -287.955537) (xy 107.649548 -288.001717) (xy 107.62197 -288.043933)
			(xy 107.58782 -288.081035) (xy 107.548029 -288.11201) (xy 107.503683 -288.136014) (xy 107.45599 -288.152393)
			(xy 107.406253 -288.160698) (xy 107.38104 -288.161222) (xy 106.440986 -288.161222) (xy 106.415775 -288.160657)
			(xy 106.366042 -288.152355) (xy 106.318353 -288.135982) (xy 106.274009 -288.111983) (xy 106.23422 -288.081012)
			(xy 106.200071 -288.043915) (xy 106.172494 -288.001703) (xy 106.152241 -287.955528) (xy 106.139863 -287.906649)
			(xy 106.135699 -287.8564) (xy 104.866445 -287.8564) (xy 104.862281 -287.906655) (xy 104.849902 -287.955539)
			(xy 104.829647 -288.001719) (xy 104.802068 -288.043936) (xy 104.767917 -288.081038) (xy 104.728125 -288.112013)
			(xy 104.683777 -288.136017) (xy 104.636084 -288.152394) (xy 104.586345 -288.160699) (xy 104.561132 -288.161222)
			(xy 103.621078 -288.161222) (xy 103.595868 -288.160656) (xy 103.546135 -288.152354) (xy 103.498447 -288.13598)
			(xy 103.454105 -288.11198) (xy 103.414317 -288.081009) (xy 103.380169 -288.043912) (xy 103.352593 -288.001701)
			(xy 103.33234 -287.955527) (xy 103.319963 -287.906649) (xy 103.315799 -287.8564) (xy 102.046545 -287.8564)
			(xy 102.04238 -287.906656) (xy 102.030002 -287.95554) (xy 102.009746 -288.001721) (xy 101.982166 -288.043938)
			(xy 101.948014 -288.081041) (xy 101.90822 -288.112016) (xy 101.863872 -288.136019) (xy 101.816177 -288.152396)
			(xy 101.766438 -288.1607) (xy 101.741224 -288.161222) (xy 100.80117 -288.161222) (xy 100.77596 -288.160655)
			(xy 100.726229 -288.152352) (xy 100.678542 -288.135977) (xy 100.634201 -288.111977) (xy 100.594414 -288.081006)
			(xy 100.560267 -288.043909) (xy 100.532692 -288.001699) (xy 100.512439 -287.955525) (xy 100.500063 -287.906648)
			(xy 100.495899 -287.8564) (xy 99.226473 -287.8564) (xy 99.222307 -287.906667) (xy 99.209924 -287.955562)
			(xy 99.189662 -288.001752) (xy 99.162072 -288.043977) (xy 99.127909 -288.081084) (xy 99.088103 -288.112061)
			(xy 99.043741 -288.136064) (xy 98.996034 -288.152437) (xy 98.946282 -288.160733) (xy 98.921062 -288.161222)
			(xy 97.981008 -288.161222) (xy 97.955794 -288.160687) (xy 97.906053 -288.152388) (xy 97.858356 -288.136015)
			(xy 97.814005 -288.112014) (xy 97.774209 -288.081041) (xy 97.740055 -288.04394) (xy 97.712472 -288.001723)
			(xy 97.692215 -287.955542) (xy 97.679835 -287.906656) (xy 97.675671 -287.8564) (xy 97.371662 -287.8564)
			(xy 97.371662 -287.856422) (xy 97.371223 -287.879976) (xy 97.364498 -287.926602) (xy 97.351229 -287.971803)
			(xy 97.331685 -288.014667) (xy 97.319338 -288.03473) (xy 97.311464 -288.046922) (xy 97.310956 -288.075116)
			(xy 97.45472 -288.323274) (xy 97.479612 -288.336736) (xy 97.49409 -288.335974) (xy 97.511108 -288.335466)
			(xy 97.537097 -288.335976) (xy 97.588434 -288.344108) (xy 97.637868 -288.360171) (xy 97.68418 -288.38377)
			(xy 97.72623 -288.414322) (xy 97.762983 -288.451076) (xy 97.793535 -288.493127) (xy 97.817132 -288.53944)
			(xy 97.833193 -288.588873) (xy 97.841324 -288.640211) (xy 97.841324 -288.6662) (xy 108.485651 -288.6662)
			(xy 108.489816 -288.615942) (xy 108.502196 -288.567055) (xy 108.522453 -288.520872) (xy 108.550036 -288.478653)
			(xy 108.584191 -288.44155) (xy 108.623987 -288.410575) (xy 108.668339 -288.386572) (xy 108.716036 -288.370196)
			(xy 108.765779 -288.361895) (xy 108.790994 -288.361374) (xy 109.731048 -288.361374) (xy 109.756257 -288.36195)
			(xy 109.805985 -288.370255) (xy 109.853669 -288.386632) (xy 109.898007 -288.410633) (xy 109.93779 -288.441603)
			(xy 109.971934 -288.478699) (xy 109.999507 -288.520908) (xy 110.019758 -288.56708) (xy 110.032133 -288.615955)
			(xy 110.036297 -288.6662) (xy 110.032133 -288.716445) (xy 110.019758 -288.76532) (xy 109.999507 -288.811492)
			(xy 109.971934 -288.853701) (xy 109.93779 -288.890797) (xy 109.898007 -288.921767) (xy 109.853669 -288.945768)
			(xy 109.805985 -288.962145) (xy 109.756257 -288.97045) (xy 109.731048 -288.970974) (xy 108.790994 -288.970974)
			(xy 108.765779 -288.970505) (xy 108.716036 -288.962204) (xy 108.668339 -288.945828) (xy 108.623987 -288.921825)
			(xy 108.584191 -288.89085) (xy 108.550036 -288.853747) (xy 108.522453 -288.811528) (xy 108.502196 -288.765345)
			(xy 108.489816 -288.716458) (xy 108.485651 -288.6662) (xy 97.841324 -288.6662) (xy 97.841324 -288.692189)
			(xy 97.833193 -288.743527) (xy 97.817132 -288.79296) (xy 97.793535 -288.839273) (xy 97.762983 -288.881324)
			(xy 97.72623 -288.918078) (xy 97.68418 -288.94863) (xy 97.637868 -288.972229) (xy 97.588434 -288.988292)
			(xy 97.537097 -288.996424) (xy 97.511108 -288.996882) (xy 97.496376 -288.996628) (xy 97.482152 -288.995866)
			(xy 97.45726 -289.009582) (xy 97.31248 -289.259264) (xy 97.312988 -289.287458) (xy 97.320608 -289.29965)
			(xy 97.332705 -289.319553) (xy 97.3518 -289.362036) (xy 97.364745 -289.406777) (xy 97.371283 -289.452892)
			(xy 97.371662 -289.47618) (xy 97.371662 -289.4762) (xy 97.675629 -289.4762) (xy 97.679794 -289.425937)
			(xy 97.692175 -289.377045) (xy 97.712435 -289.330857) (xy 97.740021 -289.288635) (xy 97.774181 -289.251528)
			(xy 97.813982 -289.220551) (xy 97.858339 -289.196547) (xy 97.906042 -289.180172) (xy 97.95579 -289.171871)
			(xy 97.981008 -289.17138) (xy 98.921062 -289.17138) (xy 98.946278 -289.171909) (xy 98.996023 -289.180204)
			(xy 99.043724 -289.196575) (xy 99.08808 -289.220574) (xy 99.12788 -289.251547) (xy 99.162039 -289.288649)
			(xy 99.189625 -289.330868) (xy 99.209885 -289.377052) (xy 99.222266 -289.42594) (xy 99.226431 -289.4762)
			(xy 100.495857 -289.4762) (xy 100.500021 -289.425945) (xy 100.5124 -289.377061) (xy 100.532655 -289.330881)
			(xy 100.560234 -289.288665) (xy 100.594386 -289.251563) (xy 100.634178 -289.220588) (xy 100.678525 -289.196584)
			(xy 100.726218 -289.180207) (xy 100.775957 -289.171903) (xy 100.80117 -289.17138) (xy 101.741224 -289.17138)
			(xy 101.766434 -289.171942) (xy 101.816167 -289.180245) (xy 101.863855 -289.196619) (xy 101.908197 -289.220619)
			(xy 101.947985 -289.25159) (xy 101.982133 -289.288687) (xy 102.009709 -289.330899) (xy 102.029962 -289.377073)
			(xy 102.042339 -289.425951) (xy 102.046503 -289.4762) (xy 103.315757 -289.4762) (xy 103.319922 -289.425945)
			(xy 103.3323 -289.37706) (xy 103.352556 -289.330879) (xy 103.380136 -289.288662) (xy 103.414289 -289.25156)
			(xy 103.454082 -289.220585) (xy 103.49843 -289.196582) (xy 103.546125 -289.180205) (xy 103.595864 -289.171902)
			(xy 103.621078 -289.17138) (xy 104.561132 -289.17138) (xy 104.586342 -289.171943) (xy 104.636073 -289.180246)
			(xy 104.68376 -289.196622) (xy 104.728102 -289.220622) (xy 104.767888 -289.251593) (xy 104.802035 -289.28869)
			(xy 104.82961 -289.330901) (xy 104.849863 -289.377075) (xy 104.862239 -289.425952) (xy 104.866403 -289.4762)
			(xy 106.135657 -289.4762) (xy 106.139822 -289.425944) (xy 106.152201 -289.377058) (xy 106.172457 -289.330877)
			(xy 106.200038 -289.288659) (xy 106.234192 -289.251557) (xy 106.273986 -289.220582) (xy 106.318336 -289.19658)
			(xy 106.366031 -289.180204) (xy 106.415772 -289.171901) (xy 106.440986 -289.17138) (xy 107.38104 -289.17138)
			(xy 107.40625 -289.171943) (xy 107.45598 -289.180248) (xy 107.503666 -289.196624) (xy 107.548006 -289.220625)
			(xy 107.587791 -289.251596) (xy 107.621937 -289.288693) (xy 107.649512 -289.330903) (xy 107.669763 -289.377076)
			(xy 107.682139 -289.425953) (xy 107.686303 -289.4762) (xy 107.682139 -289.526447) (xy 107.669763 -289.575324)
			(xy 107.649512 -289.621497) (xy 107.621937 -289.663707) (xy 107.587791 -289.700804) (xy 107.548006 -289.731775)
			(xy 107.503666 -289.755776) (xy 107.45598 -289.772152) (xy 107.40625 -289.780457) (xy 107.38104 -289.78098)
			(xy 106.440986 -289.78098) (xy 106.415772 -289.780499) (xy 106.366031 -289.772196) (xy 106.318336 -289.75582)
			(xy 106.273986 -289.731818) (xy 106.234192 -289.700843) (xy 106.200038 -289.663741) (xy 106.172457 -289.621523)
			(xy 106.152201 -289.575342) (xy 106.139822 -289.526456) (xy 106.135657 -289.4762) (xy 104.866403 -289.4762)
			(xy 104.862239 -289.526448) (xy 104.849863 -289.575325) (xy 104.82961 -289.621499) (xy 104.802035 -289.66371)
			(xy 104.767888 -289.700807) (xy 104.728102 -289.731778) (xy 104.68376 -289.755778) (xy 104.636074 -289.772154)
			(xy 104.586342 -289.780457) (xy 104.561132 -289.78098) (xy 103.621078 -289.78098) (xy 103.595864 -289.780498)
			(xy 103.546125 -289.772195) (xy 103.49843 -289.755818) (xy 103.454082 -289.731815) (xy 103.414289 -289.70084)
			(xy 103.380136 -289.663738) (xy 103.352556 -289.621521) (xy 103.3323 -289.57534) (xy 103.319922 -289.526455)
			(xy 103.315757 -289.4762) (xy 102.046503 -289.4762) (xy 102.042339 -289.526449) (xy 102.029962 -289.575327)
			(xy 102.009709 -289.621501) (xy 101.982133 -289.663713) (xy 101.947985 -289.70081) (xy 101.908197 -289.731781)
			(xy 101.863855 -289.755781) (xy 101.816167 -289.772155) (xy 101.766434 -289.780458) (xy 101.741224 -289.78098)
			(xy 100.80117 -289.78098) (xy 100.775957 -289.780497) (xy 100.726218 -289.772193) (xy 100.678525 -289.755816)
			(xy 100.634178 -289.731812) (xy 100.594386 -289.700837) (xy 100.560234 -289.663735) (xy 100.532655 -289.621519)
			(xy 100.5124 -289.575339) (xy 100.500021 -289.526455) (xy 100.495857 -289.4762) (xy 99.226431 -289.4762)
			(xy 99.222266 -289.52646) (xy 99.209885 -289.575348) (xy 99.189625 -289.621532) (xy 99.162039 -289.663751)
			(xy 99.12788 -289.700853) (xy 99.08808 -289.731826) (xy 99.043724 -289.755825) (xy 98.996023 -289.772196)
			(xy 98.946278 -289.780491) (xy 98.921062 -289.78098) (xy 97.981008 -289.78098) (xy 97.95579 -289.780529)
			(xy 97.906042 -289.772228) (xy 97.858339 -289.755853) (xy 97.813982 -289.731849) (xy 97.774181 -289.700872)
			(xy 97.740021 -289.663765) (xy 97.712435 -289.621543) (xy 97.692175 -289.575355) (xy 97.679794 -289.526463)
			(xy 97.675629 -289.4762) (xy 97.371662 -289.4762) (xy 97.37118 -289.502169) (xy 97.363051 -289.553507)
			(xy 97.34699 -289.602942) (xy 97.323393 -289.649254) (xy 97.29284 -289.691305) (xy 97.256085 -289.728057)
			(xy 97.214032 -289.758606) (xy 97.167717 -289.7822) (xy 97.118282 -289.798257) (xy 97.066943 -289.806382)
			(xy 97.040954 -289.806888) (xy 97.026476 -289.806634) (xy 97.012252 -289.805872) (xy 96.98736 -289.819588)
			(xy 96.84258 -290.06927) (xy 96.843088 -290.097464) (xy 96.850708 -290.109656) (xy 96.862805 -290.12956)
			(xy 96.881899 -290.172042) (xy 96.894843 -290.216783) (xy 96.90138 -290.262898) (xy 96.901762 -290.286186)
			(xy 96.901762 -290.2862) (xy 108.485663 -290.2862) (xy 108.489828 -290.235944) (xy 108.502207 -290.187059)
			(xy 108.522464 -290.140878) (xy 108.550045 -290.09866) (xy 108.584199 -290.061559) (xy 108.623994 -290.030585)
			(xy 108.668344 -290.006583) (xy 108.716039 -289.990208) (xy 108.76578 -289.981907) (xy 108.790994 -289.981386)
			(xy 109.731048 -289.981386) (xy 109.756258 -289.981938) (xy 109.805988 -289.990244) (xy 109.853673 -290.006621)
			(xy 109.898013 -290.030623) (xy 109.937798 -290.061594) (xy 109.971944 -290.098692) (xy 109.999518 -290.140903)
			(xy 110.019769 -290.187076) (xy 110.032145 -290.235953) (xy 110.036309 -290.2862) (xy 110.032145 -290.336447)
			(xy 110.019769 -290.385324) (xy 109.999518 -290.431497) (xy 109.971944 -290.473708) (xy 109.937798 -290.510806)
			(xy 109.898013 -290.541777) (xy 109.853673 -290.565779) (xy 109.805988 -290.582156) (xy 109.756258 -290.590462)
			(xy 109.731048 -290.590986) (xy 108.790994 -290.590986) (xy 108.76578 -290.590493) (xy 108.716039 -290.582192)
			(xy 108.668344 -290.565817) (xy 108.623994 -290.541815) (xy 108.584199 -290.510841) (xy 108.550045 -290.47374)
			(xy 108.522464 -290.431522) (xy 108.502207 -290.385341) (xy 108.489828 -290.336456) (xy 108.485663 -290.2862)
			(xy 96.901762 -290.2862) (xy 96.90128 -290.312175) (xy 96.89315 -290.363512) (xy 96.877089 -290.412946)
			(xy 96.853491 -290.459258) (xy 96.822938 -290.501307) (xy 96.786183 -290.538059) (xy 96.74413 -290.568608)
			(xy 96.697816 -290.592201) (xy 96.648381 -290.608258) (xy 96.597043 -290.616382) (xy 96.571054 -290.616894)
			(xy 96.556322 -290.61664) (xy 96.542098 -290.615878) (xy 96.51746 -290.629594) (xy 96.372426 -290.879022)
			(xy 96.372934 -290.907216) (xy 96.380554 -290.919408) (xy 96.392703 -290.939327) (xy 96.411883 -290.98186)
			(xy 96.424882 -291.02667) (xy 96.43144 -291.072863) (xy 96.431862 -291.096192) (xy 96.431862 -291.0962)
			(xy 97.675641 -291.0962) (xy 97.679806 -291.045939) (xy 97.692187 -290.997048) (xy 97.712446 -290.950863)
			(xy 97.740031 -290.908642) (xy 97.774189 -290.871537) (xy 97.813989 -290.840561) (xy 97.858344 -290.816558)
			(xy 97.906045 -290.800183) (xy 97.955791 -290.791883) (xy 97.981008 -290.791392) (xy 98.921062 -290.791392)
			(xy 98.946279 -290.791897) (xy 98.996026 -290.800193) (xy 99.043729 -290.816564) (xy 99.088087 -290.840564)
			(xy 99.127888 -290.871538) (xy 99.162049 -290.908642) (xy 99.189635 -290.950862) (xy 99.209896 -290.997048)
			(xy 99.222278 -291.045938) (xy 99.226443 -291.0962) (xy 100.495869 -291.0962) (xy 100.500033 -291.045947)
			(xy 100.512411 -290.997065) (xy 100.532665 -290.950887) (xy 100.560244 -290.908672) (xy 100.594394 -290.871572)
			(xy 100.634184 -290.840598) (xy 100.67853 -290.816595) (xy 100.726221 -290.800219) (xy 100.775958 -290.791915)
			(xy 100.80117 -290.791392) (xy 101.741224 -290.791392) (xy 101.766435 -290.79193) (xy 101.81617 -290.800233)
			(xy 101.86386 -290.816608) (xy 101.908204 -290.840609) (xy 101.947993 -290.871581) (xy 101.982142 -290.90868)
			(xy 102.00972 -290.950893) (xy 102.029973 -290.997069) (xy 102.042351 -291.045949) (xy 102.046515 -291.0962)
			(xy 103.315769 -291.0962) (xy 103.319933 -291.045947) (xy 103.332312 -290.997064) (xy 103.352567 -290.950885)
			(xy 103.380146 -290.908669) (xy 103.414297 -290.871569) (xy 103.454088 -290.840595) (xy 103.498435 -290.816593)
			(xy 103.546128 -290.800217) (xy 103.595865 -290.791914) (xy 103.621078 -290.791392) (xy 104.561132 -290.791392)
			(xy 104.586343 -290.791931) (xy 104.636076 -290.800235) (xy 104.683765 -290.816611) (xy 104.728108 -290.840612)
			(xy 104.767896 -290.871584) (xy 104.802044 -290.908683) (xy 104.829621 -290.950895) (xy 104.849874 -290.997071)
			(xy 104.862251 -291.04595) (xy 104.866415 -291.0962) (xy 106.135669 -291.0962) (xy 106.139834 -291.045946)
			(xy 106.152212 -290.997062) (xy 106.172468 -290.950883) (xy 106.200048 -290.908667) (xy 106.2342 -290.871566)
			(xy 106.273993 -290.840592) (xy 106.318341 -290.816591) (xy 106.366034 -290.800215) (xy 106.415773 -290.791913)
			(xy 106.440986 -290.791392) (xy 107.38104 -290.791392) (xy 107.40625 -290.791931) (xy 107.455983 -290.800236)
			(xy 107.50367 -290.816613) (xy 107.548012 -290.840615) (xy 107.587799 -290.871587) (xy 107.621946 -290.908685)
			(xy 107.649522 -290.950897) (xy 107.669774 -290.997073) (xy 107.682151 -291.045951) (xy 107.686315 -291.0962)
			(xy 107.682151 -291.146449) (xy 107.669774 -291.195327) (xy 107.649522 -291.241503) (xy 107.621946 -291.283715)
			(xy 107.587799 -291.320813) (xy 107.548012 -291.351785) (xy 107.50367 -291.375787) (xy 107.455983 -291.392164)
			(xy 107.406251 -291.400469) (xy 107.38104 -291.400992) (xy 106.440986 -291.400992) (xy 106.415773 -291.400487)
			(xy 106.366034 -291.392185) (xy 106.318341 -291.375809) (xy 106.273993 -291.351808) (xy 106.2342 -291.320834)
			(xy 106.200048 -291.283733) (xy 106.172468 -291.241517) (xy 106.152212 -291.195338) (xy 106.139834 -291.146454)
			(xy 106.135669 -291.0962) (xy 104.866415 -291.0962) (xy 104.862251 -291.14645) (xy 104.849874 -291.195329)
			(xy 104.829621 -291.241505) (xy 104.802044 -291.283717) (xy 104.767896 -291.320816) (xy 104.728108 -291.351788)
			(xy 104.683765 -291.375789) (xy 104.636076 -291.392165) (xy 104.586343 -291.400469) (xy 104.561132 -291.400992)
			(xy 103.621078 -291.400992) (xy 103.595865 -291.400486) (xy 103.546128 -291.392183) (xy 103.498435 -291.375807)
			(xy 103.454088 -291.351805) (xy 103.414297 -291.320831) (xy 103.380146 -291.283731) (xy 103.352567 -291.241515)
			(xy 103.332312 -291.195336) (xy 103.319933 -291.146453) (xy 103.315769 -291.0962) (xy 102.046515 -291.0962)
			(xy 102.042351 -291.146451) (xy 102.029973 -291.195331) (xy 102.00972 -291.241507) (xy 101.982142 -291.28372)
			(xy 101.947993 -291.320819) (xy 101.908204 -291.351791) (xy 101.86386 -291.375792) (xy 101.81617 -291.392167)
			(xy 101.766435 -291.40047) (xy 101.741224 -291.400992) (xy 100.80117 -291.400992) (xy 100.775958 -291.400485)
			(xy 100.726221 -291.392181) (xy 100.67853 -291.375805) (xy 100.634184 -291.351802) (xy 100.594394 -291.320828)
			(xy 100.560244 -291.283728) (xy 100.532665 -291.241513) (xy 100.512411 -291.195335) (xy 100.500033 -291.146453)
			(xy 100.495869 -291.0962) (xy 99.226443 -291.0962) (xy 99.222278 -291.146462) (xy 99.209896 -291.195352)
			(xy 99.189635 -291.241538) (xy 99.162049 -291.283758) (xy 99.127888 -291.320862) (xy 99.088087 -291.351836)
			(xy 99.043729 -291.375836) (xy 98.996026 -291.392207) (xy 98.946279 -291.400503) (xy 98.921062 -291.400992)
			(xy 97.981008 -291.400992) (xy 97.955791 -291.400517) (xy 97.906045 -291.392217) (xy 97.858344 -291.375842)
			(xy 97.813989 -291.351839) (xy 97.774189 -291.320863) (xy 97.740031 -291.283758) (xy 97.712446 -291.241537)
			(xy 97.692187 -291.195352) (xy 97.679806 -291.146461) (xy 97.675641 -291.0962) (xy 96.431862 -291.0962)
			(xy 96.431379 -291.12218) (xy 96.423249 -291.173517) (xy 96.407187 -291.22295) (xy 96.383589 -291.269261)
			(xy 96.353036 -291.31131) (xy 96.316281 -291.348061) (xy 96.274228 -291.378609) (xy 96.227915 -291.402201)
			(xy 96.17848 -291.418258) (xy 96.127142 -291.426382) (xy 96.101154 -291.4269) (xy 96.086422 -291.426646)
			(xy 96.071944 -291.425884) (xy 96.047306 -291.439346) (xy 95.902272 -291.689282) (xy 95.903034 -291.717476)
			(xy 95.910654 -291.729414) (xy 95.922761 -291.749347) (xy 95.941863 -291.791892) (xy 95.954797 -291.836699)
			(xy 95.961308 -291.882879) (xy 95.961708 -291.906198) (xy 95.961225 -291.932187) (xy 95.953094 -291.983526)
			(xy 95.937032 -292.032961) (xy 95.913434 -292.079274) (xy 95.882882 -292.121326) (xy 95.846128 -292.158081)
			(xy 95.804076 -292.188633) (xy 95.757763 -292.212231) (xy 95.708328 -292.228294) (xy 95.656989 -292.236425)
			(xy 95.631 -292.236906) (xy 95.616268 -292.236652) (xy 95.602044 -292.23589) (xy 95.577152 -292.249606)
			(xy 95.432372 -292.499034) (xy 95.43288 -292.527228) (xy 95.4405 -292.53942) (xy 95.452656 -292.559337)
			(xy 95.471851 -292.601868) (xy 95.484863 -292.646678) (xy 95.491435 -292.692873) (xy 95.491808 -292.716204)
			(xy 95.491298 -292.742191) (xy 95.483167 -292.793525) (xy 95.467106 -292.842955) (xy 95.44351 -292.889264)
			(xy 95.41296 -292.931312) (xy 95.376208 -292.968062) (xy 95.334161 -292.998612) (xy 95.287851 -293.022207)
			(xy 95.238421 -293.038268) (xy 95.187087 -293.046398) (xy 95.1611 -293.046912) (xy 95.146114 -293.046658)
			(xy 95.13189 -293.045896) (xy 95.107252 -293.059358) (xy 94.962218 -293.30904) (xy 94.962726 -293.337488)
			(xy 94.970346 -293.349426) (xy 94.9825 -293.369344) (xy 95.001691 -293.411875) (xy 95.014701 -293.456685)
			(xy 95.021271 -293.50288) (xy 95.021654 -293.52621) (xy 95.021144 -293.552198) (xy 95.013012 -293.603534)
			(xy 94.996951 -293.652966) (xy 94.973355 -293.699278) (xy 94.942806 -293.741328) (xy 94.906056 -293.778083)
			(xy 94.864008 -293.808636) (xy 94.817699 -293.832237) (xy 94.768269 -293.848304) (xy 94.716934 -293.856441)
			(xy 94.690946 -293.856918) (xy 94.665441 -293.85645) (xy 94.615034 -293.848627) (xy 94.566425 -293.833159)
			(xy 94.520766 -293.810413) (xy 94.47914 -293.780928) (xy 94.442534 -293.745402) (xy 94.411814 -293.704679)
			(xy 94.399354 -293.68242) (xy 94.39275 -293.669974) (xy 94.368874 -293.655496) (xy 94.073218 -293.655496)
			(xy 94.049342 -293.669974) (xy 94.042738 -293.68242) (xy 94.030261 -293.704667) (xy 93.99953 -293.745375)
			(xy 93.96292 -293.780888) (xy 93.921297 -293.810368) (xy 93.875646 -293.833117) (xy 93.827047 -293.848596)
			(xy 93.776648 -293.856439) (xy 93.751146 -293.856918) (xy 93.736414 -293.856664) (xy 93.721936 -293.855902)
			(xy 93.697298 -293.869364) (xy 93.53804 -294.143684) (xy 93.53804 -294.171116) (xy 93.544898 -294.1828)
			(xy 93.557884 -294.206263) (xy 93.576328 -294.256613) (xy 93.585719 -294.309406) (xy 93.5863 -294.336216)
			(xy 93.585828 -294.360206) (xy 93.57832 -294.407595) (xy 93.563491 -294.453227) (xy 93.541707 -294.495977)
			(xy 93.513503 -294.534792) (xy 93.479574 -294.568718) (xy 93.440756 -294.596919) (xy 93.398005 -294.6187)
			(xy 93.352372 -294.633526) (xy 93.304982 -294.64103) (xy 93.280992 -294.641524) (xy 93.265244 -294.641524)
			(xy 93.241622 -294.654986) (xy 93.06814 -294.95369) (xy 93.06814 -294.981122) (xy 93.074998 -294.992806)
			(xy 93.087984 -295.016269) (xy 93.106427 -295.066619) (xy 93.115816 -295.119412) (xy 93.1164 -295.146222)
			(xy 93.115928 -295.170212) (xy 93.108419 -295.2176) (xy 93.093589 -295.263231) (xy 93.071805 -295.30598)
			(xy 93.043601 -295.344795) (xy 93.009672 -295.37872) (xy 92.970854 -295.40692) (xy 92.928103 -295.428701)
			(xy 92.882471 -295.443526) (xy 92.835082 -295.45103) (xy 92.811092 -295.45153) (xy 92.795344 -295.45153)
			(xy 92.771468 -295.464992) (xy 92.61221 -295.739312) (xy 92.612972 -295.767506) (xy 92.620592 -295.779444)
			(xy 92.632705 -295.799375) (xy 92.651819 -295.841919) (xy 92.664766 -295.886726) (xy 92.671288 -295.932908)
			(xy 92.671646 -295.956228) (xy 92.671134 -295.982215) (xy 92.663001 -296.033548) (xy 92.646938 -296.082977)
			(xy 92.623341 -296.129286) (xy 92.592791 -296.171333) (xy 92.556041 -296.208085) (xy 92.513994 -296.238636)
			(xy 92.467687 -296.262234) (xy 92.418258 -296.278298) (xy 92.366925 -296.286434) (xy 92.340938 -296.286936)
			(xy 92.315433 -296.286467) (xy 92.265026 -296.278643) (xy 92.216417 -296.263175) (xy 92.170759 -296.240429)
			(xy 92.129133 -296.210945) (xy 92.092526 -296.17542) (xy 92.061805 -296.134698) (xy 92.049346 -296.112438)
			(xy 92.042742 -296.099992) (xy 92.018866 -296.085768) (xy 91.694762 -296.085768) (xy 91.671394 -296.098976)
			(xy 91.664536 -296.11066) (xy 91.651752 -296.13151) (xy 91.620609 -296.169215) (xy 91.583854 -296.201475)
			(xy 91.542427 -296.227463) (xy 91.497387 -296.246516) (xy 91.449886 -296.258147) (xy 91.401138 -296.262057)
			(xy 91.35239 -296.258147) (xy 91.304889 -296.246516) (xy 91.259849 -296.227463) (xy 91.218422 -296.201475)
			(xy 91.181667 -296.169215) (xy 91.150524 -296.13151) (xy 91.13774 -296.11066) (xy 91.130882 -296.098976)
			(xy 91.107514 -296.085768) (xy 90.783156 -296.085768) (xy 90.75928 -296.099992) (xy 90.752676 -296.112438)
			(xy 90.740203 -296.134687) (xy 90.709477 -296.175397) (xy 90.672868 -296.210912) (xy 90.631244 -296.240388)
			(xy 90.58559 -296.263129) (xy 90.536987 -296.278595) (xy 90.486586 -296.286421) (xy 90.435582 -296.286421)
			(xy 90.385181 -296.278595) (xy 90.336578 -296.263129) (xy 90.290924 -296.240388) (xy 90.2493 -296.210912)
			(xy 90.212691 -296.175397) (xy 90.181965 -296.134687) (xy 90.169492 -296.112438) (xy 90.162888 -296.099992)
			(xy 90.139012 -296.085768) (xy 89.814654 -296.085768) (xy 89.791286 -296.098976) (xy 89.784428 -296.11066)
			(xy 89.771644 -296.13151) (xy 89.740501 -296.169215) (xy 89.703746 -296.201475) (xy 89.662319 -296.227463)
			(xy 89.617279 -296.246516) (xy 89.569778 -296.258147) (xy 89.52103 -296.262057) (xy 89.472282 -296.258147)
			(xy 89.424781 -296.246516) (xy 89.379741 -296.227463) (xy 89.338314 -296.201475) (xy 89.301559 -296.169215)
			(xy 89.270416 -296.13151) (xy 89.257632 -296.11066) (xy 89.250774 -296.098976) (xy 89.227406 -296.085768)
			(xy 88.903048 -296.085768) (xy 88.879172 -296.099992) (xy 88.872568 -296.112438) (xy 88.860095 -296.134687)
			(xy 88.829369 -296.175397) (xy 88.79276 -296.210912) (xy 88.751136 -296.240388) (xy 88.705482 -296.263129)
			(xy 88.656879 -296.278595) (xy 88.606478 -296.286421) (xy 88.555474 -296.286421) (xy 88.505073 -296.278595)
			(xy 88.45647 -296.263129) (xy 88.410816 -296.240388) (xy 88.369192 -296.210912) (xy 88.332583 -296.175397)
			(xy 88.301857 -296.134687) (xy 88.289384 -296.112438) (xy 88.28278 -296.099992) (xy 88.258904 -296.085768)
			(xy 86.994746 -296.085768) (xy 86.971378 -296.098976) (xy 86.96452 -296.11066) (xy 86.951736 -296.13151)
			(xy 86.920593 -296.169215) (xy 86.883838 -296.201475) (xy 86.842411 -296.227463) (xy 86.797371 -296.246516)
			(xy 86.74987 -296.258147) (xy 86.701122 -296.262057) (xy 86.652374 -296.258147) (xy 86.604873 -296.246516)
			(xy 86.559833 -296.227463) (xy 86.518406 -296.201475) (xy 86.481651 -296.169215) (xy 86.450508 -296.13151)
			(xy 86.437724 -296.11066) (xy 86.430866 -296.098976) (xy 86.407498 -296.085768) (xy 86.08314 -296.085768)
			(xy 86.059264 -296.099992) (xy 86.05266 -296.112438) (xy 86.040187 -296.134687) (xy 86.009461 -296.175397)
			(xy 85.972852 -296.210912) (xy 85.931228 -296.240388) (xy 85.885574 -296.263129) (xy 85.836971 -296.278595)
			(xy 85.78657 -296.286421) (xy 85.735566 -296.286421) (xy 85.685165 -296.278595) (xy 85.636562 -296.263129)
			(xy 85.590908 -296.240388) (xy 85.549284 -296.210912) (xy 85.512675 -296.175397) (xy 85.481949 -296.134687)
			(xy 85.469476 -296.112438) (xy 85.462872 -296.099992) (xy 85.438996 -296.085768) (xy 85.114638 -296.085768)
			(xy 85.09127 -296.098976) (xy 85.084412 -296.11066) (xy 85.071628 -296.13151) (xy 85.040485 -296.169215)
			(xy 85.00373 -296.201475) (xy 84.962303 -296.227463) (xy 84.917263 -296.246516) (xy 84.869762 -296.258147)
			(xy 84.821014 -296.262057) (xy 84.772266 -296.258147) (xy 84.724765 -296.246516) (xy 84.679725 -296.227463)
			(xy 84.638298 -296.201475) (xy 84.601543 -296.169215) (xy 84.5704 -296.13151) (xy 84.557616 -296.11066)
			(xy 84.550758 -296.098976) (xy 84.52739 -296.085768) (xy 84.203032 -296.085768) (xy 84.179156 -296.099992)
			(xy 84.172552 -296.112438) (xy 84.160079 -296.134687) (xy 84.129353 -296.175397) (xy 84.092744 -296.210912)
			(xy 84.05112 -296.240388) (xy 84.005466 -296.263129) (xy 83.956863 -296.278595) (xy 83.906462 -296.286421)
			(xy 83.855458 -296.286421) (xy 83.805057 -296.278595) (xy 83.756454 -296.263129) (xy 83.7108 -296.240388)
			(xy 83.669176 -296.210912) (xy 83.632567 -296.175397) (xy 83.601841 -296.134687) (xy 83.589368 -296.112438)
			(xy 83.582764 -296.099992) (xy 83.558888 -296.085768) (xy 83.23453 -296.085768) (xy 83.211162 -296.098976)
			(xy 83.204304 -296.11066) (xy 83.19152 -296.13151) (xy 83.160377 -296.169215) (xy 83.123622 -296.201475)
			(xy 83.082195 -296.227463) (xy 83.037155 -296.246516) (xy 82.989654 -296.258147) (xy 82.940906 -296.262057)
			(xy 82.892158 -296.258147) (xy 82.844657 -296.246516) (xy 82.799617 -296.227463) (xy 82.75819 -296.201475)
			(xy 82.721435 -296.169215) (xy 82.690292 -296.13151) (xy 82.677508 -296.11066) (xy 82.67065 -296.098976)
			(xy 82.647282 -296.085768) (xy 79.503016 -296.085768) (xy 79.47914 -296.099992) (xy 79.472536 -296.112438)
			(xy 79.460063 -296.134689) (xy 79.429337 -296.175406) (xy 79.392729 -296.210928) (xy 79.351106 -296.240416)
			(xy 79.305453 -296.26317) (xy 79.256851 -296.278653) (xy 79.206448 -296.286499) (xy 79.180944 -296.286936)
			(xy 79.154615 -296.286422) (xy 79.102623 -296.278069) (xy 79.052611 -296.261583) (xy 79.005843 -296.237381)
			(xy 78.984348 -296.222166) (xy 78.97765 -296.217585) (xy 78.962233 -296.212544) (xy 78.954122 -296.21226)
			(xy 69.146928 -296.21226) (xy 69.136865 -296.212698) (xy 69.118285 -296.220437) (xy 69.11086 -296.227246)
			(xy 60.557664 -304.780442) (xy 78.812394 -304.780442) (xy 78.816423 -304.638121) (xy 78.828498 -304.496256)
			(xy 78.848579 -304.355302) (xy 78.876602 -304.215709) (xy 78.912478 -304.077925) (xy 78.956092 -303.942392)
			(xy 79.007304 -303.809543) (xy 79.06595 -303.679804) (xy 79.131841 -303.553591) (xy 79.204768 -303.431308)
			(xy 79.284496 -303.313346) (xy 79.37077 -303.200084) (xy 79.463314 -303.091885) (xy 79.56183 -302.989094)
			(xy 79.666005 -302.892042) (xy 79.775503 -302.801038) (xy 79.889974 -302.716376) (xy 80.009052 -302.638325)
			(xy 80.132355 -302.567136) (xy 80.259488 -302.503037) (xy 80.390044 -302.446233) (xy 80.523604 -302.396907)
			(xy 80.659741 -302.355215) (xy 80.798019 -302.321292) (xy 80.937994 -302.295247) (xy 81.079219 -302.277162)
			(xy 81.22124 -302.267097) (xy 81.363604 -302.265082) (xy 81.505854 -302.271125) (xy 81.647534 -302.285205)
			(xy 81.78819 -302.307279) (xy 81.927372 -302.337275) (xy 82.064634 -302.375097) (xy 82.199537 -302.420625)
			(xy 82.331648 -302.473711) (xy 82.460544 -302.534187) (xy 82.585812 -302.601858) (xy 82.707051 -302.676508)
			(xy 82.823872 -302.757897) (xy 82.935902 -302.845765) (xy 83.042781 -302.939831) (xy 83.144167 -303.039792)
			(xy 83.239736 -303.14533) (xy 83.329181 -303.256105) (xy 83.412215 -303.371763) (xy 83.488573 -303.491933)
			(xy 83.55801 -303.616231) (xy 83.620303 -303.744258) (xy 83.675254 -303.875605) (xy 83.722686 -304.00985)
			(xy 83.762447 -304.146563) (xy 83.794409 -304.285307) (xy 83.818471 -304.425637) (xy 83.834555 -304.567103)
			(xy 83.842611 -304.709253) (xy 83.843114 -304.780442) (xy 83.842611 -304.851631) (xy 83.834555 -304.993781)
			(xy 83.818471 -305.135247) (xy 83.794409 -305.275577) (xy 83.762447 -305.414321) (xy 83.722686 -305.551034)
			(xy 83.675254 -305.685279) (xy 83.620303 -305.816626) (xy 83.55801 -305.944653) (xy 83.488573 -306.068951)
			(xy 83.412215 -306.189121) (xy 83.329181 -306.304779) (xy 83.239736 -306.415554) (xy 83.144167 -306.521092)
			(xy 83.042781 -306.621053) (xy 82.935902 -306.715119) (xy 82.823872 -306.802987) (xy 82.707051 -306.884376)
			(xy 82.585812 -306.959026) (xy 82.460544 -307.026697) (xy 82.331648 -307.087173) (xy 82.199537 -307.140259)
			(xy 82.064634 -307.185787) (xy 81.927372 -307.223609) (xy 81.78819 -307.253605) (xy 81.647534 -307.275679)
			(xy 81.505854 -307.289759) (xy 81.363604 -307.295802) (xy 81.22124 -307.293787) (xy 81.079219 -307.283722)
			(xy 80.937994 -307.265637) (xy 80.798019 -307.239592) (xy 80.659741 -307.205669) (xy 80.523604 -307.163977)
			(xy 80.390044 -307.114651) (xy 80.259488 -307.057847) (xy 80.132355 -306.993748) (xy 80.009052 -306.922559)
			(xy 79.889974 -306.844508) (xy 79.775503 -306.759846) (xy 79.666005 -306.668842) (xy 79.56183 -306.57179)
			(xy 79.463314 -306.468999) (xy 79.37077 -306.3608) (xy 79.284496 -306.247538) (xy 79.204768 -306.129576)
			(xy 79.131841 -306.007293) (xy 79.06595 -305.88108) (xy 79.007304 -305.751341) (xy 78.956092 -305.618492)
			(xy 78.912478 -305.482959) (xy 78.876602 -305.345175) (xy 78.848579 -305.205582) (xy 78.828498 -305.064628)
			(xy 78.816423 -304.922763) (xy 78.812394 -304.780442) (xy 60.557664 -304.780442) (xy 57.078372 -308.259734)
			(xy 57.071523 -308.267131) (xy 57.06379 -308.28573) (xy 57.063386 -308.295802) (xy 57.063386 -309.504588)
			(xy 79.192628 -309.504588) (xy 79.192628 -308.640988) (xy 79.193114 -308.613737) (xy 79.20087 -308.559789)
			(xy 79.216225 -308.507494) (xy 79.238867 -308.457917) (xy 79.268333 -308.412067) (xy 79.304024 -308.370876)
			(xy 79.345215 -308.335185) (xy 79.391065 -308.305719) (xy 79.440642 -308.283077) (xy 79.492937 -308.267722)
			(xy 79.546885 -308.259966) (xy 79.601387 -308.259966) (xy 79.655335 -308.267722) (xy 79.70763 -308.283077)
			(xy 79.757207 -308.305719) (xy 79.803057 -308.335185) (xy 79.844248 -308.370876) (xy 79.879939 -308.412067)
			(xy 79.909405 -308.457917) (xy 79.92811 -308.498873) (xy 93.275072 -308.498873) (xy 93.275072 -308.444327)
			(xy 93.282834 -308.390335) (xy 93.298202 -308.337998) (xy 93.320862 -308.288381) (xy 93.350352 -308.242493)
			(xy 93.386073 -308.20127) (xy 93.427297 -308.16555) (xy 93.473184 -308.13606) (xy 93.522802 -308.113401)
			(xy 93.575139 -308.098034) (xy 93.629131 -308.090271) (xy 93.656404 -308.089808) (xy 94.520004 -308.089808)
			(xy 94.547271 -308.090355) (xy 94.60125 -308.098116) (xy 94.653575 -308.113481) (xy 94.703181 -308.136135)
			(xy 94.749058 -308.165619) (xy 94.790271 -308.201331) (xy 94.825983 -308.242546) (xy 94.855467 -308.288423)
			(xy 94.878121 -308.338029) (xy 94.893485 -308.390354) (xy 94.901246 -308.444333) (xy 94.901246 -308.498867)
			(xy 94.893485 -308.552846) (xy 94.878121 -308.605171) (xy 94.855467 -308.654777) (xy 94.825983 -308.700654)
			(xy 94.790271 -308.741869) (xy 94.749058 -308.777581) (xy 94.703181 -308.807065) (xy 94.653575 -308.829719)
			(xy 94.60125 -308.845084) (xy 94.547271 -308.852845) (xy 94.520004 -308.853332) (xy 93.656404 -308.853332)
			(xy 93.629131 -308.852929) (xy 93.575139 -308.845166) (xy 93.522802 -308.829799) (xy 93.473184 -308.80714)
			(xy 93.427297 -308.77765) (xy 93.386073 -308.74193) (xy 93.350352 -308.700707) (xy 93.320862 -308.654819)
			(xy 93.298202 -308.605202) (xy 93.282834 -308.552865) (xy 93.275072 -308.498873) (xy 79.92811 -308.498873)
			(xy 79.932047 -308.507494) (xy 79.947402 -308.559789) (xy 79.955158 -308.613737) (xy 79.955644 -308.640988)
			(xy 79.955644 -309.504588) (xy 79.955158 -309.531839) (xy 79.947402 -309.585787) (xy 79.932047 -309.638082)
			(xy 79.909405 -309.687659) (xy 79.879939 -309.733509) (xy 79.844248 -309.7747) (xy 79.803057 -309.810391)
			(xy 79.757207 -309.839857) (xy 79.70763 -309.862499) (xy 79.655335 -309.877854) (xy 79.601387 -309.88561)
			(xy 79.546885 -309.88561) (xy 79.492937 -309.877854) (xy 79.440642 -309.862499) (xy 79.391065 -309.839857)
			(xy 79.345215 -309.810391) (xy 79.304024 -309.7747) (xy 79.268333 -309.733509) (xy 79.238867 -309.687659)
			(xy 79.216225 -309.638082) (xy 79.20087 -309.585787) (xy 79.193114 -309.531839) (xy 79.192628 -309.504588)
			(xy 57.063386 -309.504588) (xy 57.063386 -310.603646) (xy 98.925888 -310.603646) (xy 98.925888 -309.740046)
			(xy 98.926374 -309.712795) (xy 98.93413 -309.658847) (xy 98.949485 -309.606552) (xy 98.972127 -309.556975)
			(xy 99.001593 -309.511125) (xy 99.037284 -309.469934) (xy 99.078475 -309.434243) (xy 99.124325 -309.404777)
			(xy 99.173902 -309.382135) (xy 99.226197 -309.36678) (xy 99.280145 -309.359024) (xy 99.334647 -309.359024)
			(xy 99.388595 -309.36678) (xy 99.44089 -309.382135) (xy 99.490467 -309.404777) (xy 99.536317 -309.434243)
			(xy 99.577508 -309.469934) (xy 99.613199 -309.511125) (xy 99.642665 -309.556975) (xy 99.665307 -309.606552)
			(xy 99.680662 -309.658847) (xy 99.688418 -309.712795) (xy 99.688904 -309.740046) (xy 99.688904 -310.603646)
			(xy 99.688418 -310.630897) (xy 99.680662 -310.684845) (xy 99.665307 -310.73714) (xy 99.642665 -310.786717)
			(xy 99.613199 -310.832567) (xy 99.577508 -310.873758) (xy 99.536317 -310.909449) (xy 99.490467 -310.938915)
			(xy 99.44089 -310.961557) (xy 99.388595 -310.976912) (xy 99.334647 -310.984668) (xy 99.280145 -310.984668)
			(xy 99.226197 -310.976912) (xy 99.173902 -310.961557) (xy 99.124325 -310.938915) (xy 99.078475 -310.909449)
			(xy 99.037284 -310.873758) (xy 99.001593 -310.832567) (xy 98.972127 -310.786717) (xy 98.949485 -310.73714)
			(xy 98.93413 -310.684845) (xy 98.926374 -310.630897) (xy 98.925888 -310.603646) (xy 57.063386 -310.603646)
			(xy 57.063386 -312.822082) (xy 57.065418 -312.829194) (xy 57.072764 -312.85512) (xy 57.08067 -312.908423)
			(xy 57.081166 -312.935366) (xy 57.080637 -312.962306) (xy 57.072731 -313.015604) (xy 57.065418 -313.041538)
			(xy 57.063386 -313.04865) (xy 57.063386 -314.997338) (xy 98.330512 -314.997338) (xy 98.330512 -314.133738)
			(xy 98.330998 -314.106487) (xy 98.338754 -314.052539) (xy 98.354109 -314.000244) (xy 98.376751 -313.950667)
			(xy 98.406217 -313.904817) (xy 98.441908 -313.863626) (xy 98.483099 -313.827935) (xy 98.528949 -313.798469)
			(xy 98.578526 -313.775827) (xy 98.630821 -313.760472) (xy 98.684769 -313.752716) (xy 98.739271 -313.752716)
			(xy 98.793219 -313.760472) (xy 98.845514 -313.775827) (xy 98.895091 -313.798469) (xy 98.940941 -313.827935)
			(xy 98.982132 -313.863626) (xy 99.017823 -313.904817) (xy 99.047289 -313.950667) (xy 99.069931 -314.000244)
			(xy 99.085286 -314.052539) (xy 99.093042 -314.106487) (xy 99.093528 -314.133738) (xy 99.093528 -314.997338)
			(xy 99.093042 -315.024589) (xy 99.085286 -315.078537) (xy 99.069931 -315.130832) (xy 99.047289 -315.180409)
			(xy 99.017823 -315.226259) (xy 98.982132 -315.26745) (xy 98.940941 -315.303141) (xy 98.895091 -315.332607)
			(xy 98.845514 -315.355249) (xy 98.793219 -315.370604) (xy 98.739271 -315.37836) (xy 98.684769 -315.37836)
			(xy 98.630821 -315.370604) (xy 98.578526 -315.355249) (xy 98.528949 -315.332607) (xy 98.483099 -315.303141)
			(xy 98.441908 -315.26745) (xy 98.406217 -315.226259) (xy 98.376751 -315.180409) (xy 98.354109 -315.130832)
			(xy 98.338754 -315.078537) (xy 98.330998 -315.024589) (xy 98.330512 -314.997338) (xy 57.063386 -314.997338)
			(xy 57.063386 -315.371988) (xy 57.065418 -315.3791) (xy 57.072764 -315.405026) (xy 57.080669 -315.458329)
			(xy 57.081166 -315.485272) (xy 57.080637 -315.512212) (xy 57.07273 -315.56551) (xy 57.065418 -315.591444)
			(xy 57.063386 -315.598556) (xy 57.063386 -334.781906) (xy 57.06381 -334.791976) (xy 57.071524 -334.81058)
			(xy 57.078372 -334.817974) (xy 57.478676 -335.218278) (xy 57.486078 -335.225115) (xy 57.504676 -335.232825)
			(xy 57.514744 -335.233264)
		)
		(stroke
			(width 0)
			(type solid)
		)
		(fill yes)
		(layer "In8.Cu")
		(net "PVDDCR_CPU1_P1")
	)
	(gr_poly
		(pts
			(xy 311.496964 -335.233518) (xy 311.507029 -335.233084) (xy 311.525619 -335.225355) (xy 311.533032 -335.218532)
			(xy 311.846976 -334.904588) (xy 311.853823 -334.89719) (xy 311.861557 -334.878592) (xy 311.861962 -334.86852)
			(xy 311.861962 -330.394818) (xy 311.862581 -330.369864) (xy 311.872331 -330.320918) (xy 311.89144 -330.274813)
			(xy 311.919175 -330.233321) (xy 311.936384 -330.21524) (xy 312.698384 -329.45324) (xy 312.716427 -329.435984)
			(xy 312.757922 -329.408235) (xy 312.80404 -329.389131) (xy 312.853002 -329.379407) (xy 312.877962 -329.378818)
			(xy 318.593724 -329.378818) (xy 318.603793 -329.378391) (xy 318.622393 -329.370673) (xy 318.629792 -329.363832)
			(xy 319.70218 -328.291444) (xy 319.708022 -328.261218) (xy 319.701672 -328.24674) (xy 319.692024 -328.222992)
			(xy 319.678453 -328.173563) (xy 319.671611 -328.122763) (xy 319.671192 -328.097134) (xy 319.671653 -328.06988)
			(xy 319.679406 -328.015925) (xy 319.694759 -327.963623) (xy 319.7174 -327.914039) (xy 319.746867 -327.868181)
			(xy 319.78256 -327.826985) (xy 319.823754 -327.791287) (xy 319.869609 -327.761816) (xy 319.919191 -327.739171)
			(xy 319.971492 -327.723813) (xy 320.025446 -327.716055) (xy 320.0527 -327.715626) (xy 320.078331 -327.716023)
			(xy 320.129133 -327.722861) (xy 320.17856 -327.736452) (xy 320.202306 -327.746106) (xy 320.216784 -327.752456)
			(xy 320.24701 -327.746614) (xy 322.223384 -325.77024) (xy 322.241427 -325.752984) (xy 322.282922 -325.725235)
			(xy 322.32904 -325.706131) (xy 322.378002 -325.696407) (xy 322.402962 -325.695818) (xy 344.246962 -325.695818)
			(xy 344.271916 -325.696435) (xy 344.320863 -325.706184) (xy 344.366968 -325.725294) (xy 344.408459 -325.753031)
			(xy 344.42654 -325.77024) (xy 346.80652 -328.15022) (xy 346.813916 -328.157072) (xy 346.832515 -328.164812)
			(xy 346.842588 -328.165206) (xy 352.404172 -328.165206) (xy 352.414237 -328.16477) (xy 352.432823 -328.157038)
			(xy 352.44024 -328.15022) (xy 353.16922 -327.42124) (xy 353.187261 -327.40398) (xy 353.228754 -327.37622)
			(xy 353.274872 -327.357104) (xy 353.323836 -327.347368) (xy 353.348798 -327.346818) (xy 358.441498 -327.346818)
			(xy 358.468168 -327.327514) (xy 358.473248 -327.311766) (xy 358.486153 -327.274052) (xy 358.518745 -327.201304)
			(xy 358.558749 -327.132353) (xy 358.605727 -327.067952) (xy 358.659166 -327.008802) (xy 358.718485 -326.95555)
			(xy 358.783035 -326.908777) (xy 358.852113 -326.868992) (xy 358.924963 -326.836631) (xy 359.000792 -326.812046)
			(xy 359.078772 -326.795505) (xy 359.158052 -326.787189) (xy 359.237768 -326.787189) (xy 359.317048 -326.795505)
			(xy 359.395028 -326.812046) (xy 359.470857 -326.836631) (xy 359.543707 -326.868992) (xy 359.612785 -326.908777)
			(xy 359.677335 -326.95555) (xy 359.736654 -327.008802) (xy 359.790093 -327.067952) (xy 359.837071 -327.132353)
			(xy 359.877075 -327.201304) (xy 359.909667 -327.274052) (xy 359.922572 -327.311766) (xy 359.927652 -327.327514)
			(xy 359.954322 -327.346818) (xy 379.045724 -327.346818) (xy 379.055793 -327.346391) (xy 379.074393 -327.338673)
			(xy 379.081792 -327.331832) (xy 379.489716 -326.923908) (xy 379.496573 -326.916514) (xy 379.504323 -326.897915)
			(xy 379.504702 -326.88784) (xy 379.504702 -299.798994) (xy 379.484382 -299.77207) (xy 379.468126 -299.767244)
			(xy 379.441983 -299.759204) (xy 379.392142 -299.736678) (xy 379.346029 -299.707266) (xy 379.304588 -299.671571)
			(xy 379.268669 -299.630323) (xy 379.239009 -299.58437) (xy 379.216214 -299.534651) (xy 379.200753 -299.482187)
			(xy 379.192942 -299.428053) (xy 379.192941 -299.373359) (xy 379.20075 -299.319225) (xy 379.21621 -299.26676)
			(xy 379.239003 -299.217041) (xy 379.268662 -299.171086) (xy 379.30458 -299.129838) (xy 379.346019 -299.094141)
			(xy 379.392132 -299.064728) (xy 379.441972 -299.0422) (xy 379.468126 -299.0342) (xy 379.484382 -299.029374)
			(xy 379.504702 -299.00245) (xy 379.504702 -296.21353) (xy 379.50442 -296.205273) (xy 379.499231 -296.189599)
			(xy 379.494542 -296.182796) (xy 379.478793 -296.161135) (xy 379.453773 -296.113788) (xy 379.436709 -296.063028)
			(xy 379.428047 -296.010181) (xy 379.427486 -295.983406) (xy 379.427947 -295.958674) (xy 379.435318 -295.909762)
			(xy 379.449896 -295.862496) (xy 379.471355 -295.817929) (xy 379.48489 -295.797224) (xy 379.493272 -295.785032)
			(xy 379.494288 -295.755822) (xy 379.339602 -295.489122) (xy 379.31471 -295.47566) (xy 379.300486 -295.476422)
			(xy 379.284738 -295.476676) (xy 379.258748 -295.476196) (xy 379.207406 -295.468069) (xy 379.157969 -295.45201)
			(xy 379.111653 -295.428413) (xy 379.069599 -295.397861) (xy 379.032843 -295.361106) (xy 379.00229 -295.319052)
			(xy 378.978693 -295.272737) (xy 378.962632 -295.223299) (xy 378.954505 -295.171958) (xy 378.95403 -295.145968)
			(xy 378.95442 -295.122535) (xy 378.961003 -295.076134) (xy 378.974076 -295.031129) (xy 378.993376 -294.988423)
			(xy 379.005592 -294.968422) (xy 379.013466 -294.956484) (xy 379.013974 -294.92829) (xy 378.869448 -294.679116)
			(xy 378.844556 -294.665654) (xy 378.830332 -294.666416) (xy 378.814838 -294.66667) (xy 378.788848 -294.66619)
			(xy 378.737507 -294.658063) (xy 378.68807 -294.642004) (xy 378.641754 -294.618407) (xy 378.599701 -294.587855)
			(xy 378.562945 -294.551099) (xy 378.532393 -294.509046) (xy 378.508796 -294.46273) (xy 378.492737 -294.413293)
			(xy 378.48461 -294.361952) (xy 378.48413 -294.335962) (xy 378.484532 -294.31256) (xy 378.491127 -294.266223)
			(xy 378.504194 -294.221281) (xy 378.523471 -294.178631) (xy 378.535692 -294.15867) (xy 378.543312 -294.146478)
			(xy 378.54382 -294.118284) (xy 378.399294 -293.86911) (xy 378.374656 -293.855648) (xy 378.360178 -293.85641)
			(xy 378.344938 -293.856664) (xy 378.319447 -293.856195) (xy 378.269068 -293.848371) (xy 378.220488 -293.832902)
			(xy 378.174861 -293.810156) (xy 378.133268 -293.780673) (xy 378.096697 -293.745151) (xy 378.066015 -293.704434)
			(xy 378.0536 -293.682166) (xy 378.046742 -293.66972) (xy 378.022866 -293.655496) (xy 377.726956 -293.655496)
			(xy 377.70308 -293.66972) (xy 377.696222 -293.682166) (xy 377.683775 -293.704415) (xy 377.653098 -293.745129)
			(xy 377.616531 -293.780649) (xy 377.574943 -293.810132) (xy 377.529321 -293.832878) (xy 377.480747 -293.848348)
			(xy 377.430373 -293.856174) (xy 377.404884 -293.856664) (xy 377.378897 -293.85618) (xy 377.327563 -293.848046)
			(xy 377.278133 -293.831982) (xy 377.231825 -293.808383) (xy 377.18978 -293.777829) (xy 377.153032 -293.741075)
			(xy 377.122486 -293.699023) (xy 377.098895 -293.652711) (xy 377.08284 -293.603279) (xy 377.074716 -293.551943)
			(xy 377.074176 -293.525956) (xy 377.074579 -293.502554) (xy 377.081175 -293.456218) (xy 377.094244 -293.411277)
			(xy 377.113524 -293.368629) (xy 377.125738 -293.348664) (xy 377.133358 -293.336472) (xy 377.133866 -293.308278)
			(xy 376.98934 -293.059104) (xy 376.964702 -293.045642) (xy 376.950224 -293.046404) (xy 376.93473 -293.046658)
			(xy 376.908741 -293.046177) (xy 376.857401 -293.038049) (xy 376.807966 -293.021989) (xy 376.761652 -292.998392)
			(xy 376.719601 -292.96784) (xy 376.682847 -292.931084) (xy 376.652297 -292.889031) (xy 376.628703 -292.842715)
			(xy 376.612646 -292.793279) (xy 376.604521 -292.741939) (xy 376.604022 -292.71595) (xy 376.604425 -292.692548)
			(xy 376.611021 -292.646212) (xy 376.624089 -292.60127) (xy 376.643367 -292.558622) (xy 376.655584 -292.538658)
			(xy 376.663204 -292.526466) (xy 376.663966 -292.498272) (xy 376.51944 -292.249098) (xy 376.494548 -292.235636)
			(xy 376.480324 -292.236398) (xy 376.46483 -292.236652) (xy 376.43884 -292.236145) (xy 376.387499 -292.228018)
			(xy 376.338062 -292.21196) (xy 376.291745 -292.188367) (xy 376.249689 -292.157818) (xy 376.21293 -292.121067)
			(xy 376.182372 -292.079018) (xy 376.158768 -292.032707) (xy 376.142699 -291.983273) (xy 376.134561 -291.931934)
			(xy 376.134122 -291.905944) (xy 376.134525 -291.882542) (xy 376.141123 -291.836207) (xy 376.154191 -291.791265)
			(xy 376.17347 -291.748617) (xy 376.185684 -291.728652) (xy 376.193304 -291.71646) (xy 376.193812 -291.688266)
			(xy 376.049286 -291.439092) (xy 376.024648 -291.42563) (xy 376.01017 -291.426392) (xy 375.99493 -291.426646)
			(xy 375.96894 -291.426139) (xy 375.9176 -291.418012) (xy 375.868163 -291.401954) (xy 375.821846 -291.378361)
			(xy 375.779791 -291.347812) (xy 375.743032 -291.311061) (xy 375.712475 -291.269012) (xy 375.688872 -291.2227)
			(xy 375.672804 -291.173266) (xy 375.664667 -291.121928) (xy 375.664222 -291.095938) (xy 375.664626 -291.072537)
			(xy 375.671224 -291.026201) (xy 375.684293 -290.98126) (xy 375.703572 -290.938612) (xy 375.715784 -290.918646)
			(xy 375.723404 -290.906708) (xy 375.723912 -290.87826) (xy 375.579386 -290.629086) (xy 375.554494 -290.615624)
			(xy 375.54027 -290.616386) (xy 375.524776 -290.61664) (xy 375.498789 -290.616129) (xy 375.447456 -290.607995)
			(xy 375.398026 -290.591933) (xy 375.351718 -290.568336) (xy 375.30967 -290.537786) (xy 375.272919 -290.501036)
			(xy 375.242368 -290.458989) (xy 375.21877 -290.412681) (xy 375.202707 -290.363252) (xy 375.194572 -290.311919)
			(xy 375.194068 -290.285932) (xy 375.194472 -290.262531) (xy 375.201072 -290.216196) (xy 375.214143 -290.171256)
			(xy 375.233425 -290.128611) (xy 375.24563 -290.10864) (xy 375.25325 -290.096448) (xy 375.254012 -290.068254)
			(xy 375.109232 -289.81908) (xy 375.084594 -289.805618) (xy 375.070116 -289.80638) (xy 375.054876 -289.806634)
			(xy 375.028889 -289.806123) (xy 374.977556 -289.797989) (xy 374.928127 -289.781927) (xy 374.881819 -289.75833)
			(xy 374.839772 -289.72778) (xy 374.803021 -289.691029) (xy 374.772471 -289.648983) (xy 374.748874 -289.602675)
			(xy 374.732811 -289.553246) (xy 374.724677 -289.501913) (xy 374.724168 -289.475926) (xy 374.724573 -289.452525)
			(xy 374.731173 -289.406191) (xy 374.744245 -289.361251) (xy 374.763528 -289.318606) (xy 374.77573 -289.298634)
			(xy 374.78335 -289.286442) (xy 374.783858 -289.258248) (xy 374.639332 -289.009074) (xy 374.61444 -288.995612)
			(xy 374.600216 -288.996374) (xy 374.584722 -288.996628) (xy 374.55873 -288.996146) (xy 374.507386 -288.988017)
			(xy 374.457945 -288.971956) (xy 374.411626 -288.948358) (xy 374.369569 -288.917805) (xy 374.33281 -288.881048)
			(xy 374.302253 -288.838993) (xy 374.278652 -288.792675) (xy 374.262588 -288.743236) (xy 374.254455 -288.691892)
			(xy 374.254455 -288.639908) (xy 374.262588 -288.588564) (xy 374.278652 -288.539125) (xy 374.302253 -288.492807)
			(xy 374.33281 -288.450752) (xy 374.369569 -288.413995) (xy 374.411626 -288.383442) (xy 374.457945 -288.359844)
			(xy 374.507386 -288.343783) (xy 374.55873 -288.335654) (xy 374.584722 -288.335212) (xy 374.60301 -288.33572)
			(xy 374.617234 -288.336482) (xy 374.64238 -288.32302) (xy 374.785636 -288.076386) (xy 374.784874 -288.047684)
			(xy 374.777 -288.035746) (xy 374.764477 -288.015581) (xy 374.74471 -287.972426) (xy 374.731319 -287.926887)
			(xy 374.724578 -287.879902) (xy 374.724168 -287.856168) (xy 374.72468 -287.830182) (xy 374.732814 -287.77885)
			(xy 374.748878 -287.729422) (xy 374.772475 -287.683115) (xy 374.803025 -287.641069) (xy 374.839775 -287.60432)
			(xy 374.881822 -287.573771) (xy 374.928129 -287.550175) (xy 374.977558 -287.534112) (xy 375.02889 -287.525979)
			(xy 375.054876 -287.52546) (xy 375.07291 -287.525968) (xy 375.087134 -287.52673) (xy 375.11228 -287.513014)
			(xy 375.255536 -287.266126) (xy 375.255028 -287.237678) (xy 375.247154 -287.225486) (xy 375.234613 -287.205324)
			(xy 375.214801 -287.162173) (xy 375.201348 -287.116638) (xy 375.19453 -287.069648) (xy 375.194068 -287.045908)
			(xy 375.194474 -287.022507) (xy 375.201077 -286.976174) (xy 375.214151 -286.931236) (xy 375.233435 -286.888592)
			(xy 375.24563 -286.868616) (xy 375.25325 -286.856424) (xy 375.253758 -286.82823) (xy 375.109486 -286.57931)
			(xy 375.084594 -286.565848) (xy 375.07037 -286.56661) (xy 375.054876 -286.566864) (xy 375.028889 -286.566379)
			(xy 374.977556 -286.558245) (xy 374.928128 -286.54218) (xy 374.881821 -286.51858) (xy 374.839776 -286.488027)
			(xy 374.803029 -286.451272) (xy 374.772485 -286.409221) (xy 374.748894 -286.362909) (xy 374.73284 -286.313478)
			(xy 374.724716 -286.262143) (xy 374.724168 -286.236156) (xy 374.724571 -286.212754) (xy 374.731167 -286.166418)
			(xy 374.744236 -286.121477) (xy 374.763515 -286.078829) (xy 374.77573 -286.058864) (xy 374.78335 -286.046672)
			(xy 374.784112 -286.018478) (xy 374.639332 -285.769304) (xy 374.614694 -285.755842) (xy 374.600216 -285.756604)
			(xy 374.584722 -285.756858) (xy 374.558728 -285.756376) (xy 374.507379 -285.748247) (xy 374.457934 -285.732184)
			(xy 374.411611 -285.708584) (xy 374.36955 -285.678027) (xy 374.332787 -285.641267) (xy 374.302228 -285.599208)
			(xy 374.278625 -285.552887) (xy 374.262559 -285.503443) (xy 374.254425 -285.452094) (xy 374.254425 -285.400106)
			(xy 374.262559 -285.348757) (xy 374.278625 -285.299313) (xy 374.302228 -285.252992) (xy 374.332787 -285.210933)
			(xy 374.36955 -285.174173) (xy 374.411611 -285.143616) (xy 374.457934 -285.120016) (xy 374.507379 -285.103953)
			(xy 374.558728 -285.095824) (xy 374.584722 -285.095442) (xy 374.602756 -285.09595) (xy 374.617234 -285.096712)
			(xy 374.64238 -285.08325) (xy 374.785636 -284.836362) (xy 374.784874 -284.80766) (xy 374.777 -284.795722)
			(xy 374.764472 -284.775559) (xy 374.744696 -284.732405) (xy 374.731294 -284.686866) (xy 374.724542 -284.639879)
			(xy 374.724168 -284.616144) (xy 374.724648 -284.590152) (xy 374.732773 -284.538806) (xy 374.748831 -284.489365)
			(xy 374.772427 -284.443044) (xy 374.802978 -284.400984) (xy 374.839732 -284.364222) (xy 374.881785 -284.333662)
			(xy 374.928102 -284.310058) (xy 374.97754 -284.293989) (xy 375.028884 -284.285853) (xy 375.054876 -284.285436)
			(xy 375.07291 -284.285944) (xy 375.087134 -284.286706) (xy 375.11228 -284.27299) (xy 375.255536 -284.026356)
			(xy 375.254774 -283.997654) (xy 375.247154 -283.985716) (xy 375.234611 -283.965555) (xy 375.214795 -283.922404)
			(xy 375.201339 -283.876869) (xy 375.194516 -283.829879) (xy 375.194068 -283.806138) (xy 375.194472 -283.782737)
			(xy 375.201071 -283.736402) (xy 375.214142 -283.691462) (xy 375.233423 -283.648815) (xy 375.24563 -283.628846)
			(xy 375.253504 -283.616654) (xy 375.254012 -283.58846) (xy 375.109486 -283.339286) (xy 375.084594 -283.325824)
			(xy 375.07037 -283.326586) (xy 375.054876 -283.32684) (xy 375.028889 -283.326329) (xy 374.977556 -283.318195)
			(xy 374.928126 -283.302133) (xy 374.881818 -283.278536) (xy 374.83977 -283.247986) (xy 374.803019 -283.211236)
			(xy 374.772468 -283.169189) (xy 374.74887 -283.122881) (xy 374.732807 -283.073452) (xy 374.724672 -283.022119)
			(xy 374.724168 -282.996132) (xy 374.724572 -282.972731) (xy 374.731172 -282.926396) (xy 374.744243 -282.881456)
			(xy 374.763525 -282.838811) (xy 374.77573 -282.81884) (xy 374.78335 -282.806648) (xy 374.784112 -282.778454)
			(xy 374.639332 -282.52928) (xy 374.614694 -282.515818) (xy 374.600216 -282.51658) (xy 374.584722 -282.516834)
			(xy 374.55873 -282.516352) (xy 374.507384 -282.508223) (xy 374.457943 -282.492162) (xy 374.411623 -282.468563)
			(xy 374.369565 -282.438009) (xy 374.332805 -282.401251) (xy 374.302248 -282.359196) (xy 374.278647 -282.312877)
			(xy 374.262582 -282.263437) (xy 374.254449 -282.212092) (xy 374.254449 -282.160108) (xy 374.262582 -282.108763)
			(xy 374.278647 -282.059323) (xy 374.302248 -282.013004) (xy 374.332805 -281.970949) (xy 374.369565 -281.934191)
			(xy 374.411623 -281.903637) (xy 374.457943 -281.880038) (xy 374.507384 -281.863977) (xy 374.55873 -281.855848)
			(xy 374.584722 -281.855418) (xy 374.602756 -281.855926) (xy 374.61698 -281.856688) (xy 374.642126 -281.843226)
			(xy 374.785382 -281.596084) (xy 374.784874 -281.567636) (xy 374.777 -281.555444) (xy 374.764492 -281.535307)
			(xy 374.744744 -281.492213) (xy 374.731353 -281.446741) (xy 374.724594 -281.399822) (xy 374.724168 -281.37612)
			(xy 374.724573 -281.352719) (xy 374.731174 -281.306385) (xy 374.744247 -281.261446) (xy 374.76353 -281.218802)
			(xy 374.77573 -281.198828) (xy 374.78335 -281.18689) (xy 374.783858 -281.158442) (xy 374.639332 -280.909268)
			(xy 374.61444 -280.895806) (xy 374.600216 -280.896568) (xy 374.584722 -280.896822) (xy 374.558731 -280.896341)
			(xy 374.507389 -280.888212) (xy 374.457951 -280.872152) (xy 374.411634 -280.848556) (xy 374.369578 -280.818004)
			(xy 374.332819 -280.78125) (xy 374.302263 -280.739197) (xy 374.278662 -280.692883) (xy 374.262596 -280.643446)
			(xy 374.254462 -280.592105) (xy 374.254014 -280.566114) (xy 374.254419 -280.542713) (xy 374.26102 -280.496379)
			(xy 374.274092 -280.451439) (xy 374.293373 -280.408794) (xy 374.305576 -280.388822) (xy 374.313196 -280.37663)
			(xy 374.313958 -280.348436) (xy 374.169432 -280.099262) (xy 374.14454 -280.0858) (xy 374.130316 -280.086562)
			(xy 374.114822 -280.086816) (xy 374.088831 -280.086334) (xy 374.037489 -280.078206) (xy 373.98805 -280.062145)
			(xy 373.941732 -280.038548) (xy 373.899677 -280.007995) (xy 373.862919 -279.97124) (xy 373.832364 -279.929186)
			(xy 373.808763 -279.882871) (xy 373.792699 -279.833433) (xy 373.784567 -279.782091) (xy 373.784567 -279.730109)
			(xy 373.792699 -279.678767) (xy 373.808763 -279.629329) (xy 373.832364 -279.583014) (xy 373.862919 -279.54096)
			(xy 373.899677 -279.504205) (xy 373.941732 -279.473652) (xy 373.98805 -279.450055) (xy 374.037489 -279.433994)
			(xy 374.088831 -279.425866) (xy 374.114822 -279.4254) (xy 374.138638 -279.425817) (xy 374.185775 -279.432656)
			(xy 374.231443 -279.446189) (xy 374.274697 -279.466135) (xy 374.294908 -279.47874) (xy 374.3071 -279.486614)
			(xy 374.335294 -279.487376) (xy 375.181368 -279.001728) (xy 375.195084 -278.976582) (xy 375.194576 -278.962104)
			(xy 375.194068 -278.946102) (xy 375.194474 -278.922701) (xy 375.201078 -278.876369) (xy 375.214153 -278.831431)
			(xy 375.233438 -278.788788) (xy 375.24563 -278.76881) (xy 375.25325 -278.756618) (xy 375.253758 -278.728424)
			(xy 375.109232 -278.47925) (xy 375.084594 -278.465788) (xy 375.070116 -278.46655) (xy 375.054876 -278.466804)
			(xy 375.02889 -278.466293) (xy 374.977559 -278.458159) (xy 374.928132 -278.442096) (xy 374.881826 -278.418499)
			(xy 374.839781 -278.387948) (xy 374.803033 -278.351197) (xy 374.772487 -278.30915) (xy 374.748893 -278.262842)
			(xy 374.732834 -278.213414) (xy 374.724705 -278.162082) (xy 374.724168 -278.136096) (xy 374.724575 -278.112696)
			(xy 374.731179 -278.066363) (xy 374.744255 -278.021426) (xy 374.76354 -277.978783) (xy 374.77573 -277.958804)
			(xy 374.78335 -277.946612) (xy 374.783858 -277.918418) (xy 374.639332 -277.669244) (xy 374.614694 -277.655782)
			(xy 374.600216 -277.656544) (xy 374.584722 -277.656798) (xy 374.558732 -277.656317) (xy 374.507393 -277.648188)
			(xy 374.457957 -277.632128) (xy 374.411642 -277.608533) (xy 374.369589 -277.577982) (xy 374.332833 -277.541228)
			(xy 374.302279 -277.499177) (xy 374.27868 -277.452864) (xy 374.262617 -277.403429) (xy 374.254485 -277.35209)
			(xy 374.254485 -277.30011) (xy 374.262617 -277.248771) (xy 374.27868 -277.199336) (xy 374.302279 -277.153023)
			(xy 374.332833 -277.110972) (xy 374.369589 -277.074218) (xy 374.411642 -277.043667) (xy 374.457957 -277.020072)
			(xy 374.507393 -277.004012) (xy 374.558732 -276.995883) (xy 374.584722 -276.995382) (xy 374.602756 -276.99589)
			(xy 374.617234 -276.996652) (xy 374.64238 -276.98319) (xy 374.785636 -276.736302) (xy 374.784874 -276.7076)
			(xy 374.777 -276.695662) (xy 374.764476 -276.675498) (xy 374.744707 -276.632343) (xy 374.731314 -276.586804)
			(xy 374.72457 -276.539818) (xy 374.724168 -276.516084) (xy 374.724679 -276.490097) (xy 374.732811 -276.438763)
			(xy 374.748873 -276.389333) (xy 374.77247 -276.343024) (xy 374.803019 -276.300976) (xy 374.83977 -276.264224)
			(xy 374.881817 -276.233674) (xy 374.928126 -276.210076) (xy 374.977555 -276.194013) (xy 375.028889 -276.185879)
			(xy 375.054876 -276.185376) (xy 375.07291 -276.185884) (xy 375.087134 -276.186646) (xy 375.11228 -276.17293)
			(xy 375.255536 -275.926296) (xy 375.254774 -275.897594) (xy 375.247154 -275.885656) (xy 375.234608 -275.865495)
			(xy 375.214788 -275.822346) (xy 375.201325 -275.77681) (xy 375.194498 -275.72982) (xy 375.194068 -275.706078)
			(xy 375.194469 -275.682676) (xy 375.201063 -275.636339) (xy 375.214129 -275.591395) (xy 375.233406 -275.548746)
			(xy 375.24563 -275.528786) (xy 375.253504 -275.516594) (xy 375.254012 -275.4884) (xy 375.109486 -275.239226)
			(xy 375.084594 -275.225764) (xy 375.07037 -275.226526) (xy 375.054876 -275.22678) (xy 375.028889 -275.226295)
			(xy 374.977555 -275.218161) (xy 374.928125 -275.202096) (xy 374.881817 -275.178496) (xy 374.839771 -275.147943)
			(xy 374.803023 -275.111189) (xy 374.772476 -275.069138) (xy 374.748884 -275.022827) (xy 374.732827 -274.973395)
			(xy 374.724701 -274.922059) (xy 374.724168 -274.896072) (xy 374.72457 -274.87267) (xy 374.731164 -274.826333)
			(xy 374.744231 -274.78139) (xy 374.763509 -274.738741) (xy 374.77573 -274.71878) (xy 374.78335 -274.706588)
			(xy 374.784112 -274.678394) (xy 374.639332 -274.42922) (xy 374.614694 -274.415758) (xy 374.600216 -274.41652)
			(xy 374.584722 -274.416774) (xy 374.558734 -274.416293) (xy 374.507398 -274.408165) (xy 374.457966 -274.392106)
			(xy 374.411654 -274.368512) (xy 374.369604 -274.337963) (xy 374.332851 -274.301213) (xy 374.302299 -274.259164)
			(xy 374.278702 -274.212854) (xy 374.26264 -274.163423) (xy 374.254509 -274.112088) (xy 374.254509 -274.060112)
			(xy 374.26264 -274.008777) (xy 374.278702 -273.959346) (xy 374.302299 -273.913036) (xy 374.332851 -273.870987)
			(xy 374.369604 -273.834237) (xy 374.411654 -273.803688) (xy 374.457966 -273.780094) (xy 374.507398 -273.764035)
			(xy 374.558734 -273.755907) (xy 374.584722 -273.755358) (xy 374.602756 -273.755866) (xy 374.617234 -273.756628)
			(xy 374.64238 -273.743166) (xy 374.785636 -273.496278) (xy 374.784874 -273.467576) (xy 374.777 -273.455638)
			(xy 374.764471 -273.435475) (xy 374.744693 -273.392321) (xy 374.731289 -273.346783) (xy 374.724534 -273.299795)
			(xy 374.724168 -273.27606) (xy 374.724681 -273.250074) (xy 374.732816 -273.198743) (xy 374.74888 -273.149316)
			(xy 374.772478 -273.103011) (xy 374.803028 -273.060966) (xy 374.839778 -273.024217) (xy 374.881824 -272.993669)
			(xy 374.928131 -272.970074) (xy 374.977559 -272.954012) (xy 375.02889 -272.945879) (xy 375.054876 -272.945352)
			(xy 375.07291 -272.94586) (xy 375.087134 -272.946622) (xy 375.11228 -272.932906) (xy 375.255536 -272.686272)
			(xy 375.254774 -272.65757) (xy 375.247154 -272.645632) (xy 375.23461 -272.625471) (xy 375.214792 -272.582321)
			(xy 375.201333 -272.536785) (xy 375.194509 -272.489795) (xy 375.194068 -272.466054) (xy 375.194471 -272.442652)
			(xy 375.201068 -272.396316) (xy 375.214137 -272.351375) (xy 375.233416 -272.308727) (xy 375.24563 -272.288762)
			(xy 375.253504 -272.27657) (xy 375.254012 -272.248376) (xy 375.109486 -271.999202) (xy 375.084594 -271.98574)
			(xy 375.07037 -271.986502) (xy 375.054876 -271.986756) (xy 375.028889 -271.986245) (xy 374.977554 -271.978111)
			(xy 374.928124 -271.962049) (xy 374.881814 -271.938453) (xy 374.839765 -271.907903) (xy 374.803012 -271.871153)
			(xy 374.77246 -271.829106) (xy 374.74886 -271.782798) (xy 374.732794 -271.733369) (xy 374.724657 -271.682035)
			(xy 374.724168 -271.656048) (xy 374.724571 -271.632647) (xy 374.731169 -271.586311) (xy 374.744238 -271.54137)
			(xy 374.763519 -271.498723) (xy 374.77573 -271.478756) (xy 374.78335 -271.466564) (xy 374.784112 -271.43837)
			(xy 374.639332 -271.189196) (xy 374.614694 -271.175734) (xy 374.600216 -271.176496) (xy 374.584722 -271.17675)
			(xy 374.558728 -271.176268) (xy 374.507381 -271.168139) (xy 374.457937 -271.152077) (xy 374.411615 -271.128477)
			(xy 374.369555 -271.097921) (xy 374.332793 -271.061162) (xy 374.302235 -271.019104) (xy 374.278632 -270.972784)
			(xy 374.262566 -270.923341) (xy 374.254433 -270.871994) (xy 374.254433 -270.820006) (xy 374.262566 -270.768659)
			(xy 374.278632 -270.719216) (xy 374.302235 -270.672896) (xy 374.332793 -270.630838) (xy 374.369555 -270.594079)
			(xy 374.411615 -270.563523) (xy 374.457937 -270.539923) (xy 374.507381 -270.523861) (xy 374.558728 -270.515732)
			(xy 374.584722 -270.515334) (xy 374.602756 -270.515842) (xy 374.617234 -270.516604) (xy 374.64238 -270.503142)
			(xy 374.785636 -270.256254) (xy 374.784874 -270.227552) (xy 374.777 -270.215614) (xy 374.764473 -270.19545)
			(xy 374.744697 -270.152296) (xy 374.731296 -270.106758) (xy 374.724546 -270.059771) (xy 374.724168 -270.036036)
			(xy 374.724648 -270.010044) (xy 374.732775 -269.9587) (xy 374.748834 -269.909259) (xy 374.772429 -269.862939)
			(xy 374.80298 -269.820881) (xy 374.839735 -269.784119) (xy 374.881788 -269.753561) (xy 374.928103 -269.729957)
			(xy 374.977541 -269.713889) (xy 375.028884 -269.705753) (xy 375.054876 -269.705328) (xy 375.07291 -269.705836)
			(xy 375.087134 -269.706598) (xy 375.11228 -269.692882) (xy 375.255536 -269.446248) (xy 375.254774 -269.417546)
			(xy 375.247154 -269.405608) (xy 375.234611 -269.385446) (xy 375.214797 -269.342296) (xy 375.201341 -269.29676)
			(xy 375.19452 -269.249771) (xy 375.194068 -269.22603) (xy 375.194472 -269.202629) (xy 375.201072 -269.156294)
			(xy 375.214144 -269.111355) (xy 375.233426 -269.068709) (xy 375.24563 -269.048738) (xy 375.25325 -269.036546)
			(xy 375.254012 -269.008352) (xy 375.109486 -268.759178) (xy 375.084594 -268.745716) (xy 375.07037 -268.746478)
			(xy 375.054876 -268.746732) (xy 375.028889 -268.746221) (xy 374.977556 -268.738087) (xy 374.928127 -268.722024)
			(xy 374.88182 -268.698428) (xy 374.839773 -268.667878) (xy 374.803022 -268.631127) (xy 374.772472 -268.58908)
			(xy 374.748876 -268.542773) (xy 374.732813 -268.493344) (xy 374.724679 -268.442011) (xy 374.724168 -268.416024)
			(xy 374.724573 -268.392623) (xy 374.731173 -268.346289) (xy 374.744246 -268.30135) (xy 374.763529 -268.258705)
			(xy 374.77573 -268.238732) (xy 374.78335 -268.22654) (xy 374.783858 -268.198346) (xy 374.639332 -267.949172)
			(xy 374.61444 -267.93571) (xy 374.600216 -267.936472) (xy 374.584722 -267.936726) (xy 374.558731 -267.936245)
			(xy 374.507389 -267.928116) (xy 374.45795 -267.912056) (xy 374.411633 -267.88846) (xy 374.369577 -267.857908)
			(xy 374.332818 -267.821154) (xy 374.302261 -267.779102) (xy 374.278659 -267.732787) (xy 374.262593 -267.68335)
			(xy 374.254459 -267.632009) (xy 374.254014 -267.606018) (xy 374.254419 -267.582617) (xy 374.26102 -267.536283)
			(xy 374.274091 -267.491343) (xy 374.293372 -267.448697) (xy 374.305576 -267.428726) (xy 374.313196 -267.416534)
			(xy 374.313704 -267.38834) (xy 374.154954 -267.114782) (xy 374.131332 -267.101066) (xy 374.117616 -267.10132)
			(xy 374.114822 -267.10132) (xy 374.088364 -267.10075) (xy 374.036241 -267.091617) (xy 373.986473 -267.073638)
			(xy 373.940547 -267.047352) (xy 373.899838 -267.013543) (xy 373.865565 -266.973226) (xy 373.851678 -266.950698)
			(xy 373.844566 -266.939014) (xy 373.821452 -266.925552) (xy 373.49684 -266.925552) (xy 373.472964 -266.939776)
			(xy 373.466106 -266.952222) (xy 373.453661 -266.974472) (xy 373.422985 -267.01519) (xy 373.38642 -267.050713)
			(xy 373.344832 -267.080198) (xy 373.299209 -267.102945) (xy 373.250633 -267.118415) (xy 373.200258 -267.12624)
			(xy 373.174768 -267.12672) (xy 373.165624 -267.12672) (xy 373.1514 -267.126212) (xy 373.127524 -267.139674)
			(xy 372.979696 -267.394182) (xy 372.97995 -267.421868) (xy 372.987316 -267.433806) (xy 372.998772 -267.453345)
			(xy 373.016821 -267.494886) (xy 373.02904 -267.538499) (xy 373.035198 -267.583371) (xy 373.035576 -267.606018)
			(xy 373.035066 -267.632005) (xy 373.026936 -267.68334) (xy 373.010875 -267.73277) (xy 372.987279 -267.77908)
			(xy 372.956729 -267.821128) (xy 372.919978 -267.857879) (xy 372.87793 -267.888429) (xy 372.83162 -267.912025)
			(xy 372.78219 -267.928086) (xy 372.730855 -267.936216) (xy 372.678881 -267.936216) (xy 372.627546 -267.928086)
			(xy 372.578116 -267.912025) (xy 372.531806 -267.888429) (xy 372.489758 -267.857879) (xy 372.453007 -267.821128)
			(xy 372.422457 -267.77908) (xy 372.398861 -267.73277) (xy 372.3828 -267.68334) (xy 372.37467 -267.632005)
			(xy 372.37416 -267.606018) (xy 372.374414 -267.594334) (xy 372.374922 -267.58011) (xy 372.36146 -267.555726)
			(xy 371.511322 -267.067538) (xy 371.483636 -267.068046) (xy 371.471444 -267.075666) (xy 371.45154 -267.087761)
			(xy 371.409057 -267.106852) (xy 371.364316 -267.119793) (xy 371.318202 -267.126329) (xy 371.294914 -267.12672)
			(xy 371.268924 -267.126238) (xy 371.217583 -267.118109) (xy 371.168146 -267.102048) (xy 371.12183 -267.078451)
			(xy 371.079775 -267.047899) (xy 371.043018 -267.011145) (xy 371.012463 -266.969093) (xy 370.988862 -266.922779)
			(xy 370.972798 -266.873343) (xy 370.964664 -266.822002) (xy 370.964206 -266.796012) (xy 370.964612 -266.772611)
			(xy 370.971213 -266.726277) (xy 370.984284 -266.681338) (xy 371.003565 -266.638692) (xy 371.015768 -266.61872)
			(xy 371.023388 -266.606782) (xy 371.023896 -266.578334) (xy 370.87937 -266.32916) (xy 370.854478 -266.315698)
			(xy 370.840254 -266.31646) (xy 370.82476 -266.316714) (xy 370.80192 -266.316307) (xy 370.756679 -266.309981)
			(xy 370.712736 -266.297496) (xy 370.670928 -266.279089) (xy 370.651278 -266.267438) (xy 370.63934 -266.260326)
			(xy 370.6114 -266.259818) (xy 369.758722 -266.74953) (xy 369.745006 -266.773914) (xy 369.745514 -266.787884)
			(xy 369.745514 -266.796012) (xy 369.745004 -266.821999) (xy 369.736872 -266.873332) (xy 369.72081 -266.922761)
			(xy 369.697213 -266.96907) (xy 369.666663 -267.011117) (xy 369.629912 -267.047867) (xy 369.587865 -267.078416)
			(xy 369.541556 -267.102012) (xy 369.492126 -267.118073) (xy 369.440793 -267.126204) (xy 369.414806 -267.12672)
			(xy 369.405408 -267.126466) (xy 369.391438 -267.126212) (xy 369.367308 -267.139674) (xy 369.21948 -267.394182)
			(xy 369.219734 -267.421614) (xy 369.227354 -267.433806) (xy 369.238808 -267.453345) (xy 369.256856 -267.494886)
			(xy 369.269073 -267.5385) (xy 369.275231 -267.583372) (xy 369.275614 -267.606018) (xy 369.275104 -267.632005)
			(xy 369.266974 -267.68334) (xy 369.250913 -267.73277) (xy 369.227317 -267.77908) (xy 369.196767 -267.821128)
			(xy 369.160016 -267.857879) (xy 369.117968 -267.888429) (xy 369.071658 -267.912025) (xy 369.022228 -267.928086)
			(xy 368.970893 -267.936216) (xy 368.918919 -267.936216) (xy 368.867584 -267.928086) (xy 368.818154 -267.912025)
			(xy 368.771844 -267.888429) (xy 368.729796 -267.857879) (xy 368.693045 -267.821128) (xy 368.662495 -267.77908)
			(xy 368.638899 -267.73277) (xy 368.622838 -267.68334) (xy 368.614708 -267.632005) (xy 368.614198 -267.606018)
			(xy 368.614452 -267.594334) (xy 368.61496 -267.58011) (xy 368.601498 -267.555726) (xy 367.75136 -267.067284)
			(xy 367.72342 -267.068046) (xy 367.711228 -267.075666) (xy 367.691323 -267.08776) (xy 367.64884 -267.106849)
			(xy 367.604099 -267.119788) (xy 367.557985 -267.126322) (xy 367.534698 -267.12672) (xy 367.508711 -267.12621)
			(xy 367.457376 -267.11808) (xy 367.407945 -267.102019) (xy 367.361634 -267.078423) (xy 367.319586 -267.047873)
			(xy 367.282833 -267.011122) (xy 367.252282 -266.969074) (xy 367.228685 -266.922765) (xy 367.212623 -266.873334)
			(xy 367.20449 -266.821999) (xy 367.20399 -266.796012) (xy 367.204396 -266.772611) (xy 367.210996 -266.726277)
			(xy 367.224067 -266.681337) (xy 367.243348 -266.638691) (xy 367.255552 -266.61872) (xy 367.263172 -266.606528)
			(xy 367.263934 -266.578334) (xy 367.119154 -266.32916) (xy 367.094262 -266.315698) (xy 367.080038 -266.31646)
			(xy 367.064798 -266.316714) (xy 367.041957 -266.31631) (xy 366.996714 -266.309989) (xy 366.952769 -266.297508)
			(xy 366.910957 -266.279104) (xy 366.891316 -266.267438) (xy 366.879378 -266.260072) (xy 366.851438 -266.259818)
			(xy 365.99876 -266.74953) (xy 365.985044 -266.773914) (xy 365.985552 -266.787884) (xy 365.985552 -266.796012)
			(xy 365.985042 -266.822) (xy 365.97691 -266.873335) (xy 365.960848 -266.922767) (xy 365.937253 -266.969078)
			(xy 365.906703 -267.011128) (xy 365.869953 -267.047883) (xy 365.827906 -267.078436) (xy 365.781597 -267.102036)
			(xy 365.732167 -267.118102) (xy 365.680832 -267.126239) (xy 365.654844 -267.12672) (xy 365.645446 -267.126466)
			(xy 365.631476 -267.126212) (xy 365.607346 -267.139674) (xy 365.459518 -267.394436) (xy 365.459772 -267.421868)
			(xy 365.467138 -267.43406) (xy 365.478591 -267.453566) (xy 365.496641 -267.495041) (xy 365.508864 -267.538591)
			(xy 365.515032 -267.583402) (xy 365.515398 -267.606018) (xy 365.514888 -267.632005) (xy 365.506758 -267.68334)
			(xy 365.490697 -267.73277) (xy 365.467101 -267.77908) (xy 365.436551 -267.821128) (xy 365.3998 -267.857879)
			(xy 365.357752 -267.888429) (xy 365.311442 -267.912025) (xy 365.262012 -267.928086) (xy 365.210677 -267.936216)
			(xy 365.158703 -267.936216) (xy 365.107368 -267.928086) (xy 365.057938 -267.912025) (xy 365.011628 -267.888429)
			(xy 364.96958 -267.857879) (xy 364.932829 -267.821128) (xy 364.902279 -267.77908) (xy 364.878683 -267.73277)
			(xy 364.862622 -267.68334) (xy 364.854492 -267.632005) (xy 364.853982 -267.606018) (xy 364.854236 -267.594334)
			(xy 364.854744 -267.579856) (xy 364.841282 -267.555472) (xy 363.991398 -267.067284) (xy 363.963458 -267.068046)
			(xy 363.951266 -267.075666) (xy 363.931362 -267.087762) (xy 363.88888 -267.106856) (xy 363.844139 -267.1198)
			(xy 363.798024 -267.12634) (xy 363.774736 -267.12672) (xy 363.748745 -267.12624) (xy 363.697401 -267.118113)
			(xy 363.647961 -267.102054) (xy 363.601642 -267.078458) (xy 363.559584 -267.047907) (xy 363.522824 -267.011152)
			(xy 363.492267 -266.969099) (xy 363.468664 -266.922784) (xy 363.452598 -266.873346) (xy 363.444464 -266.822003)
			(xy 363.444028 -266.796012) (xy 363.444434 -266.772611) (xy 363.451035 -266.726277) (xy 363.464107 -266.681338)
			(xy 363.483389 -266.638693) (xy 363.49559 -266.61872) (xy 363.50321 -266.606528) (xy 363.503972 -266.578334)
			(xy 363.359192 -266.32916) (xy 363.3343 -266.315698) (xy 363.320076 -266.31646) (xy 363.304836 -266.316714)
			(xy 363.281994 -266.316312) (xy 363.236749 -266.309996) (xy 363.192801 -266.297519) (xy 363.150987 -266.279119)
			(xy 363.131354 -266.267438) (xy 363.119416 -266.260072) (xy 363.091476 -266.259818) (xy 362.238798 -266.74953)
			(xy 362.225082 -266.773914) (xy 362.22559 -266.787884) (xy 362.22559 -266.796012) (xy 362.225106 -266.822)
			(xy 362.216973 -266.873336) (xy 362.20091 -266.922768) (xy 362.177311 -266.969078) (xy 362.146758 -267.011127)
			(xy 362.110004 -267.047878) (xy 362.067953 -267.078427) (xy 362.02164 -267.102021) (xy 361.972207 -267.11808)
			(xy 361.92087 -267.126208) (xy 361.894882 -267.12672) (xy 361.869393 -267.126247) (xy 361.819021 -267.118415)
			(xy 361.77045 -267.102939) (xy 361.724831 -267.080187) (xy 361.683248 -267.050699) (xy 361.646688 -267.015174)
			(xy 361.616017 -266.974456) (xy 361.603544 -266.952222) (xy 361.596686 -266.939776) (xy 361.57281 -266.925552)
			(xy 359.125774 -266.925552) (xy 359.119169 -266.925768) (xy 359.106422 -266.929234) (xy 359.100628 -266.93241)
			(xy 358.014778 -267.556234) (xy 358.001062 -267.580618) (xy 358.00157 -267.594842) (xy 358.001824 -267.606018)
			(xy 358.001314 -267.632005) (xy 357.993184 -267.68334) (xy 357.977123 -267.73277) (xy 357.953527 -267.77908)
			(xy 357.922977 -267.821128) (xy 357.886226 -267.857879) (xy 357.844178 -267.888429) (xy 357.797868 -267.912025)
			(xy 357.748438 -267.928086) (xy 357.697103 -267.936216) (xy 357.645129 -267.936216) (xy 357.593794 -267.928086)
			(xy 357.544364 -267.912025) (xy 357.498054 -267.888429) (xy 357.456006 -267.857879) (xy 357.419255 -267.821128)
			(xy 357.388705 -267.77908) (xy 357.365109 -267.73277) (xy 357.349048 -267.68334) (xy 357.340918 -267.632005)
			(xy 357.340408 -267.606018) (xy 357.34079 -267.583258) (xy 357.347027 -267.538168) (xy 357.359374 -267.494355)
			(xy 357.377598 -267.452642) (xy 357.389176 -267.433044) (xy 357.396542 -267.421106) (xy 357.396796 -267.393166)
			(xy 357.24973 -267.139674) (xy 357.225346 -267.126212) (xy 357.211122 -267.126466) (xy 357.201216 -267.12672)
			(xy 357.175226 -267.126238) (xy 357.123884 -267.118109) (xy 357.074447 -267.102048) (xy 357.028131 -267.078452)
			(xy 356.986076 -267.0479) (xy 356.949318 -267.011145) (xy 356.918763 -266.969093) (xy 356.895162 -266.922779)
			(xy 356.879098 -266.873343) (xy 356.870964 -266.822002) (xy 356.870508 -266.796012) (xy 356.870508 -266.787376)
			(xy 356.871016 -266.773406) (xy 356.8573 -266.749022) (xy 356.004876 -266.25931) (xy 355.976936 -266.259818)
			(xy 355.964998 -266.267184) (xy 355.945311 -266.278918) (xy 355.90339 -266.297438) (xy 355.859312 -266.309991)
			(xy 355.813923 -266.316335) (xy 355.791008 -266.316714) (xy 355.776784 -266.31646) (xy 355.76256 -266.315698)
			(xy 355.737668 -266.329414) (xy 355.592634 -266.579096) (xy 355.593142 -266.607544) (xy 355.600762 -266.619482)
			(xy 355.612856 -266.639387) (xy 355.631943 -266.68187) (xy 355.644881 -266.726611) (xy 355.651414 -266.772725)
			(xy 355.651816 -266.796012) (xy 355.651306 -266.821999) (xy 355.643174 -266.873332) (xy 355.627112 -266.922762)
			(xy 355.603515 -266.96907) (xy 355.572965 -267.011117) (xy 355.536214 -267.047868) (xy 355.494167 -267.078417)
			(xy 355.447858 -267.102013) (xy 355.398428 -267.118074) (xy 355.347095 -267.126206) (xy 355.321108 -267.12672)
			(xy 355.297893 -267.126327) (xy 355.251919 -267.119826) (xy 355.207309 -267.106951) (xy 355.164942 -267.087956)
			(xy 355.145086 -267.07592) (xy 355.132894 -267.0683) (xy 355.104954 -267.067792) (xy 354.254816 -267.556234)
			(xy 354.2411 -267.580618) (xy 354.241608 -267.594842) (xy 354.241862 -267.606018) (xy 354.241352 -267.632005)
			(xy 354.233222 -267.68334) (xy 354.217161 -267.73277) (xy 354.193565 -267.77908) (xy 354.163015 -267.821128)
			(xy 354.126264 -267.857879) (xy 354.084216 -267.888429) (xy 354.037906 -267.912025) (xy 353.988476 -267.928086)
			(xy 353.937141 -267.936216) (xy 353.885167 -267.936216) (xy 353.833832 -267.928086) (xy 353.784402 -267.912025)
			(xy 353.738092 -267.888429) (xy 353.696044 -267.857879) (xy 353.659293 -267.821128) (xy 353.628743 -267.77908)
			(xy 353.605147 -267.73277) (xy 353.589086 -267.68334) (xy 353.580956 -267.632005) (xy 353.580446 -267.606018)
			(xy 353.580828 -267.583258) (xy 353.587066 -267.538168) (xy 353.599414 -267.494356) (xy 353.61764 -267.452644)
			(xy 353.629214 -267.433044) (xy 353.63658 -267.421106) (xy 353.636834 -267.393166) (xy 353.489768 -267.139674)
			(xy 353.465384 -267.126212) (xy 353.45116 -267.126466) (xy 353.441 -267.12672) (xy 353.415012 -267.12621)
			(xy 353.363677 -267.11808) (xy 353.314246 -267.102019) (xy 353.267936 -267.078423) (xy 353.225886 -267.047874)
			(xy 353.189134 -267.011123) (xy 353.158583 -266.969075) (xy 353.134985 -266.922765) (xy 353.118923 -266.873334)
			(xy 353.11079 -266.822) (xy 353.110292 -266.796012) (xy 353.110292 -266.787376) (xy 353.1108 -266.773406)
			(xy 353.097084 -266.749022) (xy 352.244914 -266.25931) (xy 352.216974 -266.259818) (xy 352.205036 -266.267184)
			(xy 352.185348 -266.278914) (xy 352.143426 -266.297426) (xy 352.099348 -266.309971) (xy 352.05396 -266.316307)
			(xy 352.031046 -266.316714) (xy 352.016822 -266.31646) (xy 352.002598 -266.315698) (xy 351.977706 -266.329414)
			(xy 351.832672 -266.579096) (xy 351.83318 -266.607544) (xy 351.8408 -266.619482) (xy 351.852896 -266.639386)
			(xy 351.871987 -266.681869) (xy 351.884927 -266.72661) (xy 351.891461 -266.772724) (xy 351.891854 -266.796012)
			(xy 351.891344 -266.822) (xy 351.883212 -266.873336) (xy 351.86715 -266.922768) (xy 351.843555 -266.969079)
			(xy 351.813005 -267.011129) (xy 351.776255 -267.047883) (xy 351.734208 -267.078437) (xy 351.687899 -267.102037)
			(xy 351.638469 -267.118104) (xy 351.587134 -267.126241) (xy 351.561146 -267.12672) (xy 351.537972 -267.126334)
			(xy 351.492076 -267.119871) (xy 351.447532 -267.107065) (xy 351.405211 -267.088167) (xy 351.385378 -267.076174)
			(xy 351.373186 -267.068554) (xy 351.3455 -267.068046) (xy 350.682052 -267.45057) (xy 350.667383 -267.458476)
			(xy 350.635208 -267.467111) (xy 350.618552 -267.467588) (xy 350.220026 -267.467588) (xy 350.203453 -267.467017)
			(xy 350.171445 -267.458399) (xy 350.142743 -267.441818) (xy 350.130618 -267.430504) (xy 349.816166 -267.115798)
			(xy 349.788988 -267.10894) (xy 349.775526 -267.113004) (xy 349.752434 -267.119425) (xy 349.705003 -267.126314)
			(xy 349.681038 -267.12672) (xy 349.655046 -267.12624) (xy 349.603703 -267.118113) (xy 349.554262 -267.102055)
			(xy 349.507943 -267.078459) (xy 349.465885 -267.047908) (xy 349.429125 -267.011153) (xy 349.398567 -266.9691)
			(xy 349.374965 -266.922784) (xy 349.358898 -266.873346) (xy 349.350764 -266.822003) (xy 349.35033 -266.796012)
			(xy 349.35033 -266.787376) (xy 349.350838 -266.773152) (xy 349.337122 -266.748768) (xy 348.484952 -266.25931)
			(xy 348.457012 -266.259818) (xy 348.445074 -266.267184) (xy 348.425387 -266.278917) (xy 348.383465 -266.297434)
			(xy 348.339387 -266.309983) (xy 348.293999 -266.316324) (xy 348.271084 -266.316714) (xy 348.257114 -266.31646)
			(xy 348.24289 -266.315698) (xy 348.217998 -266.329414) (xy 348.072964 -266.579604) (xy 348.073472 -266.607798)
			(xy 348.081092 -266.619736) (xy 348.093128 -266.639626) (xy 348.112117 -266.682061) (xy 348.124988 -266.726734)
			(xy 348.131486 -266.772767) (xy 348.131892 -266.796012) (xy 348.131408 -266.822) (xy 348.123275 -266.873336)
			(xy 348.107212 -266.922768) (xy 348.083613 -266.969079) (xy 348.05306 -267.011127) (xy 348.016306 -267.047879)
			(xy 347.974255 -267.078428) (xy 347.927942 -267.102022) (xy 347.878509 -267.118082) (xy 347.827172 -267.12621)
			(xy 347.801184 -267.12672) (xy 347.78696 -267.126466) (xy 347.772736 -267.125704) (xy 347.748098 -267.13942)
			(xy 347.588586 -267.414248) (xy 347.588586 -267.441426) (xy 347.595444 -267.453364) (xy 347.608303 -267.476728)
			(xy 347.626542 -267.526838) (xy 347.635801 -267.579355) (xy 347.636338 -267.606018) (xy 347.635866 -267.630009)
			(xy 347.628358 -267.6774) (xy 347.613529 -267.723034) (xy 347.591745 -267.765786) (xy 347.563542 -267.804605)
			(xy 347.529614 -267.838534) (xy 347.490797 -267.866739) (xy 347.448045 -267.888525) (xy 347.402412 -267.903355)
			(xy 347.355021 -267.910865) (xy 347.33103 -267.911326) (xy 347.304585 -267.910766) (xy 347.252486 -267.901662)
			(xy 347.202733 -267.883719) (xy 347.156814 -267.857475) (xy 347.116102 -267.823714) (xy 347.081814 -267.783445)
			(xy 347.067886 -267.760958) (xy 347.061028 -267.749274) (xy 347.03766 -267.735812) (xy 346.713048 -267.735812)
			(xy 346.689172 -267.75029) (xy 346.682568 -267.762736) (xy 346.670078 -267.78493) (xy 346.63934 -267.825533)
			(xy 346.602744 -267.860948) (xy 346.561154 -267.890338) (xy 346.515554 -267.913011) (xy 346.467018 -267.92843)
			(xy 346.416693 -267.936231) (xy 346.365767 -267.936231) (xy 346.315442 -267.92843) (xy 346.266906 -267.913011)
			(xy 346.221306 -267.890338) (xy 346.179716 -267.860948) (xy 346.14312 -267.825533) (xy 346.112382 -267.78493)
			(xy 346.099892 -267.762736) (xy 346.093288 -267.75029) (xy 346.069412 -267.735812) (xy 345.744546 -267.735812)
			(xy 345.721178 -267.749274) (xy 345.71432 -267.760958) (xy 345.700455 -267.783413) (xy 345.66627 -267.823613)
			(xy 345.625686 -267.857343) (xy 345.603068 -267.87094) (xy 345.593924 -267.876274) (xy 345.581224 -267.893038)
			(xy 345.559888 -267.98651) (xy 345.563698 -268.007084) (xy 345.569794 -268.015974) (xy 345.589319 -268.045513)
			(xy 345.62308 -268.107758) (xy 345.650496 -268.173048) (xy 345.671295 -268.240736) (xy 345.685272 -268.310155)
			(xy 345.692289 -268.380618) (xy 345.69273 -268.416024) (xy 345.692241 -268.453297) (xy 345.684447 -268.527435)
			(xy 345.668946 -268.600351) (xy 345.645908 -268.671249) (xy 345.615587 -268.73935) (xy 345.578313 -268.803908)
			(xy 345.534495 -268.864217) (xy 345.484614 -268.919615) (xy 345.429215 -268.969496) (xy 345.368906 -269.013314)
			(xy 345.304348 -269.050588) (xy 345.236247 -269.080909) (xy 345.16535 -269.103947) (xy 345.092433 -269.119447)
			(xy 345.018295 -269.127241) (xy 344.981022 -269.127732) (xy 344.948002 -269.12697) (xy 344.937588 -269.126462)
			(xy 344.918284 -269.133574) (xy 344.849958 -269.198598) (xy 344.84183 -269.217394) (xy 344.84183 -269.227808)
			(xy 344.841328 -269.251132) (xy 344.834563 -269.297291) (xy 344.821368 -269.342037) (xy 344.802005 -269.384481)
			(xy 344.78976 -269.404338) (xy 344.781886 -269.41653) (xy 344.781378 -269.444724) (xy 344.925396 -269.692882)
			(xy 344.950034 -269.706344) (xy 344.964512 -269.705836) (xy 344.981022 -269.705328) (xy 345.007009 -269.705813)
			(xy 345.058343 -269.713947) (xy 345.107772 -269.730012) (xy 345.15408 -269.753611) (xy 345.196125 -269.784164)
			(xy 345.232873 -269.820919) (xy 345.263419 -269.86297) (xy 345.287011 -269.909281) (xy 345.303067 -269.958714)
			(xy 345.311192 -270.010049) (xy 345.31173 -270.036036) (xy 345.311338 -270.059584) (xy 345.304699 -270.10621)
			(xy 345.291502 -270.151419) (xy 345.272017 -270.194295) (xy 345.25966 -270.214344) (xy 345.251786 -270.226536)
			(xy 345.251278 -270.25473) (xy 345.395296 -270.503142) (xy 345.419934 -270.516604) (xy 345.434412 -270.515842)
			(xy 345.451176 -270.515334) (xy 345.477163 -270.515815) (xy 345.528498 -270.523942) (xy 345.57793 -270.540001)
			(xy 345.62424 -270.563594) (xy 345.66629 -270.594142) (xy 345.703042 -270.630892) (xy 345.733593 -270.672939)
			(xy 345.75719 -270.719248) (xy 345.773252 -270.768678) (xy 345.781383 -270.820013) (xy 345.781383 -270.871987)
			(xy 345.773252 -270.923322) (xy 345.75719 -270.972752) (xy 345.733593 -271.019061) (xy 345.703042 -271.061108)
			(xy 345.66629 -271.097858) (xy 345.62424 -271.128406) (xy 345.57793 -271.151999) (xy 345.528498 -271.168058)
			(xy 345.477163 -271.176185) (xy 345.451176 -271.17675) (xy 345.436952 -271.176496) (xy 345.422728 -271.175734)
			(xy 345.397836 -271.18945) (xy 345.252802 -271.43964) (xy 345.25331 -271.467834) (xy 345.26093 -271.479772)
			(xy 345.272968 -271.499662) (xy 345.291964 -271.542096) (xy 345.304841 -271.586768) (xy 345.311348 -271.632802)
			(xy 345.31173 -271.656048) (xy 345.311217 -271.682033) (xy 345.303081 -271.733363) (xy 345.287016 -271.782789)
			(xy 345.263418 -271.829093) (xy 345.232867 -271.871137) (xy 345.196117 -271.907884) (xy 345.154071 -271.938431)
			(xy 345.107765 -271.962026) (xy 345.058338 -271.978087) (xy 345.007007 -271.986219) (xy 344.981022 -271.986756)
			(xy 344.967052 -271.986502) (xy 344.952828 -271.98574) (xy 344.92819 -271.999456) (xy 344.782902 -272.249646)
			(xy 344.78341 -272.27784) (xy 344.79103 -272.290032) (xy 344.803061 -272.30989) (xy 344.822045 -272.352259)
			(xy 344.834915 -272.396869) (xy 344.841417 -272.44284) (xy 344.84183 -272.466054) (xy 344.841437 -272.489602)
			(xy 344.834795 -272.536226) (xy 344.821597 -272.581434) (xy 344.802109 -272.624309) (xy 344.78976 -272.644362)
			(xy 344.781886 -272.656554) (xy 344.781378 -272.684748) (xy 344.925396 -272.932906) (xy 344.950034 -272.946368)
			(xy 344.964512 -272.94586) (xy 344.981022 -272.945352) (xy 345.007009 -272.945863) (xy 345.058343 -272.953996)
			(xy 345.107774 -272.970059) (xy 345.154083 -272.993655) (xy 345.196131 -273.024204) (xy 345.232884 -273.060955)
			(xy 345.263436 -273.103002) (xy 345.287034 -273.14931) (xy 345.3031 -273.198739) (xy 345.311235 -273.250073)
			(xy 345.31173 -273.27606) (xy 345.311337 -273.299608) (xy 345.304694 -273.346232) (xy 345.291495 -273.391439)
			(xy 345.272007 -273.434313) (xy 345.25966 -273.454368) (xy 345.251786 -273.46656) (xy 345.251278 -273.494754)
			(xy 345.395296 -273.743166) (xy 345.419934 -273.756628) (xy 345.434412 -273.755866) (xy 345.451176 -273.755358)
			(xy 345.477169 -273.755839) (xy 345.528516 -273.763969) (xy 345.577959 -273.78003) (xy 345.62428 -273.803629)
			(xy 345.666339 -273.834184) (xy 345.7031 -273.870943) (xy 345.733658 -273.913) (xy 345.757261 -273.959319)
			(xy 345.773326 -274.008761) (xy 345.781459 -274.060107) (xy 345.781459 -274.112093) (xy 345.773326 -274.163439)
			(xy 345.757261 -274.212881) (xy 345.733658 -274.259201) (xy 345.7031 -274.301257) (xy 345.666339 -274.338016)
			(xy 345.62428 -274.368571) (xy 345.577959 -274.39217) (xy 345.528516 -274.408231) (xy 345.477169 -274.416361)
			(xy 345.451176 -274.416774) (xy 345.436952 -274.41652) (xy 345.422728 -274.415758) (xy 345.397836 -274.429474)
			(xy 345.252802 -274.679664) (xy 345.25331 -274.707858) (xy 345.26093 -274.719796) (xy 345.272967 -274.739686)
			(xy 345.291959 -274.78212) (xy 345.304834 -274.826793) (xy 345.311337 -274.872827) (xy 345.31173 -274.896072)
			(xy 345.311249 -274.922063) (xy 345.303121 -274.973407) (xy 345.287062 -275.022846) (xy 345.263466 -275.069165)
			(xy 345.232915 -275.111222) (xy 345.19616 -275.147982) (xy 345.154108 -275.17854) (xy 345.107793 -275.202143)
			(xy 345.058355 -275.21821) (xy 345.007013 -275.226345) (xy 344.981022 -275.22678) (xy 344.967052 -275.226526)
			(xy 344.952828 -275.225764) (xy 344.92819 -275.23948) (xy 344.782902 -275.48967) (xy 344.78341 -275.517864)
			(xy 344.79103 -275.530056) (xy 344.803065 -275.549912) (xy 344.822059 -275.592281) (xy 344.834939 -275.63689)
			(xy 344.841452 -275.682862) (xy 344.84183 -275.706078) (xy 344.841435 -275.729625) (xy 344.83479 -275.776249)
			(xy 344.821589 -275.821455) (xy 344.8021 -275.864327) (xy 344.78976 -275.884386) (xy 344.781886 -275.896578)
			(xy 344.781378 -275.924772) (xy 344.925396 -276.17293) (xy 344.950034 -276.186392) (xy 344.964512 -276.185884)
			(xy 344.981022 -276.185376) (xy 345.007009 -276.185887) (xy 345.058341 -276.19402) (xy 345.10777 -276.210083)
			(xy 345.154078 -276.23368) (xy 345.196124 -276.26423) (xy 345.232874 -276.300981) (xy 345.263423 -276.343028)
			(xy 345.287019 -276.389336) (xy 345.303081 -276.438765) (xy 345.311213 -276.490097) (xy 345.31173 -276.516084)
			(xy 345.311335 -276.539631) (xy 345.304689 -276.586254) (xy 345.291487 -276.63146) (xy 345.271997 -276.674331)
			(xy 345.25966 -276.694392) (xy 345.251786 -276.706584) (xy 345.251278 -276.734778) (xy 345.395296 -276.98319)
			(xy 345.419934 -276.996652) (xy 345.434412 -276.99589) (xy 345.451176 -276.995382) (xy 345.477167 -276.995863)
			(xy 345.52851 -277.003992) (xy 345.57795 -277.020052) (xy 345.624267 -277.04365) (xy 345.666324 -277.074202)
			(xy 345.703082 -277.110958) (xy 345.733638 -277.153012) (xy 345.757238 -277.199328) (xy 345.773303 -277.248766)
			(xy 345.781435 -277.300109) (xy 345.781435 -277.352091) (xy 345.773303 -277.403434) (xy 345.757238 -277.452872)
			(xy 345.733638 -277.499188) (xy 345.703082 -277.541242) (xy 345.666324 -277.577998) (xy 345.624267 -277.60855)
			(xy 345.57795 -277.632148) (xy 345.52851 -277.648208) (xy 345.477167 -277.656337) (xy 345.451176 -277.656798)
			(xy 345.436952 -277.656544) (xy 345.422728 -277.655782) (xy 345.397836 -277.669498) (xy 345.252802 -277.919688)
			(xy 345.25331 -277.947882) (xy 345.26093 -277.95982) (xy 345.272965 -277.97971) (xy 345.291955 -278.022145)
			(xy 345.304826 -278.066818) (xy 345.311325 -278.112851) (xy 345.31173 -278.136096) (xy 345.311221 -278.162084)
			(xy 345.303091 -278.21342) (xy 345.287031 -278.262853) (xy 345.263435 -278.309164) (xy 345.232886 -278.351215)
			(xy 345.196135 -278.387969) (xy 345.154087 -278.418522) (xy 345.107777 -278.442121) (xy 345.058346 -278.458185)
			(xy 345.00701 -278.466319) (xy 344.981022 -278.466804) (xy 344.967052 -278.46655) (xy 344.952828 -278.465788)
			(xy 344.92819 -278.479504) (xy 344.782902 -278.729694) (xy 344.78341 -278.757888) (xy 344.79103 -278.77008)
			(xy 344.803064 -278.789937) (xy 344.822055 -278.832306) (xy 344.834932 -278.876915) (xy 344.841441 -278.922887)
			(xy 344.84183 -278.946102) (xy 344.841576 -278.961342) (xy 344.840814 -278.97582) (xy 344.854276 -279.000458)
			(xy 345.701366 -279.486868) (xy 345.72956 -279.486106) (xy 345.741498 -279.478232) (xy 345.761661 -279.465704)
			(xy 345.804815 -279.445929) (xy 345.850354 -279.432528) (xy 345.897341 -279.425778) (xy 345.921076 -279.4254)
			(xy 345.947066 -279.425881) (xy 345.998406 -279.434009) (xy 346.047843 -279.450069) (xy 346.094158 -279.473665)
			(xy 346.136212 -279.504216) (xy 346.172968 -279.54097) (xy 346.203522 -279.583021) (xy 346.227122 -279.629335)
			(xy 346.243185 -279.678771) (xy 346.251317 -279.73011) (xy 346.251317 -279.78209) (xy 346.243185 -279.833429)
			(xy 346.227122 -279.882865) (xy 346.203522 -279.929179) (xy 346.172968 -279.97123) (xy 346.136212 -280.007984)
			(xy 346.094158 -280.038535) (xy 346.047843 -280.062131) (xy 345.998406 -280.078191) (xy 345.947066 -280.086319)
			(xy 345.921076 -280.086816) (xy 345.906852 -280.086562) (xy 345.892628 -280.0858) (xy 345.86799 -280.099516)
			(xy 345.722956 -280.349452) (xy 345.723464 -280.377646) (xy 345.73083 -280.389838) (xy 345.742912 -280.409714)
			(xy 345.761989 -280.452134) (xy 345.774934 -280.49681) (xy 345.781491 -280.542858) (xy 345.781884 -280.566114)
			(xy 345.7814 -280.592102) (xy 345.773267 -280.643437) (xy 345.757203 -280.692868) (xy 345.733604 -280.739178)
			(xy 345.703051 -280.781226) (xy 345.666297 -280.817976) (xy 345.624246 -280.848524) (xy 345.577933 -280.872117)
			(xy 345.5285 -280.888176) (xy 345.477164 -280.896303) (xy 345.451176 -280.896822) (xy 345.436952 -280.896568)
			(xy 345.422728 -280.895806) (xy 345.39809 -280.909522) (xy 345.252802 -281.159712) (xy 345.25331 -281.187906)
			(xy 345.26093 -281.200098) (xy 345.272963 -281.219955) (xy 345.291951 -281.262324) (xy 345.304826 -281.306934)
			(xy 345.311333 -281.352905) (xy 345.31173 -281.3761) (xy 345.615289 -281.3761) (xy 345.619459 -281.325768)
			(xy 345.631857 -281.276808) (xy 345.652144 -281.230557) (xy 345.679766 -281.188275) (xy 345.713971 -281.151116)
			(xy 345.753825 -281.120094) (xy 345.798241 -281.096054) (xy 345.846008 -281.079652) (xy 345.895824 -281.071335)
			(xy 345.921076 -281.070812) (xy 346.86113 -281.070812) (xy 346.886385 -281.071296) (xy 346.936207 -281.079614)
			(xy 346.983979 -281.096019) (xy 347.028401 -281.120062) (xy 347.068259 -281.151089) (xy 347.102467 -281.188252)
			(xy 347.130092 -281.230539) (xy 347.150381 -281.276796) (xy 347.16278 -281.325762) (xy 347.166951 -281.3761)
			(xy 348.43536 -281.3761) (xy 348.439532 -281.325756) (xy 348.451934 -281.276786) (xy 348.472227 -281.230526)
			(xy 348.499859 -281.188237) (xy 348.534075 -281.151073) (xy 348.573942 -281.120048) (xy 348.618371 -281.096009)
			(xy 348.666152 -281.079611) (xy 348.71598 -281.071302) (xy 348.741238 -281.070812) (xy 349.681292 -281.070812)
			(xy 349.706552 -281.071264) (xy 349.756383 -281.079578) (xy 349.804165 -281.095981) (xy 349.848596 -281.120025)
			(xy 349.888464 -281.151054) (xy 349.92268 -281.188222) (xy 349.950312 -281.230515) (xy 349.970606 -281.276779)
			(xy 349.983008 -281.325753) (xy 349.98718 -281.3761) (xy 370.049089 -281.3761) (xy 370.053259 -281.325769)
			(xy 370.065656 -281.276811) (xy 370.085941 -281.230561) (xy 370.113562 -281.18828) (xy 370.147764 -281.151122)
			(xy 370.187616 -281.120099) (xy 370.23203 -281.096058) (xy 370.279795 -281.079655) (xy 370.329608 -281.071337)
			(xy 370.35486 -281.070812) (xy 371.294914 -281.070812) (xy 371.32017 -281.071295) (xy 371.369993 -281.079611)
			(xy 371.417768 -281.096014) (xy 371.462192 -281.120057) (xy 371.502053 -281.151083) (xy 371.536263 -281.188247)
			(xy 371.56389 -281.230535) (xy 371.58418 -281.276793) (xy 371.59658 -281.32576) (xy 371.600751 -281.3761)
			(xy 372.868989 -281.3761) (xy 372.873159 -281.325768) (xy 372.885556 -281.27681) (xy 372.905842 -281.230559)
			(xy 372.933464 -281.188278) (xy 372.967667 -281.151119) (xy 373.00752 -281.120096) (xy 373.051935 -281.096056)
			(xy 373.099702 -281.079653) (xy 373.149516 -281.071336) (xy 373.174768 -281.070812) (xy 374.114822 -281.070812)
			(xy 374.140078 -281.071295) (xy 374.1899 -281.079613) (xy 374.237674 -281.096016) (xy 374.282096 -281.120059)
			(xy 374.321956 -281.151086) (xy 374.356165 -281.18825) (xy 374.383791 -281.230537) (xy 374.404081 -281.276795)
			(xy 374.41648 -281.325761) (xy 374.420651 -281.3761) (xy 374.41648 -281.426439) (xy 374.404081 -281.475405)
			(xy 374.383791 -281.521663) (xy 374.356165 -281.56395) (xy 374.321956 -281.601114) (xy 374.282096 -281.632141)
			(xy 374.237674 -281.656184) (xy 374.1899 -281.672587) (xy 374.140078 -281.680905) (xy 374.114822 -281.681428)
			(xy 373.174768 -281.681428) (xy 373.149516 -281.680864) (xy 373.099702 -281.672547) (xy 373.051935 -281.656144)
			(xy 373.00752 -281.632104) (xy 372.967667 -281.601081) (xy 372.933464 -281.563922) (xy 372.905842 -281.521641)
			(xy 372.885556 -281.47539) (xy 372.873159 -281.426432) (xy 372.868989 -281.3761) (xy 371.600751 -281.3761)
			(xy 371.59658 -281.42644) (xy 371.58418 -281.475407) (xy 371.56389 -281.521665) (xy 371.536263 -281.563953)
			(xy 371.502053 -281.601117) (xy 371.462192 -281.632143) (xy 371.417768 -281.656186) (xy 371.369993 -281.672589)
			(xy 371.32017 -281.680905) (xy 371.294914 -281.681428) (xy 370.35486 -281.681428) (xy 370.329609 -281.680863)
			(xy 370.279795 -281.672545) (xy 370.23203 -281.656142) (xy 370.187616 -281.632101) (xy 370.147764 -281.601078)
			(xy 370.113562 -281.56392) (xy 370.085941 -281.521639) (xy 370.065656 -281.475389) (xy 370.053259 -281.426431)
			(xy 370.049089 -281.3761) (xy 349.98718 -281.3761) (xy 349.983008 -281.426447) (xy 349.970606 -281.475421)
			(xy 349.950312 -281.521685) (xy 349.92268 -281.563978) (xy 349.888464 -281.601146) (xy 349.848596 -281.632175)
			(xy 349.804165 -281.656219) (xy 349.756383 -281.672622) (xy 349.706552 -281.680936) (xy 349.681292 -281.681428)
			(xy 348.741238 -281.681428) (xy 348.71598 -281.680898) (xy 348.666152 -281.672589) (xy 348.618371 -281.656191)
			(xy 348.573941 -281.632152) (xy 348.534075 -281.601127) (xy 348.499859 -281.563963) (xy 348.472227 -281.521674)
			(xy 348.451934 -281.475414) (xy 348.439532 -281.426444) (xy 348.43536 -281.3761) (xy 347.166951 -281.3761)
			(xy 347.16278 -281.426438) (xy 347.150381 -281.475404) (xy 347.130092 -281.521661) (xy 347.102467 -281.563948)
			(xy 347.068259 -281.601111) (xy 347.028401 -281.632138) (xy 346.983979 -281.656181) (xy 346.936207 -281.672586)
			(xy 346.886385 -281.680904) (xy 346.86113 -281.681428) (xy 345.921076 -281.681428) (xy 345.895824 -281.680865)
			(xy 345.846008 -281.672548) (xy 345.798241 -281.656146) (xy 345.753825 -281.632106) (xy 345.713971 -281.601084)
			(xy 345.679766 -281.563925) (xy 345.652144 -281.521643) (xy 345.631857 -281.475392) (xy 345.619459 -281.426432)
			(xy 345.615289 -281.3761) (xy 345.31173 -281.3761) (xy 345.31173 -281.37612) (xy 345.311333 -281.399667)
			(xy 345.304682 -281.446287) (xy 345.291476 -281.49149) (xy 345.271982 -281.534359) (xy 345.25966 -281.554428)
			(xy 345.251786 -281.56662) (xy 345.251278 -281.594814) (xy 345.395296 -281.843226) (xy 345.419934 -281.856688)
			(xy 345.434412 -281.855926) (xy 345.451176 -281.855418) (xy 345.477164 -281.855899) (xy 345.528502 -281.864027)
			(xy 345.577936 -281.880086) (xy 345.624249 -281.90368) (xy 345.6663 -281.93423) (xy 345.703055 -281.970982)
			(xy 345.733607 -282.013031) (xy 345.757205 -282.059342) (xy 345.773268 -282.108775) (xy 345.781399 -282.160112)
			(xy 345.781399 -282.1861) (xy 356.42504 -282.1861) (xy 356.429214 -282.135728) (xy 356.441621 -282.08673)
			(xy 356.461923 -282.040442) (xy 356.489566 -281.998127) (xy 356.523797 -281.960938) (xy 356.563681 -281.92989)
			(xy 356.608132 -281.90583) (xy 356.655936 -281.889414) (xy 356.70579 -281.881089) (xy 356.731062 -281.880564)
			(xy 357.671116 -281.880564) (xy 357.696394 -281.881035) (xy 357.746259 -281.889359) (xy 357.794074 -281.905776)
			(xy 357.838536 -281.929839) (xy 357.87843 -281.960892) (xy 357.912669 -281.998088) (xy 357.940319 -282.040411)
			(xy 357.960627 -282.086709) (xy 357.973037 -282.135717) (xy 357.977212 -282.1861) (xy 362.05874 -282.1861)
			(xy 362.062914 -282.135726) (xy 362.075322 -282.086726) (xy 362.095626 -282.040437) (xy 362.123271 -281.99812)
			(xy 362.157505 -281.960931) (xy 362.197392 -281.929883) (xy 362.241845 -281.905824) (xy 362.289652 -281.88941)
			(xy 362.339509 -281.881087) (xy 362.364782 -281.880564) (xy 363.304836 -281.880564) (xy 363.330113 -281.881037)
			(xy 363.379975 -281.889363) (xy 363.427788 -281.905782) (xy 363.472246 -281.929846) (xy 363.512138 -281.960899)
			(xy 363.546374 -281.998094) (xy 363.574022 -282.040417) (xy 363.594328 -282.086713) (xy 363.606737 -282.135719)
			(xy 363.610912 -282.1861) (xy 363.606737 -282.236481) (xy 363.594328 -282.285487) (xy 363.574022 -282.331783)
			(xy 363.546374 -282.374106) (xy 363.512138 -282.411301) (xy 363.472246 -282.442354) (xy 363.427788 -282.466418)
			(xy 363.379975 -282.482837) (xy 363.330113 -282.491163) (xy 363.304836 -282.491688) (xy 362.364782 -282.491688)
			(xy 362.339509 -282.491113) (xy 362.289652 -282.48279) (xy 362.241845 -282.466376) (xy 362.197392 -282.442317)
			(xy 362.157505 -282.411269) (xy 362.123271 -282.37408) (xy 362.095626 -282.331763) (xy 362.075322 -282.285474)
			(xy 362.062914 -282.236474) (xy 362.05874 -282.1861) (xy 357.977212 -282.1861) (xy 357.973037 -282.236483)
			(xy 357.960627 -282.285491) (xy 357.940319 -282.331789) (xy 357.912669 -282.374112) (xy 357.87843 -282.411308)
			(xy 357.838536 -282.442361) (xy 357.794074 -282.466424) (xy 357.746259 -282.482841) (xy 357.696394 -282.491165)
			(xy 357.671116 -282.491688) (xy 356.731062 -282.491688) (xy 356.70579 -282.491111) (xy 356.655936 -282.482786)
			(xy 356.608132 -282.46637) (xy 356.563681 -282.44231) (xy 356.523797 -282.411262) (xy 356.489566 -282.374073)
			(xy 356.461923 -282.331758) (xy 356.441621 -282.28547) (xy 356.429214 -282.236472) (xy 356.42504 -282.1861)
			(xy 345.781399 -282.1861) (xy 345.781399 -282.212088) (xy 345.773268 -282.263425) (xy 345.757205 -282.312858)
			(xy 345.733607 -282.359169) (xy 345.703055 -282.401218) (xy 345.6663 -282.43797) (xy 345.624249 -282.46852)
			(xy 345.577936 -282.492114) (xy 345.528502 -282.508173) (xy 345.477164 -282.516301) (xy 345.451176 -282.516834)
			(xy 345.436952 -282.51658) (xy 345.422728 -282.515818) (xy 345.397836 -282.529534) (xy 345.252802 -282.779724)
			(xy 345.25331 -282.807918) (xy 345.26093 -282.819856) (xy 345.272969 -282.839745) (xy 345.291967 -282.882179)
			(xy 345.304847 -282.926852) (xy 345.311355 -282.972886) (xy 345.311729 -282.9961) (xy 345.615301 -282.9961)
			(xy 345.619471 -282.94577) (xy 345.631868 -282.896812) (xy 345.652154 -282.850562) (xy 345.679775 -282.808282)
			(xy 345.713979 -282.771125) (xy 345.753831 -282.740104) (xy 345.798246 -282.716065) (xy 345.846011 -282.699663)
			(xy 345.895825 -282.691347) (xy 345.921076 -282.690824) (xy 346.86113 -282.690824) (xy 346.886386 -282.691284)
			(xy 346.936209 -282.699603) (xy 346.983984 -282.716008) (xy 347.028407 -282.740052) (xy 347.068267 -282.77108)
			(xy 347.102477 -282.808245) (xy 347.130103 -282.850534) (xy 347.150393 -282.896792) (xy 347.162792 -282.94576)
			(xy 347.166963 -282.9961) (xy 348.435372 -282.9961) (xy 348.439544 -282.945758) (xy 348.451945 -282.89679)
			(xy 348.472238 -282.850531) (xy 348.499869 -282.808244) (xy 348.534083 -282.771081) (xy 348.573948 -282.740058)
			(xy 348.618376 -282.71602) (xy 348.666155 -282.699622) (xy 348.715981 -282.691314) (xy 348.741238 -282.690824)
			(xy 349.681292 -282.690824) (xy 349.706553 -282.691252) (xy 349.756386 -282.699567) (xy 349.80417 -282.71597)
			(xy 349.848603 -282.740015) (xy 349.888472 -282.771045) (xy 349.92269 -282.808215) (xy 349.950323 -282.850509)
			(xy 349.970617 -282.896775) (xy 349.98302 -282.945751) (xy 349.987192 -282.9961) (xy 351.255272 -282.9961)
			(xy 351.259444 -282.945758) (xy 351.271846 -282.896789) (xy 351.292139 -282.850529) (xy 351.319771 -282.808241)
			(xy 351.353986 -282.771079) (xy 351.393852 -282.740055) (xy 351.438281 -282.716017) (xy 351.486061 -282.699621)
			(xy 351.535888 -282.691313) (xy 351.561146 -282.690824) (xy 352.5012 -282.690824) (xy 352.526458 -282.691282)
			(xy 352.576285 -282.699596) (xy 352.624064 -282.715999) (xy 352.668491 -282.740042) (xy 352.708355 -282.771069)
			(xy 352.742569 -282.808235) (xy 352.770198 -282.850525) (xy 352.79049 -282.896786) (xy 352.802891 -282.945757)
			(xy 352.807063 -282.9961) (xy 354.075301 -282.9961) (xy 354.079471 -282.945772) (xy 354.091867 -282.896816)
			(xy 354.112151 -282.850569) (xy 354.13977 -282.80829) (xy 354.17397 -282.771133) (xy 354.213819 -282.740111)
			(xy 354.258231 -282.716071) (xy 354.305993 -282.699668) (xy 354.355804 -282.691349) (xy 354.381054 -282.690824)
			(xy 355.321108 -282.690824) (xy 355.346366 -282.691282) (xy 355.396191 -282.699598) (xy 355.443969 -282.716001)
			(xy 355.488395 -282.740045) (xy 355.528258 -282.771072) (xy 355.562471 -282.808238) (xy 355.5901 -282.850528)
			(xy 355.610391 -282.896788) (xy 355.622792 -282.945757) (xy 355.626963 -282.9961) (xy 364.409001 -282.9961)
			(xy 364.413172 -282.945768) (xy 364.425569 -282.896809) (xy 364.445856 -282.850559) (xy 364.473479 -282.808278)
			(xy 364.507684 -282.77112) (xy 364.547539 -282.740099) (xy 364.591955 -282.71606) (xy 364.639723 -282.69966)
			(xy 364.689538 -282.691346) (xy 364.71479 -282.690824) (xy 365.654844 -282.690824) (xy 365.6801 -282.691285)
			(xy 365.729921 -282.699605) (xy 365.777694 -282.716012) (xy 365.822115 -282.740057) (xy 365.861972 -282.771085)
			(xy 365.89618 -282.80825) (xy 365.923805 -282.850538) (xy 365.944094 -282.896795) (xy 365.956492 -282.945761)
			(xy 365.960663 -282.9961) (xy 367.228901 -282.9961) (xy 367.233072 -282.945767) (xy 367.24547 -282.896808)
			(xy 367.265758 -282.850556) (xy 367.293381 -282.808275) (xy 367.327587 -282.771117) (xy 367.367443 -282.740096)
			(xy 367.411861 -282.716058) (xy 367.459629 -282.699659) (xy 367.509445 -282.691346) (xy 367.534698 -282.690824)
			(xy 368.474752 -282.690824) (xy 368.500015 -282.691249) (xy 368.549853 -282.699558) (xy 368.597643 -282.715958)
			(xy 368.642082 -282.740001) (xy 368.681956 -282.771031) (xy 368.716179 -282.808201) (xy 368.743817 -282.850498)
			(xy 368.764115 -282.896767) (xy 368.776519 -282.945747) (xy 368.780692 -282.9961) (xy 370.049101 -282.9961)
			(xy 370.053271 -282.945771) (xy 370.065667 -282.896815) (xy 370.085952 -282.850567) (xy 370.113571 -282.808288)
			(xy 370.147772 -282.771131) (xy 370.187623 -282.740109) (xy 370.232035 -282.716069) (xy 370.279798 -282.699667)
			(xy 370.329609 -282.691349) (xy 370.35486 -282.690824) (xy 371.294914 -282.690824) (xy 371.320171 -282.691283)
			(xy 371.369996 -282.699599) (xy 371.417773 -282.716003) (xy 371.462199 -282.740047) (xy 371.502061 -282.771074)
			(xy 371.536273 -282.80824) (xy 371.563901 -282.850529) (xy 371.584191 -282.896789) (xy 371.596592 -282.945758)
			(xy 371.600763 -282.9961) (xy 372.869001 -282.9961) (xy 372.873171 -282.94577) (xy 372.885568 -282.896814)
			(xy 372.905853 -282.850565) (xy 372.933473 -282.808285) (xy 372.967676 -282.771128) (xy 373.007527 -282.740106)
			(xy 373.05194 -282.716067) (xy 373.099705 -282.699665) (xy 373.149517 -282.691348) (xy 373.174768 -282.690824)
			(xy 374.114822 -282.690824) (xy 374.140079 -282.691283) (xy 374.189903 -282.699601) (xy 374.237679 -282.716005)
			(xy 374.282103 -282.740049) (xy 374.321964 -282.771077) (xy 374.356175 -282.808242) (xy 374.383802 -282.850531)
			(xy 374.404092 -282.896791) (xy 374.416492 -282.945759) (xy 374.420663 -282.9961) (xy 374.416492 -283.046441)
			(xy 374.404092 -283.095409) (xy 374.383802 -283.141669) (xy 374.356175 -283.183958) (xy 374.321964 -283.221123)
			(xy 374.282103 -283.252151) (xy 374.237679 -283.276195) (xy 374.189903 -283.292599) (xy 374.140079 -283.300917)
			(xy 374.114822 -283.30144) (xy 373.174768 -283.30144) (xy 373.149517 -283.300852) (xy 373.099705 -283.292535)
			(xy 373.05194 -283.276133) (xy 373.007527 -283.252094) (xy 372.967676 -283.221072) (xy 372.933473 -283.183915)
			(xy 372.905853 -283.141635) (xy 372.885568 -283.095386) (xy 372.873171 -283.04643) (xy 372.869001 -282.9961)
			(xy 371.600763 -282.9961) (xy 371.596592 -283.046442) (xy 371.584191 -283.095411) (xy 371.563901 -283.141671)
			(xy 371.536273 -283.18396) (xy 371.502061 -283.221126) (xy 371.462199 -283.252153) (xy 371.417773 -283.276197)
			(xy 371.369996 -283.292601) (xy 371.320171 -283.300917) (xy 371.294914 -283.30144) (xy 370.35486 -283.30144)
			(xy 370.329609 -283.300851) (xy 370.279798 -283.292533) (xy 370.232035 -283.276131) (xy 370.187623 -283.252091)
			(xy 370.147772 -283.221069) (xy 370.113571 -283.183912) (xy 370.085952 -283.141633) (xy 370.065667 -283.095385)
			(xy 370.053271 -283.046429) (xy 370.049101 -282.9961) (xy 368.780692 -282.9961) (xy 368.776519 -283.046453)
			(xy 368.764115 -283.095433) (xy 368.743817 -283.141702) (xy 368.716179 -283.183999) (xy 368.681956 -283.221169)
			(xy 368.642082 -283.252199) (xy 368.597643 -283.276242) (xy 368.549853 -283.292642) (xy 368.500015 -283.300951)
			(xy 368.474752 -283.30144) (xy 367.534698 -283.30144) (xy 367.509445 -283.300854) (xy 367.459629 -283.292541)
			(xy 367.411861 -283.276142) (xy 367.367443 -283.252104) (xy 367.327587 -283.221083) (xy 367.293381 -283.183925)
			(xy 367.265758 -283.141644) (xy 367.24547 -283.095392) (xy 367.233072 -283.046433) (xy 367.228901 -282.9961)
			(xy 365.960663 -282.9961) (xy 365.956492 -283.046439) (xy 365.944094 -283.095405) (xy 365.923805 -283.141662)
			(xy 365.89618 -283.18395) (xy 365.861972 -283.221115) (xy 365.822115 -283.252143) (xy 365.777694 -283.276188)
			(xy 365.729921 -283.292595) (xy 365.6801 -283.300915) (xy 365.654844 -283.30144) (xy 364.71479 -283.30144)
			(xy 364.689538 -283.300854) (xy 364.639723 -283.29254) (xy 364.591955 -283.27614) (xy 364.547539 -283.252101)
			(xy 364.507684 -283.22108) (xy 364.473479 -283.183922) (xy 364.445856 -283.141641) (xy 364.425569 -283.095391)
			(xy 364.413172 -283.046432) (xy 364.409001 -282.9961) (xy 355.626963 -282.9961) (xy 355.622792 -283.046443)
			(xy 355.610391 -283.095412) (xy 355.5901 -283.141672) (xy 355.562471 -283.183962) (xy 355.528258 -283.221128)
			(xy 355.488395 -283.252155) (xy 355.443969 -283.276199) (xy 355.396191 -283.292602) (xy 355.346366 -283.300918)
			(xy 355.321108 -283.30144) (xy 354.381054 -283.30144) (xy 354.355804 -283.300851) (xy 354.305993 -283.292532)
			(xy 354.258231 -283.276129) (xy 354.213819 -283.252089) (xy 354.17397 -283.221067) (xy 354.13977 -283.18391)
			(xy 354.112151 -283.141631) (xy 354.091867 -283.095384) (xy 354.079471 -283.046428) (xy 354.075301 -282.9961)
			(xy 352.807063 -282.9961) (xy 352.802891 -283.046443) (xy 352.79049 -283.095414) (xy 352.770198 -283.141675)
			(xy 352.742569 -283.183965) (xy 352.708355 -283.221131) (xy 352.668491 -283.252158) (xy 352.624064 -283.276201)
			(xy 352.576285 -283.292604) (xy 352.526458 -283.300918) (xy 352.5012 -283.30144) (xy 351.561146 -283.30144)
			(xy 351.535888 -283.300887) (xy 351.486061 -283.292579) (xy 351.438281 -283.276183) (xy 351.393852 -283.252145)
			(xy 351.353986 -283.221121) (xy 351.319771 -283.183959) (xy 351.292139 -283.141671) (xy 351.271846 -283.095411)
			(xy 351.259444 -283.046442) (xy 351.255272 -282.9961) (xy 349.987192 -282.9961) (xy 349.98302 -283.046449)
			(xy 349.970617 -283.095425) (xy 349.950323 -283.141691) (xy 349.92269 -283.183985) (xy 349.888472 -283.221155)
			(xy 349.848603 -283.252185) (xy 349.80417 -283.27623) (xy 349.756386 -283.292633) (xy 349.706553 -283.300948)
			(xy 349.681292 -283.30144) (xy 348.741238 -283.30144) (xy 348.715981 -283.300886) (xy 348.666155 -283.292578)
			(xy 348.618376 -283.27618) (xy 348.573948 -283.252142) (xy 348.534083 -283.221119) (xy 348.499869 -283.183956)
			(xy 348.472238 -283.141669) (xy 348.451945 -283.09541) (xy 348.439544 -283.046442) (xy 348.435372 -282.9961)
			(xy 347.166963 -282.9961) (xy 347.162792 -283.04644) (xy 347.150393 -283.095408) (xy 347.130103 -283.141666)
			(xy 347.102477 -283.183955) (xy 347.068267 -283.22112) (xy 347.028407 -283.252148) (xy 346.983984 -283.276192)
			(xy 346.936209 -283.292597) (xy 346.886386 -283.300916) (xy 346.86113 -283.30144) (xy 345.921076 -283.30144)
			(xy 345.895825 -283.300853) (xy 345.846011 -283.292537) (xy 345.798246 -283.276135) (xy 345.753831 -283.252096)
			(xy 345.713979 -283.221075) (xy 345.679775 -283.183918) (xy 345.652154 -283.141638) (xy 345.631868 -283.095388)
			(xy 345.619471 -283.04643) (xy 345.615301 -282.9961) (xy 345.311729 -282.9961) (xy 345.31173 -282.996132)
			(xy 345.311218 -283.022118) (xy 345.303084 -283.07345) (xy 345.28702 -283.122878) (xy 345.263423 -283.169184)
			(xy 345.232873 -283.21123) (xy 345.196122 -283.24798) (xy 345.154076 -283.278528) (xy 345.107768 -283.302124)
			(xy 345.05834 -283.318186) (xy 345.007008 -283.326319) (xy 344.981022 -283.32684) (xy 344.967052 -283.326586)
			(xy 344.952828 -283.325824) (xy 344.92819 -283.33954) (xy 344.782902 -283.58973) (xy 344.78341 -283.617924)
			(xy 344.79103 -283.630116) (xy 344.803062 -283.649973) (xy 344.822048 -283.692343) (xy 344.83492 -283.736952)
			(xy 344.841424 -283.782923) (xy 344.841829 -283.8061) (xy 356.425052 -283.8061) (xy 356.429226 -283.75573)
			(xy 356.441632 -283.706734) (xy 356.461934 -283.660448) (xy 356.489576 -283.618134) (xy 356.523805 -283.580947)
			(xy 356.563688 -283.5499) (xy 356.608136 -283.525841) (xy 356.655939 -283.509425) (xy 356.705791 -283.501101)
			(xy 356.731062 -283.500576) (xy 357.671116 -283.500576) (xy 357.696395 -283.501023) (xy 357.746262 -283.509347)
			(xy 357.794079 -283.525765) (xy 357.838542 -283.549829) (xy 357.878438 -283.580883) (xy 357.912679 -283.61808)
			(xy 357.94033 -283.660406) (xy 357.960638 -283.706705) (xy 357.973049 -283.755715) (xy 357.977224 -283.8061)
			(xy 362.058752 -283.8061) (xy 362.062926 -283.755728) (xy 362.075334 -283.70673) (xy 362.095637 -283.660442)
			(xy 362.123281 -283.618128) (xy 362.157513 -283.58094) (xy 362.197398 -283.549894) (xy 362.24185 -283.525835)
			(xy 362.289655 -283.509421) (xy 362.33951 -283.501099) (xy 362.364782 -283.500576) (xy 363.304836 -283.500576)
			(xy 363.330114 -283.501025) (xy 363.379978 -283.509351) (xy 363.427793 -283.525771) (xy 363.472253 -283.549836)
			(xy 363.512146 -283.58089) (xy 363.546384 -283.618087) (xy 363.574033 -283.660411) (xy 363.594339 -283.706709)
			(xy 363.606749 -283.755717) (xy 363.610924 -283.8061) (xy 363.606749 -283.856483) (xy 363.594339 -283.905491)
			(xy 363.574033 -283.951789) (xy 363.546384 -283.994113) (xy 363.512146 -284.03131) (xy 363.472253 -284.062364)
			(xy 363.427793 -284.086429) (xy 363.379978 -284.102849) (xy 363.330114 -284.111175) (xy 363.304836 -284.1117)
			(xy 362.364782 -284.1117) (xy 362.33951 -284.111101) (xy 362.289655 -284.102779) (xy 362.24185 -284.086365)
			(xy 362.197398 -284.062306) (xy 362.157513 -284.03126) (xy 362.123281 -283.994072) (xy 362.095637 -283.951758)
			(xy 362.075334 -283.90547) (xy 362.062926 -283.856472) (xy 362.058752 -283.8061) (xy 357.977224 -283.8061)
			(xy 357.973049 -283.856485) (xy 357.960638 -283.905495) (xy 357.94033 -283.951794) (xy 357.912679 -283.99412)
			(xy 357.878438 -284.031317) (xy 357.838542 -284.062371) (xy 357.794079 -284.086435) (xy 357.746262 -284.102853)
			(xy 357.696395 -284.111177) (xy 357.671116 -284.1117) (xy 356.731062 -284.1117) (xy 356.705791 -284.111099)
			(xy 356.655939 -284.102775) (xy 356.608136 -284.086359) (xy 356.563688 -284.0623) (xy 356.523805 -284.031253)
			(xy 356.489576 -283.994066) (xy 356.461934 -283.951752) (xy 356.441632 -283.905466) (xy 356.429226 -283.85647)
			(xy 356.425052 -283.8061) (xy 344.841829 -283.8061) (xy 344.84183 -283.806138) (xy 344.841438 -283.829686)
			(xy 344.834798 -283.876312) (xy 344.821602 -283.921521) (xy 344.802116 -283.964396) (xy 344.78976 -283.984446)
			(xy 344.781886 -283.996638) (xy 344.781378 -284.024832) (xy 344.925396 -284.27299) (xy 344.950034 -284.286452)
			(xy 344.964512 -284.285944) (xy 344.981022 -284.285436) (xy 345.007009 -284.285921) (xy 345.058342 -284.294055)
			(xy 345.107771 -284.31012) (xy 345.154078 -284.333719) (xy 345.196123 -284.364273) (xy 345.23287 -284.401027)
			(xy 345.263415 -284.443078) (xy 345.287006 -284.48939) (xy 345.30306 -284.538822) (xy 345.311184 -284.590157)
			(xy 345.311729 -284.6161) (xy 345.615313 -284.6161) (xy 345.619483 -284.565772) (xy 345.63188 -284.516816)
			(xy 345.652165 -284.470568) (xy 345.679785 -284.42829) (xy 345.713987 -284.391134) (xy 345.753838 -284.360114)
			(xy 345.798251 -284.336076) (xy 345.846014 -284.319675) (xy 345.895826 -284.311359) (xy 345.921076 -284.310836)
			(xy 346.86113 -284.310836) (xy 346.886387 -284.311272) (xy 346.936213 -284.31959) (xy 346.983989 -284.335996)
			(xy 347.028414 -284.360042) (xy 347.068275 -284.391071) (xy 347.102487 -284.428237) (xy 347.130114 -284.470528)
			(xy 347.150404 -284.516788) (xy 347.162804 -284.565758) (xy 347.166976 -284.6161) (xy 348.435384 -284.6161)
			(xy 348.439556 -284.56576) (xy 348.451957 -284.516794) (xy 348.472249 -284.470537) (xy 348.499878 -284.428251)
			(xy 348.534091 -284.39109) (xy 348.573955 -284.360068) (xy 348.618381 -284.336031) (xy 348.666158 -284.319634)
			(xy 348.715982 -284.311326) (xy 348.741238 -284.310836) (xy 349.681292 -284.310836) (xy 349.706554 -284.31124)
			(xy 349.756388 -284.319555) (xy 349.804175 -284.335959) (xy 349.848609 -284.360005) (xy 349.88848 -284.391036)
			(xy 349.922699 -284.428207) (xy 349.950333 -284.470504) (xy 349.970629 -284.516772) (xy 349.983032 -284.565749)
			(xy 349.987204 -284.6161) (xy 351.255284 -284.6161) (xy 351.259456 -284.56576) (xy 351.271857 -284.516793)
			(xy 351.29215 -284.470535) (xy 351.31978 -284.428249) (xy 351.353994 -284.391087) (xy 351.393859 -284.360065)
			(xy 351.438286 -284.336028) (xy 351.486064 -284.319632) (xy 351.535889 -284.311325) (xy 351.561146 -284.310836)
			(xy 352.5012 -284.310836) (xy 352.526459 -284.311269) (xy 352.576288 -284.319584) (xy 352.624069 -284.335987)
			(xy 352.668498 -284.360031) (xy 352.708364 -284.39106) (xy 352.742579 -284.428227) (xy 352.770209 -284.470519)
			(xy 352.790502 -284.516782) (xy 352.802904 -284.565755) (xy 352.807076 -284.6161) (xy 354.075313 -284.6161)
			(xy 354.079483 -284.565774) (xy 354.091878 -284.51682) (xy 354.112161 -284.470574) (xy 354.139779 -284.428297)
			(xy 354.173978 -284.391142) (xy 354.213826 -284.360121) (xy 354.258236 -284.336082) (xy 354.305996 -284.31968)
			(xy 354.355805 -284.311361) (xy 354.381054 -284.310836) (xy 355.321108 -284.310836) (xy 355.346367 -284.31127)
			(xy 355.396195 -284.319586) (xy 355.443974 -284.33599) (xy 355.488402 -284.360034) (xy 355.528267 -284.391063)
			(xy 355.562481 -284.42823) (xy 355.590111 -284.470522) (xy 355.610403 -284.516784) (xy 355.622804 -284.565755)
			(xy 355.626976 -284.6161) (xy 364.409013 -284.6161) (xy 364.413183 -284.56577) (xy 364.425581 -284.516813)
			(xy 364.445867 -284.470564) (xy 364.473488 -284.428285) (xy 364.507692 -284.391129) (xy 364.547545 -284.360109)
			(xy 364.59196 -284.336071) (xy 364.639726 -284.319672) (xy 364.689539 -284.311358) (xy 364.71479 -284.310836)
			(xy 365.654844 -284.310836) (xy 365.680101 -284.311273) (xy 365.729924 -284.319593) (xy 365.777699 -284.336)
			(xy 365.822121 -284.360047) (xy 365.861981 -284.391076) (xy 365.89619 -284.428242) (xy 365.923816 -284.470532)
			(xy 365.944105 -284.516791) (xy 365.956505 -284.565759) (xy 365.960676 -284.6161) (xy 367.228913 -284.6161)
			(xy 367.233084 -284.565769) (xy 367.245481 -284.516812) (xy 367.265768 -284.470562) (xy 367.293391 -284.428282)
			(xy 367.327595 -284.391126) (xy 367.367449 -284.360106) (xy 367.411865 -284.336069) (xy 367.459632 -284.31967)
			(xy 367.509446 -284.311358) (xy 367.534698 -284.310836) (xy 368.474752 -284.310836) (xy 368.500016 -284.311237)
			(xy 368.549856 -284.319547) (xy 368.597648 -284.335947) (xy 368.642088 -284.359991) (xy 368.681965 -284.391022)
			(xy 368.716189 -284.428194) (xy 368.743827 -284.470492) (xy 368.764126 -284.516764) (xy 368.776531 -284.565745)
			(xy 368.780704 -284.6161) (xy 370.049113 -284.6161) (xy 370.053283 -284.565773) (xy 370.065679 -284.516819)
			(xy 370.085962 -284.470573) (xy 370.113581 -284.428295) (xy 370.147781 -284.391139) (xy 370.187629 -284.360119)
			(xy 370.23204 -284.33608) (xy 370.279801 -284.319678) (xy 370.32961 -284.311361) (xy 370.35486 -284.310836)
			(xy 371.294914 -284.310836) (xy 371.320172 -284.31127) (xy 371.369999 -284.319587) (xy 371.417778 -284.335992)
			(xy 371.462205 -284.360036) (xy 371.502069 -284.391065) (xy 371.536282 -284.428232) (xy 371.563912 -284.470523)
			(xy 371.584203 -284.516785) (xy 371.596604 -284.565756) (xy 371.600776 -284.6161) (xy 372.869013 -284.6161)
			(xy 372.873183 -284.565772) (xy 372.885579 -284.516818) (xy 372.905864 -284.47057) (xy 372.933483 -284.428292)
			(xy 372.967684 -284.391137) (xy 373.007533 -284.360116) (xy 373.051945 -284.336078) (xy 373.099708 -284.319677)
			(xy 373.149518 -284.31136) (xy 373.174768 -284.310836) (xy 374.114822 -284.310836) (xy 374.14008 -284.311271)
			(xy 374.189906 -284.319589) (xy 374.237684 -284.335994) (xy 374.28211 -284.360039) (xy 374.321972 -284.391068)
			(xy 374.356184 -284.428235) (xy 374.383813 -284.470525) (xy 374.404104 -284.516787) (xy 374.416504 -284.565757)
			(xy 374.420676 -284.6161) (xy 374.416504 -284.666443) (xy 374.404104 -284.715413) (xy 374.383813 -284.761675)
			(xy 374.356184 -284.803965) (xy 374.321972 -284.841132) (xy 374.28211 -284.872161) (xy 374.237684 -284.896206)
			(xy 374.189906 -284.912611) (xy 374.14008 -284.920929) (xy 374.114822 -284.921452) (xy 373.174768 -284.921452)
			(xy 373.149518 -284.92084) (xy 373.099708 -284.912523) (xy 373.051945 -284.896122) (xy 373.007533 -284.872084)
			(xy 372.967684 -284.841063) (xy 372.933483 -284.803908) (xy 372.905864 -284.76163) (xy 372.885579 -284.715382)
			(xy 372.873183 -284.666428) (xy 372.869013 -284.6161) (xy 371.600776 -284.6161) (xy 371.596604 -284.666444)
			(xy 371.584203 -284.715415) (xy 371.563912 -284.761677) (xy 371.536282 -284.803968) (xy 371.502069 -284.841135)
			(xy 371.462205 -284.872164) (xy 371.417778 -284.896208) (xy 371.369999 -284.912613) (xy 371.320172 -284.92093)
			(xy 371.294914 -284.921452) (xy 370.35486 -284.921452) (xy 370.32961 -284.920839) (xy 370.279801 -284.912522)
			(xy 370.23204 -284.89612) (xy 370.187629 -284.872081) (xy 370.147781 -284.841061) (xy 370.113581 -284.803905)
			(xy 370.085962 -284.761627) (xy 370.065679 -284.715381) (xy 370.053283 -284.666427) (xy 370.049113 -284.6161)
			(xy 368.780704 -284.6161) (xy 368.776531 -284.666455) (xy 368.764126 -284.715436) (xy 368.743827 -284.761708)
			(xy 368.716189 -284.804006) (xy 368.681965 -284.841178) (xy 368.642088 -284.872209) (xy 368.597648 -284.896253)
			(xy 368.549856 -284.912653) (xy 368.500016 -284.920963) (xy 368.474752 -284.921452) (xy 367.534698 -284.921452)
			(xy 367.509446 -284.920842) (xy 367.459632 -284.91253) (xy 367.411865 -284.896131) (xy 367.367449 -284.872094)
			(xy 367.327595 -284.841074) (xy 367.293391 -284.803918) (xy 367.265768 -284.761638) (xy 367.245481 -284.715388)
			(xy 367.233084 -284.666431) (xy 367.228913 -284.6161) (xy 365.960676 -284.6161) (xy 365.956505 -284.666441)
			(xy 365.944105 -284.715409) (xy 365.923816 -284.761668) (xy 365.89619 -284.803958) (xy 365.861981 -284.841124)
			(xy 365.822121 -284.872153) (xy 365.777699 -284.8962) (xy 365.729924 -284.912607) (xy 365.680101 -284.920927)
			(xy 365.654844 -284.921452) (xy 364.71479 -284.921452) (xy 364.689539 -284.920842) (xy 364.639726 -284.912528)
			(xy 364.59196 -284.896129) (xy 364.547545 -284.872091) (xy 364.507692 -284.841071) (xy 364.473489 -284.803915)
			(xy 364.445867 -284.761636) (xy 364.425581 -284.715387) (xy 364.413183 -284.66643) (xy 364.409013 -284.6161)
			(xy 355.626976 -284.6161) (xy 355.622804 -284.666445) (xy 355.610403 -284.715416) (xy 355.590111 -284.761678)
			(xy 355.562481 -284.80397) (xy 355.528267 -284.841137) (xy 355.488402 -284.872166) (xy 355.443974 -284.89621)
			(xy 355.396195 -284.912614) (xy 355.346367 -284.92093) (xy 355.321108 -284.921452) (xy 354.381054 -284.921452)
			(xy 354.355805 -284.920839) (xy 354.305996 -284.91252) (xy 354.258236 -284.896118) (xy 354.213826 -284.872079)
			(xy 354.173978 -284.841058) (xy 354.139779 -284.803903) (xy 354.112161 -284.761626) (xy 354.091878 -284.71538)
			(xy 354.079483 -284.666426) (xy 354.075313 -284.6161) (xy 352.807076 -284.6161) (xy 352.802904 -284.666445)
			(xy 352.790502 -284.715418) (xy 352.770209 -284.761681) (xy 352.742579 -284.803973) (xy 352.708364 -284.84114)
			(xy 352.668498 -284.872169) (xy 352.624069 -284.896213) (xy 352.576288 -284.912616) (xy 352.526459 -284.920931)
			(xy 352.5012 -284.921452) (xy 351.561146 -284.921452) (xy 351.535889 -284.920875) (xy 351.486064 -284.912568)
			(xy 351.438286 -284.896172) (xy 351.393859 -284.872135) (xy 351.353994 -284.841113) (xy 351.31978 -284.803951)
			(xy 351.29215 -284.761665) (xy 351.271857 -284.715407) (xy 351.259456 -284.66644) (xy 351.255284 -284.6161)
			(xy 349.987204 -284.6161) (xy 349.983032 -284.666451) (xy 349.970629 -284.715428) (xy 349.950333 -284.761696)
			(xy 349.922699 -284.803993) (xy 349.88848 -284.841164) (xy 349.848609 -284.872195) (xy 349.804175 -284.896241)
			(xy 349.756388 -284.912645) (xy 349.706554 -284.92096) (xy 349.681292 -284.921452) (xy 348.741238 -284.921452)
			(xy 348.715982 -284.920874) (xy 348.666158 -284.912566) (xy 348.618381 -284.896169) (xy 348.573955 -284.872132)
			(xy 348.534091 -284.84111) (xy 348.499878 -284.803949) (xy 348.472249 -284.761663) (xy 348.451957 -284.715406)
			(xy 348.439556 -284.66644) (xy 348.435384 -284.6161) (xy 347.166976 -284.6161) (xy 347.162804 -284.666442)
			(xy 347.150404 -284.715412) (xy 347.130114 -284.761672) (xy 347.102487 -284.803963) (xy 347.068275 -284.841129)
			(xy 347.028414 -284.872158) (xy 346.983989 -284.896204) (xy 346.936213 -284.91261) (xy 346.886387 -284.920928)
			(xy 346.86113 -284.921452) (xy 345.921076 -284.921452) (xy 345.895826 -284.920841) (xy 345.846014 -284.912525)
			(xy 345.798251 -284.896124) (xy 345.753838 -284.872086) (xy 345.713987 -284.841066) (xy 345.679785 -284.80391)
			(xy 345.652165 -284.761632) (xy 345.63188 -284.715384) (xy 345.619483 -284.666428) (xy 345.615313 -284.6161)
			(xy 345.311729 -284.6161) (xy 345.31173 -284.616144) (xy 345.311338 -284.639692) (xy 345.304697 -284.686317)
			(xy 345.2915 -284.731526) (xy 345.272014 -284.774401) (xy 345.25966 -284.794452) (xy 345.251786 -284.806644)
			(xy 345.251278 -284.834838) (xy 345.395296 -285.08325) (xy 345.419934 -285.096712) (xy 345.434412 -285.09595)
			(xy 345.451176 -285.095442) (xy 345.477163 -285.095923) (xy 345.528496 -285.10405) (xy 345.577927 -285.120108)
			(xy 345.624236 -285.143701) (xy 345.666285 -285.174248) (xy 345.703036 -285.210997) (xy 345.733587 -285.253043)
			(xy 345.757183 -285.299351) (xy 345.773244 -285.34878) (xy 345.781375 -285.400113) (xy 345.781375 -285.4261)
			(xy 356.425064 -285.4261) (xy 356.429238 -285.375732) (xy 356.441644 -285.326738) (xy 356.461944 -285.280454)
			(xy 356.489585 -285.238142) (xy 356.523813 -285.200956) (xy 356.563694 -285.16991) (xy 356.608141 -285.145852)
			(xy 356.655942 -285.129437) (xy 356.705792 -285.121113) (xy 356.731062 -285.120588) (xy 357.671116 -285.120588)
			(xy 357.696396 -285.121011) (xy 357.746265 -285.129335) (xy 357.794084 -285.145754) (xy 357.838549 -285.169819)
			(xy 357.878446 -285.200875) (xy 357.912688 -285.238073) (xy 357.940341 -285.2804) (xy 357.960649 -285.326701)
			(xy 357.97306 -285.375713) (xy 357.977236 -285.4261) (xy 362.058764 -285.4261) (xy 362.062938 -285.37573)
			(xy 362.075345 -285.326734) (xy 362.095647 -285.280448) (xy 362.12329 -285.238135) (xy 362.157521 -285.200949)
			(xy 362.197405 -285.169904) (xy 362.241855 -285.145846) (xy 362.289658 -285.129433) (xy 362.339511 -285.121111)
			(xy 362.364782 -285.120588) (xy 363.304836 -285.120588) (xy 363.330115 -285.121013) (xy 363.379981 -285.12934)
			(xy 363.427798 -285.14576) (xy 363.472259 -285.169826) (xy 363.512154 -285.200882) (xy 363.546393 -285.23808)
			(xy 363.574044 -285.280406) (xy 363.594351 -285.326705) (xy 363.606761 -285.375716) (xy 363.610936 -285.4261)
			(xy 363.606761 -285.476485) (xy 363.594351 -285.525495) (xy 363.574044 -285.571794) (xy 363.546393 -285.61412)
			(xy 363.512154 -285.651318) (xy 363.472259 -285.682374) (xy 363.427798 -285.70644) (xy 363.379981 -285.72286)
			(xy 363.330115 -285.731187) (xy 363.304836 -285.731712) (xy 362.364782 -285.731712) (xy 362.339511 -285.731089)
			(xy 362.289658 -285.722767) (xy 362.241855 -285.706354) (xy 362.197405 -285.682296) (xy 362.157521 -285.651251)
			(xy 362.12329 -285.614065) (xy 362.095647 -285.571752) (xy 362.075345 -285.525466) (xy 362.062938 -285.47647)
			(xy 362.058764 -285.4261) (xy 357.977236 -285.4261) (xy 357.97306 -285.476487) (xy 357.960649 -285.525499)
			(xy 357.940341 -285.5718) (xy 357.912688 -285.614127) (xy 357.878446 -285.651325) (xy 357.838549 -285.682381)
			(xy 357.794084 -285.706446) (xy 357.746265 -285.722865) (xy 357.696396 -285.731189) (xy 357.671116 -285.731712)
			(xy 356.731062 -285.731712) (xy 356.705792 -285.731087) (xy 356.655942 -285.722763) (xy 356.608141 -285.706348)
			(xy 356.563694 -285.68229) (xy 356.523813 -285.651244) (xy 356.489585 -285.614058) (xy 356.461944 -285.571746)
			(xy 356.441644 -285.525462) (xy 356.429238 -285.476468) (xy 356.425064 -285.4261) (xy 345.781375 -285.4261)
			(xy 345.781375 -285.452087) (xy 345.773244 -285.50342) (xy 345.757183 -285.552849) (xy 345.733587 -285.599157)
			(xy 345.703036 -285.641203) (xy 345.666285 -285.677952) (xy 345.624236 -285.708499) (xy 345.577927 -285.732092)
			(xy 345.528496 -285.74815) (xy 345.477163 -285.756277) (xy 345.451176 -285.756858) (xy 345.436952 -285.756604)
			(xy 345.422728 -285.755842) (xy 345.397836 -285.769558) (xy 345.252802 -286.019748) (xy 345.25331 -286.047942)
			(xy 345.26093 -286.05988) (xy 345.272968 -286.07977) (xy 345.291962 -286.122204) (xy 345.304839 -286.166876)
			(xy 345.311344 -286.21291) (xy 345.31173 -286.236156) (xy 345.311729 -286.2362) (xy 345.615733 -286.2362)
			(xy 345.619898 -286.185941) (xy 345.632277 -286.137052) (xy 345.652535 -286.090868) (xy 345.680117 -286.048648)
			(xy 345.714272 -286.011543) (xy 345.754068 -285.980566) (xy 345.798419 -285.956561) (xy 345.846117 -285.940183)
			(xy 345.89586 -285.931878) (xy 345.921076 -285.931356) (xy 346.86113 -285.931356) (xy 346.886338 -285.931967)
			(xy 346.936066 -285.94027) (xy 346.983749 -285.956643) (xy 347.028087 -285.980642) (xy 347.067871 -286.01161)
			(xy 347.102015 -286.048704) (xy 347.129589 -286.090912) (xy 347.149839 -286.137082) (xy 347.162215 -286.185956)
			(xy 347.166378 -286.2362) (xy 348.435296 -286.2362) (xy 348.439469 -286.185846) (xy 348.451873 -286.136866)
			(xy 348.472171 -286.090595) (xy 348.499809 -286.048297) (xy 348.534032 -286.011126) (xy 348.573906 -285.980094)
			(xy 348.618345 -285.95605) (xy 348.666136 -285.939649) (xy 348.715975 -285.931338) (xy 348.741238 -285.930848)
			(xy 349.681292 -285.930848) (xy 349.706547 -285.931428) (xy 349.756367 -285.93974) (xy 349.804139 -285.956139)
			(xy 349.848561 -285.980178) (xy 349.88842 -286.011201) (xy 349.92263 -286.048361) (xy 349.950256 -286.090645)
			(xy 349.970545 -286.1369) (xy 349.982945 -286.185864) (xy 349.987116 -286.2362) (xy 351.255196 -286.2362)
			(xy 351.259369 -286.185845) (xy 351.271774 -286.136864) (xy 351.292072 -286.090593) (xy 351.319711 -286.048295)
			(xy 351.353935 -286.011123) (xy 351.393811 -285.980092) (xy 351.438251 -285.956048) (xy 351.486043 -285.939647)
			(xy 351.535882 -285.931337) (xy 351.561146 -285.930848) (xy 352.5012 -285.930848) (xy 352.526452 -285.931457)
			(xy 352.576266 -285.93977) (xy 352.624033 -285.956168) (xy 352.66845 -285.980205) (xy 352.708304 -286.011225)
			(xy 352.742509 -286.048382) (xy 352.770132 -286.090661) (xy 352.790419 -286.136911) (xy 352.802816 -286.185869)
			(xy 352.806987 -286.2362) (xy 354.075224 -286.2362) (xy 354.079395 -286.185859) (xy 354.091795 -286.136892)
			(xy 354.112084 -286.090632) (xy 354.139709 -286.048343) (xy 354.173918 -286.011177) (xy 354.213778 -285.980147)
			(xy 354.2582 -285.956101) (xy 354.305974 -285.939694) (xy 354.355797 -285.931373) (xy 354.381054 -285.930848)
			(xy 355.321108 -285.930848) (xy 355.346359 -285.931458) (xy 355.396173 -285.939772) (xy 355.443939 -285.956171)
			(xy 355.488354 -285.980208) (xy 355.528207 -286.011228) (xy 355.562411 -286.048384) (xy 355.590033 -286.090664)
			(xy 355.610319 -286.136913) (xy 355.622717 -286.18587) (xy 355.626887 -286.2362) (xy 364.408924 -286.2362)
			(xy 364.413096 -286.185856) (xy 364.425497 -286.136884) (xy 364.445789 -286.090622) (xy 364.473419 -286.048331)
			(xy 364.507632 -286.011164) (xy 364.547497 -285.980135) (xy 364.591924 -285.95609) (xy 364.639704 -285.939686)
			(xy 364.689532 -285.93137) (xy 364.71479 -285.930848) (xy 365.654844 -285.930848) (xy 365.680093 -285.931461)
			(xy 365.729902 -285.939779) (xy 365.777663 -285.956181) (xy 365.822073 -285.980221) (xy 365.861921 -286.011241)
			(xy 365.89612 -286.048396) (xy 365.923738 -286.090674) (xy 365.944022 -286.13692) (xy 365.956417 -286.185874)
			(xy 365.960587 -286.2362) (xy 367.228824 -286.2362) (xy 367.232996 -286.185855) (xy 367.245398 -286.136883)
			(xy 367.26569 -286.09062) (xy 367.293321 -286.048328) (xy 367.327535 -286.011161) (xy 367.367401 -285.980132)
			(xy 367.41183 -285.956088) (xy 367.45961 -285.939685) (xy 367.509439 -285.931369) (xy 367.534698 -285.930848)
			(xy 368.474752 -285.930848) (xy 368.500009 -285.931425) (xy 368.549834 -285.939732) (xy 368.597612 -285.956128)
			(xy 368.64204 -285.980164) (xy 368.681905 -286.011187) (xy 368.716119 -286.048348) (xy 368.74375 -286.090634)
			(xy 368.764043 -286.136892) (xy 368.776444 -286.185859) (xy 368.780616 -286.2362) (xy 370.049024 -286.2362)
			(xy 370.053196 -286.185859) (xy 370.065595 -286.13689) (xy 370.085885 -286.09063) (xy 370.113511 -286.048341)
			(xy 370.147721 -286.011174) (xy 370.187581 -285.980145) (xy 370.232004 -285.956099) (xy 370.279779 -285.939692)
			(xy 370.329603 -285.931372) (xy 370.35486 -285.930848) (xy 371.294914 -285.930848) (xy 371.320165 -285.931459)
			(xy 371.369978 -285.939773) (xy 371.417743 -285.956173) (xy 371.462157 -285.98021) (xy 371.502009 -286.01123)
			(xy 371.536213 -286.048386) (xy 371.563834 -286.090665) (xy 371.58412 -286.136914) (xy 371.596517 -286.185871)
			(xy 371.600687 -286.2362) (xy 371.596517 -286.286529) (xy 371.58412 -286.335486) (xy 371.563834 -286.381735)
			(xy 371.536213 -286.424014) (xy 371.502009 -286.46117) (xy 371.462157 -286.49219) (xy 371.417743 -286.516227)
			(xy 371.369978 -286.532627) (xy 371.320165 -286.540941) (xy 371.294914 -286.541464) (xy 370.35486 -286.541464)
			(xy 370.329603 -286.541028) (xy 370.279779 -286.532708) (xy 370.232004 -286.516301) (xy 370.187581 -286.492255)
			(xy 370.147721 -286.461226) (xy 370.113511 -286.424059) (xy 370.085884 -286.38177) (xy 370.065595 -286.33551)
			(xy 370.053196 -286.286541) (xy 370.049024 -286.2362) (xy 368.780616 -286.2362) (xy 368.776444 -286.286541)
			(xy 368.764043 -286.335508) (xy 368.74375 -286.381766) (xy 368.716119 -286.424052) (xy 368.681905 -286.461213)
			(xy 368.64204 -286.492236) (xy 368.597612 -286.516272) (xy 368.549834 -286.532668) (xy 368.500009 -286.540975)
			(xy 368.474752 -286.541464) (xy 367.534698 -286.541464) (xy 367.509439 -286.541031) (xy 367.45961 -286.532715)
			(xy 367.41183 -286.516312) (xy 367.367401 -286.492268) (xy 367.327535 -286.461239) (xy 367.293321 -286.424072)
			(xy 367.26569 -286.38178) (xy 367.245398 -286.335517) (xy 367.232996 -286.286545) (xy 367.228824 -286.2362)
			(xy 365.960587 -286.2362) (xy 365.956417 -286.286526) (xy 365.944022 -286.33548) (xy 365.923738 -286.381726)
			(xy 365.89612 -286.424004) (xy 365.861921 -286.461159) (xy 365.822073 -286.492179) (xy 365.777663 -286.516219)
			(xy 365.729902 -286.532621) (xy 365.680093 -286.540939) (xy 365.654844 -286.541464) (xy 364.71479 -286.541464)
			(xy 364.689532 -286.54103) (xy 364.639704 -286.532714) (xy 364.591924 -286.51631) (xy 364.547497 -286.492265)
			(xy 364.507632 -286.461236) (xy 364.473419 -286.424069) (xy 364.445789 -286.381778) (xy 364.425497 -286.335516)
			(xy 364.413096 -286.286544) (xy 364.408924 -286.2362) (xy 355.626887 -286.2362) (xy 355.622717 -286.28653)
			(xy 355.610319 -286.335487) (xy 355.590033 -286.381736) (xy 355.562411 -286.424016) (xy 355.528207 -286.461172)
			(xy 355.488354 -286.492192) (xy 355.443939 -286.516229) (xy 355.396173 -286.532628) (xy 355.346359 -286.540942)
			(xy 355.321108 -286.541464) (xy 354.381054 -286.541464) (xy 354.355797 -286.541027) (xy 354.305974 -286.532706)
			(xy 354.2582 -286.516299) (xy 354.213778 -286.492253) (xy 354.173918 -286.461223) (xy 354.139709 -286.424057)
			(xy 354.112084 -286.381768) (xy 354.091795 -286.335508) (xy 354.079395 -286.286541) (xy 354.075224 -286.2362)
			(xy 352.806987 -286.2362) (xy 352.802816 -286.286531) (xy 352.790419 -286.335489) (xy 352.770132 -286.381739)
			(xy 352.742509 -286.424018) (xy 352.708304 -286.461175) (xy 352.66845 -286.492195) (xy 352.624033 -286.516232)
			(xy 352.576266 -286.53263) (xy 352.526452 -286.540943) (xy 352.5012 -286.541464) (xy 351.561146 -286.541464)
			(xy 351.535882 -286.541063) (xy 351.486043 -286.532753) (xy 351.438251 -286.516352) (xy 351.393811 -286.492309)
			(xy 351.353935 -286.461277) (xy 351.319711 -286.424105) (xy 351.292072 -286.381807) (xy 351.271774 -286.335536)
			(xy 351.259369 -286.286555) (xy 351.255196 -286.2362) (xy 349.987116 -286.2362) (xy 349.982945 -286.286536)
			(xy 349.970545 -286.3355) (xy 349.950256 -286.381755) (xy 349.92263 -286.424039) (xy 349.88842 -286.461199)
			(xy 349.848561 -286.492222) (xy 349.804139 -286.516261) (xy 349.756367 -286.53266) (xy 349.706547 -286.540972)
			(xy 349.681292 -286.541464) (xy 348.741238 -286.541464) (xy 348.715975 -286.541062) (xy 348.666136 -286.532751)
			(xy 348.618345 -286.51635) (xy 348.573907 -286.492306) (xy 348.534032 -286.461274) (xy 348.499809 -286.424103)
			(xy 348.472171 -286.381805) (xy 348.451873 -286.335534) (xy 348.439469 -286.286554) (xy 348.435296 -286.2362)
			(xy 347.166378 -286.2362) (xy 347.162215 -286.286444) (xy 347.149839 -286.335318) (xy 347.129589 -286.381488)
			(xy 347.102015 -286.423696) (xy 347.067871 -286.46079) (xy 347.028087 -286.491758) (xy 346.983749 -286.515757)
			(xy 346.936066 -286.53213) (xy 346.886338 -286.540433) (xy 346.86113 -286.540956) (xy 345.921076 -286.540956)
			(xy 345.89586 -286.540522) (xy 345.846117 -286.532217) (xy 345.798419 -286.515839) (xy 345.754068 -286.491834)
			(xy 345.714272 -286.460857) (xy 345.680117 -286.423752) (xy 345.652535 -286.381532) (xy 345.632277 -286.335348)
			(xy 345.619898 -286.286459) (xy 345.615733 -286.2362) (xy 345.311729 -286.2362) (xy 345.31125 -286.262148)
			(xy 345.303125 -286.313493) (xy 345.287066 -286.362935) (xy 345.263471 -286.409256) (xy 345.23292 -286.451315)
			(xy 345.196166 -286.488077) (xy 345.154112 -286.518637) (xy 345.107796 -286.542241) (xy 345.058358 -286.558309)
			(xy 345.007014 -286.566445) (xy 344.981022 -286.566864) (xy 344.967052 -286.56661) (xy 344.952828 -286.565848)
			(xy 344.92819 -286.579564) (xy 344.783156 -286.8295) (xy 344.783664 -286.857948) (xy 344.79103 -286.869886)
			(xy 344.803063 -286.889743) (xy 344.822054 -286.932112) (xy 344.83493 -286.976721) (xy 344.841438 -287.022693)
			(xy 344.84183 -287.0459) (xy 356.425785 -287.0459) (xy 356.429949 -286.995651) (xy 356.442326 -286.946772)
			(xy 356.462578 -286.900597) (xy 356.490154 -286.858385) (xy 356.524301 -286.821286) (xy 356.564089 -286.790314)
			(xy 356.608431 -286.766312) (xy 356.656119 -286.749936) (xy 356.705851 -286.741631) (xy 356.731062 -286.741108)
			(xy 357.671116 -286.741108) (xy 357.696329 -286.741614) (xy 357.746067 -286.749916) (xy 357.793761 -286.766291)
			(xy 357.838108 -286.790293) (xy 357.877901 -286.821267) (xy 357.912053 -286.858367) (xy 357.939633 -286.900583)
			(xy 357.959888 -286.946763) (xy 357.972266 -286.995646) (xy 357.976431 -287.0459) (xy 357.972266 -287.096154)
			(xy 357.959888 -287.145037) (xy 357.939633 -287.191217) (xy 357.912053 -287.233433) (xy 357.877901 -287.270533)
			(xy 357.838108 -287.301507) (xy 357.793761 -287.325509) (xy 357.746067 -287.341884) (xy 357.696329 -287.350186)
			(xy 357.671116 -287.350708) (xy 356.731062 -287.350708) (xy 356.705851 -287.350169) (xy 356.656119 -287.341864)
			(xy 356.608431 -287.325488) (xy 356.564089 -287.301486) (xy 356.524301 -287.270514) (xy 356.490154 -287.233415)
			(xy 356.462578 -287.191203) (xy 356.442326 -287.145028) (xy 356.429949 -287.096149) (xy 356.425785 -287.0459)
			(xy 344.84183 -287.0459) (xy 344.84183 -287.045908) (xy 344.841392 -287.069462) (xy 344.834668 -287.116089)
			(xy 344.8214 -287.161291) (xy 344.801856 -287.204154) (xy 344.789506 -287.224216) (xy 344.781886 -287.236408)
			(xy 344.781124 -287.264602) (xy 344.925396 -287.513014) (xy 344.950034 -287.526476) (xy 344.964512 -287.525968)
			(xy 344.981022 -287.52546) (xy 345.007009 -287.525971) (xy 345.058343 -287.534104) (xy 345.107772 -287.550167)
			(xy 345.154081 -287.573763) (xy 345.196129 -287.604313) (xy 345.232881 -287.641063) (xy 345.263431 -287.68311)
			(xy 345.287029 -287.729418) (xy 345.303093 -287.778848) (xy 345.311228 -287.830181) (xy 345.31173 -287.856168)
			(xy 345.311729 -287.8562) (xy 345.615745 -287.8562) (xy 345.61991 -287.805943) (xy 345.632289 -287.757056)
			(xy 345.652545 -287.710874) (xy 345.680126 -287.668655) (xy 345.71428 -287.631552) (xy 345.754074 -287.600576)
			(xy 345.798424 -287.576572) (xy 345.84612 -287.560194) (xy 345.895861 -287.55189) (xy 345.921076 -287.551368)
			(xy 346.86113 -287.551368) (xy 346.886339 -287.551955) (xy 346.936069 -287.560258) (xy 346.983754 -287.576632)
			(xy 347.028094 -287.600631) (xy 347.067879 -287.631601) (xy 347.102025 -287.668697) (xy 347.129599 -287.710906)
			(xy 347.149851 -287.757078) (xy 347.162227 -287.805954) (xy 347.166391 -287.8562) (xy 348.435817 -287.8562)
			(xy 348.439983 -287.805932) (xy 348.452366 -287.757035) (xy 348.472629 -287.710843) (xy 348.50022 -287.668617)
			(xy 348.534384 -287.631509) (xy 348.574191 -287.60053) (xy 348.618555 -287.576527) (xy 348.666264 -287.560154)
			(xy 348.716018 -287.551857) (xy 348.741238 -287.551368) (xy 349.681292 -287.551368) (xy 349.706505 -287.551923)
			(xy 349.756245 -287.560222) (xy 349.80394 -287.576595) (xy 349.848289 -287.600594) (xy 349.888084 -287.631567)
			(xy 349.922238 -287.668667) (xy 349.949819 -287.710882) (xy 349.970075 -287.757061) (xy 349.982455 -287.805945)
			(xy 349.986619 -287.8562) (xy 351.255717 -287.8562) (xy 351.259883 -287.805931) (xy 351.272267 -287.757033)
			(xy 351.292531 -287.710841) (xy 351.320122 -287.668615) (xy 351.354288 -287.631506) (xy 351.394096 -287.600528)
			(xy 351.43846 -287.576525) (xy 351.486171 -287.560152) (xy 351.535925 -287.551856) (xy 351.561146 -287.551368)
			(xy 352.5012 -287.551368) (xy 352.526411 -287.551952) (xy 352.576144 -287.560251) (xy 352.623834 -287.576623)
			(xy 352.668178 -287.600621) (xy 352.707968 -287.63159) (xy 352.742117 -287.668687) (xy 352.769695 -287.710898)
			(xy 352.789949 -287.757072) (xy 352.802327 -287.805951) (xy 352.806491 -287.8562) (xy 354.075745 -287.8562)
			(xy 354.079909 -287.805945) (xy 354.092287 -287.757061) (xy 354.112542 -287.71088) (xy 354.14012 -287.668663)
			(xy 354.174271 -287.63156) (xy 354.214063 -287.600583) (xy 354.258409 -287.576578) (xy 354.306102 -287.560199)
			(xy 354.355841 -287.551892) (xy 354.381054 -287.551368) (xy 355.321108 -287.551368) (xy 355.346318 -287.551953)
			(xy 355.396051 -287.560253) (xy 355.443739 -287.576625) (xy 355.488082 -287.600624) (xy 355.527871 -287.631593)
			(xy 355.562019 -287.668689) (xy 355.589596 -287.7109) (xy 355.60985 -287.757074) (xy 355.622227 -287.805952)
			(xy 355.626391 -287.8562) (xy 355.622227 -287.906448) (xy 355.60985 -287.955326) (xy 355.589596 -288.0015)
			(xy 355.562019 -288.043711) (xy 355.527871 -288.080807) (xy 355.488082 -288.111776) (xy 355.443739 -288.135775)
			(xy 355.396051 -288.152147) (xy 355.346318 -288.160447) (xy 355.321108 -288.160968) (xy 354.381054 -288.160968)
			(xy 354.355841 -288.160508) (xy 354.306102 -288.152201) (xy 354.258409 -288.135822) (xy 354.214063 -288.111817)
			(xy 354.174271 -288.08084) (xy 354.14012 -288.043737) (xy 354.112542 -288.00152) (xy 354.092287 -287.955339)
			(xy 354.079909 -287.906455) (xy 354.075745 -287.8562) (xy 352.806491 -287.8562) (xy 352.802327 -287.906449)
			(xy 352.789949 -287.955328) (xy 352.769695 -288.001502) (xy 352.742117 -288.043713) (xy 352.707968 -288.08081)
			(xy 352.668178 -288.111779) (xy 352.623834 -288.135777) (xy 352.576144 -288.152149) (xy 352.526411 -288.160448)
			(xy 352.5012 -288.160968) (xy 351.561146 -288.160968) (xy 351.535925 -288.160544) (xy 351.486171 -288.152248)
			(xy 351.43846 -288.135875) (xy 351.394096 -288.111872) (xy 351.354288 -288.080894) (xy 351.320122 -288.043785)
			(xy 351.292531 -288.001559) (xy 351.272267 -287.955367) (xy 351.259883 -287.906469) (xy 351.255717 -287.8562)
			(xy 349.986619 -287.8562) (xy 349.982455 -287.906455) (xy 349.970075 -287.955339) (xy 349.949819 -288.001518)
			(xy 349.922238 -288.043733) (xy 349.888084 -288.080833) (xy 349.848289 -288.111806) (xy 349.80394 -288.135805)
			(xy 349.756245 -288.152178) (xy 349.706505 -288.160477) (xy 349.681292 -288.160968) (xy 348.741238 -288.160968)
			(xy 348.716018 -288.160543) (xy 348.666264 -288.152246) (xy 348.618555 -288.135873) (xy 348.574191 -288.11187)
			(xy 348.534384 -288.080891) (xy 348.50022 -288.043783) (xy 348.472629 -288.001557) (xy 348.452366 -287.955365)
			(xy 348.439983 -287.906468) (xy 348.435817 -287.8562) (xy 347.166391 -287.8562) (xy 347.162227 -287.906446)
			(xy 347.149851 -287.955322) (xy 347.1296 -288.001494) (xy 347.102025 -288.043703) (xy 347.067879 -288.080799)
			(xy 347.028094 -288.111769) (xy 346.983754 -288.135768) (xy 346.936069 -288.152142) (xy 346.886339 -288.160445)
			(xy 346.86113 -288.160968) (xy 345.921076 -288.160968) (xy 345.895861 -288.16051) (xy 345.84612 -288.152206)
			(xy 345.798424 -288.135828) (xy 345.754074 -288.111824) (xy 345.71428 -288.080848) (xy 345.680126 -288.043745)
			(xy 345.652545 -288.001526) (xy 345.632289 -287.955344) (xy 345.61991 -287.906457) (xy 345.615745 -287.8562)
			(xy 345.311729 -287.8562) (xy 345.311336 -287.879716) (xy 345.304692 -287.926339) (xy 345.291492 -287.971546)
			(xy 345.272004 -288.014419) (xy 345.25966 -288.034476) (xy 345.251786 -288.046668) (xy 345.251278 -288.074862)
			(xy 345.395042 -288.32302) (xy 345.419934 -288.336482) (xy 345.434412 -288.33572) (xy 345.451176 -288.335212)
			(xy 345.477165 -288.335693) (xy 345.528503 -288.343821) (xy 345.577938 -288.35988) (xy 345.624252 -288.383475)
			(xy 345.666304 -288.414025) (xy 345.703059 -288.450778) (xy 345.733612 -288.492828) (xy 345.757211 -288.53914)
			(xy 345.773273 -288.588573) (xy 345.781405 -288.639911) (xy 345.781405 -288.6659) (xy 356.425797 -288.6659)
			(xy 356.429961 -288.615653) (xy 356.442337 -288.566776) (xy 356.462589 -288.520603) (xy 356.490164 -288.478392)
			(xy 356.52431 -288.441295) (xy 356.564095 -288.410324) (xy 356.608436 -288.386323) (xy 356.656122 -288.369948)
			(xy 356.705852 -288.361643) (xy 356.731062 -288.36112) (xy 357.671116 -288.36112) (xy 357.69633 -288.361602)
			(xy 357.74607 -288.369904) (xy 357.793766 -288.38628) (xy 357.838115 -288.410283) (xy 357.877909 -288.441258)
			(xy 357.912062 -288.47836) (xy 357.939643 -288.520577) (xy 357.959899 -288.566759) (xy 357.972278 -288.615644)
			(xy 357.976443 -288.6659) (xy 357.972278 -288.716156) (xy 357.959899 -288.765041) (xy 357.939643 -288.811223)
			(xy 357.912062 -288.85344) (xy 357.877909 -288.890542) (xy 357.838115 -288.921517) (xy 357.793766 -288.94552)
			(xy 357.74607 -288.961896) (xy 357.69633 -288.970198) (xy 357.671116 -288.97072) (xy 356.731062 -288.97072)
			(xy 356.705852 -288.970157) (xy 356.656122 -288.961852) (xy 356.608436 -288.945477) (xy 356.564095 -288.921476)
			(xy 356.52431 -288.890505) (xy 356.490164 -288.853408) (xy 356.462589 -288.811197) (xy 356.442337 -288.765024)
			(xy 356.429961 -288.716147) (xy 356.425797 -288.6659) (xy 345.781405 -288.6659) (xy 345.781405 -288.691889)
			(xy 345.773273 -288.743227) (xy 345.757211 -288.79266) (xy 345.733612 -288.838972) (xy 345.703059 -288.881022)
			(xy 345.666304 -288.917775) (xy 345.624252 -288.948325) (xy 345.577938 -288.97192) (xy 345.528503 -288.987979)
			(xy 345.477165 -288.996107) (xy 345.451176 -288.996628) (xy 345.436952 -288.996374) (xy 345.422982 -288.995612)
			(xy 345.39809 -289.009328) (xy 345.252802 -289.259518) (xy 345.25331 -289.287966) (xy 345.26093 -289.299904)
			(xy 345.272962 -289.319761) (xy 345.29195 -289.362131) (xy 345.304824 -289.40674) (xy 345.31133 -289.452711)
			(xy 345.31173 -289.4759) (xy 345.615803 -289.4759) (xy 345.619967 -289.425652) (xy 345.632344 -289.376775)
			(xy 345.652596 -289.330602) (xy 345.680172 -289.288391) (xy 345.714319 -289.251295) (xy 345.754106 -289.220324)
			(xy 345.798448 -289.196325) (xy 345.846135 -289.17995) (xy 345.895866 -289.171648) (xy 345.921076 -289.171126)
			(xy 346.86113 -289.171126) (xy 346.886344 -289.171597) (xy 346.936083 -289.179901) (xy 346.983777 -289.196279)
			(xy 347.028126 -289.220283) (xy 347.067919 -289.251259) (xy 347.102071 -289.288361) (xy 347.129651 -289.330579)
			(xy 347.149906 -289.376759) (xy 347.162284 -289.425644) (xy 347.166449 -289.4759) (xy 348.435875 -289.4759)
			(xy 348.44004 -289.425641) (xy 348.452421 -289.376754) (xy 348.47268 -289.330571) (xy 348.500266 -289.288353)
			(xy 348.534424 -289.251252) (xy 348.574223 -289.220279) (xy 348.618578 -289.19628) (xy 348.666278 -289.17991)
			(xy 348.716022 -289.171615) (xy 348.741238 -289.171126) (xy 349.681292 -289.171126) (xy 349.70651 -289.171565)
			(xy 349.756259 -289.179866) (xy 349.803963 -289.196242) (xy 349.848321 -289.220246) (xy 349.888123 -289.251224)
			(xy 349.922283 -289.288331) (xy 349.94987 -289.330554) (xy 349.97013 -289.376743) (xy 349.982512 -289.425636)
			(xy 349.986677 -289.4759) (xy 351.255775 -289.4759) (xy 351.25994 -289.42564) (xy 351.272321 -289.376752)
			(xy 351.292582 -289.330569) (xy 351.320168 -289.28835) (xy 351.354327 -289.251249) (xy 351.394127 -289.220276)
			(xy 351.438483 -289.196278) (xy 351.486185 -289.179908) (xy 351.53593 -289.171614) (xy 351.561146 -289.171126)
			(xy 352.5012 -289.171126) (xy 352.526415 -289.171594) (xy 352.576159 -289.179895) (xy 352.623857 -289.19627)
			(xy 352.66821 -289.220272) (xy 352.708007 -289.251248) (xy 352.742163 -289.288351) (xy 352.769746 -289.33057)
			(xy 352.790004 -289.376754) (xy 352.802384 -289.425641) (xy 352.806549 -289.4759) (xy 354.075803 -289.4759)
			(xy 354.079967 -289.425655) (xy 354.092342 -289.37678) (xy 354.112593 -289.330608) (xy 354.140166 -289.288398)
			(xy 354.17431 -289.251302) (xy 354.214094 -289.220332) (xy 354.258433 -289.196331) (xy 354.306117 -289.179955)
			(xy 354.355845 -289.17165) (xy 354.381054 -289.171126) (xy 355.321108 -289.171126) (xy 355.346323 -289.171595)
			(xy 355.396065 -289.179897) (xy 355.443763 -289.196272) (xy 355.488114 -289.220275) (xy 355.52791 -289.251251)
			(xy 355.562065 -289.288354) (xy 355.589647 -289.330572) (xy 355.609904 -289.376755) (xy 355.622284 -289.425642)
			(xy 355.626449 -289.4759) (xy 355.622284 -289.526158) (xy 355.609904 -289.575045) (xy 355.589647 -289.621228)
			(xy 355.562065 -289.663446) (xy 355.52791 -289.700549) (xy 355.488114 -289.731525) (xy 355.443763 -289.755528)
			(xy 355.396065 -289.771903) (xy 355.346323 -289.780205) (xy 355.321108 -289.780726) (xy 354.381054 -289.780726)
			(xy 354.355845 -289.78015) (xy 354.306117 -289.771845) (xy 354.258433 -289.755469) (xy 354.214094 -289.731468)
			(xy 354.17431 -289.700498) (xy 354.140166 -289.663402) (xy 354.112593 -289.621192) (xy 354.092342 -289.57502)
			(xy 354.079967 -289.526145) (xy 354.075803 -289.4759) (xy 352.806549 -289.4759) (xy 352.802384 -289.526159)
			(xy 352.790004 -289.575046) (xy 352.769746 -289.62123) (xy 352.742163 -289.663449) (xy 352.708007 -289.700552)
			(xy 352.66821 -289.731528) (xy 352.623857 -289.75553) (xy 352.576159 -289.771905) (xy 352.526415 -289.780206)
			(xy 352.5012 -289.780726) (xy 351.561146 -289.780726) (xy 351.53593 -289.780186) (xy 351.486185 -289.771892)
			(xy 351.438483 -289.755522) (xy 351.394127 -289.731524) (xy 351.354327 -289.700551) (xy 351.320168 -289.66345)
			(xy 351.292582 -289.621231) (xy 351.272321 -289.575048) (xy 351.25994 -289.52616) (xy 351.255775 -289.4759)
			(xy 349.986677 -289.4759) (xy 349.982512 -289.526164) (xy 349.97013 -289.575057) (xy 349.94987 -289.621246)
			(xy 349.922283 -289.663469) (xy 349.888123 -289.700576) (xy 349.848321 -289.731554) (xy 349.803963 -289.755558)
			(xy 349.756259 -289.771934) (xy 349.70651 -289.780235) (xy 349.681292 -289.780726) (xy 348.741238 -289.780726)
			(xy 348.716022 -289.780185) (xy 348.666278 -289.77189) (xy 348.618578 -289.75552) (xy 348.574223 -289.731521)
			(xy 348.534424 -289.700548) (xy 348.500266 -289.663447) (xy 348.47268 -289.621229) (xy 348.452421 -289.575046)
			(xy 348.44004 -289.526159) (xy 348.435875 -289.4759) (xy 347.166449 -289.4759) (xy 347.162284 -289.526156)
			(xy 347.149906 -289.575041) (xy 347.129651 -289.621221) (xy 347.102071 -289.663439) (xy 347.067919 -289.700541)
			(xy 347.028126 -289.731517) (xy 346.983777 -289.755521) (xy 346.936083 -289.771899) (xy 346.886344 -289.780203)
			(xy 346.86113 -289.780726) (xy 345.921076 -289.780726) (xy 345.895866 -289.780152) (xy 345.846135 -289.77185)
			(xy 345.798448 -289.755475) (xy 345.754106 -289.731476) (xy 345.714319 -289.700505) (xy 345.680172 -289.663409)
			(xy 345.652596 -289.621198) (xy 345.632344 -289.575025) (xy 345.619967 -289.526148) (xy 345.615803 -289.4759)
			(xy 345.31173 -289.4759) (xy 345.31173 -289.475926) (xy 345.311219 -289.501912) (xy 345.303085 -289.553245)
			(xy 345.287022 -289.602674) (xy 345.263425 -289.648981) (xy 345.232875 -289.691027) (xy 345.196124 -289.727778)
			(xy 345.154078 -289.758327) (xy 345.10777 -289.781923) (xy 345.058341 -289.797986) (xy 345.007008 -289.806119)
			(xy 344.981022 -289.806634) (xy 344.967052 -289.80638) (xy 344.953082 -289.805872) (xy 344.92819 -289.819334)
			(xy 344.783156 -290.069524) (xy 344.783664 -290.097972) (xy 344.79103 -290.10991) (xy 344.803062 -290.129767)
			(xy 344.822049 -290.172137) (xy 344.834922 -290.216746) (xy 344.841427 -290.262717) (xy 344.841829 -290.2859)
			(xy 356.425809 -290.2859) (xy 356.429973 -290.235655) (xy 356.442348 -290.18678) (xy 356.462599 -290.140608)
			(xy 356.490173 -290.098399) (xy 356.524318 -290.061304) (xy 356.564102 -290.030334) (xy 356.608441 -290.006334)
			(xy 356.656125 -289.989959) (xy 356.705853 -289.981655) (xy 356.731062 -289.981132) (xy 357.671116 -289.981132)
			(xy 357.696331 -289.98159) (xy 357.746073 -289.989893) (xy 357.79377 -290.006269) (xy 357.838122 -290.030273)
			(xy 357.877917 -290.061249) (xy 357.912072 -290.098353) (xy 357.939654 -290.140572) (xy 357.959911 -290.186755)
			(xy 357.97229 -290.235642) (xy 357.976455 -290.2859) (xy 357.97229 -290.336158) (xy 357.959911 -290.385045)
			(xy 357.939654 -290.431228) (xy 357.912072 -290.473447) (xy 357.877917 -290.510551) (xy 357.838122 -290.541527)
			(xy 357.79377 -290.565531) (xy 357.746073 -290.581907) (xy 357.696331 -290.59021) (xy 357.671116 -290.590732)
			(xy 356.731062 -290.590732) (xy 356.705853 -290.590145) (xy 356.656125 -290.581841) (xy 356.608441 -290.565466)
			(xy 356.564102 -290.541466) (xy 356.524318 -290.510496) (xy 356.490173 -290.473401) (xy 356.462599 -290.431192)
			(xy 356.442348 -290.38502) (xy 356.429973 -290.336145) (xy 356.425809 -290.2859) (xy 344.841829 -290.2859)
			(xy 344.84183 -290.285932) (xy 344.841318 -290.311918) (xy 344.833184 -290.36325) (xy 344.81712 -290.412678)
			(xy 344.793523 -290.458984) (xy 344.762973 -290.50103) (xy 344.726222 -290.53778) (xy 344.684176 -290.568328)
			(xy 344.637868 -290.591924) (xy 344.58844 -290.607986) (xy 344.537108 -290.616119) (xy 344.511122 -290.61664)
			(xy 344.497152 -290.616386) (xy 344.482928 -290.615624) (xy 344.45829 -290.62934) (xy 344.313002 -290.87953)
			(xy 344.31351 -290.907724) (xy 344.32113 -290.919662) (xy 344.333169 -290.939552) (xy 344.352166 -290.981985)
			(xy 344.365045 -291.026658) (xy 344.371552 -291.072692) (xy 344.371929 -291.0959) (xy 345.615816 -291.0959)
			(xy 345.619979 -291.045654) (xy 345.632355 -290.996779) (xy 345.652607 -290.950608) (xy 345.680182 -290.908399)
			(xy 345.714327 -290.871304) (xy 345.754113 -290.840335) (xy 345.798453 -290.816336) (xy 345.846138 -290.799963)
			(xy 345.895867 -290.791661) (xy 345.921076 -290.791138) (xy 346.86113 -290.791138) (xy 346.886345 -290.791585)
			(xy 346.936086 -290.79989) (xy 346.983782 -290.816268) (xy 347.028132 -290.840273) (xy 347.067927 -290.87125)
			(xy 347.10208 -290.908354) (xy 347.129661 -290.950573) (xy 347.149917 -290.996756) (xy 347.162296 -291.045642)
			(xy 347.166461 -291.0959) (xy 348.435887 -291.0959) (xy 348.440052 -291.045643) (xy 348.452432 -290.996757)
			(xy 348.472691 -290.950576) (xy 348.500275 -290.90836) (xy 348.534432 -290.87126) (xy 348.57423 -290.840289)
			(xy 348.618583 -290.816291) (xy 348.666281 -290.799922) (xy 348.716023 -290.791627) (xy 348.741238 -290.791138)
			(xy 349.681292 -290.791138) (xy 349.706511 -290.791553) (xy 349.756262 -290.799854) (xy 349.803968 -290.816231)
			(xy 349.848328 -290.840236) (xy 349.888131 -290.871215) (xy 349.922293 -290.908324) (xy 349.94988 -290.950549)
			(xy 349.970142 -290.996739) (xy 349.982524 -291.045634) (xy 349.986689 -291.0959) (xy 351.255787 -291.0959)
			(xy 351.259952 -291.045642) (xy 351.272333 -290.996756) (xy 351.292592 -290.950574) (xy 351.320177 -290.908358)
			(xy 351.354335 -290.871257) (xy 351.394134 -290.840286) (xy 351.438488 -290.816289) (xy 351.486188 -290.79992)
			(xy 351.535931 -290.791626) (xy 351.561146 -290.791138) (xy 352.5012 -290.791138) (xy 352.526416 -290.791582)
			(xy 352.576162 -290.799883) (xy 352.623862 -290.816259) (xy 352.668216 -290.840262) (xy 352.708015 -290.871239)
			(xy 352.742172 -290.908344) (xy 352.769757 -290.950564) (xy 352.790015 -290.99675) (xy 352.802396 -291.045639)
			(xy 352.806561 -291.0959) (xy 354.075816 -291.0959) (xy 354.079979 -291.045657) (xy 354.092354 -290.996784)
			(xy 354.112604 -290.950614) (xy 354.140176 -290.908406) (xy 354.174319 -290.871312) (xy 354.214101 -290.840342)
			(xy 354.258438 -290.816343) (xy 354.30612 -290.799967) (xy 354.355846 -290.791662) (xy 354.381054 -290.791138)
			(xy 355.321108 -290.791138) (xy 355.346324 -290.791583) (xy 355.396068 -290.799885) (xy 355.443767 -290.816261)
			(xy 355.488121 -290.840265) (xy 355.527918 -290.871242) (xy 355.562074 -290.908346) (xy 355.589658 -290.950567)
			(xy 355.609916 -290.996751) (xy 355.622296 -291.04564) (xy 355.626461 -291.0959) (xy 355.622296 -291.14616)
			(xy 355.609916 -291.195049) (xy 355.589658 -291.241233) (xy 355.562074 -291.283454) (xy 355.527918 -291.320558)
			(xy 355.488121 -291.351535) (xy 355.443767 -291.375539) (xy 355.396068 -291.391915) (xy 355.346324 -291.400217)
			(xy 355.321108 -291.400738) (xy 354.381054 -291.400738) (xy 354.355846 -291.400138) (xy 354.30612 -291.391833)
			(xy 354.258438 -291.375457) (xy 354.214101 -291.351458) (xy 354.174319 -291.320488) (xy 354.140176 -291.283394)
			(xy 354.112604 -291.241186) (xy 354.092354 -291.195016) (xy 354.079979 -291.146143) (xy 354.075816 -291.0959)
			(xy 352.806561 -291.0959) (xy 352.802396 -291.146161) (xy 352.790015 -291.19505) (xy 352.769757 -291.241236)
			(xy 352.742172 -291.283456) (xy 352.708015 -291.320561) (xy 352.668216 -291.351538) (xy 352.623862 -291.375541)
			(xy 352.576162 -291.391917) (xy 352.526416 -291.400218) (xy 352.5012 -291.400738) (xy 351.561146 -291.400738)
			(xy 351.535931 -291.400174) (xy 351.486188 -291.39188) (xy 351.438488 -291.375511) (xy 351.394134 -291.351514)
			(xy 351.354335 -291.320542) (xy 351.320177 -291.283442) (xy 351.292592 -291.241226) (xy 351.272333 -291.195044)
			(xy 351.259952 -291.146158) (xy 351.255787 -291.0959) (xy 349.986689 -291.0959) (xy 349.982524 -291.146166)
			(xy 349.970142 -291.195061) (xy 349.94988 -291.241251) (xy 349.922293 -291.283476) (xy 349.888131 -291.320585)
			(xy 349.848328 -291.351564) (xy 349.803968 -291.375569) (xy 349.756262 -291.391946) (xy 349.706511 -291.400247)
			(xy 349.681292 -291.400738) (xy 348.741238 -291.400738) (xy 348.716023 -291.400173) (xy 348.666281 -291.391878)
			(xy 348.618583 -291.375509) (xy 348.57423 -291.351511) (xy 348.534432 -291.32054) (xy 348.500275 -291.28344)
			(xy 348.472691 -291.241223) (xy 348.452432 -291.195043) (xy 348.440052 -291.146157) (xy 348.435887 -291.0959)
			(xy 347.166461 -291.0959) (xy 347.162296 -291.146158) (xy 347.149917 -291.195044) (xy 347.129661 -291.241227)
			(xy 347.10208 -291.283446) (xy 347.067927 -291.32055) (xy 347.028132 -291.351527) (xy 346.983782 -291.375532)
			(xy 346.936086 -291.39191) (xy 346.886345 -291.400215) (xy 346.86113 -291.400738) (xy 345.921076 -291.400738)
			(xy 345.895867 -291.400139) (xy 345.846138 -291.391837) (xy 345.798453 -291.375464) (xy 345.754113 -291.351465)
			(xy 345.714327 -291.320496) (xy 345.680182 -291.283401) (xy 345.652607 -291.241192) (xy 345.632355 -291.195021)
			(xy 345.619979 -291.146146) (xy 345.615816 -291.0959) (xy 344.371929 -291.0959) (xy 344.37193 -291.095938)
			(xy 344.371418 -291.121924) (xy 344.363282 -291.173255) (xy 344.347218 -291.222682) (xy 344.323621 -291.268988)
			(xy 344.293071 -291.311033) (xy 344.25632 -291.347781) (xy 344.214274 -291.378329) (xy 344.167967 -291.401925)
			(xy 344.118539 -291.417986) (xy 344.067208 -291.426119) (xy 344.041222 -291.426646) (xy 344.026998 -291.426392)
			(xy 344.012774 -291.42563) (xy 343.988136 -291.439346) (xy 343.842848 -291.689536) (xy 343.843356 -291.71773)
			(xy 343.850976 -291.729922) (xy 343.863006 -291.74978) (xy 343.881989 -291.79215) (xy 343.894858 -291.836759)
			(xy 343.901361 -291.88273) (xy 343.901776 -291.905944) (xy 343.901263 -291.931928) (xy 343.893127 -291.983255)
			(xy 343.877062 -292.032678) (xy 343.853463 -292.078979) (xy 343.822912 -292.121018) (xy 343.786161 -292.157761)
			(xy 343.744114 -292.188303) (xy 343.697808 -292.211891) (xy 343.648381 -292.227945) (xy 343.597052 -292.236069)
			(xy 343.571068 -292.236652) (xy 343.557098 -292.236398) (xy 343.542874 -292.235636) (xy 343.517982 -292.249352)
			(xy 343.372948 -292.499542) (xy 343.373456 -292.527736) (xy 343.381076 -292.539674) (xy 343.393113 -292.559564)
			(xy 343.412105 -292.601999) (xy 343.424981 -292.646671) (xy 343.431486 -292.692705) (xy 343.431876 -292.71595)
			(xy 343.431397 -292.741941) (xy 343.423271 -292.793284) (xy 343.407213 -292.842723) (xy 343.383618 -292.889041)
			(xy 343.353066 -292.931096) (xy 343.31631 -292.967854) (xy 343.274256 -292.998408) (xy 343.227939 -293.022006)
			(xy 343.178501 -293.038067) (xy 343.127159 -293.046195) (xy 343.101168 -293.046658) (xy 343.086944 -293.046404)
			(xy 343.07272 -293.045642) (xy 343.048082 -293.059358) (xy 342.902794 -293.309548) (xy 342.903302 -293.337742)
			(xy 342.910922 -293.34968) (xy 342.92296 -293.36957) (xy 342.941955 -293.412004) (xy 342.954832 -293.456676)
			(xy 342.961337 -293.50271) (xy 342.961722 -293.525956) (xy 342.961242 -293.551948) (xy 342.953116 -293.603293)
			(xy 342.937058 -293.652734) (xy 342.913463 -293.699054) (xy 342.882912 -293.741113) (xy 342.846157 -293.777874)
			(xy 342.804104 -293.808433) (xy 342.757788 -293.832036) (xy 342.708349 -293.848103) (xy 342.657006 -293.856238)
			(xy 342.631014 -293.856664) (xy 342.60555 -293.856197) (xy 342.555222 -293.848395) (xy 342.506685 -293.832973)
			(xy 342.461084 -293.810296) (xy 342.419496 -293.7809) (xy 342.382904 -293.745477) (xy 342.352172 -293.704866)
			(xy 342.339676 -293.682674) (xy 342.333072 -293.670228) (xy 342.309196 -293.656004) (xy 342.013032 -293.656004)
			(xy 341.989156 -293.670228) (xy 341.982552 -293.682674) (xy 341.97006 -293.704868) (xy 341.939319 -293.745471)
			(xy 341.902723 -293.780887) (xy 341.861135 -293.810282) (xy 341.815536 -293.832962) (xy 341.767002 -293.848392)
			(xy 341.716678 -293.856208) (xy 341.691214 -293.856664) (xy 341.67699 -293.85641) (xy 341.662766 -293.855648)
			(xy 341.638128 -293.869364) (xy 341.478616 -294.144192) (xy 341.478616 -294.17137) (xy 341.485474 -294.183308)
			(xy 341.498332 -294.206672) (xy 341.516568 -294.256783) (xy 341.525821 -294.309299) (xy 341.526368 -294.335962)
			(xy 341.525925 -294.359956) (xy 341.518422 -294.407354) (xy 341.503597 -294.452994) (xy 341.481813 -294.495752)
			(xy 341.453607 -294.534576) (xy 341.419674 -294.568508) (xy 341.380851 -294.596714) (xy 341.338092 -294.618497)
			(xy 341.292452 -294.633323) (xy 341.245054 -294.640825) (xy 341.22106 -294.64127) (xy 341.206074 -294.64127)
			(xy 341.182452 -294.654732) (xy 341.008716 -294.954198) (xy 341.008716 -294.981376) (xy 341.015574 -294.993314)
			(xy 341.028431 -295.016678) (xy 341.046666 -295.066789) (xy 341.055919 -295.119305) (xy 341.056468 -295.145968)
			(xy 341.056024 -295.169962) (xy 341.048521 -295.217359) (xy 341.033695 -295.262998) (xy 341.011911 -295.305756)
			(xy 340.983705 -295.344578) (xy 340.949772 -295.37851) (xy 340.910949 -295.406715) (xy 340.868191 -295.428498)
			(xy 340.822551 -295.443323) (xy 340.775154 -295.450825) (xy 340.75116 -295.451276) (xy 340.736174 -295.451276)
			(xy 340.712298 -295.464738) (xy 340.552786 -295.739566) (xy 340.553294 -295.76776) (xy 340.560914 -295.779952)
			(xy 340.57295 -295.799808) (xy 340.591946 -295.842176) (xy 340.604827 -295.886786) (xy 340.61134 -295.932758)
			(xy 340.611714 -295.955974) (xy 340.611233 -295.981965) (xy 340.603105 -296.033307) (xy 340.587045 -296.082745)
			(xy 340.563449 -296.129062) (xy 340.532897 -296.171118) (xy 340.496142 -296.207876) (xy 340.45409 -296.238432)
			(xy 340.407775 -296.262033) (xy 340.358338 -296.278097) (xy 340.306997 -296.28623) (xy 340.281006 -296.286682)
			(xy 340.255542 -296.286214) (xy 340.205215 -296.278412) (xy 340.156677 -296.26299) (xy 340.111076 -296.240313)
			(xy 340.069488 -296.210917) (xy 340.032896 -296.175495) (xy 340.002163 -296.134885) (xy 339.989668 -296.112692)
			(xy 339.983064 -296.100246) (xy 339.959188 -296.085768) (xy 339.663024 -296.085768) (xy 339.639148 -296.100246)
			(xy 339.632544 -296.112692) (xy 339.620054 -296.134886) (xy 339.589316 -296.175489) (xy 339.55272 -296.210904)
			(xy 339.51113 -296.240294) (xy 339.46553 -296.262967) (xy 339.416994 -296.278386) (xy 339.366669 -296.286187)
			(xy 339.315743 -296.286187) (xy 339.265418 -296.278386) (xy 339.216882 -296.262967) (xy 339.171282 -296.240294)
			(xy 339.129692 -296.210904) (xy 339.093096 -296.175489) (xy 339.062358 -296.134886) (xy 339.049868 -296.112692)
			(xy 339.043264 -296.100246) (xy 339.019388 -296.085768) (xy 338.72297 -296.085768) (xy 338.699094 -296.100246)
			(xy 338.69249 -296.112692) (xy 338.68 -296.134886) (xy 338.649262 -296.175489) (xy 338.612666 -296.210904)
			(xy 338.571076 -296.240294) (xy 338.525476 -296.262967) (xy 338.47694 -296.278386) (xy 338.426615 -296.286187)
			(xy 338.375689 -296.286187) (xy 338.325364 -296.278386) (xy 338.276828 -296.262967) (xy 338.231228 -296.240294)
			(xy 338.189638 -296.210904) (xy 338.153042 -296.175489) (xy 338.122304 -296.134886) (xy 338.109814 -296.112692)
			(xy 338.10321 -296.100246) (xy 338.079334 -296.085768) (xy 336.842862 -296.085768) (xy 336.818986 -296.100246)
			(xy 336.812382 -296.112692) (xy 336.799892 -296.134886) (xy 336.769154 -296.175489) (xy 336.732558 -296.210904)
			(xy 336.690968 -296.240294) (xy 336.645368 -296.262967) (xy 336.596832 -296.278386) (xy 336.546507 -296.286187)
			(xy 336.495581 -296.286187) (xy 336.445256 -296.278386) (xy 336.39672 -296.262967) (xy 336.35112 -296.240294)
			(xy 336.30953 -296.210904) (xy 336.272934 -296.175489) (xy 336.242196 -296.134886) (xy 336.229706 -296.112692)
			(xy 336.223102 -296.100246) (xy 336.199226 -296.085768) (xy 334.93456 -296.085768) (xy 334.911192 -296.09923)
			(xy 334.904334 -296.110914) (xy 334.891525 -296.131693) (xy 334.860359 -296.169258) (xy 334.823617 -296.20139)
			(xy 334.782234 -296.227272) (xy 334.737262 -296.246243) (xy 334.689845 -296.257823) (xy 334.64119 -296.261716)
			(xy 334.592535 -296.257823) (xy 334.545118 -296.246243) (xy 334.500146 -296.227272) (xy 334.458763 -296.20139)
			(xy 334.422021 -296.169258) (xy 334.390855 -296.131693) (xy 334.378046 -296.110914) (xy 334.371188 -296.09923)
			(xy 334.34782 -296.085768) (xy 334.022954 -296.085768) (xy 333.999078 -296.100246) (xy 333.992474 -296.112692)
			(xy 333.979984 -296.134886) (xy 333.949246 -296.175489) (xy 333.91265 -296.210904) (xy 333.87106 -296.240294)
			(xy 333.82546 -296.262967) (xy 333.776924 -296.278386) (xy 333.726599 -296.286187) (xy 333.675673 -296.286187)
			(xy 333.625348 -296.278386) (xy 333.576812 -296.262967) (xy 333.531212 -296.240294) (xy 333.489622 -296.210904)
			(xy 333.453026 -296.175489) (xy 333.422288 -296.134886) (xy 333.409798 -296.112692) (xy 333.403194 -296.100246)
			(xy 333.379318 -296.085768) (xy 333.0829 -296.085768) (xy 333.059024 -296.100246) (xy 333.05242 -296.112692)
			(xy 333.03993 -296.134886) (xy 333.009192 -296.175489) (xy 332.972596 -296.210904) (xy 332.931006 -296.240294)
			(xy 332.885406 -296.262967) (xy 332.83687 -296.278386) (xy 332.786545 -296.286187) (xy 332.735619 -296.286187)
			(xy 332.685294 -296.278386) (xy 332.636758 -296.262967) (xy 332.591158 -296.240294) (xy 332.549568 -296.210904)
			(xy 332.512972 -296.175489) (xy 332.482234 -296.134886) (xy 332.469744 -296.112692) (xy 332.46314 -296.100246)
			(xy 332.439264 -296.085768) (xy 332.142846 -296.085768) (xy 332.11897 -296.100246) (xy 332.112366 -296.112692)
			(xy 332.099876 -296.134886) (xy 332.069138 -296.175489) (xy 332.032542 -296.210904) (xy 331.990952 -296.240294)
			(xy 331.945352 -296.262967) (xy 331.896816 -296.278386) (xy 331.846491 -296.286187) (xy 331.795565 -296.286187)
			(xy 331.74524 -296.278386) (xy 331.696704 -296.262967) (xy 331.651104 -296.240294) (xy 331.609514 -296.210904)
			(xy 331.572918 -296.175489) (xy 331.54218 -296.134886) (xy 331.52969 -296.112692) (xy 331.523086 -296.100246)
			(xy 331.49921 -296.085768) (xy 331.174598 -296.085768) (xy 331.15123 -296.09923) (xy 331.144372 -296.110914)
			(xy 331.131563 -296.131693) (xy 331.100397 -296.169258) (xy 331.063655 -296.20139) (xy 331.022272 -296.227272)
			(xy 330.9773 -296.246243) (xy 330.929883 -296.257823) (xy 330.881228 -296.261716) (xy 330.832573 -296.257823)
			(xy 330.785156 -296.246243) (xy 330.740184 -296.227272) (xy 330.698801 -296.20139) (xy 330.662059 -296.169258)
			(xy 330.630893 -296.131693) (xy 330.618084 -296.110914) (xy 330.611226 -296.09923) (xy 330.587858 -296.085768)
			(xy 327.44283 -296.085768) (xy 327.418954 -296.100246) (xy 327.41235 -296.112692) (xy 327.399862 -296.13489)
			(xy 327.369125 -296.175502) (xy 327.332531 -296.210927) (xy 327.290943 -296.24033) (xy 327.245343 -296.263015)
			(xy 327.196806 -296.278449) (xy 327.146478 -296.286267) (xy 327.121012 -296.286682) (xy 327.094796 -296.286181)
			(xy 327.043021 -296.277906) (xy 326.993201 -296.261563) (xy 326.946586 -296.23756) (xy 326.925178 -296.22242)
			(xy 326.918479 -296.217838) (xy 326.903064 -296.212794) (xy 326.894952 -296.212514) (xy 317.087504 -296.212514)
			(xy 317.077434 -296.212937) (xy 317.05883 -296.220652) (xy 317.051436 -296.2275) (xy 313.131962 -300.146974)
			(xy 340.219284 -300.146974) (xy 340.219284 -299.130974) (xy 340.21977 -299.103723) (xy 340.227526 -299.049775)
			(xy 340.242881 -298.99748) (xy 340.265523 -298.947903) (xy 340.294989 -298.902053) (xy 340.33068 -298.860862)
			(xy 340.371871 -298.825171) (xy 340.417721 -298.795705) (xy 340.467298 -298.773063) (xy 340.519593 -298.757708)
			(xy 340.573541 -298.749952) (xy 340.628043 -298.749952) (xy 340.681991 -298.757708) (xy 340.734286 -298.773063)
			(xy 340.783863 -298.795705) (xy 340.829713 -298.825171) (xy 340.870904 -298.860862) (xy 340.906595 -298.902053)
			(xy 340.936061 -298.947903) (xy 340.958703 -298.99748) (xy 340.974058 -299.049775) (xy 340.981814 -299.103723)
			(xy 340.9823 -299.130974) (xy 340.9823 -300.146974) (xy 340.981814 -300.174225) (xy 340.974058 -300.228173)
			(xy 340.958703 -300.280468) (xy 340.936061 -300.330045) (xy 340.906595 -300.375895) (xy 340.870904 -300.417086)
			(xy 340.829713 -300.452777) (xy 340.783863 -300.482243) (xy 340.734286 -300.504885) (xy 340.681991 -300.52024)
			(xy 340.628043 -300.527996) (xy 340.573541 -300.527996) (xy 340.519593 -300.52024) (xy 340.467298 -300.504885)
			(xy 340.417721 -300.482243) (xy 340.371871 -300.452777) (xy 340.33068 -300.417086) (xy 340.294989 -300.375895)
			(xy 340.265523 -300.330045) (xy 340.242881 -300.280468) (xy 340.227526 -300.228173) (xy 340.21977 -300.174225)
			(xy 340.219284 -300.146974) (xy 313.131962 -300.146974) (xy 308.498748 -304.780188) (xy 326.752462 -304.780188)
			(xy 326.756491 -304.637867) (xy 326.768566 -304.496002) (xy 326.788647 -304.355048) (xy 326.81667 -304.215455)
			(xy 326.852546 -304.077671) (xy 326.89616 -303.942138) (xy 326.947372 -303.809289) (xy 327.006018 -303.67955)
			(xy 327.071909 -303.553337) (xy 327.144836 -303.431054) (xy 327.224564 -303.313092) (xy 327.310838 -303.19983)
			(xy 327.403382 -303.091631) (xy 327.501898 -302.98884) (xy 327.606073 -302.891788) (xy 327.715571 -302.800784)
			(xy 327.830042 -302.716122) (xy 327.94912 -302.638071) (xy 328.072423 -302.566882) (xy 328.199556 -302.502783)
			(xy 328.330112 -302.445979) (xy 328.463672 -302.396653) (xy 328.599809 -302.354961) (xy 328.738087 -302.321038)
			(xy 328.878062 -302.294993) (xy 329.019287 -302.276908) (xy 329.161308 -302.266843) (xy 329.303672 -302.264828)
			(xy 329.445922 -302.270871) (xy 329.587602 -302.284951) (xy 329.728258 -302.307025) (xy 329.86744 -302.337021)
			(xy 330.004702 -302.374843) (xy 330.139605 -302.420371) (xy 330.271716 -302.473457) (xy 330.400612 -302.533933)
			(xy 330.52588 -302.601604) (xy 330.647119 -302.676254) (xy 330.76394 -302.757643) (xy 330.87597 -302.845511)
			(xy 330.982849 -302.939577) (xy 331.084235 -303.039538) (xy 331.179804 -303.145076) (xy 331.269249 -303.255851)
			(xy 331.352283 -303.371509) (xy 331.428641 -303.491679) (xy 331.498078 -303.615977) (xy 331.560371 -303.744004)
			(xy 331.615322 -303.875351) (xy 331.662754 -304.009596) (xy 331.702515 -304.146309) (xy 331.734477 -304.285053)
			(xy 331.758539 -304.425383) (xy 331.774623 -304.566849) (xy 331.781099 -304.681128) (xy 333.795116 -304.681128)
			(xy 333.795116 -303.817528) (xy 333.795602 -303.790259) (xy 333.803364 -303.736275) (xy 333.818729 -303.683945)
			(xy 333.841386 -303.634335) (xy 333.870872 -303.588454) (xy 333.906587 -303.547237) (xy 333.947804 -303.511522)
			(xy 333.993685 -303.482036) (xy 334.043295 -303.459379) (xy 334.095625 -303.444014) (xy 334.149609 -303.436252)
			(xy 334.204147 -303.436252) (xy 334.258131 -303.444014) (xy 334.310461 -303.459379) (xy 334.360071 -303.482036)
			(xy 334.405952 -303.511522) (xy 334.447169 -303.547237) (xy 334.482884 -303.588454) (xy 334.51237 -303.634335)
			(xy 334.535027 -303.683945) (xy 334.550392 -303.736275) (xy 334.558154 -303.790259) (xy 334.55864 -303.817528)
			(xy 334.55864 -304.681128) (xy 334.558154 -304.708397) (xy 334.550392 -304.762381) (xy 334.535027 -304.814711)
			(xy 334.51237 -304.864321) (xy 334.482884 -304.910202) (xy 334.447169 -304.951419) (xy 334.405952 -304.987134)
			(xy 334.360071 -305.01662) (xy 334.310461 -305.039277) (xy 334.258131 -305.054642) (xy 334.204147 -305.062404)
			(xy 334.149609 -305.062404) (xy 334.095625 -305.054642) (xy 334.043295 -305.039277) (xy 333.993685 -305.01662)
			(xy 333.947804 -304.987134) (xy 333.906587 -304.951419) (xy 333.870872 -304.910202) (xy 333.841386 -304.864321)
			(xy 333.818729 -304.814711) (xy 333.803364 -304.762381) (xy 333.795602 -304.708397) (xy 333.795116 -304.681128)
			(xy 331.781099 -304.681128) (xy 331.782679 -304.708999) (xy 331.783182 -304.780188) (xy 331.782679 -304.851377)
			(xy 331.774623 -304.993527) (xy 331.758539 -305.134993) (xy 331.734477 -305.275323) (xy 331.702515 -305.414067)
			(xy 331.662754 -305.55078) (xy 331.615322 -305.685025) (xy 331.560371 -305.816372) (xy 331.498078 -305.944399)
			(xy 331.428641 -306.068697) (xy 331.352283 -306.188867) (xy 331.269249 -306.304525) (xy 331.179804 -306.4153)
			(xy 331.163807 -306.432966) (xy 340.495636 -306.432966) (xy 340.495636 -305.569366) (xy 340.496122 -305.542115)
			(xy 340.503878 -305.488167) (xy 340.519233 -305.435872) (xy 340.541875 -305.386295) (xy 340.571341 -305.340445)
			(xy 340.607032 -305.299254) (xy 340.648223 -305.263563) (xy 340.694073 -305.234097) (xy 340.74365 -305.211455)
			(xy 340.795945 -305.1961) (xy 340.849893 -305.188344) (xy 340.904395 -305.188344) (xy 340.958343 -305.1961)
			(xy 341.010638 -305.211455) (xy 341.060215 -305.234097) (xy 341.106065 -305.263563) (xy 341.147256 -305.299254)
			(xy 341.182947 -305.340445) (xy 341.212413 -305.386295) (xy 341.235055 -305.435872) (xy 341.25041 -305.488167)
			(xy 341.258166 -305.542115) (xy 341.258652 -305.569366) (xy 341.258652 -306.432966) (xy 341.258166 -306.460217)
			(xy 341.25041 -306.514165) (xy 341.235055 -306.56646) (xy 341.212413 -306.616037) (xy 341.182947 -306.661887)
			(xy 341.147256 -306.703078) (xy 341.106065 -306.738769) (xy 341.060215 -306.768235) (xy 341.010638 -306.790877)
			(xy 340.958343 -306.806232) (xy 340.904395 -306.813988) (xy 340.849893 -306.813988) (xy 340.795945 -306.806232)
			(xy 340.74365 -306.790877) (xy 340.694073 -306.768235) (xy 340.648223 -306.738769) (xy 340.607032 -306.703078)
			(xy 340.571341 -306.661887) (xy 340.541875 -306.616037) (xy 340.519233 -306.56646) (xy 340.503878 -306.514165)
			(xy 340.496122 -306.460217) (xy 340.495636 -306.432966) (xy 331.163807 -306.432966) (xy 331.084235 -306.520838)
			(xy 330.982849 -306.620799) (xy 330.87597 -306.714865) (xy 330.76394 -306.802733) (xy 330.647119 -306.884122)
			(xy 330.52588 -306.958772) (xy 330.400612 -307.026443) (xy 330.271716 -307.086919) (xy 330.139605 -307.140005)
			(xy 330.004702 -307.185533) (xy 329.86744 -307.223355) (xy 329.728258 -307.253351) (xy 329.587602 -307.275425)
			(xy 329.445922 -307.289505) (xy 329.303672 -307.295548) (xy 329.161308 -307.293533) (xy 329.019287 -307.283468)
			(xy 328.878062 -307.265383) (xy 328.738087 -307.239338) (xy 328.599809 -307.205415) (xy 328.463672 -307.163723)
			(xy 328.330112 -307.114397) (xy 328.199556 -307.057593) (xy 328.072423 -306.993494) (xy 327.94912 -306.922305)
			(xy 327.830042 -306.844254) (xy 327.715571 -306.759592) (xy 327.606073 -306.668588) (xy 327.501898 -306.571536)
			(xy 327.403382 -306.468745) (xy 327.310838 -306.360546) (xy 327.224564 -306.247284) (xy 327.144836 -306.129322)
			(xy 327.071909 -306.007039) (xy 327.006018 -305.880826) (xy 326.947372 -305.751087) (xy 326.89616 -305.618238)
			(xy 326.852546 -305.482705) (xy 326.81667 -305.344921) (xy 326.788647 -305.205328) (xy 326.768566 -305.064374)
			(xy 326.756491 -304.922509) (xy 326.752462 -304.780188) (xy 308.498748 -304.780188) (xy 304.129948 -309.148988)
			(xy 304.123095 -309.156384) (xy 304.115348 -309.174982) (xy 304.114962 -309.185056) (xy 304.114962 -309.303166)
			(xy 341.51824 -309.303166) (xy 341.51824 -308.439566) (xy 341.518726 -308.412297) (xy 341.526488 -308.358313)
			(xy 341.541853 -308.305983) (xy 341.56451 -308.256373) (xy 341.593996 -308.210492) (xy 341.629711 -308.169275)
			(xy 341.670928 -308.13356) (xy 341.716809 -308.104074) (xy 341.766419 -308.081417) (xy 341.818749 -308.066052)
			(xy 341.872733 -308.05829) (xy 341.927271 -308.05829) (xy 341.981255 -308.066052) (xy 342.033585 -308.081417)
			(xy 342.083195 -308.104074) (xy 342.129076 -308.13356) (xy 342.170293 -308.169275) (xy 342.206008 -308.210492)
			(xy 342.235494 -308.256373) (xy 342.258151 -308.305983) (xy 342.273516 -308.358313) (xy 342.281278 -308.412297)
			(xy 342.281764 -308.439566) (xy 342.281764 -309.303166) (xy 342.281278 -309.330435) (xy 342.273516 -309.384419)
			(xy 342.258151 -309.436749) (xy 342.235494 -309.486359) (xy 342.206008 -309.53224) (xy 342.170293 -309.573457)
			(xy 342.129076 -309.609172) (xy 342.083195 -309.638658) (xy 342.033585 -309.661315) (xy 341.981255 -309.67668)
			(xy 341.927271 -309.684442) (xy 341.872733 -309.684442) (xy 341.818749 -309.67668) (xy 341.766419 -309.661315)
			(xy 341.716809 -309.638658) (xy 341.670928 -309.609172) (xy 341.629711 -309.573457) (xy 341.593996 -309.53224)
			(xy 341.56451 -309.486359) (xy 341.541853 -309.436749) (xy 341.526488 -309.384419) (xy 341.518726 -309.330435)
			(xy 341.51824 -309.303166) (xy 304.114962 -309.303166) (xy 304.114962 -311.513728) (xy 347.772228 -311.513728)
			(xy 347.772228 -310.650128) (xy 347.772714 -310.622859) (xy 347.780476 -310.568875) (xy 347.795841 -310.516545)
			(xy 347.818498 -310.466935) (xy 347.847984 -310.421054) (xy 347.883699 -310.379837) (xy 347.924916 -310.344122)
			(xy 347.970797 -310.314636) (xy 348.020407 -310.291979) (xy 348.072737 -310.276614) (xy 348.126721 -310.268852)
			(xy 348.181259 -310.268852) (xy 348.235243 -310.276614) (xy 348.287573 -310.291979) (xy 348.337183 -310.314636)
			(xy 348.383064 -310.344122) (xy 348.424281 -310.379837) (xy 348.459996 -310.421054) (xy 348.489482 -310.466935)
			(xy 348.512139 -310.516545) (xy 348.527504 -310.568875) (xy 348.535266 -310.622859) (xy 348.535752 -310.650128)
			(xy 348.535752 -311.513728) (xy 348.535266 -311.540997) (xy 348.527504 -311.594981) (xy 348.512139 -311.647311)
			(xy 348.489482 -311.696921) (xy 348.459996 -311.742802) (xy 348.424281 -311.784019) (xy 348.383064 -311.819734)
			(xy 348.337183 -311.84922) (xy 348.287573 -311.871877) (xy 348.235243 -311.887242) (xy 348.181259 -311.895004)
			(xy 348.126721 -311.895004) (xy 348.072737 -311.887242) (xy 348.020407 -311.871877) (xy 347.970797 -311.84922)
			(xy 347.924916 -311.819734) (xy 347.883699 -311.784019) (xy 347.847984 -311.742802) (xy 347.818498 -311.696921)
			(xy 347.795841 -311.647311) (xy 347.780476 -311.594981) (xy 347.772714 -311.540997) (xy 347.772228 -311.513728)
			(xy 304.114962 -311.513728) (xy 304.114962 -334.78216) (xy 304.115398 -334.792224) (xy 304.123134 -334.810807)
			(xy 304.129948 -334.818228) (xy 304.530252 -335.218532) (xy 304.53765 -335.225378) (xy 304.556249 -335.233104)
			(xy 304.56632 -335.233518)
		)
		(stroke
			(width 0)
			(type solid)
		)
		(fill yes)
		(layer "In8.Cu")
		(net "PVDDCR_CPU1_P0")
	)
	(gr_poly
		(pts
			(xy 255.800098 -33.611058) (xy 255.832245 -33.610555) (xy 255.89599 -33.602163) (xy 255.958093 -33.585522)
			(xy 256.017493 -33.560917) (xy 256.073173 -33.528769) (xy 256.124181 -33.489628) (xy 256.169643 -33.444164)
			(xy 256.208781 -33.393155) (xy 256.240927 -33.337473) (xy 256.265529 -33.278072) (xy 256.282167 -33.215968)
			(xy 256.290557 -33.152223) (xy 256.29108 -33.120076) (xy 256.29108 -11.780012) (xy 256.291564 -11.709629)
			(xy 256.299456 -11.569085) (xy 256.315217 -11.429205) (xy 256.338795 -11.290428) (xy 256.370118 -11.153191)
			(xy 256.409086 -11.017927) (xy 256.455577 -10.885061) (xy 256.509445 -10.75501) (xy 256.570521 -10.628184)
			(xy 256.638611 -10.504983) (xy 256.713502 -10.385793) (xy 256.794959 -10.27099) (xy 256.882724 -10.160934)
			(xy 256.976523 -10.055973) (xy 257.076059 -9.956436) (xy 257.181019 -9.862637) (xy 257.291074 -9.774871)
			(xy 257.405876 -9.693414) (xy 257.525065 -9.618521) (xy 257.648266 -9.55043) (xy 257.775092 -9.489354)
			(xy 257.905142 -9.435484) (xy 258.038008 -9.388992) (xy 258.173272 -9.350023) (xy 258.310508 -9.318699)
			(xy 258.449285 -9.295119) (xy 258.589165 -9.279358) (xy 258.729709 -9.271465) (xy 258.800092 -9.271)
			(xy 383.601976 -9.271) (xy 383.657746 -9.270492) (xy 383.768975 -9.262159) (xy 383.87927 -9.245536)
			(xy 383.988015 -9.220718) (xy 384.094601 -9.187842) (xy 384.198432 -9.147093) (xy 384.298927 -9.098699)
			(xy 384.395525 -9.04293) (xy 384.487685 -8.980099) (xy 384.574892 -8.910555) (xy 384.656659 -8.83469)
			(xy 384.732527 -8.752926) (xy 384.802073 -8.665721) (xy 384.864907 -8.573562) (xy 384.920679 -8.476966)
			(xy 384.969076 -8.376472) (xy 385.009828 -8.272642) (xy 385.042706 -8.166058) (xy 385.067528 -8.057314)
			(xy 385.084154 -7.947019) (xy 385.092491 -7.83579) (xy 385.092956 -7.78002) (xy 385.092956 0.40005)
			(xy 385.093451 0.470432) (xy 385.101346 0.610973) (xy 385.117109 0.750851) (xy 385.14069 0.889625)
			(xy 385.172015 1.026859) (xy 385.210985 1.16212) (xy 385.257478 1.294984) (xy 385.311348 1.425032)
			(xy 385.372424 1.551855) (xy 385.440515 1.675053) (xy 385.515407 1.79424) (xy 385.596863 1.909041)
			(xy 385.684628 2.019094) (xy 385.778426 2.124052) (xy 385.877961 2.223587) (xy 385.98292 2.317383)
			(xy 386.092974 2.405148) (xy 386.207775 2.486603) (xy 386.326962 2.561494) (xy 386.450161 2.629584)
			(xy 386.576985 2.69066) (xy 386.707033 2.744528) (xy 386.839897 2.79102) (xy 386.975158 2.829989)
			(xy 387.112392 2.861313) (xy 387.251166 2.884893) (xy 387.391045 2.900655) (xy 387.531586 2.908549)
			(xy 387.601968 2.909062) (xy 456.202034 2.909062) (xy 456.272416 2.908567) (xy 456.412959 2.900673)
			(xy 456.552838 2.884911) (xy 456.691613 2.861331) (xy 456.828848 2.830006) (xy 456.96411 2.791037)
			(xy 457.096975 2.744544) (xy 457.227024 2.690676) (xy 457.353848 2.6296) (xy 457.477048 2.561509)
			(xy 457.596236 2.486618) (xy 457.711038 2.405161) (xy 457.821092 2.317396) (xy 457.926052 2.223599)
			(xy 458.025588 2.124064) (xy 458.119386 2.019104) (xy 458.207152 1.909051) (xy 458.288609 1.79425)
			(xy 458.363501 1.675062) (xy 458.431592 1.551862) (xy 458.492669 1.425039) (xy 458.546539 1.29499)
			(xy 458.593032 1.162126) (xy 458.632002 1.026863) (xy 458.663327 0.889629) (xy 458.686909 0.750854)
			(xy 458.702672 0.610975) (xy 458.710567 0.470432) (xy 458.711046 0.40005) (xy 458.711046 -4.844596)
			(xy 464.704165 -4.844596) (xy 464.704165 -4.715456) (xy 464.712115 -4.586561) (xy 464.727985 -4.458401)
			(xy 464.751714 -4.33146) (xy 464.783213 -4.206221) (xy 464.822362 -4.083158) (xy 464.869013 -3.962739)
			(xy 464.922988 -3.84542) (xy 464.984083 -3.731646) (xy 465.052066 -3.621849) (xy 465.12668 -3.516446)
			(xy 465.207641 -3.415836) (xy 465.294641 -3.320401) (xy 465.387352 -3.230502) (xy 465.485422 -3.146481)
			(xy 465.588477 -3.068657) (xy 465.696128 -2.997325) (xy 465.807967 -2.932755) (xy 465.923568 -2.875193)
			(xy 466.042493 -2.824856) (xy 466.164292 -2.781936) (xy 466.288502 -2.746595) (xy 466.414651 -2.718968)
			(xy 466.542263 -2.699159) (xy 466.670852 -2.687243) (xy 466.79993 -2.683267) (xy 466.929008 -2.687243)
			(xy 467.057597 -2.699159) (xy 467.185209 -2.718968) (xy 467.311358 -2.746595) (xy 467.435568 -2.781936)
			(xy 467.557367 -2.824856) (xy 467.676292 -2.875193) (xy 467.791893 -2.932755) (xy 467.903732 -2.997325)
			(xy 468.011383 -3.068657) (xy 468.114438 -3.146481) (xy 468.212508 -3.230502) (xy 468.305219 -3.320401)
			(xy 468.392219 -3.415836) (xy 468.47318 -3.516446) (xy 468.547794 -3.621849) (xy 468.615777 -3.731646)
			(xy 468.676872 -3.84542) (xy 468.730847 -3.962739) (xy 468.777498 -4.083158) (xy 468.816647 -4.206221)
			(xy 468.848146 -4.33146) (xy 468.871875 -4.458401) (xy 468.887745 -4.586561) (xy 468.895695 -4.715456)
			(xy 468.896192 -4.780026) (xy 468.895695 -4.844596) (xy 468.887745 -4.973491) (xy 468.871875 -5.101651)
			(xy 468.848146 -5.228592) (xy 468.816647 -5.353831) (xy 468.777498 -5.476894) (xy 468.730847 -5.597313)
			(xy 468.676872 -5.714632) (xy 468.615777 -5.828406) (xy 468.547794 -5.938203) (xy 468.47318 -6.043606)
			(xy 468.392219 -6.144216) (xy 468.305219 -6.239651) (xy 468.212508 -6.32955) (xy 468.114438 -6.413571)
			(xy 468.011383 -6.491395) (xy 467.903732 -6.562727) (xy 467.791893 -6.627297) (xy 467.676292 -6.684859)
			(xy 467.557367 -6.735196) (xy 467.435568 -6.778116) (xy 467.311358 -6.813457) (xy 467.185209 -6.841084)
			(xy 467.057597 -6.860893) (xy 466.929008 -6.872809) (xy 466.79993 -6.876786) (xy 466.670852 -6.872809)
			(xy 466.542263 -6.860893) (xy 466.414651 -6.841084) (xy 466.288502 -6.813457) (xy 466.164292 -6.778116)
			(xy 466.042493 -6.735196) (xy 465.923568 -6.684859) (xy 465.807967 -6.627297) (xy 465.696128 -6.562727)
			(xy 465.588477 -6.491395) (xy 465.485422 -6.413571) (xy 465.387352 -6.32955) (xy 465.294641 -6.239651)
			(xy 465.207641 -6.144216) (xy 465.12668 -6.043606) (xy 465.052066 -5.938203) (xy 464.984083 -5.828406)
			(xy 464.922988 -5.714632) (xy 464.869013 -5.597313) (xy 464.822362 -5.476894) (xy 464.783213 -5.353831)
			(xy 464.751714 -5.228592) (xy 464.727985 -5.101651) (xy 464.712115 -4.973491) (xy 464.704165 -4.844596)
			(xy 458.711046 -4.844596) (xy 458.711046 -7.78002) (xy 458.711555 -7.835789) (xy 458.719892 -7.947014)
			(xy 458.736517 -8.057305) (xy 458.761338 -8.166046) (xy 458.794216 -8.272628) (xy 458.834967 -8.376454)
			(xy 458.883362 -8.476945) (xy 458.939132 -8.573538) (xy 459.001965 -8.665694) (xy 459.071509 -8.752896)
			(xy 459.147375 -8.834658) (xy 459.229138 -8.910521) (xy 459.316343 -8.980062) (xy 459.4085 -9.042892)
			(xy 459.505096 -9.098659) (xy 459.605588 -9.147052) (xy 459.709416 -9.187799) (xy 459.815999 -9.220674)
			(xy 459.92474 -9.245491) (xy 460.035032 -9.262113) (xy 460.146257 -9.270446) (xy 460.202026 -9.271)
			(xy 469.799924 -9.271) (xy 469.855693 -9.270478) (xy 469.966918 -9.262141) (xy 470.07721 -9.245516)
			(xy 470.18595 -9.220695) (xy 470.292532 -9.187817) (xy 470.396359 -9.147067) (xy 470.49685 -9.098672)
			(xy 470.593444 -9.042903) (xy 470.685601 -8.980071) (xy 470.772804 -8.910528) (xy 470.854566 -8.834664)
			(xy 470.930431 -8.752901) (xy 470.999974 -8.665697) (xy 471.062805 -8.573541) (xy 471.118574 -8.476947)
			(xy 471.166969 -8.376455) (xy 471.207719 -8.272628) (xy 471.240596 -8.166046) (xy 471.265416 -8.057306)
			(xy 471.282041 -7.947014) (xy 471.290378 -7.835789) (xy 471.290904 -7.78002) (xy 471.290904 10.40003)
			(xy 471.290381 10.455799) (xy 471.282044 10.567024) (xy 471.265419 10.677315) (xy 471.240598 10.786055)
			(xy 471.20772 10.892637) (xy 471.16697 10.996464) (xy 471.118574 11.096955) (xy 471.062805 11.193548)
			(xy 470.999973 11.285705) (xy 470.930431 11.372908) (xy 470.854566 11.45467) (xy 470.772803 11.530534)
			(xy 470.6856 11.600077) (xy 470.593443 11.662908) (xy 470.49685 11.718677) (xy 470.396358 11.767072)
			(xy 470.292531 11.807822) (xy 470.18595 11.840699) (xy 470.077209 11.86552) (xy 469.966918 11.882145)
			(xy 469.855693 11.890482) (xy 469.799924 11.89101) (xy 1.999996 11.89101) (xy 1.944227 11.890488)
			(xy 1.833001 11.882153) (xy 1.722709 11.865529) (xy 1.613968 11.840709) (xy 1.507385 11.807832) (xy 1.403558 11.767083)
			(xy 1.303066 11.718688) (xy 1.206471 11.662919) (xy 1.114314 11.600087) (xy 1.027111 11.530545) (xy 0.945348 11.454679)
			(xy 0.869483 11.372916) (xy 0.79994 11.285712) (xy 0.737109 11.193555) (xy 0.68134 11.096961) (xy 0.632946 10.996469)
			(xy 0.592196 10.892641) (xy 0.55932 10.786058) (xy 0.534501 10.677317) (xy 0.517877 10.567025) (xy 0.509541 10.455799)
			(xy 0.509016 10.40003) (xy 0.509016 9.916973) (xy 385.651997 9.916973) (xy 385.651997 10.002723)
			(xy 385.659909 10.088106) (xy 385.675665 10.172396) (xy 385.699132 10.254872) (xy 385.730108 10.334831)
			(xy 385.76833 10.411591) (xy 385.813471 10.484497) (xy 385.865147 10.552926) (xy 385.922916 10.616296)
			(xy 385.986286 10.674065) (xy 386.054715 10.725741) (xy 386.127621 10.770882) (xy 386.204381 10.809104)
			(xy 386.28434 10.84008) (xy 386.366816 10.863547) (xy 386.451106 10.879303) (xy 386.536489 10.887215)
			(xy 386.622239 10.887215) (xy 386.707622 10.879303) (xy 386.791912 10.863547) (xy 386.874388 10.84008)
			(xy 386.954347 10.809104) (xy 387.031107 10.770882) (xy 387.104013 10.725741) (xy 387.172442 10.674065)
			(xy 387.235812 10.616296) (xy 387.293581 10.552926) (xy 387.345257 10.484497) (xy 387.390398 10.411591)
			(xy 387.42862 10.334831) (xy 387.459596 10.254872) (xy 387.483063 10.172396) (xy 387.498819 10.088106)
			(xy 387.506731 10.002723) (xy 387.507226 9.959848) (xy 387.506731 9.916973) (xy 392.001997 9.916973)
			(xy 392.001997 10.002723) (xy 392.009909 10.088106) (xy 392.025665 10.172396) (xy 392.049132 10.254872)
			(xy 392.080108 10.334831) (xy 392.11833 10.411591) (xy 392.163471 10.484497) (xy 392.215147 10.552926)
			(xy 392.272916 10.616296) (xy 392.336286 10.674065) (xy 392.404715 10.725741) (xy 392.477621 10.770882)
			(xy 392.554381 10.809104) (xy 392.63434 10.84008) (xy 392.716816 10.863547) (xy 392.801106 10.879303)
			(xy 392.886489 10.887215) (xy 392.972239 10.887215) (xy 393.057622 10.879303) (xy 393.141912 10.863547)
			(xy 393.224388 10.84008) (xy 393.304347 10.809104) (xy 393.381107 10.770882) (xy 393.454013 10.725741)
			(xy 393.522442 10.674065) (xy 393.585812 10.616296) (xy 393.643581 10.552926) (xy 393.695257 10.484497)
			(xy 393.740398 10.411591) (xy 393.77862 10.334831) (xy 393.809596 10.254872) (xy 393.833063 10.172396)
			(xy 393.848819 10.088106) (xy 393.856731 10.002723) (xy 393.857226 9.959848) (xy 393.856731 9.916973)
			(xy 436.390783 9.916973) (xy 436.390783 10.002723) (xy 436.398695 10.088106) (xy 436.414451 10.172396)
			(xy 436.437918 10.254872) (xy 436.468894 10.334831) (xy 436.507116 10.411591) (xy 436.552257 10.484497)
			(xy 436.603933 10.552926) (xy 436.661702 10.616296) (xy 436.725072 10.674065) (xy 436.793501 10.725741)
			(xy 436.866407 10.770882) (xy 436.943167 10.809104) (xy 437.023126 10.84008) (xy 437.105602 10.863547)
			(xy 437.189892 10.879303) (xy 437.275275 10.887215) (xy 437.361025 10.887215) (xy 437.446408 10.879303)
			(xy 437.530698 10.863547) (xy 437.613174 10.84008) (xy 437.693133 10.809104) (xy 437.769893 10.770882)
			(xy 437.842799 10.725741) (xy 437.911228 10.674065) (xy 437.974598 10.616296) (xy 438.032367 10.552926)
			(xy 438.084043 10.484497) (xy 438.129184 10.411591) (xy 438.167406 10.334831) (xy 438.198382 10.254872)
			(xy 438.221849 10.172396) (xy 438.237605 10.088106) (xy 438.245517 10.002723) (xy 438.246012 9.959848)
			(xy 438.245517 9.916973) (xy 442.740783 9.916973) (xy 442.740783 10.002723) (xy 442.748695 10.088106)
			(xy 442.764451 10.172396) (xy 442.787918 10.254872) (xy 442.818894 10.334831) (xy 442.857116 10.411591)
			(xy 442.902257 10.484497) (xy 442.953933 10.552926) (xy 443.011702 10.616296) (xy 443.075072 10.674065)
			(xy 443.143501 10.725741) (xy 443.216407 10.770882) (xy 443.293167 10.809104) (xy 443.373126 10.84008)
			(xy 443.455602 10.863547) (xy 443.539892 10.879303) (xy 443.625275 10.887215) (xy 443.711025 10.887215)
			(xy 443.796408 10.879303) (xy 443.880698 10.863547) (xy 443.963174 10.84008) (xy 444.043133 10.809104)
			(xy 444.119893 10.770882) (xy 444.192799 10.725741) (xy 444.261228 10.674065) (xy 444.324598 10.616296)
			(xy 444.382367 10.552926) (xy 444.434043 10.484497) (xy 444.479184 10.411591) (xy 444.517406 10.334831)
			(xy 444.548382 10.254872) (xy 444.571849 10.172396) (xy 444.587605 10.088106) (xy 444.595517 10.002723)
			(xy 444.596012 9.959848) (xy 444.595517 9.916973) (xy 444.587605 9.83159) (xy 444.571849 9.7473)
			(xy 444.548382 9.664824) (xy 444.517406 9.584865) (xy 444.479184 9.508105) (xy 444.434043 9.435199)
			(xy 444.382367 9.36677) (xy 444.324598 9.3034) (xy 444.261228 9.245631) (xy 444.192799 9.193955)
			(xy 444.119893 9.148814) (xy 444.043133 9.110592) (xy 443.963174 9.079616) (xy 443.880698 9.056149)
			(xy 443.796408 9.040393) (xy 443.711025 9.032481) (xy 443.625275 9.032481) (xy 443.539892 9.040393)
			(xy 443.455602 9.056149) (xy 443.373126 9.079616) (xy 443.293167 9.110592) (xy 443.216407 9.148814)
			(xy 443.143501 9.193955) (xy 443.075072 9.245631) (xy 443.011702 9.3034) (xy 442.953933 9.36677)
			(xy 442.902257 9.435199) (xy 442.857116 9.508105) (xy 442.818894 9.584865) (xy 442.787918 9.664824)
			(xy 442.764451 9.7473) (xy 442.748695 9.83159) (xy 442.740783 9.916973) (xy 438.245517 9.916973)
			(xy 438.237605 9.83159) (xy 438.221849 9.7473) (xy 438.198382 9.664824) (xy 438.167406 9.584865)
			(xy 438.129184 9.508105) (xy 438.084043 9.435199) (xy 438.032367 9.36677) (xy 437.974598 9.3034)
			(xy 437.911228 9.245631) (xy 437.842799 9.193955) (xy 437.769893 9.148814) (xy 437.693133 9.110592)
			(xy 437.613174 9.079616) (xy 437.530698 9.056149) (xy 437.446408 9.040393) (xy 437.361025 9.032481)
			(xy 437.275275 9.032481) (xy 437.189892 9.040393) (xy 437.105602 9.056149) (xy 437.023126 9.079616)
			(xy 436.943167 9.110592) (xy 436.866407 9.148814) (xy 436.793501 9.193955) (xy 436.725072 9.245631)
			(xy 436.661702 9.3034) (xy 436.603933 9.36677) (xy 436.552257 9.435199) (xy 436.507116 9.508105)
			(xy 436.468894 9.584865) (xy 436.437918 9.664824) (xy 436.414451 9.7473) (xy 436.398695 9.83159)
			(xy 436.390783 9.916973) (xy 393.856731 9.916973) (xy 393.848819 9.83159) (xy 393.833063 9.7473)
			(xy 393.809596 9.664824) (xy 393.77862 9.584865) (xy 393.740398 9.508105) (xy 393.695257 9.435199)
			(xy 393.643581 9.36677) (xy 393.585812 9.3034) (xy 393.522442 9.245631) (xy 393.454013 9.193955)
			(xy 393.381107 9.148814) (xy 393.304347 9.110592) (xy 393.224388 9.079616) (xy 393.141912 9.056149)
			(xy 393.057622 9.040393) (xy 392.972239 9.032481) (xy 392.886489 9.032481) (xy 392.801106 9.040393)
			(xy 392.716816 9.056149) (xy 392.63434 9.079616) (xy 392.554381 9.110592) (xy 392.477621 9.148814)
			(xy 392.404715 9.193955) (xy 392.336286 9.245631) (xy 392.272916 9.3034) (xy 392.215147 9.36677)
			(xy 392.163471 9.435199) (xy 392.11833 9.508105) (xy 392.080108 9.584865) (xy 392.049132 9.664824)
			(xy 392.025665 9.7473) (xy 392.009909 9.83159) (xy 392.001997 9.916973) (xy 387.506731 9.916973)
			(xy 387.498819 9.83159) (xy 387.483063 9.7473) (xy 387.459596 9.664824) (xy 387.42862 9.584865) (xy 387.390398 9.508105)
			(xy 387.345257 9.435199) (xy 387.293581 9.36677) (xy 387.235812 9.3034) (xy 387.172442 9.245631)
			(xy 387.104013 9.193955) (xy 387.031107 9.148814) (xy 386.954347 9.110592) (xy 386.874388 9.079616)
			(xy 386.791912 9.056149) (xy 386.707622 9.040393) (xy 386.622239 9.032481) (xy 386.536489 9.032481)
			(xy 386.451106 9.040393) (xy 386.366816 9.056149) (xy 386.28434 9.079616) (xy 386.204381 9.110592)
			(xy 386.127621 9.148814) (xy 386.054715 9.193955) (xy 385.986286 9.245631) (xy 385.922916 9.3034)
			(xy 385.865147 9.36677) (xy 385.813471 9.435199) (xy 385.76833 9.508105) (xy 385.730108 9.584865)
			(xy 385.699132 9.664824) (xy 385.675665 9.7473) (xy 385.659909 9.83159) (xy 385.651997 9.916973)
			(xy 0.509016 9.916973) (xy 0.509016 7.335466) (xy 2.904225 7.335466) (xy 2.904225 7.464606) (xy 2.912175 7.593501)
			(xy 2.928045 7.721661) (xy 2.951774 7.848602) (xy 2.983273 7.973841) (xy 3.022422 8.096904) (xy 3.069073 8.217323)
			(xy 3.123048 8.334642) (xy 3.184143 8.448416) (xy 3.252126 8.558213) (xy 3.32674 8.663616) (xy 3.407701 8.764226)
			(xy 3.494701 8.859661) (xy 3.587412 8.94956) (xy 3.685482 9.033581) (xy 3.788537 9.111405) (xy 3.896188 9.182737)
			(xy 4.008027 9.247307) (xy 4.123628 9.304869) (xy 4.242553 9.355206) (xy 4.364352 9.398126) (xy 4.488562 9.433467)
			(xy 4.614711 9.461094) (xy 4.742323 9.480903) (xy 4.870912 9.492819) (xy 4.99999 9.496796) (xy 5.129068 9.492819)
			(xy 5.257657 9.480903) (xy 5.385269 9.461094) (xy 5.511418 9.433467) (xy 5.635628 9.398126) (xy 5.757427 9.355206)
			(xy 5.876352 9.304869) (xy 5.991953 9.247307) (xy 6.103792 9.182737) (xy 6.211443 9.111405) (xy 6.314498 9.033581)
			(xy 6.412568 8.94956) (xy 6.505279 8.859661) (xy 6.51416 8.849919) (xy 208.661241 8.849919) (xy 208.661241 8.935669)
			(xy 208.669153 9.021052) (xy 208.684909 9.105342) (xy 208.708376 9.187818) (xy 208.739352 9.267777)
			(xy 208.777574 9.344537) (xy 208.822715 9.417443) (xy 208.874391 9.485872) (xy 208.93216 9.549242)
			(xy 208.99553 9.607011) (xy 209.063959 9.658687) (xy 209.136865 9.703828) (xy 209.213625 9.74205)
			(xy 209.293584 9.773026) (xy 209.37606 9.796493) (xy 209.46035 9.812249) (xy 209.545733 9.820161)
			(xy 209.631483 9.820161) (xy 209.716866 9.812249) (xy 209.801156 9.796493) (xy 209.883632 9.773026)
			(xy 209.963591 9.74205) (xy 210.040351 9.703828) (xy 210.113257 9.658687) (xy 210.181686 9.607011)
			(xy 210.245056 9.549242) (xy 210.302825 9.485872) (xy 210.354501 9.417443) (xy 210.399642 9.344537)
			(xy 210.437864 9.267777) (xy 210.46884 9.187818) (xy 210.492307 9.105342) (xy 210.508063 9.021052)
			(xy 210.515975 8.935669) (xy 210.51647 8.892794) (xy 210.515975 8.849919) (xy 215.011241 8.849919)
			(xy 215.011241 8.935669) (xy 215.019153 9.021052) (xy 215.034909 9.105342) (xy 215.058376 9.187818)
			(xy 215.089352 9.267777) (xy 215.127574 9.344537) (xy 215.172715 9.417443) (xy 215.224391 9.485872)
			(xy 215.28216 9.549242) (xy 215.34553 9.607011) (xy 215.413959 9.658687) (xy 215.486865 9.703828)
			(xy 215.563625 9.74205) (xy 215.643584 9.773026) (xy 215.72606 9.796493) (xy 215.81035 9.812249)
			(xy 215.895733 9.820161) (xy 215.981483 9.820161) (xy 216.066866 9.812249) (xy 216.151156 9.796493)
			(xy 216.233632 9.773026) (xy 216.313591 9.74205) (xy 216.390351 9.703828) (xy 216.463257 9.658687)
			(xy 216.531686 9.607011) (xy 216.595056 9.549242) (xy 216.652825 9.485872) (xy 216.704501 9.417443)
			(xy 216.749642 9.344537) (xy 216.787864 9.267777) (xy 216.81884 9.187818) (xy 216.842307 9.105342)
			(xy 216.858063 9.021052) (xy 216.865975 8.935669) (xy 216.86647 8.892794) (xy 216.865975 8.849919)
			(xy 296.143921 8.849919) (xy 296.143921 8.935669) (xy 296.151833 9.021052) (xy 296.167589 9.105342)
			(xy 296.191056 9.187818) (xy 296.222032 9.267777) (xy 296.260254 9.344537) (xy 296.305395 9.417443)
			(xy 296.357071 9.485872) (xy 296.41484 9.549242) (xy 296.47821 9.607011) (xy 296.546639 9.658687)
			(xy 296.619545 9.703828) (xy 296.696305 9.74205) (xy 296.776264 9.773026) (xy 296.85874 9.796493)
			(xy 296.94303 9.812249) (xy 297.028413 9.820161) (xy 297.114163 9.820161) (xy 297.199546 9.812249)
			(xy 297.283836 9.796493) (xy 297.366312 9.773026) (xy 297.446271 9.74205) (xy 297.523031 9.703828)
			(xy 297.595937 9.658687) (xy 297.664366 9.607011) (xy 297.727736 9.549242) (xy 297.785505 9.485872)
			(xy 297.837181 9.417443) (xy 297.882322 9.344537) (xy 297.920544 9.267777) (xy 297.95152 9.187818)
			(xy 297.974987 9.105342) (xy 297.990743 9.021052) (xy 297.998655 8.935669) (xy 297.99915 8.892794)
			(xy 297.998655 8.849919) (xy 302.493921 8.849919) (xy 302.493921 8.935669) (xy 302.501833 9.021052)
			(xy 302.517589 9.105342) (xy 302.541056 9.187818) (xy 302.572032 9.267777) (xy 302.610254 9.344537)
			(xy 302.655395 9.417443) (xy 302.707071 9.485872) (xy 302.76484 9.549242) (xy 302.82821 9.607011)
			(xy 302.896639 9.658687) (xy 302.969545 9.703828) (xy 303.046305 9.74205) (xy 303.126264 9.773026)
			(xy 303.20874 9.796493) (xy 303.29303 9.812249) (xy 303.378413 9.820161) (xy 303.464163 9.820161)
			(xy 303.549546 9.812249) (xy 303.633836 9.796493) (xy 303.716312 9.773026) (xy 303.796271 9.74205)
			(xy 303.873031 9.703828) (xy 303.945937 9.658687) (xy 304.014366 9.607011) (xy 304.077736 9.549242)
			(xy 304.135505 9.485872) (xy 304.187181 9.417443) (xy 304.232322 9.344537) (xy 304.270544 9.267777)
			(xy 304.30152 9.187818) (xy 304.324987 9.105342) (xy 304.340743 9.021052) (xy 304.348655 8.935669)
			(xy 304.34915 8.892794) (xy 304.348655 8.849919) (xy 311.155321 8.849919) (xy 311.155321 8.935669)
			(xy 311.163233 9.021052) (xy 311.178989 9.105342) (xy 311.202456 9.187818) (xy 311.233432 9.267777)
			(xy 311.271654 9.344537) (xy 311.316795 9.417443) (xy 311.368471 9.485872) (xy 311.42624 9.549242)
			(xy 311.48961 9.607011) (xy 311.558039 9.658687) (xy 311.630945 9.703828) (xy 311.707705 9.74205)
			(xy 311.787664 9.773026) (xy 311.87014 9.796493) (xy 311.95443 9.812249) (xy 312.039813 9.820161)
			(xy 312.125563 9.820161) (xy 312.210946 9.812249) (xy 312.295236 9.796493) (xy 312.377712 9.773026)
			(xy 312.457671 9.74205) (xy 312.534431 9.703828) (xy 312.607337 9.658687) (xy 312.675766 9.607011)
			(xy 312.739136 9.549242) (xy 312.796905 9.485872) (xy 312.848581 9.417443) (xy 312.893722 9.344537)
			(xy 312.931944 9.267777) (xy 312.96292 9.187818) (xy 312.986387 9.105342) (xy 313.002143 9.021052)
			(xy 313.010055 8.935669) (xy 313.01055 8.892794) (xy 313.010055 8.849919) (xy 317.505321 8.849919)
			(xy 317.505321 8.935669) (xy 317.513233 9.021052) (xy 317.528989 9.105342) (xy 317.552456 9.187818)
			(xy 317.583432 9.267777) (xy 317.621654 9.344537) (xy 317.666795 9.417443) (xy 317.718471 9.485872)
			(xy 317.77624 9.549242) (xy 317.83961 9.607011) (xy 317.908039 9.658687) (xy 317.980945 9.703828)
			(xy 318.057705 9.74205) (xy 318.137664 9.773026) (xy 318.22014 9.796493) (xy 318.30443 9.812249)
			(xy 318.389813 9.820161) (xy 318.475563 9.820161) (xy 318.560946 9.812249) (xy 318.645236 9.796493)
			(xy 318.727712 9.773026) (xy 318.807671 9.74205) (xy 318.884431 9.703828) (xy 318.957337 9.658687)
			(xy 319.025766 9.607011) (xy 319.089136 9.549242) (xy 319.146905 9.485872) (xy 319.198581 9.417443)
			(xy 319.243722 9.344537) (xy 319.281944 9.267777) (xy 319.31292 9.187818) (xy 319.336387 9.105342)
			(xy 319.352143 9.021052) (xy 319.360055 8.935669) (xy 319.36055 8.892794) (xy 319.360055 8.849919)
			(xy 361.894107 8.849919) (xy 361.894107 8.935669) (xy 361.902019 9.021052) (xy 361.917775 9.105342)
			(xy 361.941242 9.187818) (xy 361.972218 9.267777) (xy 362.01044 9.344537) (xy 362.055581 9.417443)
			(xy 362.107257 9.485872) (xy 362.165026 9.549242) (xy 362.228396 9.607011) (xy 362.296825 9.658687)
			(xy 362.369731 9.703828) (xy 362.446491 9.74205) (xy 362.52645 9.773026) (xy 362.608926 9.796493)
			(xy 362.693216 9.812249) (xy 362.778599 9.820161) (xy 362.864349 9.820161) (xy 362.949732 9.812249)
			(xy 363.034022 9.796493) (xy 363.116498 9.773026) (xy 363.196457 9.74205) (xy 363.273217 9.703828)
			(xy 363.346123 9.658687) (xy 363.414552 9.607011) (xy 363.477922 9.549242) (xy 363.535691 9.485872)
			(xy 363.587367 9.417443) (xy 363.632508 9.344537) (xy 363.67073 9.267777) (xy 363.701706 9.187818)
			(xy 363.725173 9.105342) (xy 363.740929 9.021052) (xy 363.748841 8.935669) (xy 363.749336 8.892794)
			(xy 363.748841 8.849919) (xy 368.244107 8.849919) (xy 368.244107 8.935669) (xy 368.252019 9.021052)
			(xy 368.267775 9.105342) (xy 368.291242 9.187818) (xy 368.322218 9.267777) (xy 368.36044 9.344537)
			(xy 368.405581 9.417443) (xy 368.457257 9.485872) (xy 368.515026 9.549242) (xy 368.578396 9.607011)
			(xy 368.646825 9.658687) (xy 368.719731 9.703828) (xy 368.796491 9.74205) (xy 368.87645 9.773026)
			(xy 368.958926 9.796493) (xy 369.043216 9.812249) (xy 369.128599 9.820161) (xy 369.214349 9.820161)
			(xy 369.299732 9.812249) (xy 369.384022 9.796493) (xy 369.466498 9.773026) (xy 369.546457 9.74205)
			(xy 369.623217 9.703828) (xy 369.696123 9.658687) (xy 369.764552 9.607011) (xy 369.827922 9.549242)
			(xy 369.885691 9.485872) (xy 369.937367 9.417443) (xy 369.982508 9.344537) (xy 370.02073 9.267777)
			(xy 370.051706 9.187818) (xy 370.075173 9.105342) (xy 370.090929 9.021052) (xy 370.098841 8.935669)
			(xy 370.099336 8.892794) (xy 370.098841 8.849919) (xy 370.090929 8.764536) (xy 370.075173 8.680246)
			(xy 370.051706 8.59777) (xy 370.02073 8.517811) (xy 369.982508 8.441051) (xy 369.937367 8.368145)
			(xy 369.885691 8.299716) (xy 369.827922 8.236346) (xy 369.764552 8.178577) (xy 369.696123 8.126901)
			(xy 369.623217 8.08176) (xy 369.546457 8.043538) (xy 369.466498 8.012562) (xy 369.384022 7.989095)
			(xy 369.299732 7.973339) (xy 369.214349 7.965427) (xy 369.128599 7.965427) (xy 369.043216 7.973339)
			(xy 368.958926 7.989095) (xy 368.87645 8.012562) (xy 368.796491 8.043538) (xy 368.719731 8.08176)
			(xy 368.646825 8.126901) (xy 368.578396 8.178577) (xy 368.515026 8.236346) (xy 368.457257 8.299716)
			(xy 368.405581 8.368145) (xy 368.36044 8.441051) (xy 368.322218 8.517811) (xy 368.291242 8.59777)
			(xy 368.267775 8.680246) (xy 368.252019 8.764536) (xy 368.244107 8.849919) (xy 363.748841 8.849919)
			(xy 363.740929 8.764536) (xy 363.725173 8.680246) (xy 363.701706 8.59777) (xy 363.67073 8.517811)
			(xy 363.632508 8.441051) (xy 363.587367 8.368145) (xy 363.535691 8.299716) (xy 363.477922 8.236346)
			(xy 363.414552 8.178577) (xy 363.346123 8.126901) (xy 363.273217 8.08176) (xy 363.196457 8.043538)
			(xy 363.116498 8.012562) (xy 363.034022 7.989095) (xy 362.949732 7.973339) (xy 362.864349 7.965427)
			(xy 362.778599 7.965427) (xy 362.693216 7.973339) (xy 362.608926 7.989095) (xy 362.52645 8.012562)
			(xy 362.446491 8.043538) (xy 362.369731 8.08176) (xy 362.296825 8.126901) (xy 362.228396 8.178577)
			(xy 362.165026 8.236346) (xy 362.107257 8.299716) (xy 362.055581 8.368145) (xy 362.01044 8.441051)
			(xy 361.972218 8.517811) (xy 361.941242 8.59777) (xy 361.917775 8.680246) (xy 361.902019 8.764536)
			(xy 361.894107 8.849919) (xy 319.360055 8.849919) (xy 319.352143 8.764536) (xy 319.336387 8.680246)
			(xy 319.31292 8.59777) (xy 319.281944 8.517811) (xy 319.243722 8.441051) (xy 319.198581 8.368145)
			(xy 319.146905 8.299716) (xy 319.089136 8.236346) (xy 319.025766 8.178577) (xy 318.957337 8.126901)
			(xy 318.884431 8.08176) (xy 318.807671 8.043538) (xy 318.727712 8.012562) (xy 318.645236 7.989095)
			(xy 318.560946 7.973339) (xy 318.475563 7.965427) (xy 318.389813 7.965427) (xy 318.30443 7.973339)
			(xy 318.22014 7.989095) (xy 318.137664 8.012562) (xy 318.057705 8.043538) (xy 317.980945 8.08176)
			(xy 317.908039 8.126901) (xy 317.83961 8.178577) (xy 317.77624 8.236346) (xy 317.718471 8.299716)
			(xy 317.666795 8.368145) (xy 317.621654 8.441051) (xy 317.583432 8.517811) (xy 317.552456 8.59777)
			(xy 317.528989 8.680246) (xy 317.513233 8.764536) (xy 317.505321 8.849919) (xy 313.010055 8.849919)
			(xy 313.002143 8.764536) (xy 312.986387 8.680246) (xy 312.96292 8.59777) (xy 312.931944 8.517811)
			(xy 312.893722 8.441051) (xy 312.848581 8.368145) (xy 312.796905 8.299716) (xy 312.739136 8.236346)
			(xy 312.675766 8.178577) (xy 312.607337 8.126901) (xy 312.534431 8.08176) (xy 312.457671 8.043538)
			(xy 312.377712 8.012562) (xy 312.295236 7.989095) (xy 312.210946 7.973339) (xy 312.125563 7.965427)
			(xy 312.039813 7.965427) (xy 311.95443 7.973339) (xy 311.87014 7.989095) (xy 311.787664 8.012562)
			(xy 311.707705 8.043538) (xy 311.630945 8.08176) (xy 311.558039 8.126901) (xy 311.48961 8.178577)
			(xy 311.42624 8.236346) (xy 311.368471 8.299716) (xy 311.316795 8.368145) (xy 311.271654 8.441051)
			(xy 311.233432 8.517811) (xy 311.202456 8.59777) (xy 311.178989 8.680246) (xy 311.163233 8.764536)
			(xy 311.155321 8.849919) (xy 304.348655 8.849919) (xy 304.340743 8.764536) (xy 304.324987 8.680246)
			(xy 304.30152 8.59777) (xy 304.270544 8.517811) (xy 304.232322 8.441051) (xy 304.187181 8.368145)
			(xy 304.135505 8.299716) (xy 304.077736 8.236346) (xy 304.014366 8.178577) (xy 303.945937 8.126901)
			(xy 303.873031 8.08176) (xy 303.796271 8.043538) (xy 303.716312 8.012562) (xy 303.633836 7.989095)
			(xy 303.549546 7.973339) (xy 303.464163 7.965427) (xy 303.378413 7.965427) (xy 303.29303 7.973339)
			(xy 303.20874 7.989095) (xy 303.126264 8.012562) (xy 303.046305 8.043538) (xy 302.969545 8.08176)
			(xy 302.896639 8.126901) (xy 302.82821 8.178577) (xy 302.76484 8.236346) (xy 302.707071 8.299716)
			(xy 302.655395 8.368145) (xy 302.610254 8.441051) (xy 302.572032 8.517811) (xy 302.541056 8.59777)
			(xy 302.517589 8.680246) (xy 302.501833 8.764536) (xy 302.493921 8.849919) (xy 297.998655 8.849919)
			(xy 297.990743 8.764536) (xy 297.974987 8.680246) (xy 297.95152 8.59777) (xy 297.920544 8.517811)
			(xy 297.882322 8.441051) (xy 297.837181 8.368145) (xy 297.785505 8.299716) (xy 297.727736 8.236346)
			(xy 297.664366 8.178577) (xy 297.595937 8.126901) (xy 297.523031 8.08176) (xy 297.446271 8.043538)
			(xy 297.366312 8.012562) (xy 297.283836 7.989095) (xy 297.199546 7.973339) (xy 297.114163 7.965427)
			(xy 297.028413 7.965427) (xy 296.94303 7.973339) (xy 296.85874 7.989095) (xy 296.776264 8.012562)
			(xy 296.696305 8.043538) (xy 296.619545 8.08176) (xy 296.546639 8.126901) (xy 296.47821 8.178577)
			(xy 296.41484 8.236346) (xy 296.357071 8.299716) (xy 296.305395 8.368145) (xy 296.260254 8.441051)
			(xy 296.222032 8.517811) (xy 296.191056 8.59777) (xy 296.167589 8.680246) (xy 296.151833 8.764536)
			(xy 296.143921 8.849919) (xy 216.865975 8.849919) (xy 216.858063 8.764536) (xy 216.842307 8.680246)
			(xy 216.81884 8.59777) (xy 216.787864 8.517811) (xy 216.749642 8.441051) (xy 216.704501 8.368145)
			(xy 216.652825 8.299716) (xy 216.595056 8.236346) (xy 216.531686 8.178577) (xy 216.463257 8.126901)
			(xy 216.390351 8.08176) (xy 216.313591 8.043538) (xy 216.233632 8.012562) (xy 216.151156 7.989095)
			(xy 216.066866 7.973339) (xy 215.981483 7.965427) (xy 215.895733 7.965427) (xy 215.81035 7.973339)
			(xy 215.72606 7.989095) (xy 215.643584 8.012562) (xy 215.563625 8.043538) (xy 215.486865 8.08176)
			(xy 215.413959 8.126901) (xy 215.34553 8.178577) (xy 215.28216 8.236346) (xy 215.224391 8.299716)
			(xy 215.172715 8.368145) (xy 215.127574 8.441051) (xy 215.089352 8.517811) (xy 215.058376 8.59777)
			(xy 215.034909 8.680246) (xy 215.019153 8.764536) (xy 215.011241 8.849919) (xy 210.515975 8.849919)
			(xy 210.508063 8.764536) (xy 210.492307 8.680246) (xy 210.46884 8.59777) (xy 210.437864 8.517811)
			(xy 210.399642 8.441051) (xy 210.354501 8.368145) (xy 210.302825 8.299716) (xy 210.245056 8.236346)
			(xy 210.181686 8.178577) (xy 210.113257 8.126901) (xy 210.040351 8.08176) (xy 209.963591 8.043538)
			(xy 209.883632 8.012562) (xy 209.801156 7.989095) (xy 209.716866 7.973339) (xy 209.631483 7.965427)
			(xy 209.545733 7.965427) (xy 209.46035 7.973339) (xy 209.37606 7.989095) (xy 209.293584 8.012562)
			(xy 209.213625 8.043538) (xy 209.136865 8.08176) (xy 209.063959 8.126901) (xy 208.99553 8.178577)
			(xy 208.93216 8.236346) (xy 208.874391 8.299716) (xy 208.822715 8.368145) (xy 208.777574 8.441051)
			(xy 208.739352 8.517811) (xy 208.708376 8.59777) (xy 208.684909 8.680246) (xy 208.669153 8.764536)
			(xy 208.661241 8.849919) (xy 6.51416 8.849919) (xy 6.592279 8.764226) (xy 6.67324 8.663616) (xy 6.747854 8.558213)
			(xy 6.815837 8.448416) (xy 6.876932 8.334642) (xy 6.930907 8.217323) (xy 6.977558 8.096904) (xy 7.016707 7.973841)
			(xy 7.048206 7.848602) (xy 7.071935 7.721661) (xy 7.087805 7.593501) (xy 7.095755 7.464606) (xy 7.096252 7.400036)
			(xy 7.095755 7.335466) (xy 7.092973 7.290359) (xy 93.985575 7.290359) (xy 93.985575 7.376109) (xy 93.993487 7.461492)
			(xy 94.009243 7.545782) (xy 94.03271 7.628258) (xy 94.063686 7.708217) (xy 94.101908 7.784977) (xy 94.147049 7.857883)
			(xy 94.198725 7.926312) (xy 94.256494 7.989682) (xy 94.319864 8.047451) (xy 94.388293 8.099127) (xy 94.461199 8.144268)
			(xy 94.537959 8.18249) (xy 94.617918 8.213466) (xy 94.700394 8.236933) (xy 94.784684 8.252689) (xy 94.870067 8.260601)
			(xy 94.955817 8.260601) (xy 95.0412 8.252689) (xy 95.12549 8.236933) (xy 95.207966 8.213466) (xy 95.287925 8.18249)
			(xy 95.364685 8.144268) (xy 95.437591 8.099127) (xy 95.50602 8.047451) (xy 95.56939 7.989682) (xy 95.627159 7.926312)
			(xy 95.678835 7.857883) (xy 95.723976 7.784977) (xy 95.762198 7.708217) (xy 95.793174 7.628258) (xy 95.816641 7.545782)
			(xy 95.832397 7.461492) (xy 95.840309 7.376109) (xy 95.840804 7.333234) (xy 95.840309 7.290359) (xy 100.335575 7.290359)
			(xy 100.335575 7.376109) (xy 100.343487 7.461492) (xy 100.359243 7.545782) (xy 100.38271 7.628258)
			(xy 100.413686 7.708217) (xy 100.451908 7.784977) (xy 100.497049 7.857883) (xy 100.548725 7.926312)
			(xy 100.606494 7.989682) (xy 100.669864 8.047451) (xy 100.738293 8.099127) (xy 100.811199 8.144268)
			(xy 100.887959 8.18249) (xy 100.967918 8.213466) (xy 101.050394 8.236933) (xy 101.134684 8.252689)
			(xy 101.220067 8.260601) (xy 101.305817 8.260601) (xy 101.3912 8.252689) (xy 101.47549 8.236933)
			(xy 101.557966 8.213466) (xy 101.637925 8.18249) (xy 101.714685 8.144268) (xy 101.787591 8.099127)
			(xy 101.85602 8.047451) (xy 101.91939 7.989682) (xy 101.977159 7.926312) (xy 102.028835 7.857883)
			(xy 102.073976 7.784977) (xy 102.112198 7.708217) (xy 102.143174 7.628258) (xy 102.166641 7.545782)
			(xy 102.182397 7.461492) (xy 102.190309 7.376109) (xy 102.190804 7.333234) (xy 102.190309 7.290359)
			(xy 181.468255 7.290359) (xy 181.468255 7.376109) (xy 181.476167 7.461492) (xy 181.491923 7.545782)
			(xy 181.51539 7.628258) (xy 181.546366 7.708217) (xy 181.584588 7.784977) (xy 181.629729 7.857883)
			(xy 181.681405 7.926312) (xy 181.739174 7.989682) (xy 181.802544 8.047451) (xy 181.870973 8.099127)
			(xy 181.943879 8.144268) (xy 182.020639 8.18249) (xy 182.100598 8.213466) (xy 182.183074 8.236933)
			(xy 182.267364 8.252689) (xy 182.352747 8.260601) (xy 182.438497 8.260601) (xy 182.52388 8.252689)
			(xy 182.60817 8.236933) (xy 182.690646 8.213466) (xy 182.770605 8.18249) (xy 182.847365 8.144268)
			(xy 182.920271 8.099127) (xy 182.9887 8.047451) (xy 183.05207 7.989682) (xy 183.109839 7.926312)
			(xy 183.161515 7.857883) (xy 183.206656 7.784977) (xy 183.244878 7.708217) (xy 183.275854 7.628258)
			(xy 183.299321 7.545782) (xy 183.315077 7.461492) (xy 183.322989 7.376109) (xy 183.323484 7.333234)
			(xy 183.322989 7.290359) (xy 187.818255 7.290359) (xy 187.818255 7.376109) (xy 187.826167 7.461492)
			(xy 187.841923 7.545782) (xy 187.86539 7.628258) (xy 187.896366 7.708217) (xy 187.934588 7.784977)
			(xy 187.979729 7.857883) (xy 188.031405 7.926312) (xy 188.089174 7.989682) (xy 188.152544 8.047451)
			(xy 188.220973 8.099127) (xy 188.293879 8.144268) (xy 188.370639 8.18249) (xy 188.450598 8.213466)
			(xy 188.533074 8.236933) (xy 188.617364 8.252689) (xy 188.702747 8.260601) (xy 188.788497 8.260601)
			(xy 188.87388 8.252689) (xy 188.95817 8.236933) (xy 189.040646 8.213466) (xy 189.120605 8.18249)
			(xy 189.197365 8.144268) (xy 189.270271 8.099127) (xy 189.3387 8.047451) (xy 189.40207 7.989682)
			(xy 189.459839 7.926312) (xy 189.511515 7.857883) (xy 189.556656 7.784977) (xy 189.594878 7.708217)
			(xy 189.625854 7.628258) (xy 189.649321 7.545782) (xy 189.665077 7.461492) (xy 189.672989 7.376109)
			(xy 189.673484 7.333234) (xy 189.672989 7.290359) (xy 189.665077 7.204976) (xy 189.649321 7.120686)
			(xy 189.625854 7.03821) (xy 189.594878 6.958251) (xy 189.556656 6.881491) (xy 189.511515 6.808585)
			(xy 189.459839 6.740156) (xy 189.40207 6.676786) (xy 189.3387 6.619017) (xy 189.270271 6.567341)
			(xy 189.197365 6.5222) (xy 189.120605 6.483978) (xy 189.040646 6.453002) (xy 188.95817 6.429535)
			(xy 188.87388 6.413779) (xy 188.788497 6.405867) (xy 188.702747 6.405867) (xy 188.617364 6.413779)
			(xy 188.533074 6.429535) (xy 188.450598 6.453002) (xy 188.370639 6.483978) (xy 188.293879 6.5222)
			(xy 188.220973 6.567341) (xy 188.152544 6.619017) (xy 188.089174 6.676786) (xy 188.031405 6.740156)
			(xy 187.979729 6.808585) (xy 187.934588 6.881491) (xy 187.896366 6.958251) (xy 187.86539 7.03821)
			(xy 187.841923 7.120686) (xy 187.826167 7.204976) (xy 187.818255 7.290359) (xy 183.322989 7.290359)
			(xy 183.315077 7.204976) (xy 183.299321 7.120686) (xy 183.275854 7.03821) (xy 183.244878 6.958251)
			(xy 183.206656 6.881491) (xy 183.161515 6.808585) (xy 183.109839 6.740156) (xy 183.05207 6.676786)
			(xy 182.9887 6.619017) (xy 182.920271 6.567341) (xy 182.847365 6.5222) (xy 182.770605 6.483978) (xy 182.690646 6.453002)
			(xy 182.60817 6.429535) (xy 182.52388 6.413779) (xy 182.438497 6.405867) (xy 182.352747 6.405867)
			(xy 182.267364 6.413779) (xy 182.183074 6.429535) (xy 182.100598 6.453002) (xy 182.020639 6.483978)
			(xy 181.943879 6.5222) (xy 181.870973 6.567341) (xy 181.802544 6.619017) (xy 181.739174 6.676786)
			(xy 181.681405 6.740156) (xy 181.629729 6.808585) (xy 181.584588 6.881491) (xy 181.546366 6.958251)
			(xy 181.51539 7.03821) (xy 181.491923 7.120686) (xy 181.476167 7.204976) (xy 181.468255 7.290359)
			(xy 102.190309 7.290359) (xy 102.182397 7.204976) (xy 102.166641 7.120686) (xy 102.143174 7.03821)
			(xy 102.112198 6.958251) (xy 102.073976 6.881491) (xy 102.028835 6.808585) (xy 101.977159 6.740156)
			(xy 101.91939 6.676786) (xy 101.85602 6.619017) (xy 101.787591 6.567341) (xy 101.714685 6.5222) (xy 101.637925 6.483978)
			(xy 101.557966 6.453002) (xy 101.47549 6.429535) (xy 101.3912 6.413779) (xy 101.305817 6.405867)
			(xy 101.220067 6.405867) (xy 101.134684 6.413779) (xy 101.050394 6.429535) (xy 100.967918 6.453002)
			(xy 100.887959 6.483978) (xy 100.811199 6.5222) (xy 100.738293 6.567341) (xy 100.669864 6.619017)
			(xy 100.606494 6.676786) (xy 100.548725 6.740156) (xy 100.497049 6.808585) (xy 100.451908 6.881491)
			(xy 100.413686 6.958251) (xy 100.38271 7.03821) (xy 100.359243 7.120686) (xy 100.343487 7.204976)
			(xy 100.335575 7.290359) (xy 95.840309 7.290359) (xy 95.832397 7.204976) (xy 95.816641 7.120686)
			(xy 95.793174 7.03821) (xy 95.762198 6.958251) (xy 95.723976 6.881491) (xy 95.678835 6.808585) (xy 95.627159 6.740156)
			(xy 95.56939 6.676786) (xy 95.50602 6.619017) (xy 95.437591 6.567341) (xy 95.364685 6.5222) (xy 95.287925 6.483978)
			(xy 95.207966 6.453002) (xy 95.12549 6.429535) (xy 95.0412 6.413779) (xy 94.955817 6.405867) (xy 94.870067 6.405867)
			(xy 94.784684 6.413779) (xy 94.700394 6.429535) (xy 94.617918 6.453002) (xy 94.537959 6.483978) (xy 94.461199 6.5222)
			(xy 94.388293 6.567341) (xy 94.319864 6.619017) (xy 94.256494 6.676786) (xy 94.198725 6.740156) (xy 94.147049 6.808585)
			(xy 94.101908 6.881491) (xy 94.063686 6.958251) (xy 94.03271 7.03821) (xy 94.009243 7.120686) (xy 93.993487 7.204976)
			(xy 93.985575 7.290359) (xy 7.092973 7.290359) (xy 7.087805 7.206571) (xy 7.071935 7.078411) (xy 7.048206 6.95147)
			(xy 7.016707 6.826231) (xy 6.977558 6.703168) (xy 6.930907 6.582749) (xy 6.876932 6.46543) (xy 6.815837 6.351656)
			(xy 6.747854 6.241859) (xy 6.67324 6.136456) (xy 6.592279 6.035846) (xy 6.505279 5.940411) (xy 6.412568 5.850512)
			(xy 6.314498 5.766491) (xy 6.211443 5.688667) (xy 6.103792 5.617335) (xy 5.991953 5.552765) (xy 5.876352 5.495203)
			(xy 5.757427 5.444866) (xy 5.635628 5.401946) (xy 5.511418 5.366605) (xy 5.385269 5.338978) (xy 5.257657 5.319169)
			(xy 5.129068 5.307253) (xy 4.99999 5.303277) (xy 4.870912 5.307253) (xy 4.742323 5.319169) (xy 4.614711 5.338978)
			(xy 4.488562 5.366605) (xy 4.364352 5.401946) (xy 4.242553 5.444866) (xy 4.123628 5.495203) (xy 4.008027 5.552765)
			(xy 3.896188 5.617335) (xy 3.788537 5.688667) (xy 3.685482 5.766491) (xy 3.587412 5.850512) (xy 3.494701 5.940411)
			(xy 3.407701 6.035846) (xy 3.32674 6.136456) (xy 3.252126 6.241859) (xy 3.184143 6.351656) (xy 3.123048 6.46543)
			(xy 3.069073 6.582749) (xy 3.022422 6.703168) (xy 2.983273 6.826231) (xy 2.951774 6.95147) (xy 2.928045 7.078411)
			(xy 2.912175 7.206571) (xy 2.904225 7.335466) (xy 0.509016 7.335466) (xy 0.509016 4.750359) (xy 93.985575 4.750359)
			(xy 93.985575 4.836109) (xy 93.993487 4.921492) (xy 94.009243 5.005782) (xy 94.03271 5.088258) (xy 94.063686 5.168217)
			(xy 94.101908 5.244977) (xy 94.147049 5.317883) (xy 94.198725 5.386312) (xy 94.256494 5.449682) (xy 94.319864 5.507451)
			(xy 94.388293 5.559127) (xy 94.461199 5.604268) (xy 94.537959 5.64249) (xy 94.617918 5.673466) (xy 94.700394 5.696933)
			(xy 94.784684 5.712689) (xy 94.870067 5.720601) (xy 94.955817 5.720601) (xy 95.0412 5.712689) (xy 95.12549 5.696933)
			(xy 95.207966 5.673466) (xy 95.287925 5.64249) (xy 95.308598 5.632196) (xy 98.842576 5.632196) (xy 98.842576 6.495796)
			(xy 98.84308 6.525332) (xy 98.851124 6.583854) (xy 98.867061 6.640736) (xy 98.890596 6.694918) (xy 98.921289 6.745391)
			(xy 98.958569 6.791214) (xy 99.001741 6.831534) (xy 99.050001 6.8656) (xy 99.102451 6.892777) (xy 99.158112 6.912559)
			(xy 99.215949 6.924578) (xy 99.274884 6.928609) (xy 99.333819 6.924578) (xy 99.391656 6.912559) (xy 99.447317 6.892777)
			(xy 99.499767 6.8656) (xy 99.548027 6.831534) (xy 99.591199 6.791214) (xy 99.628479 6.745391) (xy 99.659172 6.694918)
			(xy 99.682707 6.640736) (xy 99.698644 6.583854) (xy 99.706688 6.525332) (xy 99.707192 6.495796) (xy 99.707192 5.632196)
			(xy 99.706688 5.60266) (xy 99.698644 5.544138) (xy 99.682707 5.487256) (xy 99.659172 5.433074) (xy 99.628479 5.382601)
			(xy 99.591199 5.336778) (xy 99.548027 5.296458) (xy 99.499767 5.262392) (xy 99.447317 5.235215) (xy 99.391656 5.215433)
			(xy 99.333819 5.203414) (xy 99.274884 5.199383) (xy 99.215949 5.203414) (xy 99.158112 5.215433) (xy 99.102451 5.235215)
			(xy 99.050001 5.262392) (xy 99.001741 5.296458) (xy 98.958569 5.336778) (xy 98.921289 5.382601) (xy 98.890596 5.433074)
			(xy 98.867061 5.487256) (xy 98.851124 5.544138) (xy 98.84308 5.60266) (xy 98.842576 5.632196) (xy 95.308598 5.632196)
			(xy 95.364685 5.604268) (xy 95.437591 5.559127) (xy 95.50602 5.507451) (xy 95.56939 5.449682) (xy 95.627159 5.386312)
			(xy 95.678835 5.317883) (xy 95.723976 5.244977) (xy 95.762198 5.168217) (xy 95.793174 5.088258) (xy 95.816641 5.005782)
			(xy 95.832397 4.921492) (xy 95.840309 4.836109) (xy 95.840804 4.793234) (xy 95.840309 4.750359) (xy 100.335575 4.750359)
			(xy 100.335575 4.836109) (xy 100.343487 4.921492) (xy 100.359243 5.005782) (xy 100.38271 5.088258)
			(xy 100.413686 5.168217) (xy 100.451908 5.244977) (xy 100.497049 5.317883) (xy 100.548725 5.386312)
			(xy 100.606494 5.449682) (xy 100.669864 5.507451) (xy 100.738293 5.559127) (xy 100.811199 5.604268)
			(xy 100.887959 5.64249) (xy 100.967918 5.673466) (xy 101.050394 5.696933) (xy 101.134684 5.712689)
			(xy 101.220067 5.720601) (xy 101.305817 5.720601) (xy 101.3912 5.712689) (xy 101.47549 5.696933)
			(xy 101.557966 5.673466) (xy 101.637925 5.64249) (xy 101.714685 5.604268) (xy 101.787591 5.559127)
			(xy 101.85602 5.507451) (xy 101.91939 5.449682) (xy 101.977159 5.386312) (xy 102.028835 5.317883)
			(xy 102.073976 5.244977) (xy 102.112198 5.168217) (xy 102.143174 5.088258) (xy 102.166641 5.005782)
			(xy 102.182397 4.921492) (xy 102.190309 4.836109) (xy 102.190804 4.793234) (xy 102.190309 4.750359)
			(xy 181.468255 4.750359) (xy 181.468255 4.836109) (xy 181.476167 4.921492) (xy 181.491923 5.005782)
			(xy 181.51539 5.088258) (xy 181.546366 5.168217) (xy 181.584588 5.244977) (xy 181.629729 5.317883)
			(xy 181.681405 5.386312) (xy 181.739174 5.449682) (xy 181.802544 5.507451) (xy 181.870973 5.559127)
			(xy 181.943879 5.604268) (xy 182.020639 5.64249) (xy 182.100598 5.673466) (xy 182.183074 5.696933)
			(xy 182.267364 5.712689) (xy 182.352747 5.720601) (xy 182.438497 5.720601) (xy 182.52388 5.712689)
			(xy 182.60817 5.696933) (xy 182.690646 5.673466) (xy 182.770605 5.64249) (xy 182.791278 5.632196)
			(xy 183.953912 5.632196) (xy 183.953912 6.495796) (xy 183.954416 6.525332) (xy 183.96246 6.583854)
			(xy 183.978397 6.640736) (xy 184.001932 6.694918) (xy 184.032625 6.745391) (xy 184.069905 6.791214)
			(xy 184.113077 6.831534) (xy 184.161337 6.8656) (xy 184.213787 6.892777) (xy 184.269448 6.912559)
			(xy 184.327285 6.924578) (xy 184.38622 6.928609) (xy 184.445155 6.924578) (xy 184.502992 6.912559)
			(xy 184.558653 6.892777) (xy 184.611103 6.8656) (xy 184.659363 6.831534) (xy 184.702535 6.791214)
			(xy 184.739815 6.745391) (xy 184.770508 6.694918) (xy 184.794043 6.640736) (xy 184.80998 6.583854)
			(xy 184.818024 6.525332) (xy 184.818528 6.495796) (xy 184.818528 6.309919) (xy 208.661241 6.309919)
			(xy 208.661241 6.395669) (xy 208.669153 6.481052) (xy 208.684909 6.565342) (xy 208.708376 6.647818)
			(xy 208.739352 6.727777) (xy 208.777574 6.804537) (xy 208.822715 6.877443) (xy 208.874391 6.945872)
			(xy 208.93216 7.009242) (xy 208.99553 7.067011) (xy 209.063959 7.118687) (xy 209.136865 7.163828)
			(xy 209.213625 7.20205) (xy 209.293584 7.233026) (xy 209.37606 7.256493) (xy 209.46035 7.272249)
			(xy 209.545733 7.280161) (xy 209.631483 7.280161) (xy 209.716866 7.272249) (xy 209.801156 7.256493)
			(xy 209.883632 7.233026) (xy 209.963591 7.20205) (xy 210.040351 7.163828) (xy 210.113257 7.118687)
			(xy 210.181686 7.067011) (xy 210.245056 7.009242) (xy 210.302825 6.945872) (xy 210.354501 6.877443)
			(xy 210.399642 6.804537) (xy 210.437864 6.727777) (xy 210.46884 6.647818) (xy 210.492307 6.565342)
			(xy 210.508063 6.481052) (xy 210.515975 6.395669) (xy 210.51647 6.352794) (xy 210.515975 6.309919)
			(xy 215.011241 6.309919) (xy 215.011241 6.395669) (xy 215.019153 6.481052) (xy 215.034909 6.565342)
			(xy 215.058376 6.647818) (xy 215.089352 6.727777) (xy 215.127574 6.804537) (xy 215.172715 6.877443)
			(xy 215.224391 6.945872) (xy 215.28216 7.009242) (xy 215.34553 7.067011) (xy 215.413959 7.118687)
			(xy 215.486865 7.163828) (xy 215.563625 7.20205) (xy 215.643584 7.233026) (xy 215.72606 7.256493)
			(xy 215.81035 7.272249) (xy 215.895733 7.280161) (xy 215.981483 7.280161) (xy 216.066866 7.272249)
			(xy 216.151156 7.256493) (xy 216.233632 7.233026) (xy 216.313591 7.20205) (xy 216.390351 7.163828)
			(xy 216.463257 7.118687) (xy 216.531686 7.067011) (xy 216.595056 7.009242) (xy 216.652825 6.945872)
			(xy 216.704501 6.877443) (xy 216.749642 6.804537) (xy 216.787864 6.727777) (xy 216.81884 6.647818)
			(xy 216.842307 6.565342) (xy 216.858063 6.481052) (xy 216.865975 6.395669) (xy 216.86647 6.352794)
			(xy 216.865975 6.309919) (xy 296.143921 6.309919) (xy 296.143921 6.395669) (xy 296.151833 6.481052)
			(xy 296.167589 6.565342) (xy 296.191056 6.647818) (xy 296.222032 6.727777) (xy 296.260254 6.804537)
			(xy 296.305395 6.877443) (xy 296.357071 6.945872) (xy 296.41484 7.009242) (xy 296.47821 7.067011)
			(xy 296.546639 7.118687) (xy 296.619545 7.163828) (xy 296.696305 7.20205) (xy 296.776264 7.233026)
			(xy 296.85874 7.256493) (xy 296.94303 7.272249) (xy 297.028413 7.280161) (xy 297.114163 7.280161)
			(xy 297.199546 7.272249) (xy 297.283836 7.256493) (xy 297.366312 7.233026) (xy 297.446271 7.20205)
			(xy 297.523031 7.163828) (xy 297.595937 7.118687) (xy 297.664366 7.067011) (xy 297.727736 7.009242)
			(xy 297.785505 6.945872) (xy 297.837181 6.877443) (xy 297.882322 6.804537) (xy 297.920544 6.727777)
			(xy 297.95152 6.647818) (xy 297.974987 6.565342) (xy 297.990743 6.481052) (xy 297.998655 6.395669)
			(xy 297.99915 6.352794) (xy 297.998655 6.309919) (xy 302.493921 6.309919) (xy 302.493921 6.395669)
			(xy 302.501833 6.481052) (xy 302.517589 6.565342) (xy 302.541056 6.647818) (xy 302.572032 6.727777)
			(xy 302.610254 6.804537) (xy 302.655395 6.877443) (xy 302.707071 6.945872) (xy 302.76484 7.009242)
			(xy 302.82821 7.067011) (xy 302.896639 7.118687) (xy 302.969545 7.163828) (xy 303.046305 7.20205)
			(xy 303.126264 7.233026) (xy 303.20874 7.256493) (xy 303.29303 7.272249) (xy 303.378413 7.280161)
			(xy 303.464163 7.280161) (xy 303.549546 7.272249) (xy 303.633836 7.256493) (xy 303.716312 7.233026)
			(xy 303.796271 7.20205) (xy 303.873031 7.163828) (xy 303.945937 7.118687) (xy 304.014366 7.067011)
			(xy 304.077736 7.009242) (xy 304.135505 6.945872) (xy 304.187181 6.877443) (xy 304.232322 6.804537)
			(xy 304.270544 6.727777) (xy 304.30152 6.647818) (xy 304.324987 6.565342) (xy 304.340743 6.481052)
			(xy 304.348655 6.395669) (xy 304.34915 6.352794) (xy 304.348655 6.309919) (xy 311.155321 6.309919)
			(xy 311.155321 6.395669) (xy 311.163233 6.481052) (xy 311.178989 6.565342) (xy 311.202456 6.647818)
			(xy 311.233432 6.727777) (xy 311.271654 6.804537) (xy 311.316795 6.877443) (xy 311.368471 6.945872)
			(xy 311.42624 7.009242) (xy 311.48961 7.067011) (xy 311.558039 7.118687) (xy 311.630945 7.163828)
			(xy 311.707705 7.20205) (xy 311.787664 7.233026) (xy 311.87014 7.256493) (xy 311.95443 7.272249)
			(xy 312.039813 7.280161) (xy 312.125563 7.280161) (xy 312.210946 7.272249) (xy 312.295236 7.256493)
			(xy 312.377712 7.233026) (xy 312.457671 7.20205) (xy 312.478344 7.191756) (xy 316.012068 7.191756)
			(xy 316.012068 8.055356) (xy 316.012572 8.08491) (xy 316.020621 8.143466) (xy 316.036567 8.200381)
			(xy 316.060116 8.254595) (xy 316.090827 8.305098) (xy 316.128129 8.350948) (xy 316.171326 8.391291)
			(xy 316.219615 8.425377) (xy 316.272095 8.45257) (xy 316.32779 8.472364) (xy 316.385661 8.48439)
			(xy 316.44463 8.488424) (xy 316.503599 8.48439) (xy 316.56147 8.472364) (xy 316.617165 8.45257) (xy 316.669645 8.425377)
			(xy 316.717934 8.391291) (xy 316.761131 8.350948) (xy 316.798433 8.305098) (xy 316.829144 8.254595)
			(xy 316.852693 8.200381) (xy 316.868639 8.143466) (xy 316.876688 8.08491) (xy 316.877192 8.055356)
			(xy 316.877192 7.191756) (xy 316.876688 7.162202) (xy 316.868639 7.103646) (xy 316.852693 7.046731)
			(xy 316.829144 6.992517) (xy 316.798433 6.942014) (xy 316.761131 6.896164) (xy 316.717934 6.855821)
			(xy 316.669645 6.821735) (xy 316.617165 6.794542) (xy 316.56147 6.774748) (xy 316.503599 6.762722)
			(xy 316.44463 6.758689) (xy 316.385661 6.762722) (xy 316.32779 6.774748) (xy 316.272095 6.794542)
			(xy 316.219615 6.821735) (xy 316.171326 6.855821) (xy 316.128129 6.896164) (xy 316.090827 6.942014)
			(xy 316.060116 6.992517) (xy 316.036567 7.046731) (xy 316.020621 7.103646) (xy 316.012572 7.162202)
			(xy 316.012068 7.191756) (xy 312.478344 7.191756) (xy 312.534431 7.163828) (xy 312.607337 7.118687)
			(xy 312.675766 7.067011) (xy 312.739136 7.009242) (xy 312.796905 6.945872) (xy 312.848581 6.877443)
			(xy 312.893722 6.804537) (xy 312.931944 6.727777) (xy 312.96292 6.647818) (xy 312.986387 6.565342)
			(xy 313.002143 6.481052) (xy 313.010055 6.395669) (xy 313.01055 6.352794) (xy 313.010055 6.309919)
			(xy 317.505321 6.309919) (xy 317.505321 6.395669) (xy 317.513233 6.481052) (xy 317.528989 6.565342)
			(xy 317.552456 6.647818) (xy 317.583432 6.727777) (xy 317.621654 6.804537) (xy 317.666795 6.877443)
			(xy 317.718471 6.945872) (xy 317.77624 7.009242) (xy 317.83961 7.067011) (xy 317.908039 7.118687)
			(xy 317.980945 7.163828) (xy 318.057705 7.20205) (xy 318.137664 7.233026) (xy 318.22014 7.256493)
			(xy 318.30443 7.272249) (xy 318.389813 7.280161) (xy 318.475563 7.280161) (xy 318.560946 7.272249)
			(xy 318.645236 7.256493) (xy 318.727712 7.233026) (xy 318.807671 7.20205) (xy 318.884431 7.163828)
			(xy 318.957337 7.118687) (xy 319.025766 7.067011) (xy 319.089136 7.009242) (xy 319.146905 6.945872)
			(xy 319.198581 6.877443) (xy 319.243722 6.804537) (xy 319.281944 6.727777) (xy 319.31292 6.647818)
			(xy 319.336387 6.565342) (xy 319.352143 6.481052) (xy 319.360055 6.395669) (xy 319.36055 6.352794)
			(xy 319.360055 6.309919) (xy 361.894107 6.309919) (xy 361.894107 6.395669) (xy 361.902019 6.481052)
			(xy 361.917775 6.565342) (xy 361.941242 6.647818) (xy 361.972218 6.727777) (xy 362.01044 6.804537)
			(xy 362.055581 6.877443) (xy 362.107257 6.945872) (xy 362.165026 7.009242) (xy 362.228396 7.067011)
			(xy 362.296825 7.118687) (xy 362.369731 7.163828) (xy 362.446491 7.20205) (xy 362.52645 7.233026)
			(xy 362.608926 7.256493) (xy 362.693216 7.272249) (xy 362.778599 7.280161) (xy 362.864349 7.280161)
			(xy 362.949732 7.272249) (xy 363.034022 7.256493) (xy 363.116498 7.233026) (xy 363.196457 7.20205)
			(xy 363.21713 7.191756) (xy 364.379764 7.191756) (xy 364.379764 8.055356) (xy 364.380268 8.084892)
			(xy 364.388312 8.143414) (xy 364.404249 8.200296) (xy 364.427784 8.254478) (xy 364.458477 8.304951)
			(xy 364.495757 8.350774) (xy 364.538929 8.391094) (xy 364.587189 8.42516) (xy 364.639639 8.452337)
			(xy 364.6953 8.472119) (xy 364.753137 8.484138) (xy 364.812072 8.488169) (xy 364.871007 8.484138)
			(xy 364.928844 8.472119) (xy 364.984505 8.452337) (xy 365.036955 8.42516) (xy 365.085215 8.391094)
			(xy 365.128387 8.350774) (xy 365.165667 8.304951) (xy 365.19636 8.254478) (xy 365.219895 8.200296)
			(xy 365.235832 8.143414) (xy 365.243876 8.084892) (xy 365.24438 8.055356) (xy 365.24438 7.376973)
			(xy 385.651997 7.376973) (xy 385.651997 7.462723) (xy 385.659909 7.548106) (xy 385.675665 7.632396)
			(xy 385.699132 7.714872) (xy 385.730108 7.794831) (xy 385.76833 7.871591) (xy 385.813471 7.944497)
			(xy 385.865147 8.012926) (xy 385.922916 8.076296) (xy 385.986286 8.134065) (xy 386.054715 8.185741)
			(xy 386.127621 8.230882) (xy 386.204381 8.269104) (xy 386.28434 8.30008) (xy 386.366816 8.323547)
			(xy 386.451106 8.339303) (xy 386.536489 8.347215) (xy 386.622239 8.347215) (xy 386.707622 8.339303)
			(xy 386.791912 8.323547) (xy 386.874388 8.30008) (xy 386.954347 8.269104) (xy 386.97502 8.25881)
			(xy 390.508744 8.25881) (xy 390.508744 9.12241) (xy 390.509248 9.151964) (xy 390.517297 9.21052)
			(xy 390.533243 9.267435) (xy 390.556792 9.321649) (xy 390.587503 9.372152) (xy 390.624805 9.418002)
			(xy 390.668002 9.458345) (xy 390.716291 9.492431) (xy 390.768771 9.519624) (xy 390.824466 9.539418)
			(xy 390.882337 9.551444) (xy 390.941306 9.555478) (xy 391.000275 9.551444) (xy 391.058146 9.539418)
			(xy 391.113841 9.519624) (xy 391.166321 9.492431) (xy 391.21461 9.458345) (xy 391.257807 9.418002)
			(xy 391.295109 9.372152) (xy 391.32582 9.321649) (xy 391.349369 9.267435) (xy 391.365315 9.21052)
			(xy 391.373364 9.151964) (xy 391.373868 9.12241) (xy 391.373868 8.25881) (xy 391.373364 8.229256)
			(xy 391.365315 8.1707) (xy 391.349369 8.113785) (xy 391.32582 8.059571) (xy 391.295109 8.009068)
			(xy 391.257807 7.963218) (xy 391.21461 7.922875) (xy 391.166321 7.888789) (xy 391.113841 7.861596)
			(xy 391.058146 7.841802) (xy 391.000275 7.829776) (xy 390.941306 7.825743) (xy 390.882337 7.829776)
			(xy 390.824466 7.841802) (xy 390.768771 7.861596) (xy 390.716291 7.888789) (xy 390.668002 7.922875)
			(xy 390.624805 7.963218) (xy 390.587503 8.009068) (xy 390.556792 8.059571) (xy 390.533243 8.113785)
			(xy 390.517297 8.1707) (xy 390.509248 8.229256) (xy 390.508744 8.25881) (xy 386.97502 8.25881) (xy 387.031107 8.230882)
			(xy 387.104013 8.185741) (xy 387.172442 8.134065) (xy 387.235812 8.076296) (xy 387.293581 8.012926)
			(xy 387.345257 7.944497) (xy 387.390398 7.871591) (xy 387.42862 7.794831) (xy 387.459596 7.714872)
			(xy 387.483063 7.632396) (xy 387.498819 7.548106) (xy 387.506731 7.462723) (xy 387.507226 7.419848)
			(xy 387.506731 7.376973) (xy 392.001997 7.376973) (xy 392.001997 7.462723) (xy 392.009909 7.548106)
			(xy 392.025665 7.632396) (xy 392.049132 7.714872) (xy 392.080108 7.794831) (xy 392.11833 7.871591)
			(xy 392.163471 7.944497) (xy 392.215147 8.012926) (xy 392.272916 8.076296) (xy 392.336286 8.134065)
			(xy 392.404715 8.185741) (xy 392.477621 8.230882) (xy 392.554381 8.269104) (xy 392.63434 8.30008)
			(xy 392.716816 8.323547) (xy 392.801106 8.339303) (xy 392.886489 8.347215) (xy 392.972239 8.347215)
			(xy 393.057622 8.339303) (xy 393.141912 8.323547) (xy 393.224388 8.30008) (xy 393.304347 8.269104)
			(xy 393.381107 8.230882) (xy 393.454013 8.185741) (xy 393.522442 8.134065) (xy 393.585812 8.076296)
			(xy 393.643581 8.012926) (xy 393.695257 7.944497) (xy 393.740398 7.871591) (xy 393.77862 7.794831)
			(xy 393.809596 7.714872) (xy 393.833063 7.632396) (xy 393.848819 7.548106) (xy 393.856731 7.462723)
			(xy 393.857226 7.419848) (xy 393.856731 7.376973) (xy 436.390783 7.376973) (xy 436.390783 7.462723)
			(xy 436.398695 7.548106) (xy 436.414451 7.632396) (xy 436.437918 7.714872) (xy 436.468894 7.794831)
			(xy 436.507116 7.871591) (xy 436.552257 7.944497) (xy 436.603933 8.012926) (xy 436.661702 8.076296)
			(xy 436.725072 8.134065) (xy 436.793501 8.185741) (xy 436.866407 8.230882) (xy 436.943167 8.269104)
			(xy 437.023126 8.30008) (xy 437.105602 8.323547) (xy 437.189892 8.339303) (xy 437.275275 8.347215)
			(xy 437.361025 8.347215) (xy 437.446408 8.339303) (xy 437.530698 8.323547) (xy 437.613174 8.30008)
			(xy 437.693133 8.269104) (xy 437.713806 8.25881) (xy 438.87644 8.25881) (xy 438.87644 9.12241) (xy 438.876944 9.151946)
			(xy 438.884988 9.210468) (xy 438.900925 9.26735) (xy 438.92446 9.321532) (xy 438.955153 9.372005)
			(xy 438.992433 9.417828) (xy 439.035605 9.458148) (xy 439.083865 9.492214) (xy 439.136315 9.519391)
			(xy 439.191976 9.539173) (xy 439.249813 9.551192) (xy 439.308748 9.555223) (xy 439.367683 9.551192)
			(xy 439.42552 9.539173) (xy 439.481181 9.519391) (xy 439.533631 9.492214) (xy 439.581891 9.458148)
			(xy 439.625063 9.417828) (xy 439.662343 9.372005) (xy 439.693036 9.321532) (xy 439.716571 9.26735)
			(xy 439.732508 9.210468) (xy 439.740552 9.151946) (xy 439.741056 9.12241) (xy 439.741056 8.25881)
			(xy 439.740552 8.229274) (xy 439.732508 8.170752) (xy 439.716571 8.11387) (xy 439.693036 8.059688)
			(xy 439.662343 8.009215) (xy 439.625063 7.963392) (xy 439.581891 7.923072) (xy 439.533631 7.889006)
			(xy 439.481181 7.861829) (xy 439.42552 7.842047) (xy 439.367683 7.830028) (xy 439.308748 7.825997)
			(xy 439.249813 7.830028) (xy 439.191976 7.842047) (xy 439.136315 7.861829) (xy 439.083865 7.889006)
			(xy 439.035605 7.923072) (xy 438.992433 7.963392) (xy 438.955153 8.009215) (xy 438.92446 8.059688)
			(xy 438.900925 8.11387) (xy 438.884988 8.170752) (xy 438.876944 8.229274) (xy 438.87644 8.25881)
			(xy 437.713806 8.25881) (xy 437.769893 8.230882) (xy 437.842799 8.185741) (xy 437.911228 8.134065)
			(xy 437.974598 8.076296) (xy 438.032367 8.012926) (xy 438.084043 7.944497) (xy 438.129184 7.871591)
			(xy 438.167406 7.794831) (xy 438.198382 7.714872) (xy 438.221849 7.632396) (xy 438.237605 7.548106)
			(xy 438.245517 7.462723) (xy 438.246012 7.419848) (xy 438.245517 7.376973) (xy 442.740783 7.376973)
			(xy 442.740783 7.462723) (xy 442.748695 7.548106) (xy 442.764451 7.632396) (xy 442.787918 7.714872)
			(xy 442.818894 7.794831) (xy 442.857116 7.871591) (xy 442.902257 7.944497) (xy 442.953933 8.012926)
			(xy 443.011702 8.076296) (xy 443.075072 8.134065) (xy 443.143501 8.185741) (xy 443.216407 8.230882)
			(xy 443.293167 8.269104) (xy 443.373126 8.30008) (xy 443.455602 8.323547) (xy 443.539892 8.339303)
			(xy 443.625275 8.347215) (xy 443.711025 8.347215) (xy 443.796408 8.339303) (xy 443.880698 8.323547)
			(xy 443.963174 8.30008) (xy 444.043133 8.269104) (xy 444.119893 8.230882) (xy 444.192799 8.185741)
			(xy 444.261228 8.134065) (xy 444.324598 8.076296) (xy 444.382367 8.012926) (xy 444.434043 7.944497)
			(xy 444.479184 7.871591) (xy 444.517406 7.794831) (xy 444.548382 7.714872) (xy 444.571849 7.632396)
			(xy 444.587605 7.548106) (xy 444.595517 7.462723) (xy 444.596012 7.419848) (xy 444.595517 7.376973)
			(xy 444.587605 7.29159) (xy 444.571849 7.2073) (xy 444.548382 7.124824) (xy 444.517406 7.044865)
			(xy 444.479184 6.968105) (xy 444.434043 6.895199) (xy 444.382367 6.82677) (xy 444.324598 6.7634)
			(xy 444.261228 6.705631) (xy 444.192799 6.653955) (xy 444.119893 6.608814) (xy 444.043133 6.570592)
			(xy 443.963174 6.539616) (xy 443.880698 6.516149) (xy 443.796408 6.500393) (xy 443.711025 6.492481)
			(xy 443.625275 6.492481) (xy 443.539892 6.500393) (xy 443.455602 6.516149) (xy 443.373126 6.539616)
			(xy 443.293167 6.570592) (xy 443.216407 6.608814) (xy 443.143501 6.653955) (xy 443.075072 6.705631)
			(xy 443.011702 6.7634) (xy 442.953933 6.82677) (xy 442.902257 6.895199) (xy 442.857116 6.968105)
			(xy 442.818894 7.044865) (xy 442.787918 7.124824) (xy 442.764451 7.2073) (xy 442.748695 7.29159)
			(xy 442.740783 7.376973) (xy 438.245517 7.376973) (xy 438.237605 7.29159) (xy 438.221849 7.2073)
			(xy 438.198382 7.124824) (xy 438.167406 7.044865) (xy 438.129184 6.968105) (xy 438.084043 6.895199)
			(xy 438.032367 6.82677) (xy 437.974598 6.7634) (xy 437.911228 6.705631) (xy 437.842799 6.653955)
			(xy 437.769893 6.608814) (xy 437.693133 6.570592) (xy 437.613174 6.539616) (xy 437.530698 6.516149)
			(xy 437.446408 6.500393) (xy 437.361025 6.492481) (xy 437.275275 6.492481) (xy 437.189892 6.500393)
			(xy 437.105602 6.516149) (xy 437.023126 6.539616) (xy 436.943167 6.570592) (xy 436.866407 6.608814)
			(xy 436.793501 6.653955) (xy 436.725072 6.705631) (xy 436.661702 6.7634) (xy 436.603933 6.82677)
			(xy 436.552257 6.895199) (xy 436.507116 6.968105) (xy 436.468894 7.044865) (xy 436.437918 7.124824)
			(xy 436.414451 7.2073) (xy 436.398695 7.29159) (xy 436.390783 7.376973) (xy 393.856731 7.376973)
			(xy 393.848819 7.29159) (xy 393.833063 7.2073) (xy 393.809596 7.124824) (xy 393.77862 7.044865) (xy 393.740398 6.968105)
			(xy 393.695257 6.895199) (xy 393.643581 6.82677) (xy 393.585812 6.7634) (xy 393.522442 6.705631)
			(xy 393.454013 6.653955) (xy 393.381107 6.608814) (xy 393.304347 6.570592) (xy 393.224388 6.539616)
			(xy 393.141912 6.516149) (xy 393.057622 6.500393) (xy 392.972239 6.492481) (xy 392.886489 6.492481)
			(xy 392.801106 6.500393) (xy 392.716816 6.516149) (xy 392.63434 6.539616) (xy 392.554381 6.570592)
			(xy 392.477621 6.608814) (xy 392.404715 6.653955) (xy 392.336286 6.705631) (xy 392.272916 6.7634)
			(xy 392.215147 6.82677) (xy 392.163471 6.895199) (xy 392.11833 6.968105) (xy 392.080108 7.044865)
			(xy 392.049132 7.124824) (xy 392.025665 7.2073) (xy 392.009909 7.29159) (xy 392.001997 7.376973)
			(xy 387.506731 7.376973) (xy 387.498819 7.29159) (xy 387.483063 7.2073) (xy 387.459596 7.124824)
			(xy 387.42862 7.044865) (xy 387.390398 6.968105) (xy 387.345257 6.895199) (xy 387.293581 6.82677)
			(xy 387.235812 6.7634) (xy 387.172442 6.705631) (xy 387.104013 6.653955) (xy 387.031107 6.608814)
			(xy 386.954347 6.570592) (xy 386.874388 6.539616) (xy 386.791912 6.516149) (xy 386.707622 6.500393)
			(xy 386.622239 6.492481) (xy 386.536489 6.492481) (xy 386.451106 6.500393) (xy 386.366816 6.516149)
			(xy 386.28434 6.539616) (xy 386.204381 6.570592) (xy 386.127621 6.608814) (xy 386.054715 6.653955)
			(xy 385.986286 6.705631) (xy 385.922916 6.7634) (xy 385.865147 6.82677) (xy 385.813471 6.895199)
			(xy 385.76833 6.968105) (xy 385.730108 7.044865) (xy 385.699132 7.124824) (xy 385.675665 7.2073)
			(xy 385.659909 7.29159) (xy 385.651997 7.376973) (xy 365.24438 7.376973) (xy 365.24438 7.191756)
			(xy 365.243876 7.16222) (xy 365.235832 7.103698) (xy 365.219895 7.046816) (xy 365.19636 6.992634)
			(xy 365.165667 6.942161) (xy 365.128387 6.896338) (xy 365.085215 6.856018) (xy 365.036955 6.821952)
			(xy 364.984505 6.794775) (xy 364.928844 6.774993) (xy 364.871007 6.762974) (xy 364.812072 6.758943)
			(xy 364.753137 6.762974) (xy 364.6953 6.774993) (xy 364.639639 6.794775) (xy 364.587189 6.821952)
			(xy 364.538929 6.856018) (xy 364.495757 6.896338) (xy 364.458477 6.942161) (xy 364.427784 6.992634)
			(xy 364.404249 7.046816) (xy 364.388312 7.103698) (xy 364.380268 7.16222) (xy 364.379764 7.191756)
			(xy 363.21713 7.191756) (xy 363.273217 7.163828) (xy 363.346123 7.118687) (xy 363.414552 7.067011)
			(xy 363.477922 7.009242) (xy 363.535691 6.945872) (xy 363.587367 6.877443) (xy 363.632508 6.804537)
			(xy 363.67073 6.727777) (xy 363.701706 6.647818) (xy 363.725173 6.565342) (xy 363.740929 6.481052)
			(xy 363.748841 6.395669) (xy 363.749336 6.352794) (xy 363.748841 6.309919) (xy 368.244107 6.309919)
			(xy 368.244107 6.395669) (xy 368.252019 6.481052) (xy 368.267775 6.565342) (xy 368.291242 6.647818)
			(xy 368.322218 6.727777) (xy 368.36044 6.804537) (xy 368.405581 6.877443) (xy 368.457257 6.945872)
			(xy 368.515026 7.009242) (xy 368.578396 7.067011) (xy 368.646825 7.118687) (xy 368.719731 7.163828)
			(xy 368.796491 7.20205) (xy 368.87645 7.233026) (xy 368.958926 7.256493) (xy 369.043216 7.272249)
			(xy 369.128599 7.280161) (xy 369.214349 7.280161) (xy 369.299732 7.272249) (xy 369.384022 7.256493)
			(xy 369.466498 7.233026) (xy 369.546457 7.20205) (xy 369.623217 7.163828) (xy 369.696123 7.118687)
			(xy 369.764552 7.067011) (xy 369.827922 7.009242) (xy 369.885691 6.945872) (xy 369.937367 6.877443)
			(xy 369.982508 6.804537) (xy 370.02073 6.727777) (xy 370.051706 6.647818) (xy 370.075173 6.565342)
			(xy 370.090929 6.481052) (xy 370.098841 6.395669) (xy 370.099336 6.352794) (xy 370.098841 6.309919)
			(xy 370.090929 6.224536) (xy 370.075173 6.140246) (xy 370.051706 6.05777) (xy 370.02073 5.977811)
			(xy 369.982508 5.901051) (xy 369.937367 5.828145) (xy 369.885691 5.759716) (xy 369.827922 5.696346)
			(xy 369.764552 5.638577) (xy 369.696123 5.586901) (xy 369.623217 5.54176) (xy 369.546457 5.503538)
			(xy 369.466498 5.472562) (xy 369.384022 5.449095) (xy 369.299732 5.433339) (xy 369.214349 5.425427)
			(xy 369.128599 5.425427) (xy 369.043216 5.433339) (xy 368.958926 5.449095) (xy 368.87645 5.472562)
			(xy 368.796491 5.503538) (xy 368.719731 5.54176) (xy 368.646825 5.586901) (xy 368.578396 5.638577)
			(xy 368.515026 5.696346) (xy 368.457257 5.759716) (xy 368.405581 5.828145) (xy 368.36044 5.901051)
			(xy 368.322218 5.977811) (xy 368.291242 6.05777) (xy 368.267775 6.140246) (xy 368.252019 6.224536)
			(xy 368.244107 6.309919) (xy 363.748841 6.309919) (xy 363.740929 6.224536) (xy 363.725173 6.140246)
			(xy 363.701706 6.05777) (xy 363.67073 5.977811) (xy 363.632508 5.901051) (xy 363.587367 5.828145)
			(xy 363.535691 5.759716) (xy 363.477922 5.696346) (xy 363.414552 5.638577) (xy 363.346123 5.586901)
			(xy 363.273217 5.54176) (xy 363.196457 5.503538) (xy 363.116498 5.472562) (xy 363.034022 5.449095)
			(xy 362.949732 5.433339) (xy 362.864349 5.425427) (xy 362.778599 5.425427) (xy 362.693216 5.433339)
			(xy 362.608926 5.449095) (xy 362.52645 5.472562) (xy 362.446491 5.503538) (xy 362.369731 5.54176)
			(xy 362.296825 5.586901) (xy 362.228396 5.638577) (xy 362.165026 5.696346) (xy 362.107257 5.759716)
			(xy 362.055581 5.828145) (xy 362.01044 5.901051) (xy 361.972218 5.977811) (xy 361.941242 6.05777)
			(xy 361.917775 6.140246) (xy 361.902019 6.224536) (xy 361.894107 6.309919) (xy 319.360055 6.309919)
			(xy 319.352143 6.224536) (xy 319.336387 6.140246) (xy 319.31292 6.05777) (xy 319.281944 5.977811)
			(xy 319.243722 5.901051) (xy 319.198581 5.828145) (xy 319.146905 5.759716) (xy 319.089136 5.696346)
			(xy 319.025766 5.638577) (xy 318.957337 5.586901) (xy 318.884431 5.54176) (xy 318.807671 5.503538)
			(xy 318.727712 5.472562) (xy 318.645236 5.449095) (xy 318.560946 5.433339) (xy 318.475563 5.425427)
			(xy 318.389813 5.425427) (xy 318.30443 5.433339) (xy 318.22014 5.449095) (xy 318.137664 5.472562)
			(xy 318.057705 5.503538) (xy 317.980945 5.54176) (xy 317.908039 5.586901) (xy 317.83961 5.638577)
			(xy 317.77624 5.696346) (xy 317.718471 5.759716) (xy 317.666795 5.828145) (xy 317.621654 5.901051)
			(xy 317.583432 5.977811) (xy 317.552456 6.05777) (xy 317.528989 6.140246) (xy 317.513233 6.224536)
			(xy 317.505321 6.309919) (xy 313.010055 6.309919) (xy 313.002143 6.224536) (xy 312.986387 6.140246)
			(xy 312.96292 6.05777) (xy 312.931944 5.977811) (xy 312.893722 5.901051) (xy 312.848581 5.828145)
			(xy 312.796905 5.759716) (xy 312.739136 5.696346) (xy 312.675766 5.638577) (xy 312.607337 5.586901)
			(xy 312.534431 5.54176) (xy 312.457671 5.503538) (xy 312.377712 5.472562) (xy 312.295236 5.449095)
			(xy 312.210946 5.433339) (xy 312.125563 5.425427) (xy 312.039813 5.425427) (xy 311.95443 5.433339)
			(xy 311.87014 5.449095) (xy 311.787664 5.472562) (xy 311.707705 5.503538) (xy 311.630945 5.54176)
			(xy 311.558039 5.586901) (xy 311.48961 5.638577) (xy 311.42624 5.696346) (xy 311.368471 5.759716)
			(xy 311.316795 5.828145) (xy 311.271654 5.901051) (xy 311.233432 5.977811) (xy 311.202456 6.05777)
			(xy 311.178989 6.140246) (xy 311.163233 6.224536) (xy 311.155321 6.309919) (xy 304.348655 6.309919)
			(xy 304.340743 6.224536) (xy 304.324987 6.140246) (xy 304.30152 6.05777) (xy 304.270544 5.977811)
			(xy 304.232322 5.901051) (xy 304.187181 5.828145) (xy 304.135505 5.759716) (xy 304.077736 5.696346)
			(xy 304.014366 5.638577) (xy 303.945937 5.586901) (xy 303.873031 5.54176) (xy 303.796271 5.503538)
			(xy 303.716312 5.472562) (xy 303.633836 5.449095) (xy 303.549546 5.433339) (xy 303.464163 5.425427)
			(xy 303.378413 5.425427) (xy 303.29303 5.433339) (xy 303.20874 5.449095) (xy 303.126264 5.472562)
			(xy 303.046305 5.503538) (xy 302.969545 5.54176) (xy 302.896639 5.586901) (xy 302.82821 5.638577)
			(xy 302.76484 5.696346) (xy 302.707071 5.759716) (xy 302.655395 5.828145) (xy 302.610254 5.901051)
			(xy 302.572032 5.977811) (xy 302.541056 6.05777) (xy 302.517589 6.140246) (xy 302.501833 6.224536)
			(xy 302.493921 6.309919) (xy 297.998655 6.309919) (xy 297.990743 6.224536) (xy 297.974987 6.140246)
			(xy 297.95152 6.05777) (xy 297.920544 5.977811) (xy 297.882322 5.901051) (xy 297.837181 5.828145)
			(xy 297.785505 5.759716) (xy 297.727736 5.696346) (xy 297.664366 5.638577) (xy 297.595937 5.586901)
			(xy 297.523031 5.54176) (xy 297.446271 5.503538) (xy 297.366312 5.472562) (xy 297.283836 5.449095)
			(xy 297.199546 5.433339) (xy 297.114163 5.425427) (xy 297.028413 5.425427) (xy 296.94303 5.433339)
			(xy 296.85874 5.449095) (xy 296.776264 5.472562) (xy 296.696305 5.503538) (xy 296.619545 5.54176)
			(xy 296.546639 5.586901) (xy 296.47821 5.638577) (xy 296.41484 5.696346) (xy 296.357071 5.759716)
			(xy 296.305395 5.828145) (xy 296.260254 5.901051) (xy 296.222032 5.977811) (xy 296.191056 6.05777)
			(xy 296.167589 6.140246) (xy 296.151833 6.224536) (xy 296.143921 6.309919) (xy 216.865975 6.309919)
			(xy 216.858063 6.224536) (xy 216.842307 6.140246) (xy 216.81884 6.05777) (xy 216.787864 5.977811)
			(xy 216.749642 5.901051) (xy 216.704501 5.828145) (xy 216.652825 5.759716) (xy 216.595056 5.696346)
			(xy 216.531686 5.638577) (xy 216.463257 5.586901) (xy 216.390351 5.54176) (xy 216.313591 5.503538)
			(xy 216.233632 5.472562) (xy 216.151156 5.449095) (xy 216.066866 5.433339) (xy 215.981483 5.425427)
			(xy 215.895733 5.425427) (xy 215.81035 5.433339) (xy 215.72606 5.449095) (xy 215.643584 5.472562)
			(xy 215.563625 5.503538) (xy 215.486865 5.54176) (xy 215.413959 5.586901) (xy 215.34553 5.638577)
			(xy 215.28216 5.696346) (xy 215.224391 5.759716) (xy 215.172715 5.828145) (xy 215.127574 5.901051)
			(xy 215.089352 5.977811) (xy 215.058376 6.05777) (xy 215.034909 6.140246) (xy 215.019153 6.224536)
			(xy 215.011241 6.309919) (xy 210.515975 6.309919) (xy 210.508063 6.224536) (xy 210.492307 6.140246)
			(xy 210.46884 6.05777) (xy 210.437864 5.977811) (xy 210.399642 5.901051) (xy 210.354501 5.828145)
			(xy 210.302825 5.759716) (xy 210.245056 5.696346) (xy 210.181686 5.638577) (xy 210.113257 5.586901)
			(xy 210.040351 5.54176) (xy 209.963591 5.503538) (xy 209.883632 5.472562) (xy 209.801156 5.449095)
			(xy 209.716866 5.433339) (xy 209.631483 5.425427) (xy 209.545733 5.425427) (xy 209.46035 5.433339)
			(xy 209.37606 5.449095) (xy 209.293584 5.472562) (xy 209.213625 5.503538) (xy 209.136865 5.54176)
			(xy 209.063959 5.586901) (xy 208.99553 5.638577) (xy 208.93216 5.696346) (xy 208.874391 5.759716)
			(xy 208.822715 5.828145) (xy 208.777574 5.901051) (xy 208.739352 5.977811) (xy 208.708376 6.05777)
			(xy 208.684909 6.140246) (xy 208.669153 6.224536) (xy 208.661241 6.309919) (xy 184.818528 6.309919)
			(xy 184.818528 5.632196) (xy 184.818024 5.60266) (xy 184.80998 5.544138) (xy 184.794043 5.487256)
			(xy 184.770508 5.433074) (xy 184.739815 5.382601) (xy 184.702535 5.336778) (xy 184.659363 5.296458)
			(xy 184.611103 5.262392) (xy 184.558653 5.235215) (xy 184.502992 5.215433) (xy 184.445155 5.203414)
			(xy 184.38622 5.199383) (xy 184.327285 5.203414) (xy 184.269448 5.215433) (xy 184.213787 5.235215)
			(xy 184.161337 5.262392) (xy 184.113077 5.296458) (xy 184.069905 5.336778) (xy 184.032625 5.382601)
			(xy 184.001932 5.433074) (xy 183.978397 5.487256) (xy 183.96246 5.544138) (xy 183.954416 5.60266)
			(xy 183.953912 5.632196) (xy 182.791278 5.632196) (xy 182.847365 5.604268) (xy 182.920271 5.559127)
			(xy 182.9887 5.507451) (xy 183.05207 5.449682) (xy 183.109839 5.386312) (xy 183.161515 5.317883)
			(xy 183.206656 5.244977) (xy 183.244878 5.168217) (xy 183.275854 5.088258) (xy 183.299321 5.005782)
			(xy 183.315077 4.921492) (xy 183.322989 4.836109) (xy 183.323484 4.793234) (xy 183.322989 4.750359)
			(xy 187.818255 4.750359) (xy 187.818255 4.836109) (xy 187.826167 4.921492) (xy 187.841923 5.005782)
			(xy 187.86539 5.088258) (xy 187.896366 5.168217) (xy 187.934588 5.244977) (xy 187.979729 5.317883)
			(xy 188.031405 5.386312) (xy 188.089174 5.449682) (xy 188.152544 5.507451) (xy 188.220973 5.559127)
			(xy 188.293879 5.604268) (xy 188.370639 5.64249) (xy 188.450598 5.673466) (xy 188.533074 5.696933)
			(xy 188.617364 5.712689) (xy 188.702747 5.720601) (xy 188.788497 5.720601) (xy 188.87388 5.712689)
			(xy 188.95817 5.696933) (xy 189.040646 5.673466) (xy 189.120605 5.64249) (xy 189.197365 5.604268)
			(xy 189.270271 5.559127) (xy 189.3387 5.507451) (xy 189.40207 5.449682) (xy 189.459839 5.386312)
			(xy 189.511515 5.317883) (xy 189.556656 5.244977) (xy 189.594878 5.168217) (xy 189.625854 5.088258)
			(xy 189.649321 5.005782) (xy 189.665077 4.921492) (xy 189.672989 4.836109) (xy 189.673484 4.793234)
			(xy 189.672989 4.750359) (xy 189.665077 4.664976) (xy 189.649321 4.580686) (xy 189.625854 4.49821)
			(xy 189.594878 4.418251) (xy 189.556656 4.341491) (xy 189.511515 4.268585) (xy 189.459839 4.200156)
			(xy 189.40207 4.136786) (xy 189.3387 4.079017) (xy 189.270271 4.027341) (xy 189.197365 3.9822) (xy 189.120605 3.943978)
			(xy 189.040646 3.913002) (xy 188.95817 3.889535) (xy 188.87388 3.873779) (xy 188.788497 3.865867)
			(xy 188.702747 3.865867) (xy 188.617364 3.873779) (xy 188.533074 3.889535) (xy 188.450598 3.913002)
			(xy 188.370639 3.943978) (xy 188.293879 3.9822) (xy 188.220973 4.027341) (xy 188.152544 4.079017)
			(xy 188.089174 4.136786) (xy 188.031405 4.200156) (xy 187.979729 4.268585) (xy 187.934588 4.341491)
			(xy 187.896366 4.418251) (xy 187.86539 4.49821) (xy 187.841923 4.580686) (xy 187.826167 4.664976)
			(xy 187.818255 4.750359) (xy 183.322989 4.750359) (xy 183.315077 4.664976) (xy 183.299321 4.580686)
			(xy 183.275854 4.49821) (xy 183.244878 4.418251) (xy 183.206656 4.341491) (xy 183.161515 4.268585)
			(xy 183.109839 4.200156) (xy 183.05207 4.136786) (xy 182.9887 4.079017) (xy 182.920271 4.027341)
			(xy 182.847365 3.9822) (xy 182.770605 3.943978) (xy 182.690646 3.913002) (xy 182.60817 3.889535)
			(xy 182.52388 3.873779) (xy 182.438497 3.865867) (xy 182.352747 3.865867) (xy 182.267364 3.873779)
			(xy 182.183074 3.889535) (xy 182.100598 3.913002) (xy 182.020639 3.943978) (xy 181.943879 3.9822)
			(xy 181.870973 4.027341) (xy 181.802544 4.079017) (xy 181.739174 4.136786) (xy 181.681405 4.200156)
			(xy 181.629729 4.268585) (xy 181.584588 4.341491) (xy 181.546366 4.418251) (xy 181.51539 4.49821)
			(xy 181.491923 4.580686) (xy 181.476167 4.664976) (xy 181.468255 4.750359) (xy 102.190309 4.750359)
			(xy 102.182397 4.664976) (xy 102.166641 4.580686) (xy 102.143174 4.49821) (xy 102.112198 4.418251)
			(xy 102.073976 4.341491) (xy 102.028835 4.268585) (xy 101.977159 4.200156) (xy 101.91939 4.136786)
			(xy 101.85602 4.079017) (xy 101.787591 4.027341) (xy 101.714685 3.9822) (xy 101.637925 3.943978)
			(xy 101.557966 3.913002) (xy 101.47549 3.889535) (xy 101.3912 3.873779) (xy 101.305817 3.865867)
			(xy 101.220067 3.865867) (xy 101.134684 3.873779) (xy 101.050394 3.889535) (xy 100.967918 3.913002)
			(xy 100.887959 3.943978) (xy 100.811199 3.9822) (xy 100.738293 4.027341) (xy 100.669864 4.079017)
			(xy 100.606494 4.136786) (xy 100.548725 4.200156) (xy 100.497049 4.268585) (xy 100.451908 4.341491)
			(xy 100.413686 4.418251) (xy 100.38271 4.49821) (xy 100.359243 4.580686) (xy 100.343487 4.664976)
			(xy 100.335575 4.750359) (xy 95.840309 4.750359) (xy 95.832397 4.664976) (xy 95.816641 4.580686)
			(xy 95.793174 4.49821) (xy 95.762198 4.418251) (xy 95.723976 4.341491) (xy 95.678835 4.268585) (xy 95.627159 4.200156)
			(xy 95.56939 4.136786) (xy 95.50602 4.079017) (xy 95.437591 4.027341) (xy 95.364685 3.9822) (xy 95.287925 3.943978)
			(xy 95.207966 3.913002) (xy 95.12549 3.889535) (xy 95.0412 3.873779) (xy 94.955817 3.865867) (xy 94.870067 3.865867)
			(xy 94.784684 3.873779) (xy 94.700394 3.889535) (xy 94.617918 3.913002) (xy 94.537959 3.943978) (xy 94.461199 3.9822)
			(xy 94.388293 4.027341) (xy 94.319864 4.079017) (xy 94.256494 4.136786) (xy 94.198725 4.200156) (xy 94.147049 4.268585)
			(xy 94.101908 4.341491) (xy 94.063686 4.418251) (xy 94.03271 4.49821) (xy 94.009243 4.580686) (xy 93.993487 4.664976)
			(xy 93.985575 4.750359) (xy 0.509016 4.750359) (xy 0.509016 -7.78002) (xy 0.509537 -7.835789) (xy 0.517873 -7.947015)
			(xy 0.534497 -8.057308) (xy 0.559316 -8.166049) (xy 0.592193 -8.272632) (xy 0.632942 -8.37646) (xy 0.681336 -8.476953)
			(xy 0.737105 -8.573548) (xy 0.799937 -8.665705) (xy 0.86948 -8.752909) (xy 0.945345 -8.834672) (xy 1.027108 -8.910538)
			(xy 1.114312 -8.980081) (xy 1.206469 -9.042912) (xy 1.303064 -9.098682) (xy 1.403556 -9.147076) (xy 1.507384 -9.187826)
			(xy 1.613967 -9.220703) (xy 1.722708 -9.245523) (xy 1.833001 -9.262147) (xy 1.944227 -9.270482) (xy 1.999996 -9.271)
			(xy 9.10209 -9.271) (xy 9.15786 -9.270479) (xy 9.269087 -9.262144) (xy 9.37938 -9.245521) (xy 9.488123 -9.220702)
			(xy 9.594707 -9.187826) (xy 9.698536 -9.147077) (xy 9.79903 -9.098683) (xy 9.895626 -9.042915) (xy 9.987784 -8.980083)
			(xy 10.07499 -8.910541) (xy 10.156754 -8.834676) (xy 10.232621 -8.752912) (xy 10.302165 -8.665708)
			(xy 10.364999 -8.573551) (xy 10.420769 -8.476956) (xy 10.469165 -8.376463) (xy 10.509916 -8.272635)
			(xy 10.542794 -8.166052) (xy 10.567616 -8.05731) (xy 10.584241 -7.947017) (xy 10.592578 -7.83579)
			(xy 10.59307 -7.78002) (xy 10.59307 0.40005) (xy 10.593555 0.470432) (xy 10.601447 0.610976) (xy 10.617208 0.750856)
			(xy 10.640787 0.889632) (xy 10.67211 1.026868) (xy 10.711079 1.162131) (xy 10.757571 1.294997) (xy 10.811439 1.425046)
			(xy 10.872515 1.551871) (xy 10.940606 1.675072) (xy 11.015497 1.794261) (xy 11.096954 1.909063) (xy 11.184719 2.019118)
			(xy 11.278518 2.124078) (xy 11.378053 2.223614) (xy 11.483014 2.317412) (xy 11.593068 2.405178) (xy 11.707871 2.486634)
			(xy 11.82706 2.561525) (xy 11.950261 2.629616) (xy 12.077085 2.690692) (xy 12.207135 2.74456) (xy 12.340001 2.791052)
			(xy 12.475264 2.83002) (xy 12.6125 2.861343) (xy 12.751276 2.884922) (xy 12.891156 2.900683) (xy 13.0317 2.908575)
			(xy 13.102082 2.909062) (xy 81.701894 2.909062) (xy 81.772277 2.908568) (xy 81.912821 2.900676) (xy 82.052702 2.884916)
			(xy 82.191479 2.861337) (xy 82.328715 2.830015) (xy 82.46398 2.791046) (xy 82.596846 2.744555) (xy 82.726897 2.690688)
			(xy 82.853723 2.629613) (xy 82.976925 2.561522) (xy 83.096116 2.486632) (xy 83.210919 2.405176) (xy 83.320975 2.317411)
			(xy 83.425937 2.223613) (xy 83.439191 2.210359) (xy 93.985575 2.210359) (xy 93.985575 2.296109) (xy 93.993487 2.381492)
			(xy 94.009243 2.465782) (xy 94.03271 2.548258) (xy 94.063686 2.628217) (xy 94.101908 2.704977) (xy 94.147049 2.777883)
			(xy 94.198725 2.846312) (xy 94.256494 2.909682) (xy 94.319864 2.967451) (xy 94.388293 3.019127) (xy 94.461199 3.064268)
			(xy 94.537959 3.10249) (xy 94.617918 3.133466) (xy 94.700394 3.156933) (xy 94.784684 3.172689) (xy 94.870067 3.180601)
			(xy 94.955817 3.180601) (xy 95.0412 3.172689) (xy 95.12549 3.156933) (xy 95.207966 3.133466) (xy 95.287925 3.10249)
			(xy 95.308598 3.092196) (xy 98.842576 3.092196) (xy 98.842576 3.955796) (xy 98.84308 3.985332) (xy 98.851124 4.043854)
			(xy 98.867061 4.100736) (xy 98.890596 4.154918) (xy 98.921289 4.205391) (xy 98.958569 4.251214) (xy 99.001741 4.291534)
			(xy 99.050001 4.3256) (xy 99.102451 4.352777) (xy 99.158112 4.372559) (xy 99.215949 4.384578) (xy 99.274884 4.388609)
			(xy 99.333819 4.384578) (xy 99.391656 4.372559) (xy 99.447317 4.352777) (xy 99.499767 4.3256) (xy 99.548027 4.291534)
			(xy 99.591199 4.251214) (xy 99.628479 4.205391) (xy 99.659172 4.154918) (xy 99.682707 4.100736) (xy 99.698644 4.043854)
			(xy 99.706688 3.985332) (xy 99.707192 3.955796) (xy 99.707192 3.092196) (xy 99.706688 3.06266) (xy 99.698644 3.004138)
			(xy 99.682707 2.947256) (xy 99.659172 2.893074) (xy 99.628479 2.842601) (xy 99.591199 2.796778) (xy 99.548027 2.756458)
			(xy 99.499767 2.722392) (xy 99.447317 2.695215) (xy 99.391656 2.675433) (xy 99.333819 2.663414) (xy 99.274884 2.659383)
			(xy 99.215949 2.663414) (xy 99.158112 2.675433) (xy 99.102451 2.695215) (xy 99.050001 2.722392) (xy 99.001741 2.756458)
			(xy 98.958569 2.796778) (xy 98.921289 2.842601) (xy 98.890596 2.893074) (xy 98.867061 2.947256) (xy 98.851124 3.004138)
			(xy 98.84308 3.06266) (xy 98.842576 3.092196) (xy 95.308598 3.092196) (xy 95.364685 3.064268) (xy 95.437591 3.019127)
			(xy 95.50602 2.967451) (xy 95.56939 2.909682) (xy 95.627159 2.846312) (xy 95.678835 2.777883) (xy 95.723976 2.704977)
			(xy 95.762198 2.628217) (xy 95.793174 2.548258) (xy 95.816641 2.465782) (xy 95.832397 2.381492) (xy 95.840309 2.296109)
			(xy 95.840804 2.253234) (xy 95.840309 2.210359) (xy 100.335575 2.210359) (xy 100.335575 2.296109)
			(xy 100.343487 2.381492) (xy 100.359243 2.465782) (xy 100.38271 2.548258) (xy 100.413686 2.628217)
			(xy 100.451908 2.704977) (xy 100.497049 2.777883) (xy 100.548725 2.846312) (xy 100.606494 2.909682)
			(xy 100.669864 2.967451) (xy 100.738293 3.019127) (xy 100.811199 3.064268) (xy 100.887959 3.10249)
			(xy 100.967918 3.133466) (xy 101.050394 3.156933) (xy 101.134684 3.172689) (xy 101.220067 3.180601)
			(xy 101.305817 3.180601) (xy 101.3912 3.172689) (xy 101.47549 3.156933) (xy 101.557966 3.133466)
			(xy 101.637925 3.10249) (xy 101.714685 3.064268) (xy 101.787591 3.019127) (xy 101.85602 2.967451)
			(xy 101.91939 2.909682) (xy 101.977159 2.846312) (xy 102.028835 2.777883) (xy 102.073976 2.704977)
			(xy 102.112198 2.628217) (xy 102.143174 2.548258) (xy 102.166641 2.465782) (xy 102.182397 2.381492)
			(xy 102.190309 2.296109) (xy 102.190804 2.253234) (xy 102.190309 2.210359) (xy 181.468255 2.210359)
			(xy 181.468255 2.296109) (xy 181.476167 2.381492) (xy 181.491923 2.465782) (xy 181.51539 2.548258)
			(xy 181.546366 2.628217) (xy 181.584588 2.704977) (xy 181.629729 2.777883) (xy 181.681405 2.846312)
			(xy 181.739174 2.909682) (xy 181.802544 2.967451) (xy 181.870973 3.019127) (xy 181.943879 3.064268)
			(xy 182.020639 3.10249) (xy 182.100598 3.133466) (xy 182.183074 3.156933) (xy 182.267364 3.172689)
			(xy 182.352747 3.180601) (xy 182.438497 3.180601) (xy 182.52388 3.172689) (xy 182.60817 3.156933)
			(xy 182.690646 3.133466) (xy 182.770605 3.10249) (xy 182.791278 3.092196) (xy 183.953912 3.092196)
			(xy 183.953912 3.955796) (xy 183.954416 3.985332) (xy 183.96246 4.043854) (xy 183.978397 4.100736)
			(xy 184.001932 4.154918) (xy 184.032625 4.205391) (xy 184.069905 4.251214) (xy 184.113077 4.291534)
			(xy 184.161337 4.3256) (xy 184.213787 4.352777) (xy 184.269448 4.372559) (xy 184.327285 4.384578)
			(xy 184.38622 4.388609) (xy 184.445155 4.384578) (xy 184.502992 4.372559) (xy 184.558653 4.352777)
			(xy 184.611103 4.3256) (xy 184.659363 4.291534) (xy 184.702535 4.251214) (xy 184.739815 4.205391)
			(xy 184.770508 4.154918) (xy 184.794043 4.100736) (xy 184.80998 4.043854) (xy 184.818024 3.985332)
			(xy 184.818528 3.955796) (xy 184.818528 3.769919) (xy 208.661241 3.769919) (xy 208.661241 3.855669)
			(xy 208.669153 3.941052) (xy 208.684909 4.025342) (xy 208.708376 4.107818) (xy 208.739352 4.187777)
			(xy 208.777574 4.264537) (xy 208.822715 4.337443) (xy 208.874391 4.405872) (xy 208.93216 4.469242)
			(xy 208.99553 4.527011) (xy 209.063959 4.578687) (xy 209.136865 4.623828) (xy 209.213625 4.66205)
			(xy 209.293584 4.693026) (xy 209.37606 4.716493) (xy 209.46035 4.732249) (xy 209.545733 4.740161)
			(xy 209.631483 4.740161) (xy 209.716866 4.732249) (xy 209.801156 4.716493) (xy 209.883632 4.693026)
			(xy 209.963591 4.66205) (xy 209.984264 4.651756) (xy 213.517988 4.651756) (xy 213.517988 5.515356)
			(xy 213.518492 5.54491) (xy 213.526541 5.603466) (xy 213.542487 5.660381) (xy 213.566036 5.714595)
			(xy 213.596747 5.765098) (xy 213.634049 5.810948) (xy 213.677246 5.851291) (xy 213.725535 5.885377)
			(xy 213.778015 5.91257) (xy 213.83371 5.932364) (xy 213.891581 5.94439) (xy 213.95055 5.948424) (xy 214.009519 5.94439)
			(xy 214.06739 5.932364) (xy 214.123085 5.91257) (xy 214.175565 5.885377) (xy 214.223854 5.851291)
			(xy 214.267051 5.810948) (xy 214.304353 5.765098) (xy 214.335064 5.714595) (xy 214.358613 5.660381)
			(xy 214.374559 5.603466) (xy 214.382608 5.54491) (xy 214.383112 5.515356) (xy 214.383112 4.651756)
			(xy 214.382608 4.622202) (xy 214.374559 4.563646) (xy 214.358613 4.506731) (xy 214.335064 4.452517)
			(xy 214.304353 4.402014) (xy 214.267051 4.356164) (xy 214.223854 4.315821) (xy 214.175565 4.281735)
			(xy 214.123085 4.254542) (xy 214.06739 4.234748) (xy 214.009519 4.222722) (xy 213.95055 4.218689)
			(xy 213.891581 4.222722) (xy 213.83371 4.234748) (xy 213.778015 4.254542) (xy 213.725535 4.281735)
			(xy 213.677246 4.315821) (xy 213.634049 4.356164) (xy 213.596747 4.402014) (xy 213.566036 4.452517)
			(xy 213.542487 4.506731) (xy 213.526541 4.563646) (xy 213.518492 4.622202) (xy 213.517988 4.651756)
			(xy 209.984264 4.651756) (xy 210.040351 4.623828) (xy 210.113257 4.578687) (xy 210.181686 4.527011)
			(xy 210.245056 4.469242) (xy 210.302825 4.405872) (xy 210.354501 4.337443) (xy 210.399642 4.264537)
			(xy 210.437864 4.187777) (xy 210.46884 4.107818) (xy 210.492307 4.025342) (xy 210.508063 3.941052)
			(xy 210.515975 3.855669) (xy 210.51647 3.812794) (xy 210.515975 3.769919) (xy 215.011241 3.769919)
			(xy 215.011241 3.855669) (xy 215.019153 3.941052) (xy 215.034909 4.025342) (xy 215.058376 4.107818)
			(xy 215.089352 4.187777) (xy 215.127574 4.264537) (xy 215.172715 4.337443) (xy 215.224391 4.405872)
			(xy 215.28216 4.469242) (xy 215.34553 4.527011) (xy 215.413959 4.578687) (xy 215.486865 4.623828)
			(xy 215.563625 4.66205) (xy 215.643584 4.693026) (xy 215.72606 4.716493) (xy 215.81035 4.732249)
			(xy 215.895733 4.740161) (xy 215.981483 4.740161) (xy 216.066866 4.732249) (xy 216.151156 4.716493)
			(xy 216.233632 4.693026) (xy 216.313591 4.66205) (xy 216.390351 4.623828) (xy 216.463257 4.578687)
			(xy 216.531686 4.527011) (xy 216.595056 4.469242) (xy 216.652825 4.405872) (xy 216.704501 4.337443)
			(xy 216.749642 4.264537) (xy 216.787864 4.187777) (xy 216.81884 4.107818) (xy 216.842307 4.025342)
			(xy 216.858063 3.941052) (xy 216.865975 3.855669) (xy 216.86647 3.812794) (xy 216.865975 3.769919)
			(xy 296.143921 3.769919) (xy 296.143921 3.855669) (xy 296.151833 3.941052) (xy 296.167589 4.025342)
			(xy 296.191056 4.107818) (xy 296.222032 4.187777) (xy 296.260254 4.264537) (xy 296.305395 4.337443)
			(xy 296.357071 4.405872) (xy 296.41484 4.469242) (xy 296.47821 4.527011) (xy 296.546639 4.578687)
			(xy 296.619545 4.623828) (xy 296.696305 4.66205) (xy 296.776264 4.693026) (xy 296.85874 4.716493)
			(xy 296.94303 4.732249) (xy 297.028413 4.740161) (xy 297.114163 4.740161) (xy 297.199546 4.732249)
			(xy 297.283836 4.716493) (xy 297.366312 4.693026) (xy 297.446271 4.66205) (xy 297.466944 4.651756)
			(xy 298.629324 4.651756) (xy 298.629324 5.515356) (xy 298.629828 5.54491) (xy 298.637877 5.603466)
			(xy 298.653823 5.660381) (xy 298.677372 5.714595) (xy 298.708083 5.765098) (xy 298.745385 5.810948)
			(xy 298.788582 5.851291) (xy 298.836871 5.885377) (xy 298.889351 5.91257) (xy 298.945046 5.932364)
			(xy 299.002917 5.94439) (xy 299.061886 5.948424) (xy 299.120855 5.94439) (xy 299.178726 5.932364)
			(xy 299.234421 5.91257) (xy 299.286901 5.885377) (xy 299.33519 5.851291) (xy 299.378387 5.810948)
			(xy 299.415689 5.765098) (xy 299.4464 5.714595) (xy 299.469949 5.660381) (xy 299.485895 5.603466)
			(xy 299.493944 5.54491) (xy 299.494448 5.515356) (xy 299.494448 4.651756) (xy 299.493944 4.622202)
			(xy 299.485895 4.563646) (xy 299.469949 4.506731) (xy 299.4464 4.452517) (xy 299.415689 4.402014)
			(xy 299.378387 4.356164) (xy 299.33519 4.315821) (xy 299.286901 4.281735) (xy 299.234421 4.254542)
			(xy 299.178726 4.234748) (xy 299.120855 4.222722) (xy 299.061886 4.218689) (xy 299.002917 4.222722)
			(xy 298.945046 4.234748) (xy 298.889351 4.254542) (xy 298.836871 4.281735) (xy 298.788582 4.315821)
			(xy 298.745385 4.356164) (xy 298.708083 4.402014) (xy 298.677372 4.452517) (xy 298.653823 4.506731)
			(xy 298.637877 4.563646) (xy 298.629828 4.622202) (xy 298.629324 4.651756) (xy 297.466944 4.651756)
			(xy 297.523031 4.623828) (xy 297.595937 4.578687) (xy 297.664366 4.527011) (xy 297.727736 4.469242)
			(xy 297.785505 4.405872) (xy 297.837181 4.337443) (xy 297.882322 4.264537) (xy 297.920544 4.187777)
			(xy 297.95152 4.107818) (xy 297.974987 4.025342) (xy 297.990743 3.941052) (xy 297.998655 3.855669)
			(xy 297.99915 3.812794) (xy 297.998655 3.769919) (xy 302.493921 3.769919) (xy 302.493921 3.855669)
			(xy 302.501833 3.941052) (xy 302.517589 4.025342) (xy 302.541056 4.107818) (xy 302.572032 4.187777)
			(xy 302.610254 4.264537) (xy 302.655395 4.337443) (xy 302.707071 4.405872) (xy 302.76484 4.469242)
			(xy 302.82821 4.527011) (xy 302.896639 4.578687) (xy 302.969545 4.623828) (xy 303.046305 4.66205)
			(xy 303.126264 4.693026) (xy 303.20874 4.716493) (xy 303.29303 4.732249) (xy 303.378413 4.740161)
			(xy 303.464163 4.740161) (xy 303.549546 4.732249) (xy 303.633836 4.716493) (xy 303.716312 4.693026)
			(xy 303.796271 4.66205) (xy 303.873031 4.623828) (xy 303.945937 4.578687) (xy 304.014366 4.527011)
			(xy 304.077736 4.469242) (xy 304.135505 4.405872) (xy 304.187181 4.337443) (xy 304.232322 4.264537)
			(xy 304.270544 4.187777) (xy 304.30152 4.107818) (xy 304.324987 4.025342) (xy 304.340743 3.941052)
			(xy 304.348655 3.855669) (xy 304.34915 3.812794) (xy 304.348655 3.769919) (xy 311.155321 3.769919)
			(xy 311.155321 3.855669) (xy 311.163233 3.941052) (xy 311.178989 4.025342) (xy 311.202456 4.107818)
			(xy 311.233432 4.187777) (xy 311.271654 4.264537) (xy 311.316795 4.337443) (xy 311.368471 4.405872)
			(xy 311.42624 4.469242) (xy 311.48961 4.527011) (xy 311.558039 4.578687) (xy 311.630945 4.623828)
			(xy 311.707705 4.66205) (xy 311.787664 4.693026) (xy 311.87014 4.716493) (xy 311.95443 4.732249)
			(xy 312.039813 4.740161) (xy 312.125563 4.740161) (xy 312.210946 4.732249) (xy 312.295236 4.716493)
			(xy 312.377712 4.693026) (xy 312.457671 4.66205) (xy 312.478344 4.651756) (xy 316.012068 4.651756)
			(xy 316.012068 5.515356) (xy 316.012572 5.54491) (xy 316.020621 5.603466) (xy 316.036567 5.660381)
			(xy 316.060116 5.714595) (xy 316.090827 5.765098) (xy 316.128129 5.810948) (xy 316.171326 5.851291)
			(xy 316.219615 5.885377) (xy 316.272095 5.91257) (xy 316.32779 5.932364) (xy 316.385661 5.94439)
			(xy 316.44463 5.948424) (xy 316.503599 5.94439) (xy 316.56147 5.932364) (xy 316.617165 5.91257) (xy 316.669645 5.885377)
			(xy 316.717934 5.851291) (xy 316.761131 5.810948) (xy 316.798433 5.765098) (xy 316.829144 5.714595)
			(xy 316.852693 5.660381) (xy 316.868639 5.603466) (xy 316.876688 5.54491) (xy 316.877192 5.515356)
			(xy 316.877192 4.651756) (xy 316.876688 4.622202) (xy 316.868639 4.563646) (xy 316.852693 4.506731)
			(xy 316.829144 4.452517) (xy 316.798433 4.402014) (xy 316.761131 4.356164) (xy 316.717934 4.315821)
			(xy 316.669645 4.281735) (xy 316.617165 4.254542) (xy 316.56147 4.234748) (xy 316.503599 4.222722)
			(xy 316.44463 4.218689) (xy 316.385661 4.222722) (xy 316.32779 4.234748) (xy 316.272095 4.254542)
			(xy 316.219615 4.281735) (xy 316.171326 4.315821) (xy 316.128129 4.356164) (xy 316.090827 4.402014)
			(xy 316.060116 4.452517) (xy 316.036567 4.506731) (xy 316.020621 4.563646) (xy 316.012572 4.622202)
			(xy 316.012068 4.651756) (xy 312.478344 4.651756) (xy 312.534431 4.623828) (xy 312.607337 4.578687)
			(xy 312.675766 4.527011) (xy 312.739136 4.469242) (xy 312.796905 4.405872) (xy 312.848581 4.337443)
			(xy 312.893722 4.264537) (xy 312.931944 4.187777) (xy 312.96292 4.107818) (xy 312.986387 4.025342)
			(xy 313.002143 3.941052) (xy 313.010055 3.855669) (xy 313.01055 3.812794) (xy 313.010055 3.769919)
			(xy 317.505321 3.769919) (xy 317.505321 3.855669) (xy 317.513233 3.941052) (xy 317.528989 4.025342)
			(xy 317.552456 4.107818) (xy 317.583432 4.187777) (xy 317.621654 4.264537) (xy 317.666795 4.337443)
			(xy 317.718471 4.405872) (xy 317.77624 4.469242) (xy 317.83961 4.527011) (xy 317.908039 4.578687)
			(xy 317.980945 4.623828) (xy 318.057705 4.66205) (xy 318.137664 4.693026) (xy 318.22014 4.716493)
			(xy 318.30443 4.732249) (xy 318.389813 4.740161) (xy 318.475563 4.740161) (xy 318.560946 4.732249)
			(xy 318.645236 4.716493) (xy 318.727712 4.693026) (xy 318.807671 4.66205) (xy 318.884431 4.623828)
			(xy 318.957337 4.578687) (xy 319.025766 4.527011) (xy 319.089136 4.469242) (xy 319.146905 4.405872)
			(xy 319.198581 4.337443) (xy 319.243722 4.264537) (xy 319.281944 4.187777) (xy 319.31292 4.107818)
			(xy 319.336387 4.025342) (xy 319.352143 3.941052) (xy 319.360055 3.855669) (xy 319.36055 3.812794)
			(xy 319.360055 3.769919) (xy 361.894107 3.769919) (xy 361.894107 3.855669) (xy 361.902019 3.941052)
			(xy 361.917775 4.025342) (xy 361.941242 4.107818) (xy 361.972218 4.187777) (xy 362.01044 4.264537)
			(xy 362.055581 4.337443) (xy 362.107257 4.405872) (xy 362.165026 4.469242) (xy 362.228396 4.527011)
			(xy 362.296825 4.578687) (xy 362.369731 4.623828) (xy 362.446491 4.66205) (xy 362.52645 4.693026)
			(xy 362.608926 4.716493) (xy 362.693216 4.732249) (xy 362.778599 4.740161) (xy 362.864349 4.740161)
			(xy 362.949732 4.732249) (xy 363.034022 4.716493) (xy 363.116498 4.693026) (xy 363.196457 4.66205)
			(xy 363.21713 4.651756) (xy 364.379764 4.651756) (xy 364.379764 5.515356) (xy 364.380268 5.544892)
			(xy 364.388312 5.603414) (xy 364.404249 5.660296) (xy 364.427784 5.714478) (xy 364.458477 5.764951)
			(xy 364.495757 5.810774) (xy 364.538929 5.851094) (xy 364.587189 5.88516) (xy 364.639639 5.912337)
			(xy 364.6953 5.932119) (xy 364.753137 5.944138) (xy 364.812072 5.948169) (xy 364.871007 5.944138)
			(xy 364.928844 5.932119) (xy 364.984505 5.912337) (xy 365.036955 5.88516) (xy 365.085215 5.851094)
			(xy 365.128387 5.810774) (xy 365.165667 5.764951) (xy 365.19636 5.714478) (xy 365.219895 5.660296)
			(xy 365.235832 5.603414) (xy 365.243876 5.544892) (xy 365.24438 5.515356) (xy 365.24438 4.836973)
			(xy 385.651997 4.836973) (xy 385.651997 4.922723) (xy 385.659909 5.008106) (xy 385.675665 5.092396)
			(xy 385.699132 5.174872) (xy 385.730108 5.254831) (xy 385.76833 5.331591) (xy 385.813471 5.404497)
			(xy 385.865147 5.472926) (xy 385.922916 5.536296) (xy 385.986286 5.594065) (xy 386.054715 5.645741)
			(xy 386.127621 5.690882) (xy 386.204381 5.729104) (xy 386.28434 5.76008) (xy 386.366816 5.783547)
			(xy 386.451106 5.799303) (xy 386.536489 5.807215) (xy 386.622239 5.807215) (xy 386.707622 5.799303)
			(xy 386.791912 5.783547) (xy 386.874388 5.76008) (xy 386.954347 5.729104) (xy 386.97502 5.71881)
			(xy 390.508744 5.71881) (xy 390.508744 6.58241) (xy 390.509248 6.611964) (xy 390.517297 6.67052)
			(xy 390.533243 6.727435) (xy 390.556792 6.781649) (xy 390.587503 6.832152) (xy 390.624805 6.878002)
			(xy 390.668002 6.918345) (xy 390.716291 6.952431) (xy 390.768771 6.979624) (xy 390.824466 6.999418)
			(xy 390.882337 7.011444) (xy 390.941306 7.015478) (xy 391.000275 7.011444) (xy 391.058146 6.999418)
			(xy 391.113841 6.979624) (xy 391.166321 6.952431) (xy 391.21461 6.918345) (xy 391.257807 6.878002)
			(xy 391.295109 6.832152) (xy 391.32582 6.781649) (xy 391.349369 6.727435) (xy 391.365315 6.67052)
			(xy 391.373364 6.611964) (xy 391.373868 6.58241) (xy 391.373868 5.71881) (xy 391.373364 5.689256)
			(xy 391.365315 5.6307) (xy 391.349369 5.573785) (xy 391.32582 5.519571) (xy 391.295109 5.469068)
			(xy 391.257807 5.423218) (xy 391.21461 5.382875) (xy 391.166321 5.348789) (xy 391.113841 5.321596)
			(xy 391.058146 5.301802) (xy 391.000275 5.289776) (xy 390.941306 5.285743) (xy 390.882337 5.289776)
			(xy 390.824466 5.301802) (xy 390.768771 5.321596) (xy 390.716291 5.348789) (xy 390.668002 5.382875)
			(xy 390.624805 5.423218) (xy 390.587503 5.469068) (xy 390.556792 5.519571) (xy 390.533243 5.573785)
			(xy 390.517297 5.6307) (xy 390.509248 5.689256) (xy 390.508744 5.71881) (xy 386.97502 5.71881) (xy 387.031107 5.690882)
			(xy 387.104013 5.645741) (xy 387.172442 5.594065) (xy 387.235812 5.536296) (xy 387.293581 5.472926)
			(xy 387.345257 5.404497) (xy 387.390398 5.331591) (xy 387.42862 5.254831) (xy 387.459596 5.174872)
			(xy 387.483063 5.092396) (xy 387.498819 5.008106) (xy 387.506731 4.922723) (xy 387.507226 4.879848)
			(xy 387.506731 4.836973) (xy 392.001997 4.836973) (xy 392.001997 4.922723) (xy 392.009909 5.008106)
			(xy 392.025665 5.092396) (xy 392.049132 5.174872) (xy 392.080108 5.254831) (xy 392.11833 5.331591)
			(xy 392.163471 5.404497) (xy 392.215147 5.472926) (xy 392.272916 5.536296) (xy 392.336286 5.594065)
			(xy 392.404715 5.645741) (xy 392.477621 5.690882) (xy 392.554381 5.729104) (xy 392.63434 5.76008)
			(xy 392.716816 5.783547) (xy 392.801106 5.799303) (xy 392.886489 5.807215) (xy 392.972239 5.807215)
			(xy 393.057622 5.799303) (xy 393.141912 5.783547) (xy 393.224388 5.76008) (xy 393.304347 5.729104)
			(xy 393.381107 5.690882) (xy 393.454013 5.645741) (xy 393.522442 5.594065) (xy 393.585812 5.536296)
			(xy 393.643581 5.472926) (xy 393.695257 5.404497) (xy 393.740398 5.331591) (xy 393.77862 5.254831)
			(xy 393.809596 5.174872) (xy 393.833063 5.092396) (xy 393.848819 5.008106) (xy 393.856731 4.922723)
			(xy 393.857226 4.879848) (xy 393.856731 4.836973) (xy 436.390783 4.836973) (xy 436.390783 4.922723)
			(xy 436.398695 5.008106) (xy 436.414451 5.092396) (xy 436.437918 5.174872) (xy 436.468894 5.254831)
			(xy 436.507116 5.331591) (xy 436.552257 5.404497) (xy 436.603933 5.472926) (xy 436.661702 5.536296)
			(xy 436.725072 5.594065) (xy 436.793501 5.645741) (xy 436.866407 5.690882) (xy 436.943167 5.729104)
			(xy 437.023126 5.76008) (xy 437.105602 5.783547) (xy 437.189892 5.799303) (xy 437.275275 5.807215)
			(xy 437.361025 5.807215) (xy 437.446408 5.799303) (xy 437.530698 5.783547) (xy 437.613174 5.76008)
			(xy 437.693133 5.729104) (xy 437.713806 5.71881) (xy 438.87644 5.71881) (xy 438.87644 6.58241) (xy 438.876944 6.611946)
			(xy 438.884988 6.670468) (xy 438.900925 6.72735) (xy 438.92446 6.781532) (xy 438.955153 6.832005)
			(xy 438.992433 6.877828) (xy 439.035605 6.918148) (xy 439.083865 6.952214) (xy 439.136315 6.979391)
			(xy 439.191976 6.999173) (xy 439.249813 7.011192) (xy 439.308748 7.015223) (xy 439.367683 7.011192)
			(xy 439.42552 6.999173) (xy 439.481181 6.979391) (xy 439.533631 6.952214) (xy 439.581891 6.918148)
			(xy 439.625063 6.877828) (xy 439.662343 6.832005) (xy 439.693036 6.781532) (xy 439.716571 6.72735)
			(xy 439.732508 6.670468) (xy 439.740552 6.611946) (xy 439.741056 6.58241) (xy 439.741056 5.71881)
			(xy 439.740552 5.689274) (xy 439.732508 5.630752) (xy 439.716571 5.57387) (xy 439.693036 5.519688)
			(xy 439.662343 5.469215) (xy 439.625063 5.423392) (xy 439.581891 5.383072) (xy 439.533631 5.349006)
			(xy 439.481181 5.321829) (xy 439.42552 5.302047) (xy 439.367683 5.290028) (xy 439.308748 5.285997)
			(xy 439.249813 5.290028) (xy 439.191976 5.302047) (xy 439.136315 5.321829) (xy 439.083865 5.349006)
			(xy 439.035605 5.383072) (xy 438.992433 5.423392) (xy 438.955153 5.469215) (xy 438.92446 5.519688)
			(xy 438.900925 5.57387) (xy 438.884988 5.630752) (xy 438.876944 5.689274) (xy 438.87644 5.71881)
			(xy 437.713806 5.71881) (xy 437.769893 5.690882) (xy 437.842799 5.645741) (xy 437.911228 5.594065)
			(xy 437.974598 5.536296) (xy 438.032367 5.472926) (xy 438.084043 5.404497) (xy 438.129184 5.331591)
			(xy 438.167406 5.254831) (xy 438.198382 5.174872) (xy 438.221849 5.092396) (xy 438.237605 5.008106)
			(xy 438.245517 4.922723) (xy 438.246012 4.879848) (xy 438.245517 4.836973) (xy 442.740783 4.836973)
			(xy 442.740783 4.922723) (xy 442.748695 5.008106) (xy 442.764451 5.092396) (xy 442.787918 5.174872)
			(xy 442.818894 5.254831) (xy 442.857116 5.331591) (xy 442.902257 5.404497) (xy 442.953933 5.472926)
			(xy 443.011702 5.536296) (xy 443.075072 5.594065) (xy 443.143501 5.645741) (xy 443.216407 5.690882)
			(xy 443.293167 5.729104) (xy 443.373126 5.76008) (xy 443.455602 5.783547) (xy 443.539892 5.799303)
			(xy 443.625275 5.807215) (xy 443.711025 5.807215) (xy 443.796408 5.799303) (xy 443.880698 5.783547)
			(xy 443.963174 5.76008) (xy 444.043133 5.729104) (xy 444.119893 5.690882) (xy 444.192799 5.645741)
			(xy 444.261228 5.594065) (xy 444.324598 5.536296) (xy 444.382367 5.472926) (xy 444.434043 5.404497)
			(xy 444.479184 5.331591) (xy 444.517406 5.254831) (xy 444.548382 5.174872) (xy 444.571849 5.092396)
			(xy 444.587605 5.008106) (xy 444.595517 4.922723) (xy 444.596012 4.879848) (xy 444.595517 4.836973)
			(xy 444.587605 4.75159) (xy 444.571849 4.6673) (xy 444.548382 4.584824) (xy 444.517406 4.504865)
			(xy 444.479184 4.428105) (xy 444.434043 4.355199) (xy 444.382367 4.28677) (xy 444.324598 4.2234)
			(xy 444.261228 4.165631) (xy 444.192799 4.113955) (xy 444.119893 4.068814) (xy 444.043133 4.030592)
			(xy 443.963174 3.999616) (xy 443.880698 3.976149) (xy 443.796408 3.960393) (xy 443.711025 3.952481)
			(xy 443.625275 3.952481) (xy 443.539892 3.960393) (xy 443.455602 3.976149) (xy 443.373126 3.999616)
			(xy 443.293167 4.030592) (xy 443.216407 4.068814) (xy 443.143501 4.113955) (xy 443.075072 4.165631)
			(xy 443.011702 4.2234) (xy 442.953933 4.28677) (xy 442.902257 4.355199) (xy 442.857116 4.428105)
			(xy 442.818894 4.504865) (xy 442.787918 4.584824) (xy 442.764451 4.6673) (xy 442.748695 4.75159)
			(xy 442.740783 4.836973) (xy 438.245517 4.836973) (xy 438.237605 4.75159) (xy 438.221849 4.6673)
			(xy 438.198382 4.584824) (xy 438.167406 4.504865) (xy 438.129184 4.428105) (xy 438.084043 4.355199)
			(xy 438.032367 4.28677) (xy 437.974598 4.2234) (xy 437.911228 4.165631) (xy 437.842799 4.113955)
			(xy 437.769893 4.068814) (xy 437.693133 4.030592) (xy 437.613174 3.999616) (xy 437.530698 3.976149)
			(xy 437.446408 3.960393) (xy 437.361025 3.952481) (xy 437.275275 3.952481) (xy 437.189892 3.960393)
			(xy 437.105602 3.976149) (xy 437.023126 3.999616) (xy 436.943167 4.030592) (xy 436.866407 4.068814)
			(xy 436.793501 4.113955) (xy 436.725072 4.165631) (xy 436.661702 4.2234) (xy 436.603933 4.28677)
			(xy 436.552257 4.355199) (xy 436.507116 4.428105) (xy 436.468894 4.504865) (xy 436.437918 4.584824)
			(xy 436.414451 4.6673) (xy 436.398695 4.75159) (xy 436.390783 4.836973) (xy 393.856731 4.836973)
			(xy 393.848819 4.75159) (xy 393.833063 4.6673) (xy 393.809596 4.584824) (xy 393.77862 4.504865) (xy 393.740398 4.428105)
			(xy 393.695257 4.355199) (xy 393.643581 4.28677) (xy 393.585812 4.2234) (xy 393.522442 4.165631)
			(xy 393.454013 4.113955) (xy 393.381107 4.068814) (xy 393.304347 4.030592) (xy 393.224388 3.999616)
			(xy 393.141912 3.976149) (xy 393.057622 3.960393) (xy 392.972239 3.952481) (xy 392.886489 3.952481)
			(xy 392.801106 3.960393) (xy 392.716816 3.976149) (xy 392.63434 3.999616) (xy 392.554381 4.030592)
			(xy 392.477621 4.068814) (xy 392.404715 4.113955) (xy 392.336286 4.165631) (xy 392.272916 4.2234)
			(xy 392.215147 4.28677) (xy 392.163471 4.355199) (xy 392.11833 4.428105) (xy 392.080108 4.504865)
			(xy 392.049132 4.584824) (xy 392.025665 4.6673) (xy 392.009909 4.75159) (xy 392.001997 4.836973)
			(xy 387.506731 4.836973) (xy 387.498819 4.75159) (xy 387.483063 4.6673) (xy 387.459596 4.584824)
			(xy 387.42862 4.504865) (xy 387.390398 4.428105) (xy 387.345257 4.355199) (xy 387.293581 4.28677)
			(xy 387.235812 4.2234) (xy 387.172442 4.165631) (xy 387.104013 4.113955) (xy 387.031107 4.068814)
			(xy 386.954347 4.030592) (xy 386.874388 3.999616) (xy 386.791912 3.976149) (xy 386.707622 3.960393)
			(xy 386.622239 3.952481) (xy 386.536489 3.952481) (xy 386.451106 3.960393) (xy 386.366816 3.976149)
			(xy 386.28434 3.999616) (xy 386.204381 4.030592) (xy 386.127621 4.068814) (xy 386.054715 4.113955)
			(xy 385.986286 4.165631) (xy 385.922916 4.2234) (xy 385.865147 4.28677) (xy 385.813471 4.355199)
			(xy 385.76833 4.428105) (xy 385.730108 4.504865) (xy 385.699132 4.584824) (xy 385.675665 4.6673)
			(xy 385.659909 4.75159) (xy 385.651997 4.836973) (xy 365.24438 4.836973) (xy 365.24438 4.651756)
			(xy 365.243876 4.62222) (xy 365.235832 4.563698) (xy 365.219895 4.506816) (xy 365.19636 4.452634)
			(xy 365.165667 4.402161) (xy 365.128387 4.356338) (xy 365.085215 4.316018) (xy 365.036955 4.281952)
			(xy 364.984505 4.254775) (xy 364.928844 4.234993) (xy 364.871007 4.222974) (xy 364.812072 4.218943)
			(xy 364.753137 4.222974) (xy 364.6953 4.234993) (xy 364.639639 4.254775) (xy 364.587189 4.281952)
			(xy 364.538929 4.316018) (xy 364.495757 4.356338) (xy 364.458477 4.402161) (xy 364.427784 4.452634)
			(xy 364.404249 4.506816) (xy 364.388312 4.563698) (xy 364.380268 4.62222) (xy 364.379764 4.651756)
			(xy 363.21713 4.651756) (xy 363.273217 4.623828) (xy 363.346123 4.578687) (xy 363.414552 4.527011)
			(xy 363.477922 4.469242) (xy 363.535691 4.405872) (xy 363.587367 4.337443) (xy 363.632508 4.264537)
			(xy 363.67073 4.187777) (xy 363.701706 4.107818) (xy 363.725173 4.025342) (xy 363.740929 3.941052)
			(xy 363.748841 3.855669) (xy 363.749336 3.812794) (xy 363.748841 3.769919) (xy 368.244107 3.769919)
			(xy 368.244107 3.855669) (xy 368.252019 3.941052) (xy 368.267775 4.025342) (xy 368.291242 4.107818)
			(xy 368.322218 4.187777) (xy 368.36044 4.264537) (xy 368.405581 4.337443) (xy 368.457257 4.405872)
			(xy 368.515026 4.469242) (xy 368.578396 4.527011) (xy 368.646825 4.578687) (xy 368.719731 4.623828)
			(xy 368.796491 4.66205) (xy 368.87645 4.693026) (xy 368.958926 4.716493) (xy 369.043216 4.732249)
			(xy 369.128599 4.740161) (xy 369.214349 4.740161) (xy 369.299732 4.732249) (xy 369.384022 4.716493)
			(xy 369.466498 4.693026) (xy 369.546457 4.66205) (xy 369.623217 4.623828) (xy 369.696123 4.578687)
			(xy 369.764552 4.527011) (xy 369.827922 4.469242) (xy 369.885691 4.405872) (xy 369.937367 4.337443)
			(xy 369.982508 4.264537) (xy 370.02073 4.187777) (xy 370.051706 4.107818) (xy 370.075173 4.025342)
			(xy 370.090929 3.941052) (xy 370.098841 3.855669) (xy 370.099336 3.812794) (xy 370.098841 3.769919)
			(xy 370.090929 3.684536) (xy 370.075173 3.600246) (xy 370.051706 3.51777) (xy 370.02073 3.437811)
			(xy 369.982508 3.361051) (xy 369.937367 3.288145) (xy 369.885691 3.219716) (xy 369.827922 3.156346)
			(xy 369.764552 3.098577) (xy 369.696123 3.046901) (xy 369.623217 3.00176) (xy 369.546457 2.963538)
			(xy 369.466498 2.932562) (xy 369.384022 2.909095) (xy 369.299732 2.893339) (xy 369.214349 2.885427)
			(xy 369.128599 2.885427) (xy 369.043216 2.893339) (xy 368.958926 2.909095) (xy 368.87645 2.932562)
			(xy 368.796491 2.963538) (xy 368.719731 3.00176) (xy 368.646825 3.046901) (xy 368.578396 3.098577)
			(xy 368.515026 3.156346) (xy 368.457257 3.219716) (xy 368.405581 3.288145) (xy 368.36044 3.361051)
			(xy 368.322218 3.437811) (xy 368.291242 3.51777) (xy 368.267775 3.600246) (xy 368.252019 3.684536)
			(xy 368.244107 3.769919) (xy 363.748841 3.769919) (xy 363.740929 3.684536) (xy 363.725173 3.600246)
			(xy 363.701706 3.51777) (xy 363.67073 3.437811) (xy 363.632508 3.361051) (xy 363.587367 3.288145)
			(xy 363.535691 3.219716) (xy 363.477922 3.156346) (xy 363.414552 3.098577) (xy 363.346123 3.046901)
			(xy 363.273217 3.00176) (xy 363.196457 2.963538) (xy 363.116498 2.932562) (xy 363.034022 2.909095)
			(xy 362.949732 2.893339) (xy 362.864349 2.885427) (xy 362.778599 2.885427) (xy 362.693216 2.893339)
			(xy 362.608926 2.909095) (xy 362.52645 2.932562) (xy 362.446491 2.963538) (xy 362.369731 3.00176)
			(xy 362.296825 3.046901) (xy 362.228396 3.098577) (xy 362.165026 3.156346) (xy 362.107257 3.219716)
			(xy 362.055581 3.288145) (xy 362.01044 3.361051) (xy 361.972218 3.437811) (xy 361.941242 3.51777)
			(xy 361.917775 3.600246) (xy 361.902019 3.684536) (xy 361.894107 3.769919) (xy 319.360055 3.769919)
			(xy 319.352143 3.684536) (xy 319.336387 3.600246) (xy 319.31292 3.51777) (xy 319.281944 3.437811)
			(xy 319.243722 3.361051) (xy 319.198581 3.288145) (xy 319.146905 3.219716) (xy 319.089136 3.156346)
			(xy 319.025766 3.098577) (xy 318.957337 3.046901) (xy 318.884431 3.00176) (xy 318.807671 2.963538)
			(xy 318.727712 2.932562) (xy 318.645236 2.909095) (xy 318.560946 2.893339) (xy 318.475563 2.885427)
			(xy 318.389813 2.885427) (xy 318.30443 2.893339) (xy 318.22014 2.909095) (xy 318.137664 2.932562)
			(xy 318.057705 2.963538) (xy 317.980945 3.00176) (xy 317.908039 3.046901) (xy 317.83961 3.098577)
			(xy 317.77624 3.156346) (xy 317.718471 3.219716) (xy 317.666795 3.288145) (xy 317.621654 3.361051)
			(xy 317.583432 3.437811) (xy 317.552456 3.51777) (xy 317.528989 3.600246) (xy 317.513233 3.684536)
			(xy 317.505321 3.769919) (xy 313.010055 3.769919) (xy 313.002143 3.684536) (xy 312.986387 3.600246)
			(xy 312.96292 3.51777) (xy 312.931944 3.437811) (xy 312.893722 3.361051) (xy 312.848581 3.288145)
			(xy 312.796905 3.219716) (xy 312.739136 3.156346) (xy 312.675766 3.098577) (xy 312.607337 3.046901)
			(xy 312.534431 3.00176) (xy 312.457671 2.963538) (xy 312.377712 2.932562) (xy 312.295236 2.909095)
			(xy 312.210946 2.893339) (xy 312.125563 2.885427) (xy 312.039813 2.885427) (xy 311.95443 2.893339)
			(xy 311.87014 2.909095) (xy 311.787664 2.932562) (xy 311.707705 2.963538) (xy 311.630945 3.00176)
			(xy 311.558039 3.046901) (xy 311.48961 3.098577) (xy 311.42624 3.156346) (xy 311.368471 3.219716)
			(xy 311.316795 3.288145) (xy 311.271654 3.361051) (xy 311.233432 3.437811) (xy 311.202456 3.51777)
			(xy 311.178989 3.600246) (xy 311.163233 3.684536) (xy 311.155321 3.769919) (xy 304.348655 3.769919)
			(xy 304.340743 3.684536) (xy 304.324987 3.600246) (xy 304.30152 3.51777) (xy 304.270544 3.437811)
			(xy 304.232322 3.361051) (xy 304.187181 3.288145) (xy 304.135505 3.219716) (xy 304.077736 3.156346)
			(xy 304.014366 3.098577) (xy 303.945937 3.046901) (xy 303.873031 3.00176) (xy 303.796271 2.963538)
			(xy 303.716312 2.932562) (xy 303.633836 2.909095) (xy 303.549546 2.893339) (xy 303.464163 2.885427)
			(xy 303.378413 2.885427) (xy 303.29303 2.893339) (xy 303.20874 2.909095) (xy 303.126264 2.932562)
			(xy 303.046305 2.963538) (xy 302.969545 3.00176) (xy 302.896639 3.046901) (xy 302.82821 3.098577)
			(xy 302.76484 3.156346) (xy 302.707071 3.219716) (xy 302.655395 3.288145) (xy 302.610254 3.361051)
			(xy 302.572032 3.437811) (xy 302.541056 3.51777) (xy 302.517589 3.600246) (xy 302.501833 3.684536)
			(xy 302.493921 3.769919) (xy 297.998655 3.769919) (xy 297.990743 3.684536) (xy 297.974987 3.600246)
			(xy 297.95152 3.51777) (xy 297.920544 3.437811) (xy 297.882322 3.361051) (xy 297.837181 3.288145)
			(xy 297.785505 3.219716) (xy 297.727736 3.156346) (xy 297.664366 3.098577) (xy 297.595937 3.046901)
			(xy 297.523031 3.00176) (xy 297.446271 2.963538) (xy 297.366312 2.932562) (xy 297.283836 2.909095)
			(xy 297.199546 2.893339) (xy 297.114163 2.885427) (xy 297.028413 2.885427) (xy 296.94303 2.893339)
			(xy 296.85874 2.909095) (xy 296.776264 2.932562) (xy 296.696305 2.963538) (xy 296.619545 3.00176)
			(xy 296.546639 3.046901) (xy 296.47821 3.098577) (xy 296.41484 3.156346) (xy 296.357071 3.219716)
			(xy 296.305395 3.288145) (xy 296.260254 3.361051) (xy 296.222032 3.437811) (xy 296.191056 3.51777)
			(xy 296.167589 3.600246) (xy 296.151833 3.684536) (xy 296.143921 3.769919) (xy 216.865975 3.769919)
			(xy 216.858063 3.684536) (xy 216.842307 3.600246) (xy 216.81884 3.51777) (xy 216.787864 3.437811)
			(xy 216.749642 3.361051) (xy 216.704501 3.288145) (xy 216.652825 3.219716) (xy 216.595056 3.156346)
			(xy 216.531686 3.098577) (xy 216.463257 3.046901) (xy 216.390351 3.00176) (xy 216.313591 2.963538)
			(xy 216.233632 2.932562) (xy 216.151156 2.909095) (xy 216.066866 2.893339) (xy 215.981483 2.885427)
			(xy 215.895733 2.885427) (xy 215.81035 2.893339) (xy 215.72606 2.909095) (xy 215.643584 2.932562)
			(xy 215.563625 2.963538) (xy 215.486865 3.00176) (xy 215.413959 3.046901) (xy 215.34553 3.098577)
			(xy 215.28216 3.156346) (xy 215.224391 3.219716) (xy 215.172715 3.288145) (xy 215.127574 3.361051)
			(xy 215.089352 3.437811) (xy 215.058376 3.51777) (xy 215.034909 3.600246) (xy 215.019153 3.684536)
			(xy 215.011241 3.769919) (xy 210.515975 3.769919) (xy 210.508063 3.684536) (xy 210.492307 3.600246)
			(xy 210.46884 3.51777) (xy 210.437864 3.437811) (xy 210.399642 3.361051) (xy 210.354501 3.288145)
			(xy 210.302825 3.219716) (xy 210.245056 3.156346) (xy 210.181686 3.098577) (xy 210.113257 3.046901)
			(xy 210.040351 3.00176) (xy 209.963591 2.963538) (xy 209.883632 2.932562) (xy 209.801156 2.909095)
			(xy 209.716866 2.893339) (xy 209.631483 2.885427) (xy 209.545733 2.885427) (xy 209.46035 2.893339)
			(xy 209.37606 2.909095) (xy 209.293584 2.932562) (xy 209.213625 2.963538) (xy 209.136865 3.00176)
			(xy 209.063959 3.046901) (xy 208.99553 3.098577) (xy 208.93216 3.156346) (xy 208.874391 3.219716)
			(xy 208.822715 3.288145) (xy 208.777574 3.361051) (xy 208.739352 3.437811) (xy 208.708376 3.51777)
			(xy 208.684909 3.600246) (xy 208.669153 3.684536) (xy 208.661241 3.769919) (xy 184.818528 3.769919)
			(xy 184.818528 3.092196) (xy 184.818024 3.06266) (xy 184.80998 3.004138) (xy 184.794043 2.947256)
			(xy 184.770508 2.893074) (xy 184.739815 2.842601) (xy 184.702535 2.796778) (xy 184.659363 2.756458)
			(xy 184.611103 2.722392) (xy 184.558653 2.695215) (xy 184.502992 2.675433) (xy 184.445155 2.663414)
			(xy 184.38622 2.659383) (xy 184.327285 2.663414) (xy 184.269448 2.675433) (xy 184.213787 2.695215)
			(xy 184.161337 2.722392) (xy 184.113077 2.756458) (xy 184.069905 2.796778) (xy 184.032625 2.842601)
			(xy 184.001932 2.893074) (xy 183.978397 2.947256) (xy 183.96246 3.004138) (xy 183.954416 3.06266)
			(xy 183.953912 3.092196) (xy 182.791278 3.092196) (xy 182.847365 3.064268) (xy 182.920271 3.019127)
			(xy 182.9887 2.967451) (xy 183.05207 2.909682) (xy 183.109839 2.846312) (xy 183.161515 2.777883)
			(xy 183.206656 2.704977) (xy 183.244878 2.628217) (xy 183.275854 2.548258) (xy 183.299321 2.465782)
			(xy 183.315077 2.381492) (xy 183.322989 2.296109) (xy 183.323484 2.253234) (xy 183.322989 2.210359)
			(xy 187.818255 2.210359) (xy 187.818255 2.296109) (xy 187.826167 2.381492) (xy 187.841923 2.465782)
			(xy 187.86539 2.548258) (xy 187.896366 2.628217) (xy 187.934588 2.704977) (xy 187.979729 2.777883)
			(xy 188.031405 2.846312) (xy 188.089174 2.909682) (xy 188.152544 2.967451) (xy 188.220973 3.019127)
			(xy 188.293879 3.064268) (xy 188.370639 3.10249) (xy 188.450598 3.133466) (xy 188.533074 3.156933)
			(xy 188.617364 3.172689) (xy 188.702747 3.180601) (xy 188.788497 3.180601) (xy 188.87388 3.172689)
			(xy 188.95817 3.156933) (xy 189.040646 3.133466) (xy 189.120605 3.10249) (xy 189.197365 3.064268)
			(xy 189.270271 3.019127) (xy 189.3387 2.967451) (xy 189.40207 2.909682) (xy 189.459839 2.846312)
			(xy 189.511515 2.777883) (xy 189.556656 2.704977) (xy 189.594878 2.628217) (xy 189.625854 2.548258)
			(xy 189.649321 2.465782) (xy 189.665077 2.381492) (xy 189.672989 2.296109) (xy 189.673484 2.253234)
			(xy 189.672989 2.210359) (xy 189.665077 2.124976) (xy 189.649321 2.040686) (xy 189.625854 1.95821)
			(xy 189.594878 1.878251) (xy 189.556656 1.801491) (xy 189.511515 1.728585) (xy 189.459839 1.660156)
			(xy 189.40207 1.596786) (xy 189.3387 1.539017) (xy 189.270271 1.487341) (xy 189.197365 1.4422) (xy 189.120605 1.403978)
			(xy 189.040646 1.373002) (xy 188.95817 1.349535) (xy 188.87388 1.333779) (xy 188.788497 1.325867)
			(xy 188.702747 1.325867) (xy 188.617364 1.333779) (xy 188.533074 1.349535) (xy 188.450598 1.373002)
			(xy 188.370639 1.403978) (xy 188.293879 1.4422) (xy 188.220973 1.487341) (xy 188.152544 1.539017)
			(xy 188.089174 1.596786) (xy 188.031405 1.660156) (xy 187.979729 1.728585) (xy 187.934588 1.801491)
			(xy 187.896366 1.878251) (xy 187.86539 1.95821) (xy 187.841923 2.040686) (xy 187.826167 2.124976)
			(xy 187.818255 2.210359) (xy 183.322989 2.210359) (xy 183.315077 2.124976) (xy 183.299321 2.040686)
			(xy 183.275854 1.95821) (xy 183.244878 1.878251) (xy 183.206656 1.801491) (xy 183.161515 1.728585)
			(xy 183.109839 1.660156) (xy 183.05207 1.596786) (xy 182.9887 1.539017) (xy 182.920271 1.487341)
			(xy 182.847365 1.4422) (xy 182.770605 1.403978) (xy 182.690646 1.373002) (xy 182.60817 1.349535)
			(xy 182.52388 1.333779) (xy 182.438497 1.325867) (xy 182.352747 1.325867) (xy 182.267364 1.333779)
			(xy 182.183074 1.349535) (xy 182.100598 1.373002) (xy 182.020639 1.403978) (xy 181.943879 1.4422)
			(xy 181.870973 1.487341) (xy 181.802544 1.539017) (xy 181.739174 1.596786) (xy 181.681405 1.660156)
			(xy 181.629729 1.728585) (xy 181.584588 1.801491) (xy 181.546366 1.878251) (xy 181.51539 1.95821)
			(xy 181.491923 2.040686) (xy 181.476167 2.124976) (xy 181.468255 2.210359) (xy 102.190309 2.210359)
			(xy 102.182397 2.124976) (xy 102.166641 2.040686) (xy 102.143174 1.95821) (xy 102.112198 1.878251)
			(xy 102.073976 1.801491) (xy 102.028835 1.728585) (xy 101.977159 1.660156) (xy 101.91939 1.596786)
			(xy 101.85602 1.539017) (xy 101.787591 1.487341) (xy 101.714685 1.4422) (xy 101.637925 1.403978)
			(xy 101.557966 1.373002) (xy 101.47549 1.349535) (xy 101.3912 1.333779) (xy 101.305817 1.325867)
			(xy 101.220067 1.325867) (xy 101.134684 1.333779) (xy 101.050394 1.349535) (xy 100.967918 1.373002)
			(xy 100.887959 1.403978) (xy 100.811199 1.4422) (xy 100.738293 1.487341) (xy 100.669864 1.539017)
			(xy 100.606494 1.596786) (xy 100.548725 1.660156) (xy 100.497049 1.728585) (xy 100.451908 1.801491)
			(xy 100.413686 1.878251) (xy 100.38271 1.95821) (xy 100.359243 2.040686) (xy 100.343487 2.124976)
			(xy 100.335575 2.210359) (xy 95.840309 2.210359) (xy 95.832397 2.124976) (xy 95.816641 2.040686)
			(xy 95.793174 1.95821) (xy 95.762198 1.878251) (xy 95.723976 1.801491) (xy 95.678835 1.728585) (xy 95.627159 1.660156)
			(xy 95.56939 1.596786) (xy 95.50602 1.539017) (xy 95.437591 1.487341) (xy 95.364685 1.4422) (xy 95.287925 1.403978)
			(xy 95.207966 1.373002) (xy 95.12549 1.349535) (xy 95.0412 1.333779) (xy 94.955817 1.325867) (xy 94.870067 1.325867)
			(xy 94.784684 1.333779) (xy 94.700394 1.349535) (xy 94.617918 1.373002) (xy 94.537959 1.403978) (xy 94.461199 1.4422)
			(xy 94.388293 1.487341) (xy 94.319864 1.539017) (xy 94.256494 1.596786) (xy 94.198725 1.660156) (xy 94.147049 1.728585)
			(xy 94.101908 1.801491) (xy 94.063686 1.878251) (xy 94.03271 1.95821) (xy 94.009243 2.040686) (xy 93.993487 2.124976)
			(xy 93.985575 2.210359) (xy 83.439191 2.210359) (xy 83.525475 2.124078) (xy 83.619275 2.019118) (xy 83.707042 1.909064)
			(xy 83.788501 1.794262) (xy 83.863394 1.675073) (xy 83.931487 1.551873) (xy 83.992565 1.425048) (xy 84.046435 1.294999)
			(xy 84.069209 1.229919) (xy 208.661241 1.229919) (xy 208.661241 1.315669) (xy 208.669153 1.401052)
			(xy 208.684909 1.485342) (xy 208.708376 1.567818) (xy 208.739352 1.647777) (xy 208.777574 1.724537)
			(xy 208.822715 1.797443) (xy 208.874391 1.865872) (xy 208.93216 1.929242) (xy 208.99553 1.987011)
			(xy 209.063959 2.038687) (xy 209.136865 2.083828) (xy 209.213625 2.12205) (xy 209.293584 2.153026)
			(xy 209.37606 2.176493) (xy 209.46035 2.192249) (xy 209.545733 2.200161) (xy 209.631483 2.200161)
			(xy 209.716866 2.192249) (xy 209.801156 2.176493) (xy 209.883632 2.153026) (xy 209.963591 2.12205)
			(xy 209.984264 2.111756) (xy 213.517988 2.111756) (xy 213.517988 2.975356) (xy 213.518492 3.00491)
			(xy 213.526541 3.063466) (xy 213.542487 3.120381) (xy 213.566036 3.174595) (xy 213.596747 3.225098)
			(xy 213.634049 3.270948) (xy 213.677246 3.311291) (xy 213.725535 3.345377) (xy 213.778015 3.37257)
			(xy 213.83371 3.392364) (xy 213.891581 3.40439) (xy 213.95055 3.408424) (xy 214.009519 3.40439) (xy 214.06739 3.392364)
			(xy 214.123085 3.37257) (xy 214.175565 3.345377) (xy 214.223854 3.311291) (xy 214.267051 3.270948)
			(xy 214.304353 3.225098) (xy 214.335064 3.174595) (xy 214.358613 3.120381) (xy 214.374559 3.063466)
			(xy 214.382608 3.00491) (xy 214.383112 2.975356) (xy 214.383112 2.111756) (xy 214.382608 2.082202)
			(xy 214.374559 2.023646) (xy 214.358613 1.966731) (xy 214.335064 1.912517) (xy 214.304353 1.862014)
			(xy 214.267051 1.816164) (xy 214.223854 1.775821) (xy 214.175565 1.741735) (xy 214.123085 1.714542)
			(xy 214.06739 1.694748) (xy 214.009519 1.682722) (xy 213.95055 1.678689) (xy 213.891581 1.682722)
			(xy 213.83371 1.694748) (xy 213.778015 1.714542) (xy 213.725535 1.741735) (xy 213.677246 1.775821)
			(xy 213.634049 1.816164) (xy 213.596747 1.862014) (xy 213.566036 1.912517) (xy 213.542487 1.966731)
			(xy 213.526541 2.023646) (xy 213.518492 2.082202) (xy 213.517988 2.111756) (xy 209.984264 2.111756)
			(xy 210.040351 2.083828) (xy 210.113257 2.038687) (xy 210.181686 1.987011) (xy 210.245056 1.929242)
			(xy 210.302825 1.865872) (xy 210.354501 1.797443) (xy 210.399642 1.724537) (xy 210.437864 1.647777)
			(xy 210.46884 1.567818) (xy 210.492307 1.485342) (xy 210.508063 1.401052) (xy 210.515975 1.315669)
			(xy 210.51647 1.272794) (xy 210.515975 1.229919) (xy 215.011241 1.229919) (xy 215.011241 1.315669)
			(xy 215.019153 1.401052) (xy 215.034909 1.485342) (xy 215.058376 1.567818) (xy 215.089352 1.647777)
			(xy 215.127574 1.724537) (xy 215.172715 1.797443) (xy 215.224391 1.865872) (xy 215.28216 1.929242)
			(xy 215.34553 1.987011) (xy 215.413959 2.038687) (xy 215.486865 2.083828) (xy 215.563625 2.12205)
			(xy 215.643584 2.153026) (xy 215.72606 2.176493) (xy 215.81035 2.192249) (xy 215.895733 2.200161)
			(xy 215.981483 2.200161) (xy 216.066866 2.192249) (xy 216.151156 2.176493) (xy 216.233632 2.153026)
			(xy 216.313591 2.12205) (xy 216.390351 2.083828) (xy 216.463257 2.038687) (xy 216.531686 1.987011)
			(xy 216.595056 1.929242) (xy 216.652825 1.865872) (xy 216.704501 1.797443) (xy 216.749642 1.724537)
			(xy 216.787864 1.647777) (xy 216.81884 1.567818) (xy 216.842307 1.485342) (xy 216.858063 1.401052)
			(xy 216.865975 1.315669) (xy 216.86647 1.272794) (xy 216.865975 1.229919) (xy 296.143921 1.229919)
			(xy 296.143921 1.315669) (xy 296.151833 1.401052) (xy 296.167589 1.485342) (xy 296.191056 1.567818)
			(xy 296.222032 1.647777) (xy 296.260254 1.724537) (xy 296.305395 1.797443) (xy 296.357071 1.865872)
			(xy 296.41484 1.929242) (xy 296.47821 1.987011) (xy 296.546639 2.038687) (xy 296.619545 2.083828)
			(xy 296.696305 2.12205) (xy 296.776264 2.153026) (xy 296.85874 2.176493) (xy 296.94303 2.192249)
			(xy 297.028413 2.200161) (xy 297.114163 2.200161) (xy 297.199546 2.192249) (xy 297.283836 2.176493)
			(xy 297.366312 2.153026) (xy 297.446271 2.12205) (xy 297.466944 2.111756) (xy 298.629324 2.111756)
			(xy 298.629324 2.975356) (xy 298.629828 3.00491) (xy 298.637877 3.063466) (xy 298.653823 3.120381)
			(xy 298.677372 3.174595) (xy 298.708083 3.225098) (xy 298.745385 3.270948) (xy 298.788582 3.311291)
			(xy 298.836871 3.345377) (xy 298.889351 3.37257) (xy 298.945046 3.392364) (xy 299.002917 3.40439)
			(xy 299.061886 3.408424) (xy 299.120855 3.40439) (xy 299.178726 3.392364) (xy 299.234421 3.37257)
			(xy 299.286901 3.345377) (xy 299.33519 3.311291) (xy 299.378387 3.270948) (xy 299.415689 3.225098)
			(xy 299.4464 3.174595) (xy 299.469949 3.120381) (xy 299.485895 3.063466) (xy 299.493944 3.00491)
			(xy 299.494448 2.975356) (xy 299.494448 2.111756) (xy 299.493944 2.082202) (xy 299.485895 2.023646)
			(xy 299.469949 1.966731) (xy 299.4464 1.912517) (xy 299.415689 1.862014) (xy 299.378387 1.816164)
			(xy 299.33519 1.775821) (xy 299.286901 1.741735) (xy 299.234421 1.714542) (xy 299.178726 1.694748)
			(xy 299.120855 1.682722) (xy 299.061886 1.678689) (xy 299.002917 1.682722) (xy 298.945046 1.694748)
			(xy 298.889351 1.714542) (xy 298.836871 1.741735) (xy 298.788582 1.775821) (xy 298.745385 1.816164)
			(xy 298.708083 1.862014) (xy 298.677372 1.912517) (xy 298.653823 1.966731) (xy 298.637877 2.023646)
			(xy 298.629828 2.082202) (xy 298.629324 2.111756) (xy 297.466944 2.111756) (xy 297.523031 2.083828)
			(xy 297.595937 2.038687) (xy 297.664366 1.987011) (xy 297.727736 1.929242) (xy 297.785505 1.865872)
			(xy 297.837181 1.797443) (xy 297.882322 1.724537) (xy 297.920544 1.647777) (xy 297.95152 1.567818)
			(xy 297.974987 1.485342) (xy 297.990743 1.401052) (xy 297.998655 1.315669) (xy 297.99915 1.272794)
			(xy 297.998655 1.229919) (xy 302.493921 1.229919) (xy 302.493921 1.315669) (xy 302.501833 1.401052)
			(xy 302.517589 1.485342) (xy 302.541056 1.567818) (xy 302.572032 1.647777) (xy 302.610254 1.724537)
			(xy 302.655395 1.797443) (xy 302.707071 1.865872) (xy 302.76484 1.929242) (xy 302.82821 1.987011)
			(xy 302.896639 2.038687) (xy 302.969545 2.083828) (xy 303.046305 2.12205) (xy 303.126264 2.153026)
			(xy 303.20874 2.176493) (xy 303.29303 2.192249) (xy 303.378413 2.200161) (xy 303.464163 2.200161)
			(xy 303.549546 2.192249) (xy 303.633836 2.176493) (xy 303.716312 2.153026) (xy 303.796271 2.12205)
			(xy 303.873031 2.083828) (xy 303.945937 2.038687) (xy 304.014366 1.987011) (xy 304.077736 1.929242)
			(xy 304.135505 1.865872) (xy 304.187181 1.797443) (xy 304.232322 1.724537) (xy 304.270544 1.647777)
			(xy 304.30152 1.567818) (xy 304.324987 1.485342) (xy 304.340743 1.401052) (xy 304.348655 1.315669)
			(xy 304.34915 1.272794) (xy 304.348655 1.229919) (xy 311.155321 1.229919) (xy 311.155321 1.315669)
			(xy 311.163233 1.401052) (xy 311.178989 1.485342) (xy 311.202456 1.567818) (xy 311.233432 1.647777)
			(xy 311.271654 1.724537) (xy 311.316795 1.797443) (xy 311.368471 1.865872) (xy 311.42624 1.929242)
			(xy 311.48961 1.987011) (xy 311.558039 2.038687) (xy 311.630945 2.083828) (xy 311.707705 2.12205)
			(xy 311.787664 2.153026) (xy 311.87014 2.176493) (xy 311.95443 2.192249) (xy 312.039813 2.200161)
			(xy 312.125563 2.200161) (xy 312.210946 2.192249) (xy 312.295236 2.176493) (xy 312.377712 2.153026)
			(xy 312.457671 2.12205) (xy 312.534431 2.083828) (xy 312.607337 2.038687) (xy 312.675766 1.987011)
			(xy 312.739136 1.929242) (xy 312.796905 1.865872) (xy 312.848581 1.797443) (xy 312.893722 1.724537)
			(xy 312.931944 1.647777) (xy 312.96292 1.567818) (xy 312.986387 1.485342) (xy 313.002143 1.401052)
			(xy 313.010055 1.315669) (xy 313.01055 1.272794) (xy 313.010055 1.229919) (xy 317.505321 1.229919)
			(xy 317.505321 1.315669) (xy 317.513233 1.401052) (xy 317.528989 1.485342) (xy 317.552456 1.567818)
			(xy 317.583432 1.647777) (xy 317.621654 1.724537) (xy 317.666795 1.797443) (xy 317.718471 1.865872)
			(xy 317.77624 1.929242) (xy 317.83961 1.987011) (xy 317.908039 2.038687) (xy 317.980945 2.083828)
			(xy 318.057705 2.12205) (xy 318.137664 2.153026) (xy 318.22014 2.176493) (xy 318.30443 2.192249)
			(xy 318.389813 2.200161) (xy 318.475563 2.200161) (xy 318.560946 2.192249) (xy 318.645236 2.176493)
			(xy 318.727712 2.153026) (xy 318.807671 2.12205) (xy 318.884431 2.083828) (xy 318.957337 2.038687)
			(xy 319.025766 1.987011) (xy 319.089136 1.929242) (xy 319.146905 1.865872) (xy 319.198581 1.797443)
			(xy 319.243722 1.724537) (xy 319.281944 1.647777) (xy 319.31292 1.567818) (xy 319.336387 1.485342)
			(xy 319.352143 1.401052) (xy 319.360055 1.315669) (xy 319.36055 1.272794) (xy 319.360055 1.229919)
			(xy 361.894107 1.229919) (xy 361.894107 1.315669) (xy 361.902019 1.401052) (xy 361.917775 1.485342)
			(xy 361.941242 1.567818) (xy 361.972218 1.647777) (xy 362.01044 1.724537) (xy 362.055581 1.797443)
			(xy 362.107257 1.865872) (xy 362.165026 1.929242) (xy 362.228396 1.987011) (xy 362.296825 2.038687)
			(xy 362.369731 2.083828) (xy 362.446491 2.12205) (xy 362.52645 2.153026) (xy 362.608926 2.176493)
			(xy 362.693216 2.192249) (xy 362.778599 2.200161) (xy 362.864349 2.200161) (xy 362.949732 2.192249)
			(xy 363.034022 2.176493) (xy 363.116498 2.153026) (xy 363.196457 2.12205) (xy 363.273217 2.083828)
			(xy 363.346123 2.038687) (xy 363.414552 1.987011) (xy 363.477922 1.929242) (xy 363.535691 1.865872)
			(xy 363.587367 1.797443) (xy 363.632508 1.724537) (xy 363.67073 1.647777) (xy 363.701706 1.567818)
			(xy 363.725173 1.485342) (xy 363.740929 1.401052) (xy 363.748841 1.315669) (xy 363.749336 1.272794)
			(xy 363.748841 1.229919) (xy 368.244107 1.229919) (xy 368.244107 1.315669) (xy 368.252019 1.401052)
			(xy 368.267775 1.485342) (xy 368.291242 1.567818) (xy 368.322218 1.647777) (xy 368.36044 1.724537)
			(xy 368.405581 1.797443) (xy 368.457257 1.865872) (xy 368.515026 1.929242) (xy 368.578396 1.987011)
			(xy 368.646825 2.038687) (xy 368.719731 2.083828) (xy 368.796491 2.12205) (xy 368.87645 2.153026)
			(xy 368.958926 2.176493) (xy 369.043216 2.192249) (xy 369.128599 2.200161) (xy 369.214349 2.200161)
			(xy 369.299732 2.192249) (xy 369.384022 2.176493) (xy 369.466498 2.153026) (xy 369.546457 2.12205)
			(xy 369.623217 2.083828) (xy 369.696123 2.038687) (xy 369.764552 1.987011) (xy 369.827922 1.929242)
			(xy 369.885691 1.865872) (xy 369.937367 1.797443) (xy 369.982508 1.724537) (xy 370.02073 1.647777)
			(xy 370.051706 1.567818) (xy 370.075173 1.485342) (xy 370.090929 1.401052) (xy 370.098841 1.315669)
			(xy 370.099336 1.272794) (xy 370.098841 1.229919) (xy 370.090929 1.144536) (xy 370.075173 1.060246)
			(xy 370.051706 0.97777) (xy 370.02073 0.897811) (xy 369.982508 0.821051) (xy 369.937367 0.748145)
			(xy 369.885691 0.679716) (xy 369.827922 0.616346) (xy 369.764552 0.558577) (xy 369.696123 0.506901)
			(xy 369.623217 0.46176) (xy 369.546457 0.423538) (xy 369.466498 0.392562) (xy 369.384022 0.369095)
			(xy 369.299732 0.353339) (xy 369.214349 0.345427) (xy 369.128599 0.345427) (xy 369.043216 0.353339)
			(xy 368.958926 0.369095) (xy 368.87645 0.392562) (xy 368.796491 0.423538) (xy 368.719731 0.46176)
			(xy 368.646825 0.506901) (xy 368.578396 0.558577) (xy 368.515026 0.616346) (xy 368.457257 0.679716)
			(xy 368.405581 0.748145) (xy 368.36044 0.821051) (xy 368.322218 0.897811) (xy 368.291242 0.97777)
			(xy 368.267775 1.060246) (xy 368.252019 1.144536) (xy 368.244107 1.229919) (xy 363.748841 1.229919)
			(xy 363.740929 1.144536) (xy 363.725173 1.060246) (xy 363.701706 0.97777) (xy 363.67073 0.897811)
			(xy 363.632508 0.821051) (xy 363.587367 0.748145) (xy 363.535691 0.679716) (xy 363.477922 0.616346)
			(xy 363.414552 0.558577) (xy 363.346123 0.506901) (xy 363.273217 0.46176) (xy 363.196457 0.423538)
			(xy 363.116498 0.392562) (xy 363.034022 0.369095) (xy 362.949732 0.353339) (xy 362.864349 0.345427)
			(xy 362.778599 0.345427) (xy 362.693216 0.353339) (xy 362.608926 0.369095) (xy 362.52645 0.392562)
			(xy 362.446491 0.423538) (xy 362.369731 0.46176) (xy 362.296825 0.506901) (xy 362.228396 0.558577)
			(xy 362.165026 0.616346) (xy 362.107257 0.679716) (xy 362.055581 0.748145) (xy 362.01044 0.821051)
			(xy 361.972218 0.897811) (xy 361.941242 0.97777) (xy 361.917775 1.060246) (xy 361.902019 1.144536)
			(xy 361.894107 1.229919) (xy 319.360055 1.229919) (xy 319.352143 1.144536) (xy 319.336387 1.060246)
			(xy 319.31292 0.97777) (xy 319.281944 0.897811) (xy 319.243722 0.821051) (xy 319.198581 0.748145)
			(xy 319.146905 0.679716) (xy 319.089136 0.616346) (xy 319.025766 0.558577) (xy 318.957337 0.506901)
			(xy 318.884431 0.46176) (xy 318.807671 0.423538) (xy 318.727712 0.392562) (xy 318.645236 0.369095)
			(xy 318.560946 0.353339) (xy 318.475563 0.345427) (xy 318.389813 0.345427) (xy 318.30443 0.353339)
			(xy 318.22014 0.369095) (xy 318.137664 0.392562) (xy 318.057705 0.423538) (xy 317.980945 0.46176)
			(xy 317.908039 0.506901) (xy 317.83961 0.558577) (xy 317.77624 0.616346) (xy 317.718471 0.679716)
			(xy 317.666795 0.748145) (xy 317.621654 0.821051) (xy 317.583432 0.897811) (xy 317.552456 0.97777)
			(xy 317.528989 1.060246) (xy 317.513233 1.144536) (xy 317.505321 1.229919) (xy 313.010055 1.229919)
			(xy 313.002143 1.144536) (xy 312.986387 1.060246) (xy 312.96292 0.97777) (xy 312.931944 0.897811)
			(xy 312.893722 0.821051) (xy 312.848581 0.748145) (xy 312.796905 0.679716) (xy 312.739136 0.616346)
			(xy 312.675766 0.558577) (xy 312.607337 0.506901) (xy 312.534431 0.46176) (xy 312.457671 0.423538)
			(xy 312.377712 0.392562) (xy 312.295236 0.369095) (xy 312.210946 0.353339) (xy 312.125563 0.345427)
			(xy 312.039813 0.345427) (xy 311.95443 0.353339) (xy 311.87014 0.369095) (xy 311.787664 0.392562)
			(xy 311.707705 0.423538) (xy 311.630945 0.46176) (xy 311.558039 0.506901) (xy 311.48961 0.558577)
			(xy 311.42624 0.616346) (xy 311.368471 0.679716) (xy 311.316795 0.748145) (xy 311.271654 0.821051)
			(xy 311.233432 0.897811) (xy 311.202456 0.97777) (xy 311.178989 1.060246) (xy 311.163233 1.144536)
			(xy 311.155321 1.229919) (xy 304.348655 1.229919) (xy 304.340743 1.144536) (xy 304.324987 1.060246)
			(xy 304.30152 0.97777) (xy 304.270544 0.897811) (xy 304.232322 0.821051) (xy 304.187181 0.748145)
			(xy 304.135505 0.679716) (xy 304.077736 0.616346) (xy 304.014366 0.558577) (xy 303.945937 0.506901)
			(xy 303.873031 0.46176) (xy 303.796271 0.423538) (xy 303.716312 0.392562) (xy 303.633836 0.369095)
			(xy 303.549546 0.353339) (xy 303.464163 0.345427) (xy 303.378413 0.345427) (xy 303.29303 0.353339)
			(xy 303.20874 0.369095) (xy 303.126264 0.392562) (xy 303.046305 0.423538) (xy 302.969545 0.46176)
			(xy 302.896639 0.506901) (xy 302.82821 0.558577) (xy 302.76484 0.616346) (xy 302.707071 0.679716)
			(xy 302.655395 0.748145) (xy 302.610254 0.821051) (xy 302.572032 0.897811) (xy 302.541056 0.97777)
			(xy 302.517589 1.060246) (xy 302.501833 1.144536) (xy 302.493921 1.229919) (xy 297.998655 1.229919)
			(xy 297.990743 1.144536) (xy 297.974987 1.060246) (xy 297.95152 0.97777) (xy 297.920544 0.897811)
			(xy 297.882322 0.821051) (xy 297.837181 0.748145) (xy 297.785505 0.679716) (xy 297.727736 0.616346)
			(xy 297.664366 0.558577) (xy 297.595937 0.506901) (xy 297.523031 0.46176) (xy 297.446271 0.423538)
			(xy 297.366312 0.392562) (xy 297.283836 0.369095) (xy 297.199546 0.353339) (xy 297.114163 0.345427)
			(xy 297.028413 0.345427) (xy 296.94303 0.353339) (xy 296.85874 0.369095) (xy 296.776264 0.392562)
			(xy 296.696305 0.423538) (xy 296.619545 0.46176) (xy 296.546639 0.506901) (xy 296.47821 0.558577)
			(xy 296.41484 0.616346) (xy 296.357071 0.679716) (xy 296.305395 0.748145) (xy 296.260254 0.821051)
			(xy 296.222032 0.897811) (xy 296.191056 0.97777) (xy 296.167589 1.060246) (xy 296.151833 1.144536)
			(xy 296.143921 1.229919) (xy 216.865975 1.229919) (xy 216.858063 1.144536) (xy 216.842307 1.060246)
			(xy 216.81884 0.97777) (xy 216.787864 0.897811) (xy 216.749642 0.821051) (xy 216.704501 0.748145)
			(xy 216.652825 0.679716) (xy 216.595056 0.616346) (xy 216.531686 0.558577) (xy 216.463257 0.506901)
			(xy 216.390351 0.46176) (xy 216.313591 0.423538) (xy 216.233632 0.392562) (xy 216.151156 0.369095)
			(xy 216.066866 0.353339) (xy 215.981483 0.345427) (xy 215.895733 0.345427) (xy 215.81035 0.353339)
			(xy 215.72606 0.369095) (xy 215.643584 0.392562) (xy 215.563625 0.423538) (xy 215.486865 0.46176)
			(xy 215.413959 0.506901) (xy 215.34553 0.558577) (xy 215.28216 0.616346) (xy 215.224391 0.679716)
			(xy 215.172715 0.748145) (xy 215.127574 0.821051) (xy 215.089352 0.897811) (xy 215.058376 0.97777)
			(xy 215.034909 1.060246) (xy 215.019153 1.144536) (xy 215.011241 1.229919) (xy 210.515975 1.229919)
			(xy 210.508063 1.144536) (xy 210.492307 1.060246) (xy 210.46884 0.97777) (xy 210.437864 0.897811)
			(xy 210.399642 0.821051) (xy 210.354501 0.748145) (xy 210.302825 0.679716) (xy 210.245056 0.616346)
			(xy 210.181686 0.558577) (xy 210.113257 0.506901) (xy 210.040351 0.46176) (xy 209.963591 0.423538)
			(xy 209.883632 0.392562) (xy 209.801156 0.369095) (xy 209.716866 0.353339) (xy 209.631483 0.345427)
			(xy 209.545733 0.345427) (xy 209.46035 0.353339) (xy 209.37606 0.369095) (xy 209.293584 0.392562)
			(xy 209.213625 0.423538) (xy 209.136865 0.46176) (xy 209.063959 0.506901) (xy 208.99553 0.558577)
			(xy 208.93216 0.616346) (xy 208.874391 0.679716) (xy 208.822715 0.748145) (xy 208.777574 0.821051)
			(xy 208.739352 0.897811) (xy 208.708376 0.97777) (xy 208.684909 1.060246) (xy 208.669153 1.144536)
			(xy 208.661241 1.229919) (xy 84.069209 1.229919) (xy 84.092929 1.162133) (xy 84.131901 1.02687) (xy 84.163226 0.889634)
			(xy 84.186808 0.750857) (xy 84.202571 0.610977) (xy 84.210467 0.470433) (xy 84.210906 0.40005) (xy 84.210906 -1.310081)
			(xy 208.661241 -1.310081) (xy 208.661241 -1.224331) (xy 208.669153 -1.138948) (xy 208.684909 -1.054658)
			(xy 208.708376 -0.972182) (xy 208.739352 -0.892223) (xy 208.777574 -0.815463) (xy 208.822715 -0.742557)
			(xy 208.874391 -0.674128) (xy 208.93216 -0.610758) (xy 208.99553 -0.552989) (xy 209.063959 -0.501313)
			(xy 209.136865 -0.456172) (xy 209.213625 -0.41795) (xy 209.293584 -0.386974) (xy 209.37606 -0.363507)
			(xy 209.46035 -0.347751) (xy 209.545733 -0.339839) (xy 209.631483 -0.339839) (xy 209.716866 -0.347751)
			(xy 209.801156 -0.363507) (xy 209.883632 -0.386974) (xy 209.963591 -0.41795) (xy 210.040351 -0.456172)
			(xy 210.113257 -0.501313) (xy 210.181686 -0.552989) (xy 210.245056 -0.610758) (xy 210.302825 -0.674128)
			(xy 210.354501 -0.742557) (xy 210.399642 -0.815463) (xy 210.437864 -0.892223) (xy 210.46884 -0.972182)
			(xy 210.492307 -1.054658) (xy 210.508063 -1.138948) (xy 210.515975 -1.224331) (xy 210.51647 -1.267206)
			(xy 210.515975 -1.310081) (xy 215.011241 -1.310081) (xy 215.011241 -1.224331) (xy 215.019153 -1.138948)
			(xy 215.034909 -1.054658) (xy 215.058376 -0.972182) (xy 215.089352 -0.892223) (xy 215.127574 -0.815463)
			(xy 215.172715 -0.742557) (xy 215.224391 -0.674128) (xy 215.28216 -0.610758) (xy 215.34553 -0.552989)
			(xy 215.413959 -0.501313) (xy 215.486865 -0.456172) (xy 215.563625 -0.41795) (xy 215.643584 -0.386974)
			(xy 215.72606 -0.363507) (xy 215.81035 -0.347751) (xy 215.895733 -0.339839) (xy 215.981483 -0.339839)
			(xy 216.066866 -0.347751) (xy 216.151156 -0.363507) (xy 216.233632 -0.386974) (xy 216.313591 -0.41795)
			(xy 216.390351 -0.456172) (xy 216.463257 -0.501313) (xy 216.531686 -0.552989) (xy 216.595056 -0.610758)
			(xy 216.652825 -0.674128) (xy 216.704501 -0.742557) (xy 216.749642 -0.815463) (xy 216.787864 -0.892223)
			(xy 216.81884 -0.972182) (xy 216.842307 -1.054658) (xy 216.858063 -1.138948) (xy 216.865975 -1.224331)
			(xy 216.86647 -1.267206) (xy 216.865975 -1.310081) (xy 296.143921 -1.310081) (xy 296.143921 -1.224331)
			(xy 296.151833 -1.138948) (xy 296.167589 -1.054658) (xy 296.191056 -0.972182) (xy 296.222032 -0.892223)
			(xy 296.260254 -0.815463) (xy 296.305395 -0.742557) (xy 296.357071 -0.674128) (xy 296.41484 -0.610758)
			(xy 296.47821 -0.552989) (xy 296.546639 -0.501313) (xy 296.619545 -0.456172) (xy 296.696305 -0.41795)
			(xy 296.776264 -0.386974) (xy 296.85874 -0.363507) (xy 296.94303 -0.347751) (xy 297.028413 -0.339839)
			(xy 297.114163 -0.339839) (xy 297.199546 -0.347751) (xy 297.283836 -0.363507) (xy 297.366312 -0.386974)
			(xy 297.446271 -0.41795) (xy 297.523031 -0.456172) (xy 297.595937 -0.501313) (xy 297.664366 -0.552989)
			(xy 297.727736 -0.610758) (xy 297.785505 -0.674128) (xy 297.837181 -0.742557) (xy 297.882322 -0.815463)
			(xy 297.920544 -0.892223) (xy 297.95152 -0.972182) (xy 297.974987 -1.054658) (xy 297.990743 -1.138948)
			(xy 297.998655 -1.224331) (xy 297.99915 -1.267206) (xy 297.998655 -1.310081) (xy 302.493921 -1.310081)
			(xy 302.493921 -1.224331) (xy 302.501833 -1.138948) (xy 302.517589 -1.054658) (xy 302.541056 -0.972182)
			(xy 302.572032 -0.892223) (xy 302.610254 -0.815463) (xy 302.655395 -0.742557) (xy 302.707071 -0.674128)
			(xy 302.76484 -0.610758) (xy 302.82821 -0.552989) (xy 302.896639 -0.501313) (xy 302.969545 -0.456172)
			(xy 303.046305 -0.41795) (xy 303.126264 -0.386974) (xy 303.20874 -0.363507) (xy 303.29303 -0.347751)
			(xy 303.378413 -0.339839) (xy 303.464163 -0.339839) (xy 303.549546 -0.347751) (xy 303.633836 -0.363507)
			(xy 303.716312 -0.386974) (xy 303.796271 -0.41795) (xy 303.873031 -0.456172) (xy 303.945937 -0.501313)
			(xy 304.014366 -0.552989) (xy 304.077736 -0.610758) (xy 304.135505 -0.674128) (xy 304.187181 -0.742557)
			(xy 304.232322 -0.815463) (xy 304.270544 -0.892223) (xy 304.30152 -0.972182) (xy 304.324987 -1.054658)
			(xy 304.340743 -1.138948) (xy 304.348655 -1.224331) (xy 304.34915 -1.267206) (xy 304.348655 -1.310081)
			(xy 311.155321 -1.310081) (xy 311.155321 -1.224331) (xy 311.163233 -1.138948) (xy 311.178989 -1.054658)
			(xy 311.202456 -0.972182) (xy 311.233432 -0.892223) (xy 311.271654 -0.815463) (xy 311.316795 -0.742557)
			(xy 311.368471 -0.674128) (xy 311.42624 -0.610758) (xy 311.48961 -0.552989) (xy 311.558039 -0.501313)
			(xy 311.630945 -0.456172) (xy 311.707705 -0.41795) (xy 311.787664 -0.386974) (xy 311.87014 -0.363507)
			(xy 311.95443 -0.347751) (xy 312.039813 -0.339839) (xy 312.125563 -0.339839) (xy 312.210946 -0.347751)
			(xy 312.295236 -0.363507) (xy 312.377712 -0.386974) (xy 312.457671 -0.41795) (xy 312.478344 -0.428244)
			(xy 316.012068 -0.428244) (xy 316.012068 0.435356) (xy 316.012572 0.46491) (xy 316.020621 0.523466)
			(xy 316.036567 0.580381) (xy 316.060116 0.634595) (xy 316.090827 0.685098) (xy 316.128129 0.730948)
			(xy 316.171326 0.771291) (xy 316.219615 0.805377) (xy 316.272095 0.83257) (xy 316.32779 0.852364)
			(xy 316.385661 0.86439) (xy 316.44463 0.868424) (xy 316.503599 0.86439) (xy 316.56147 0.852364) (xy 316.617165 0.83257)
			(xy 316.669645 0.805377) (xy 316.717934 0.771291) (xy 316.761131 0.730948) (xy 316.798433 0.685098)
			(xy 316.829144 0.634595) (xy 316.852693 0.580381) (xy 316.868639 0.523466) (xy 316.876688 0.46491)
			(xy 316.877192 0.435356) (xy 316.877192 -0.428244) (xy 316.876688 -0.457798) (xy 316.868639 -0.516354)
			(xy 316.852693 -0.573269) (xy 316.829144 -0.627483) (xy 316.798433 -0.677986) (xy 316.761131 -0.723836)
			(xy 316.717934 -0.764179) (xy 316.669645 -0.798265) (xy 316.617165 -0.825458) (xy 316.56147 -0.845252)
			(xy 316.503599 -0.857278) (xy 316.44463 -0.861312) (xy 316.385661 -0.857278) (xy 316.32779 -0.845252)
			(xy 316.272095 -0.825458) (xy 316.219615 -0.798265) (xy 316.171326 -0.764179) (xy 316.128129 -0.723836)
			(xy 316.090827 -0.677986) (xy 316.060116 -0.627483) (xy 316.036567 -0.573269) (xy 316.020621 -0.516354)
			(xy 316.012572 -0.457798) (xy 316.012068 -0.428244) (xy 312.478344 -0.428244) (xy 312.534431 -0.456172)
			(xy 312.607337 -0.501313) (xy 312.675766 -0.552989) (xy 312.739136 -0.610758) (xy 312.796905 -0.674128)
			(xy 312.848581 -0.742557) (xy 312.893722 -0.815463) (xy 312.931944 -0.892223) (xy 312.96292 -0.972182)
			(xy 312.986387 -1.054658) (xy 313.002143 -1.138948) (xy 313.010055 -1.224331) (xy 313.01055 -1.267206)
			(xy 313.010055 -1.310081) (xy 317.505321 -1.310081) (xy 317.505321 -1.224331) (xy 317.513233 -1.138948)
			(xy 317.528989 -1.054658) (xy 317.552456 -0.972182) (xy 317.583432 -0.892223) (xy 317.621654 -0.815463)
			(xy 317.666795 -0.742557) (xy 317.718471 -0.674128) (xy 317.77624 -0.610758) (xy 317.83961 -0.552989)
			(xy 317.908039 -0.501313) (xy 317.980945 -0.456172) (xy 318.057705 -0.41795) (xy 318.137664 -0.386974)
			(xy 318.22014 -0.363507) (xy 318.30443 -0.347751) (xy 318.389813 -0.339839) (xy 318.475563 -0.339839)
			(xy 318.560946 -0.347751) (xy 318.645236 -0.363507) (xy 318.727712 -0.386974) (xy 318.807671 -0.41795)
			(xy 318.884431 -0.456172) (xy 318.957337 -0.501313) (xy 319.025766 -0.552989) (xy 319.089136 -0.610758)
			(xy 319.146905 -0.674128) (xy 319.198581 -0.742557) (xy 319.243722 -0.815463) (xy 319.281944 -0.892223)
			(xy 319.31292 -0.972182) (xy 319.336387 -1.054658) (xy 319.352143 -1.138948) (xy 319.360055 -1.224331)
			(xy 319.36055 -1.267206) (xy 319.360055 -1.310081) (xy 361.894107 -1.310081) (xy 361.894107 -1.224331)
			(xy 361.902019 -1.138948) (xy 361.917775 -1.054658) (xy 361.941242 -0.972182) (xy 361.972218 -0.892223)
			(xy 362.01044 -0.815463) (xy 362.055581 -0.742557) (xy 362.107257 -0.674128) (xy 362.165026 -0.610758)
			(xy 362.228396 -0.552989) (xy 362.296825 -0.501313) (xy 362.369731 -0.456172) (xy 362.446491 -0.41795)
			(xy 362.52645 -0.386974) (xy 362.608926 -0.363507) (xy 362.693216 -0.347751) (xy 362.778599 -0.339839)
			(xy 362.864349 -0.339839) (xy 362.949732 -0.347751) (xy 363.034022 -0.363507) (xy 363.116498 -0.386974)
			(xy 363.196457 -0.41795) (xy 363.21713 -0.428244) (xy 364.379764 -0.428244) (xy 364.379764 0.435356)
			(xy 364.380268 0.464892) (xy 364.388312 0.523414) (xy 364.404249 0.580296) (xy 364.427784 0.634478)
			(xy 364.458477 0.684951) (xy 364.495757 0.730774) (xy 364.538929 0.771094) (xy 364.587189 0.80516)
			(xy 364.639639 0.832337) (xy 364.6953 0.852119) (xy 364.753137 0.864138) (xy 364.812072 0.868169)
			(xy 364.871007 0.864138) (xy 364.928844 0.852119) (xy 364.984505 0.832337) (xy 365.036955 0.80516)
			(xy 365.085215 0.771094) (xy 365.128387 0.730774) (xy 365.165667 0.684951) (xy 365.19636 0.634478)
			(xy 365.219895 0.580296) (xy 365.235832 0.523414) (xy 365.243876 0.464892) (xy 365.24438 0.435356)
			(xy 365.24438 -0.428244) (xy 365.243876 -0.45778) (xy 365.235832 -0.516302) (xy 365.219895 -0.573184)
			(xy 365.19636 -0.627366) (xy 365.165667 -0.677839) (xy 365.128387 -0.723662) (xy 365.085215 -0.763982)
			(xy 365.036955 -0.798048) (xy 364.984505 -0.825225) (xy 364.928844 -0.845007) (xy 364.871007 -0.857026)
			(xy 364.812072 -0.861057) (xy 364.753137 -0.857026) (xy 364.6953 -0.845007) (xy 364.639639 -0.825225)
			(xy 364.587189 -0.798048) (xy 364.538929 -0.763982) (xy 364.495757 -0.723662) (xy 364.458477 -0.677839)
			(xy 364.427784 -0.627366) (xy 364.404249 -0.573184) (xy 364.388312 -0.516302) (xy 364.380268 -0.45778)
			(xy 364.379764 -0.428244) (xy 363.21713 -0.428244) (xy 363.273217 -0.456172) (xy 363.346123 -0.501313)
			(xy 363.414552 -0.552989) (xy 363.477922 -0.610758) (xy 363.535691 -0.674128) (xy 363.587367 -0.742557)
			(xy 363.632508 -0.815463) (xy 363.67073 -0.892223) (xy 363.701706 -0.972182) (xy 363.725173 -1.054658)
			(xy 363.740929 -1.138948) (xy 363.748841 -1.224331) (xy 363.749336 -1.267206) (xy 363.748841 -1.310081)
			(xy 368.244107 -1.310081) (xy 368.244107 -1.224331) (xy 368.252019 -1.138948) (xy 368.267775 -1.054658)
			(xy 368.291242 -0.972182) (xy 368.322218 -0.892223) (xy 368.36044 -0.815463) (xy 368.405581 -0.742557)
			(xy 368.457257 -0.674128) (xy 368.515026 -0.610758) (xy 368.578396 -0.552989) (xy 368.646825 -0.501313)
			(xy 368.719731 -0.456172) (xy 368.796491 -0.41795) (xy 368.87645 -0.386974) (xy 368.958926 -0.363507)
			(xy 369.043216 -0.347751) (xy 369.128599 -0.339839) (xy 369.214349 -0.339839) (xy 369.299732 -0.347751)
			(xy 369.384022 -0.363507) (xy 369.466498 -0.386974) (xy 369.546457 -0.41795) (xy 369.623217 -0.456172)
			(xy 369.696123 -0.501313) (xy 369.764552 -0.552989) (xy 369.827922 -0.610758) (xy 369.885691 -0.674128)
			(xy 369.937367 -0.742557) (xy 369.982508 -0.815463) (xy 370.02073 -0.892223) (xy 370.051706 -0.972182)
			(xy 370.075173 -1.054658) (xy 370.090929 -1.138948) (xy 370.098841 -1.224331) (xy 370.099336 -1.267206)
			(xy 370.098841 -1.310081) (xy 370.090929 -1.395464) (xy 370.075173 -1.479754) (xy 370.051706 -1.56223)
			(xy 370.02073 -1.642189) (xy 369.982508 -1.718949) (xy 369.937367 -1.791855) (xy 369.885691 -1.860284)
			(xy 369.827922 -1.923654) (xy 369.764552 -1.981423) (xy 369.696123 -2.033099) (xy 369.623217 -2.07824)
			(xy 369.546457 -2.116462) (xy 369.466498 -2.147438) (xy 369.384022 -2.170905) (xy 369.299732 -2.186661)
			(xy 369.214349 -2.194573) (xy 369.128599 -2.194573) (xy 369.043216 -2.186661) (xy 368.958926 -2.170905)
			(xy 368.87645 -2.147438) (xy 368.796491 -2.116462) (xy 368.719731 -2.07824) (xy 368.646825 -2.033099)
			(xy 368.578396 -1.981423) (xy 368.515026 -1.923654) (xy 368.457257 -1.860284) (xy 368.405581 -1.791855)
			(xy 368.36044 -1.718949) (xy 368.322218 -1.642189) (xy 368.291242 -1.56223) (xy 368.267775 -1.479754)
			(xy 368.252019 -1.395464) (xy 368.244107 -1.310081) (xy 363.748841 -1.310081) (xy 363.740929 -1.395464)
			(xy 363.725173 -1.479754) (xy 363.701706 -1.56223) (xy 363.67073 -1.642189) (xy 363.632508 -1.718949)
			(xy 363.587367 -1.791855) (xy 363.535691 -1.860284) (xy 363.477922 -1.923654) (xy 363.414552 -1.981423)
			(xy 363.346123 -2.033099) (xy 363.273217 -2.07824) (xy 363.196457 -2.116462) (xy 363.116498 -2.147438)
			(xy 363.034022 -2.170905) (xy 362.949732 -2.186661) (xy 362.864349 -2.194573) (xy 362.778599 -2.194573)
			(xy 362.693216 -2.186661) (xy 362.608926 -2.170905) (xy 362.52645 -2.147438) (xy 362.446491 -2.116462)
			(xy 362.369731 -2.07824) (xy 362.296825 -2.033099) (xy 362.228396 -1.981423) (xy 362.165026 -1.923654)
			(xy 362.107257 -1.860284) (xy 362.055581 -1.791855) (xy 362.01044 -1.718949) (xy 361.972218 -1.642189)
			(xy 361.941242 -1.56223) (xy 361.917775 -1.479754) (xy 361.902019 -1.395464) (xy 361.894107 -1.310081)
			(xy 319.360055 -1.310081) (xy 319.352143 -1.395464) (xy 319.336387 -1.479754) (xy 319.31292 -1.56223)
			(xy 319.281944 -1.642189) (xy 319.243722 -1.718949) (xy 319.198581 -1.791855) (xy 319.146905 -1.860284)
			(xy 319.089136 -1.923654) (xy 319.025766 -1.981423) (xy 318.957337 -2.033099) (xy 318.884431 -2.07824)
			(xy 318.807671 -2.116462) (xy 318.727712 -2.147438) (xy 318.645236 -2.170905) (xy 318.560946 -2.186661)
			(xy 318.475563 -2.194573) (xy 318.389813 -2.194573) (xy 318.30443 -2.186661) (xy 318.22014 -2.170905)
			(xy 318.137664 -2.147438) (xy 318.057705 -2.116462) (xy 317.980945 -2.07824) (xy 317.908039 -2.033099)
			(xy 317.83961 -1.981423) (xy 317.77624 -1.923654) (xy 317.718471 -1.860284) (xy 317.666795 -1.791855)
			(xy 317.621654 -1.718949) (xy 317.583432 -1.642189) (xy 317.552456 -1.56223) (xy 317.528989 -1.479754)
			(xy 317.513233 -1.395464) (xy 317.505321 -1.310081) (xy 313.010055 -1.310081) (xy 313.002143 -1.395464)
			(xy 312.986387 -1.479754) (xy 312.96292 -1.56223) (xy 312.931944 -1.642189) (xy 312.893722 -1.718949)
			(xy 312.848581 -1.791855) (xy 312.796905 -1.860284) (xy 312.739136 -1.923654) (xy 312.675766 -1.981423)
			(xy 312.607337 -2.033099) (xy 312.534431 -2.07824) (xy 312.457671 -2.116462) (xy 312.377712 -2.147438)
			(xy 312.295236 -2.170905) (xy 312.210946 -2.186661) (xy 312.125563 -2.194573) (xy 312.039813 -2.194573)
			(xy 311.95443 -2.186661) (xy 311.87014 -2.170905) (xy 311.787664 -2.147438) (xy 311.707705 -2.116462)
			(xy 311.630945 -2.07824) (xy 311.558039 -2.033099) (xy 311.48961 -1.981423) (xy 311.42624 -1.923654)
			(xy 311.368471 -1.860284) (xy 311.316795 -1.791855) (xy 311.271654 -1.718949) (xy 311.233432 -1.642189)
			(xy 311.202456 -1.56223) (xy 311.178989 -1.479754) (xy 311.163233 -1.395464) (xy 311.155321 -1.310081)
			(xy 304.348655 -1.310081) (xy 304.340743 -1.395464) (xy 304.324987 -1.479754) (xy 304.30152 -1.56223)
			(xy 304.270544 -1.642189) (xy 304.232322 -1.718949) (xy 304.187181 -1.791855) (xy 304.135505 -1.860284)
			(xy 304.077736 -1.923654) (xy 304.014366 -1.981423) (xy 303.945937 -2.033099) (xy 303.873031 -2.07824)
			(xy 303.796271 -2.116462) (xy 303.716312 -2.147438) (xy 303.633836 -2.170905) (xy 303.549546 -2.186661)
			(xy 303.464163 -2.194573) (xy 303.378413 -2.194573) (xy 303.29303 -2.186661) (xy 303.20874 -2.170905)
			(xy 303.126264 -2.147438) (xy 303.046305 -2.116462) (xy 302.969545 -2.07824) (xy 302.896639 -2.033099)
			(xy 302.82821 -1.981423) (xy 302.76484 -1.923654) (xy 302.707071 -1.860284) (xy 302.655395 -1.791855)
			(xy 302.610254 -1.718949) (xy 302.572032 -1.642189) (xy 302.541056 -1.56223) (xy 302.517589 -1.479754)
			(xy 302.501833 -1.395464) (xy 302.493921 -1.310081) (xy 297.998655 -1.310081) (xy 297.990743 -1.395464)
			(xy 297.974987 -1.479754) (xy 297.95152 -1.56223) (xy 297.920544 -1.642189) (xy 297.882322 -1.718949)
			(xy 297.837181 -1.791855) (xy 297.785505 -1.860284) (xy 297.727736 -1.923654) (xy 297.664366 -1.981423)
			(xy 297.595937 -2.033099) (xy 297.523031 -2.07824) (xy 297.446271 -2.116462) (xy 297.366312 -2.147438)
			(xy 297.283836 -2.170905) (xy 297.199546 -2.186661) (xy 297.114163 -2.194573) (xy 297.028413 -2.194573)
			(xy 296.94303 -2.186661) (xy 296.85874 -2.170905) (xy 296.776264 -2.147438) (xy 296.696305 -2.116462)
			(xy 296.619545 -2.07824) (xy 296.546639 -2.033099) (xy 296.47821 -1.981423) (xy 296.41484 -1.923654)
			(xy 296.357071 -1.860284) (xy 296.305395 -1.791855) (xy 296.260254 -1.718949) (xy 296.222032 -1.642189)
			(xy 296.191056 -1.56223) (xy 296.167589 -1.479754) (xy 296.151833 -1.395464) (xy 296.143921 -1.310081)
			(xy 216.865975 -1.310081) (xy 216.858063 -1.395464) (xy 216.842307 -1.479754) (xy 216.81884 -1.56223)
			(xy 216.787864 -1.642189) (xy 216.749642 -1.718949) (xy 216.704501 -1.791855) (xy 216.652825 -1.860284)
			(xy 216.595056 -1.923654) (xy 216.531686 -1.981423) (xy 216.463257 -2.033099) (xy 216.390351 -2.07824)
			(xy 216.313591 -2.116462) (xy 216.233632 -2.147438) (xy 216.151156 -2.170905) (xy 216.066866 -2.186661)
			(xy 215.981483 -2.194573) (xy 215.895733 -2.194573) (xy 215.81035 -2.186661) (xy 215.72606 -2.170905)
			(xy 215.643584 -2.147438) (xy 215.563625 -2.116462) (xy 215.486865 -2.07824) (xy 215.413959 -2.033099)
			(xy 215.34553 -1.981423) (xy 215.28216 -1.923654) (xy 215.224391 -1.860284) (xy 215.172715 -1.791855)
			(xy 215.127574 -1.718949) (xy 215.089352 -1.642189) (xy 215.058376 -1.56223) (xy 215.034909 -1.479754)
			(xy 215.019153 -1.395464) (xy 215.011241 -1.310081) (xy 210.515975 -1.310081) (xy 210.508063 -1.395464)
			(xy 210.492307 -1.479754) (xy 210.46884 -1.56223) (xy 210.437864 -1.642189) (xy 210.399642 -1.718949)
			(xy 210.354501 -1.791855) (xy 210.302825 -1.860284) (xy 210.245056 -1.923654) (xy 210.181686 -1.981423)
			(xy 210.113257 -2.033099) (xy 210.040351 -2.07824) (xy 209.963591 -2.116462) (xy 209.883632 -2.147438)
			(xy 209.801156 -2.170905) (xy 209.716866 -2.186661) (xy 209.631483 -2.194573) (xy 209.545733 -2.194573)
			(xy 209.46035 -2.186661) (xy 209.37606 -2.170905) (xy 209.293584 -2.147438) (xy 209.213625 -2.116462)
			(xy 209.136865 -2.07824) (xy 209.063959 -2.033099) (xy 208.99553 -1.981423) (xy 208.93216 -1.923654)
			(xy 208.874391 -1.860284) (xy 208.822715 -1.791855) (xy 208.777574 -1.718949) (xy 208.739352 -1.642189)
			(xy 208.708376 -1.56223) (xy 208.684909 -1.479754) (xy 208.669153 -1.395464) (xy 208.661241 -1.310081)
			(xy 84.210906 -1.310081) (xy 84.210906 -7.78002) (xy 84.211428 -7.835789) (xy 84.219765 -7.947014)
			(xy 84.23639 -8.057306) (xy 84.26121 -8.166046) (xy 84.294088 -8.272628) (xy 84.334838 -8.376455)
			(xy 84.383233 -8.476947) (xy 84.439002 -8.573541) (xy 84.501834 -8.665697) (xy 84.571376 -8.7529)
			(xy 84.647241 -8.834663) (xy 84.729004 -8.910527) (xy 84.816208 -8.98007) (xy 84.908364 -9.042901)
			(xy 85.004959 -9.09867) (xy 85.10545 -9.147065) (xy 85.209277 -9.187814) (xy 85.315859 -9.220691)
			(xy 85.4246 -9.245511) (xy 85.534892 -9.262136) (xy 85.646117 -9.270472) (xy 85.701886 -9.271) (xy 122.102118 -9.271)
			(xy 122.157887 -9.270478) (xy 122.269113 -9.262141) (xy 122.379404 -9.245517) (xy 122.488145 -9.220696)
			(xy 122.594728 -9.187819) (xy 122.698555 -9.147069) (xy 122.799047 -9.098674) (xy 122.895641 -9.042905)
			(xy 122.987798 -8.980073) (xy 123.075001 -8.910531) (xy 123.156764 -8.834666) (xy 123.232629 -8.752903)
			(xy 123.302172 -8.665699) (xy 123.365004 -8.573543) (xy 123.420773 -8.476948) (xy 123.469168 -8.376457)
			(xy 123.509918 -8.27263) (xy 123.542796 -8.166047) (xy 123.567616 -8.057306) (xy 123.584241 -7.947015)
			(xy 123.592578 -7.835789) (xy 123.593098 -7.78002) (xy 123.593098 -4.879848) (xy 123.593581 -4.809465)
			(xy 123.601472 -4.66892) (xy 123.61723 -4.529038) (xy 123.640807 -4.39026) (xy 123.672128 -4.253022)
			(xy 123.711095 -4.117757) (xy 123.757586 -3.984889) (xy 123.811453 -3.854837) (xy 123.872528 -3.72801)
			(xy 123.940618 -3.604807) (xy 124.015509 -3.485616) (xy 124.096965 -3.370811) (xy 124.184731 -3.260755)
			(xy 124.278529 -3.155793) (xy 124.378065 -3.056255) (xy 124.483026 -2.962455) (xy 124.593081 -2.874688)
			(xy 124.707884 -2.79323) (xy 124.827074 -2.718337) (xy 124.950276 -2.650245) (xy 125.077102 -2.589169)
			(xy 125.207153 -2.535299) (xy 125.340021 -2.488807) (xy 125.475285 -2.449838) (xy 125.612523 -2.418514)
			(xy 125.7513 -2.394935) (xy 125.891182 -2.379175) (xy 126.031727 -2.371282) (xy 126.10211 -2.370836)
			(xy 194.701922 -2.370836) (xy 194.772304 -2.371321) (xy 194.912845 -2.379215) (xy 195.052723 -2.394977)
			(xy 195.191497 -2.418557) (xy 195.328731 -2.449881) (xy 195.463992 -2.488851) (xy 195.596856 -2.535344)
			(xy 195.726904 -2.589213) (xy 195.853726 -2.650289) (xy 195.976925 -2.71838) (xy 196.096111 -2.793273)
			(xy 196.210911 -2.87473) (xy 196.320963 -2.962495) (xy 196.425921 -3.056294) (xy 196.525454 -3.15583)
			(xy 196.61925 -3.26079) (xy 196.707012 -3.370845) (xy 196.788466 -3.485647) (xy 196.863355 -3.604836)
			(xy 196.931443 -3.728036) (xy 196.990215 -3.850081) (xy 208.661241 -3.850081) (xy 208.661241 -3.764331)
			(xy 208.669153 -3.678948) (xy 208.684909 -3.594658) (xy 208.708376 -3.512182) (xy 208.739352 -3.432223)
			(xy 208.777574 -3.355463) (xy 208.822715 -3.282557) (xy 208.874391 -3.214128) (xy 208.93216 -3.150758)
			(xy 208.99553 -3.092989) (xy 209.063959 -3.041313) (xy 209.136865 -2.996172) (xy 209.213625 -2.95795)
			(xy 209.293584 -2.926974) (xy 209.37606 -2.903507) (xy 209.46035 -2.887751) (xy 209.545733 -2.879839)
			(xy 209.631483 -2.879839) (xy 209.716866 -2.887751) (xy 209.801156 -2.903507) (xy 209.883632 -2.926974)
			(xy 209.963591 -2.95795) (xy 209.984264 -2.968244) (xy 213.517988 -2.968244) (xy 213.517988 -2.104644)
			(xy 213.518492 -2.07509) (xy 213.526541 -2.016534) (xy 213.542487 -1.959619) (xy 213.566036 -1.905405)
			(xy 213.596747 -1.854902) (xy 213.634049 -1.809052) (xy 213.677246 -1.768709) (xy 213.725535 -1.734623)
			(xy 213.778015 -1.70743) (xy 213.83371 -1.687636) (xy 213.891581 -1.67561) (xy 213.95055 -1.671577)
			(xy 214.009519 -1.67561) (xy 214.06739 -1.687636) (xy 214.123085 -1.70743) (xy 214.175565 -1.734623)
			(xy 214.223854 -1.768709) (xy 214.267051 -1.809052) (xy 214.304353 -1.854902) (xy 214.335064 -1.905405)
			(xy 214.358613 -1.959619) (xy 214.374559 -2.016534) (xy 214.382608 -2.07509) (xy 214.383112 -2.104644)
			(xy 214.383112 -2.968244) (xy 214.382608 -2.997798) (xy 214.374559 -3.056354) (xy 214.358613 -3.113269)
			(xy 214.335064 -3.167483) (xy 214.304353 -3.217986) (xy 214.267051 -3.263836) (xy 214.223854 -3.304179)
			(xy 214.175565 -3.338265) (xy 214.123085 -3.365458) (xy 214.06739 -3.385252) (xy 214.009519 -3.397278)
			(xy 213.95055 -3.401312) (xy 213.891581 -3.397278) (xy 213.83371 -3.385252) (xy 213.778015 -3.365458)
			(xy 213.725535 -3.338265) (xy 213.677246 -3.304179) (xy 213.634049 -3.263836) (xy 213.596747 -3.217986)
			(xy 213.566036 -3.167483) (xy 213.542487 -3.113269) (xy 213.526541 -3.056354) (xy 213.518492 -2.997798)
			(xy 213.517988 -2.968244) (xy 209.984264 -2.968244) (xy 210.040351 -2.996172) (xy 210.113257 -3.041313)
			(xy 210.181686 -3.092989) (xy 210.245056 -3.150758) (xy 210.302825 -3.214128) (xy 210.354501 -3.282557)
			(xy 210.399642 -3.355463) (xy 210.437864 -3.432223) (xy 210.46884 -3.512182) (xy 210.492307 -3.594658)
			(xy 210.508063 -3.678948) (xy 210.515975 -3.764331) (xy 210.51647 -3.807206) (xy 210.515975 -3.850081)
			(xy 215.011241 -3.850081) (xy 215.011241 -3.764331) (xy 215.019153 -3.678948) (xy 215.034909 -3.594658)
			(xy 215.058376 -3.512182) (xy 215.089352 -3.432223) (xy 215.127574 -3.355463) (xy 215.172715 -3.282557)
			(xy 215.224391 -3.214128) (xy 215.28216 -3.150758) (xy 215.34553 -3.092989) (xy 215.413959 -3.041313)
			(xy 215.486865 -2.996172) (xy 215.563625 -2.95795) (xy 215.643584 -2.926974) (xy 215.72606 -2.903507)
			(xy 215.81035 -2.887751) (xy 215.895733 -2.879839) (xy 215.981483 -2.879839) (xy 216.066866 -2.887751)
			(xy 216.151156 -2.903507) (xy 216.233632 -2.926974) (xy 216.313591 -2.95795) (xy 216.390351 -2.996172)
			(xy 216.463257 -3.041313) (xy 216.531686 -3.092989) (xy 216.595056 -3.150758) (xy 216.652825 -3.214128)
			(xy 216.704501 -3.282557) (xy 216.749642 -3.355463) (xy 216.787864 -3.432223) (xy 216.81884 -3.512182)
			(xy 216.842307 -3.594658) (xy 216.858063 -3.678948) (xy 216.865975 -3.764331) (xy 216.86647 -3.807206)
			(xy 216.865975 -3.850081) (xy 296.143921 -3.850081) (xy 296.143921 -3.764331) (xy 296.151833 -3.678948)
			(xy 296.167589 -3.594658) (xy 296.191056 -3.512182) (xy 296.222032 -3.432223) (xy 296.260254 -3.355463)
			(xy 296.305395 -3.282557) (xy 296.357071 -3.214128) (xy 296.41484 -3.150758) (xy 296.47821 -3.092989)
			(xy 296.546639 -3.041313) (xy 296.619545 -2.996172) (xy 296.696305 -2.95795) (xy 296.776264 -2.926974)
			(xy 296.85874 -2.903507) (xy 296.94303 -2.887751) (xy 297.028413 -2.879839) (xy 297.114163 -2.879839)
			(xy 297.199546 -2.887751) (xy 297.283836 -2.903507) (xy 297.366312 -2.926974) (xy 297.446271 -2.95795)
			(xy 297.466944 -2.968244) (xy 298.629324 -2.968244) (xy 298.629324 -2.104644) (xy 298.629828 -2.07509)
			(xy 298.637877 -2.016534) (xy 298.653823 -1.959619) (xy 298.677372 -1.905405) (xy 298.708083 -1.854902)
			(xy 298.745385 -1.809052) (xy 298.788582 -1.768709) (xy 298.836871 -1.734623) (xy 298.889351 -1.70743)
			(xy 298.945046 -1.687636) (xy 299.002917 -1.67561) (xy 299.061886 -1.671577) (xy 299.120855 -1.67561)
			(xy 299.178726 -1.687636) (xy 299.234421 -1.70743) (xy 299.286901 -1.734623) (xy 299.33519 -1.768709)
			(xy 299.378387 -1.809052) (xy 299.415689 -1.854902) (xy 299.4464 -1.905405) (xy 299.469949 -1.959619)
			(xy 299.485895 -2.016534) (xy 299.493944 -2.07509) (xy 299.494448 -2.104644) (xy 299.494448 -2.968244)
			(xy 299.493944 -2.997798) (xy 299.485895 -3.056354) (xy 299.469949 -3.113269) (xy 299.4464 -3.167483)
			(xy 299.415689 -3.217986) (xy 299.378387 -3.263836) (xy 299.33519 -3.304179) (xy 299.286901 -3.338265)
			(xy 299.234421 -3.365458) (xy 299.178726 -3.385252) (xy 299.120855 -3.397278) (xy 299.061886 -3.401312)
			(xy 299.002917 -3.397278) (xy 298.945046 -3.385252) (xy 298.889351 -3.365458) (xy 298.836871 -3.338265)
			(xy 298.788582 -3.304179) (xy 298.745385 -3.263836) (xy 298.708083 -3.217986) (xy 298.677372 -3.167483)
			(xy 298.653823 -3.113269) (xy 298.637877 -3.056354) (xy 298.629828 -2.997798) (xy 298.629324 -2.968244)
			(xy 297.466944 -2.968244) (xy 297.523031 -2.996172) (xy 297.595937 -3.041313) (xy 297.664366 -3.092989)
			(xy 297.727736 -3.150758) (xy 297.785505 -3.214128) (xy 297.837181 -3.282557) (xy 297.882322 -3.355463)
			(xy 297.920544 -3.432223) (xy 297.95152 -3.512182) (xy 297.974987 -3.594658) (xy 297.990743 -3.678948)
			(xy 297.998655 -3.764331) (xy 297.99915 -3.807206) (xy 297.998655 -3.850081) (xy 302.493921 -3.850081)
			(xy 302.493921 -3.764331) (xy 302.501833 -3.678948) (xy 302.517589 -3.594658) (xy 302.541056 -3.512182)
			(xy 302.572032 -3.432223) (xy 302.610254 -3.355463) (xy 302.655395 -3.282557) (xy 302.707071 -3.214128)
			(xy 302.76484 -3.150758) (xy 302.82821 -3.092989) (xy 302.896639 -3.041313) (xy 302.969545 -2.996172)
			(xy 303.046305 -2.95795) (xy 303.126264 -2.926974) (xy 303.20874 -2.903507) (xy 303.29303 -2.887751)
			(xy 303.378413 -2.879839) (xy 303.464163 -2.879839) (xy 303.549546 -2.887751) (xy 303.633836 -2.903507)
			(xy 303.716312 -2.926974) (xy 303.796271 -2.95795) (xy 303.873031 -2.996172) (xy 303.945937 -3.041313)
			(xy 304.014366 -3.092989) (xy 304.077736 -3.150758) (xy 304.135505 -3.214128) (xy 304.187181 -3.282557)
			(xy 304.232322 -3.355463) (xy 304.270544 -3.432223) (xy 304.30152 -3.512182) (xy 304.324987 -3.594658)
			(xy 304.340743 -3.678948) (xy 304.348655 -3.764331) (xy 304.34915 -3.807206) (xy 304.348655 -3.850081)
			(xy 311.155321 -3.850081) (xy 311.155321 -3.764331) (xy 311.163233 -3.678948) (xy 311.178989 -3.594658)
			(xy 311.202456 -3.512182) (xy 311.233432 -3.432223) (xy 311.271654 -3.355463) (xy 311.316795 -3.282557)
			(xy 311.368471 -3.214128) (xy 311.42624 -3.150758) (xy 311.48961 -3.092989) (xy 311.558039 -3.041313)
			(xy 311.630945 -2.996172) (xy 311.707705 -2.95795) (xy 311.787664 -2.926974) (xy 311.87014 -2.903507)
			(xy 311.95443 -2.887751) (xy 312.039813 -2.879839) (xy 312.125563 -2.879839) (xy 312.210946 -2.887751)
			(xy 312.295236 -2.903507) (xy 312.377712 -2.926974) (xy 312.457671 -2.95795) (xy 312.478344 -2.968244)
			(xy 316.012068 -2.968244) (xy 316.012068 -2.104644) (xy 316.012572 -2.07509) (xy 316.020621 -2.016534)
			(xy 316.036567 -1.959619) (xy 316.060116 -1.905405) (xy 316.090827 -1.854902) (xy 316.128129 -1.809052)
			(xy 316.171326 -1.768709) (xy 316.219615 -1.734623) (xy 316.272095 -1.70743) (xy 316.32779 -1.687636)
			(xy 316.385661 -1.67561) (xy 316.44463 -1.671577) (xy 316.503599 -1.67561) (xy 316.56147 -1.687636)
			(xy 316.617165 -1.70743) (xy 316.669645 -1.734623) (xy 316.717934 -1.768709) (xy 316.761131 -1.809052)
			(xy 316.798433 -1.854902) (xy 316.829144 -1.905405) (xy 316.852693 -1.959619) (xy 316.868639 -2.016534)
			(xy 316.876688 -2.07509) (xy 316.877192 -2.104644) (xy 316.877192 -2.968244) (xy 316.876688 -2.997798)
			(xy 316.868639 -3.056354) (xy 316.852693 -3.113269) (xy 316.829144 -3.167483) (xy 316.798433 -3.217986)
			(xy 316.761131 -3.263836) (xy 316.717934 -3.304179) (xy 316.669645 -3.338265) (xy 316.617165 -3.365458)
			(xy 316.56147 -3.385252) (xy 316.503599 -3.397278) (xy 316.44463 -3.401312) (xy 316.385661 -3.397278)
			(xy 316.32779 -3.385252) (xy 316.272095 -3.365458) (xy 316.219615 -3.338265) (xy 316.171326 -3.304179)
			(xy 316.128129 -3.263836) (xy 316.090827 -3.217986) (xy 316.060116 -3.167483) (xy 316.036567 -3.113269)
			(xy 316.020621 -3.056354) (xy 316.012572 -2.997798) (xy 316.012068 -2.968244) (xy 312.478344 -2.968244)
			(xy 312.534431 -2.996172) (xy 312.607337 -3.041313) (xy 312.675766 -3.092989) (xy 312.739136 -3.150758)
			(xy 312.796905 -3.214128) (xy 312.848581 -3.282557) (xy 312.893722 -3.355463) (xy 312.931944 -3.432223)
			(xy 312.96292 -3.512182) (xy 312.986387 -3.594658) (xy 313.002143 -3.678948) (xy 313.010055 -3.764331)
			(xy 313.01055 -3.807206) (xy 313.010055 -3.850081) (xy 317.505321 -3.850081) (xy 317.505321 -3.764331)
			(xy 317.513233 -3.678948) (xy 317.528989 -3.594658) (xy 317.552456 -3.512182) (xy 317.583432 -3.432223)
			(xy 317.621654 -3.355463) (xy 317.666795 -3.282557) (xy 317.718471 -3.214128) (xy 317.77624 -3.150758)
			(xy 317.83961 -3.092989) (xy 317.908039 -3.041313) (xy 317.980945 -2.996172) (xy 318.057705 -2.95795)
			(xy 318.137664 -2.926974) (xy 318.22014 -2.903507) (xy 318.30443 -2.887751) (xy 318.389813 -2.879839)
			(xy 318.475563 -2.879839) (xy 318.560946 -2.887751) (xy 318.645236 -2.903507) (xy 318.727712 -2.926974)
			(xy 318.807671 -2.95795) (xy 318.884431 -2.996172) (xy 318.957337 -3.041313) (xy 319.025766 -3.092989)
			(xy 319.089136 -3.150758) (xy 319.146905 -3.214128) (xy 319.198581 -3.282557) (xy 319.243722 -3.355463)
			(xy 319.281944 -3.432223) (xy 319.31292 -3.512182) (xy 319.336387 -3.594658) (xy 319.352143 -3.678948)
			(xy 319.360055 -3.764331) (xy 319.36055 -3.807206) (xy 319.360055 -3.850081) (xy 361.894107 -3.850081)
			(xy 361.894107 -3.764331) (xy 361.902019 -3.678948) (xy 361.917775 -3.594658) (xy 361.941242 -3.512182)
			(xy 361.972218 -3.432223) (xy 362.01044 -3.355463) (xy 362.055581 -3.282557) (xy 362.107257 -3.214128)
			(xy 362.165026 -3.150758) (xy 362.228396 -3.092989) (xy 362.296825 -3.041313) (xy 362.369731 -2.996172)
			(xy 362.446491 -2.95795) (xy 362.52645 -2.926974) (xy 362.608926 -2.903507) (xy 362.693216 -2.887751)
			(xy 362.778599 -2.879839) (xy 362.864349 -2.879839) (xy 362.949732 -2.887751) (xy 363.034022 -2.903507)
			(xy 363.116498 -2.926974) (xy 363.196457 -2.95795) (xy 363.21713 -2.968244) (xy 364.379764 -2.968244)
			(xy 364.379764 -2.104644) (xy 364.380268 -2.075108) (xy 364.388312 -2.016586) (xy 364.404249 -1.959704)
			(xy 364.427784 -1.905522) (xy 364.458477 -1.855049) (xy 364.495757 -1.809226) (xy 364.538929 -1.768906)
			(xy 364.587189 -1.73484) (xy 364.639639 -1.707663) (xy 364.6953 -1.687881) (xy 364.753137 -1.675862)
			(xy 364.812072 -1.671831) (xy 364.871007 -1.675862) (xy 364.928844 -1.687881) (xy 364.984505 -1.707663)
			(xy 365.036955 -1.73484) (xy 365.085215 -1.768906) (xy 365.128387 -1.809226) (xy 365.165667 -1.855049)
			(xy 365.19636 -1.905522) (xy 365.219895 -1.959704) (xy 365.235832 -2.016586) (xy 365.243876 -2.075108)
			(xy 365.24438 -2.104644) (xy 365.24438 -2.968244) (xy 365.243876 -2.99778) (xy 365.235832 -3.056302)
			(xy 365.219895 -3.113184) (xy 365.19636 -3.167366) (xy 365.165667 -3.217839) (xy 365.128387 -3.263662)
			(xy 365.085215 -3.303982) (xy 365.036955 -3.338048) (xy 364.984505 -3.365225) (xy 364.928844 -3.385007)
			(xy 364.871007 -3.397026) (xy 364.812072 -3.401057) (xy 364.753137 -3.397026) (xy 364.6953 -3.385007)
			(xy 364.639639 -3.365225) (xy 364.587189 -3.338048) (xy 364.538929 -3.303982) (xy 364.495757 -3.263662)
			(xy 364.458477 -3.217839) (xy 364.427784 -3.167366) (xy 364.404249 -3.113184) (xy 364.388312 -3.056302)
			(xy 364.380268 -2.99778) (xy 364.379764 -2.968244) (xy 363.21713 -2.968244) (xy 363.273217 -2.996172)
			(xy 363.346123 -3.041313) (xy 363.414552 -3.092989) (xy 363.477922 -3.150758) (xy 363.535691 -3.214128)
			(xy 363.587367 -3.282557) (xy 363.632508 -3.355463) (xy 363.67073 -3.432223) (xy 363.701706 -3.512182)
			(xy 363.725173 -3.594658) (xy 363.740929 -3.678948) (xy 363.748841 -3.764331) (xy 363.749336 -3.807206)
			(xy 363.748841 -3.850081) (xy 368.244107 -3.850081) (xy 368.244107 -3.764331) (xy 368.252019 -3.678948)
			(xy 368.267775 -3.594658) (xy 368.291242 -3.512182) (xy 368.322218 -3.432223) (xy 368.36044 -3.355463)
			(xy 368.405581 -3.282557) (xy 368.457257 -3.214128) (xy 368.515026 -3.150758) (xy 368.578396 -3.092989)
			(xy 368.646825 -3.041313) (xy 368.719731 -2.996172) (xy 368.796491 -2.95795) (xy 368.87645 -2.926974)
			(xy 368.958926 -2.903507) (xy 369.043216 -2.887751) (xy 369.128599 -2.879839) (xy 369.214349 -2.879839)
			(xy 369.299732 -2.887751) (xy 369.384022 -2.903507) (xy 369.466498 -2.926974) (xy 369.546457 -2.95795)
			(xy 369.623217 -2.996172) (xy 369.696123 -3.041313) (xy 369.764552 -3.092989) (xy 369.827922 -3.150758)
			(xy 369.885691 -3.214128) (xy 369.937367 -3.282557) (xy 369.982508 -3.355463) (xy 370.02073 -3.432223)
			(xy 370.051706 -3.512182) (xy 370.075173 -3.594658) (xy 370.090929 -3.678948) (xy 370.098841 -3.764331)
			(xy 370.099336 -3.807206) (xy 370.098841 -3.850081) (xy 370.090929 -3.935464) (xy 370.075173 -4.019754)
			(xy 370.051706 -4.10223) (xy 370.02073 -4.182189) (xy 369.982508 -4.258949) (xy 369.937367 -4.331855)
			(xy 369.885691 -4.400284) (xy 369.827922 -4.463654) (xy 369.764552 -4.521423) (xy 369.696123 -4.573099)
			(xy 369.623217 -4.61824) (xy 369.546457 -4.656462) (xy 369.466498 -4.687438) (xy 369.384022 -4.710905)
			(xy 369.299732 -4.726661) (xy 369.214349 -4.734573) (xy 369.128599 -4.734573) (xy 369.043216 -4.726661)
			(xy 368.958926 -4.710905) (xy 368.87645 -4.687438) (xy 368.796491 -4.656462) (xy 368.719731 -4.61824)
			(xy 368.646825 -4.573099) (xy 368.578396 -4.521423) (xy 368.515026 -4.463654) (xy 368.457257 -4.400284)
			(xy 368.405581 -4.331855) (xy 368.36044 -4.258949) (xy 368.322218 -4.182189) (xy 368.291242 -4.10223)
			(xy 368.267775 -4.019754) (xy 368.252019 -3.935464) (xy 368.244107 -3.850081) (xy 363.748841 -3.850081)
			(xy 363.740929 -3.935464) (xy 363.725173 -4.019754) (xy 363.701706 -4.10223) (xy 363.67073 -4.182189)
			(xy 363.632508 -4.258949) (xy 363.587367 -4.331855) (xy 363.535691 -4.400284) (xy 363.477922 -4.463654)
			(xy 363.414552 -4.521423) (xy 363.346123 -4.573099) (xy 363.273217 -4.61824) (xy 363.196457 -4.656462)
			(xy 363.116498 -4.687438) (xy 363.034022 -4.710905) (xy 362.949732 -4.726661) (xy 362.864349 -4.734573)
			(xy 362.778599 -4.734573) (xy 362.693216 -4.726661) (xy 362.608926 -4.710905) (xy 362.52645 -4.687438)
			(xy 362.446491 -4.656462) (xy 362.369731 -4.61824) (xy 362.296825 -4.573099) (xy 362.228396 -4.521423)
			(xy 362.165026 -4.463654) (xy 362.107257 -4.400284) (xy 362.055581 -4.331855) (xy 362.01044 -4.258949)
			(xy 361.972218 -4.182189) (xy 361.941242 -4.10223) (xy 361.917775 -4.019754) (xy 361.902019 -3.935464)
			(xy 361.894107 -3.850081) (xy 319.360055 -3.850081) (xy 319.352143 -3.935464) (xy 319.336387 -4.019754)
			(xy 319.31292 -4.10223) (xy 319.281944 -4.182189) (xy 319.243722 -4.258949) (xy 319.198581 -4.331855)
			(xy 319.146905 -4.400284) (xy 319.089136 -4.463654) (xy 319.025766 -4.521423) (xy 318.957337 -4.573099)
			(xy 318.884431 -4.61824) (xy 318.807671 -4.656462) (xy 318.727712 -4.687438) (xy 318.645236 -4.710905)
			(xy 318.560946 -4.726661) (xy 318.475563 -4.734573) (xy 318.389813 -4.734573) (xy 318.30443 -4.726661)
			(xy 318.22014 -4.710905) (xy 318.137664 -4.687438) (xy 318.057705 -4.656462) (xy 317.980945 -4.61824)
			(xy 317.908039 -4.573099) (xy 317.83961 -4.521423) (xy 317.77624 -4.463654) (xy 317.718471 -4.400284)
			(xy 317.666795 -4.331855) (xy 317.621654 -4.258949) (xy 317.583432 -4.182189) (xy 317.552456 -4.10223)
			(xy 317.528989 -4.019754) (xy 317.513233 -3.935464) (xy 317.505321 -3.850081) (xy 313.010055 -3.850081)
			(xy 313.002143 -3.935464) (xy 312.986387 -4.019754) (xy 312.96292 -4.10223) (xy 312.931944 -4.182189)
			(xy 312.893722 -4.258949) (xy 312.848581 -4.331855) (xy 312.796905 -4.400284) (xy 312.739136 -4.463654)
			(xy 312.675766 -4.521423) (xy 312.607337 -4.573099) (xy 312.534431 -4.61824) (xy 312.457671 -4.656462)
			(xy 312.377712 -4.687438) (xy 312.295236 -4.710905) (xy 312.210946 -4.726661) (xy 312.125563 -4.734573)
			(xy 312.039813 -4.734573) (xy 311.95443 -4.726661) (xy 311.87014 -4.710905) (xy 311.787664 -4.687438)
			(xy 311.707705 -4.656462) (xy 311.630945 -4.61824) (xy 311.558039 -4.573099) (xy 311.48961 -4.521423)
			(xy 311.42624 -4.463654) (xy 311.368471 -4.400284) (xy 311.316795 -4.331855) (xy 311.271654 -4.258949)
			(xy 311.233432 -4.182189) (xy 311.202456 -4.10223) (xy 311.178989 -4.019754) (xy 311.163233 -3.935464)
			(xy 311.155321 -3.850081) (xy 304.348655 -3.850081) (xy 304.340743 -3.935464) (xy 304.324987 -4.019754)
			(xy 304.30152 -4.10223) (xy 304.270544 -4.182189) (xy 304.232322 -4.258949) (xy 304.187181 -4.331855)
			(xy 304.135505 -4.400284) (xy 304.077736 -4.463654) (xy 304.014366 -4.521423) (xy 303.945937 -4.573099)
			(xy 303.873031 -4.61824) (xy 303.796271 -4.656462) (xy 303.716312 -4.687438) (xy 303.633836 -4.710905)
			(xy 303.549546 -4.726661) (xy 303.464163 -4.734573) (xy 303.378413 -4.734573) (xy 303.29303 -4.726661)
			(xy 303.20874 -4.710905) (xy 303.126264 -4.687438) (xy 303.046305 -4.656462) (xy 302.969545 -4.61824)
			(xy 302.896639 -4.573099) (xy 302.82821 -4.521423) (xy 302.76484 -4.463654) (xy 302.707071 -4.400284)
			(xy 302.655395 -4.331855) (xy 302.610254 -4.258949) (xy 302.572032 -4.182189) (xy 302.541056 -4.10223)
			(xy 302.517589 -4.019754) (xy 302.501833 -3.935464) (xy 302.493921 -3.850081) (xy 297.998655 -3.850081)
			(xy 297.990743 -3.935464) (xy 297.974987 -4.019754) (xy 297.95152 -4.10223) (xy 297.920544 -4.182189)
			(xy 297.882322 -4.258949) (xy 297.837181 -4.331855) (xy 297.785505 -4.400284) (xy 297.727736 -4.463654)
			(xy 297.664366 -4.521423) (xy 297.595937 -4.573099) (xy 297.523031 -4.61824) (xy 297.446271 -4.656462)
			(xy 297.366312 -4.687438) (xy 297.283836 -4.710905) (xy 297.199546 -4.726661) (xy 297.114163 -4.734573)
			(xy 297.028413 -4.734573) (xy 296.94303 -4.726661) (xy 296.85874 -4.710905) (xy 296.776264 -4.687438)
			(xy 296.696305 -4.656462) (xy 296.619545 -4.61824) (xy 296.546639 -4.573099) (xy 296.47821 -4.521423)
			(xy 296.41484 -4.463654) (xy 296.357071 -4.400284) (xy 296.305395 -4.331855) (xy 296.260254 -4.258949)
			(xy 296.222032 -4.182189) (xy 296.191056 -4.10223) (xy 296.167589 -4.019754) (xy 296.151833 -3.935464)
			(xy 296.143921 -3.850081) (xy 216.865975 -3.850081) (xy 216.858063 -3.935464) (xy 216.842307 -4.019754)
			(xy 216.81884 -4.10223) (xy 216.787864 -4.182189) (xy 216.749642 -4.258949) (xy 216.704501 -4.331855)
			(xy 216.652825 -4.400284) (xy 216.595056 -4.463654) (xy 216.531686 -4.521423) (xy 216.463257 -4.573099)
			(xy 216.390351 -4.61824) (xy 216.313591 -4.656462) (xy 216.233632 -4.687438) (xy 216.151156 -4.710905)
			(xy 216.066866 -4.726661) (xy 215.981483 -4.734573) (xy 215.895733 -4.734573) (xy 215.81035 -4.726661)
			(xy 215.72606 -4.710905) (xy 215.643584 -4.687438) (xy 215.563625 -4.656462) (xy 215.486865 -4.61824)
			(xy 215.413959 -4.573099) (xy 215.34553 -4.521423) (xy 215.28216 -4.463654) (xy 215.224391 -4.400284)
			(xy 215.172715 -4.331855) (xy 215.127574 -4.258949) (xy 215.089352 -4.182189) (xy 215.058376 -4.10223)
			(xy 215.034909 -4.019754) (xy 215.019153 -3.935464) (xy 215.011241 -3.850081) (xy 210.515975 -3.850081)
			(xy 210.508063 -3.935464) (xy 210.492307 -4.019754) (xy 210.46884 -4.10223) (xy 210.437864 -4.182189)
			(xy 210.399642 -4.258949) (xy 210.354501 -4.331855) (xy 210.302825 -4.400284) (xy 210.245056 -4.463654)
			(xy 210.181686 -4.521423) (xy 210.113257 -4.573099) (xy 210.040351 -4.61824) (xy 209.963591 -4.656462)
			(xy 209.883632 -4.687438) (xy 209.801156 -4.710905) (xy 209.716866 -4.726661) (xy 209.631483 -4.734573)
			(xy 209.545733 -4.734573) (xy 209.46035 -4.726661) (xy 209.37606 -4.710905) (xy 209.293584 -4.687438)
			(xy 209.213625 -4.656462) (xy 209.136865 -4.61824) (xy 209.063959 -4.573099) (xy 208.99553 -4.521423)
			(xy 208.93216 -4.463654) (xy 208.874391 -4.400284) (xy 208.822715 -4.331855) (xy 208.777574 -4.258949)
			(xy 208.739352 -4.182189) (xy 208.708376 -4.10223) (xy 208.684909 -4.019754) (xy 208.669153 -3.935464)
			(xy 208.661241 -3.850081) (xy 196.990215 -3.850081) (xy 196.992516 -3.85486) (xy 197.046381 -3.984909)
			(xy 197.09287 -4.117774) (xy 197.131836 -4.253037) (xy 197.163157 -4.390271) (xy 197.186733 -4.529046)
			(xy 197.202491 -4.668924) (xy 197.210381 -4.809466) (xy 197.210934 -4.879848) (xy 197.210934 -6.390081)
			(xy 208.661241 -6.390081) (xy 208.661241 -6.304331) (xy 208.669153 -6.218948) (xy 208.684909 -6.134658)
			(xy 208.708376 -6.052182) (xy 208.739352 -5.972223) (xy 208.777574 -5.895463) (xy 208.822715 -5.822557)
			(xy 208.874391 -5.754128) (xy 208.93216 -5.690758) (xy 208.99553 -5.632989) (xy 209.063959 -5.581313)
			(xy 209.136865 -5.536172) (xy 209.213625 -5.49795) (xy 209.293584 -5.466974) (xy 209.37606 -5.443507)
			(xy 209.46035 -5.427751) (xy 209.545733 -5.419839) (xy 209.631483 -5.419839) (xy 209.716866 -5.427751)
			(xy 209.801156 -5.443507) (xy 209.883632 -5.466974) (xy 209.963591 -5.49795) (xy 209.984264 -5.508244)
			(xy 213.517988 -5.508244) (xy 213.517988 -4.644644) (xy 213.518492 -4.61509) (xy 213.526541 -4.556534)
			(xy 213.542487 -4.499619) (xy 213.566036 -4.445405) (xy 213.596747 -4.394902) (xy 213.634049 -4.349052)
			(xy 213.677246 -4.308709) (xy 213.725535 -4.274623) (xy 213.778015 -4.24743) (xy 213.83371 -4.227636)
			(xy 213.891581 -4.21561) (xy 213.95055 -4.211577) (xy 214.009519 -4.21561) (xy 214.06739 -4.227636)
			(xy 214.123085 -4.24743) (xy 214.175565 -4.274623) (xy 214.223854 -4.308709) (xy 214.267051 -4.349052)
			(xy 214.304353 -4.394902) (xy 214.335064 -4.445405) (xy 214.358613 -4.499619) (xy 214.374559 -4.556534)
			(xy 214.382608 -4.61509) (xy 214.383112 -4.644644) (xy 214.383112 -5.508244) (xy 214.382608 -5.537798)
			(xy 214.374559 -5.596354) (xy 214.358613 -5.653269) (xy 214.335064 -5.707483) (xy 214.304353 -5.757986)
			(xy 214.267051 -5.803836) (xy 214.223854 -5.844179) (xy 214.175565 -5.878265) (xy 214.123085 -5.905458)
			(xy 214.06739 -5.925252) (xy 214.009519 -5.937278) (xy 213.95055 -5.941312) (xy 213.891581 -5.937278)
			(xy 213.83371 -5.925252) (xy 213.778015 -5.905458) (xy 213.725535 -5.878265) (xy 213.677246 -5.844179)
			(xy 213.634049 -5.803836) (xy 213.596747 -5.757986) (xy 213.566036 -5.707483) (xy 213.542487 -5.653269)
			(xy 213.526541 -5.596354) (xy 213.518492 -5.537798) (xy 213.517988 -5.508244) (xy 209.984264 -5.508244)
			(xy 210.040351 -5.536172) (xy 210.113257 -5.581313) (xy 210.181686 -5.632989) (xy 210.245056 -5.690758)
			(xy 210.302825 -5.754128) (xy 210.354501 -5.822557) (xy 210.399642 -5.895463) (xy 210.437864 -5.972223)
			(xy 210.46884 -6.052182) (xy 210.492307 -6.134658) (xy 210.508063 -6.218948) (xy 210.515975 -6.304331)
			(xy 210.51647 -6.347206) (xy 210.515975 -6.390081) (xy 215.011241 -6.390081) (xy 215.011241 -6.304331)
			(xy 215.019153 -6.218948) (xy 215.034909 -6.134658) (xy 215.058376 -6.052182) (xy 215.089352 -5.972223)
			(xy 215.127574 -5.895463) (xy 215.172715 -5.822557) (xy 215.224391 -5.754128) (xy 215.28216 -5.690758)
			(xy 215.34553 -5.632989) (xy 215.413959 -5.581313) (xy 215.486865 -5.536172) (xy 215.563625 -5.49795)
			(xy 215.643584 -5.466974) (xy 215.72606 -5.443507) (xy 215.81035 -5.427751) (xy 215.895733 -5.419839)
			(xy 215.981483 -5.419839) (xy 216.066866 -5.427751) (xy 216.151156 -5.443507) (xy 216.233632 -5.466974)
			(xy 216.313591 -5.49795) (xy 216.390351 -5.536172) (xy 216.463257 -5.581313) (xy 216.531686 -5.632989)
			(xy 216.595056 -5.690758) (xy 216.652825 -5.754128) (xy 216.704501 -5.822557) (xy 216.749642 -5.895463)
			(xy 216.787864 -5.972223) (xy 216.81884 -6.052182) (xy 216.842307 -6.134658) (xy 216.858063 -6.218948)
			(xy 216.865975 -6.304331) (xy 216.86647 -6.347206) (xy 216.865975 -6.390081) (xy 296.143921 -6.390081)
			(xy 296.143921 -6.304331) (xy 296.151833 -6.218948) (xy 296.167589 -6.134658) (xy 296.191056 -6.052182)
			(xy 296.222032 -5.972223) (xy 296.260254 -5.895463) (xy 296.305395 -5.822557) (xy 296.357071 -5.754128)
			(xy 296.41484 -5.690758) (xy 296.47821 -5.632989) (xy 296.546639 -5.581313) (xy 296.619545 -5.536172)
			(xy 296.696305 -5.49795) (xy 296.776264 -5.466974) (xy 296.85874 -5.443507) (xy 296.94303 -5.427751)
			(xy 297.028413 -5.419839) (xy 297.114163 -5.419839) (xy 297.199546 -5.427751) (xy 297.283836 -5.443507)
			(xy 297.366312 -5.466974) (xy 297.446271 -5.49795) (xy 297.466944 -5.508244) (xy 298.629324 -5.508244)
			(xy 298.629324 -4.644644) (xy 298.629828 -4.61509) (xy 298.637877 -4.556534) (xy 298.653823 -4.499619)
			(xy 298.677372 -4.445405) (xy 298.708083 -4.394902) (xy 298.745385 -4.349052) (xy 298.788582 -4.308709)
			(xy 298.836871 -4.274623) (xy 298.889351 -4.24743) (xy 298.945046 -4.227636) (xy 299.002917 -4.21561)
			(xy 299.061886 -4.211577) (xy 299.120855 -4.21561) (xy 299.178726 -4.227636) (xy 299.234421 -4.24743)
			(xy 299.286901 -4.274623) (xy 299.33519 -4.308709) (xy 299.378387 -4.349052) (xy 299.415689 -4.394902)
			(xy 299.4464 -4.445405) (xy 299.469949 -4.499619) (xy 299.485895 -4.556534) (xy 299.493944 -4.61509)
			(xy 299.494448 -4.644644) (xy 299.494448 -5.508244) (xy 299.493944 -5.537798) (xy 299.485895 -5.596354)
			(xy 299.469949 -5.653269) (xy 299.4464 -5.707483) (xy 299.415689 -5.757986) (xy 299.378387 -5.803836)
			(xy 299.33519 -5.844179) (xy 299.286901 -5.878265) (xy 299.234421 -5.905458) (xy 299.178726 -5.925252)
			(xy 299.120855 -5.937278) (xy 299.061886 -5.941312) (xy 299.002917 -5.937278) (xy 298.945046 -5.925252)
			(xy 298.889351 -5.905458) (xy 298.836871 -5.878265) (xy 298.788582 -5.844179) (xy 298.745385 -5.803836)
			(xy 298.708083 -5.757986) (xy 298.677372 -5.707483) (xy 298.653823 -5.653269) (xy 298.637877 -5.596354)
			(xy 298.629828 -5.537798) (xy 298.629324 -5.508244) (xy 297.466944 -5.508244) (xy 297.523031 -5.536172)
			(xy 297.595937 -5.581313) (xy 297.664366 -5.632989) (xy 297.727736 -5.690758) (xy 297.785505 -5.754128)
			(xy 297.837181 -5.822557) (xy 297.882322 -5.895463) (xy 297.920544 -5.972223) (xy 297.95152 -6.052182)
			(xy 297.974987 -6.134658) (xy 297.990743 -6.218948) (xy 297.998655 -6.304331) (xy 297.99915 -6.347206)
			(xy 297.998655 -6.390081) (xy 302.493921 -6.390081) (xy 302.493921 -6.304331) (xy 302.501833 -6.218948)
			(xy 302.517589 -6.134658) (xy 302.541056 -6.052182) (xy 302.572032 -5.972223) (xy 302.610254 -5.895463)
			(xy 302.655395 -5.822557) (xy 302.707071 -5.754128) (xy 302.76484 -5.690758) (xy 302.82821 -5.632989)
			(xy 302.896639 -5.581313) (xy 302.969545 -5.536172) (xy 303.046305 -5.49795) (xy 303.126264 -5.466974)
			(xy 303.20874 -5.443507) (xy 303.29303 -5.427751) (xy 303.378413 -5.419839) (xy 303.464163 -5.419839)
			(xy 303.549546 -5.427751) (xy 303.633836 -5.443507) (xy 303.716312 -5.466974) (xy 303.796271 -5.49795)
			(xy 303.873031 -5.536172) (xy 303.945937 -5.581313) (xy 304.014366 -5.632989) (xy 304.077736 -5.690758)
			(xy 304.135505 -5.754128) (xy 304.187181 -5.822557) (xy 304.232322 -5.895463) (xy 304.270544 -5.972223)
			(xy 304.30152 -6.052182) (xy 304.324987 -6.134658) (xy 304.340743 -6.218948) (xy 304.348655 -6.304331)
			(xy 304.34915 -6.347206) (xy 304.348655 -6.390081) (xy 311.155321 -6.390081) (xy 311.155321 -6.304331)
			(xy 311.163233 -6.218948) (xy 311.178989 -6.134658) (xy 311.202456 -6.052182) (xy 311.233432 -5.972223)
			(xy 311.271654 -5.895463) (xy 311.316795 -5.822557) (xy 311.368471 -5.754128) (xy 311.42624 -5.690758)
			(xy 311.48961 -5.632989) (xy 311.558039 -5.581313) (xy 311.630945 -5.536172) (xy 311.707705 -5.49795)
			(xy 311.787664 -5.466974) (xy 311.87014 -5.443507) (xy 311.95443 -5.427751) (xy 312.039813 -5.419839)
			(xy 312.125563 -5.419839) (xy 312.210946 -5.427751) (xy 312.295236 -5.443507) (xy 312.377712 -5.466974)
			(xy 312.457671 -5.49795) (xy 312.534431 -5.536172) (xy 312.607337 -5.581313) (xy 312.675766 -5.632989)
			(xy 312.739136 -5.690758) (xy 312.796905 -5.754128) (xy 312.848581 -5.822557) (xy 312.893722 -5.895463)
			(xy 312.931944 -5.972223) (xy 312.96292 -6.052182) (xy 312.986387 -6.134658) (xy 313.002143 -6.218948)
			(xy 313.010055 -6.304331) (xy 313.01055 -6.347206) (xy 313.010055 -6.390081) (xy 317.505321 -6.390081)
			(xy 317.505321 -6.304331) (xy 317.513233 -6.218948) (xy 317.528989 -6.134658) (xy 317.552456 -6.052182)
			(xy 317.583432 -5.972223) (xy 317.621654 -5.895463) (xy 317.666795 -5.822557) (xy 317.718471 -5.754128)
			(xy 317.77624 -5.690758) (xy 317.83961 -5.632989) (xy 317.908039 -5.581313) (xy 317.980945 -5.536172)
			(xy 318.057705 -5.49795) (xy 318.137664 -5.466974) (xy 318.22014 -5.443507) (xy 318.30443 -5.427751)
			(xy 318.389813 -5.419839) (xy 318.475563 -5.419839) (xy 318.560946 -5.427751) (xy 318.645236 -5.443507)
			(xy 318.727712 -5.466974) (xy 318.807671 -5.49795) (xy 318.884431 -5.536172) (xy 318.957337 -5.581313)
			(xy 319.025766 -5.632989) (xy 319.089136 -5.690758) (xy 319.146905 -5.754128) (xy 319.198581 -5.822557)
			(xy 319.243722 -5.895463) (xy 319.281944 -5.972223) (xy 319.31292 -6.052182) (xy 319.336387 -6.134658)
			(xy 319.352143 -6.218948) (xy 319.360055 -6.304331) (xy 319.36055 -6.347206) (xy 319.360055 -6.390081)
			(xy 361.894107 -6.390081) (xy 361.894107 -6.304331) (xy 361.902019 -6.218948) (xy 361.917775 -6.134658)
			(xy 361.941242 -6.052182) (xy 361.972218 -5.972223) (xy 362.01044 -5.895463) (xy 362.055581 -5.822557)
			(xy 362.107257 -5.754128) (xy 362.165026 -5.690758) (xy 362.228396 -5.632989) (xy 362.296825 -5.581313)
			(xy 362.369731 -5.536172) (xy 362.446491 -5.49795) (xy 362.52645 -5.466974) (xy 362.608926 -5.443507)
			(xy 362.693216 -5.427751) (xy 362.778599 -5.419839) (xy 362.864349 -5.419839) (xy 362.949732 -5.427751)
			(xy 363.034022 -5.443507) (xy 363.116498 -5.466974) (xy 363.196457 -5.49795) (xy 363.273217 -5.536172)
			(xy 363.346123 -5.581313) (xy 363.414552 -5.632989) (xy 363.477922 -5.690758) (xy 363.535691 -5.754128)
			(xy 363.587367 -5.822557) (xy 363.632508 -5.895463) (xy 363.67073 -5.972223) (xy 363.701706 -6.052182)
			(xy 363.725173 -6.134658) (xy 363.740929 -6.218948) (xy 363.748841 -6.304331) (xy 363.749336 -6.347206)
			(xy 363.748841 -6.390081) (xy 368.244107 -6.390081) (xy 368.244107 -6.304331) (xy 368.252019 -6.218948)
			(xy 368.267775 -6.134658) (xy 368.291242 -6.052182) (xy 368.322218 -5.972223) (xy 368.36044 -5.895463)
			(xy 368.405581 -5.822557) (xy 368.457257 -5.754128) (xy 368.515026 -5.690758) (xy 368.578396 -5.632989)
			(xy 368.646825 -5.581313) (xy 368.719731 -5.536172) (xy 368.796491 -5.49795) (xy 368.87645 -5.466974)
			(xy 368.958926 -5.443507) (xy 369.043216 -5.427751) (xy 369.128599 -5.419839) (xy 369.214349 -5.419839)
			(xy 369.299732 -5.427751) (xy 369.384022 -5.443507) (xy 369.466498 -5.466974) (xy 369.546457 -5.49795)
			(xy 369.623217 -5.536172) (xy 369.696123 -5.581313) (xy 369.764552 -5.632989) (xy 369.827922 -5.690758)
			(xy 369.885691 -5.754128) (xy 369.937367 -5.822557) (xy 369.982508 -5.895463) (xy 370.02073 -5.972223)
			(xy 370.051706 -6.052182) (xy 370.075173 -6.134658) (xy 370.090929 -6.218948) (xy 370.098841 -6.304331)
			(xy 370.099336 -6.347206) (xy 370.098841 -6.390081) (xy 370.090929 -6.475464) (xy 370.075173 -6.559754)
			(xy 370.051706 -6.64223) (xy 370.02073 -6.722189) (xy 369.982508 -6.798949) (xy 369.937367 -6.871855)
			(xy 369.885691 -6.940284) (xy 369.827922 -7.003654) (xy 369.764552 -7.061423) (xy 369.696123 -7.113099)
			(xy 369.623217 -7.15824) (xy 369.546457 -7.196462) (xy 369.466498 -7.227438) (xy 369.384022 -7.250905)
			(xy 369.299732 -7.266661) (xy 369.214349 -7.274573) (xy 369.128599 -7.274573) (xy 369.043216 -7.266661)
			(xy 368.958926 -7.250905) (xy 368.87645 -7.227438) (xy 368.796491 -7.196462) (xy 368.719731 -7.15824)
			(xy 368.646825 -7.113099) (xy 368.578396 -7.061423) (xy 368.515026 -7.003654) (xy 368.457257 -6.940284)
			(xy 368.405581 -6.871855) (xy 368.36044 -6.798949) (xy 368.322218 -6.722189) (xy 368.291242 -6.64223)
			(xy 368.267775 -6.559754) (xy 368.252019 -6.475464) (xy 368.244107 -6.390081) (xy 363.748841 -6.390081)
			(xy 363.740929 -6.475464) (xy 363.725173 -6.559754) (xy 363.701706 -6.64223) (xy 363.67073 -6.722189)
			(xy 363.632508 -6.798949) (xy 363.587367 -6.871855) (xy 363.535691 -6.940284) (xy 363.477922 -7.003654)
			(xy 363.414552 -7.061423) (xy 363.346123 -7.113099) (xy 363.273217 -7.15824) (xy 363.196457 -7.196462)
			(xy 363.116498 -7.227438) (xy 363.034022 -7.250905) (xy 362.949732 -7.266661) (xy 362.864349 -7.274573)
			(xy 362.778599 -7.274573) (xy 362.693216 -7.266661) (xy 362.608926 -7.250905) (xy 362.52645 -7.227438)
			(xy 362.446491 -7.196462) (xy 362.369731 -7.15824) (xy 362.296825 -7.113099) (xy 362.228396 -7.061423)
			(xy 362.165026 -7.003654) (xy 362.107257 -6.940284) (xy 362.055581 -6.871855) (xy 362.01044 -6.798949)
			(xy 361.972218 -6.722189) (xy 361.941242 -6.64223) (xy 361.917775 -6.559754) (xy 361.902019 -6.475464)
			(xy 361.894107 -6.390081) (xy 319.360055 -6.390081) (xy 319.352143 -6.475464) (xy 319.336387 -6.559754)
			(xy 319.31292 -6.64223) (xy 319.281944 -6.722189) (xy 319.243722 -6.798949) (xy 319.198581 -6.871855)
			(xy 319.146905 -6.940284) (xy 319.089136 -7.003654) (xy 319.025766 -7.061423) (xy 318.957337 -7.113099)
			(xy 318.884431 -7.15824) (xy 318.807671 -7.196462) (xy 318.727712 -7.227438) (xy 318.645236 -7.250905)
			(xy 318.560946 -7.266661) (xy 318.475563 -7.274573) (xy 318.389813 -7.274573) (xy 318.30443 -7.266661)
			(xy 318.22014 -7.250905) (xy 318.137664 -7.227438) (xy 318.057705 -7.196462) (xy 317.980945 -7.15824)
			(xy 317.908039 -7.113099) (xy 317.83961 -7.061423) (xy 317.77624 -7.003654) (xy 317.718471 -6.940284)
			(xy 317.666795 -6.871855) (xy 317.621654 -6.798949) (xy 317.583432 -6.722189) (xy 317.552456 -6.64223)
			(xy 317.528989 -6.559754) (xy 317.513233 -6.475464) (xy 317.505321 -6.390081) (xy 313.010055 -6.390081)
			(xy 313.002143 -6.475464) (xy 312.986387 -6.559754) (xy 312.96292 -6.64223) (xy 312.931944 -6.722189)
			(xy 312.893722 -6.798949) (xy 312.848581 -6.871855) (xy 312.796905 -6.940284) (xy 312.739136 -7.003654)
			(xy 312.675766 -7.061423) (xy 312.607337 -7.113099) (xy 312.534431 -7.15824) (xy 312.457671 -7.196462)
			(xy 312.377712 -7.227438) (xy 312.295236 -7.250905) (xy 312.210946 -7.266661) (xy 312.125563 -7.274573)
			(xy 312.039813 -7.274573) (xy 311.95443 -7.266661) (xy 311.87014 -7.250905) (xy 311.787664 -7.227438)
			(xy 311.707705 -7.196462) (xy 311.630945 -7.15824) (xy 311.558039 -7.113099) (xy 311.48961 -7.061423)
			(xy 311.42624 -7.003654) (xy 311.368471 -6.940284) (xy 311.316795 -6.871855) (xy 311.271654 -6.798949)
			(xy 311.233432 -6.722189) (xy 311.202456 -6.64223) (xy 311.178989 -6.559754) (xy 311.163233 -6.475464)
			(xy 311.155321 -6.390081) (xy 304.348655 -6.390081) (xy 304.340743 -6.475464) (xy 304.324987 -6.559754)
			(xy 304.30152 -6.64223) (xy 304.270544 -6.722189) (xy 304.232322 -6.798949) (xy 304.187181 -6.871855)
			(xy 304.135505 -6.940284) (xy 304.077736 -7.003654) (xy 304.014366 -7.061423) (xy 303.945937 -7.113099)
			(xy 303.873031 -7.15824) (xy 303.796271 -7.196462) (xy 303.716312 -7.227438) (xy 303.633836 -7.250905)
			(xy 303.549546 -7.266661) (xy 303.464163 -7.274573) (xy 303.378413 -7.274573) (xy 303.29303 -7.266661)
			(xy 303.20874 -7.250905) (xy 303.126264 -7.227438) (xy 303.046305 -7.196462) (xy 302.969545 -7.15824)
			(xy 302.896639 -7.113099) (xy 302.82821 -7.061423) (xy 302.76484 -7.003654) (xy 302.707071 -6.940284)
			(xy 302.655395 -6.871855) (xy 302.610254 -6.798949) (xy 302.572032 -6.722189) (xy 302.541056 -6.64223)
			(xy 302.517589 -6.559754) (xy 302.501833 -6.475464) (xy 302.493921 -6.390081) (xy 297.998655 -6.390081)
			(xy 297.990743 -6.475464) (xy 297.974987 -6.559754) (xy 297.95152 -6.64223) (xy 297.920544 -6.722189)
			(xy 297.882322 -6.798949) (xy 297.837181 -6.871855) (xy 297.785505 -6.940284) (xy 297.727736 -7.003654)
			(xy 297.664366 -7.061423) (xy 297.595937 -7.113099) (xy 297.523031 -7.15824) (xy 297.446271 -7.196462)
			(xy 297.366312 -7.227438) (xy 297.283836 -7.250905) (xy 297.199546 -7.266661) (xy 297.114163 -7.274573)
			(xy 297.028413 -7.274573) (xy 296.94303 -7.266661) (xy 296.85874 -7.250905) (xy 296.776264 -7.227438)
			(xy 296.696305 -7.196462) (xy 296.619545 -7.15824) (xy 296.546639 -7.113099) (xy 296.47821 -7.061423)
			(xy 296.41484 -7.003654) (xy 296.357071 -6.940284) (xy 296.305395 -6.871855) (xy 296.260254 -6.798949)
			(xy 296.222032 -6.722189) (xy 296.191056 -6.64223) (xy 296.167589 -6.559754) (xy 296.151833 -6.475464)
			(xy 296.143921 -6.390081) (xy 216.865975 -6.390081) (xy 216.858063 -6.475464) (xy 216.842307 -6.559754)
			(xy 216.81884 -6.64223) (xy 216.787864 -6.722189) (xy 216.749642 -6.798949) (xy 216.704501 -6.871855)
			(xy 216.652825 -6.940284) (xy 216.595056 -7.003654) (xy 216.531686 -7.061423) (xy 216.463257 -7.113099)
			(xy 216.390351 -7.15824) (xy 216.313591 -7.196462) (xy 216.233632 -7.227438) (xy 216.151156 -7.250905)
			(xy 216.066866 -7.266661) (xy 215.981483 -7.274573) (xy 215.895733 -7.274573) (xy 215.81035 -7.266661)
			(xy 215.72606 -7.250905) (xy 215.643584 -7.227438) (xy 215.563625 -7.196462) (xy 215.486865 -7.15824)
			(xy 215.413959 -7.113099) (xy 215.34553 -7.061423) (xy 215.28216 -7.003654) (xy 215.224391 -6.940284)
			(xy 215.172715 -6.871855) (xy 215.127574 -6.798949) (xy 215.089352 -6.722189) (xy 215.058376 -6.64223)
			(xy 215.034909 -6.559754) (xy 215.019153 -6.475464) (xy 215.011241 -6.390081) (xy 210.515975 -6.390081)
			(xy 210.508063 -6.475464) (xy 210.492307 -6.559754) (xy 210.46884 -6.64223) (xy 210.437864 -6.722189)
			(xy 210.399642 -6.798949) (xy 210.354501 -6.871855) (xy 210.302825 -6.940284) (xy 210.245056 -7.003654)
			(xy 210.181686 -7.061423) (xy 210.113257 -7.113099) (xy 210.040351 -7.15824) (xy 209.963591 -7.196462)
			(xy 209.883632 -7.227438) (xy 209.801156 -7.250905) (xy 209.716866 -7.266661) (xy 209.631483 -7.274573)
			(xy 209.545733 -7.274573) (xy 209.46035 -7.266661) (xy 209.37606 -7.250905) (xy 209.293584 -7.227438)
			(xy 209.213625 -7.196462) (xy 209.136865 -7.15824) (xy 209.063959 -7.113099) (xy 208.99553 -7.061423)
			(xy 208.93216 -7.003654) (xy 208.874391 -6.940284) (xy 208.822715 -6.871855) (xy 208.777574 -6.798949)
			(xy 208.739352 -6.722189) (xy 208.708376 -6.64223) (xy 208.684909 -6.559754) (xy 208.669153 -6.475464)
			(xy 208.661241 -6.390081) (xy 197.210934 -6.390081) (xy 197.210934 -7.78002) (xy 197.211456 -7.835788)
			(xy 197.219793 -7.947013) (xy 197.236418 -8.057304) (xy 197.261239 -8.166044) (xy 197.294116 -8.272625)
			(xy 197.334866 -8.376451) (xy 197.383261 -8.476941) (xy 197.439031 -8.573534) (xy 197.501863 -8.66569)
			(xy 197.571406 -8.752892) (xy 197.647271 -8.834653) (xy 197.729034 -8.910516) (xy 197.816238 -8.980057)
			(xy 197.908394 -9.042887) (xy 198.004989 -9.098654) (xy 198.10548 -9.147047) (xy 198.209307 -9.187795)
			(xy 198.315889 -9.22067) (xy 198.42463 -9.245488) (xy 198.534921 -9.262111) (xy 198.646146 -9.270445)
			(xy 198.701914 -9.271) (xy 223.300036 -9.271) (xy 223.370417 -9.271495) (xy 223.510959 -9.279389)
			(xy 223.650836 -9.295152) (xy 223.78961 -9.318732) (xy 223.926844 -9.350057) (xy 224.062105 -9.389027)
			(xy 224.194968 -9.435519) (xy 224.325015 -9.489388) (xy 224.451838 -9.550465) (xy 224.575036 -9.618556)
			(xy 224.694222 -9.693447) (xy 224.809022 -9.774904) (xy 224.919074 -9.862669) (xy 225.024032 -9.956467)
			(xy 225.123566 -10.056003) (xy 225.217361 -10.160962) (xy 225.305125 -10.271016) (xy 225.386579 -10.385818)
			(xy 225.461469 -10.505006) (xy 225.529557 -10.628205) (xy 225.590631 -10.755029) (xy 225.644498 -10.885077)
			(xy 225.690988 -11.017941) (xy 225.729955 -11.153203) (xy 225.761277 -11.290437) (xy 225.784855 -11.429211)
			(xy 225.800615 -11.569089) (xy 225.808507 -11.709631) (xy 225.809048 -11.780012) (xy 225.809048 -33.120076)
			(xy 225.809549 -33.152224) (xy 225.817939 -33.21597) (xy 225.834578 -33.278076) (xy 225.859182 -33.337478)
			(xy 225.891329 -33.39316) (xy 225.93047 -33.44417) (xy 225.975934 -33.489634) (xy 226.026945 -33.528774)
			(xy 226.082627 -33.560921) (xy 226.14203 -33.585524) (xy 226.204136 -33.602162) (xy 226.267882 -33.610551)
			(xy 226.30003 -33.611058)
		)
		(stroke
			(width 0)
			(type solid)
		)
		(fill yes)
		(layer "In8.Cu")
		(net "DELTA_L_GND_1")
	)
	(gr_poly
		(pts
			(xy 302.049942 -421.84701) (xy 302.065455 -421.826072) (xy 302.101599 -421.788535) (xy 302.142827 -421.756665)
			(xy 302.188259 -421.731143) (xy 302.236924 -421.712513) (xy 302.287786 -421.701174) (xy 302.339756 -421.697367)
			(xy 302.391726 -421.701174) (xy 302.442588 -421.712513) (xy 302.491253 -421.731143) (xy 302.536685 -421.756665)
			(xy 302.577913 -421.788535) (xy 302.614057 -421.826072) (xy 302.62957 -421.84701) (xy 302.670972 -421.868346)
			(xy 365.260636 -421.868346) (xy 365.269866 -421.86794) (xy 365.287122 -421.861378) (xy 365.300927 -421.849122)
			(xy 365.309487 -421.832766) (xy 365.310928 -421.823642) (xy 365.310928 -415.898584) (xy 365.311359 -415.888368)
			(xy 365.319187 -415.869493) (xy 365.333644 -415.855053) (xy 365.352527 -415.847247) (xy 365.362744 -415.846768)
			(xy 370.261388 -415.846768) (xy 370.271599 -415.847264) (xy 370.290467 -415.855074) (xy 370.304911 -415.86951)
			(xy 370.312731 -415.888374) (xy 370.313204 -415.898584) (xy 370.313204 -418.439456) (xy 372.044623 -418.439456)
			(xy 372.044623 -418.384944) (xy 372.052381 -418.330986) (xy 372.06774 -418.278682) (xy 372.090386 -418.229097)
			(xy 372.119858 -418.183238) (xy 372.155557 -418.142042) (xy 372.196756 -418.106345) (xy 372.242616 -418.076875)
			(xy 372.292203 -418.054232) (xy 372.344508 -418.038877) (xy 372.398466 -418.031121) (xy 372.425722 -418.03066)
			(xy 373.289322 -418.03066) (xy 373.31657 -418.031212) (xy 373.370511 -418.03897) (xy 373.422798 -418.054326)
			(xy 373.472369 -418.076966) (xy 373.518212 -418.106431) (xy 373.559396 -418.142119) (xy 373.595083 -418.183305)
			(xy 373.624544 -418.229151) (xy 373.647182 -418.278722) (xy 373.662535 -418.331011) (xy 373.67029 -418.384952)
			(xy 373.67029 -418.439448) (xy 373.670289 -418.439452) (xy 375.107946 -418.439452) (xy 375.107946 -418.384948)
			(xy 375.115702 -418.330999) (xy 375.131056 -418.278703) (xy 375.153697 -418.229124) (xy 375.183162 -418.183272)
			(xy 375.218852 -418.142079) (xy 375.260041 -418.106385) (xy 375.305891 -418.076915) (xy 375.355468 -418.05427)
			(xy 375.407762 -418.03891) (xy 375.46171 -418.031148) (xy 375.488962 -418.03066) (xy 376.352562 -418.03066)
			(xy 376.379814 -418.031185) (xy 376.433765 -418.038937) (xy 376.486063 -418.054288) (xy 376.535644 -418.076926)
			(xy 376.581498 -418.106391) (xy 376.622691 -418.142082) (xy 376.658386 -418.183272) (xy 376.687855 -418.229123)
			(xy 376.710499 -418.278701) (xy 376.725855 -418.330998) (xy 376.733613 -418.384948) (xy 376.733613 -418.439452)
			(xy 376.733613 -418.439455) (xy 378.171123 -418.439455) (xy 378.171123 -418.384945) (xy 378.178881 -418.330989)
			(xy 378.194238 -418.278687) (xy 378.216883 -418.229102) (xy 378.246353 -418.183245) (xy 378.28205 -418.142049)
			(xy 378.323247 -418.106352) (xy 378.369104 -418.076882) (xy 378.418688 -418.054237) (xy 378.470991 -418.03888)
			(xy 378.524947 -418.031123) (xy 378.552202 -418.03066) (xy 379.415802 -418.03066) (xy 379.443051 -418.03121)
			(xy 379.496994 -418.038966) (xy 379.549284 -418.05432) (xy 379.598857 -418.07696) (xy 379.644703 -418.106424)
			(xy 379.685889 -418.142112) (xy 379.721578 -418.183299) (xy 379.751041 -418.229145) (xy 379.77368 -418.278718)
			(xy 379.789034 -418.331008) (xy 379.79679 -418.384951) (xy 379.79679 -418.439449) (xy 379.796789 -418.439457)
			(xy 381.234323 -418.439457) (xy 381.234323 -418.384943) (xy 381.242082 -418.330984) (xy 381.257441 -418.278678)
			(xy 381.280089 -418.229091) (xy 381.309563 -418.183232) (xy 381.345264 -418.142035) (xy 381.386466 -418.106338)
			(xy 381.432328 -418.076869) (xy 381.481917 -418.054227) (xy 381.534225 -418.038873) (xy 381.588185 -418.03112)
			(xy 381.615442 -418.03066) (xy 382.479042 -418.03066) (xy 382.506289 -418.031213) (xy 382.560228 -418.038974)
			(xy 382.612513 -418.054331) (xy 382.662081 -418.076973) (xy 382.707922 -418.106438) (xy 382.749103 -418.142126)
			(xy 382.784787 -418.183312) (xy 382.814247 -418.229156) (xy 382.836883 -418.278727) (xy 382.852235 -418.331014)
			(xy 382.85999 -418.384953) (xy 382.85999 -418.439447) (xy 382.859989 -418.439453) (xy 384.297646 -418.439453)
			(xy 384.297646 -418.384947) (xy 384.305403 -418.330997) (xy 384.320758 -418.278699) (xy 384.3434 -418.229119)
			(xy 384.372867 -418.183265) (xy 384.408559 -418.142072) (xy 384.449751 -418.106378) (xy 384.495603 -418.076908)
			(xy 384.545182 -418.054264) (xy 384.597479 -418.038906) (xy 384.651429 -418.031147) (xy 384.678682 -418.03066)
			(xy 385.542282 -418.03066) (xy 385.569533 -418.031186) (xy 385.623482 -418.03894) (xy 385.675777 -418.054293)
			(xy 385.725356 -418.076933) (xy 385.771207 -418.106398) (xy 385.812399 -418.142089) (xy 385.848091 -418.183278)
			(xy 385.877558 -418.229129) (xy 385.9002 -418.278706) (xy 385.915556 -418.331001) (xy 385.923313 -418.384949)
			(xy 385.923313 -418.439451) (xy 385.923312 -418.439456) (xy 387.360823 -418.439456) (xy 387.360823 -418.384944)
			(xy 387.368581 -418.330986) (xy 387.38394 -418.278682) (xy 387.406586 -418.229097) (xy 387.436058 -418.183238)
			(xy 387.471757 -418.142042) (xy 387.512956 -418.106345) (xy 387.558816 -418.076875) (xy 387.608403 -418.054232)
			(xy 387.660708 -418.038877) (xy 387.714666 -418.031121) (xy 387.741922 -418.03066) (xy 388.605522 -418.03066)
			(xy 388.63277 -418.031212) (xy 388.686711 -418.03897) (xy 388.738998 -418.054326) (xy 388.788569 -418.076966)
			(xy 388.834412 -418.106431) (xy 388.875596 -418.142119) (xy 388.911283 -418.183305) (xy 388.940744 -418.229151)
			(xy 388.963382 -418.278722) (xy 388.978735 -418.331011) (xy 388.98649 -418.384952) (xy 388.98649 -418.439448)
			(xy 388.986489 -418.439452) (xy 390.424146 -418.439452) (xy 390.424146 -418.384948) (xy 390.431902 -418.330999)
			(xy 390.447256 -418.278703) (xy 390.469897 -418.229124) (xy 390.499362 -418.183272) (xy 390.535052 -418.142079)
			(xy 390.576241 -418.106385) (xy 390.622091 -418.076915) (xy 390.671668 -418.05427) (xy 390.723962 -418.03891)
			(xy 390.77791 -418.031148) (xy 390.805162 -418.03066) (xy 391.668762 -418.03066) (xy 391.696014 -418.031185)
			(xy 391.749965 -418.038937) (xy 391.802263 -418.054288) (xy 391.851844 -418.076926) (xy 391.897698 -418.106391)
			(xy 391.938891 -418.142082) (xy 391.974586 -418.183272) (xy 392.004055 -418.229123) (xy 392.026699 -418.278701)
			(xy 392.042055 -418.330998) (xy 392.049813 -418.384948) (xy 392.049813 -418.439452) (xy 392.049813 -418.439455)
			(xy 393.487323 -418.439455) (xy 393.487323 -418.384945) (xy 393.495081 -418.330989) (xy 393.510438 -418.278687)
			(xy 393.533083 -418.229102) (xy 393.562553 -418.183245) (xy 393.59825 -418.142049) (xy 393.639447 -418.106352)
			(xy 393.685304 -418.076882) (xy 393.734888 -418.054237) (xy 393.787191 -418.03888) (xy 393.841147 -418.031123)
			(xy 393.868402 -418.03066) (xy 394.732002 -418.03066) (xy 394.759251 -418.03121) (xy 394.813194 -418.038966)
			(xy 394.865484 -418.05432) (xy 394.915057 -418.07696) (xy 394.960903 -418.106424) (xy 395.002089 -418.142112)
			(xy 395.037778 -418.183299) (xy 395.067241 -418.229145) (xy 395.08988 -418.278718) (xy 395.105234 -418.331008)
			(xy 395.11299 -418.384951) (xy 395.11299 -418.439449) (xy 395.112989 -418.439457) (xy 396.550523 -418.439457)
			(xy 396.550523 -418.384943) (xy 396.558282 -418.330984) (xy 396.573641 -418.278678) (xy 396.596289 -418.229091)
			(xy 396.625763 -418.183232) (xy 396.661464 -418.142035) (xy 396.702666 -418.106338) (xy 396.748528 -418.076869)
			(xy 396.798117 -418.054227) (xy 396.850425 -418.038873) (xy 396.904385 -418.03112) (xy 396.931642 -418.03066)
			(xy 397.795242 -418.03066) (xy 397.822489 -418.031213) (xy 397.876428 -418.038974) (xy 397.928713 -418.054331)
			(xy 397.978281 -418.076973) (xy 398.024122 -418.106438) (xy 398.065303 -418.142126) (xy 398.100987 -418.183312)
			(xy 398.130447 -418.229156) (xy 398.153083 -418.278727) (xy 398.168435 -418.331014) (xy 398.17619 -418.384953)
			(xy 398.17619 -418.439447) (xy 398.176189 -418.439453) (xy 399.613846 -418.439453) (xy 399.613846 -418.384947)
			(xy 399.621603 -418.330997) (xy 399.636958 -418.278699) (xy 399.6596 -418.229119) (xy 399.689067 -418.183265)
			(xy 399.724759 -418.142072) (xy 399.765951 -418.106378) (xy 399.811803 -418.076908) (xy 399.861382 -418.054264)
			(xy 399.913679 -418.038906) (xy 399.967629 -418.031147) (xy 399.994882 -418.03066) (xy 400.858482 -418.03066)
			(xy 400.885733 -418.031186) (xy 400.939682 -418.03894) (xy 400.991977 -418.054293) (xy 401.041556 -418.076933)
			(xy 401.087407 -418.106398) (xy 401.128599 -418.142089) (xy 401.164291 -418.183278) (xy 401.193758 -418.229129)
			(xy 401.2164 -418.278706) (xy 401.231756 -418.331001) (xy 401.239513 -418.384949) (xy 401.239513 -418.439451)
			(xy 401.239512 -418.439456) (xy 402.677023 -418.439456) (xy 402.677023 -418.384944) (xy 402.684781 -418.330986)
			(xy 402.70014 -418.278682) (xy 402.722786 -418.229097) (xy 402.752258 -418.183238) (xy 402.787957 -418.142042)
			(xy 402.829156 -418.106345) (xy 402.875016 -418.076875) (xy 402.924603 -418.054232) (xy 402.976908 -418.038877)
			(xy 403.030866 -418.031121) (xy 403.058122 -418.03066) (xy 403.921722 -418.03066) (xy 403.94897 -418.031212)
			(xy 404.002911 -418.03897) (xy 404.055198 -418.054326) (xy 404.104769 -418.076966) (xy 404.150612 -418.106431)
			(xy 404.191796 -418.142119) (xy 404.227483 -418.183305) (xy 404.256944 -418.229151) (xy 404.279582 -418.278722)
			(xy 404.294935 -418.331011) (xy 404.30269 -418.384952) (xy 404.30269 -418.439448) (xy 404.302689 -418.439452)
			(xy 405.740346 -418.439452) (xy 405.740346 -418.384948) (xy 405.748102 -418.330999) (xy 405.763456 -418.278703)
			(xy 405.786097 -418.229124) (xy 405.815562 -418.183272) (xy 405.851252 -418.142079) (xy 405.892441 -418.106385)
			(xy 405.938291 -418.076915) (xy 405.987868 -418.05427) (xy 406.040162 -418.03891) (xy 406.09411 -418.031148)
			(xy 406.121362 -418.03066) (xy 406.984962 -418.03066) (xy 407.012214 -418.031185) (xy 407.066165 -418.038937)
			(xy 407.118463 -418.054288) (xy 407.168044 -418.076926) (xy 407.213898 -418.106391) (xy 407.255091 -418.142082)
			(xy 407.290786 -418.183272) (xy 407.320255 -418.229123) (xy 407.342899 -418.278701) (xy 407.358255 -418.330998)
			(xy 407.366013 -418.384948) (xy 407.366013 -418.439452) (xy 407.366013 -418.439455) (xy 408.803523 -418.439455)
			(xy 408.803523 -418.384945) (xy 408.811281 -418.330989) (xy 408.826638 -418.278687) (xy 408.849283 -418.229102)
			(xy 408.878753 -418.183245) (xy 408.91445 -418.142049) (xy 408.955647 -418.106352) (xy 409.001504 -418.076882)
			(xy 409.051088 -418.054237) (xy 409.103391 -418.03888) (xy 409.157347 -418.031123) (xy 409.184602 -418.03066)
			(xy 410.048202 -418.03066) (xy 410.075451 -418.03121) (xy 410.129394 -418.038966) (xy 410.181684 -418.05432)
			(xy 410.231257 -418.07696) (xy 410.277103 -418.106424) (xy 410.318289 -418.142112) (xy 410.353978 -418.183299)
			(xy 410.383441 -418.229145) (xy 410.40608 -418.278718) (xy 410.421434 -418.331008) (xy 410.42919 -418.384951)
			(xy 410.42919 -418.439449) (xy 410.429189 -418.439457) (xy 411.866723 -418.439457) (xy 411.866723 -418.384943)
			(xy 411.874482 -418.330984) (xy 411.889841 -418.278678) (xy 411.912489 -418.229091) (xy 411.941963 -418.183232)
			(xy 411.977664 -418.142035) (xy 412.018866 -418.106338) (xy 412.064728 -418.076869) (xy 412.114317 -418.054227)
			(xy 412.166625 -418.038873) (xy 412.220585 -418.03112) (xy 412.247842 -418.03066) (xy 413.111442 -418.03066)
			(xy 413.138689 -418.031213) (xy 413.192628 -418.038974) (xy 413.244913 -418.054331) (xy 413.294481 -418.076973)
			(xy 413.340322 -418.106438) (xy 413.381503 -418.142126) (xy 413.417187 -418.183312) (xy 413.446647 -418.229156)
			(xy 413.469283 -418.278727) (xy 413.484635 -418.331014) (xy 413.49239 -418.384953) (xy 413.49239 -418.439447)
			(xy 413.492389 -418.439453) (xy 414.930046 -418.439453) (xy 414.930046 -418.384947) (xy 414.937803 -418.330997)
			(xy 414.953158 -418.278699) (xy 414.9758 -418.229119) (xy 415.005267 -418.183265) (xy 415.040959 -418.142072)
			(xy 415.082151 -418.106378) (xy 415.128003 -418.076908) (xy 415.177582 -418.054264) (xy 415.229879 -418.038906)
			(xy 415.283829 -418.031147) (xy 415.311082 -418.03066) (xy 416.174682 -418.03066) (xy 416.201933 -418.031186)
			(xy 416.255882 -418.03894) (xy 416.308177 -418.054293) (xy 416.357756 -418.076933) (xy 416.403607 -418.106398)
			(xy 416.444799 -418.142089) (xy 416.480491 -418.183278) (xy 416.509958 -418.229129) (xy 416.5326 -418.278706)
			(xy 416.547956 -418.331001) (xy 416.555713 -418.384949) (xy 416.555713 -418.439451) (xy 416.555712 -418.439456)
			(xy 417.993223 -418.439456) (xy 417.993223 -418.384944) (xy 418.000981 -418.330986) (xy 418.01634 -418.278682)
			(xy 418.038986 -418.229097) (xy 418.068458 -418.183238) (xy 418.104157 -418.142042) (xy 418.145356 -418.106345)
			(xy 418.191216 -418.076875) (xy 418.240803 -418.054232) (xy 418.293108 -418.038877) (xy 418.347066 -418.031121)
			(xy 418.374322 -418.03066) (xy 419.237922 -418.03066) (xy 419.26517 -418.031212) (xy 419.319111 -418.03897)
			(xy 419.371398 -418.054326) (xy 419.420969 -418.076966) (xy 419.466812 -418.106431) (xy 419.507996 -418.142119)
			(xy 419.543683 -418.183305) (xy 419.573144 -418.229151) (xy 419.595782 -418.278722) (xy 419.611135 -418.331011)
			(xy 419.61889 -418.384952) (xy 419.61889 -418.439448) (xy 419.611135 -418.493389) (xy 419.595782 -418.545678)
			(xy 419.573144 -418.595249) (xy 419.543683 -418.641095) (xy 419.507996 -418.682281) (xy 419.466812 -418.717969)
			(xy 419.420969 -418.747434) (xy 419.371398 -418.770074) (xy 419.319111 -418.78543) (xy 419.26517 -418.793188)
			(xy 419.237922 -418.793676) (xy 418.374322 -418.793676) (xy 418.347066 -418.793279) (xy 418.293108 -418.785523)
			(xy 418.240803 -418.770168) (xy 418.191216 -418.747525) (xy 418.145356 -418.718055) (xy 418.104157 -418.682358)
			(xy 418.068458 -418.641162) (xy 418.038986 -418.595303) (xy 418.01634 -418.545718) (xy 418.000981 -418.493414)
			(xy 417.993223 -418.439456) (xy 416.555712 -418.439456) (xy 416.547956 -418.493399) (xy 416.5326 -418.545694)
			(xy 416.509958 -418.595271) (xy 416.480491 -418.641122) (xy 416.444799 -418.682311) (xy 416.403607 -418.718002)
			(xy 416.357756 -418.747467) (xy 416.308177 -418.770107) (xy 416.255882 -418.78546) (xy 416.201933 -418.793214)
			(xy 416.174682 -418.793676) (xy 415.311082 -418.793676) (xy 415.283829 -418.793253) (xy 415.229879 -418.785494)
			(xy 415.177582 -418.770136) (xy 415.128003 -418.747492) (xy 415.082151 -418.718022) (xy 415.040959 -418.682328)
			(xy 415.005267 -418.641135) (xy 414.9758 -418.595281) (xy 414.953158 -418.545701) (xy 414.937803 -418.493403)
			(xy 414.930046 -418.439453) (xy 413.492389 -418.439453) (xy 413.484635 -418.493386) (xy 413.469283 -418.545673)
			(xy 413.446647 -418.595244) (xy 413.417187 -418.641088) (xy 413.381503 -418.682274) (xy 413.340322 -418.717962)
			(xy 413.294481 -418.747427) (xy 413.244913 -418.770069) (xy 413.192628 -418.785426) (xy 413.138689 -418.793187)
			(xy 413.111442 -418.793676) (xy 412.247842 -418.793676) (xy 412.220585 -418.79328) (xy 412.166625 -418.785527)
			(xy 412.114317 -418.770173) (xy 412.064728 -418.747531) (xy 412.018866 -418.718062) (xy 411.977664 -418.682365)
			(xy 411.941963 -418.641168) (xy 411.912489 -418.595309) (xy 411.889841 -418.545722) (xy 411.874482 -418.493416)
			(xy 411.866723 -418.439457) (xy 410.429189 -418.439457) (xy 410.421434 -418.493392) (xy 410.40608 -418.545682)
			(xy 410.383441 -418.595255) (xy 410.353978 -418.641101) (xy 410.318289 -418.682288) (xy 410.277103 -418.717976)
			(xy 410.231257 -418.74744) (xy 410.181684 -418.77008) (xy 410.129394 -418.785434) (xy 410.075451 -418.79319)
			(xy 410.048202 -418.793676) (xy 409.184602 -418.793676) (xy 409.157347 -418.793277) (xy 409.103391 -418.78552)
			(xy 409.051088 -418.770163) (xy 409.001504 -418.747518) (xy 408.955647 -418.718048) (xy 408.91445 -418.682351)
			(xy 408.878753 -418.641155) (xy 408.849283 -418.595298) (xy 408.826638 -418.545713) (xy 408.811281 -418.493411)
			(xy 408.803523 -418.439455) (xy 407.366013 -418.439455) (xy 407.358255 -418.493402) (xy 407.342899 -418.545699)
			(xy 407.320255 -418.595277) (xy 407.290786 -418.641128) (xy 407.255091 -418.682318) (xy 407.213898 -418.718009)
			(xy 407.168044 -418.747474) (xy 407.118463 -418.770112) (xy 407.066165 -418.785463) (xy 407.012214 -418.793215)
			(xy 406.984962 -418.793676) (xy 406.121362 -418.793676) (xy 406.09411 -418.793252) (xy 406.040162 -418.78549)
			(xy 405.987868 -418.77013) (xy 405.938291 -418.747485) (xy 405.892441 -418.718015) (xy 405.851252 -418.682321)
			(xy 405.815562 -418.641128) (xy 405.786097 -418.595276) (xy 405.763456 -418.545697) (xy 405.748102 -418.493401)
			(xy 405.740346 -418.439452) (xy 404.302689 -418.439452) (xy 404.294935 -418.493389) (xy 404.279582 -418.545678)
			(xy 404.256944 -418.595249) (xy 404.227483 -418.641095) (xy 404.191796 -418.682281) (xy 404.150612 -418.717969)
			(xy 404.104769 -418.747434) (xy 404.055198 -418.770074) (xy 404.002911 -418.78543) (xy 403.94897 -418.793188)
			(xy 403.921722 -418.793676) (xy 403.058122 -418.793676) (xy 403.030866 -418.793279) (xy 402.976908 -418.785523)
			(xy 402.924603 -418.770168) (xy 402.875016 -418.747525) (xy 402.829156 -418.718055) (xy 402.787957 -418.682358)
			(xy 402.752258 -418.641162) (xy 402.722786 -418.595303) (xy 402.70014 -418.545718) (xy 402.684781 -418.493414)
			(xy 402.677023 -418.439456) (xy 401.239512 -418.439456) (xy 401.231756 -418.493399) (xy 401.2164 -418.545694)
			(xy 401.193758 -418.595271) (xy 401.164291 -418.641122) (xy 401.128599 -418.682311) (xy 401.087407 -418.718002)
			(xy 401.041556 -418.747467) (xy 400.991977 -418.770107) (xy 400.939682 -418.78546) (xy 400.885733 -418.793214)
			(xy 400.858482 -418.793676) (xy 399.994882 -418.793676) (xy 399.967629 -418.793253) (xy 399.913679 -418.785494)
			(xy 399.861382 -418.770136) (xy 399.811803 -418.747492) (xy 399.765951 -418.718022) (xy 399.724759 -418.682328)
			(xy 399.689067 -418.641135) (xy 399.6596 -418.595281) (xy 399.636958 -418.545701) (xy 399.621603 -418.493403)
			(xy 399.613846 -418.439453) (xy 398.176189 -418.439453) (xy 398.168435 -418.493386) (xy 398.153083 -418.545673)
			(xy 398.130447 -418.595244) (xy 398.100987 -418.641088) (xy 398.065303 -418.682274) (xy 398.024122 -418.717962)
			(xy 397.978281 -418.747427) (xy 397.928713 -418.770069) (xy 397.876428 -418.785426) (xy 397.822489 -418.793187)
			(xy 397.795242 -418.793676) (xy 396.931642 -418.793676) (xy 396.904385 -418.79328) (xy 396.850425 -418.785527)
			(xy 396.798117 -418.770173) (xy 396.748528 -418.747531) (xy 396.702666 -418.718062) (xy 396.661464 -418.682365)
			(xy 396.625763 -418.641168) (xy 396.596289 -418.595309) (xy 396.573641 -418.545722) (xy 396.558282 -418.493416)
			(xy 396.550523 -418.439457) (xy 395.112989 -418.439457) (xy 395.105234 -418.493392) (xy 395.08988 -418.545682)
			(xy 395.067241 -418.595255) (xy 395.037778 -418.641101) (xy 395.002089 -418.682288) (xy 394.960903 -418.717976)
			(xy 394.915057 -418.74744) (xy 394.865484 -418.77008) (xy 394.813194 -418.785434) (xy 394.759251 -418.79319)
			(xy 394.732002 -418.793676) (xy 393.868402 -418.793676) (xy 393.841147 -418.793277) (xy 393.787191 -418.78552)
			(xy 393.734888 -418.770163) (xy 393.685304 -418.747518) (xy 393.639447 -418.718048) (xy 393.59825 -418.682351)
			(xy 393.562553 -418.641155) (xy 393.533083 -418.595298) (xy 393.510438 -418.545713) (xy 393.495081 -418.493411)
			(xy 393.487323 -418.439455) (xy 392.049813 -418.439455) (xy 392.042055 -418.493402) (xy 392.026699 -418.545699)
			(xy 392.004055 -418.595277) (xy 391.974586 -418.641128) (xy 391.938891 -418.682318) (xy 391.897698 -418.718009)
			(xy 391.851844 -418.747474) (xy 391.802263 -418.770112) (xy 391.749965 -418.785463) (xy 391.696014 -418.793215)
			(xy 391.668762 -418.793676) (xy 390.805162 -418.793676) (xy 390.77791 -418.793252) (xy 390.723962 -418.78549)
			(xy 390.671668 -418.77013) (xy 390.622091 -418.747485) (xy 390.576241 -418.718015) (xy 390.535052 -418.682321)
			(xy 390.499362 -418.641128) (xy 390.469897 -418.595276) (xy 390.447256 -418.545697) (xy 390.431902 -418.493401)
			(xy 390.424146 -418.439452) (xy 388.986489 -418.439452) (xy 388.978735 -418.493389) (xy 388.963382 -418.545678)
			(xy 388.940744 -418.595249) (xy 388.911283 -418.641095) (xy 388.875596 -418.682281) (xy 388.834412 -418.717969)
			(xy 388.788569 -418.747434) (xy 388.738998 -418.770074) (xy 388.686711 -418.78543) (xy 388.63277 -418.793188)
			(xy 388.605522 -418.793676) (xy 387.741922 -418.793676) (xy 387.714666 -418.793279) (xy 387.660708 -418.785523)
			(xy 387.608403 -418.770168) (xy 387.558816 -418.747525) (xy 387.512956 -418.718055) (xy 387.471757 -418.682358)
			(xy 387.436058 -418.641162) (xy 387.406586 -418.595303) (xy 387.38394 -418.545718) (xy 387.368581 -418.493414)
			(xy 387.360823 -418.439456) (xy 385.923312 -418.439456) (xy 385.915556 -418.493399) (xy 385.9002 -418.545694)
			(xy 385.877558 -418.595271) (xy 385.848091 -418.641122) (xy 385.812399 -418.682311) (xy 385.771207 -418.718002)
			(xy 385.725356 -418.747467) (xy 385.675777 -418.770107) (xy 385.623482 -418.78546) (xy 385.569533 -418.793214)
			(xy 385.542282 -418.793676) (xy 384.678682 -418.793676) (xy 384.651429 -418.793253) (xy 384.597479 -418.785494)
			(xy 384.545182 -418.770136) (xy 384.495603 -418.747492) (xy 384.449751 -418.718022) (xy 384.408559 -418.682328)
			(xy 384.372867 -418.641135) (xy 384.3434 -418.595281) (xy 384.320758 -418.545701) (xy 384.305403 -418.493403)
			(xy 384.297646 -418.439453) (xy 382.859989 -418.439453) (xy 382.852235 -418.493386) (xy 382.836883 -418.545673)
			(xy 382.814247 -418.595244) (xy 382.784787 -418.641088) (xy 382.749103 -418.682274) (xy 382.707922 -418.717962)
			(xy 382.662081 -418.747427) (xy 382.612513 -418.770069) (xy 382.560228 -418.785426) (xy 382.506289 -418.793187)
			(xy 382.479042 -418.793676) (xy 381.615442 -418.793676) (xy 381.588185 -418.79328) (xy 381.534225 -418.785527)
			(xy 381.481917 -418.770173) (xy 381.432328 -418.747531) (xy 381.386466 -418.718062) (xy 381.345264 -418.682365)
			(xy 381.309563 -418.641168) (xy 381.280089 -418.595309) (xy 381.257441 -418.545722) (xy 381.242082 -418.493416)
			(xy 381.234323 -418.439457) (xy 379.796789 -418.439457) (xy 379.789034 -418.493392) (xy 379.77368 -418.545682)
			(xy 379.751041 -418.595255) (xy 379.721578 -418.641101) (xy 379.685889 -418.682288) (xy 379.644703 -418.717976)
			(xy 379.598857 -418.74744) (xy 379.549284 -418.77008) (xy 379.496994 -418.785434) (xy 379.443051 -418.79319)
			(xy 379.415802 -418.793676) (xy 378.552202 -418.793676) (xy 378.524947 -418.793277) (xy 378.470991 -418.78552)
			(xy 378.418688 -418.770163) (xy 378.369104 -418.747518) (xy 378.323247 -418.718048) (xy 378.28205 -418.682351)
			(xy 378.246353 -418.641155) (xy 378.216883 -418.595298) (xy 378.194238 -418.545713) (xy 378.178881 -418.493411)
			(xy 378.171123 -418.439455) (xy 376.733613 -418.439455) (xy 376.725855 -418.493402) (xy 376.710499 -418.545699)
			(xy 376.687855 -418.595277) (xy 376.658386 -418.641128) (xy 376.622691 -418.682318) (xy 376.581498 -418.718009)
			(xy 376.535644 -418.747474) (xy 376.486063 -418.770112) (xy 376.433765 -418.785463) (xy 376.379814 -418.793215)
			(xy 376.352562 -418.793676) (xy 375.488962 -418.793676) (xy 375.46171 -418.793252) (xy 375.407762 -418.78549)
			(xy 375.355468 -418.77013) (xy 375.305891 -418.747485) (xy 375.260041 -418.718015) (xy 375.218852 -418.682321)
			(xy 375.183162 -418.641128) (xy 375.153697 -418.595276) (xy 375.131056 -418.545697) (xy 375.115702 -418.493401)
			(xy 375.107946 -418.439452) (xy 373.670289 -418.439452) (xy 373.662535 -418.493389) (xy 373.647182 -418.545678)
			(xy 373.624544 -418.595249) (xy 373.595083 -418.641095) (xy 373.559396 -418.682281) (xy 373.518212 -418.717969)
			(xy 373.472369 -418.747434) (xy 373.422798 -418.770074) (xy 373.370511 -418.78543) (xy 373.31657 -418.793188)
			(xy 373.289322 -418.793676) (xy 372.425722 -418.793676) (xy 372.398466 -418.793279) (xy 372.344508 -418.785523)
			(xy 372.292203 -418.770168) (xy 372.242616 -418.747525) (xy 372.196756 -418.718055) (xy 372.155557 -418.682358)
			(xy 372.119858 -418.641162) (xy 372.090386 -418.595303) (xy 372.06774 -418.545718) (xy 372.052381 -418.493414)
			(xy 372.044623 -418.439456) (xy 370.313204 -418.439456) (xy 370.313204 -420.739316) (xy 370.16182 -420.739316)
			(xy 370.150196 -420.741249) (xy 370.130459 -420.754067) (xy 370.118529 -420.774354) (xy 370.117116 -420.786052)
			(xy 370.117116 -420.979455) (xy 370.513023 -420.979455) (xy 370.513023 -420.924945) (xy 370.520781 -420.870989)
			(xy 370.536138 -420.818687) (xy 370.558783 -420.769102) (xy 370.588253 -420.723245) (xy 370.62395 -420.682049)
			(xy 370.665147 -420.646352) (xy 370.711004 -420.616882) (xy 370.760588 -420.594237) (xy 370.812891 -420.57888)
			(xy 370.866847 -420.571123) (xy 370.894102 -420.57066) (xy 371.757702 -420.57066) (xy 371.784951 -420.57121)
			(xy 371.838894 -420.578966) (xy 371.891184 -420.59432) (xy 371.940757 -420.61696) (xy 371.986603 -420.646424)
			(xy 372.027789 -420.682112) (xy 372.063478 -420.723299) (xy 372.092941 -420.769145) (xy 372.11558 -420.818718)
			(xy 372.130934 -420.871008) (xy 372.13869 -420.924951) (xy 372.13869 -420.979449) (xy 372.138689 -420.979457)
			(xy 373.576223 -420.979457) (xy 373.576223 -420.924943) (xy 373.583982 -420.870984) (xy 373.599341 -420.818678)
			(xy 373.621989 -420.769091) (xy 373.651463 -420.723232) (xy 373.687164 -420.682035) (xy 373.728366 -420.646338)
			(xy 373.774228 -420.616869) (xy 373.823817 -420.594227) (xy 373.876125 -420.578873) (xy 373.930085 -420.57112)
			(xy 373.957342 -420.57066) (xy 374.820942 -420.57066) (xy 374.848189 -420.571213) (xy 374.902128 -420.578974)
			(xy 374.954413 -420.594331) (xy 375.003981 -420.616973) (xy 375.049822 -420.646438) (xy 375.091003 -420.682126)
			(xy 375.126687 -420.723312) (xy 375.156147 -420.769156) (xy 375.178783 -420.818727) (xy 375.194135 -420.871014)
			(xy 375.20189 -420.924953) (xy 375.20189 -420.979447) (xy 375.201889 -420.979453) (xy 376.639546 -420.979453)
			(xy 376.639546 -420.924947) (xy 376.647303 -420.870997) (xy 376.662658 -420.818699) (xy 376.6853 -420.769119)
			(xy 376.714767 -420.723265) (xy 376.750459 -420.682072) (xy 376.791651 -420.646378) (xy 376.837503 -420.616908)
			(xy 376.887082 -420.594264) (xy 376.939379 -420.578906) (xy 376.993329 -420.571147) (xy 377.020582 -420.57066)
			(xy 377.884182 -420.57066) (xy 377.911433 -420.571186) (xy 377.965382 -420.57894) (xy 378.017677 -420.594293)
			(xy 378.067256 -420.616933) (xy 378.113107 -420.646398) (xy 378.154299 -420.682089) (xy 378.189991 -420.723278)
			(xy 378.219458 -420.769129) (xy 378.2421 -420.818706) (xy 378.257456 -420.871001) (xy 378.265213 -420.924949)
			(xy 378.265213 -420.979451) (xy 378.265212 -420.979456) (xy 379.702723 -420.979456) (xy 379.702723 -420.924944)
			(xy 379.710481 -420.870986) (xy 379.72584 -420.818682) (xy 379.748486 -420.769097) (xy 379.777958 -420.723238)
			(xy 379.813657 -420.682042) (xy 379.854856 -420.646345) (xy 379.900716 -420.616875) (xy 379.950303 -420.594232)
			(xy 380.002608 -420.578877) (xy 380.056566 -420.571121) (xy 380.083822 -420.57066) (xy 380.947422 -420.57066)
			(xy 380.97467 -420.571212) (xy 381.028611 -420.57897) (xy 381.080898 -420.594326) (xy 381.130469 -420.616966)
			(xy 381.176312 -420.646431) (xy 381.217496 -420.682119) (xy 381.253183 -420.723305) (xy 381.282644 -420.769151)
			(xy 381.305282 -420.818722) (xy 381.320635 -420.871011) (xy 381.32839 -420.924952) (xy 381.32839 -420.979448)
			(xy 381.328389 -420.979452) (xy 382.766046 -420.979452) (xy 382.766046 -420.924948) (xy 382.773802 -420.870999)
			(xy 382.789156 -420.818703) (xy 382.811797 -420.769124) (xy 382.841262 -420.723272) (xy 382.876952 -420.682079)
			(xy 382.918141 -420.646385) (xy 382.963991 -420.616915) (xy 383.013568 -420.59427) (xy 383.065862 -420.57891)
			(xy 383.11981 -420.571148) (xy 383.147062 -420.57066) (xy 384.010662 -420.57066) (xy 384.037914 -420.571185)
			(xy 384.091865 -420.578937) (xy 384.144163 -420.594288) (xy 384.193744 -420.616926) (xy 384.239598 -420.646391)
			(xy 384.280791 -420.682082) (xy 384.316486 -420.723272) (xy 384.345955 -420.769123) (xy 384.368599 -420.818701)
			(xy 384.383955 -420.870998) (xy 384.391713 -420.924948) (xy 384.391713 -420.979452) (xy 384.391713 -420.979455)
			(xy 385.829223 -420.979455) (xy 385.829223 -420.924945) (xy 385.836981 -420.870989) (xy 385.852338 -420.818687)
			(xy 385.874983 -420.769102) (xy 385.904453 -420.723245) (xy 385.94015 -420.682049) (xy 385.981347 -420.646352)
			(xy 386.027204 -420.616882) (xy 386.076788 -420.594237) (xy 386.129091 -420.57888) (xy 386.183047 -420.571123)
			(xy 386.210302 -420.57066) (xy 387.073902 -420.57066) (xy 387.101151 -420.57121) (xy 387.155094 -420.578966)
			(xy 387.207384 -420.59432) (xy 387.256957 -420.61696) (xy 387.302803 -420.646424) (xy 387.343989 -420.682112)
			(xy 387.379678 -420.723299) (xy 387.409141 -420.769145) (xy 387.43178 -420.818718) (xy 387.447134 -420.871008)
			(xy 387.45489 -420.924951) (xy 387.45489 -420.979449) (xy 387.454889 -420.979457) (xy 388.892423 -420.979457)
			(xy 388.892423 -420.924943) (xy 388.900182 -420.870984) (xy 388.915541 -420.818678) (xy 388.938189 -420.769091)
			(xy 388.967663 -420.723232) (xy 389.003364 -420.682035) (xy 389.044566 -420.646338) (xy 389.090428 -420.616869)
			(xy 389.140017 -420.594227) (xy 389.192325 -420.578873) (xy 389.246285 -420.57112) (xy 389.273542 -420.57066)
			(xy 390.137142 -420.57066) (xy 390.164389 -420.571213) (xy 390.218328 -420.578974) (xy 390.270613 -420.594331)
			(xy 390.320181 -420.616973) (xy 390.366022 -420.646438) (xy 390.407203 -420.682126) (xy 390.442887 -420.723312)
			(xy 390.472347 -420.769156) (xy 390.494983 -420.818727) (xy 390.510335 -420.871014) (xy 390.51809 -420.924953)
			(xy 390.51809 -420.979447) (xy 390.518089 -420.979453) (xy 391.955746 -420.979453) (xy 391.955746 -420.924947)
			(xy 391.963503 -420.870997) (xy 391.978858 -420.818699) (xy 392.0015 -420.769119) (xy 392.030967 -420.723265)
			(xy 392.066659 -420.682072) (xy 392.107851 -420.646378) (xy 392.153703 -420.616908) (xy 392.203282 -420.594264)
			(xy 392.255579 -420.578906) (xy 392.309529 -420.571147) (xy 392.336782 -420.57066) (xy 393.200382 -420.57066)
			(xy 393.227633 -420.571186) (xy 393.281582 -420.57894) (xy 393.333877 -420.594293) (xy 393.383456 -420.616933)
			(xy 393.429307 -420.646398) (xy 393.470499 -420.682089) (xy 393.506191 -420.723278) (xy 393.535658 -420.769129)
			(xy 393.5583 -420.818706) (xy 393.573656 -420.871001) (xy 393.581413 -420.924949) (xy 393.581413 -420.979451)
			(xy 393.581412 -420.979456) (xy 395.018923 -420.979456) (xy 395.018923 -420.924944) (xy 395.026681 -420.870986)
			(xy 395.04204 -420.818682) (xy 395.064686 -420.769097) (xy 395.094158 -420.723238) (xy 395.129857 -420.682042)
			(xy 395.171056 -420.646345) (xy 395.216916 -420.616875) (xy 395.266503 -420.594232) (xy 395.318808 -420.578877)
			(xy 395.372766 -420.571121) (xy 395.400022 -420.57066) (xy 396.263622 -420.57066) (xy 396.29087 -420.571212)
			(xy 396.344811 -420.57897) (xy 396.397098 -420.594326) (xy 396.446669 -420.616966) (xy 396.492512 -420.646431)
			(xy 396.533696 -420.682119) (xy 396.569383 -420.723305) (xy 396.598844 -420.769151) (xy 396.621482 -420.818722)
			(xy 396.636835 -420.871011) (xy 396.64459 -420.924952) (xy 396.64459 -420.979448) (xy 396.644589 -420.979452)
			(xy 398.082246 -420.979452) (xy 398.082246 -420.924948) (xy 398.090002 -420.870999) (xy 398.105356 -420.818703)
			(xy 398.127997 -420.769124) (xy 398.157462 -420.723272) (xy 398.193152 -420.682079) (xy 398.234341 -420.646385)
			(xy 398.280191 -420.616915) (xy 398.329768 -420.59427) (xy 398.382062 -420.57891) (xy 398.43601 -420.571148)
			(xy 398.463262 -420.57066) (xy 399.326862 -420.57066) (xy 399.354114 -420.571185) (xy 399.408065 -420.578937)
			(xy 399.460363 -420.594288) (xy 399.509944 -420.616926) (xy 399.555798 -420.646391) (xy 399.596991 -420.682082)
			(xy 399.632686 -420.723272) (xy 399.662155 -420.769123) (xy 399.684799 -420.818701) (xy 399.700155 -420.870998)
			(xy 399.707913 -420.924948) (xy 399.707913 -420.979452) (xy 399.707913 -420.979455) (xy 401.145423 -420.979455)
			(xy 401.145423 -420.924945) (xy 401.153181 -420.870989) (xy 401.168538 -420.818687) (xy 401.191183 -420.769102)
			(xy 401.220653 -420.723245) (xy 401.25635 -420.682049) (xy 401.297547 -420.646352) (xy 401.343404 -420.616882)
			(xy 401.392988 -420.594237) (xy 401.445291 -420.57888) (xy 401.499247 -420.571123) (xy 401.526502 -420.57066)
			(xy 402.390102 -420.57066) (xy 402.417351 -420.57121) (xy 402.471294 -420.578966) (xy 402.523584 -420.59432)
			(xy 402.573157 -420.61696) (xy 402.619003 -420.646424) (xy 402.660189 -420.682112) (xy 402.695878 -420.723299)
			(xy 402.725341 -420.769145) (xy 402.74798 -420.818718) (xy 402.763334 -420.871008) (xy 402.77109 -420.924951)
			(xy 402.77109 -420.979449) (xy 402.771089 -420.979457) (xy 404.208623 -420.979457) (xy 404.208623 -420.924943)
			(xy 404.216382 -420.870984) (xy 404.231741 -420.818678) (xy 404.254389 -420.769091) (xy 404.283863 -420.723232)
			(xy 404.319564 -420.682035) (xy 404.360766 -420.646338) (xy 404.406628 -420.616869) (xy 404.456217 -420.594227)
			(xy 404.508525 -420.578873) (xy 404.562485 -420.57112) (xy 404.589742 -420.57066) (xy 405.453342 -420.57066)
			(xy 405.480589 -420.571213) (xy 405.534528 -420.578974) (xy 405.586813 -420.594331) (xy 405.636381 -420.616973)
			(xy 405.682222 -420.646438) (xy 405.723403 -420.682126) (xy 405.759087 -420.723312) (xy 405.788547 -420.769156)
			(xy 405.811183 -420.818727) (xy 405.826535 -420.871014) (xy 405.83429 -420.924953) (xy 405.83429 -420.979447)
			(xy 405.834289 -420.979453) (xy 407.271946 -420.979453) (xy 407.271946 -420.924947) (xy 407.279703 -420.870997)
			(xy 407.295058 -420.818699) (xy 407.3177 -420.769119) (xy 407.347167 -420.723265) (xy 407.382859 -420.682072)
			(xy 407.424051 -420.646378) (xy 407.469903 -420.616908) (xy 407.519482 -420.594264) (xy 407.571779 -420.578906)
			(xy 407.625729 -420.571147) (xy 407.652982 -420.57066) (xy 408.516582 -420.57066) (xy 408.543833 -420.571186)
			(xy 408.597782 -420.57894) (xy 408.650077 -420.594293) (xy 408.699656 -420.616933) (xy 408.745507 -420.646398)
			(xy 408.786699 -420.682089) (xy 408.822391 -420.723278) (xy 408.851858 -420.769129) (xy 408.8745 -420.818706)
			(xy 408.889856 -420.871001) (xy 408.897613 -420.924949) (xy 408.897613 -420.979451) (xy 408.897612 -420.979456)
			(xy 410.335123 -420.979456) (xy 410.335123 -420.924944) (xy 410.342881 -420.870986) (xy 410.35824 -420.818682)
			(xy 410.380886 -420.769097) (xy 410.410358 -420.723238) (xy 410.446057 -420.682042) (xy 410.487256 -420.646345)
			(xy 410.533116 -420.616875) (xy 410.582703 -420.594232) (xy 410.635008 -420.578877) (xy 410.688966 -420.571121)
			(xy 410.716222 -420.57066) (xy 411.579822 -420.57066) (xy 411.60707 -420.571212) (xy 411.661011 -420.57897)
			(xy 411.713298 -420.594326) (xy 411.762869 -420.616966) (xy 411.808712 -420.646431) (xy 411.849896 -420.682119)
			(xy 411.885583 -420.723305) (xy 411.915044 -420.769151) (xy 411.937682 -420.818722) (xy 411.953035 -420.871011)
			(xy 411.96079 -420.924952) (xy 411.96079 -420.979448) (xy 411.960789 -420.979452) (xy 413.398446 -420.979452)
			(xy 413.398446 -420.924948) (xy 413.406202 -420.870999) (xy 413.421556 -420.818703) (xy 413.444197 -420.769124)
			(xy 413.473662 -420.723272) (xy 413.509352 -420.682079) (xy 413.550541 -420.646385) (xy 413.596391 -420.616915)
			(xy 413.645968 -420.59427) (xy 413.698262 -420.57891) (xy 413.75221 -420.571148) (xy 413.779462 -420.57066)
			(xy 414.643062 -420.57066) (xy 414.670314 -420.571185) (xy 414.724265 -420.578937) (xy 414.776563 -420.594288)
			(xy 414.826144 -420.616926) (xy 414.871998 -420.646391) (xy 414.913191 -420.682082) (xy 414.948886 -420.723272)
			(xy 414.978355 -420.769123) (xy 415.000999 -420.818701) (xy 415.016355 -420.870998) (xy 415.024113 -420.924948)
			(xy 415.024113 -420.979452) (xy 415.024113 -420.979455) (xy 416.461623 -420.979455) (xy 416.461623 -420.924945)
			(xy 416.469381 -420.870989) (xy 416.484738 -420.818687) (xy 416.507383 -420.769102) (xy 416.536853 -420.723245)
			(xy 416.57255 -420.682049) (xy 416.613747 -420.646352) (xy 416.659604 -420.616882) (xy 416.709188 -420.594237)
			(xy 416.761491 -420.57888) (xy 416.815447 -420.571123) (xy 416.842702 -420.57066) (xy 417.706302 -420.57066)
			(xy 417.733551 -420.57121) (xy 417.787494 -420.578966) (xy 417.839784 -420.59432) (xy 417.889357 -420.61696)
			(xy 417.935203 -420.646424) (xy 417.976389 -420.682112) (xy 418.012078 -420.723299) (xy 418.041541 -420.769145)
			(xy 418.06418 -420.818718) (xy 418.079534 -420.871008) (xy 418.08729 -420.924951) (xy 418.08729 -420.979449)
			(xy 418.079534 -421.033392) (xy 418.06418 -421.085682) (xy 418.041541 -421.135255) (xy 418.012078 -421.181101)
			(xy 417.976389 -421.222288) (xy 417.935203 -421.257976) (xy 417.889357 -421.28744) (xy 417.839784 -421.31008)
			(xy 417.787494 -421.325434) (xy 417.733551 -421.33319) (xy 417.706302 -421.333676) (xy 416.842702 -421.333676)
			(xy 416.815447 -421.333277) (xy 416.761491 -421.32552) (xy 416.709188 -421.310163) (xy 416.659604 -421.287518)
			(xy 416.613747 -421.258048) (xy 416.57255 -421.222351) (xy 416.536853 -421.181155) (xy 416.507383 -421.135298)
			(xy 416.484738 -421.085713) (xy 416.469381 -421.033411) (xy 416.461623 -420.979455) (xy 415.024113 -420.979455)
			(xy 415.016355 -421.033402) (xy 415.000999 -421.085699) (xy 414.978355 -421.135277) (xy 414.948886 -421.181128)
			(xy 414.913191 -421.222318) (xy 414.871998 -421.258009) (xy 414.826144 -421.287474) (xy 414.776563 -421.310112)
			(xy 414.724265 -421.325463) (xy 414.670314 -421.333215) (xy 414.643062 -421.333676) (xy 413.779462 -421.333676)
			(xy 413.75221 -421.333252) (xy 413.698262 -421.32549) (xy 413.645968 -421.31013) (xy 413.596391 -421.287485)
			(xy 413.550541 -421.258015) (xy 413.509352 -421.222321) (xy 413.473662 -421.181128) (xy 413.444197 -421.135276)
			(xy 413.421556 -421.085697) (xy 413.406202 -421.033401) (xy 413.398446 -420.979452) (xy 411.960789 -420.979452)
			(xy 411.953035 -421.033389) (xy 411.937682 -421.085678) (xy 411.915044 -421.135249) (xy 411.885583 -421.181095)
			(xy 411.849896 -421.222281) (xy 411.808712 -421.257969) (xy 411.762869 -421.287434) (xy 411.713298 -421.310074)
			(xy 411.661011 -421.32543) (xy 411.60707 -421.333188) (xy 411.579822 -421.333676) (xy 410.716222 -421.333676)
			(xy 410.688966 -421.333279) (xy 410.635008 -421.325523) (xy 410.582703 -421.310168) (xy 410.533116 -421.287525)
			(xy 410.487256 -421.258055) (xy 410.446057 -421.222358) (xy 410.410358 -421.181162) (xy 410.380886 -421.135303)
			(xy 410.35824 -421.085718) (xy 410.342881 -421.033414) (xy 410.335123 -420.979456) (xy 408.897612 -420.979456)
			(xy 408.889856 -421.033399) (xy 408.8745 -421.085694) (xy 408.851858 -421.135271) (xy 408.822391 -421.181122)
			(xy 408.786699 -421.222311) (xy 408.745507 -421.258002) (xy 408.699656 -421.287467) (xy 408.650077 -421.310107)
			(xy 408.597782 -421.32546) (xy 408.543833 -421.333214) (xy 408.516582 -421.333676) (xy 407.652982 -421.333676)
			(xy 407.625729 -421.333253) (xy 407.571779 -421.325494) (xy 407.519482 -421.310136) (xy 407.469903 -421.287492)
			(xy 407.424051 -421.258022) (xy 407.382859 -421.222328) (xy 407.347167 -421.181135) (xy 407.3177 -421.135281)
			(xy 407.295058 -421.085701) (xy 407.279703 -421.033403) (xy 407.271946 -420.979453) (xy 405.834289 -420.979453)
			(xy 405.826535 -421.033386) (xy 405.811183 -421.085673) (xy 405.788547 -421.135244) (xy 405.759087 -421.181088)
			(xy 405.723403 -421.222274) (xy 405.682222 -421.257962) (xy 405.636381 -421.287427) (xy 405.586813 -421.310069)
			(xy 405.534528 -421.325426) (xy 405.480589 -421.333187) (xy 405.453342 -421.333676) (xy 404.589742 -421.333676)
			(xy 404.562485 -421.33328) (xy 404.508525 -421.325527) (xy 404.456217 -421.310173) (xy 404.406628 -421.287531)
			(xy 404.360766 -421.258062) (xy 404.319564 -421.222365) (xy 404.283863 -421.181168) (xy 404.254389 -421.135309)
			(xy 404.231741 -421.085722) (xy 404.216382 -421.033416) (xy 404.208623 -420.979457) (xy 402.771089 -420.979457)
			(xy 402.763334 -421.033392) (xy 402.74798 -421.085682) (xy 402.725341 -421.135255) (xy 402.695878 -421.181101)
			(xy 402.660189 -421.222288) (xy 402.619003 -421.257976) (xy 402.573157 -421.28744) (xy 402.523584 -421.31008)
			(xy 402.471294 -421.325434) (xy 402.417351 -421.33319) (xy 402.390102 -421.333676) (xy 401.526502 -421.333676)
			(xy 401.499247 -421.333277) (xy 401.445291 -421.32552) (xy 401.392988 -421.310163) (xy 401.343404 -421.287518)
			(xy 401.297547 -421.258048) (xy 401.25635 -421.222351) (xy 401.220653 -421.181155) (xy 401.191183 -421.135298)
			(xy 401.168538 -421.085713) (xy 401.153181 -421.033411) (xy 401.145423 -420.979455) (xy 399.707913 -420.979455)
			(xy 399.700155 -421.033402) (xy 399.684799 -421.085699) (xy 399.662155 -421.135277) (xy 399.632686 -421.181128)
			(xy 399.596991 -421.222318) (xy 399.555798 -421.258009) (xy 399.509944 -421.287474) (xy 399.460363 -421.310112)
			(xy 399.408065 -421.325463) (xy 399.354114 -421.333215) (xy 399.326862 -421.333676) (xy 398.463262 -421.333676)
			(xy 398.43601 -421.333252) (xy 398.382062 -421.32549) (xy 398.329768 -421.31013) (xy 398.280191 -421.287485)
			(xy 398.234341 -421.258015) (xy 398.193152 -421.222321) (xy 398.157462 -421.181128) (xy 398.127997 -421.135276)
			(xy 398.105356 -421.085697) (xy 398.090002 -421.033401) (xy 398.082246 -420.979452) (xy 396.644589 -420.979452)
			(xy 396.636835 -421.033389) (xy 396.621482 -421.085678) (xy 396.598844 -421.135249) (xy 396.569383 -421.181095)
			(xy 396.533696 -421.222281) (xy 396.492512 -421.257969) (xy 396.446669 -421.287434) (xy 396.397098 -421.310074)
			(xy 396.344811 -421.32543) (xy 396.29087 -421.333188) (xy 396.263622 -421.333676) (xy 395.400022 -421.333676)
			(xy 395.372766 -421.333279) (xy 395.318808 -421.325523) (xy 395.266503 -421.310168) (xy 395.216916 -421.287525)
			(xy 395.171056 -421.258055) (xy 395.129857 -421.222358) (xy 395.094158 -421.181162) (xy 395.064686 -421.135303)
			(xy 395.04204 -421.085718) (xy 395.026681 -421.033414) (xy 395.018923 -420.979456) (xy 393.581412 -420.979456)
			(xy 393.573656 -421.033399) (xy 393.5583 -421.085694) (xy 393.535658 -421.135271) (xy 393.506191 -421.181122)
			(xy 393.470499 -421.222311) (xy 393.429307 -421.258002) (xy 393.383456 -421.287467) (xy 393.333877 -421.310107)
			(xy 393.281582 -421.32546) (xy 393.227633 -421.333214) (xy 393.200382 -421.333676) (xy 392.336782 -421.333676)
			(xy 392.309529 -421.333253) (xy 392.255579 -421.325494) (xy 392.203282 -421.310136) (xy 392.153703 -421.287492)
			(xy 392.107851 -421.258022) (xy 392.066659 -421.222328) (xy 392.030967 -421.181135) (xy 392.0015 -421.135281)
			(xy 391.978858 -421.085701) (xy 391.963503 -421.033403) (xy 391.955746 -420.979453) (xy 390.518089 -420.979453)
			(xy 390.510335 -421.033386) (xy 390.494983 -421.085673) (xy 390.472347 -421.135244) (xy 390.442887 -421.181088)
			(xy 390.407203 -421.222274) (xy 390.366022 -421.257962) (xy 390.320181 -421.287427) (xy 390.270613 -421.310069)
			(xy 390.218328 -421.325426) (xy 390.164389 -421.333187) (xy 390.137142 -421.333676) (xy 389.273542 -421.333676)
			(xy 389.246285 -421.33328) (xy 389.192325 -421.325527) (xy 389.140017 -421.310173) (xy 389.090428 -421.287531)
			(xy 389.044566 -421.258062) (xy 389.003364 -421.222365) (xy 388.967663 -421.181168) (xy 388.938189 -421.135309)
			(xy 388.915541 -421.085722) (xy 388.900182 -421.033416) (xy 388.892423 -420.979457) (xy 387.454889 -420.979457)
			(xy 387.447134 -421.033392) (xy 387.43178 -421.085682) (xy 387.409141 -421.135255) (xy 387.379678 -421.181101)
			(xy 387.343989 -421.222288) (xy 387.302803 -421.257976) (xy 387.256957 -421.28744) (xy 387.207384 -421.31008)
			(xy 387.155094 -421.325434) (xy 387.101151 -421.33319) (xy 387.073902 -421.333676) (xy 386.210302 -421.333676)
			(xy 386.183047 -421.333277) (xy 386.129091 -421.32552) (xy 386.076788 -421.310163) (xy 386.027204 -421.287518)
			(xy 385.981347 -421.258048) (xy 385.94015 -421.222351) (xy 385.904453 -421.181155) (xy 385.874983 -421.135298)
			(xy 385.852338 -421.085713) (xy 385.836981 -421.033411) (xy 385.829223 -420.979455) (xy 384.391713 -420.979455)
			(xy 384.383955 -421.033402) (xy 384.368599 -421.085699) (xy 384.345955 -421.135277) (xy 384.316486 -421.181128)
			(xy 384.280791 -421.222318) (xy 384.239598 -421.258009) (xy 384.193744 -421.287474) (xy 384.144163 -421.310112)
			(xy 384.091865 -421.325463) (xy 384.037914 -421.333215) (xy 384.010662 -421.333676) (xy 383.147062 -421.333676)
			(xy 383.11981 -421.333252) (xy 383.065862 -421.32549) (xy 383.013568 -421.31013) (xy 382.963991 -421.287485)
			(xy 382.918141 -421.258015) (xy 382.876952 -421.222321) (xy 382.841262 -421.181128) (xy 382.811797 -421.135276)
			(xy 382.789156 -421.085697) (xy 382.773802 -421.033401) (xy 382.766046 -420.979452) (xy 381.328389 -420.979452)
			(xy 381.320635 -421.033389) (xy 381.305282 -421.085678) (xy 381.282644 -421.135249) (xy 381.253183 -421.181095)
			(xy 381.217496 -421.222281) (xy 381.176312 -421.257969) (xy 381.130469 -421.287434) (xy 381.080898 -421.310074)
			(xy 381.028611 -421.32543) (xy 380.97467 -421.333188) (xy 380.947422 -421.333676) (xy 380.083822 -421.333676)
			(xy 380.056566 -421.333279) (xy 380.002608 -421.325523) (xy 379.950303 -421.310168) (xy 379.900716 -421.287525)
			(xy 379.854856 -421.258055) (xy 379.813657 -421.222358) (xy 379.777958 -421.181162) (xy 379.748486 -421.135303)
			(xy 379.72584 -421.085718) (xy 379.710481 -421.033414) (xy 379.702723 -420.979456) (xy 378.265212 -420.979456)
			(xy 378.257456 -421.033399) (xy 378.2421 -421.085694) (xy 378.219458 -421.135271) (xy 378.189991 -421.181122)
			(xy 378.154299 -421.222311) (xy 378.113107 -421.258002) (xy 378.067256 -421.287467) (xy 378.017677 -421.310107)
			(xy 377.965382 -421.32546) (xy 377.911433 -421.333214) (xy 377.884182 -421.333676) (xy 377.020582 -421.333676)
			(xy 376.993329 -421.333253) (xy 376.939379 -421.325494) (xy 376.887082 -421.310136) (xy 376.837503 -421.287492)
			(xy 376.791651 -421.258022) (xy 376.750459 -421.222328) (xy 376.714767 -421.181135) (xy 376.6853 -421.135281)
			(xy 376.662658 -421.085701) (xy 376.647303 -421.033403) (xy 376.639546 -420.979453) (xy 375.201889 -420.979453)
			(xy 375.194135 -421.033386) (xy 375.178783 -421.085673) (xy 375.156147 -421.135244) (xy 375.126687 -421.181088)
			(xy 375.091003 -421.222274) (xy 375.049822 -421.257962) (xy 375.003981 -421.287427) (xy 374.954413 -421.310069)
			(xy 374.902128 -421.325426) (xy 374.848189 -421.333187) (xy 374.820942 -421.333676) (xy 373.957342 -421.333676)
			(xy 373.930085 -421.33328) (xy 373.876125 -421.325527) (xy 373.823817 -421.310173) (xy 373.774228 -421.287531)
			(xy 373.728366 -421.258062) (xy 373.687164 -421.222365) (xy 373.651463 -421.181168) (xy 373.621989 -421.135309)
			(xy 373.599341 -421.085722) (xy 373.583982 -421.033416) (xy 373.576223 -420.979457) (xy 372.138689 -420.979457)
			(xy 372.130934 -421.033392) (xy 372.11558 -421.085682) (xy 372.092941 -421.135255) (xy 372.063478 -421.181101)
			(xy 372.027789 -421.222288) (xy 371.986603 -421.257976) (xy 371.940757 -421.28744) (xy 371.891184 -421.31008)
			(xy 371.838894 -421.325434) (xy 371.784951 -421.33319) (xy 371.757702 -421.333676) (xy 370.894102 -421.333676)
			(xy 370.866847 -421.333277) (xy 370.812891 -421.32552) (xy 370.760588 -421.310163) (xy 370.711004 -421.287518)
			(xy 370.665147 -421.258048) (xy 370.62395 -421.222351) (xy 370.588253 -421.181155) (xy 370.558783 -421.135298)
			(xy 370.536138 -421.085713) (xy 370.520781 -421.033411) (xy 370.513023 -420.979455) (xy 370.117116 -420.979455)
			(xy 370.117116 -421.132508) (xy 370.118615 -421.144169) (xy 370.130586 -421.164375) (xy 370.150236 -421.177236)
			(xy 370.16182 -421.179244) (xy 370.313204 -421.179244) (xy 370.313204 -421.823642) (xy 370.314662 -421.832769)
			(xy 370.323178 -421.849157) (xy 370.336984 -421.861423) (xy 370.35426 -421.867951) (xy 370.363496 -421.868346)
			(xy 435.27853 -421.868346) (xy 435.288597 -421.867916) (xy 435.307188 -421.860188) (xy 435.314598 -421.85336)
			(xy 446.82664 -410.341318) (xy 446.828418 -410.339286) (xy 446.853056 -410.314648) (xy 446.855088 -410.31287)
			(xy 448.826636 -408.341322) (xy 448.83332 -408.333912) (xy 448.840904 -408.315476) (xy 448.841368 -408.305508)
			(xy 448.831462 -408.275282) (xy 448.815029 -408.252144) (xy 448.788939 -408.201748) (xy 448.771173 -408.147852)
			(xy 448.76218 -408.09182) (xy 448.761612 -408.063446) (xy 448.762129 -408.035459) (xy 448.770879 -407.980173)
			(xy 448.788171 -407.926937) (xy 448.813579 -407.877062) (xy 448.846478 -407.831776) (xy 448.886056 -407.792195)
			(xy 448.931339 -407.759293) (xy 448.981213 -407.733881) (xy 449.034448 -407.716585) (xy 449.089733 -407.707831)
			(xy 449.11772 -407.707338) (xy 449.146095 -407.70789) (xy 449.202125 -407.716892) (xy 449.25602 -407.734666)
			(xy 449.306414 -407.76076) (xy 449.329556 -407.777188) (xy 449.359782 -407.787094) (xy 449.369743 -407.786605)
			(xy 449.388162 -407.779012) (xy 449.395596 -407.772362) (xy 464.51012 -392.657838) (xy 464.516965 -392.65044)
			(xy 464.52469 -392.631841) (xy 464.525106 -392.62177) (xy 464.525106 -381.559816) (xy 464.524668 -381.549752)
			(xy 464.516933 -381.531169) (xy 464.51012 -381.523748) (xy 464.294982 -381.30861) (xy 464.287583 -381.301765)
			(xy 464.268985 -381.294036) (xy 464.258914 -381.293624) (xy 436.215536 -381.293624) (xy 436.205001 -381.294145)
			(xy 436.185707 -381.302609) (xy 436.17145 -381.318121) (xy 436.16753 -381.327914) (xy 436.130954 -381.43434)
			(xy 436.140098 -381.465074) (xy 436.153052 -381.475234) (xy 436.226304 -381.533079) (xy 436.368323 -381.654229)
			(xy 436.504975 -381.781402) (xy 436.636003 -381.914362) (xy 436.761163 -382.052859) (xy 436.880222 -382.196635)
			(xy 436.992957 -382.345422) (xy 437.099157 -382.498942) (xy 437.198625 -382.656907) (xy 437.291173 -382.819022)
			(xy 437.376629 -382.984986) (xy 437.454835 -383.154487) (xy 437.525642 -383.327209) (xy 437.58892 -383.50283)
			(xy 437.64455 -383.681021) (xy 437.692428 -383.861449) (xy 437.732464 -384.043778) (xy 437.764585 -384.227666)
			(xy 437.788729 -384.412771) (xy 437.804852 -384.598746) (xy 437.812924 -384.785244) (xy 437.81345 -384.87858)
			(xy 437.812937 -384.972789) (xy 437.804719 -385.161026) (xy 437.788298 -385.348727) (xy 437.763706 -385.535532)
			(xy 437.730989 -385.721087) (xy 437.690209 -385.905038) (xy 437.641444 -386.087035) (xy 437.584787 -386.266732)
			(xy 437.520345 -386.443787) (xy 437.448242 -386.617862) (xy 437.368615 -386.788626) (xy 437.281615 -386.955755)
			(xy 437.187407 -387.11893) (xy 437.086172 -387.27784) (xy 436.978102 -387.432183) (xy 436.863402 -387.581665)
			(xy 436.742291 -387.726002) (xy 436.614999 -387.864918) (xy 436.481769 -387.998151) (xy 436.342854 -388.125444)
			(xy 436.198519 -388.246558) (xy 436.049039 -388.36126) (xy 435.894698 -388.469333) (xy 435.735789 -388.570571)
			(xy 435.572616 -388.664781) (xy 435.405489 -388.751784) (xy 435.234726 -388.831414) (xy 435.060652 -388.90352)
			(xy 434.883598 -388.967964) (xy 434.703902 -389.024624) (xy 434.521906 -389.073392) (xy 434.337955 -389.114175)
			(xy 434.152401 -389.146895) (xy 433.965596 -389.171491) (xy 433.777896 -389.187914) (xy 433.589659 -389.196135)
			(xy 433.49545 -389.19658) (xy 433.402878 -389.196089) (xy 433.217903 -389.188156) (xy 433.033438 -389.172302)
			(xy 432.849823 -389.148557) (xy 432.667394 -389.116963) (xy 432.486486 -389.07758) (xy 432.307433 -389.030479)
			(xy 432.130563 -388.975748) (xy 431.956201 -388.913486) (xy 431.784668 -388.843808) (xy 431.616279 -388.766843)
			(xy 431.451344 -388.682731) (xy 431.290165 -388.591627) (xy 431.133038 -388.493699) (xy 430.980254 -388.389126)
			(xy 430.832092 -388.278101) (xy 430.688824 -388.160828) (xy 430.550715 -388.037523) (xy 430.484026 -387.973316)
			(xy 430.47285 -387.962394) (xy 430.443132 -387.956806) (xy 430.342548 -387.999224) (xy 430.33358 -388.003534)
			(xy 430.319585 -388.017651) (xy 430.311993 -388.036022) (xy 430.31156 -388.04596) (xy 430.31156 -396.983712)
			(xy 430.310987 -397.008672) (xy 430.301245 -397.057631) (xy 430.282137 -397.103749) (xy 430.254399 -397.145252)
			(xy 430.237138 -397.16329) (xy 429.478948 -397.92148) (xy 429.460908 -397.938742) (xy 429.419416 -397.966505)
			(xy 429.373298 -397.985622) (xy 429.324332 -397.995355) (xy 429.29937 -397.995902) (xy 426.371766 -397.995902)
			(xy 426.346811 -397.995287) (xy 426.29786 -397.985544) (xy 426.251751 -397.966439) (xy 426.210254 -397.938706)
			(xy 426.192188 -397.92148) (xy 425.605702 -397.334994) (xy 425.59829 -397.32831) (xy 425.579857 -397.320713)
			(xy 425.559919 -397.320713) (xy 425.541486 -397.32831) (xy 425.534074 -397.334994) (xy 424.968162 -397.900906)
			(xy 424.950122 -397.918168) (xy 424.90863 -397.945931) (xy 424.862511 -397.965048) (xy 424.813546 -397.974783)
			(xy 424.788584 -397.975328) (xy 422.305988 -397.975328) (xy 422.28162 -397.974752) (xy 422.233786 -397.96542)
			(xy 422.210992 -397.956786) (xy 422.202102 -397.95323) (xy 422.184068 -397.952722) (xy 422.103042 -397.980662)
			(xy 422.089072 -397.992346) (xy 422.0845 -398.000474) (xy 422.072753 -398.020232) (xy 422.044255 -398.056298)
			(xy 422.010677 -398.087688) (xy 421.972775 -398.113694) (xy 421.931405 -398.133729) (xy 421.887501 -398.147341)
			(xy 421.842053 -398.154222) (xy 421.81907 -398.154652) (xy 421.795499 -398.154212) (xy 421.748918 -398.14696)
			(xy 421.704006 -398.132632) (xy 421.66183 -398.111571) (xy 421.623394 -398.084275) (xy 421.589611 -398.051395)
			(xy 421.561285 -398.013712) (xy 421.54983 -397.993108) (xy 421.549322 -397.992346) (xy 421.151558 -397.304006)
			(xy 421.13966 -397.281338) (xy 421.122784 -397.233007) (xy 421.114223 -397.182536) (xy 421.113712 -397.15694)
			(xy 421.113712 -397.156432) (xy 421.113796 -397.145087) (xy 421.115452 -397.122457) (xy 421.117014 -397.11122)
			(xy 421.118284 -397.10233) (xy 421.114728 -397.085058) (xy 421.071294 -397.013938) (xy 421.057324 -397.003016)
			(xy 421.048942 -396.999968) (xy 421.025093 -396.991429) (xy 420.980398 -396.967595) (xy 420.940248 -396.936712)
			(xy 420.905744 -396.899628) (xy 420.877833 -396.857359) (xy 420.857279 -396.811063) (xy 420.844646 -396.76201)
			(xy 420.841932 -396.736824) (xy 420.84117 -396.727172) (xy 420.832788 -396.710154) (xy 420.77513 -396.657322)
			(xy 420.76793 -396.651159) (xy 420.750309 -396.644219) (xy 420.74084 -396.64386) (xy 416.774376 -396.64386)
			(xy 416.753217 -396.643445) (xy 416.711483 -396.636446) (xy 416.671485 -396.622629) (xy 416.63433 -396.602376)
			(xy 416.601043 -396.576247) (xy 416.572546 -396.544963) (xy 416.549626 -396.509391) (xy 416.532917 -396.470512)
			(xy 416.527488 -396.450058) (xy 416.525202 -396.440152) (xy 416.514026 -396.424404) (xy 416.437064 -396.37589)
			(xy 416.418014 -396.372588) (xy 416.408108 -396.37462) (xy 416.392787 -396.377596) (xy 416.361738 -396.380782)
			(xy 416.346132 -396.38097) (xy 416.322138 -396.380526) (xy 416.274741 -396.373023) (xy 416.229102 -396.358197)
			(xy 416.186344 -396.336413) (xy 416.147521 -396.308207) (xy 416.113589 -396.274275) (xy 416.085384 -396.235451)
			(xy 416.063601 -396.192693) (xy 416.048775 -396.147053) (xy 416.041273 -396.099656) (xy 416.040824 -396.075662)
			(xy 416.041253 -396.052227) (xy 416.048416 -396.005906) (xy 416.062568 -395.961223) (xy 416.072574 -395.940026)
			(xy 416.07994 -395.925294) (xy 416.074606 -395.893036) (xy 415.368232 -395.186662) (xy 415.360833 -395.179819)
			(xy 415.342234 -395.1721) (xy 415.332164 -395.171676) (xy 415.032952 -395.171676) (xy 415.022885 -395.172107)
			(xy 415.004291 -395.179831) (xy 414.996884 -395.186662) (xy 414.239964 -395.943582) (xy 414.23336 -395.971014)
			(xy 414.237424 -395.984476) (xy 414.243932 -396.006709) (xy 414.25095 -396.0525) (xy 414.251394 -396.075662)
			(xy 414.250951 -396.099657) (xy 414.243449 -396.147056) (xy 414.228623 -396.192698) (xy 414.20684 -396.235458)
			(xy 414.178634 -396.274284) (xy 414.144702 -396.308219) (xy 414.105879 -396.336427) (xy 414.06312 -396.358214)
			(xy 414.017479 -396.373043) (xy 413.970081 -396.380549) (xy 413.946086 -396.38097) (xy 413.922923 -396.380541)
			(xy 413.877131 -396.373522) (xy 413.8549 -396.367) (xy 413.841438 -396.362936) (xy 413.814006 -396.36954)
			(xy 413.271716 -396.91183) (xy 413.265035 -396.91924) (xy 413.257461 -396.937677) (xy 413.256984 -396.947644)
			(xy 413.266636 -396.977362) (xy 413.273323 -396.986855) (xy 413.285399 -397.006689) (xy 413.290766 -397.016986)
			(xy 413.291274 -397.018002) (xy 413.37158 -397.15694) (xy 413.91332 -397.15694) (xy 413.91332 -397.156432)
			(xy 413.913769 -397.132426) (xy 413.921279 -397.085004) (xy 413.936121 -397.039343) (xy 413.957927 -396.996568)
			(xy 413.98616 -396.957733) (xy 414.020124 -396.923797) (xy 414.058981 -396.895596) (xy 414.101774 -396.873825)
			(xy 414.147448 -396.859021) (xy 414.194875 -396.851549) (xy 414.218882 -396.851124) (xy 414.242819 -396.851537)
			(xy 414.290108 -396.859001) (xy 414.335653 -396.87375) (xy 414.378341 -396.895422) (xy 414.417126 -396.923486)
			(xy 414.451059 -396.957257) (xy 414.47931 -396.995907) (xy 414.490662 -397.016986) (xy 414.49117 -397.018002)
			(xy 414.571476 -397.15694) (xy 415.113724 -397.15694) (xy 415.113724 -397.156432) (xy 415.114168 -397.132438)
			(xy 415.121671 -397.085041) (xy 415.136497 -397.039401) (xy 415.158281 -396.996643) (xy 415.186487 -396.957819)
			(xy 415.220419 -396.923887) (xy 415.259243 -396.895681) (xy 415.302001 -396.873897) (xy 415.347641 -396.859071)
			(xy 415.395038 -396.851568) (xy 415.419032 -396.851124) (xy 415.442968 -396.851578) (xy 415.490254 -396.859034)
			(xy 415.535799 -396.873775) (xy 415.578487 -396.89544) (xy 415.617272 -396.923499) (xy 415.651207 -396.957264)
			(xy 415.679459 -396.995909) (xy 415.690812 -397.016986) (xy 415.69132 -397.018002) (xy 415.771626 -397.15694)
			(xy 416.31362 -397.15694) (xy 416.31362 -397.156432) (xy 416.314068 -397.132438) (xy 416.321571 -397.085041)
			(xy 416.336397 -397.039402) (xy 416.35818 -396.996644) (xy 416.386386 -396.95782) (xy 416.420317 -396.923888)
			(xy 416.45914 -396.895682) (xy 416.501898 -396.873898) (xy 416.547537 -396.859072) (xy 416.594934 -396.851568)
			(xy 416.618928 -396.851124) (xy 416.642863 -396.851581) (xy 416.69015 -396.859037) (xy 416.735695 -396.873777)
			(xy 416.778382 -396.895442) (xy 416.817168 -396.9235) (xy 416.851103 -396.957265) (xy 416.879355 -396.995909)
			(xy 416.890708 -397.016986) (xy 416.891216 -397.018002) (xy 416.971522 -397.15694) (xy 417.513516 -397.15694)
			(xy 417.513516 -397.156432) (xy 417.513968 -397.132439) (xy 417.521471 -397.085042) (xy 417.536296 -397.039403)
			(xy 417.55808 -396.996645) (xy 417.586284 -396.957822) (xy 417.620216 -396.92389) (xy 417.659038 -396.895684)
			(xy 417.701795 -396.873899) (xy 417.747434 -396.859072) (xy 417.794831 -396.851568) (xy 417.818824 -396.851124)
			(xy 417.842759 -396.851584) (xy 417.890046 -396.859039) (xy 417.93559 -396.873779) (xy 417.978278 -396.895444)
			(xy 418.017064 -396.923501) (xy 418.050998 -396.957265) (xy 418.079251 -396.99591) (xy 418.090604 -397.016986)
			(xy 418.091112 -397.018002) (xy 418.171418 -397.15694) (xy 418.713412 -397.15694) (xy 418.713412 -397.156432)
			(xy 418.713869 -397.132426) (xy 418.721379 -397.085005) (xy 418.73622 -397.039345) (xy 418.758025 -396.99657)
			(xy 418.786257 -396.957736) (xy 418.82022 -396.9238) (xy 418.859077 -396.895599) (xy 418.901869 -396.873827)
			(xy 418.947541 -396.859023) (xy 418.994968 -396.85155) (xy 419.018974 -396.851124) (xy 419.042911 -396.851543)
			(xy 419.090199 -396.859006) (xy 419.135744 -396.873754) (xy 419.178432 -396.895425) (xy 419.217218 -396.923488)
			(xy 419.251151 -396.957258) (xy 419.279402 -396.995907) (xy 419.290754 -397.016986) (xy 419.291262 -397.018002)
			(xy 419.371568 -397.15694) (xy 419.913308 -397.15694) (xy 419.913308 -397.156432) (xy 419.913769 -397.132426)
			(xy 419.921279 -397.085006) (xy 419.93612 -397.039346) (xy 419.957925 -396.996571) (xy 419.986156 -396.957737)
			(xy 420.020119 -396.923801) (xy 420.058975 -396.8956) (xy 420.101766 -396.873828) (xy 420.147438 -396.859023)
			(xy 420.194864 -396.85155) (xy 420.21887 -396.851124) (xy 420.242807 -396.851547) (xy 420.290095 -396.859009)
			(xy 420.33564 -396.873756) (xy 420.378328 -396.895426) (xy 420.417113 -396.923489) (xy 420.451047 -396.957259)
			(xy 420.479298 -396.995907) (xy 420.49065 -397.016986) (xy 420.491158 -397.018002) (xy 420.883588 -397.696944)
			(xy 420.896319 -397.72031) (xy 420.914436 -397.770338) (xy 420.923646 -397.822741) (xy 420.924228 -397.849344)
			(xy 420.923778 -397.873335) (xy 420.916266 -397.920727) (xy 420.901434 -397.96636) (xy 420.879647 -398.009111)
			(xy 420.851441 -398.047928) (xy 420.81751 -398.081856) (xy 420.778691 -398.110059) (xy 420.735937 -398.131843)
			(xy 420.690303 -398.146672) (xy 420.642911 -398.15418) (xy 420.61892 -398.154652) (xy 420.595348 -398.154215)
			(xy 420.548763 -398.146978) (xy 420.503847 -398.132658) (xy 420.46167 -398.111595) (xy 420.423236 -398.084293)
			(xy 420.389462 -398.051402) (xy 420.361153 -398.013704) (xy 420.34968 -397.993108) (xy 420.349172 -397.992346)
			(xy 419.951408 -397.304006) (xy 419.939493 -397.281337) (xy 419.922555 -397.233012) (xy 419.913896 -397.182542)
			(xy 419.913308 -397.15694) (xy 419.371568 -397.15694) (xy 419.683692 -397.696944) (xy 419.696424 -397.72031)
			(xy 419.71454 -397.770338) (xy 419.72375 -397.822741) (xy 419.724332 -397.849344) (xy 419.723878 -397.873335)
			(xy 419.716366 -397.920726) (xy 419.701534 -397.966359) (xy 419.679747 -398.00911) (xy 419.651542 -398.047927)
			(xy 419.617612 -398.081855) (xy 419.578793 -398.110058) (xy 419.53604 -398.131842) (xy 419.490407 -398.146671)
			(xy 419.443015 -398.15418) (xy 419.419024 -398.154652) (xy 419.395452 -398.154211) (xy 419.348867 -398.146975)
			(xy 419.303951 -398.132656) (xy 419.261774 -398.111594) (xy 419.223341 -398.084292) (xy 419.189567 -398.051401)
			(xy 419.161257 -398.013704) (xy 419.149784 -397.993108) (xy 419.149276 -397.992346) (xy 418.751512 -397.304006)
			(xy 418.739598 -397.281337) (xy 418.72266 -397.233012) (xy 418.714 -397.182542) (xy 418.713412 -397.15694)
			(xy 418.171418 -397.15694) (xy 418.483542 -397.696944) (xy 418.496349 -397.720286) (xy 418.514576 -397.770304)
			(xy 418.523843 -397.822727) (xy 418.524436 -397.849344) (xy 418.524002 -397.87335) (xy 418.516481 -397.920768)
			(xy 418.501633 -397.966426) (xy 418.479822 -398.009197) (xy 418.451587 -398.048029) (xy 418.417623 -398.081963)
			(xy 418.378767 -398.110164) (xy 418.335976 -398.131936) (xy 418.290305 -398.146744) (xy 418.24288 -398.154223)
			(xy 418.218874 -398.154652) (xy 418.195301 -398.154252) (xy 418.148714 -398.147008) (xy 418.103797 -398.132681)
			(xy 418.06162 -398.111613) (xy 418.023187 -398.084305) (xy 417.989414 -398.051408) (xy 417.961106 -398.013706)
			(xy 417.949634 -397.993108) (xy 417.949126 -397.992346) (xy 417.551362 -397.304006) (xy 417.539486 -397.281329)
			(xy 417.522635 -397.232996) (xy 417.514062 -397.182533) (xy 417.513516 -397.15694) (xy 416.971522 -397.15694)
			(xy 417.283646 -397.696944) (xy 417.296453 -397.720286) (xy 417.31468 -397.770304) (xy 417.323947 -397.822727)
			(xy 417.32454 -397.849344) (xy 417.324102 -397.873349) (xy 417.316581 -397.920768) (xy 417.301733 -397.966425)
			(xy 417.279923 -398.009196) (xy 417.251688 -398.048027) (xy 417.217725 -398.081961) (xy 417.178869 -398.110162)
			(xy 417.136079 -398.131935) (xy 417.090409 -398.146744) (xy 417.042984 -398.154222) (xy 417.018978 -398.154652)
			(xy 416.995405 -398.154249) (xy 416.948818 -398.147005) (xy 416.903901 -398.132679) (xy 416.861724 -398.111611)
			(xy 416.823291 -398.084304) (xy 416.789518 -398.051408) (xy 416.76121 -398.013706) (xy 416.749738 -397.993108)
			(xy 416.74923 -397.992346) (xy 416.351466 -397.304006) (xy 416.339591 -397.281329) (xy 416.322739 -397.232996)
			(xy 416.314166 -397.182533) (xy 416.31362 -397.15694) (xy 415.771626 -397.15694) (xy 416.08375 -397.696944)
			(xy 416.096557 -397.720285) (xy 416.114784 -397.770304) (xy 416.124051 -397.822726) (xy 416.124644 -397.849344)
			(xy 416.124202 -397.873349) (xy 416.116682 -397.920767) (xy 416.101834 -397.966424) (xy 416.080024 -398.009195)
			(xy 416.05179 -398.048026) (xy 416.017826 -398.08196) (xy 415.978971 -398.110161) (xy 415.936182 -398.131934)
			(xy 415.890512 -398.146743) (xy 415.843088 -398.154222) (xy 415.819082 -398.154652) (xy 415.795509 -398.154245)
			(xy 415.748922 -398.147003) (xy 415.704006 -398.132677) (xy 415.661828 -398.11161) (xy 415.623395 -398.084303)
			(xy 415.589623 -398.051407) (xy 415.561314 -398.013706) (xy 415.549842 -397.993108) (xy 415.549334 -397.992346)
			(xy 415.15157 -397.304006) (xy 415.139695 -397.281329) (xy 415.122843 -397.232996) (xy 415.11427 -397.182533)
			(xy 415.113724 -397.15694) (xy 414.571476 -397.15694) (xy 414.8836 -397.696944) (xy 414.896332 -397.72031)
			(xy 414.914448 -397.770338) (xy 414.923658 -397.822741) (xy 414.92424 -397.849344) (xy 414.923778 -397.873335)
			(xy 414.916266 -397.920725) (xy 414.901435 -397.966357) (xy 414.879649 -398.009107) (xy 414.851444 -398.047924)
			(xy 414.817515 -398.081852) (xy 414.778697 -398.110055) (xy 414.735946 -398.13184) (xy 414.690313 -398.146669)
			(xy 414.642923 -398.154179) (xy 414.618932 -398.154652) (xy 414.59536 -398.154205) (xy 414.548776 -398.14697)
			(xy 414.50386 -398.132651) (xy 414.461683 -398.111591) (xy 414.423249 -398.08429) (xy 414.389475 -398.0514)
			(xy 414.361165 -398.013703) (xy 414.349692 -397.993108) (xy 414.349184 -397.992346) (xy 413.95142 -397.304006)
			(xy 413.939506 -397.281337) (xy 413.922568 -397.233012) (xy 413.913908 -397.182542) (xy 413.91332 -397.15694)
			(xy 413.37158 -397.15694) (xy 413.683704 -397.696944) (xy 413.696464 -397.720252) (xy 413.714596 -397.770194)
			(xy 413.723794 -397.822524) (xy 413.724344 -397.84909) (xy 413.724344 -397.849344) (xy 413.72387 -397.873334)
			(xy 413.716359 -397.920722) (xy 413.701528 -397.966353) (xy 413.679743 -398.009102) (xy 413.651539 -398.047918)
			(xy 413.617612 -398.081844) (xy 413.578795 -398.110047) (xy 413.536046 -398.131831) (xy 413.490415 -398.146661)
			(xy 413.443026 -398.154171) (xy 413.419036 -398.154652) (xy 413.395466 -398.154209) (xy 413.348889 -398.146953)
			(xy 413.30398 -398.132622) (xy 413.261809 -398.111558) (xy 413.223377 -398.084261) (xy 413.189598 -398.05138)
			(xy 413.161276 -398.013698) (xy 413.149796 -397.993108) (xy 413.149288 -397.992346) (xy 412.751524 -397.304006)
			(xy 412.739593 -397.281345) (xy 412.722646 -397.23302) (xy 412.714005 -397.182544) (xy 412.713424 -397.15694)
			(xy 412.713424 -397.156432) (xy 412.715456 -397.122904) (xy 412.716726 -397.111982) (xy 412.710122 -397.091662)
			(xy 412.65221 -397.027146) (xy 412.644643 -397.019529) (xy 412.625084 -397.010733) (xy 412.614364 -397.010128)
			(xy 412.17469 -397.010128) (xy 412.165793 -397.010453) (xy 412.149066 -397.016524) (xy 412.135435 -397.027961)
			(xy 412.130748 -397.035528) (xy 412.123636 -397.047466) (xy 412.12389 -397.07439) (xy 412.483554 -397.696944)
			(xy 412.496336 -397.720295) (xy 412.514527 -397.770318) (xy 412.52381 -397.822731) (xy 412.524448 -397.849344)
			(xy 412.523975 -397.873321) (xy 412.516472 -397.920686) (xy 412.501656 -397.966295) (xy 412.479893 -398.009027)
			(xy 412.451718 -398.047832) (xy 412.417822 -398.081755) (xy 412.379041 -398.109962) (xy 412.336326 -398.13176)
			(xy 412.290729 -398.146613) (xy 412.243371 -398.154155) (xy 412.219394 -398.154652) (xy 412.218886 -398.154652)
			(xy 412.195314 -398.154213) (xy 412.148732 -398.146963) (xy 412.103818 -398.132637) (xy 412.06164 -398.111577)
			(xy 412.023202 -398.084282) (xy 411.989417 -398.051402) (xy 411.961089 -398.013719) (xy 411.949646 -397.993108)
			(xy 411.949138 -397.992346) (xy 411.551374 -397.304006) (xy 411.539475 -397.281338) (xy 411.522599 -397.233007)
			(xy 411.514037 -397.182536) (xy 411.513528 -397.15694) (xy 411.513528 -397.156432) (xy 411.515306 -397.122904)
			(xy 411.516576 -397.111982) (xy 411.509972 -397.091662) (xy 411.45206 -397.027146) (xy 411.44449 -397.019537)
			(xy 411.424931 -397.01076) (xy 411.414214 -397.010128) (xy 410.974794 -397.010128) (xy 410.965896 -397.010453)
			(xy 410.949169 -397.016522) (xy 410.935536 -397.027959) (xy 410.930852 -397.035528) (xy 410.92374 -397.047466)
			(xy 410.923994 -397.07439) (xy 411.283658 -397.696944) (xy 411.29644 -397.720295) (xy 411.314631 -397.770318)
			(xy 411.323913 -397.822731) (xy 411.324552 -397.849344) (xy 411.324079 -397.873322) (xy 411.316576 -397.920686)
			(xy 411.30176 -397.966295) (xy 411.279997 -398.009028) (xy 411.251822 -398.047833) (xy 411.217927 -398.081757)
			(xy 411.179145 -398.109964) (xy 411.13643 -398.131763) (xy 411.090833 -398.146616) (xy 411.043475 -398.154159)
			(xy 411.019498 -398.154652) (xy 411.01899 -398.154652) (xy 410.995418 -398.154213) (xy 410.948835 -398.146964)
			(xy 410.903921 -398.132638) (xy 410.861743 -398.111578) (xy 410.823304 -398.084284) (xy 410.789519 -398.051404)
			(xy 410.76119 -398.013721) (xy 410.74975 -397.993108) (xy 410.749242 -397.992346) (xy 410.351478 -397.304006)
			(xy 410.339579 -397.281338) (xy 410.322702 -397.233007) (xy 410.31414 -397.182536) (xy 410.313632 -397.15694)
			(xy 410.313632 -397.156432) (xy 410.313716 -397.145087) (xy 410.315372 -397.122457) (xy 410.316934 -397.11122)
			(xy 410.318204 -397.10233) (xy 410.314648 -397.085058) (xy 410.271214 -397.013938) (xy 410.257244 -397.003016)
			(xy 410.248862 -396.999968) (xy 410.228034 -396.992348) (xy 410.227526 -396.99184) (xy 410.214606 -396.9865)
			(xy 410.189913 -396.973387) (xy 410.17825 -396.965678) (xy 410.177488 -396.96517) (xy 410.158328 -396.951912)
			(xy 410.123888 -396.920532) (xy 410.108908 -396.902686) (xy 410.105352 -396.898876) (xy 409.567888 -396.361412)
			(xy 409.55063 -396.34337) (xy 409.522877 -396.301876) (xy 409.503769 -396.255758) (xy 409.494044 -396.206794)
			(xy 409.493466 -396.181834) (xy 409.493466 -394.445236) (xy 409.493277 -394.438567) (xy 409.489813 -394.425687)
			(xy 409.486608 -394.419836) (xy 409.151582 -393.839954) (xy 409.139687 -393.817285) (xy 409.122818 -393.768954)
			(xy 409.114265 -393.718483) (xy 409.113736 -393.692888) (xy 409.113736 -393.69238) (xy 409.114184 -393.668389)
			(xy 409.121693 -393.620999) (xy 409.136524 -393.575366) (xy 409.158311 -393.532616) (xy 409.186518 -393.493801)
			(xy 409.22045 -393.459876) (xy 409.259271 -393.431678) (xy 409.302026 -393.4099) (xy 409.347661 -393.395078)
			(xy 409.395053 -393.387579) (xy 409.419044 -393.387072) (xy 409.419806 -393.387072) (xy 409.429413 -393.386653)
			(xy 409.447285 -393.379595) (xy 409.454604 -393.373356) (xy 409.477464 -393.35202) (xy 409.48473 -393.344519)
			(xy 409.492998 -393.325368) (xy 409.493466 -393.314936) (xy 409.493466 -392.081258) (xy 409.49297 -392.071258)
			(xy 409.485302 -392.052787) (xy 409.471149 -392.038655) (xy 409.452666 -392.031015) (xy 409.442666 -392.030458)
			(xy 397.169894 -392.030458) (xy 397.159826 -392.030884) (xy 397.141228 -392.038606) (xy 397.133826 -392.045444)
			(xy 396.515336 -392.663934) (xy 396.508491 -392.671333) (xy 396.500763 -392.689931) (xy 396.50035 -392.700002)
			(xy 396.50035 -393.692888) (xy 403.113748 -393.692888) (xy 403.113748 -393.69238) (xy 403.114244 -393.66839)
			(xy 403.121752 -393.621002) (xy 403.136579 -393.575372) (xy 403.158361 -393.532622) (xy 403.186562 -393.493805)
			(xy 403.220487 -393.459878) (xy 403.259301 -393.431674) (xy 403.302049 -393.409888) (xy 403.347679 -393.395057)
			(xy 403.395066 -393.387546) (xy 403.419056 -393.387072) (xy 403.442991 -393.387534) (xy 403.490276 -393.394993)
			(xy 403.535819 -393.409735) (xy 403.578505 -393.431399) (xy 403.617291 -393.459456) (xy 403.651226 -393.493218)
			(xy 403.679481 -393.531859) (xy 403.690836 -393.552934) (xy 403.691344 -393.55395) (xy 403.77165 -393.692888)
			(xy 404.313644 -393.692888) (xy 404.313644 -393.69238) (xy 404.314144 -393.668391) (xy 404.321652 -393.621003)
			(xy 404.336479 -393.575373) (xy 404.358261 -393.532623) (xy 404.386461 -393.493807) (xy 404.420386 -393.459879)
			(xy 404.459199 -393.431675) (xy 404.501947 -393.40989) (xy 404.547576 -393.395058) (xy 404.594963 -393.387546)
			(xy 404.618952 -393.387072) (xy 404.642887 -393.387537) (xy 404.690171 -393.394995) (xy 404.735714 -393.409737)
			(xy 404.778401 -393.431401) (xy 404.817187 -393.459457) (xy 404.851122 -393.493218) (xy 404.879377 -393.531859)
			(xy 404.890732 -393.552934) (xy 404.89124 -393.55395) (xy 404.971546 -393.692888) (xy 405.51354 -393.692888)
			(xy 405.51354 -393.69238) (xy 405.51392 -393.668384) (xy 405.521431 -393.620983) (xy 405.536265 -393.575341)
			(xy 405.558057 -393.532582) (xy 405.58627 -393.493758) (xy 405.62021 -393.459826) (xy 405.65904 -393.431622)
			(xy 405.701804 -393.409839) (xy 405.747449 -393.395015) (xy 405.794852 -393.387515) (xy 405.818848 -393.387072)
			(xy 405.842783 -393.387541) (xy 405.890067 -393.394998) (xy 405.93561 -393.409739) (xy 405.978297 -393.431402)
			(xy 406.017082 -393.459458) (xy 406.051018 -393.493219) (xy 406.079273 -393.531859) (xy 406.090628 -393.552934)
			(xy 406.091136 -393.55395) (xy 406.171442 -393.692888) (xy 406.713436 -393.692888) (xy 406.713436 -393.69238)
			(xy 406.713821 -393.668371) (xy 406.72134 -393.620947) (xy 406.736189 -393.575283) (xy 406.758003 -393.532507)
			(xy 406.786244 -393.493672) (xy 406.820215 -393.459737) (xy 406.859079 -393.431537) (xy 406.901877 -393.409767)
			(xy 406.947556 -393.394965) (xy 406.994989 -393.387496) (xy 407.018998 -393.387072) (xy 407.042934 -393.3875)
			(xy 407.090221 -393.394965) (xy 407.135764 -393.409713) (xy 407.178451 -393.431383) (xy 407.217236 -393.459445)
			(xy 407.25117 -393.493212) (xy 407.279424 -393.531857) (xy 407.290778 -393.552934) (xy 407.291286 -393.55395)
			(xy 407.371592 -393.692888) (xy 407.913332 -393.692888) (xy 407.913332 -393.69238) (xy 407.913721 -393.668372)
			(xy 407.92124 -393.620947) (xy 407.936089 -393.575284) (xy 407.957902 -393.532508) (xy 407.986142 -393.493674)
			(xy 408.020113 -393.459738) (xy 408.058976 -393.431538) (xy 408.101775 -393.409769) (xy 408.147453 -393.394966)
			(xy 408.194885 -393.387496) (xy 408.218894 -393.387072) (xy 408.24283 -393.387503) (xy 408.290116 -393.394968)
			(xy 408.33566 -393.409715) (xy 408.378347 -393.431385) (xy 408.417132 -393.459446) (xy 408.451066 -393.493212)
			(xy 408.47932 -393.531857) (xy 408.490674 -393.552934) (xy 408.491182 -393.55395) (xy 408.883612 -394.232892)
			(xy 408.896363 -394.256248) (xy 408.914472 -394.306281) (xy 408.923674 -394.358688) (xy 408.924252 -394.385292)
			(xy 408.92373 -394.409281) (xy 408.916227 -394.456668) (xy 408.901403 -394.502298) (xy 408.879624 -394.545048)
			(xy 408.851427 -394.583865) (xy 408.817504 -394.617793) (xy 408.778692 -394.645997) (xy 408.735946 -394.667783)
			(xy 408.690319 -394.682614) (xy 408.642933 -394.690126) (xy 408.618944 -394.6906) (xy 408.595371 -394.690171)
			(xy 408.548785 -394.682936) (xy 408.503867 -394.668616) (xy 408.461689 -394.647554) (xy 408.423255 -394.620249)
			(xy 408.389482 -394.587355) (xy 408.361175 -394.549654) (xy 408.349704 -394.529056) (xy 408.349196 -394.528294)
			(xy 407.951432 -393.839954) (xy 407.9395 -393.817294) (xy 407.922568 -393.768965) (xy 407.913915 -393.718491)
			(xy 407.913332 -393.692888) (xy 407.371592 -393.692888) (xy 407.683716 -394.232892) (xy 407.696468 -394.256248)
			(xy 407.714576 -394.306281) (xy 407.723778 -394.358688) (xy 407.724356 -394.385292) (xy 407.72383 -394.409281)
			(xy 407.716327 -394.456667) (xy 407.701503 -394.502297) (xy 407.679725 -394.545047) (xy 407.651528 -394.583863)
			(xy 407.617606 -394.617791) (xy 407.578794 -394.645996) (xy 407.536049 -394.667782) (xy 407.490422 -394.682614)
			(xy 407.443037 -394.690126) (xy 407.419048 -394.6906) (xy 407.395475 -394.690168) (xy 407.348889 -394.682933)
			(xy 407.303971 -394.668614) (xy 407.261793 -394.647552) (xy 407.223359 -394.620248) (xy 407.189586 -394.587354)
			(xy 407.161279 -394.549654) (xy 407.149808 -394.529056) (xy 407.1493 -394.528294) (xy 406.751536 -393.839954)
			(xy 406.739605 -393.817294) (xy 406.722672 -393.768964) (xy 406.714019 -393.718491) (xy 406.713436 -393.692888)
			(xy 406.171442 -393.692888) (xy 406.483566 -394.232892) (xy 406.496393 -394.256223) (xy 406.514612 -394.306247)
			(xy 406.523871 -394.358673) (xy 406.52446 -394.385292) (xy 406.524053 -394.4093) (xy 406.516538 -394.456724)
			(xy 406.501693 -394.502388) (xy 406.479882 -394.545164) (xy 406.451644 -394.583999) (xy 406.417675 -394.617935)
			(xy 406.378813 -394.646136) (xy 406.336016 -394.667905) (xy 406.290338 -394.682707) (xy 406.242906 -394.690176)
			(xy 406.218898 -394.6906) (xy 406.195324 -394.690208) (xy 406.148736 -394.682966) (xy 406.103817 -394.66864)
			(xy 406.061639 -394.647571) (xy 406.023206 -394.620261) (xy 405.989434 -394.587361) (xy 405.961128 -394.549656)
			(xy 405.949658 -394.529056) (xy 405.94915 -394.528294) (xy 405.551386 -393.839954) (xy 405.53953 -393.817267)
			(xy 405.522671 -393.768939) (xy 405.51409 -393.718479) (xy 405.51354 -393.692888) (xy 404.971546 -393.692888)
			(xy 405.28367 -394.232892) (xy 405.296497 -394.256223) (xy 405.314716 -394.306247) (xy 405.323975 -394.358673)
			(xy 405.324564 -394.385292) (xy 405.324153 -394.4093) (xy 405.316639 -394.456724) (xy 405.301793 -394.502387)
			(xy 405.279983 -394.545163) (xy 405.251745 -394.583998) (xy 405.217777 -394.617934) (xy 405.178915 -394.646134)
			(xy 405.136118 -394.667904) (xy 405.090441 -394.682706) (xy 405.04301 -394.690176) (xy 405.019002 -394.6906)
			(xy 404.995428 -394.690205) (xy 404.94884 -394.682963) (xy 404.903921 -394.668638) (xy 404.861743 -394.64757)
			(xy 404.82331 -394.62026) (xy 404.789538 -394.587361) (xy 404.761233 -394.549656) (xy 404.749762 -394.529056)
			(xy 404.749254 -394.528294) (xy 404.35149 -393.839954) (xy 404.339634 -393.817267) (xy 404.322775 -393.768939)
			(xy 404.314194 -393.718479) (xy 404.313644 -393.692888) (xy 403.77165 -393.692888) (xy 404.083774 -394.232892)
			(xy 404.096601 -394.256223) (xy 404.11482 -394.306247) (xy 404.124079 -394.358673) (xy 404.124668 -394.385292)
			(xy 404.124253 -394.4093) (xy 404.116739 -394.456723) (xy 404.101893 -394.502386) (xy 404.080083 -394.545162)
			(xy 404.051846 -394.583996) (xy 404.017879 -394.617932) (xy 403.979017 -394.646133) (xy 403.936221 -394.667903)
			(xy 403.890545 -394.682706) (xy 403.843114 -394.690176) (xy 403.819106 -394.6906) (xy 403.795532 -394.690201)
			(xy 403.748944 -394.682961) (xy 403.704026 -394.668636) (xy 403.661847 -394.647568) (xy 403.623414 -394.620259)
			(xy 403.589642 -394.58736) (xy 403.561337 -394.549655) (xy 403.549866 -394.529056) (xy 403.549358 -394.528294)
			(xy 403.151594 -393.839954) (xy 403.139738 -393.817267) (xy 403.122879 -393.768939) (xy 403.114298 -393.718479)
			(xy 403.113748 -393.692888) (xy 396.50035 -393.692888) (xy 396.50035 -394.428726) (xy 396.499776 -394.453685)
			(xy 396.490031 -394.502643) (xy 396.470921 -394.548758) (xy 396.44318 -394.590259) (xy 396.425928 -394.608304)
			(xy 394.862558 -396.171674) (xy 396.529052 -396.171674) (xy 396.529052 -395.308074) (xy 396.529538 -395.280823)
			(xy 396.537294 -395.226875) (xy 396.552649 -395.17458) (xy 396.575291 -395.125003) (xy 396.604757 -395.079153)
			(xy 396.640448 -395.037962) (xy 396.681639 -395.002271) (xy 396.727489 -394.972805) (xy 396.777066 -394.950163)
			(xy 396.829361 -394.934808) (xy 396.883309 -394.927052) (xy 396.937811 -394.927052) (xy 396.991759 -394.934808)
			(xy 397.044054 -394.950163) (xy 397.093631 -394.972805) (xy 397.139481 -395.002271) (xy 397.180672 -395.037962)
			(xy 397.216363 -395.079153) (xy 397.245829 -395.125003) (xy 397.268471 -395.17458) (xy 397.283826 -395.226875)
			(xy 397.291582 -395.280823) (xy 397.292068 -395.308074) (xy 397.292068 -396.171674) (xy 397.291582 -396.198925)
			(xy 397.283826 -396.252873) (xy 397.268471 -396.305168) (xy 397.245829 -396.354745) (xy 397.216363 -396.400595)
			(xy 397.180672 -396.441786) (xy 397.139481 -396.477477) (xy 397.093631 -396.506943) (xy 397.044054 -396.529585)
			(xy 396.991759 -396.54494) (xy 396.937811 -396.552696) (xy 396.883309 -396.552696) (xy 396.829361 -396.54494)
			(xy 396.777066 -396.529585) (xy 396.727489 -396.506943) (xy 396.681639 -396.477477) (xy 396.640448 -396.441786)
			(xy 396.604757 -396.400595) (xy 396.575291 -396.354745) (xy 396.552649 -396.305168) (xy 396.537294 -396.252873)
			(xy 396.529538 -396.198925) (xy 396.529052 -396.171674) (xy 394.862558 -396.171674) (xy 394.7922 -396.242032)
			(xy 394.774158 -396.259288) (xy 394.732662 -396.287037) (xy 394.686544 -396.306141) (xy 394.637582 -396.315863)
			(xy 394.612622 -396.316454) (xy 393.015216 -396.316454) (xy 393.005154 -396.316894) (xy 392.986577 -396.324636)
			(xy 392.979148 -396.33144) (xy 392.735562 -396.575026) (xy 392.717522 -396.592287) (xy 392.676029 -396.620047)
			(xy 392.62991 -396.639163) (xy 392.580946 -396.648897) (xy 392.555984 -396.649448) (xy 384.32613 -396.649448)
			(xy 384.301173 -396.64887) (xy 384.25222 -396.639118) (xy 384.20611 -396.620002) (xy 384.164616 -396.592257)
			(xy 384.146552 -396.575026) (xy 383.943352 -396.371826) (xy 383.916682 -396.364968) (xy 383.90322 -396.369032)
			(xy 383.882585 -396.374608) (xy 383.840264 -396.380595) (xy 383.818892 -396.38097) (xy 383.818384 -396.38097)
			(xy 383.794393 -396.380523) (xy 383.747001 -396.373014) (xy 383.701368 -396.358183) (xy 383.658617 -396.336396)
			(xy 383.619801 -396.30819) (xy 383.585875 -396.274258) (xy 383.557675 -396.235437) (xy 383.535896 -396.192682)
			(xy 383.521074 -396.147046) (xy 383.513573 -396.099653) (xy 383.513076 -396.075662) (xy 383.513076 -396.075154)
			(xy 383.513456 -396.053783) (xy 383.519453 -396.011464) (xy 383.525014 -395.990826) (xy 383.529078 -395.977364)
			(xy 383.52222 -395.950694) (xy 382.85039 -395.278864) (xy 382.842994 -395.272012) (xy 382.824395 -395.264272)
			(xy 382.814322 -395.263878) (xy 382.250696 -395.263878) (xy 382.240626 -395.264301) (xy 382.22202 -395.272014)
			(xy 382.214628 -395.278864) (xy 380.702058 -396.791434) (xy 380.695175 -396.798885) (xy 380.687442 -396.817619)
			(xy 380.687072 -396.827756) (xy 380.687834 -396.91056) (xy 380.695962 -396.929102) (xy 380.703328 -396.936468)
			(xy 380.721266 -396.954414) (xy 380.75153 -396.995136) (xy 380.763526 -397.017494) (xy 380.764034 -397.018764)
			(xy 380.830217 -397.133286) (xy 381.385926 -397.133286) (xy 381.393258 -397.085736) (xy 381.407951 -397.039923)
			(xy 381.429644 -396.996979) (xy 381.457799 -396.957966) (xy 381.49172 -396.923847) (xy 381.53057 -396.895467)
			(xy 381.573388 -396.873527) (xy 381.619116 -396.858569) (xy 381.666622 -396.850962) (xy 381.714734 -396.850896)
			(xy 381.762261 -396.858371) (xy 381.80803 -396.873202) (xy 381.850908 -396.895024) (xy 381.889837 -396.923297)
			(xy 381.923853 -396.957321) (xy 381.952115 -396.996256) (xy 381.963422 -397.017494) (xy 381.96393 -397.018764)
			(xy 382.057097 -397.179979) (xy 382.586212 -397.179979) (xy 382.586461 -397.129044) (xy 382.595154 -397.078856)
			(xy 382.612052 -397.030805) (xy 382.636685 -396.986222) (xy 382.668371 -396.946342) (xy 382.706233 -396.912271)
			(xy 382.749222 -396.884951) (xy 382.796147 -396.86514) (xy 382.845708 -396.853387) (xy 382.896532 -396.850016)
			(xy 382.947211 -396.855122) (xy 382.996341 -396.868563) (xy 383.042561 -396.889967) (xy 383.084591 -396.91874)
			(xy 383.121266 -396.954086) (xy 383.151571 -396.995026) (xy 383.163572 -397.017494) (xy 383.16408 -397.018764)
			(xy 383.257246 -397.179978) (xy 383.786116 -397.179978) (xy 383.786365 -397.129044) (xy 383.795058 -397.078856)
			(xy 383.811955 -397.030806) (xy 383.836588 -396.986224) (xy 383.868274 -396.946345) (xy 383.906135 -396.912274)
			(xy 383.949124 -396.884955) (xy 383.996048 -396.865144) (xy 384.045608 -396.85339) (xy 384.096431 -396.85002)
			(xy 384.147109 -396.855125) (xy 384.196238 -396.868566) (xy 384.242458 -396.889969) (xy 384.284487 -396.918742)
			(xy 384.321162 -396.954087) (xy 384.351467 -396.995026) (xy 384.363468 -397.017494) (xy 384.363976 -397.018764)
			(xy 384.457141 -397.179977) (xy 384.986019 -397.179977) (xy 384.986268 -397.129044) (xy 384.994961 -397.078857)
			(xy 385.011858 -397.030807) (xy 385.036491 -396.986226) (xy 385.068176 -396.946348) (xy 385.106037 -396.912277)
			(xy 385.149025 -396.884958) (xy 385.195948 -396.865147) (xy 385.245508 -396.853394) (xy 385.29633 -396.850023)
			(xy 385.347007 -396.855129) (xy 385.396136 -396.868569) (xy 385.442355 -396.889972) (xy 385.484384 -396.918744)
			(xy 385.521058 -396.954088) (xy 385.551363 -396.995026) (xy 385.563364 -397.017494) (xy 385.563872 -397.018764)
			(xy 385.630054 -397.133285) (xy 386.186033 -397.133285) (xy 386.193365 -397.085737) (xy 386.208058 -397.039925)
			(xy 386.22975 -396.996982) (xy 386.257904 -396.95797) (xy 386.291825 -396.923853) (xy 386.330673 -396.895474)
			(xy 386.37349 -396.873534) (xy 386.419216 -396.858576) (xy 386.466721 -396.85097) (xy 386.514831 -396.850903)
			(xy 386.562358 -396.858377) (xy 386.608125 -396.873208) (xy 386.651002 -396.895029) (xy 386.68993 -396.9233)
			(xy 386.723945 -396.957323) (xy 386.752207 -396.996257) (xy 386.763514 -397.017494) (xy 386.764022 -397.018764)
			(xy 386.830204 -397.133285) (xy 387.385937 -397.133285) (xy 387.393268 -397.085737) (xy 387.407961 -397.039926)
			(xy 387.429653 -396.996984) (xy 387.457807 -396.957973) (xy 387.491727 -396.923856) (xy 387.530575 -396.895477)
			(xy 387.573391 -396.873537) (xy 387.619116 -396.85858) (xy 387.666621 -396.850973) (xy 387.71473 -396.850906)
			(xy 387.762256 -396.85838) (xy 387.808023 -396.873211) (xy 387.850899 -396.895031) (xy 387.889826 -396.923302)
			(xy 387.923841 -396.957324) (xy 387.952103 -396.996257) (xy 387.96341 -397.017494) (xy 387.963918 -397.018764)
			(xy 388.057083 -397.179976) (xy 388.586223 -397.179976) (xy 388.586472 -397.129043) (xy 388.595165 -397.078858)
			(xy 388.612062 -397.030809) (xy 388.636694 -396.986228) (xy 388.668379 -396.94635) (xy 388.706239 -396.91228)
			(xy 388.749226 -396.884961) (xy 388.796149 -396.865151) (xy 388.845707 -396.853397) (xy 388.896529 -396.850027)
			(xy 388.947206 -396.855132) (xy 388.996334 -396.868572) (xy 389.042552 -396.889974) (xy 389.08458 -396.918746)
			(xy 389.121255 -396.95409) (xy 389.151559 -396.995027) (xy 389.16356 -397.017494) (xy 389.164068 -397.018764)
			(xy 389.24392 -397.15694) (xy 403.113748 -397.15694) (xy 403.113748 -397.156432) (xy 403.114292 -397.132444)
			(xy 403.121792 -397.085057) (xy 403.136612 -397.039428) (xy 403.158388 -396.996678) (xy 403.186583 -396.957861)
			(xy 403.220503 -396.923933) (xy 403.259313 -396.895728) (xy 403.302057 -396.873941) (xy 403.347683 -396.85911)
			(xy 403.395068 -396.851598) (xy 403.419056 -396.851124) (xy 403.442992 -396.851558) (xy 403.49028 -396.859018)
			(xy 403.535825 -396.873763) (xy 403.578513 -396.895431) (xy 403.617298 -396.923493) (xy 403.651232 -396.957261)
			(xy 403.679483 -396.995908) (xy 403.690836 -397.016986) (xy 403.691344 -397.018002) (xy 403.77165 -397.15694)
			(xy 404.313644 -397.15694) (xy 404.313644 -397.156432) (xy 404.314192 -397.132444) (xy 404.321692 -397.085058)
			(xy 404.336512 -397.039429) (xy 404.358287 -396.996679) (xy 404.386482 -396.957862) (xy 404.420401 -396.923934)
			(xy 404.459211 -396.895729) (xy 404.501955 -396.873943) (xy 404.54758 -396.859111) (xy 404.594964 -396.851598)
			(xy 404.618952 -396.851124) (xy 404.642888 -396.851561) (xy 404.690176 -396.859021) (xy 404.735721 -396.873765)
			(xy 404.778408 -396.895433) (xy 404.817194 -396.923494) (xy 404.851128 -396.957261) (xy 404.879379 -396.995908)
			(xy 404.890732 -397.016986) (xy 404.89124 -397.018002) (xy 404.971546 -397.15694) (xy 405.51354 -397.15694)
			(xy 405.51354 -397.156432) (xy 405.513968 -397.132437) (xy 405.521471 -397.085038) (xy 405.536298 -397.039397)
			(xy 405.558084 -396.996638) (xy 405.586291 -396.957814) (xy 405.620226 -396.923881) (xy 405.659051 -396.895676)
			(xy 405.701812 -396.873892) (xy 405.747454 -396.859068) (xy 405.794853 -396.851567) (xy 405.818848 -396.851124)
			(xy 405.842784 -396.851565) (xy 405.890071 -396.859024) (xy 405.935616 -396.873767) (xy 405.978304 -396.895434)
			(xy 406.01709 -396.923495) (xy 406.051024 -396.957262) (xy 406.079275 -396.995908) (xy 406.090628 -397.016986)
			(xy 406.091136 -397.018002) (xy 406.171442 -397.15694) (xy 406.713436 -397.15694) (xy 406.713436 -397.156432)
			(xy 406.713869 -397.132425) (xy 406.72138 -397.085002) (xy 406.736222 -397.039339) (xy 406.75803 -396.996563)
			(xy 406.786264 -396.957728) (xy 406.82023 -396.923791) (xy 406.85909 -396.89559) (xy 406.901885 -396.87382)
			(xy 406.947561 -396.859018) (xy 406.99499 -396.851548) (xy 407.018998 -396.851124) (xy 407.042935 -396.851524)
			(xy 407.090225 -396.858991) (xy 407.135771 -396.873741) (xy 407.178458 -396.895415) (xy 407.217243 -396.923482)
			(xy 407.251176 -396.957255) (xy 407.279426 -396.995906) (xy 407.290778 -397.016986) (xy 407.291286 -397.018002)
			(xy 407.371592 -397.15694) (xy 407.913332 -397.15694) (xy 407.913332 -397.156432) (xy 407.913769 -397.132425)
			(xy 407.92128 -397.085002) (xy 407.936122 -397.03934) (xy 407.957929 -396.996564) (xy 407.986163 -396.957729)
			(xy 408.020129 -396.923793) (xy 408.058988 -396.895592) (xy 408.101783 -396.873822) (xy 408.147458 -396.859019)
			(xy 408.194887 -396.851548) (xy 408.218894 -396.851124) (xy 408.242831 -396.851527) (xy 408.29012 -396.858993)
			(xy 408.335666 -396.873744) (xy 408.378354 -396.895417) (xy 408.417139 -396.923483) (xy 408.451072 -396.957255)
			(xy 408.479322 -396.995906) (xy 408.490674 -397.016986) (xy 408.491182 -397.018002) (xy 408.571488 -397.15694)
			(xy 409.113736 -397.15694) (xy 409.113736 -397.156432) (xy 409.114168 -397.132438) (xy 409.121671 -397.085039)
			(xy 409.136498 -397.039398) (xy 409.158283 -396.996639) (xy 409.18649 -396.957815) (xy 409.220424 -396.923882)
			(xy 409.259249 -396.895677) (xy 409.302009 -396.873893) (xy 409.347651 -396.859068) (xy 409.39505 -396.851567)
			(xy 409.419044 -396.851124) (xy 409.44298 -396.851568) (xy 409.490267 -396.859026) (xy 409.535812 -396.873769)
			(xy 409.5785 -396.895436) (xy 409.617285 -396.923496) (xy 409.651219 -396.957262) (xy 409.679471 -396.995909)
			(xy 409.690824 -397.016986) (xy 409.691332 -397.018002) (xy 410.083762 -397.696944) (xy 410.09657 -397.720285)
			(xy 410.114796 -397.770304) (xy 410.124063 -397.822726) (xy 410.124656 -397.849344) (xy 410.124202 -397.873349)
			(xy 410.116682 -397.920765) (xy 410.101835 -397.966421) (xy 410.080026 -398.009191) (xy 410.051793 -398.048022)
			(xy 410.017831 -398.081956) (xy 409.978978 -398.110157) (xy 409.93619 -398.131931) (xy 409.890522 -398.14674)
			(xy 409.843099 -398.154221) (xy 409.819094 -398.154652) (xy 409.795521 -398.154236) (xy 409.748935 -398.146995)
			(xy 409.704019 -398.132671) (xy 409.661841 -398.111605) (xy 409.623408 -398.0843) (xy 409.589635 -398.051405)
			(xy 409.561327 -398.013705) (xy 409.549854 -397.993108) (xy 409.549346 -397.992346) (xy 409.151582 -397.304006)
			(xy 409.139708 -397.281328) (xy 409.122856 -397.232996) (xy 409.114282 -397.182533) (xy 409.113736 -397.15694)
			(xy 408.571488 -397.15694) (xy 408.883612 -397.696944) (xy 408.896345 -397.720309) (xy 408.91446 -397.770337)
			(xy 408.92367 -397.822741) (xy 408.924252 -397.849344) (xy 408.923778 -397.873334) (xy 408.916267 -397.920723)
			(xy 408.901436 -397.966354) (xy 408.879651 -398.009104) (xy 408.851448 -398.04792) (xy 408.81752 -398.081848)
			(xy 408.778704 -398.110051) (xy 408.735954 -398.131836) (xy 408.690323 -398.146667) (xy 408.642934 -398.154178)
			(xy 408.618944 -398.154652) (xy 408.595373 -398.154195) (xy 408.548789 -398.146962) (xy 408.503873 -398.132645)
			(xy 408.461696 -398.111586) (xy 408.423262 -398.084287) (xy 408.389488 -398.051398) (xy 408.361178 -398.013703)
			(xy 408.349704 -397.993108) (xy 408.349196 -397.992346) (xy 407.951432 -397.304006) (xy 407.939519 -397.281336)
			(xy 407.92258 -397.233012) (xy 407.91392 -397.182542) (xy 407.913332 -397.15694) (xy 407.371592 -397.15694)
			(xy 407.683716 -397.696944) (xy 407.69645 -397.720309) (xy 407.714565 -397.770337) (xy 407.723774 -397.822741)
			(xy 407.724356 -397.849344) (xy 407.723878 -397.873334) (xy 407.716367 -397.920723) (xy 407.701536 -397.966353)
			(xy 407.679752 -398.009103) (xy 407.651549 -398.047919) (xy 407.617622 -398.081846) (xy 407.578806 -398.11005)
			(xy 407.536057 -398.131835) (xy 407.490427 -398.146666) (xy 407.443038 -398.154178) (xy 407.419048 -398.154652)
			(xy 407.395477 -398.154192) (xy 407.348893 -398.146959) (xy 407.303977 -398.132643) (xy 407.2618 -398.111585)
			(xy 407.223366 -398.084286) (xy 407.189592 -398.051398) (xy 407.161282 -398.013703) (xy 407.149808 -397.993108)
			(xy 407.1493 -397.992346) (xy 406.751536 -397.304006) (xy 406.739623 -397.281336) (xy 406.722684 -397.233012)
			(xy 406.714024 -397.182542) (xy 406.713436 -397.15694) (xy 406.171442 -397.15694) (xy 406.483566 -397.696944)
			(xy 406.496375 -397.720285) (xy 406.5146 -397.770303) (xy 406.523867 -397.822726) (xy 406.52446 -397.849344)
			(xy 406.524101 -397.873353) (xy 406.516579 -397.92078) (xy 406.501726 -397.966444) (xy 406.479909 -398.00922)
			(xy 406.451665 -398.048055) (xy 406.417691 -398.08199) (xy 406.378825 -398.11019) (xy 406.336023 -398.131958)
			(xy 406.290342 -398.146759) (xy 406.242908 -398.154228) (xy 406.218898 -398.154652) (xy 406.195325 -398.154232)
			(xy 406.14874 -398.146992) (xy 406.103823 -398.132669) (xy 406.061646 -398.111604) (xy 406.023213 -398.084299)
			(xy 405.989439 -398.051405) (xy 405.961131 -398.013705) (xy 405.949658 -397.993108) (xy 405.94915 -397.992346)
			(xy 405.551386 -397.304006) (xy 405.539512 -397.281328) (xy 405.52266 -397.232996) (xy 405.514086 -397.182533)
			(xy 405.51354 -397.15694) (xy 404.971546 -397.15694) (xy 405.28367 -397.696944) (xy 405.296479 -397.720285)
			(xy 405.314704 -397.770303) (xy 405.323971 -397.822726) (xy 405.324564 -397.849344) (xy 405.324201 -397.873353)
			(xy 405.316679 -397.920779) (xy 405.301826 -397.966443) (xy 405.280009 -398.009219) (xy 405.251766 -398.048053)
			(xy 405.217793 -398.081989) (xy 405.178927 -398.110188) (xy 405.136126 -398.131957) (xy 405.090446 -398.146759)
			(xy 405.043012 -398.154228) (xy 405.019002 -398.154652) (xy 404.995429 -398.154229) (xy 404.948844 -398.14699)
			(xy 404.903927 -398.132667) (xy 404.86175 -398.111602) (xy 404.823317 -398.084298) (xy 404.789544 -398.051404)
			(xy 404.761235 -398.013705) (xy 404.749762 -397.993108) (xy 404.749254 -397.992346) (xy 404.35149 -397.304006)
			(xy 404.339616 -397.281328) (xy 404.322764 -397.232995) (xy 404.31419 -397.182533) (xy 404.313644 -397.15694)
			(xy 403.77165 -397.15694) (xy 404.083774 -397.696944) (xy 404.096583 -397.720284) (xy 404.114808 -397.770303)
			(xy 404.124075 -397.822726) (xy 404.124668 -397.849344) (xy 404.124301 -397.873353) (xy 404.116779 -397.920778)
			(xy 404.101926 -397.966442) (xy 404.08011 -398.009218) (xy 404.051867 -398.048052) (xy 404.017895 -398.081987)
			(xy 403.979029 -398.110187) (xy 403.936229 -398.131956) (xy 403.890549 -398.146758) (xy 403.843116 -398.154228)
			(xy 403.819106 -398.154652) (xy 403.795534 -398.154226) (xy 403.748948 -398.146987) (xy 403.704032 -398.132665)
			(xy 403.661854 -398.111601) (xy 403.623421 -398.084297) (xy 403.589648 -398.051404) (xy 403.561339 -398.013705)
			(xy 403.549866 -397.993108) (xy 403.549358 -397.992346) (xy 403.151594 -397.304006) (xy 403.139721 -397.281328)
			(xy 403.122868 -397.232995) (xy 403.114294 -397.182532) (xy 403.113748 -397.15694) (xy 389.24392 -397.15694)
			(xy 389.55599 -397.696944) (xy 389.556244 -397.697452) (xy 389.556498 -397.697452) (xy 389.557768 -397.699992)
			(xy 389.570036 -397.722909) (xy 389.587445 -397.771886) (xy 389.59632 -397.823102) (xy 389.596884 -397.84909)
			(xy 389.596884 -397.849344) (xy 389.596501 -397.873352) (xy 389.588979 -397.920776) (xy 389.574128 -397.966438)
			(xy 389.552313 -398.009213) (xy 389.524072 -398.048046) (xy 389.490101 -398.081981) (xy 389.451238 -398.110181)
			(xy 389.40844 -398.131951) (xy 389.362762 -398.146755) (xy 389.315331 -398.154227) (xy 389.291322 -398.154652)
			(xy 389.267658 -398.154195) (xy 389.220898 -398.146888) (xy 389.175823 -398.13246) (xy 389.133511 -398.111257)
			(xy 389.094972 -398.083784) (xy 389.061129 -398.0507) (xy 389.032791 -398.012795) (xy 389.02132 -397.992092)
			(xy 389.021066 -397.99133) (xy 388.62381 -397.304006) (xy 388.611629 -397.280791) (xy 388.594516 -397.231239)
			(xy 388.589774 -397.205454) (xy 388.589774 -397.2052) (xy 388.586223 -397.179976) (xy 388.057083 -397.179976)
			(xy 388.35584 -397.696944) (xy 388.356094 -397.697452) (xy 388.356348 -397.697452) (xy 388.357618 -397.699992)
			(xy 388.369851 -397.722916) (xy 388.387171 -397.771902) (xy 388.395958 -397.823111) (xy 388.39648 -397.84909)
			(xy 388.39648 -397.849344) (xy 388.396078 -397.873338) (xy 388.388564 -397.920734) (xy 388.373729 -397.966371)
			(xy 388.351938 -398.009125) (xy 388.323726 -398.047945) (xy 388.28979 -398.081873) (xy 388.250964 -398.110075)
			(xy 388.208204 -398.131857) (xy 388.162564 -398.146681) (xy 388.115166 -398.154184) (xy 388.091172 -398.154652)
			(xy 388.06751 -398.154155) (xy 388.020751 -398.146855) (xy 387.975677 -398.132434) (xy 387.933365 -398.111238)
			(xy 387.894826 -398.083772) (xy 387.860982 -398.050693) (xy 387.832641 -398.012793) (xy 387.82117 -397.992092)
			(xy 387.820916 -397.99133) (xy 387.42366 -397.304006) (xy 387.411482 -397.280789) (xy 387.394366 -397.231239)
			(xy 387.389624 -397.205454) (xy 387.389624 -397.2052) (xy 387.386148 -397.181394) (xy 387.385937 -397.133285)
			(xy 386.830204 -397.133285) (xy 387.155944 -397.696944) (xy 387.156198 -397.697452) (xy 387.156452 -397.697452)
			(xy 387.157722 -397.699992) (xy 387.169955 -397.722916) (xy 387.187275 -397.771902) (xy 387.196062 -397.823111)
			(xy 387.196584 -397.84909) (xy 387.196584 -397.849344) (xy 387.196178 -397.873338) (xy 387.188664 -397.920733)
			(xy 387.17383 -397.96637) (xy 387.152038 -398.009124) (xy 387.123828 -398.047943) (xy 387.089892 -398.081872)
			(xy 387.051066 -398.110074) (xy 387.008307 -398.131856) (xy 386.962667 -398.14668) (xy 386.91527 -398.154183)
			(xy 386.891276 -398.154652) (xy 386.867611 -398.154232) (xy 386.820849 -398.146918) (xy 386.775773 -398.132483)
			(xy 386.733461 -398.111274) (xy 386.694923 -398.083796) (xy 386.661081 -398.050707) (xy 386.632744 -398.012797)
			(xy 386.621274 -397.992092) (xy 386.62102 -397.99133) (xy 386.223764 -397.304006) (xy 386.211586 -397.280789)
			(xy 386.19447 -397.231239) (xy 386.189728 -397.205454) (xy 386.189728 -397.2052) (xy 386.186245 -397.181395)
			(xy 386.186033 -397.133285) (xy 385.630054 -397.133285) (xy 385.955794 -397.696944) (xy 385.956048 -397.697452)
			(xy 385.956302 -397.697452) (xy 385.957572 -397.699992) (xy 385.969841 -397.722909) (xy 385.987249 -397.771886)
			(xy 385.996124 -397.823102) (xy 385.996688 -397.84909) (xy 385.996688 -397.849344) (xy 385.996301 -397.873352)
			(xy 385.98878 -397.920775) (xy 385.973928 -397.966437) (xy 385.952114 -398.009212) (xy 385.923873 -398.048045)
			(xy 385.889903 -398.08198) (xy 385.85104 -398.11018) (xy 385.808243 -398.13195) (xy 385.762566 -398.146754)
			(xy 385.715134 -398.154226) (xy 385.691126 -398.154652) (xy 385.667462 -398.154192) (xy 385.620702 -398.146885)
			(xy 385.575627 -398.132458) (xy 385.533315 -398.111255) (xy 385.494777 -398.083783) (xy 385.460934 -398.0507)
			(xy 385.432595 -398.012795) (xy 385.421124 -397.992092) (xy 385.42087 -397.99133) (xy 385.023614 -397.304006)
			(xy 385.011433 -397.28079) (xy 384.99432 -397.231239) (xy 384.989578 -397.205454) (xy 384.989578 -397.2052)
			(xy 384.986019 -397.179977) (xy 384.457141 -397.179977) (xy 384.755898 -397.696944) (xy 384.756152 -397.697452)
			(xy 384.756406 -397.697452) (xy 384.757676 -397.699992) (xy 384.769945 -397.722909) (xy 384.787353 -397.771886)
			(xy 384.796228 -397.823102) (xy 384.796792 -397.84909) (xy 384.796792 -397.849344) (xy 384.796401 -397.873352)
			(xy 384.78888 -397.920775) (xy 384.774029 -397.966436) (xy 384.752214 -398.009211) (xy 384.723974 -398.048044)
			(xy 384.690005 -398.081979) (xy 384.651142 -398.110179) (xy 384.608346 -398.131949) (xy 384.562669 -398.146753)
			(xy 384.515238 -398.154226) (xy 384.49123 -398.154652) (xy 384.467566 -398.154188) (xy 384.420807 -398.146882)
			(xy 384.375732 -398.132456) (xy 384.333419 -398.111254) (xy 384.294881 -398.083782) (xy 384.261038 -398.050699)
			(xy 384.232699 -398.012794) (xy 384.221228 -397.992092) (xy 384.220974 -397.99133) (xy 383.823718 -397.304006)
			(xy 383.811537 -397.28079) (xy 383.794424 -397.231239) (xy 383.789682 -397.205454) (xy 383.789682 -397.2052)
			(xy 383.786116 -397.179978) (xy 383.257246 -397.179978) (xy 383.556002 -397.696944) (xy 383.556256 -397.697452)
			(xy 383.55651 -397.697452) (xy 383.55778 -397.699992) (xy 383.570049 -397.722909) (xy 383.587457 -397.771886)
			(xy 383.596332 -397.823102) (xy 383.596896 -397.84909) (xy 383.596896 -397.849344) (xy 383.596501 -397.873352)
			(xy 383.58898 -397.920774) (xy 383.574129 -397.966435) (xy 383.552315 -398.009209) (xy 383.524075 -398.048042)
			(xy 383.490106 -398.081977) (xy 383.451245 -398.110177) (xy 383.408448 -398.131948) (xy 383.362772 -398.146752)
			(xy 383.315342 -398.154226) (xy 383.291334 -398.154652) (xy 383.267671 -398.154185) (xy 383.220911 -398.14688)
			(xy 383.175836 -398.132454) (xy 383.133524 -398.111252) (xy 383.094985 -398.083781) (xy 383.061142 -398.050699)
			(xy 383.032803 -398.012794) (xy 383.021332 -397.992092) (xy 383.021078 -397.99133) (xy 382.623822 -397.304006)
			(xy 382.611641 -397.28079) (xy 382.594528 -397.231239) (xy 382.589786 -397.205454) (xy 382.589786 -397.2052)
			(xy 382.586212 -397.179979) (xy 382.057097 -397.179979) (xy 382.355852 -397.696944) (xy 382.356106 -397.697452)
			(xy 382.35636 -397.697452) (xy 382.35763 -397.699992) (xy 382.369864 -397.722916) (xy 382.387183 -397.771902)
			(xy 382.395971 -397.823111) (xy 382.396492 -397.84909) (xy 382.396492 -397.849344) (xy 382.396078 -397.873337)
			(xy 382.388565 -397.920732) (xy 382.37373 -397.966368) (xy 382.35194 -398.009122) (xy 382.32373 -398.047941)
			(xy 382.289795 -398.081869) (xy 382.250971 -398.110071) (xy 382.208212 -398.131853) (xy 382.162574 -398.146679)
			(xy 382.115177 -398.154183) (xy 382.091184 -398.154652) (xy 382.067519 -398.154226) (xy 382.020757 -398.146913)
			(xy 381.975682 -398.132479) (xy 381.933369 -398.111271) (xy 381.894832 -398.083794) (xy 381.860989 -398.050706)
			(xy 381.832652 -398.012796) (xy 381.821182 -397.992092) (xy 381.820928 -397.99133) (xy 381.423672 -397.304006)
			(xy 381.411495 -397.280788) (xy 381.394379 -397.231238) (xy 381.389636 -397.205454) (xy 381.389636 -397.2052)
			(xy 381.386138 -397.181397) (xy 381.385926 -397.133286) (xy 380.830217 -397.133286) (xy 381.155956 -397.696944)
			(xy 381.15621 -397.697452) (xy 381.156464 -397.697452) (xy 381.157734 -397.699992) (xy 381.169965 -397.722918)
			(xy 381.187296 -397.7719) (xy 381.196081 -397.823111) (xy 381.196596 -397.84909) (xy 381.196596 -397.849344)
			(xy 381.196122 -397.873333) (xy 381.18861 -397.920718) (xy 381.173779 -397.966346) (xy 381.151993 -398.009091)
			(xy 381.123789 -398.047903) (xy 381.08986 -398.081825) (xy 381.051044 -398.110022) (xy 381.008294 -398.1318)
			(xy 380.962664 -398.146624) (xy 380.915277 -398.154126) (xy 380.891288 -398.154652) (xy 380.867624 -398.154207)
			(xy 380.820862 -398.146905) (xy 380.775787 -398.132478) (xy 380.733476 -398.111271) (xy 380.694942 -398.083792)
			(xy 380.661108 -398.050698) (xy 380.632783 -398.012781) (xy 380.621286 -397.992092) (xy 380.621032 -397.99133)
			(xy 380.223776 -397.304006) (xy 380.211588 -397.280794) (xy 380.194479 -397.23124) (xy 380.18974 -397.205454)
			(xy 380.18974 -397.2052) (xy 380.186347 -397.181838) (xy 380.185969 -397.134634) (xy 380.188978 -397.11122)
			(xy 380.190248 -397.10233) (xy 380.186946 -397.085058) (xy 380.143258 -397.013938) (xy 380.129542 -397.002762)
			(xy 380.120906 -396.999968) (xy 380.097985 -396.991718) (xy 380.054902 -396.968989) (xy 380.015973 -396.939708)
			(xy 379.998732 -396.922498) (xy 379.991281 -396.915445) (xy 379.972406 -396.907452) (xy 379.962156 -396.907004)
			(xy 379.617478 -396.907004) (xy 379.608309 -396.907387) (xy 379.591155 -396.913866) (xy 379.577417 -396.926011)
			(xy 379.572774 -396.933928) (xy 379.55855 -396.960598) (xy 379.555749 -396.966167) (xy 379.552669 -396.978244)
			(xy 379.552454 -396.984474) (xy 379.558804 -397.008858) (xy 379.563376 -397.017494) (xy 379.563884 -397.018764)
			(xy 379.955806 -397.696944) (xy 379.95606 -397.697452) (xy 379.956314 -397.697452) (xy 379.957584 -397.699992)
			(xy 379.969852 -397.722909) (xy 379.98726 -397.771885) (xy 379.996127 -397.823102) (xy 379.9967 -397.84909)
			(xy 379.9967 -397.849344) (xy 379.996227 -397.87332) (xy 379.988723 -397.920682) (xy 379.973907 -397.966288)
			(xy 379.952144 -398.009016) (xy 379.923967 -398.047817) (xy 379.890071 -398.081736) (xy 379.851289 -398.109938)
			(xy 379.808574 -398.13173) (xy 379.762978 -398.146576) (xy 379.715622 -398.154111) (xy 379.691646 -398.154652)
			(xy 379.691138 -398.154652) (xy 379.667472 -398.154211) (xy 379.620706 -398.146915) (xy 379.575624 -398.132493)
			(xy 379.533307 -398.11129) (xy 379.494767 -398.083813) (xy 379.460927 -398.05072) (xy 379.432597 -398.012803)
			(xy 379.421136 -397.992092) (xy 379.420882 -397.99133) (xy 379.023626 -397.304006) (xy 379.011439 -397.280793)
			(xy 378.994334 -397.231239) (xy 378.98959 -397.205454) (xy 378.98959 -397.2052) (xy 378.986198 -397.181838)
			(xy 378.985819 -397.134634) (xy 378.988828 -397.11122) (xy 378.990352 -397.10233) (xy 378.986796 -397.084804)
			(xy 378.943362 -397.013938) (xy 378.929392 -397.002762) (xy 378.92101 -396.999968) (xy 378.898089 -396.991718)
			(xy 378.855005 -396.96899) (xy 378.816076 -396.939709) (xy 378.798836 -396.922498) (xy 378.791385 -396.915445)
			(xy 378.77251 -396.90745) (xy 378.76226 -396.907004) (xy 378.417582 -396.907004) (xy 378.408413 -396.907386)
			(xy 378.391258 -396.913865) (xy 378.377518 -396.926009) (xy 378.372878 -396.933928) (xy 378.358654 -396.960598)
			(xy 378.355853 -396.966167) (xy 378.352773 -396.978244) (xy 378.352558 -396.984474) (xy 378.358908 -397.008858)
			(xy 378.36348 -397.017494) (xy 378.363988 -397.018764) (xy 378.75591 -397.696944) (xy 378.756164 -397.697452)
			(xy 378.756418 -397.697452) (xy 378.757688 -397.699992) (xy 378.769956 -397.722909) (xy 378.787364 -397.771886)
			(xy 378.796231 -397.823102) (xy 378.796804 -397.84909) (xy 378.796804 -397.849344) (xy 378.796331 -397.87332)
			(xy 378.788827 -397.920682) (xy 378.774011 -397.966288) (xy 378.752248 -398.009017) (xy 378.724071 -398.047818)
			(xy 378.690175 -398.081737) (xy 378.651393 -398.10994) (xy 378.608679 -398.131733) (xy 378.563082 -398.146579)
			(xy 378.515726 -398.154115) (xy 378.49175 -398.154652) (xy 378.491242 -398.154652) (xy 378.467576 -398.154211)
			(xy 378.420809 -398.146916) (xy 378.375727 -398.132495) (xy 378.33341 -398.111292) (xy 378.294869 -398.083815)
			(xy 378.261029 -398.050721) (xy 378.232698 -398.012804) (xy 378.22124 -397.992092) (xy 378.220986 -397.99133)
			(xy 377.82373 -397.304006) (xy 377.811543 -397.280793) (xy 377.794437 -397.231239) (xy 377.789694 -397.205454)
			(xy 377.789694 -397.2052) (xy 377.786302 -397.181838) (xy 377.785923 -397.134634) (xy 377.788932 -397.11122)
			(xy 377.790202 -397.10233) (xy 377.7869 -397.085058) (xy 377.743212 -397.013938) (xy 377.729496 -397.002762)
			(xy 377.72086 -396.999968) (xy 377.699778 -396.992469) (xy 377.659901 -396.97217) (xy 377.623418 -396.946262)
			(xy 377.591114 -396.915301) (xy 377.577096 -396.89786) (xy 377.558554 -396.882874) (xy 377.538837 -396.873095)
			(xy 377.502825 -396.847801) (xy 377.486926 -396.832582) (xy 377.004072 -396.349728) (xy 376.986814 -396.331687)
			(xy 376.959059 -396.290193) (xy 376.93995 -396.244074) (xy 376.930222 -396.195111) (xy 376.92965 -396.17015)
			(xy 376.92965 -394.382752) (xy 376.92945 -394.376086) (xy 376.925967 -394.363218) (xy 376.922792 -394.357352)
			(xy 376.623834 -393.839954) (xy 376.61194 -393.817284) (xy 376.595075 -393.768953) (xy 376.586523 -393.718483)
			(xy 376.585988 -393.692888) (xy 376.585988 -393.69238) (xy 376.586494 -393.667314) (xy 376.594682 -393.617855)
			(xy 376.610835 -393.570397) (xy 376.634519 -393.526212) (xy 376.665098 -393.486487) (xy 376.701753 -393.452288)
			(xy 376.7435 -393.424531) (xy 376.789218 -393.403963) (xy 376.83768 -393.391134) (xy 376.862594 -393.388342)
			(xy 376.871535 -393.387118) (xy 376.88779 -393.379306) (xy 376.894344 -393.373102) (xy 376.915426 -393.351004)
			(xy 376.921882 -393.34371) (xy 376.929216 -393.325682) (xy 376.92965 -393.315952) (xy 376.92965 -392.60526)
			(xy 376.929218 -392.595194) (xy 376.921488 -392.576605) (xy 376.914664 -392.569192) (xy 376.728736 -392.383264)
			(xy 376.721337 -392.376421) (xy 376.702738 -392.368699) (xy 376.692668 -392.368278) (xy 367.482882 -392.368278)
			(xy 367.445798 -392.384534) (xy 367.427667 -392.403444) (xy 367.387123 -392.436619) (xy 367.342424 -392.46394)
			(xy 367.294409 -392.484892) (xy 367.243979 -392.499082) (xy 367.192084 -392.506244) (xy 367.16589 -392.506708)
			(xy 367.139459 -392.506258) (xy 367.087103 -392.498958) (xy 367.036256 -392.4845) (xy 366.987892 -392.463161)
			(xy 366.942938 -392.435348) (xy 366.922304 -392.418824) (xy 366.915068 -392.413294) (xy 366.897882 -392.407308)
			(xy 366.888776 -392.40714) (xy 366.85855 -392.407902) (xy 366.848819 -392.408574) (xy 366.830915 -392.41627)
			(xy 366.823752 -392.422888) (xy 366.62868 -392.61796) (xy 366.621834 -392.625358) (xy 366.614109 -392.643957)
			(xy 366.613694 -392.654028) (xy 366.613694 -393.692888) (xy 370.586 -393.692888) (xy 370.586 -393.69238)
			(xy 370.586444 -393.668388) (xy 370.593954 -393.620995) (xy 370.608784 -393.57536) (xy 370.630571 -393.532606)
			(xy 370.658777 -393.493788) (xy 370.692709 -393.459859) (xy 370.73153 -393.431656) (xy 370.774286 -393.409873)
			(xy 370.819922 -393.395047) (xy 370.867316 -393.387542) (xy 370.891308 -393.387072) (xy 370.915241 -393.387573)
			(xy 370.962524 -393.395024) (xy 371.008067 -393.409759) (xy 371.050753 -393.431417) (xy 371.089539 -393.459468)
			(xy 371.123476 -393.493224) (xy 371.151732 -393.531861) (xy 371.163088 -393.552934) (xy 371.163596 -393.55395)
			(xy 371.243902 -393.692888) (xy 371.785896 -393.692888) (xy 371.785896 -393.69238) (xy 371.786344 -393.668388)
			(xy 371.793853 -393.620995) (xy 371.808684 -393.575361) (xy 371.83047 -393.532608) (xy 371.858676 -393.493789)
			(xy 371.892607 -393.459861) (xy 371.931428 -393.431658) (xy 371.974183 -393.409875) (xy 372.019819 -393.395048)
			(xy 372.067212 -393.387542) (xy 372.091204 -393.387072) (xy 372.115137 -393.387576) (xy 372.16242 -393.395027)
			(xy 372.207962 -393.409762) (xy 372.250649 -393.431419) (xy 372.289435 -393.459469) (xy 372.323372 -393.493225)
			(xy 372.351628 -393.531861) (xy 372.362984 -393.552934) (xy 372.363492 -393.55395) (xy 372.443798 -393.692888)
			(xy 372.985792 -393.692888) (xy 372.985792 -393.69238) (xy 372.986244 -393.668388) (xy 372.993753 -393.620996)
			(xy 373.008583 -393.575362) (xy 373.030369 -393.532609) (xy 373.058575 -393.49379) (xy 373.092506 -393.459862)
			(xy 373.131326 -393.431659) (xy 373.17408 -393.409876) (xy 373.219715 -393.395049) (xy 373.267108 -393.387543)
			(xy 373.2911 -393.387072) (xy 373.315033 -393.38758) (xy 373.362316 -393.39503) (xy 373.407858 -393.409764)
			(xy 373.450544 -393.43142) (xy 373.489331 -393.45947) (xy 373.523268 -393.493226) (xy 373.551524 -393.531862)
			(xy 373.56288 -393.552934) (xy 373.563388 -393.55395) (xy 373.643694 -393.692888) (xy 374.185688 -393.692888)
			(xy 374.185688 -393.69238) (xy 374.186121 -393.668374) (xy 374.193638 -393.620954) (xy 374.208485 -393.575294)
			(xy 374.230294 -393.532521) (xy 374.25853 -393.493689) (xy 374.292494 -393.459754) (xy 374.331352 -393.431553)
			(xy 374.374144 -393.409781) (xy 374.419817 -393.394975) (xy 374.467243 -393.3875) (xy 374.49125 -393.387072)
			(xy 374.515185 -393.387539) (xy 374.562469 -393.394997) (xy 374.608012 -393.409738) (xy 374.650699 -393.431401)
			(xy 374.689484 -393.459457) (xy 374.72342 -393.493218) (xy 374.751675 -393.531859) (xy 374.76303 -393.552934)
			(xy 374.763538 -393.55395) (xy 374.843844 -393.692888) (xy 375.385584 -393.692888) (xy 375.385584 -393.69238)
			(xy 375.386021 -393.668374) (xy 375.393538 -393.620954) (xy 375.408384 -393.575295) (xy 375.430194 -393.532522)
			(xy 375.458428 -393.49369) (xy 375.492393 -393.459755) (xy 375.53125 -393.431554) (xy 375.574041 -393.409782)
			(xy 375.619713 -393.394976) (xy 375.66714 -393.3875) (xy 375.691146 -393.387072) (xy 375.715081 -393.387542)
			(xy 375.762365 -393.394999) (xy 375.807908 -393.40974) (xy 375.850594 -393.431403) (xy 375.88938 -393.459458)
			(xy 375.923316 -393.493219) (xy 375.951571 -393.531859) (xy 375.962926 -393.552934) (xy 375.963434 -393.55395)
			(xy 376.355864 -394.232892) (xy 376.36862 -394.256246) (xy 376.386726 -394.30628) (xy 376.395926 -394.358688)
			(xy 376.396504 -394.385292) (xy 376.396054 -394.409285) (xy 376.388549 -394.456681) (xy 376.373721 -394.502319)
			(xy 376.351936 -394.545075) (xy 376.323731 -394.583897) (xy 376.2898 -394.617829) (xy 376.250978 -394.646034)
			(xy 376.208222 -394.66782) (xy 376.162585 -394.682648) (xy 376.115189 -394.690154) (xy 376.091196 -394.6906)
			(xy 376.067622 -394.690209) (xy 376.021033 -394.682967) (xy 375.976115 -394.668641) (xy 375.933936 -394.647572)
			(xy 375.895503 -394.620262) (xy 375.861732 -394.587362) (xy 375.833426 -394.549656) (xy 375.821956 -394.529056)
			(xy 375.821448 -394.528294) (xy 375.423684 -393.839954) (xy 375.411748 -393.817296) (xy 375.394819 -393.768965)
			(xy 375.386167 -393.718492) (xy 375.385584 -393.692888) (xy 374.843844 -393.692888) (xy 375.155968 -394.232892)
			(xy 375.168724 -394.256246) (xy 375.18683 -394.30628) (xy 375.19603 -394.358688) (xy 375.196608 -394.385292)
			(xy 375.196154 -394.409285) (xy 375.188649 -394.45668) (xy 375.173821 -394.502318) (xy 375.152037 -394.545074)
			(xy 375.123832 -394.583896) (xy 375.089902 -394.617827) (xy 375.051081 -394.646033) (xy 375.008325 -394.667818)
			(xy 374.962688 -394.682647) (xy 374.915293 -394.690154) (xy 374.8913 -394.6906) (xy 374.867726 -394.690206)
			(xy 374.821138 -394.682965) (xy 374.776219 -394.668639) (xy 374.734041 -394.64757) (xy 374.695608 -394.620261)
			(xy 374.661836 -394.587361) (xy 374.63353 -394.549656) (xy 374.62206 -394.529056) (xy 374.621552 -394.528294)
			(xy 374.223788 -393.839954) (xy 374.211853 -393.817296) (xy 374.194923 -393.768965) (xy 374.186271 -393.718491)
			(xy 374.185688 -393.692888) (xy 373.643694 -393.692888) (xy 373.955818 -394.232892) (xy 373.968641 -394.256226)
			(xy 373.986862 -394.306248) (xy 373.996123 -394.358673) (xy 373.996712 -394.385292) (xy 373.996254 -394.409297)
			(xy 373.98874 -394.456717) (xy 373.973898 -394.502376) (xy 373.952091 -394.545149) (xy 373.923859 -394.583981)
			(xy 373.889897 -394.617917) (xy 373.851042 -394.646118) (xy 373.808252 -394.66789) (xy 373.762581 -394.682697)
			(xy 373.715156 -394.690172) (xy 373.69115 -394.6906) (xy 373.667577 -394.690166) (xy 373.620991 -394.682932)
			(xy 373.576073 -394.668613) (xy 373.533895 -394.647551) (xy 373.495461 -394.620248) (xy 373.461688 -394.587354)
			(xy 373.433381 -394.549653) (xy 373.42191 -394.529056) (xy 373.421402 -394.528294) (xy 373.023638 -393.839954)
			(xy 373.011778 -393.817269) (xy 372.994922 -393.76894) (xy 372.986342 -393.71848) (xy 372.985792 -393.692888)
			(xy 372.443798 -393.692888) (xy 372.755922 -394.232892) (xy 372.768745 -394.256225) (xy 372.786966 -394.306248)
			(xy 372.796227 -394.358673) (xy 372.796816 -394.385292) (xy 372.796354 -394.409297) (xy 372.78884 -394.456716)
			(xy 372.773998 -394.502375) (xy 372.752192 -394.545147) (xy 372.72396 -394.58398) (xy 372.689999 -394.617915)
			(xy 372.651144 -394.646117) (xy 372.608354 -394.667889) (xy 372.562684 -394.682696) (xy 372.51526 -394.690172)
			(xy 372.491254 -394.6906) (xy 372.467682 -394.690163) (xy 372.421095 -394.682929) (xy 372.376178 -394.668611)
			(xy 372.333999 -394.64755) (xy 372.295566 -394.620247) (xy 372.261793 -394.587353) (xy 372.233485 -394.549653)
			(xy 372.222014 -394.529056) (xy 372.221506 -394.528294) (xy 371.823742 -393.839954) (xy 371.811882 -393.817269)
			(xy 371.795026 -393.76894) (xy 371.786446 -393.71848) (xy 371.785896 -393.692888) (xy 371.243902 -393.692888)
			(xy 371.556026 -394.232892) (xy 371.56885 -394.256225) (xy 371.587071 -394.306247) (xy 371.596331 -394.358673)
			(xy 371.59692 -394.385292) (xy 371.596454 -394.409297) (xy 371.588941 -394.456716) (xy 371.574098 -394.502374)
			(xy 371.552293 -394.545146) (xy 371.524062 -394.583979) (xy 371.4901 -394.617914) (xy 371.451246 -394.646115)
			(xy 371.408457 -394.667888) (xy 371.362788 -394.682695) (xy 371.315363 -394.690172) (xy 371.291358 -394.6906)
			(xy 371.267786 -394.690159) (xy 371.2212 -394.682927) (xy 371.176282 -394.668609) (xy 371.134104 -394.647548)
			(xy 371.09567 -394.620246) (xy 371.061897 -394.587353) (xy 371.03359 -394.549653) (xy 371.022118 -394.529056)
			(xy 371.02161 -394.528294) (xy 370.623846 -393.839954) (xy 370.611986 -393.817269) (xy 370.59513 -393.76894)
			(xy 370.58655 -393.71848) (xy 370.586 -393.692888) (xy 366.613694 -393.692888) (xy 366.613694 -395.371066)
			(xy 366.613076 -395.39602) (xy 366.603328 -395.444967) (xy 366.584218 -395.491072) (xy 366.556481 -395.532563)
			(xy 366.539272 -395.550644) (xy 365.9632 -396.126716) (xy 365.945158 -396.143973) (xy 365.903663 -396.171724)
			(xy 365.857545 -396.190829) (xy 365.808582 -396.200552) (xy 365.783622 -396.201138) (xy 364.789212 -396.201138)
			(xy 364.761272 -396.224252) (xy 364.757716 -396.24254) (xy 364.752073 -396.26978) (xy 364.733946 -396.322372)
			(xy 364.708373 -396.371774) (xy 364.675896 -396.416938) (xy 364.637205 -396.456906) (xy 364.593119 -396.490832)
			(xy 364.544573 -396.517994) (xy 364.492597 -396.537818) (xy 364.438293 -396.549883) (xy 364.382812 -396.553934)
			(xy 364.327331 -396.549883) (xy 364.273027 -396.537818) (xy 364.221051 -396.517994) (xy 364.172505 -396.490832)
			(xy 364.128419 -396.456906) (xy 364.089728 -396.416938) (xy 364.057251 -396.371774) (xy 364.031678 -396.322372)
			(xy 364.013551 -396.26978) (xy 364.007908 -396.24254) (xy 364.004352 -396.224252) (xy 363.976412 -396.201138)
			(xy 361.273598 -396.201138) (xy 361.245658 -396.22476) (xy 361.242356 -396.243048) (xy 361.236978 -396.270567)
			(xy 361.219223 -396.32375) (xy 361.193874 -396.373763) (xy 361.161479 -396.419526) (xy 361.122734 -396.460055)
			(xy 361.078474 -396.494477) (xy 361.029653 -396.52205) (xy 360.977322 -396.542181) (xy 360.922608 -396.554435)
			(xy 360.86669 -396.55855) (xy 360.810772 -396.554435) (xy 360.756058 -396.542181) (xy 360.703727 -396.52205)
			(xy 360.654906 -396.494477) (xy 360.610646 -396.460055) (xy 360.571901 -396.419526) (xy 360.539506 -396.373763)
			(xy 360.514157 -396.32375) (xy 360.496402 -396.270567) (xy 360.491024 -396.243048) (xy 360.487722 -396.22476)
			(xy 360.459782 -396.201138) (xy 358.619298 -396.201138) (xy 358.609229 -396.201562) (xy 358.590628 -396.209281)
			(xy 358.58323 -396.216124) (xy 358.26446 -396.534894) (xy 358.246421 -396.552157) (xy 358.204928 -396.57992)
			(xy 358.15881 -396.599038) (xy 358.109844 -396.608773) (xy 358.084882 -396.609316) (xy 349.829374 -396.609316)
			(xy 349.804418 -396.608702) (xy 349.755467 -396.598961) (xy 349.709355 -396.579857) (xy 349.667857 -396.552126)
			(xy 349.649796 -396.534894) (xy 349.449644 -396.334742) (xy 349.415354 -396.33017) (xy 349.400368 -396.33906)
			(xy 349.376776 -396.35221) (xy 349.326104 -396.370892) (xy 349.272939 -396.380384) (xy 349.245936 -396.38097)
			(xy 349.221942 -396.380526) (xy 349.174544 -396.373024) (xy 349.128904 -396.358198) (xy 349.086146 -396.336414)
			(xy 349.047323 -396.308208) (xy 349.01339 -396.274276) (xy 348.985185 -396.235452) (xy 348.963401 -396.192694)
			(xy 348.948576 -396.147054) (xy 348.941073 -396.099656) (xy 348.940628 -396.075662) (xy 348.941199 -396.048657)
			(xy 348.950685 -395.995487) (xy 348.96937 -395.944813) (xy 348.982538 -395.92123) (xy 348.991428 -395.906244)
			(xy 348.986856 -395.871954) (xy 348.35465 -395.239748) (xy 348.347251 -395.232904) (xy 348.328652 -395.22518)
			(xy 348.318582 -395.224762) (xy 347.881448 -395.224762) (xy 347.871383 -395.225196) (xy 347.852798 -395.232931)
			(xy 347.84538 -395.239748) (xy 347.140022 -395.945106) (xy 347.133418 -395.97203) (xy 347.137736 -395.985746)
			(xy 347.144004 -396.007566) (xy 347.150763 -396.052456) (xy 347.151198 -396.075154) (xy 347.151198 -396.075662)
			(xy 347.150755 -396.099657) (xy 347.143253 -396.147056) (xy 347.128427 -396.192698) (xy 347.106644 -396.235459)
			(xy 347.078439 -396.274285) (xy 347.044506 -396.30822) (xy 347.005683 -396.336429) (xy 346.962924 -396.358217)
			(xy 346.917284 -396.373046) (xy 346.869885 -396.380552) (xy 346.84589 -396.38097) (xy 346.845382 -396.38097)
			(xy 346.822684 -396.380538) (xy 346.777792 -396.373783) (xy 346.755974 -396.367508) (xy 346.742258 -396.36319)
			(xy 346.715334 -396.369794) (xy 346.234258 -396.85087) (xy 346.228407 -396.85661) (xy 346.216077 -396.867412)
			(xy 346.20962 -396.87246) (xy 346.202 -396.878302) (xy 346.192602 -396.893796) (xy 346.175838 -396.97787)
			(xy 346.178886 -396.99565) (xy 346.183458 -397.003778) (xy 346.191078 -397.017494) (xy 346.191586 -397.018764)
			(xy 346.284753 -397.179979) (xy 346.813611 -397.179979) (xy 346.813859 -397.129044) (xy 346.822553 -397.078855)
			(xy 346.83945 -397.030804) (xy 346.864083 -396.986221) (xy 346.89577 -396.946341) (xy 346.933633 -396.912269)
			(xy 346.976622 -396.884949) (xy 347.023547 -396.865138) (xy 347.073108 -396.853385) (xy 347.123932 -396.850014)
			(xy 347.174611 -396.85512) (xy 347.223742 -396.868562) (xy 347.269962 -396.889966) (xy 347.311992 -396.918739)
			(xy 347.348668 -396.954086) (xy 347.378973 -396.995025) (xy 347.390974 -397.017494) (xy 347.391482 -397.018764)
			(xy 347.457665 -397.133286) (xy 348.013624 -397.133286) (xy 348.020956 -397.085735) (xy 348.03565 -397.039922)
			(xy 348.057342 -396.996978) (xy 348.085497 -396.957964) (xy 348.119419 -396.923846) (xy 348.15827 -396.895466)
			(xy 348.201088 -396.873525) (xy 348.246815 -396.858567) (xy 348.294322 -396.850961) (xy 348.342434 -396.850894)
			(xy 348.389962 -396.858369) (xy 348.435731 -396.873201) (xy 348.47861 -396.895023) (xy 348.517538 -396.923296)
			(xy 348.551554 -396.95732) (xy 348.579817 -396.996256) (xy 348.591124 -397.017494) (xy 348.591632 -397.018764)
			(xy 348.657814 -397.133285) (xy 349.213528 -397.133285) (xy 349.220859 -397.085736) (xy 349.235553 -397.039923)
			(xy 349.257245 -396.99698) (xy 349.2854 -396.957967) (xy 349.319322 -396.923849) (xy 349.358171 -396.895469)
			(xy 349.400989 -396.873529) (xy 349.446716 -396.858571) (xy 349.494222 -396.850964) (xy 349.542333 -396.850898)
			(xy 349.58986 -396.858372) (xy 349.635629 -396.873204) (xy 349.678507 -396.895025) (xy 349.717435 -396.923297)
			(xy 349.751451 -396.957321) (xy 349.779713 -396.996256) (xy 349.79102 -397.017494) (xy 349.791528 -397.018764)
			(xy 349.85771 -397.133285) (xy 350.413431 -397.133285) (xy 350.420763 -397.085737) (xy 350.435456 -397.039924)
			(xy 350.457148 -396.996982) (xy 350.485303 -396.957969) (xy 350.519224 -396.923851) (xy 350.558073 -396.895472)
			(xy 350.60089 -396.873532) (xy 350.646616 -396.858574) (xy 350.694121 -396.850968) (xy 350.742232 -396.850901)
			(xy 350.789759 -396.858376) (xy 350.835526 -396.873207) (xy 350.878404 -396.895028) (xy 350.917331 -396.923299)
			(xy 350.951347 -396.957323) (xy 350.979609 -396.996257) (xy 350.990916 -397.017494) (xy 350.991424 -397.018764)
			(xy 351.084589 -397.179977) (xy 351.613718 -397.179977) (xy 351.613966 -397.129044) (xy 351.62266 -397.078857)
			(xy 351.639557 -397.030807) (xy 351.664189 -396.986225) (xy 351.695875 -396.946346) (xy 351.733736 -396.912275)
			(xy 351.776724 -396.884956) (xy 351.823648 -396.865145) (xy 351.873208 -396.853392) (xy 351.92403 -396.850021)
			(xy 351.974708 -396.855127) (xy 352.023837 -396.868568) (xy 352.070056 -396.88997) (xy 352.112086 -396.918743)
			(xy 352.14876 -396.954088) (xy 352.179065 -396.995026) (xy 352.191066 -397.017494) (xy 352.191574 -397.018764)
			(xy 352.284739 -397.179976) (xy 352.813621 -397.179976) (xy 352.81387 -397.129044) (xy 352.822563 -397.078857)
			(xy 352.83946 -397.030808) (xy 352.864092 -396.986227) (xy 352.895778 -396.946349) (xy 352.933638 -396.912278)
			(xy 352.976626 -396.88496) (xy 353.023549 -396.865149) (xy 353.073108 -396.853396) (xy 353.123929 -396.850025)
			(xy 353.174606 -396.85513) (xy 353.223735 -396.86857) (xy 353.269953 -396.889973) (xy 353.311982 -396.918745)
			(xy 353.348657 -396.954089) (xy 353.378961 -396.995027) (xy 353.390962 -397.017494) (xy 353.39147 -397.018764)
			(xy 353.457652 -397.133285) (xy 354.013635 -397.133285) (xy 354.020967 -397.085737) (xy 354.03566 -397.039926)
			(xy 354.057351 -396.996983) (xy 354.085505 -396.957971) (xy 354.119426 -396.923854) (xy 354.158274 -396.895475)
			(xy 354.20109 -396.873536) (xy 354.246816 -396.858578) (xy 354.294321 -396.850971) (xy 354.342431 -396.850905)
			(xy 354.389957 -396.858379) (xy 354.435724 -396.873209) (xy 354.478601 -396.89503) (xy 354.517528 -396.923301)
			(xy 354.551543 -396.957324) (xy 354.579805 -396.996257) (xy 354.591112 -397.017494) (xy 354.59162 -397.018764)
			(xy 354.657801 -397.133284) (xy 370.586149 -397.133284) (xy 370.593481 -397.085739) (xy 370.608173 -397.03993)
			(xy 370.629864 -396.996991) (xy 370.658016 -396.957981) (xy 370.691934 -396.923866) (xy 370.73078 -396.895488)
			(xy 370.773594 -396.87355) (xy 370.819317 -396.858592) (xy 370.866819 -396.850986) (xy 370.914926 -396.850918)
			(xy 370.962449 -396.858392) (xy 371.008214 -396.873221) (xy 371.051089 -396.895039) (xy 371.090014 -396.923308)
			(xy 371.124028 -396.957328) (xy 371.15229 -396.996259) (xy 371.163596 -397.017494) (xy 371.164104 -397.018764)
			(xy 371.230285 -397.133284) (xy 371.786053 -397.133284) (xy 371.793384 -397.08574) (xy 371.808077 -397.039932)
			(xy 371.829767 -396.996992) (xy 371.857919 -396.957983) (xy 371.891837 -396.923869) (xy 371.930682 -396.895491)
			(xy 371.973495 -396.873553) (xy 372.019217 -396.858596) (xy 372.066718 -396.850989) (xy 372.114825 -396.850922)
			(xy 372.162347 -396.858395) (xy 372.208111 -396.873224) (xy 372.250986 -396.895042) (xy 372.289911 -396.92331)
			(xy 372.323924 -396.957329) (xy 372.352186 -396.996259) (xy 372.363492 -397.017494) (xy 372.364 -397.018764)
			(xy 372.430181 -397.133284) (xy 372.985956 -397.133284) (xy 372.993288 -397.08574) (xy 373.00798 -397.039933)
			(xy 373.02967 -396.996994) (xy 373.057821 -396.957986) (xy 373.091739 -396.923872) (xy 373.130584 -396.895495)
			(xy 373.173396 -396.873557) (xy 373.219117 -396.858599) (xy 373.266618 -396.850993) (xy 373.314724 -396.850925)
			(xy 373.362246 -396.858398) (xy 373.408009 -396.873226) (xy 373.450883 -396.895044) (xy 373.489807 -396.923311)
			(xy 373.523821 -396.95733) (xy 373.552082 -396.996259) (xy 373.563388 -397.017494) (xy 373.563896 -397.018764)
			(xy 373.630079 -397.133286) (xy 374.186012 -397.133286) (xy 374.193344 -397.085734) (xy 374.208038 -397.039918)
			(xy 374.229732 -396.996971) (xy 374.257888 -396.957956) (xy 374.291812 -396.923836) (xy 374.330664 -396.895454)
			(xy 374.373485 -396.873513) (xy 374.419215 -396.858554) (xy 374.466724 -396.850948) (xy 374.514839 -396.850882)
			(xy 374.562369 -396.858358) (xy 374.60814 -396.873191) (xy 374.65102 -396.895015) (xy 374.68995 -396.92329)
			(xy 374.723968 -396.957317) (xy 374.752231 -396.996255) (xy 374.763538 -397.017494) (xy 374.764046 -397.018764)
			(xy 374.830229 -397.133286) (xy 375.385915 -397.133286) (xy 375.393247 -397.085734) (xy 375.407941 -397.039919)
			(xy 375.429635 -396.996973) (xy 375.457791 -396.957958) (xy 375.491714 -396.923839) (xy 375.530566 -396.895457)
			(xy 375.573385 -396.873516) (xy 375.619115 -396.858558) (xy 375.666624 -396.850952) (xy 375.714737 -396.850885)
			(xy 375.762267 -396.858361) (xy 375.808037 -396.873194) (xy 375.850917 -396.895017) (xy 375.889847 -396.923291)
			(xy 375.923864 -396.957318) (xy 375.952127 -396.996255) (xy 375.963434 -397.017494) (xy 375.963942 -397.018764)
			(xy 376.030123 -397.133284) (xy 376.58616 -397.133284) (xy 376.593491 -397.085741) (xy 376.608183 -397.039934)
			(xy 376.629873 -396.996996) (xy 376.658024 -396.957988) (xy 376.691941 -396.923874) (xy 376.730785 -396.895498)
			(xy 376.773597 -396.87356) (xy 376.819317 -396.858603) (xy 376.866817 -396.850997) (xy 376.914922 -396.850929)
			(xy 376.962444 -396.858401) (xy 377.008207 -396.873229) (xy 377.05108 -396.895046) (xy 377.090004 -396.923313)
			(xy 377.124017 -396.957331) (xy 377.152278 -396.99626) (xy 377.163584 -397.017494) (xy 377.164092 -397.018764)
			(xy 377.556014 -397.696944) (xy 377.556268 -397.697452) (xy 377.556522 -397.697452) (xy 377.557792 -397.699992)
			(xy 377.570062 -397.722908) (xy 377.587469 -397.771886) (xy 377.596344 -397.823101) (xy 377.596908 -397.84909)
			(xy 377.596908 -397.849344) (xy 377.596501 -397.873351) (xy 377.58898 -397.920772) (xy 377.57413 -397.966432)
			(xy 377.552317 -398.009206) (xy 377.524079 -398.048038) (xy 377.490111 -398.081973) (xy 377.451251 -398.110173)
			(xy 377.408457 -398.131944) (xy 377.362782 -398.14675) (xy 377.315353 -398.154225) (xy 377.291346 -398.154652)
			(xy 377.267683 -398.154176) (xy 377.220924 -398.146872) (xy 377.175849 -398.132448) (xy 377.133537 -398.111248)
			(xy 377.094998 -398.083778) (xy 377.061154 -398.050697) (xy 377.032815 -398.012794) (xy 377.021344 -397.992092)
			(xy 377.02109 -397.99133) (xy 376.623834 -397.304006) (xy 376.611654 -397.28079) (xy 376.59454 -397.231239)
			(xy 376.589798 -397.205454) (xy 376.589798 -397.2052) (xy 376.586371 -397.181389) (xy 376.58616 -397.133284)
			(xy 376.030123 -397.133284) (xy 376.355864 -397.696944) (xy 376.356118 -397.697452) (xy 376.356372 -397.697452)
			(xy 376.357642 -397.699992) (xy 376.369877 -397.722915) (xy 376.387196 -397.771902) (xy 376.395983 -397.823111)
			(xy 376.396504 -397.84909) (xy 376.396504 -397.849344) (xy 376.396078 -397.873337) (xy 376.388565 -397.92073)
			(xy 376.373731 -397.966365) (xy 376.351942 -398.009118) (xy 376.323733 -398.047937) (xy 376.2898 -398.081865)
			(xy 376.250977 -398.110067) (xy 376.208221 -398.13185) (xy 376.162583 -398.146676) (xy 376.115189 -398.154182)
			(xy 376.091196 -398.154652) (xy 376.067531 -398.154216) (xy 376.02077 -398.146905) (xy 375.975695 -398.132473)
			(xy 375.933382 -398.111266) (xy 375.894844 -398.083791) (xy 375.861002 -398.050704) (xy 375.832664 -398.012796)
			(xy 375.821194 -397.992092) (xy 375.82094 -397.99133) (xy 375.423684 -397.304006) (xy 375.411508 -397.280788)
			(xy 375.394391 -397.231238) (xy 375.389648 -397.205454) (xy 375.389648 -397.2052) (xy 375.386127 -397.181399)
			(xy 375.385915 -397.133286) (xy 374.830229 -397.133286) (xy 375.155968 -397.696944) (xy 375.156222 -397.697452)
			(xy 375.156476 -397.697452) (xy 375.157746 -397.699992) (xy 375.169981 -397.722915) (xy 375.1873 -397.771902)
			(xy 375.196087 -397.823111) (xy 375.196608 -397.84909) (xy 375.196608 -397.849344) (xy 375.196178 -397.873336)
			(xy 375.188665 -397.92073) (xy 375.173832 -397.966364) (xy 375.152043 -398.009117) (xy 375.123835 -398.047935)
			(xy 375.089902 -398.081863) (xy 375.051079 -398.110066) (xy 375.008324 -398.131849) (xy 374.962687 -398.146676)
			(xy 374.915292 -398.154181) (xy 374.8913 -398.154652) (xy 374.867636 -398.154213) (xy 374.820875 -398.146902)
			(xy 374.775799 -398.132471) (xy 374.733487 -398.111265) (xy 374.694949 -398.08379) (xy 374.661106 -398.050703)
			(xy 374.632768 -398.012796) (xy 374.621298 -397.992092) (xy 374.621044 -397.99133) (xy 374.223788 -397.304006)
			(xy 374.211612 -397.280788) (xy 374.194495 -397.231238) (xy 374.189752 -397.205454) (xy 374.189752 -397.2052)
			(xy 374.186223 -397.1814) (xy 374.186012 -397.133286) (xy 373.630079 -397.133286) (xy 373.955818 -397.696944)
			(xy 373.956072 -397.697452) (xy 373.956326 -397.697452) (xy 373.957596 -397.699992) (xy 373.969867 -397.722908)
			(xy 373.987274 -397.771886) (xy 373.996148 -397.823101) (xy 373.996712 -397.84909) (xy 373.996712 -397.849344)
			(xy 373.996302 -397.873351) (xy 373.98878 -397.920772) (xy 373.973931 -397.966432) (xy 373.952118 -398.009205)
			(xy 373.92388 -398.048037) (xy 373.889913 -398.081971) (xy 373.851053 -398.110172) (xy 373.808259 -398.131943)
			(xy 373.762586 -398.146749) (xy 373.715157 -398.154225) (xy 373.69115 -398.154652) (xy 373.667487 -398.154172)
			(xy 373.620728 -398.146869) (xy 373.575653 -398.132446) (xy 373.533341 -398.111246) (xy 373.494802 -398.083777)
			(xy 373.460959 -398.050696) (xy 373.432619 -398.012793) (xy 373.421148 -397.992092) (xy 373.420894 -397.99133)
			(xy 373.023638 -397.304006) (xy 373.011458 -397.28079) (xy 372.994344 -397.231239) (xy 372.989602 -397.205454)
			(xy 372.989602 -397.2052) (xy 372.986167 -397.181389) (xy 372.985956 -397.133284) (xy 372.430181 -397.133284)
			(xy 372.755922 -397.696944) (xy 372.756176 -397.697452) (xy 372.75643 -397.697452) (xy 372.7577 -397.699992)
			(xy 372.769971 -397.722908) (xy 372.787378 -397.771886) (xy 372.796252 -397.823101) (xy 372.796816 -397.84909)
			(xy 372.796816 -397.849344) (xy 372.796402 -397.873351) (xy 372.788881 -397.920771) (xy 372.774031 -397.966431)
			(xy 372.752219 -398.009203) (xy 372.723981 -398.048036) (xy 372.690015 -398.08197) (xy 372.651156 -398.110171)
			(xy 372.608362 -398.131942) (xy 372.562689 -398.146748) (xy 372.515261 -398.154224) (xy 372.491254 -398.154652)
			(xy 372.467591 -398.154169) (xy 372.420832 -398.146867) (xy 372.375758 -398.132444) (xy 372.333445 -398.111245)
			(xy 372.294907 -398.083776) (xy 372.261063 -398.050696) (xy 372.232723 -398.012793) (xy 372.221252 -397.992092)
			(xy 372.220998 -397.99133) (xy 371.823742 -397.304006) (xy 371.811563 -397.280789) (xy 371.794448 -397.231239)
			(xy 371.789706 -397.205454) (xy 371.789706 -397.2052) (xy 371.786264 -397.18139) (xy 371.786053 -397.133284)
			(xy 371.230285 -397.133284) (xy 371.556026 -397.696944) (xy 371.55628 -397.697452) (xy 371.556534 -397.697452)
			(xy 371.557804 -397.699992) (xy 371.570075 -397.722908) (xy 371.587482 -397.771886) (xy 371.596356 -397.823101)
			(xy 371.59692 -397.84909) (xy 371.59692 -397.849344) (xy 371.596502 -397.87335) (xy 371.588981 -397.920771)
			(xy 371.574131 -397.96643) (xy 371.552319 -398.009202) (xy 371.524082 -398.048034) (xy 371.490116 -398.081969)
			(xy 371.451258 -398.110169) (xy 371.408465 -398.131941) (xy 371.362792 -398.146748) (xy 371.315365 -398.154224)
			(xy 371.291358 -398.154652) (xy 371.267695 -398.154166) (xy 371.220936 -398.146864) (xy 371.175862 -398.132442)
			(xy 371.13355 -398.111243) (xy 371.095011 -398.083775) (xy 371.061167 -398.050695) (xy 371.032827 -398.012793)
			(xy 371.021356 -397.992092) (xy 371.021102 -397.99133) (xy 370.623846 -397.304006) (xy 370.611667 -397.280789)
			(xy 370.594552 -397.231239) (xy 370.58981 -397.205454) (xy 370.58981 -397.2052) (xy 370.58636 -397.181391)
			(xy 370.586149 -397.133284) (xy 354.657801 -397.133284) (xy 354.983542 -397.696944) (xy 354.983796 -397.697452)
			(xy 354.98405 -397.697452) (xy 354.98532 -397.699992) (xy 354.997593 -397.722907) (xy 355.014998 -397.771885)
			(xy 355.023872 -397.823101) (xy 355.024436 -397.84909) (xy 355.024436 -397.849344) (xy 355.024002 -397.87335)
			(xy 355.016481 -397.920768) (xy 355.001633 -397.966426) (xy 354.979822 -398.009197) (xy 354.951587 -398.048029)
			(xy 354.917623 -398.081963) (xy 354.878767 -398.110164) (xy 354.835976 -398.131936) (xy 354.790305 -398.146744)
			(xy 354.74288 -398.154223) (xy 354.718874 -398.154652) (xy 354.695212 -398.154153) (xy 354.648453 -398.146854)
			(xy 354.603379 -398.132433) (xy 354.561067 -398.111237) (xy 354.522528 -398.083771) (xy 354.488684 -398.050693)
			(xy 354.460343 -398.012792) (xy 354.448872 -397.992092) (xy 354.448618 -397.99133) (xy 354.051362 -397.304006)
			(xy 354.039184 -397.280789) (xy 354.022068 -397.231239) (xy 354.017326 -397.205454) (xy 354.017326 -397.2052)
			(xy 354.013846 -397.181395) (xy 354.013635 -397.133285) (xy 353.457652 -397.133285) (xy 353.783392 -397.696944)
			(xy 353.783646 -397.697452) (xy 353.7839 -397.697452) (xy 353.78517 -397.699992) (xy 353.797399 -397.722918)
			(xy 353.814722 -397.771903) (xy 353.82351 -397.823111) (xy 353.824032 -397.84909) (xy 353.824032 -397.849344)
			(xy 353.823578 -397.873335) (xy 353.816066 -397.920726) (xy 353.801234 -397.966359) (xy 353.779447 -398.00911)
			(xy 353.751242 -398.047927) (xy 353.717312 -398.081855) (xy 353.678493 -398.110058) (xy 353.63574 -398.131842)
			(xy 353.590107 -398.146671) (xy 353.542715 -398.15418) (xy 353.518724 -398.154652) (xy 353.49506 -398.154193)
			(xy 353.4483 -398.146886) (xy 353.403225 -398.132459) (xy 353.360913 -398.111256) (xy 353.322374 -398.083784)
			(xy 353.288531 -398.0507) (xy 353.260193 -398.012795) (xy 353.248722 -397.992092) (xy 353.248468 -397.99133)
			(xy 352.851212 -397.304006) (xy 352.839031 -397.28079) (xy 352.821918 -397.231239) (xy 352.817176 -397.205454)
			(xy 352.817176 -397.2052) (xy 352.813621 -397.179976) (xy 352.284739 -397.179976) (xy 352.583496 -397.696944)
			(xy 352.58375 -397.697452) (xy 352.584004 -397.697452) (xy 352.585274 -397.699992) (xy 352.597504 -397.722918)
			(xy 352.614826 -397.771903) (xy 352.623614 -397.823111) (xy 352.624136 -397.84909) (xy 352.624136 -397.849344)
			(xy 352.623678 -397.873335) (xy 352.616166 -397.920726) (xy 352.601335 -397.966358) (xy 352.579548 -398.009109)
			(xy 352.551343 -398.047926) (xy 352.517413 -398.081853) (xy 352.478595 -398.110056) (xy 352.435843 -398.131841)
			(xy 352.39021 -398.14667) (xy 352.342819 -398.154179) (xy 352.318828 -398.154652) (xy 352.295164 -398.15419)
			(xy 352.248404 -398.146884) (xy 352.203329 -398.132457) (xy 352.161017 -398.111254) (xy 352.122479 -398.083783)
			(xy 352.088636 -398.050699) (xy 352.060297 -398.012794) (xy 352.048826 -397.992092) (xy 352.048572 -397.99133)
			(xy 351.651316 -397.304006) (xy 351.639135 -397.28079) (xy 351.622022 -397.231239) (xy 351.61728 -397.205454)
			(xy 351.61728 -397.2052) (xy 351.613718 -397.179977) (xy 351.084589 -397.179977) (xy 351.383346 -397.696944)
			(xy 351.3836 -397.697452) (xy 351.383854 -397.697452) (xy 351.385124 -397.699992) (xy 351.397397 -397.722907)
			(xy 351.414802 -397.771885) (xy 351.423676 -397.823101) (xy 351.42424 -397.84909) (xy 351.42424 -397.849344)
			(xy 351.423802 -397.873349) (xy 351.416281 -397.920768) (xy 351.401433 -397.966425) (xy 351.379623 -398.009196)
			(xy 351.351388 -398.048027) (xy 351.317425 -398.081961) (xy 351.278569 -398.110162) (xy 351.235779 -398.131935)
			(xy 351.190109 -398.146744) (xy 351.142684 -398.154222) (xy 351.118678 -398.154652) (xy 351.095013 -398.15423)
			(xy 351.048251 -398.146916) (xy 351.003175 -398.132482) (xy 350.960863 -398.111273) (xy 350.922325 -398.083796)
			(xy 350.888483 -398.050707) (xy 350.860146 -398.012797) (xy 350.848676 -397.992092) (xy 350.848422 -397.99133)
			(xy 350.451166 -397.304006) (xy 350.438988 -397.280789) (xy 350.421872 -397.231239) (xy 350.41713 -397.205454)
			(xy 350.41713 -397.2052) (xy 350.413643 -397.181396) (xy 350.413431 -397.133285) (xy 349.85771 -397.133285)
			(xy 350.18345 -397.696944) (xy 350.183704 -397.697452) (xy 350.183958 -397.697452) (xy 350.185228 -397.699992)
			(xy 350.197501 -397.722907) (xy 350.214906 -397.771885) (xy 350.22378 -397.823101) (xy 350.224344 -397.84909)
			(xy 350.224344 -397.849344) (xy 350.223902 -397.873349) (xy 350.216382 -397.920767) (xy 350.201534 -397.966424)
			(xy 350.179724 -398.009195) (xy 350.15149 -398.048026) (xy 350.117526 -398.08196) (xy 350.078671 -398.110161)
			(xy 350.035882 -398.131934) (xy 349.990212 -398.146743) (xy 349.942788 -398.154222) (xy 349.918782 -398.154652)
			(xy 349.895117 -398.154227) (xy 349.848355 -398.146914) (xy 349.80328 -398.13248) (xy 349.760967 -398.111272)
			(xy 349.722429 -398.083795) (xy 349.688587 -398.050706) (xy 349.66025 -398.012797) (xy 349.64878 -397.992092)
			(xy 349.648526 -397.99133) (xy 349.25127 -397.304006) (xy 349.239093 -397.280789) (xy 349.221977 -397.231238)
			(xy 349.217234 -397.205454) (xy 349.217234 -397.2052) (xy 349.213739 -397.181396) (xy 349.213528 -397.133285)
			(xy 348.657814 -397.133285) (xy 348.983554 -397.696944) (xy 348.983808 -397.697452) (xy 348.984062 -397.697452)
			(xy 348.985332 -397.699992) (xy 348.997606 -397.722907) (xy 349.015011 -397.771885) (xy 349.023884 -397.823101)
			(xy 349.024448 -397.84909) (xy 349.024448 -397.849344) (xy 349.024002 -397.873349) (xy 349.016482 -397.920767)
			(xy 349.001634 -397.966423) (xy 348.979825 -398.009194) (xy 348.951591 -398.048025) (xy 348.917628 -398.081959)
			(xy 348.878773 -398.11016) (xy 348.835984 -398.131933) (xy 348.790315 -398.146742) (xy 348.742891 -398.154222)
			(xy 348.718886 -398.154652) (xy 348.695221 -398.154224) (xy 348.64846 -398.146911) (xy 348.603384 -398.132478)
			(xy 348.561072 -398.11127) (xy 348.522534 -398.083794) (xy 348.488692 -398.050705) (xy 348.460354 -398.012796)
			(xy 348.448884 -397.992092) (xy 348.44863 -397.99133) (xy 348.051374 -397.304006) (xy 348.039197 -397.280788)
			(xy 348.022081 -397.231238) (xy 348.017338 -397.205454) (xy 348.017338 -397.2052) (xy 348.013836 -397.181397)
			(xy 348.013624 -397.133286) (xy 347.457665 -397.133286) (xy 347.783404 -397.696944) (xy 347.783658 -397.697452)
			(xy 347.783912 -397.697452) (xy 347.785182 -397.699992) (xy 347.797412 -397.722918) (xy 347.814734 -397.771903)
			(xy 347.823522 -397.823111) (xy 347.824044 -397.84909) (xy 347.824044 -397.849344) (xy 347.823578 -397.873335)
			(xy 347.816067 -397.920724) (xy 347.801235 -397.966356) (xy 347.779449 -398.009106) (xy 347.751245 -398.047923)
			(xy 347.717317 -398.08185) (xy 347.678499 -398.110054) (xy 347.635749 -398.131838) (xy 347.590117 -398.146668)
			(xy 347.542727 -398.154179) (xy 347.518736 -398.154652) (xy 347.495073 -398.154184) (xy 347.448313 -398.146878)
			(xy 347.403238 -398.132453) (xy 347.360926 -398.111251) (xy 347.322387 -398.083781) (xy 347.288544 -398.050698)
			(xy 347.260205 -398.012794) (xy 347.248734 -397.992092) (xy 347.24848 -397.99133) (xy 346.851224 -397.304006)
			(xy 346.839044 -397.28079) (xy 346.82193 -397.231239) (xy 346.817188 -397.205454) (xy 346.817188 -397.2052)
			(xy 346.813611 -397.179979) (xy 346.284753 -397.179979) (xy 346.583508 -397.696944) (xy 346.583762 -397.697452)
			(xy 346.584016 -397.697452) (xy 346.585286 -397.699992) (xy 346.597519 -397.722917) (xy 346.614853 -397.7719)
			(xy 346.623639 -397.82311) (xy 346.624148 -397.84909) (xy 346.624148 -397.849344) (xy 346.623674 -397.873334)
			(xy 346.616163 -397.920723) (xy 346.601332 -397.966354) (xy 346.579547 -398.009103) (xy 346.551343 -398.047919)
			(xy 346.517416 -398.081846) (xy 346.4786 -398.110049) (xy 346.43585 -398.131834) (xy 346.390219 -398.146664)
			(xy 346.34283 -398.154174) (xy 346.31884 -398.154652) (xy 346.295174 -398.154211) (xy 346.248407 -398.146916)
			(xy 346.203326 -398.132494) (xy 346.161008 -398.111291) (xy 346.122468 -398.083814) (xy 346.088628 -398.050721)
			(xy 346.060297 -398.012803) (xy 346.048838 -397.992092) (xy 346.048584 -397.99133) (xy 345.651328 -397.304006)
			(xy 345.639141 -397.280793) (xy 345.622036 -397.231239) (xy 345.617292 -397.205454) (xy 345.617292 -397.2052)
			(xy 345.6139 -397.181838) (xy 345.613521 -397.134634) (xy 345.61653 -397.11122) (xy 345.6178 -397.10233)
			(xy 345.614498 -397.085058) (xy 345.57081 -397.013938) (xy 345.557094 -397.002762) (xy 345.548458 -396.999968)
			(xy 345.529062 -396.993077) (xy 345.492179 -396.974804) (xy 345.458095 -396.951727) (xy 345.44254 -396.938246)
			(xy 345.435345 -396.932386) (xy 345.418027 -396.92576) (xy 345.408758 -396.925292) (xy 345.02598 -396.925292)
			(xy 345.015974 -396.925784) (xy 344.997488 -396.933446) (xy 344.98334 -396.947598) (xy 344.975681 -396.966086)
			(xy 344.97518 -396.976092) (xy 344.97518 -396.989808) (xy 344.982292 -397.001746) (xy 344.990928 -397.017494)
			(xy 344.991436 -397.018764) (xy 345.383358 -397.696944) (xy 345.383612 -397.697452) (xy 345.383866 -397.697452)
			(xy 345.385136 -397.699992) (xy 345.397405 -397.722909) (xy 345.414816 -397.771885) (xy 345.423685 -397.823101)
			(xy 345.424252 -397.84909) (xy 345.424252 -397.849344) (xy 345.423779 -397.873322) (xy 345.416276 -397.920686)
			(xy 345.40146 -397.966295) (xy 345.379697 -398.009028) (xy 345.351522 -398.047833) (xy 345.317627 -398.081757)
			(xy 345.278845 -398.109964) (xy 345.23613 -398.131763) (xy 345.190533 -398.146616) (xy 345.143175 -398.154159)
			(xy 345.119198 -398.154652) (xy 345.11869 -398.154652) (xy 345.095026 -398.154207) (xy 345.048264 -398.146906)
			(xy 345.003188 -398.132479) (xy 344.960877 -398.111272) (xy 344.922343 -398.083793) (xy 344.888509 -398.050699)
			(xy 344.860184 -398.012782) (xy 344.848688 -397.992092) (xy 344.848434 -397.99133) (xy 344.451178 -397.304006)
			(xy 344.43899 -397.280794) (xy 344.421881 -397.23124) (xy 344.417142 -397.205454) (xy 344.417142 -397.2052)
			(xy 344.413749 -397.181838) (xy 344.413371 -397.134634) (xy 344.41638 -397.11122) (xy 344.417904 -397.10233)
			(xy 344.414348 -397.084804) (xy 344.370914 -397.013938) (xy 344.356944 -397.002762) (xy 344.348562 -396.999968)
			(xy 344.329166 -396.993078) (xy 344.292283 -396.974804) (xy 344.258198 -396.951727) (xy 344.242644 -396.938246)
			(xy 344.235449 -396.932386) (xy 344.218131 -396.925758) (xy 344.208862 -396.925292) (xy 343.826084 -396.925292)
			(xy 343.816078 -396.925783) (xy 343.79759 -396.933445) (xy 343.78344 -396.947597) (xy 343.775781 -396.966086)
			(xy 343.775284 -396.976092) (xy 343.775284 -396.989808) (xy 343.782396 -397.001746) (xy 343.791032 -397.017494)
			(xy 343.79154 -397.018764) (xy 344.183462 -397.696944) (xy 344.183716 -397.697452) (xy 344.18397 -397.697452)
			(xy 344.18524 -397.699992) (xy 344.197509 -397.722909) (xy 344.21492 -397.771885) (xy 344.223788 -397.823101)
			(xy 344.224356 -397.84909) (xy 344.224356 -397.849344) (xy 344.223883 -397.873322) (xy 344.21638 -397.920686)
			(xy 344.201565 -397.966296) (xy 344.179802 -398.009029) (xy 344.151626 -398.047834) (xy 344.117731 -398.081758)
			(xy 344.078949 -398.109967) (xy 344.036235 -398.131766) (xy 343.990638 -398.146619) (xy 343.943279 -398.154163)
			(xy 343.919302 -398.154652) (xy 343.918794 -398.154652) (xy 343.89513 -398.154207) (xy 343.848368 -398.146906)
			(xy 343.803291 -398.13248) (xy 343.760979 -398.111273) (xy 343.722445 -398.083794) (xy 343.68861 -398.0507)
			(xy 343.660285 -398.012784) (xy 343.648792 -397.992092) (xy 343.648538 -397.99133) (xy 343.251282 -397.304006)
			(xy 343.239093 -397.280794) (xy 343.221985 -397.23124) (xy 343.217246 -397.205454) (xy 343.217246 -397.2052)
			(xy 343.213853 -397.181838) (xy 343.213475 -397.134634) (xy 343.216484 -397.11122) (xy 343.217754 -397.10233)
			(xy 343.214452 -397.085058) (xy 343.170764 -397.013938) (xy 343.157048 -397.002762) (xy 343.148412 -396.999968)
			(xy 343.127556 -396.992527) (xy 343.088081 -396.972464) (xy 343.051934 -396.946887) (xy 343.035636 -396.931896)
			(xy 343.030531 -396.927308) (xy 343.018418 -396.920861) (xy 343.01176 -396.919196) (xy 342.988451 -396.913444)
			(xy 342.944379 -396.894415) (xy 342.904661 -396.867453) (xy 342.8873 -396.85087) (xy 342.450674 -396.414244)
			(xy 342.433414 -396.396203) (xy 342.405657 -396.35471) (xy 342.386545 -396.308591) (xy 342.376814 -396.259627)
			(xy 342.376252 -396.234666) (xy 342.376252 -394.415772) (xy 342.376055 -394.409105) (xy 342.372576 -394.396234)
			(xy 342.369394 -394.390372) (xy 342.051386 -393.839954) (xy 342.039491 -393.817285) (xy 342.022622 -393.768954)
			(xy 342.014069 -393.718483) (xy 342.01354 -393.692888) (xy 342.01354 -393.69238) (xy 342.013988 -393.668389)
			(xy 342.021497 -393.620999) (xy 342.036328 -393.575367) (xy 342.058115 -393.532617) (xy 342.086322 -393.493802)
			(xy 342.120254 -393.459878) (xy 342.159075 -393.43168) (xy 342.20183 -393.409902) (xy 342.247465 -393.395081)
			(xy 342.294857 -393.387582) (xy 342.318848 -393.387072) (xy 342.324436 -393.387072) (xy 342.361012 -393.351258)
			(xy 342.367966 -393.343835) (xy 342.375843 -393.325099) (xy 342.376252 -393.314936) (xy 342.376252 -392.652504)
			(xy 342.375828 -392.642435) (xy 342.368109 -392.623834) (xy 342.361266 -392.616436) (xy 342.162638 -392.417808)
			(xy 342.155237 -392.41097) (xy 342.136638 -392.403257) (xy 342.12657 -392.402822) (xy 332.87462 -392.402822)
			(xy 332.8416 -392.415014) (xy 332.820758 -392.432227) (xy 332.775138 -392.461221) (xy 332.725885 -392.483489)
			(xy 332.673982 -392.498587) (xy 332.620469 -392.506212) (xy 332.566415 -392.506212) (xy 332.512902 -392.498587)
			(xy 332.460999 -392.483489) (xy 332.411746 -392.461221) (xy 332.366126 -392.432227) (xy 332.345284 -392.415014)
			(xy 332.312264 -392.402822) (xy 330.129642 -392.402822) (xy 330.119577 -392.403256) (xy 330.10099 -392.410988)
			(xy 330.093574 -392.417808) (xy 329.571858 -392.939524) (xy 329.565009 -392.946921) (xy 329.557274 -392.96552)
			(xy 329.556872 -392.975592) (xy 329.556872 -393.692888) (xy 336.013552 -393.692888) (xy 336.013552 -393.69238)
			(xy 336.014044 -393.66839) (xy 336.021552 -393.621002) (xy 336.03638 -393.575371) (xy 336.058162 -393.532621)
			(xy 336.086363 -393.493804) (xy 336.120289 -393.459876) (xy 336.159104 -393.431673) (xy 336.201852 -393.409887)
			(xy 336.247482 -393.395057) (xy 336.29487 -393.387546) (xy 336.31886 -393.387072) (xy 336.342795 -393.387531)
			(xy 336.39008 -393.39499) (xy 336.435623 -393.409733) (xy 336.47831 -393.431398) (xy 336.517095 -393.459455)
			(xy 336.551031 -393.493217) (xy 336.579285 -393.531859) (xy 336.59064 -393.552934) (xy 336.591148 -393.55395)
			(xy 336.671454 -393.692888) (xy 337.213448 -393.692888) (xy 337.213448 -393.69238) (xy 337.213944 -393.66839)
			(xy 337.221452 -393.621002) (xy 337.236279 -393.575372) (xy 337.258061 -393.532622) (xy 337.286262 -393.493805)
			(xy 337.320187 -393.459878) (xy 337.359001 -393.431674) (xy 337.401749 -393.409888) (xy 337.447379 -393.395057)
			(xy 337.494766 -393.387546) (xy 337.518756 -393.387072) (xy 337.542691 -393.387534) (xy 337.589976 -393.394993)
			(xy 337.635519 -393.409735) (xy 337.678205 -393.431399) (xy 337.716991 -393.459456) (xy 337.750926 -393.493218)
			(xy 337.779181 -393.531859) (xy 337.790536 -393.552934) (xy 337.791044 -393.55395) (xy 337.87135 -393.692888)
			(xy 338.413344 -393.692888) (xy 338.413344 -393.69238) (xy 338.413844 -393.668391) (xy 338.421352 -393.621003)
			(xy 338.436179 -393.575373) (xy 338.457961 -393.532623) (xy 338.486161 -393.493807) (xy 338.520086 -393.459879)
			(xy 338.558899 -393.431675) (xy 338.601647 -393.40989) (xy 338.647276 -393.395058) (xy 338.694663 -393.387546)
			(xy 338.718652 -393.387072) (xy 338.718906 -393.387072) (xy 338.742839 -393.387575) (xy 338.790122 -393.395026)
			(xy 338.835664 -393.40976) (xy 338.878351 -393.431418) (xy 338.917137 -393.459468) (xy 338.951074 -393.493225)
			(xy 338.97933 -393.531861) (xy 338.990686 -393.552934) (xy 338.991194 -393.55395) (xy 339.0715 -393.692888)
			(xy 339.61324 -393.692888) (xy 339.61324 -393.69238) (xy 339.613621 -393.668371) (xy 339.62114 -393.620946)
			(xy 339.63599 -393.575282) (xy 339.657804 -393.532506) (xy 339.686045 -393.493671) (xy 339.720016 -393.459735)
			(xy 339.758881 -393.431535) (xy 339.80168 -393.409766) (xy 339.84736 -393.394965) (xy 339.894793 -393.387496)
			(xy 339.918802 -393.387072) (xy 339.942735 -393.387578) (xy 339.990018 -393.395028) (xy 340.03556 -393.409763)
			(xy 340.078247 -393.43142) (xy 340.117033 -393.459469) (xy 340.15097 -393.493225) (xy 340.179226 -393.531861)
			(xy 340.190582 -393.552934) (xy 340.19109 -393.55395) (xy 340.271396 -393.692888) (xy 340.813136 -393.692888)
			(xy 340.813136 -393.69238) (xy 340.813521 -393.668371) (xy 340.82104 -393.620947) (xy 340.835889 -393.575283)
			(xy 340.857703 -393.532507) (xy 340.885944 -393.493672) (xy 340.919915 -393.459737) (xy 340.958779 -393.431537)
			(xy 341.001577 -393.409767) (xy 341.047256 -393.394965) (xy 341.094689 -393.387496) (xy 341.118698 -393.387072)
			(xy 341.142634 -393.3875) (xy 341.189921 -393.394965) (xy 341.235464 -393.409713) (xy 341.278151 -393.431383)
			(xy 341.316936 -393.459445) (xy 341.35087 -393.493212) (xy 341.379124 -393.531857) (xy 341.390478 -393.552934)
			(xy 341.390986 -393.55395) (xy 341.783416 -394.232892) (xy 341.796168 -394.256248) (xy 341.814276 -394.306281)
			(xy 341.823478 -394.358688) (xy 341.824056 -394.385292) (xy 341.82353 -394.409281) (xy 341.816027 -394.456667)
			(xy 341.801203 -394.502297) (xy 341.779425 -394.545047) (xy 341.751228 -394.583863) (xy 341.717306 -394.617791)
			(xy 341.678494 -394.645996) (xy 341.635749 -394.667782) (xy 341.590122 -394.682614) (xy 341.542737 -394.690126)
			(xy 341.518748 -394.6906) (xy 341.495175 -394.690168) (xy 341.448589 -394.682933) (xy 341.403671 -394.668614)
			(xy 341.361493 -394.647552) (xy 341.323059 -394.620248) (xy 341.289286 -394.587354) (xy 341.260979 -394.549654)
			(xy 341.249508 -394.529056) (xy 341.249 -394.528294) (xy 340.851236 -393.839954) (xy 340.839305 -393.817294)
			(xy 340.822372 -393.768964) (xy 340.813719 -393.718491) (xy 340.813136 -393.692888) (xy 340.271396 -393.692888)
			(xy 340.58352 -394.232892) (xy 340.596272 -394.256248) (xy 340.61438 -394.306281) (xy 340.623582 -394.358688)
			(xy 340.62416 -394.385292) (xy 340.623754 -394.409287) (xy 340.616247 -394.456687) (xy 340.601417 -394.502329)
			(xy 340.579628 -394.545088) (xy 340.551418 -394.583912) (xy 340.517482 -394.617844) (xy 340.478654 -394.646049)
			(xy 340.435892 -394.667832) (xy 340.390248 -394.682657) (xy 340.342847 -394.690157) (xy 340.318852 -394.6906)
			(xy 340.295279 -394.690164) (xy 340.248693 -394.682931) (xy 340.203776 -394.668612) (xy 340.161597 -394.647551)
			(xy 340.123164 -394.620247) (xy 340.089391 -394.587354) (xy 340.061083 -394.549653) (xy 340.049612 -394.529056)
			(xy 340.049104 -394.528294) (xy 339.65134 -393.839954) (xy 339.639409 -393.817293) (xy 339.622476 -393.768964)
			(xy 339.613823 -393.718491) (xy 339.61324 -393.692888) (xy 339.0715 -393.692888) (xy 339.383624 -394.232892)
			(xy 339.396376 -394.256248) (xy 339.414484 -394.30628) (xy 339.423686 -394.358688) (xy 339.424264 -394.385292)
			(xy 339.423854 -394.409287) (xy 339.416347 -394.456687) (xy 339.401517 -394.502328) (xy 339.379729 -394.545087)
			(xy 339.351519 -394.583911) (xy 339.317583 -394.617843) (xy 339.278756 -394.646048) (xy 339.235995 -394.667831)
			(xy 339.190352 -394.682656) (xy 339.142951 -394.690157) (xy 339.118956 -394.6906) (xy 339.118702 -394.6906)
			(xy 339.095128 -394.690205) (xy 339.04854 -394.682963) (xy 339.003621 -394.668638) (xy 338.961443 -394.64757)
			(xy 338.92301 -394.62026) (xy 338.889238 -394.587361) (xy 338.860933 -394.549656) (xy 338.849462 -394.529056)
			(xy 338.848954 -394.528294) (xy 338.45119 -393.839954) (xy 338.439334 -393.817267) (xy 338.422475 -393.768939)
			(xy 338.413894 -393.718479) (xy 338.413344 -393.692888) (xy 337.87135 -393.692888) (xy 338.183474 -394.232892)
			(xy 338.196301 -394.256223) (xy 338.21452 -394.306247) (xy 338.223779 -394.358673) (xy 338.224368 -394.385292)
			(xy 338.223953 -394.4093) (xy 338.216439 -394.456723) (xy 338.201593 -394.502386) (xy 338.179783 -394.545162)
			(xy 338.151546 -394.583996) (xy 338.117579 -394.617932) (xy 338.078717 -394.646133) (xy 338.035921 -394.667903)
			(xy 337.990245 -394.682706) (xy 337.942814 -394.690176) (xy 337.918806 -394.6906) (xy 337.895232 -394.690201)
			(xy 337.848644 -394.682961) (xy 337.803726 -394.668636) (xy 337.761547 -394.647568) (xy 337.723114 -394.620259)
			(xy 337.689342 -394.58736) (xy 337.661037 -394.549655) (xy 337.649566 -394.529056) (xy 337.649058 -394.528294)
			(xy 337.251294 -393.839954) (xy 337.239438 -393.817267) (xy 337.222579 -393.768939) (xy 337.213998 -393.718479)
			(xy 337.213448 -393.692888) (xy 336.671454 -393.692888) (xy 336.983578 -394.232892) (xy 336.996406 -394.256223)
			(xy 337.014624 -394.306247) (xy 337.023883 -394.358673) (xy 337.024472 -394.385292) (xy 337.024053 -394.409299)
			(xy 337.016539 -394.456723) (xy 337.001694 -394.502385) (xy 336.979884 -394.545161) (xy 336.951648 -394.583995)
			(xy 336.91768 -394.617931) (xy 336.87882 -394.646132) (xy 336.836024 -394.667902) (xy 336.790348 -394.682705)
			(xy 336.742918 -394.690175) (xy 336.71891 -394.6906) (xy 336.695336 -394.690198) (xy 336.648748 -394.682958)
			(xy 336.60383 -394.668634) (xy 336.561652 -394.647566) (xy 336.523218 -394.620258) (xy 336.489447 -394.58736)
			(xy 336.461141 -394.549655) (xy 336.44967 -394.529056) (xy 336.449162 -394.528294) (xy 336.051398 -393.839954)
			(xy 336.039542 -393.817267) (xy 336.022683 -393.768939) (xy 336.014102 -393.718479) (xy 336.013552 -393.692888)
			(xy 329.556872 -393.692888) (xy 329.556872 -394.14196) (xy 329.556295 -394.166918) (xy 329.546545 -394.215873)
			(xy 329.527432 -394.261985) (xy 329.49969 -394.303482) (xy 329.48245 -394.321538) (xy 327.906634 -395.897354)
			(xy 327.888592 -395.914611) (xy 327.847097 -395.942364) (xy 327.800979 -395.961472) (xy 327.752016 -395.9712)
			(xy 327.727056 -395.971776) (xy 325.906384 -395.971776) (xy 325.896315 -395.972201) (xy 325.877712 -395.979917)
			(xy 325.870316 -395.986762) (xy 325.685404 -396.171674) (xy 329.428856 -396.171674) (xy 329.428856 -395.308074)
			(xy 329.429342 -395.280823) (xy 329.437098 -395.226875) (xy 329.452453 -395.17458) (xy 329.475095 -395.125003)
			(xy 329.504561 -395.079153) (xy 329.540252 -395.037962) (xy 329.581443 -395.002271) (xy 329.627293 -394.972805)
			(xy 329.67687 -394.950163) (xy 329.729165 -394.934808) (xy 329.783113 -394.927052) (xy 329.837615 -394.927052)
			(xy 329.891563 -394.934808) (xy 329.943858 -394.950163) (xy 329.993435 -394.972805) (xy 330.039285 -395.002271)
			(xy 330.080476 -395.037962) (xy 330.116167 -395.079153) (xy 330.145633 -395.125003) (xy 330.168275 -395.17458)
			(xy 330.18363 -395.226875) (xy 330.191386 -395.280823) (xy 330.191872 -395.308074) (xy 330.191872 -396.171674)
			(xy 330.191386 -396.198925) (xy 330.18363 -396.252873) (xy 330.168275 -396.305168) (xy 330.145633 -396.354745)
			(xy 330.116167 -396.400595) (xy 330.080476 -396.441786) (xy 330.039285 -396.477477) (xy 329.993435 -396.506943)
			(xy 329.943858 -396.529585) (xy 329.891563 -396.54494) (xy 329.837615 -396.552696) (xy 329.783113 -396.552696)
			(xy 329.729165 -396.54494) (xy 329.67687 -396.529585) (xy 329.627293 -396.506943) (xy 329.581443 -396.477477)
			(xy 329.540252 -396.441786) (xy 329.504561 -396.400595) (xy 329.475095 -396.354745) (xy 329.452453 -396.305168)
			(xy 329.437098 -396.252873) (xy 329.429342 -396.198925) (xy 329.428856 -396.171674) (xy 325.685404 -396.171674)
			(xy 325.362062 -396.495016) (xy 325.344022 -396.512278) (xy 325.302529 -396.540039) (xy 325.256411 -396.559155)
			(xy 325.207446 -396.56889) (xy 325.182484 -396.569438) (xy 317.145416 -396.569438) (xy 317.120462 -396.568819)
			(xy 317.071516 -396.559068) (xy 317.025412 -396.539959) (xy 316.98392 -396.512224) (xy 316.965838 -396.495016)
			(xy 316.842902 -396.37208) (xy 316.816232 -396.365222) (xy 316.80277 -396.369032) (xy 316.782072 -396.374618)
			(xy 316.739623 -396.380611) (xy 316.718188 -396.38097) (xy 316.694197 -396.380523) (xy 316.646805 -396.373014)
			(xy 316.601171 -396.358184) (xy 316.558419 -396.336398) (xy 316.519602 -396.308191) (xy 316.485676 -396.274259)
			(xy 316.457476 -396.235438) (xy 316.435697 -396.192683) (xy 316.420874 -396.147047) (xy 316.413373 -396.099654)
			(xy 316.41288 -396.075662) (xy 316.413244 -396.054227) (xy 316.419238 -396.011779) (xy 316.424818 -395.99108)
			(xy 316.428628 -395.977618) (xy 316.42177 -395.950948) (xy 315.698886 -395.228064) (xy 315.69149 -395.221213)
			(xy 315.672891 -395.213474) (xy 315.662818 -395.213078) (xy 315.214508 -395.213078) (xy 315.204437 -395.213499)
			(xy 315.185828 -395.221209) (xy 315.17844 -395.228064) (xy 314.57265 -395.833854) (xy 314.565964 -395.841264)
			(xy 314.558373 -395.859699) (xy 314.557918 -395.869668) (xy 314.567316 -395.899132) (xy 314.58056 -395.918596)
			(xy 314.601541 -395.960739) (xy 314.615806 -396.005602) (xy 314.62302 -396.052123) (xy 314.62345 -396.075662)
			(xy 314.622982 -396.099656) (xy 314.615481 -396.147055) (xy 314.600658 -396.192697) (xy 314.578877 -396.235458)
			(xy 314.550675 -396.274285) (xy 314.516746 -396.308223) (xy 314.477926 -396.336435) (xy 314.435171 -396.358227)
			(xy 314.389533 -396.373062) (xy 314.342136 -396.380576) (xy 314.318142 -396.38097) (xy 314.294605 -396.380533)
			(xy 314.248088 -396.373309) (xy 314.203227 -396.359042) (xy 314.161083 -396.338067) (xy 314.141612 -396.324836)
			(xy 314.112148 -396.315438) (xy 314.102186 -396.315923) (xy 314.083761 -396.323511) (xy 314.076334 -396.33017)
			(xy 313.608466 -396.798038) (xy 313.601654 -396.805382) (xy 313.593925 -396.823845) (xy 313.59348 -396.833852)
			(xy 313.593226 -396.915894) (xy 313.600846 -396.934182) (xy 313.607958 -396.941548) (xy 313.624173 -396.95846)
			(xy 313.651727 -396.99635) (xy 313.662822 -397.016986) (xy 313.66333 -397.018002) (xy 313.743636 -397.15694)
			(xy 314.285376 -397.15694) (xy 314.285376 -397.156432) (xy 314.285869 -397.132428) (xy 314.293378 -397.085011)
			(xy 314.308217 -397.039353) (xy 314.330019 -396.996581) (xy 314.358247 -396.957748) (xy 314.392205 -396.923813)
			(xy 314.431057 -396.895611) (xy 314.473844 -396.873838) (xy 314.519511 -396.85903) (xy 314.566934 -396.851552)
			(xy 314.590938 -396.851124) (xy 314.614874 -396.851573) (xy 314.662161 -396.85903) (xy 314.707705 -396.873772)
			(xy 314.750393 -396.895438) (xy 314.789179 -396.923498) (xy 314.823113 -396.957263) (xy 314.851365 -396.995909)
			(xy 314.862718 -397.016986) (xy 314.863226 -397.018002) (xy 314.943532 -397.15694) (xy 315.48578 -397.15694)
			(xy 315.48578 -397.156432) (xy 315.486268 -397.13244) (xy 315.493769 -397.085047) (xy 315.508593 -397.039411)
			(xy 315.530373 -396.996656) (xy 315.558574 -396.957834) (xy 315.592501 -396.923902) (xy 315.631318 -396.895696)
			(xy 315.67407 -396.87391) (xy 315.719704 -396.85908) (xy 315.767096 -396.851571) (xy 315.791088 -396.851124)
			(xy 315.815025 -396.851532) (xy 315.862314 -396.858997) (xy 315.90786 -396.873747) (xy 315.950547 -396.895419)
			(xy 315.989333 -396.923485) (xy 316.023266 -396.957256) (xy 316.051516 -396.995907) (xy 316.062868 -397.016986)
			(xy 316.063376 -397.018002) (xy 316.143682 -397.15694) (xy 316.685676 -397.15694) (xy 316.685676 -397.156432)
			(xy 316.686168 -397.132441) (xy 316.693669 -397.085048) (xy 316.708492 -397.039412) (xy 316.730272 -396.996657)
			(xy 316.758473 -396.957836) (xy 316.792399 -396.923904) (xy 316.831216 -396.895697) (xy 316.873967 -396.873911)
			(xy 316.919601 -396.85908) (xy 316.966993 -396.851571) (xy 316.990984 -396.851124) (xy 317.014921 -396.851535)
			(xy 317.06221 -396.859) (xy 317.107755 -396.873749) (xy 317.150443 -396.895421) (xy 317.189228 -396.923486)
			(xy 317.223161 -396.957257) (xy 317.251412 -396.995907) (xy 317.262764 -397.016986) (xy 317.263272 -397.018002)
			(xy 317.343578 -397.15694) (xy 317.885572 -397.15694) (xy 317.885572 -397.156432) (xy 317.886068 -397.132441)
			(xy 317.893569 -397.085048) (xy 317.908392 -397.039413) (xy 317.930172 -396.996658) (xy 317.958371 -396.957837)
			(xy 317.992297 -396.923905) (xy 318.031114 -396.895699) (xy 318.073865 -396.873912) (xy 318.119498 -396.859081)
			(xy 318.166889 -396.851572) (xy 318.19088 -396.851124) (xy 318.214817 -396.851539) (xy 318.262105 -396.859002)
			(xy 318.307651 -396.873751) (xy 318.350339 -396.895422) (xy 318.389124 -396.923487) (xy 318.423057 -396.957257)
			(xy 318.451308 -396.995907) (xy 318.46266 -397.016986) (xy 318.463168 -397.018002) (xy 318.543474 -397.15694)
			(xy 319.085468 -397.15694) (xy 319.085468 -397.156432) (xy 319.085969 -397.132428) (xy 319.093478 -397.085012)
			(xy 319.108316 -397.039355) (xy 319.130117 -396.996583) (xy 319.158345 -396.957751) (xy 319.192302 -396.923816)
			(xy 319.231152 -396.895614) (xy 319.273938 -396.87384) (xy 319.319605 -396.859031) (xy 319.367026 -396.851553)
			(xy 319.39103 -396.851124) (xy 319.414965 -396.851579) (xy 319.462252 -396.859035) (xy 319.507797 -396.873776)
			(xy 319.550484 -396.895441) (xy 319.58927 -396.9235) (xy 319.623205 -396.957264) (xy 319.651457 -396.995909)
			(xy 319.66281 -397.016986) (xy 319.663318 -397.018002) (xy 319.743624 -397.15694) (xy 320.285364 -397.15694)
			(xy 320.285364 -397.156432) (xy 320.285869 -397.132428) (xy 320.293378 -397.085012) (xy 320.308215 -397.039356)
			(xy 320.330017 -396.996584) (xy 320.358243 -396.957753) (xy 320.3922 -396.923817) (xy 320.43105 -396.895615)
			(xy 320.473835 -396.873841) (xy 320.519501 -396.859032) (xy 320.566922 -396.851553) (xy 320.590926 -396.851124)
			(xy 320.614861 -396.851582) (xy 320.662148 -396.859038) (xy 320.707692 -396.873778) (xy 320.75038 -396.895443)
			(xy 320.789166 -396.923501) (xy 320.823101 -396.957265) (xy 320.851353 -396.995909) (xy 320.862706 -397.016986)
			(xy 320.863214 -397.018002) (xy 320.94352 -397.15694) (xy 321.485768 -397.15694) (xy 321.485768 -397.156432)
			(xy 321.486268 -397.132441) (xy 321.493769 -397.085049) (xy 321.508592 -397.039414) (xy 321.530371 -396.996659)
			(xy 321.55857 -396.957838) (xy 321.592496 -396.923907) (xy 321.631311 -396.8957) (xy 321.674062 -396.873913)
			(xy 321.719694 -396.859082) (xy 321.767085 -396.851572) (xy 321.791076 -396.851124) (xy 321.815013 -396.851542)
			(xy 321.862301 -396.859005) (xy 321.907847 -396.873753) (xy 321.950534 -396.895424) (xy 321.98932 -396.923488)
			(xy 322.023253 -396.957258) (xy 322.051504 -396.995907) (xy 322.062856 -397.016986) (xy 322.063364 -397.018002)
			(xy 322.129999 -397.133287) (xy 336.013603 -397.133287) (xy 336.020935 -397.085732) (xy 336.035629 -397.039915)
			(xy 336.057324 -396.996967) (xy 336.085482 -396.95795) (xy 336.119407 -396.923829) (xy 336.15826 -396.895446)
			(xy 336.201082 -396.873504) (xy 336.246814 -396.858545) (xy 336.294325 -396.850939) (xy 336.342442 -396.850873)
			(xy 336.389974 -396.85835) (xy 336.435746 -396.873184) (xy 336.478628 -396.895009) (xy 336.517559 -396.923285)
			(xy 336.551577 -396.957314) (xy 336.579841 -396.996254) (xy 336.591148 -397.017494) (xy 336.591656 -397.018764)
			(xy 336.657839 -397.133287) (xy 337.213506 -397.133287) (xy 337.220838 -397.085733) (xy 337.235533 -397.039916)
			(xy 337.257227 -396.996969) (xy 337.285384 -396.957952) (xy 337.319309 -396.923831) (xy 337.358162 -396.895449)
			(xy 337.400983 -396.873508) (xy 337.446714 -396.858549) (xy 337.494225 -396.850942) (xy 337.54234 -396.850877)
			(xy 337.589872 -396.858353) (xy 337.635644 -396.873187) (xy 337.678525 -396.895011) (xy 337.717455 -396.923287)
			(xy 337.751473 -396.957315) (xy 337.779737 -396.996254) (xy 337.791044 -397.017494) (xy 337.791552 -397.018764)
			(xy 337.857735 -397.133286) (xy 338.41341 -397.133286) (xy 338.420742 -397.085733) (xy 338.435436 -397.039917)
			(xy 338.45713 -396.996971) (xy 338.485287 -396.957955) (xy 338.519211 -396.923834) (xy 338.558063 -396.895453)
			(xy 338.600884 -396.873511) (xy 338.646615 -396.858552) (xy 338.694124 -396.850946) (xy 338.742239 -396.85088)
			(xy 338.78977 -396.858356) (xy 338.835541 -396.87319) (xy 338.878422 -396.895014) (xy 338.917352 -396.923289)
			(xy 338.951369 -396.957316) (xy 338.979633 -396.996254) (xy 338.99094 -397.017494) (xy 338.991448 -397.018764)
			(xy 339.057629 -397.133284) (xy 339.613655 -397.133284) (xy 339.620986 -397.08574) (xy 339.635678 -397.039932)
			(xy 339.657368 -396.996993) (xy 339.68552 -396.957985) (xy 339.719438 -396.92387) (xy 339.758283 -396.895493)
			(xy 339.801095 -396.873555) (xy 339.846817 -396.858598) (xy 339.894318 -396.850991) (xy 339.942424 -396.850924)
			(xy 339.989947 -396.858397) (xy 340.03571 -396.873225) (xy 340.078584 -396.895043) (xy 340.117509 -396.923311)
			(xy 340.151522 -396.95733) (xy 340.179784 -396.996259) (xy 340.19109 -397.017494) (xy 340.191598 -397.018764)
			(xy 340.257779 -397.133284) (xy 340.813558 -397.133284) (xy 340.82089 -397.08574) (xy 340.835582 -397.039933)
			(xy 340.857271 -396.996995) (xy 340.885423 -396.957987) (xy 340.91934 -396.923873) (xy 340.958184 -396.895496)
			(xy 341.000996 -396.873558) (xy 341.046717 -396.858601) (xy 341.094218 -396.850995) (xy 341.142323 -396.850927)
			(xy 341.189845 -396.8584) (xy 341.235608 -396.873228) (xy 341.278481 -396.895045) (xy 341.317406 -396.923312)
			(xy 341.351419 -396.957331) (xy 341.37968 -396.996259) (xy 341.390986 -397.017494) (xy 341.391494 -397.018764)
			(xy 341.457677 -397.133286) (xy 342.013613 -397.133286) (xy 342.020945 -397.085734) (xy 342.03564 -397.039918)
			(xy 342.057333 -396.996972) (xy 342.08549 -396.957957) (xy 342.119413 -396.923837) (xy 342.158265 -396.895456)
			(xy 342.201085 -396.873515) (xy 342.246815 -396.858556) (xy 342.294324 -396.85095) (xy 342.342438 -396.850884)
			(xy 342.389968 -396.858359) (xy 342.435739 -396.873192) (xy 342.478619 -396.895016) (xy 342.517549 -396.92329)
			(xy 342.551566 -396.957317) (xy 342.579829 -396.996255) (xy 342.591136 -397.017494) (xy 342.591644 -397.018764)
			(xy 342.983566 -397.696944) (xy 342.98382 -397.697452) (xy 342.984074 -397.697452) (xy 342.985344 -397.699992)
			(xy 342.997619 -397.722906) (xy 343.015023 -397.771885) (xy 343.023896 -397.823101) (xy 343.02446 -397.84909)
			(xy 343.02446 -397.849344) (xy 343.024101 -397.873353) (xy 343.016579 -397.92078) (xy 343.001726 -397.966444)
			(xy 342.979909 -398.00922) (xy 342.951665 -398.048055) (xy 342.917691 -398.08199) (xy 342.878825 -398.11019)
			(xy 342.836023 -398.131958) (xy 342.790342 -398.146759) (xy 342.742908 -398.154228) (xy 342.718898 -398.154652)
			(xy 342.695234 -398.154214) (xy 342.648472 -398.146903) (xy 342.603397 -398.132472) (xy 342.561085 -398.111266)
			(xy 342.522547 -398.083791) (xy 342.488704 -398.050704) (xy 342.460366 -398.012796) (xy 342.448896 -397.992092)
			(xy 342.448642 -397.99133) (xy 342.051386 -397.304006) (xy 342.03921 -397.280788) (xy 342.022093 -397.231238)
			(xy 342.01735 -397.205454) (xy 342.01735 -397.2052) (xy 342.013825 -397.1814) (xy 342.013613 -397.133286)
			(xy 341.457677 -397.133286) (xy 341.783416 -397.696944) (xy 341.78367 -397.697452) (xy 341.783924 -397.697452)
			(xy 341.785194 -397.699992) (xy 341.797425 -397.722917) (xy 341.814746 -397.771902) (xy 341.823534 -397.823111)
			(xy 341.824056 -397.84909) (xy 341.824056 -397.849344) (xy 341.823578 -397.873334) (xy 341.816067 -397.920723)
			(xy 341.801236 -397.966353) (xy 341.779452 -398.009103) (xy 341.751249 -398.047919) (xy 341.717322 -398.081846)
			(xy 341.678506 -398.11005) (xy 341.635757 -398.131835) (xy 341.590127 -398.146666) (xy 341.542738 -398.154178)
			(xy 341.518748 -398.154652) (xy 341.495085 -398.154174) (xy 341.448326 -398.146871) (xy 341.403251 -398.132447)
			(xy 341.360939 -398.111247) (xy 341.3224 -398.083778) (xy 341.288557 -398.050697) (xy 341.260217 -398.012794)
			(xy 341.248746 -397.992092) (xy 341.248492 -397.99133) (xy 340.851236 -397.304006) (xy 340.839056 -397.28079)
			(xy 340.821942 -397.231239) (xy 340.8172 -397.205454) (xy 340.8172 -397.2052) (xy 340.813769 -397.181389)
			(xy 340.813558 -397.133284) (xy 340.257779 -397.133284) (xy 340.58352 -397.696944) (xy 340.583774 -397.697452)
			(xy 340.584028 -397.697452) (xy 340.585298 -397.699992) (xy 340.597529 -397.722917) (xy 340.61485 -397.771902)
			(xy 340.623638 -397.823111) (xy 340.62416 -397.84909) (xy 340.62416 -397.849344) (xy 340.623802 -397.873341)
			(xy 340.616287 -397.920742) (xy 340.60145 -397.966385) (xy 340.579655 -398.009144) (xy 340.551439 -398.047968)
			(xy 340.517498 -398.081899) (xy 340.478666 -398.110103) (xy 340.4359 -398.131885) (xy 340.390253 -398.146709)
			(xy 340.342849 -398.154209) (xy 340.318852 -398.154652) (xy 340.295189 -398.154171) (xy 340.24843 -398.146868)
			(xy 340.203356 -398.132445) (xy 340.161043 -398.111245) (xy 340.122505 -398.083777) (xy 340.088661 -398.050696)
			(xy 340.060321 -398.012793) (xy 340.04885 -397.992092) (xy 340.048596 -397.99133) (xy 339.65134 -397.304006)
			(xy 339.639161 -397.28079) (xy 339.622046 -397.231239) (xy 339.617304 -397.205454) (xy 339.617304 -397.2052)
			(xy 339.613866 -397.18139) (xy 339.613655 -397.133284) (xy 339.057629 -397.133284) (xy 339.38337 -397.696944)
			(xy 339.383624 -397.697452) (xy 339.383878 -397.697452) (xy 339.385148 -397.699992) (xy 339.397423 -397.722906)
			(xy 339.414827 -397.771885) (xy 339.4237 -397.823101) (xy 339.424264 -397.84909) (xy 339.424264 -397.849344)
			(xy 339.423901 -397.873353) (xy 339.416379 -397.920779) (xy 339.401526 -397.966443) (xy 339.379709 -398.009219)
			(xy 339.351466 -398.048053) (xy 339.317493 -398.081989) (xy 339.278627 -398.110188) (xy 339.235826 -398.131957)
			(xy 339.190146 -398.146759) (xy 339.142712 -398.154228) (xy 339.118702 -398.154652) (xy 339.095038 -398.154211)
			(xy 339.048277 -398.146901) (xy 339.003201 -398.13247) (xy 338.960889 -398.111264) (xy 338.922351 -398.08379)
			(xy 338.888508 -398.050703) (xy 338.86017 -398.012796) (xy 338.8487 -397.992092) (xy 338.848446 -397.99133)
			(xy 338.45119 -397.304006) (xy 338.439014 -397.280788) (xy 338.421897 -397.231238) (xy 338.417154 -397.205454)
			(xy 338.417154 -397.2052) (xy 338.413622 -397.181401) (xy 338.41341 -397.133286) (xy 337.857735 -397.133286)
			(xy 338.183474 -397.696944) (xy 338.183728 -397.697452) (xy 338.183982 -397.697452) (xy 338.185252 -397.699992)
			(xy 338.197527 -397.722906) (xy 338.214931 -397.771885) (xy 338.223804 -397.823101) (xy 338.224368 -397.84909)
			(xy 338.224368 -397.849344) (xy 338.224001 -397.873353) (xy 338.216479 -397.920778) (xy 338.201626 -397.966442)
			(xy 338.17981 -398.009218) (xy 338.151567 -398.048052) (xy 338.117595 -398.081987) (xy 338.078729 -398.110187)
			(xy 338.035929 -398.131956) (xy 337.990249 -398.146758) (xy 337.942816 -398.154228) (xy 337.918806 -398.154652)
			(xy 337.895142 -398.154208) (xy 337.848381 -398.146898) (xy 337.803306 -398.132468) (xy 337.760993 -398.111263)
			(xy 337.722455 -398.083789) (xy 337.688613 -398.050703) (xy 337.660274 -398.012795) (xy 337.648804 -397.992092)
			(xy 337.64855 -397.99133) (xy 337.251294 -397.304006) (xy 337.239112 -397.280791) (xy 337.221999 -397.231239)
			(xy 337.217258 -397.205454) (xy 337.217258 -397.2052) (xy 337.213718 -397.181402) (xy 337.213506 -397.133287)
			(xy 336.657839 -397.133287) (xy 336.983578 -397.696944) (xy 336.983832 -397.697452) (xy 336.984086 -397.697452)
			(xy 336.985356 -397.699992) (xy 336.997631 -397.722906) (xy 337.015035 -397.771885) (xy 337.023908 -397.823101)
			(xy 337.024472 -397.84909) (xy 337.024472 -397.849344) (xy 337.024101 -397.873353) (xy 337.016579 -397.920778)
			(xy 337.001727 -397.966441) (xy 336.979911 -398.009217) (xy 336.951668 -398.048051) (xy 336.917696 -398.081986)
			(xy 336.878831 -398.110185) (xy 336.836032 -398.131955) (xy 336.790352 -398.146757) (xy 336.742919 -398.154228)
			(xy 336.71891 -398.154652) (xy 336.695246 -398.154205) (xy 336.648485 -398.146896) (xy 336.60341 -398.132466)
			(xy 336.561098 -398.111261) (xy 336.522559 -398.083788) (xy 336.488717 -398.050702) (xy 336.460378 -398.012795)
			(xy 336.448908 -397.992092) (xy 336.448654 -397.99133) (xy 336.051398 -397.304006) (xy 336.039216 -397.280791)
			(xy 336.022103 -397.231239) (xy 336.017362 -397.205454) (xy 336.017362 -397.2052) (xy 336.013815 -397.181402)
			(xy 336.013603 -397.133287) (xy 322.129999 -397.133287) (xy 322.455794 -397.696944) (xy 322.468605 -397.720283)
			(xy 322.486829 -397.770303) (xy 322.496095 -397.822726) (xy 322.496688 -397.849344) (xy 322.496301 -397.873352)
			(xy 322.48878 -397.920775) (xy 322.473928 -397.966437) (xy 322.452114 -398.009212) (xy 322.423873 -398.048045)
			(xy 322.389903 -398.08198) (xy 322.35104 -398.11018) (xy 322.308243 -398.13195) (xy 322.262566 -398.146754)
			(xy 322.215134 -398.154226) (xy 322.191126 -398.154652) (xy 322.167554 -398.15421) (xy 322.120969 -398.146974)
			(xy 322.076053 -398.132654) (xy 322.033876 -398.111593) (xy 321.995443 -398.084292) (xy 321.961669 -398.051401)
			(xy 321.933359 -398.013704) (xy 321.921886 -397.993108) (xy 321.921378 -397.992346) (xy 321.523614 -397.304006)
			(xy 321.511735 -397.281331) (xy 321.494886 -397.232997) (xy 321.486314 -397.182533) (xy 321.485768 -397.15694)
			(xy 320.94352 -397.15694) (xy 321.255644 -397.696944) (xy 321.26838 -397.720308) (xy 321.286493 -397.770337)
			(xy 321.295702 -397.822741) (xy 321.296284 -397.849344) (xy 321.295878 -397.873338) (xy 321.288364 -397.920733)
			(xy 321.27353 -397.96637) (xy 321.251738 -398.009124) (xy 321.223528 -398.047943) (xy 321.189592 -398.081872)
			(xy 321.150766 -398.110074) (xy 321.108007 -398.131856) (xy 321.062367 -398.14668) (xy 321.01497 -398.154183)
			(xy 320.990976 -398.154652) (xy 320.967403 -398.15425) (xy 320.920816 -398.147007) (xy 320.875899 -398.13268)
			(xy 320.833722 -398.111612) (xy 320.795289 -398.084305) (xy 320.761516 -398.051408) (xy 320.733208 -398.013706)
			(xy 320.721736 -397.993108) (xy 320.721228 -397.992346) (xy 320.323464 -397.304006) (xy 320.311554 -397.281335)
			(xy 320.294614 -397.233011) (xy 320.285952 -397.182542) (xy 320.285364 -397.15694) (xy 319.743624 -397.15694)
			(xy 320.055748 -397.696944) (xy 320.068484 -397.720308) (xy 320.086597 -397.770337) (xy 320.095806 -397.822741)
			(xy 320.096388 -397.849344) (xy 320.095978 -397.873337) (xy 320.088465 -397.920733) (xy 320.07363 -397.966369)
			(xy 320.051839 -398.009123) (xy 320.023629 -398.047942) (xy 319.989693 -398.08187) (xy 319.950868 -398.110073)
			(xy 319.90811 -398.131854) (xy 319.86247 -398.14668) (xy 319.815074 -398.154183) (xy 319.79108 -398.154652)
			(xy 319.767507 -398.154247) (xy 319.72092 -398.147004) (xy 319.676003 -398.132678) (xy 319.633826 -398.111611)
			(xy 319.595393 -398.084304) (xy 319.561621 -398.051407) (xy 319.533312 -398.013706) (xy 319.52184 -397.993108)
			(xy 319.521332 -397.992346) (xy 319.123568 -397.304006) (xy 319.111658 -397.281335) (xy 319.094718 -397.233011)
			(xy 319.086056 -397.182542) (xy 319.085468 -397.15694) (xy 318.543474 -397.15694) (xy 318.855598 -397.696944)
			(xy 318.868401 -397.720288) (xy 318.88663 -397.770305) (xy 318.895899 -397.822727) (xy 318.896492 -397.849344)
			(xy 318.896101 -397.873352) (xy 318.88858 -397.920775) (xy 318.873729 -397.966436) (xy 318.851914 -398.009211)
			(xy 318.823674 -398.048044) (xy 318.789705 -398.081979) (xy 318.750842 -398.110179) (xy 318.708046 -398.131949)
			(xy 318.662369 -398.146753) (xy 318.614938 -398.154226) (xy 318.59093 -398.154652) (xy 318.567358 -398.154207)
			(xy 318.520774 -398.146971) (xy 318.475858 -398.132652) (xy 318.43368 -398.111592) (xy 318.395247 -398.084291)
			(xy 318.361473 -398.0514) (xy 318.333163 -398.013704) (xy 318.32169 -397.993108) (xy 318.321182 -397.992346)
			(xy 317.923418 -397.304006) (xy 317.911539 -397.281331) (xy 317.89469 -397.232997) (xy 317.886118 -397.182533)
			(xy 317.885572 -397.15694) (xy 317.343578 -397.15694) (xy 317.655702 -397.696944) (xy 317.668505 -397.720288)
			(xy 317.686734 -397.770305) (xy 317.696003 -397.822727) (xy 317.696596 -397.849344) (xy 317.696201 -397.873352)
			(xy 317.68868 -397.920774) (xy 317.673829 -397.966435) (xy 317.652015 -398.009209) (xy 317.623775 -398.048042)
			(xy 317.589806 -398.081977) (xy 317.550945 -398.110177) (xy 317.508148 -398.131948) (xy 317.462472 -398.146752)
			(xy 317.415042 -398.154226) (xy 317.391034 -398.154652) (xy 317.367462 -398.154203) (xy 317.320878 -398.146969)
			(xy 317.275962 -398.13265) (xy 317.233785 -398.11159) (xy 317.195351 -398.08429) (xy 317.161577 -398.0514)
			(xy 317.133267 -398.013703) (xy 317.121794 -397.993108) (xy 317.121286 -397.992346) (xy 316.723522 -397.304006)
			(xy 316.711643 -397.281331) (xy 316.694794 -397.232996) (xy 316.686222 -397.182533) (xy 316.685676 -397.15694)
			(xy 316.143682 -397.15694) (xy 316.455806 -397.696944) (xy 316.46861 -397.720287) (xy 316.486838 -397.770304)
			(xy 316.496107 -397.822727) (xy 316.4967 -397.849344) (xy 316.496301 -397.873351) (xy 316.48878 -397.920774)
			(xy 316.47393 -397.966434) (xy 316.452116 -398.009208) (xy 316.423877 -398.048041) (xy 316.389908 -398.081976)
			(xy 316.351047 -398.110176) (xy 316.308251 -398.131947) (xy 316.262576 -398.146752) (xy 316.215146 -398.154225)
			(xy 316.191138 -398.154652) (xy 316.167566 -398.1542) (xy 316.120982 -398.146966) (xy 316.076066 -398.132648)
			(xy 316.033889 -398.111589) (xy 315.995456 -398.084289) (xy 315.961681 -398.051399) (xy 315.933371 -398.013703)
			(xy 315.921898 -397.993108) (xy 315.92139 -397.992346) (xy 315.523626 -397.304006) (xy 315.511747 -397.28133)
			(xy 315.494898 -397.232996) (xy 315.486326 -397.182533) (xy 315.48578 -397.15694) (xy 314.943532 -397.15694)
			(xy 315.255656 -397.696944) (xy 315.268393 -397.720307) (xy 315.286506 -397.770337) (xy 315.295714 -397.822741)
			(xy 315.296296 -397.849344) (xy 315.295878 -397.873337) (xy 315.288365 -397.920731) (xy 315.273531 -397.966367)
			(xy 315.251741 -398.009121) (xy 315.223531 -398.047939) (xy 315.189597 -398.081868) (xy 315.150773 -398.11007)
			(xy 315.108015 -398.131852) (xy 315.062377 -398.146678) (xy 315.014981 -398.154182) (xy 314.990988 -398.154652)
			(xy 314.967415 -398.154241) (xy 314.920829 -398.146999) (xy 314.875912 -398.132674) (xy 314.833735 -398.111608)
			(xy 314.795302 -398.084301) (xy 314.761529 -398.051406) (xy 314.733221 -398.013705) (xy 314.721748 -397.993108)
			(xy 314.72124 -397.992346) (xy 314.323476 -397.304006) (xy 314.311559 -397.281339) (xy 314.294623 -397.233013)
			(xy 314.285963 -397.182542) (xy 314.285376 -397.15694) (xy 313.743636 -397.15694) (xy 314.05576 -397.696944)
			(xy 314.068521 -397.720252) (xy 314.086657 -397.770193) (xy 314.095856 -397.822524) (xy 314.0964 -397.84909)
			(xy 314.0964 -397.849344) (xy 314.095926 -397.873333) (xy 314.088414 -397.920719) (xy 314.073583 -397.966346)
			(xy 314.051797 -398.009092) (xy 314.023593 -398.047904) (xy 313.989665 -398.081827) (xy 313.950848 -398.110024)
			(xy 313.908098 -398.131803) (xy 313.862468 -398.146627) (xy 313.815081 -398.15413) (xy 313.791092 -398.154652)
			(xy 313.76752 -398.154213) (xy 313.720937 -398.146964) (xy 313.676022 -398.132639) (xy 313.633844 -398.111579)
			(xy 313.595405 -398.084285) (xy 313.56162 -398.051405) (xy 313.533291 -398.013722) (xy 313.521852 -397.993108)
			(xy 313.521344 -397.992346) (xy 313.12358 -397.304006) (xy 313.111647 -397.281345) (xy 313.094696 -397.233021)
			(xy 313.086055 -397.182544) (xy 313.08548 -397.15694) (xy 313.08548 -397.156432) (xy 313.085734 -397.145256)
			(xy 313.086242 -397.135096) (xy 313.078876 -397.115792) (xy 313.020964 -397.055594) (xy 313.013515 -397.048536)
			(xy 312.99464 -397.040532) (xy 312.984388 -397.0401) (xy 312.564018 -397.0401) (xy 312.555129 -397.040439)
			(xy 312.538429 -397.04653) (xy 312.52483 -397.05798) (xy 312.520076 -397.0655) (xy 312.513218 -397.077438)
			(xy 312.513218 -397.104362) (xy 312.85561 -397.696944) (xy 312.868394 -397.720294) (xy 312.886587 -397.770317)
			(xy 312.895871 -397.822731) (xy 312.896504 -397.849344) (xy 312.896031 -397.87332) (xy 312.888527 -397.920682)
			(xy 312.873711 -397.966288) (xy 312.851948 -398.009017) (xy 312.823771 -398.047818) (xy 312.789875 -398.081737)
			(xy 312.751093 -398.10994) (xy 312.708379 -398.131733) (xy 312.662782 -398.146579) (xy 312.615426 -398.154115)
			(xy 312.59145 -398.154652) (xy 312.590942 -398.154652) (xy 312.567372 -398.15421) (xy 312.520794 -398.146954)
			(xy 312.475885 -398.132624) (xy 312.433713 -398.11156) (xy 312.39528 -398.084263) (xy 312.3615 -398.051383)
			(xy 312.333177 -398.0137) (xy 312.321702 -397.993108) (xy 312.321194 -397.992346) (xy 311.92343 -397.304006)
			(xy 311.911533 -397.281337) (xy 311.894659 -397.233007) (xy 311.886098 -397.182536) (xy 311.885584 -397.15694)
			(xy 311.885584 -397.145256) (xy 311.886092 -397.135096) (xy 311.878726 -397.115792) (xy 311.820814 -397.055594)
			(xy 311.813362 -397.048544) (xy 311.794487 -397.040559) (xy 311.784238 -397.0401) (xy 311.364122 -397.0401)
			(xy 311.355233 -397.040438) (xy 311.338531 -397.046529) (xy 311.324932 -397.057978) (xy 311.32018 -397.0655)
			(xy 311.313322 -397.077438) (xy 311.313322 -397.104362) (xy 311.655714 -397.696944) (xy 311.668498 -397.720294)
			(xy 311.686691 -397.770318) (xy 311.695975 -397.822731) (xy 311.696608 -397.849344) (xy 311.696135 -397.87332)
			(xy 311.688631 -397.920682) (xy 311.673816 -397.966289) (xy 311.652052 -398.009018) (xy 311.623876 -398.04782)
			(xy 311.58998 -398.081739) (xy 311.551197 -398.109942) (xy 311.508483 -398.131735) (xy 311.462887 -398.146582)
			(xy 311.41553 -398.154119) (xy 311.391554 -398.154652) (xy 311.391046 -398.154652) (xy 311.367476 -398.15421)
			(xy 311.320897 -398.146955) (xy 311.275988 -398.132625) (xy 311.233815 -398.111561) (xy 311.195382 -398.084265)
			(xy 311.161602 -398.051385) (xy 311.133278 -398.013702) (xy 311.121806 -397.993108) (xy 311.121298 -397.992346)
			(xy 310.723534 -397.304006) (xy 310.711636 -397.281337) (xy 310.694762 -397.233007) (xy 310.686202 -397.182536)
			(xy 310.685688 -397.15694) (xy 310.685688 -397.145256) (xy 310.686196 -397.135096) (xy 310.67883 -397.115792)
			(xy 310.620918 -397.055594) (xy 310.613466 -397.048544) (xy 310.594591 -397.040557) (xy 310.584342 -397.0401)
			(xy 310.572404 -397.0401) (xy 310.547451 -397.039479) (xy 310.498507 -397.029726) (xy 310.452406 -397.010613)
			(xy 310.410919 -396.982874) (xy 310.392826 -396.965678) (xy 309.945786 -396.518638) (xy 309.928526 -396.500597)
			(xy 309.900768 -396.459104) (xy 309.881656 -396.412986) (xy 309.871926 -396.364021) (xy 309.871364 -396.33906)
			(xy 309.871364 -394.978636) (xy 309.87095 -394.968613) (xy 309.863285 -394.95009) (xy 309.84911 -394.935915)
			(xy 309.830587 -394.92825) (xy 309.820564 -394.927836) (xy 309.714646 -394.927836) (xy 309.689246 -394.9446)
			(xy 309.683404 -394.959078) (xy 309.672908 -394.982747) (xy 309.645653 -395.026765) (xy 309.611875 -395.066002)
			(xy 309.572399 -395.0995) (xy 309.528188 -395.126441) (xy 309.480321 -395.146169) (xy 309.429965 -395.158201)
			(xy 309.37835 -395.162245) (xy 309.326735 -395.158201) (xy 309.276379 -395.146169) (xy 309.228512 -395.126441)
			(xy 309.184301 -395.0995) (xy 309.144825 -395.066002) (xy 309.111047 -395.026765) (xy 309.083792 -394.982747)
			(xy 309.073296 -394.959078) (xy 309.067454 -394.9446) (xy 309.042054 -394.927836) (xy 308.514496 -394.927836)
			(xy 308.489096 -394.9446) (xy 308.483254 -394.959078) (xy 308.472758 -394.982747) (xy 308.445503 -395.026765)
			(xy 308.411725 -395.066002) (xy 308.372249 -395.0995) (xy 308.328038 -395.126441) (xy 308.280171 -395.146169)
			(xy 308.229815 -395.158201) (xy 308.1782 -395.162245) (xy 308.126585 -395.158201) (xy 308.076229 -395.146169)
			(xy 308.028362 -395.126441) (xy 307.984151 -395.0995) (xy 307.944675 -395.066002) (xy 307.910897 -395.026765)
			(xy 307.883642 -394.982747) (xy 307.873146 -394.959078) (xy 307.867304 -394.9446) (xy 307.841904 -394.927836)
			(xy 307.3146 -394.927836) (xy 307.2892 -394.9446) (xy 307.283358 -394.959078) (xy 307.272862 -394.982747)
			(xy 307.245607 -395.026765) (xy 307.211829 -395.066002) (xy 307.172353 -395.0995) (xy 307.128142 -395.126441)
			(xy 307.080275 -395.146169) (xy 307.029919 -395.158201) (xy 306.978304 -395.162245) (xy 306.926689 -395.158201)
			(xy 306.876333 -395.146169) (xy 306.828466 -395.126441) (xy 306.784255 -395.0995) (xy 306.744779 -395.066002)
			(xy 306.711001 -395.026765) (xy 306.683746 -394.982747) (xy 306.67325 -394.959078) (xy 306.667408 -394.9446)
			(xy 306.642008 -394.927836) (xy 306.114704 -394.927836) (xy 306.089304 -394.9446) (xy 306.083462 -394.959078)
			(xy 306.072966 -394.982747) (xy 306.045711 -395.026765) (xy 306.011933 -395.066002) (xy 305.972457 -395.0995)
			(xy 305.928246 -395.126441) (xy 305.880379 -395.146169) (xy 305.830023 -395.158201) (xy 305.778408 -395.162245)
			(xy 305.726793 -395.158201) (xy 305.676437 -395.146169) (xy 305.62857 -395.126441) (xy 305.584359 -395.0995)
			(xy 305.544883 -395.066002) (xy 305.511105 -395.026765) (xy 305.48385 -394.982747) (xy 305.473354 -394.959078)
			(xy 305.467512 -394.9446) (xy 305.442112 -394.927836) (xy 304.914554 -394.927836) (xy 304.889154 -394.9446)
			(xy 304.883312 -394.959078) (xy 304.872816 -394.982747) (xy 304.845561 -395.026765) (xy 304.811783 -395.066002)
			(xy 304.772307 -395.0995) (xy 304.728096 -395.126441) (xy 304.680229 -395.146169) (xy 304.629873 -395.158201)
			(xy 304.578258 -395.162245) (xy 304.526643 -395.158201) (xy 304.476287 -395.146169) (xy 304.42842 -395.126441)
			(xy 304.384209 -395.0995) (xy 304.344733 -395.066002) (xy 304.310955 -395.026765) (xy 304.2837 -394.982747)
			(xy 304.273204 -394.959078) (xy 304.267362 -394.9446) (xy 304.241962 -394.927836) (xy 303.714658 -394.927836)
			(xy 303.689258 -394.9446) (xy 303.683416 -394.959078) (xy 303.67292 -394.982747) (xy 303.645665 -395.026765)
			(xy 303.611887 -395.066002) (xy 303.572411 -395.0995) (xy 303.5282 -395.126441) (xy 303.480333 -395.146169)
			(xy 303.429977 -395.158201) (xy 303.378362 -395.162245) (xy 303.326747 -395.158201) (xy 303.276391 -395.146169)
			(xy 303.228524 -395.126441) (xy 303.184313 -395.0995) (xy 303.144837 -395.066002) (xy 303.111059 -395.026765)
			(xy 303.083804 -394.982747) (xy 303.073308 -394.959078) (xy 303.067466 -394.9446) (xy 303.042066 -394.927836)
			(xy 301.404274 -394.927836) (xy 301.377604 -394.947394) (xy 301.372524 -394.963396) (xy 301.364814 -394.986285)
			(xy 301.343199 -395.029475) (xy 301.315055 -395.068724) (xy 301.281085 -395.103056) (xy 301.242136 -395.131612)
			(xy 301.199177 -395.153683) (xy 301.15328 -395.168717) (xy 301.105588 -395.17634) (xy 301.08144 -395.176756)
			(xy 301.072042 -395.176502) (xy 301.061374 -395.176248) (xy 301.041816 -395.184122) (xy 299.068998 -397.15694)
			(xy 303.485804 -397.15694) (xy 303.485804 -397.156432) (xy 303.486268 -397.132439) (xy 303.49377 -397.085044)
			(xy 303.508595 -397.039405) (xy 303.530377 -396.996648) (xy 303.558581 -396.957826) (xy 303.592511 -396.923894)
			(xy 303.631331 -396.895688) (xy 303.674087 -396.873903) (xy 303.719724 -396.859075) (xy 303.767119 -396.851569)
			(xy 303.791112 -396.851124) (xy 303.815047 -396.851594) (xy 303.862333 -396.859047) (xy 303.907877 -396.873786)
			(xy 303.950565 -396.895448) (xy 303.989351 -396.923504) (xy 304.023286 -396.957267) (xy 304.051539 -396.99591)
			(xy 304.062892 -397.016986) (xy 304.0634 -397.018002) (xy 304.143706 -397.15694) (xy 304.6857 -397.15694)
			(xy 304.6857 -397.156432) (xy 304.686168 -397.132439) (xy 304.69367 -397.085044) (xy 304.708495 -397.039406)
			(xy 304.730277 -396.99665) (xy 304.75848 -396.957827) (xy 304.792409 -396.923895) (xy 304.831229 -396.895689)
			(xy 304.873984 -396.873904) (xy 304.919621 -396.859076) (xy 304.967015 -396.85157) (xy 304.991008 -396.851124)
			(xy 305.014943 -396.851597) (xy 305.062229 -396.85905) (xy 305.107773 -396.873788) (xy 305.150461 -396.89545)
			(xy 305.189247 -396.923505) (xy 305.223182 -396.957268) (xy 305.251435 -396.99591) (xy 305.262788 -397.016986)
			(xy 305.263296 -397.018002) (xy 305.343602 -397.15694) (xy 305.885596 -397.15694) (xy 305.885596 -397.156432)
			(xy 305.886068 -397.13244) (xy 305.89357 -397.085045) (xy 305.908394 -397.039407) (xy 305.930176 -396.996651)
			(xy 305.958378 -396.957829) (xy 305.992307 -396.923897) (xy 306.031127 -396.895691) (xy 306.073881 -396.873905)
			(xy 306.119517 -396.859076) (xy 306.166912 -396.85157) (xy 306.190904 -396.851124) (xy 306.214839 -396.8516)
			(xy 306.262124 -396.859053) (xy 306.307668 -396.87379) (xy 306.350356 -396.895451) (xy 306.389142 -396.923506)
			(xy 306.423077 -396.957268) (xy 306.451331 -396.99591) (xy 306.462684 -397.016986) (xy 306.463192 -397.018002)
			(xy 306.543498 -397.15694) (xy 307.085492 -397.15694) (xy 307.085492 -397.156432) (xy 307.085969 -397.132427)
			(xy 307.093478 -397.085008) (xy 307.108318 -397.039349) (xy 307.130122 -396.996576) (xy 307.158352 -396.957743)
			(xy 307.192312 -396.923807) (xy 307.231166 -396.895605) (xy 307.273955 -396.873833) (xy 307.319624 -396.859027)
			(xy 307.367049 -396.851551) (xy 307.391054 -396.851124) (xy 307.41499 -396.85156) (xy 307.462278 -396.85902)
			(xy 307.507823 -396.873764) (xy 307.550511 -396.895432) (xy 307.589296 -396.923493) (xy 307.62323 -396.957261)
			(xy 307.651481 -396.995908) (xy 307.662834 -397.016986) (xy 307.663342 -397.018002) (xy 307.743648 -397.15694)
			(xy 308.285388 -397.15694) (xy 308.285388 -397.156432) (xy 308.285869 -397.132427) (xy 308.293378 -397.085009)
			(xy 308.308218 -397.03935) (xy 308.330021 -396.996577) (xy 308.35825 -396.957744) (xy 308.39221 -396.923809)
			(xy 308.431063 -396.895607) (xy 308.473852 -396.873834) (xy 308.519521 -396.859027) (xy 308.566945 -396.851552)
			(xy 308.59095 -396.851124) (xy 308.614886 -396.851563) (xy 308.662173 -396.859022) (xy 308.707718 -396.873766)
			(xy 308.750406 -396.895434) (xy 308.789192 -396.923494) (xy 308.823126 -396.957262) (xy 308.851377 -396.995908)
			(xy 308.86273 -397.016986) (xy 308.863238 -397.018002) (xy 308.943544 -397.15694) (xy 309.485792 -397.15694)
			(xy 309.485792 -397.156432) (xy 309.486268 -397.13244) (xy 309.49377 -397.085045) (xy 309.508594 -397.039408)
			(xy 309.530375 -396.996652) (xy 309.558577 -396.95783) (xy 309.592506 -396.923898) (xy 309.631325 -396.895692)
			(xy 309.674079 -396.873906) (xy 309.719714 -396.859077) (xy 309.767108 -396.85157) (xy 309.7911 -396.851124)
			(xy 309.815035 -396.851603) (xy 309.86232 -396.859055) (xy 309.907864 -396.873792) (xy 309.950552 -396.895453)
			(xy 309.989338 -396.923507) (xy 310.023273 -396.957269) (xy 310.051526 -396.995911) (xy 310.06288 -397.016986)
			(xy 310.063388 -397.018002) (xy 310.455818 -397.696944) (xy 310.468623 -397.720287) (xy 310.486851 -397.770304)
			(xy 310.496119 -397.822727) (xy 310.496712 -397.849344) (xy 310.496302 -397.873351) (xy 310.48878 -397.920772)
			(xy 310.473931 -397.966432) (xy 310.452118 -398.009205) (xy 310.42388 -398.048037) (xy 310.389913 -398.081971)
			(xy 310.351053 -398.110172) (xy 310.308259 -398.131943) (xy 310.262586 -398.146749) (xy 310.215157 -398.154225)
			(xy 310.19115 -398.154652) (xy 310.167579 -398.154191) (xy 310.120995 -398.146958) (xy 310.076079 -398.132642)
			(xy 310.033902 -398.111584) (xy 309.995468 -398.084286) (xy 309.961694 -398.051397) (xy 309.933384 -398.013703)
			(xy 309.92191 -397.993108) (xy 309.921402 -397.992346) (xy 309.523638 -397.304006) (xy 309.51176 -397.28133)
			(xy 309.494911 -397.232996) (xy 309.486338 -397.182533) (xy 309.485792 -397.15694) (xy 308.943544 -397.15694)
			(xy 309.255668 -397.696944) (xy 309.268406 -397.720307) (xy 309.286518 -397.770336) (xy 309.295726 -397.822741)
			(xy 309.296308 -397.849344) (xy 309.295878 -397.873336) (xy 309.288365 -397.92073) (xy 309.273532 -397.966364)
			(xy 309.251743 -398.009117) (xy 309.223535 -398.047935) (xy 309.189602 -398.081863) (xy 309.150779 -398.110066)
			(xy 309.108024 -398.131849) (xy 309.062387 -398.146676) (xy 309.014992 -398.154181) (xy 308.991 -398.154652)
			(xy 308.967427 -398.154231) (xy 308.920842 -398.146991) (xy 308.875925 -398.132668) (xy 308.833748 -398.111603)
			(xy 308.795315 -398.084298) (xy 308.761542 -398.051404) (xy 308.733233 -398.013705) (xy 308.72176 -397.993108)
			(xy 308.721252 -397.992346) (xy 308.323488 -397.304006) (xy 308.311572 -397.281338) (xy 308.294635 -397.233013)
			(xy 308.285975 -397.182542) (xy 308.285388 -397.15694) (xy 307.743648 -397.15694) (xy 308.055772 -397.696944)
			(xy 308.06851 -397.720307) (xy 308.086622 -397.770336) (xy 308.09583 -397.822741) (xy 308.096412 -397.849344)
			(xy 308.095978 -397.873336) (xy 308.088465 -397.920729) (xy 308.073632 -397.966363) (xy 308.051844 -398.009116)
			(xy 308.023636 -398.047934) (xy 307.989703 -398.081862) (xy 307.950882 -398.110065) (xy 307.908126 -398.131848)
			(xy 307.86249 -398.146675) (xy 307.815096 -398.154181) (xy 307.791104 -398.154652) (xy 307.767532 -398.154228)
			(xy 307.720946 -398.146988) (xy 307.676029 -398.132666) (xy 307.633852 -398.111602) (xy 307.595419 -398.084297)
			(xy 307.561646 -398.051404) (xy 307.533337 -398.013705) (xy 307.521864 -397.993108) (xy 307.521356 -397.992346)
			(xy 307.123592 -397.304006) (xy 307.111676 -397.281338) (xy 307.094739 -397.233012) (xy 307.086079 -397.182542)
			(xy 307.085492 -397.15694) (xy 306.543498 -397.15694) (xy 306.855622 -397.696944) (xy 306.868427 -397.720287)
			(xy 306.886655 -397.770304) (xy 306.895923 -397.822727) (xy 306.896516 -397.849344) (xy 306.896102 -397.873351)
			(xy 306.888581 -397.920771) (xy 306.873731 -397.966431) (xy 306.851919 -398.009203) (xy 306.823681 -398.048036)
			(xy 306.789715 -398.08197) (xy 306.750856 -398.110171) (xy 306.708062 -398.131942) (xy 306.662389 -398.146748)
			(xy 306.614961 -398.154224) (xy 306.590954 -398.154652) (xy 306.567383 -398.154187) (xy 306.520799 -398.146955)
			(xy 306.475884 -398.13264) (xy 306.433706 -398.111583) (xy 306.395273 -398.084285) (xy 306.361498 -398.051397)
			(xy 306.333188 -398.013702) (xy 306.321714 -397.993108) (xy 306.321206 -397.992346) (xy 305.923442 -397.304006)
			(xy 305.911565 -397.28133) (xy 305.894715 -397.232996) (xy 305.886142 -397.182533) (xy 305.885596 -397.15694)
			(xy 305.343602 -397.15694) (xy 305.655726 -397.696944) (xy 305.668531 -397.720286) (xy 305.686759 -397.770304)
			(xy 305.696027 -397.822727) (xy 305.69662 -397.849344) (xy 305.696202 -397.87335) (xy 305.688681 -397.920771)
			(xy 305.673831 -397.96643) (xy 305.652019 -398.009202) (xy 305.623782 -398.048034) (xy 305.589816 -398.081969)
			(xy 305.550958 -398.110169) (xy 305.508165 -398.131941) (xy 305.462492 -398.146748) (xy 305.415065 -398.154224)
			(xy 305.391058 -398.154652) (xy 305.367487 -398.154184) (xy 305.320904 -398.146953) (xy 305.275988 -398.132638)
			(xy 305.233811 -398.111581) (xy 305.195377 -398.084284) (xy 305.161602 -398.051396) (xy 305.133292 -398.013702)
			(xy 305.121818 -397.993108) (xy 305.12131 -397.992346) (xy 304.723546 -397.304006) (xy 304.711669 -397.28133)
			(xy 304.694819 -397.232996) (xy 304.686246 -397.182533) (xy 304.6857 -397.15694) (xy 304.143706 -397.15694)
			(xy 304.45583 -397.696944) (xy 304.468636 -397.720286) (xy 304.486863 -397.770304) (xy 304.496131 -397.822727)
			(xy 304.496724 -397.849344) (xy 304.496302 -397.87335) (xy 304.488781 -397.92077) (xy 304.473932 -397.966429)
			(xy 304.45212 -398.009201) (xy 304.423884 -398.048033) (xy 304.389918 -398.081967) (xy 304.35106 -398.110168)
			(xy 304.308268 -398.13194) (xy 304.262595 -398.146747) (xy 304.215169 -398.154224) (xy 304.191162 -398.154652)
			(xy 304.167591 -398.154181) (xy 304.121008 -398.14695) (xy 304.076092 -398.132636) (xy 304.033915 -398.11158)
			(xy 303.995481 -398.084283) (xy 303.961707 -398.051396) (xy 303.933396 -398.013702) (xy 303.921922 -397.993108)
			(xy 303.921414 -397.992346) (xy 303.52365 -397.304006) (xy 303.511773 -397.281329) (xy 303.494923 -397.232996)
			(xy 303.48635 -397.182533) (xy 303.485804 -397.15694) (xy 299.068998 -397.15694) (xy 296.302684 -399.923254)
			(xy 296.295837 -399.930651) (xy 296.288109 -399.949251) (xy 296.287698 -399.959322) (xy 296.287698 -401.674838)
			(xy 303.434496 -401.674838) (xy 303.434496 -400.811238) (xy 303.434982 -400.783969) (xy 303.442744 -400.729985)
			(xy 303.458109 -400.677655) (xy 303.480766 -400.628045) (xy 303.510252 -400.582164) (xy 303.545967 -400.540947)
			(xy 303.587184 -400.505232) (xy 303.633065 -400.475746) (xy 303.682675 -400.453089) (xy 303.735005 -400.437724)
			(xy 303.788989 -400.429962) (xy 303.843527 -400.429962) (xy 303.897511 -400.437724) (xy 303.949841 -400.453089)
			(xy 303.999451 -400.475746) (xy 304.045332 -400.505232) (xy 304.086549 -400.540947) (xy 304.122264 -400.582164)
			(xy 304.15175 -400.628045) (xy 304.174407 -400.677655) (xy 304.189772 -400.729985) (xy 304.197534 -400.783969)
			(xy 304.19802 -400.811238) (xy 304.19802 -401.674838) (xy 304.634392 -401.674838) (xy 304.634392 -400.811238)
			(xy 304.634878 -400.783969) (xy 304.64264 -400.729985) (xy 304.658005 -400.677655) (xy 304.680662 -400.628045)
			(xy 304.710148 -400.582164) (xy 304.745863 -400.540947) (xy 304.78708 -400.505232) (xy 304.832961 -400.475746)
			(xy 304.882571 -400.453089) (xy 304.934901 -400.437724) (xy 304.988885 -400.429962) (xy 305.043423 -400.429962)
			(xy 305.097407 -400.437724) (xy 305.149737 -400.453089) (xy 305.199347 -400.475746) (xy 305.245228 -400.505232)
			(xy 305.286445 -400.540947) (xy 305.32216 -400.582164) (xy 305.351646 -400.628045) (xy 305.374303 -400.677655)
			(xy 305.389668 -400.729985) (xy 305.39743 -400.783969) (xy 305.397916 -400.811238) (xy 305.397916 -401.674838)
			(xy 305.834796 -401.674838) (xy 305.834796 -400.811238) (xy 305.835282 -400.783987) (xy 305.843038 -400.730039)
			(xy 305.858393 -400.677744) (xy 305.881035 -400.628167) (xy 305.910501 -400.582317) (xy 305.946192 -400.541126)
			(xy 305.987383 -400.505435) (xy 306.033233 -400.475969) (xy 306.08281 -400.453327) (xy 306.135105 -400.437972)
			(xy 306.189053 -400.430216) (xy 306.243555 -400.430216) (xy 306.297503 -400.437972) (xy 306.349798 -400.453327)
			(xy 306.399375 -400.475969) (xy 306.445225 -400.505435) (xy 306.486416 -400.541126) (xy 306.522107 -400.582317)
			(xy 306.551573 -400.628167) (xy 306.574215 -400.677744) (xy 306.58957 -400.730039) (xy 306.597326 -400.783987)
			(xy 306.597812 -400.811238) (xy 306.597812 -401.674838) (xy 307.034692 -401.674838) (xy 307.034692 -400.811238)
			(xy 307.035178 -400.783987) (xy 307.042934 -400.730039) (xy 307.058289 -400.677744) (xy 307.080931 -400.628167)
			(xy 307.110397 -400.582317) (xy 307.146088 -400.541126) (xy 307.187279 -400.505435) (xy 307.233129 -400.475969)
			(xy 307.282706 -400.453327) (xy 307.335001 -400.437972) (xy 307.388949 -400.430216) (xy 307.443451 -400.430216)
			(xy 307.497399 -400.437972) (xy 307.549694 -400.453327) (xy 307.599271 -400.475969) (xy 307.645121 -400.505435)
			(xy 307.686312 -400.541126) (xy 307.722003 -400.582317) (xy 307.751469 -400.628167) (xy 307.774111 -400.677744)
			(xy 307.789466 -400.730039) (xy 307.797222 -400.783987) (xy 307.797708 -400.811238) (xy 307.797708 -401.674838)
			(xy 308.234588 -401.674838) (xy 308.234588 -400.811238) (xy 308.235074 -400.783969) (xy 308.242836 -400.729985)
			(xy 308.258201 -400.677655) (xy 308.280858 -400.628045) (xy 308.310344 -400.582164) (xy 308.346059 -400.540947)
			(xy 308.387276 -400.505232) (xy 308.433157 -400.475746) (xy 308.482767 -400.453089) (xy 308.535097 -400.437724)
			(xy 308.589081 -400.429962) (xy 308.643619 -400.429962) (xy 308.697603 -400.437724) (xy 308.749933 -400.453089)
			(xy 308.799543 -400.475746) (xy 308.845424 -400.505232) (xy 308.886641 -400.540947) (xy 308.922356 -400.582164)
			(xy 308.951842 -400.628045) (xy 308.974499 -400.677655) (xy 308.989864 -400.729985) (xy 308.997626 -400.783969)
			(xy 308.998112 -400.811238) (xy 308.998112 -401.674838) (xy 309.434484 -401.674838) (xy 309.434484 -400.811238)
			(xy 309.43497 -400.783969) (xy 309.442732 -400.729985) (xy 309.458097 -400.677655) (xy 309.480754 -400.628045)
			(xy 309.51024 -400.582164) (xy 309.545955 -400.540947) (xy 309.587172 -400.505232) (xy 309.633053 -400.475746)
			(xy 309.682663 -400.453089) (xy 309.734993 -400.437724) (xy 309.788977 -400.429962) (xy 309.843515 -400.429962)
			(xy 309.897499 -400.437724) (xy 309.949829 -400.453089) (xy 309.999439 -400.475746) (xy 310.04532 -400.505232)
			(xy 310.086537 -400.540947) (xy 310.122252 -400.582164) (xy 310.151738 -400.628045) (xy 310.174395 -400.677655)
			(xy 310.18976 -400.729985) (xy 310.197522 -400.783969) (xy 310.198008 -400.811238) (xy 310.198008 -401.674838)
			(xy 310.634888 -401.674838) (xy 310.634888 -400.811238) (xy 310.635374 -400.783987) (xy 310.64313 -400.730039)
			(xy 310.658485 -400.677744) (xy 310.681127 -400.628167) (xy 310.710593 -400.582317) (xy 310.746284 -400.541126)
			(xy 310.787475 -400.505435) (xy 310.833325 -400.475969) (xy 310.882902 -400.453327) (xy 310.935197 -400.437972)
			(xy 310.989145 -400.430216) (xy 311.043647 -400.430216) (xy 311.097595 -400.437972) (xy 311.14989 -400.453327)
			(xy 311.199467 -400.475969) (xy 311.245317 -400.505435) (xy 311.286508 -400.541126) (xy 311.322199 -400.582317)
			(xy 311.351665 -400.628167) (xy 311.374307 -400.677744) (xy 311.389662 -400.730039) (xy 311.397418 -400.783987)
			(xy 311.397904 -400.811238) (xy 311.397904 -401.674838) (xy 311.834784 -401.674838) (xy 311.834784 -400.811238)
			(xy 311.83527 -400.783987) (xy 311.843026 -400.730039) (xy 311.858381 -400.677744) (xy 311.881023 -400.628167)
			(xy 311.910489 -400.582317) (xy 311.94618 -400.541126) (xy 311.987371 -400.505435) (xy 312.033221 -400.475969)
			(xy 312.082798 -400.453327) (xy 312.135093 -400.437972) (xy 312.189041 -400.430216) (xy 312.243543 -400.430216)
			(xy 312.297491 -400.437972) (xy 312.349786 -400.453327) (xy 312.399363 -400.475969) (xy 312.445213 -400.505435)
			(xy 312.486404 -400.541126) (xy 312.522095 -400.582317) (xy 312.551561 -400.628167) (xy 312.574203 -400.677744)
			(xy 312.589558 -400.730039) (xy 312.597314 -400.783987) (xy 312.5978 -400.811238) (xy 312.5978 -401.674838)
			(xy 313.03468 -401.674838) (xy 313.03468 -400.811238) (xy 313.035166 -400.783969) (xy 313.042928 -400.729985)
			(xy 313.058293 -400.677655) (xy 313.08095 -400.628045) (xy 313.110436 -400.582164) (xy 313.146151 -400.540947)
			(xy 313.187368 -400.505232) (xy 313.233249 -400.475746) (xy 313.282859 -400.453089) (xy 313.335189 -400.437724)
			(xy 313.389173 -400.429962) (xy 313.443711 -400.429962) (xy 313.497695 -400.437724) (xy 313.550025 -400.453089)
			(xy 313.599635 -400.475746) (xy 313.645516 -400.505232) (xy 313.686733 -400.540947) (xy 313.722448 -400.582164)
			(xy 313.751934 -400.628045) (xy 313.774591 -400.677655) (xy 313.789956 -400.729985) (xy 313.797718 -400.783969)
			(xy 313.798204 -400.811238) (xy 313.798204 -401.674838) (xy 314.234576 -401.674838) (xy 314.234576 -400.811238)
			(xy 314.235062 -400.783969) (xy 314.242824 -400.729985) (xy 314.258189 -400.677655) (xy 314.280846 -400.628045)
			(xy 314.310332 -400.582164) (xy 314.346047 -400.540947) (xy 314.387264 -400.505232) (xy 314.433145 -400.475746)
			(xy 314.482755 -400.453089) (xy 314.535085 -400.437724) (xy 314.589069 -400.429962) (xy 314.643607 -400.429962)
			(xy 314.697591 -400.437724) (xy 314.749921 -400.453089) (xy 314.799531 -400.475746) (xy 314.845412 -400.505232)
			(xy 314.886629 -400.540947) (xy 314.922344 -400.582164) (xy 314.95183 -400.628045) (xy 314.974487 -400.677655)
			(xy 314.989852 -400.729985) (xy 314.997614 -400.783969) (xy 314.9981 -400.811238) (xy 314.9981 -401.674838)
			(xy 315.43498 -401.674838) (xy 315.43498 -400.811238) (xy 315.435466 -400.783987) (xy 315.443222 -400.730039)
			(xy 315.458577 -400.677744) (xy 315.481219 -400.628167) (xy 315.510685 -400.582317) (xy 315.546376 -400.541126)
			(xy 315.587567 -400.505435) (xy 315.633417 -400.475969) (xy 315.682994 -400.453327) (xy 315.735289 -400.437972)
			(xy 315.789237 -400.430216) (xy 315.843739 -400.430216) (xy 315.897687 -400.437972) (xy 315.949982 -400.453327)
			(xy 315.999559 -400.475969) (xy 316.045409 -400.505435) (xy 316.0866 -400.541126) (xy 316.122291 -400.582317)
			(xy 316.151757 -400.628167) (xy 316.174399 -400.677744) (xy 316.189754 -400.730039) (xy 316.19751 -400.783987)
			(xy 316.197996 -400.811238) (xy 316.197996 -401.674838) (xy 316.634876 -401.674838) (xy 316.634876 -400.811238)
			(xy 316.635362 -400.783987) (xy 316.643118 -400.730039) (xy 316.658473 -400.677744) (xy 316.681115 -400.628167)
			(xy 316.710581 -400.582317) (xy 316.746272 -400.541126) (xy 316.787463 -400.505435) (xy 316.833313 -400.475969)
			(xy 316.88289 -400.453327) (xy 316.935185 -400.437972) (xy 316.989133 -400.430216) (xy 317.043635 -400.430216)
			(xy 317.097583 -400.437972) (xy 317.149878 -400.453327) (xy 317.199455 -400.475969) (xy 317.245305 -400.505435)
			(xy 317.286496 -400.541126) (xy 317.322187 -400.582317) (xy 317.351653 -400.628167) (xy 317.374295 -400.677744)
			(xy 317.38965 -400.730039) (xy 317.397406 -400.783987) (xy 317.397892 -400.811238) (xy 317.397892 -401.674838)
			(xy 317.834772 -401.674838) (xy 317.834772 -400.811238) (xy 317.835258 -400.783987) (xy 317.843014 -400.730039)
			(xy 317.858369 -400.677744) (xy 317.881011 -400.628167) (xy 317.910477 -400.582317) (xy 317.946168 -400.541126)
			(xy 317.987359 -400.505435) (xy 318.033209 -400.475969) (xy 318.082786 -400.453327) (xy 318.135081 -400.437972)
			(xy 318.189029 -400.430216) (xy 318.243531 -400.430216) (xy 318.297479 -400.437972) (xy 318.349774 -400.453327)
			(xy 318.399351 -400.475969) (xy 318.445201 -400.505435) (xy 318.486392 -400.541126) (xy 318.522083 -400.582317)
			(xy 318.551549 -400.628167) (xy 318.574191 -400.677744) (xy 318.589546 -400.730039) (xy 318.597302 -400.783987)
			(xy 318.597788 -400.811238) (xy 318.597788 -401.674838) (xy 319.034668 -401.674838) (xy 319.034668 -400.811238)
			(xy 319.035154 -400.783987) (xy 319.04291 -400.730039) (xy 319.058265 -400.677744) (xy 319.080907 -400.628167)
			(xy 319.110373 -400.582317) (xy 319.146064 -400.541126) (xy 319.187255 -400.505435) (xy 319.233105 -400.475969)
			(xy 319.282682 -400.453327) (xy 319.334977 -400.437972) (xy 319.388925 -400.430216) (xy 319.443427 -400.430216)
			(xy 319.497375 -400.437972) (xy 319.54967 -400.453327) (xy 319.599247 -400.475969) (xy 319.645097 -400.505435)
			(xy 319.686288 -400.541126) (xy 319.721979 -400.582317) (xy 319.751445 -400.628167) (xy 319.774087 -400.677744)
			(xy 319.789442 -400.730039) (xy 319.797198 -400.783987) (xy 319.797684 -400.811238) (xy 319.797684 -401.674838)
			(xy 320.234564 -401.674838) (xy 320.234564 -400.811238) (xy 320.23505 -400.783969) (xy 320.242812 -400.729985)
			(xy 320.258177 -400.677655) (xy 320.280834 -400.628045) (xy 320.31032 -400.582164) (xy 320.346035 -400.540947)
			(xy 320.387252 -400.505232) (xy 320.433133 -400.475746) (xy 320.482743 -400.453089) (xy 320.535073 -400.437724)
			(xy 320.589057 -400.429962) (xy 320.643595 -400.429962) (xy 320.697579 -400.437724) (xy 320.749909 -400.453089)
			(xy 320.799519 -400.475746) (xy 320.8454 -400.505232) (xy 320.886617 -400.540947) (xy 320.922332 -400.582164)
			(xy 320.951818 -400.628045) (xy 320.974475 -400.677655) (xy 320.98984 -400.729985) (xy 320.997602 -400.783969)
			(xy 320.998088 -400.811238) (xy 320.998088 -401.674838) (xy 321.43446 -401.674838) (xy 321.43446 -400.811238)
			(xy 321.434946 -400.783969) (xy 321.442708 -400.729985) (xy 321.458073 -400.677655) (xy 321.48073 -400.628045)
			(xy 321.510216 -400.582164) (xy 321.545931 -400.540947) (xy 321.587148 -400.505232) (xy 321.633029 -400.475746)
			(xy 321.682639 -400.453089) (xy 321.734969 -400.437724) (xy 321.788953 -400.429962) (xy 321.843491 -400.429962)
			(xy 321.897475 -400.437724) (xy 321.949805 -400.453089) (xy 321.999415 -400.475746) (xy 322.045296 -400.505232)
			(xy 322.086513 -400.540947) (xy 322.122228 -400.582164) (xy 322.151714 -400.628045) (xy 322.174371 -400.677655)
			(xy 322.189736 -400.729985) (xy 322.197498 -400.783969) (xy 322.197984 -400.811238) (xy 322.197984 -401.674838)
			(xy 335.962244 -401.674838) (xy 335.962244 -400.811238) (xy 335.96273 -400.783969) (xy 335.970492 -400.729985)
			(xy 335.985857 -400.677655) (xy 336.008514 -400.628045) (xy 336.038 -400.582164) (xy 336.073715 -400.540947)
			(xy 336.114932 -400.505232) (xy 336.160813 -400.475746) (xy 336.210423 -400.453089) (xy 336.262753 -400.437724)
			(xy 336.316737 -400.429962) (xy 336.371275 -400.429962) (xy 336.425259 -400.437724) (xy 336.477589 -400.453089)
			(xy 336.527199 -400.475746) (xy 336.57308 -400.505232) (xy 336.614297 -400.540947) (xy 336.650012 -400.582164)
			(xy 336.679498 -400.628045) (xy 336.702155 -400.677655) (xy 336.71752 -400.729985) (xy 336.725282 -400.783969)
			(xy 336.725768 -400.811238) (xy 336.725768 -401.674838) (xy 337.16214 -401.674838) (xy 337.16214 -400.811238)
			(xy 337.162626 -400.783969) (xy 337.170388 -400.729985) (xy 337.185753 -400.677655) (xy 337.20841 -400.628045)
			(xy 337.237896 -400.582164) (xy 337.273611 -400.540947) (xy 337.314828 -400.505232) (xy 337.360709 -400.475746)
			(xy 337.410319 -400.453089) (xy 337.462649 -400.437724) (xy 337.516633 -400.429962) (xy 337.571171 -400.429962)
			(xy 337.625155 -400.437724) (xy 337.677485 -400.453089) (xy 337.727095 -400.475746) (xy 337.772976 -400.505232)
			(xy 337.814193 -400.540947) (xy 337.849908 -400.582164) (xy 337.879394 -400.628045) (xy 337.902051 -400.677655)
			(xy 337.917416 -400.729985) (xy 337.925178 -400.783969) (xy 337.925664 -400.811238) (xy 337.925664 -401.674838)
			(xy 338.362544 -401.674838) (xy 338.362544 -400.811238) (xy 338.36303 -400.783987) (xy 338.370786 -400.730039)
			(xy 338.386141 -400.677744) (xy 338.408783 -400.628167) (xy 338.438249 -400.582317) (xy 338.47394 -400.541126)
			(xy 338.515131 -400.505435) (xy 338.560981 -400.475969) (xy 338.610558 -400.453327) (xy 338.662853 -400.437972)
			(xy 338.716801 -400.430216) (xy 338.771303 -400.430216) (xy 338.825251 -400.437972) (xy 338.877546 -400.453327)
			(xy 338.927123 -400.475969) (xy 338.972973 -400.505435) (xy 339.014164 -400.541126) (xy 339.049855 -400.582317)
			(xy 339.079321 -400.628167) (xy 339.101963 -400.677744) (xy 339.117318 -400.730039) (xy 339.125074 -400.783987)
			(xy 339.12556 -400.811238) (xy 339.12556 -401.674838) (xy 339.56244 -401.674838) (xy 339.56244 -400.811238)
			(xy 339.562926 -400.783987) (xy 339.570682 -400.730039) (xy 339.586037 -400.677744) (xy 339.608679 -400.628167)
			(xy 339.638145 -400.582317) (xy 339.673836 -400.541126) (xy 339.715027 -400.505435) (xy 339.760877 -400.475969)
			(xy 339.810454 -400.453327) (xy 339.862749 -400.437972) (xy 339.916697 -400.430216) (xy 339.971199 -400.430216)
			(xy 340.025147 -400.437972) (xy 340.077442 -400.453327) (xy 340.127019 -400.475969) (xy 340.172869 -400.505435)
			(xy 340.21406 -400.541126) (xy 340.249751 -400.582317) (xy 340.279217 -400.628167) (xy 340.301859 -400.677744)
			(xy 340.317214 -400.730039) (xy 340.32497 -400.783987) (xy 340.325456 -400.811238) (xy 340.325456 -401.674838)
			(xy 340.762336 -401.674838) (xy 340.762336 -400.811238) (xy 340.762822 -400.783969) (xy 340.770584 -400.729985)
			(xy 340.785949 -400.677655) (xy 340.808606 -400.628045) (xy 340.838092 -400.582164) (xy 340.873807 -400.540947)
			(xy 340.915024 -400.505232) (xy 340.960905 -400.475746) (xy 341.010515 -400.453089) (xy 341.062845 -400.437724)
			(xy 341.116829 -400.429962) (xy 341.171367 -400.429962) (xy 341.225351 -400.437724) (xy 341.277681 -400.453089)
			(xy 341.327291 -400.475746) (xy 341.373172 -400.505232) (xy 341.414389 -400.540947) (xy 341.450104 -400.582164)
			(xy 341.47959 -400.628045) (xy 341.502247 -400.677655) (xy 341.517612 -400.729985) (xy 341.525374 -400.783969)
			(xy 341.52586 -400.811238) (xy 341.52586 -401.674838) (xy 341.962232 -401.674838) (xy 341.962232 -400.811238)
			(xy 341.962718 -400.783969) (xy 341.97048 -400.729985) (xy 341.985845 -400.677655) (xy 342.008502 -400.628045)
			(xy 342.037988 -400.582164) (xy 342.073703 -400.540947) (xy 342.11492 -400.505232) (xy 342.160801 -400.475746)
			(xy 342.210411 -400.453089) (xy 342.262741 -400.437724) (xy 342.316725 -400.429962) (xy 342.371263 -400.429962)
			(xy 342.425247 -400.437724) (xy 342.477577 -400.453089) (xy 342.527187 -400.475746) (xy 342.573068 -400.505232)
			(xy 342.614285 -400.540947) (xy 342.65 -400.582164) (xy 342.679486 -400.628045) (xy 342.702143 -400.677655)
			(xy 342.717508 -400.729985) (xy 342.72527 -400.783969) (xy 342.725756 -400.811238) (xy 342.725756 -401.674838)
			(xy 343.162636 -401.674838) (xy 343.162636 -400.811238) (xy 343.163122 -400.783987) (xy 343.170878 -400.730039)
			(xy 343.186233 -400.677744) (xy 343.208875 -400.628167) (xy 343.238341 -400.582317) (xy 343.274032 -400.541126)
			(xy 343.315223 -400.505435) (xy 343.361073 -400.475969) (xy 343.41065 -400.453327) (xy 343.462945 -400.437972)
			(xy 343.516893 -400.430216) (xy 343.571395 -400.430216) (xy 343.625343 -400.437972) (xy 343.677638 -400.453327)
			(xy 343.727215 -400.475969) (xy 343.773065 -400.505435) (xy 343.814256 -400.541126) (xy 343.849947 -400.582317)
			(xy 343.879413 -400.628167) (xy 343.902055 -400.677744) (xy 343.91741 -400.730039) (xy 343.925166 -400.783987)
			(xy 343.925652 -400.811238) (xy 343.925652 -401.674838) (xy 344.362532 -401.674838) (xy 344.362532 -400.811238)
			(xy 344.363018 -400.783987) (xy 344.370774 -400.730039) (xy 344.386129 -400.677744) (xy 344.408771 -400.628167)
			(xy 344.438237 -400.582317) (xy 344.473928 -400.541126) (xy 344.515119 -400.505435) (xy 344.560969 -400.475969)
			(xy 344.610546 -400.453327) (xy 344.662841 -400.437972) (xy 344.716789 -400.430216) (xy 344.771291 -400.430216)
			(xy 344.825239 -400.437972) (xy 344.877534 -400.453327) (xy 344.927111 -400.475969) (xy 344.972961 -400.505435)
			(xy 345.014152 -400.541126) (xy 345.049843 -400.582317) (xy 345.079309 -400.628167) (xy 345.101951 -400.677744)
			(xy 345.117306 -400.730039) (xy 345.125062 -400.783987) (xy 345.125548 -400.811238) (xy 345.125548 -401.674838)
			(xy 345.562428 -401.674838) (xy 345.562428 -400.811238) (xy 345.562914 -400.783969) (xy 345.570676 -400.729985)
			(xy 345.586041 -400.677655) (xy 345.608698 -400.628045) (xy 345.638184 -400.582164) (xy 345.673899 -400.540947)
			(xy 345.715116 -400.505232) (xy 345.760997 -400.475746) (xy 345.810607 -400.453089) (xy 345.862937 -400.437724)
			(xy 345.916921 -400.429962) (xy 345.971459 -400.429962) (xy 346.025443 -400.437724) (xy 346.077773 -400.453089)
			(xy 346.127383 -400.475746) (xy 346.173264 -400.505232) (xy 346.214481 -400.540947) (xy 346.250196 -400.582164)
			(xy 346.279682 -400.628045) (xy 346.302339 -400.677655) (xy 346.317704 -400.729985) (xy 346.325466 -400.783969)
			(xy 346.325952 -400.811238) (xy 346.325952 -401.674838) (xy 346.762324 -401.674838) (xy 346.762324 -400.811238)
			(xy 346.76281 -400.783969) (xy 346.770572 -400.729985) (xy 346.785937 -400.677655) (xy 346.808594 -400.628045)
			(xy 346.83808 -400.582164) (xy 346.873795 -400.540947) (xy 346.915012 -400.505232) (xy 346.960893 -400.475746)
			(xy 347.010503 -400.453089) (xy 347.062833 -400.437724) (xy 347.116817 -400.429962) (xy 347.171355 -400.429962)
			(xy 347.225339 -400.437724) (xy 347.277669 -400.453089) (xy 347.327279 -400.475746) (xy 347.37316 -400.505232)
			(xy 347.414377 -400.540947) (xy 347.450092 -400.582164) (xy 347.479578 -400.628045) (xy 347.502235 -400.677655)
			(xy 347.5176 -400.729985) (xy 347.525362 -400.783969) (xy 347.525848 -400.811238) (xy 347.525848 -401.674838)
			(xy 347.962728 -401.674838) (xy 347.962728 -400.811238) (xy 347.963214 -400.783987) (xy 347.97097 -400.730039)
			(xy 347.986325 -400.677744) (xy 348.008967 -400.628167) (xy 348.038433 -400.582317) (xy 348.074124 -400.541126)
			(xy 348.115315 -400.505435) (xy 348.161165 -400.475969) (xy 348.210742 -400.453327) (xy 348.263037 -400.437972)
			(xy 348.316985 -400.430216) (xy 348.371487 -400.430216) (xy 348.425435 -400.437972) (xy 348.47773 -400.453327)
			(xy 348.527307 -400.475969) (xy 348.573157 -400.505435) (xy 348.614348 -400.541126) (xy 348.650039 -400.582317)
			(xy 348.679505 -400.628167) (xy 348.702147 -400.677744) (xy 348.717502 -400.730039) (xy 348.725258 -400.783987)
			(xy 348.725744 -400.811238) (xy 348.725744 -401.674838) (xy 349.162624 -401.674838) (xy 349.162624 -400.811238)
			(xy 349.16311 -400.783987) (xy 349.170866 -400.730039) (xy 349.186221 -400.677744) (xy 349.208863 -400.628167)
			(xy 349.238329 -400.582317) (xy 349.27402 -400.541126) (xy 349.315211 -400.505435) (xy 349.361061 -400.475969)
			(xy 349.410638 -400.453327) (xy 349.462933 -400.437972) (xy 349.516881 -400.430216) (xy 349.571383 -400.430216)
			(xy 349.625331 -400.437972) (xy 349.677626 -400.453327) (xy 349.727203 -400.475969) (xy 349.773053 -400.505435)
			(xy 349.814244 -400.541126) (xy 349.849935 -400.582317) (xy 349.879401 -400.628167) (xy 349.902043 -400.677744)
			(xy 349.917398 -400.730039) (xy 349.925154 -400.783987) (xy 349.92564 -400.811238) (xy 349.92564 -401.674838)
			(xy 350.36252 -401.674838) (xy 350.36252 -400.811238) (xy 350.363006 -400.783987) (xy 350.370762 -400.730039)
			(xy 350.386117 -400.677744) (xy 350.408759 -400.628167) (xy 350.438225 -400.582317) (xy 350.473916 -400.541126)
			(xy 350.515107 -400.505435) (xy 350.560957 -400.475969) (xy 350.610534 -400.453327) (xy 350.662829 -400.437972)
			(xy 350.716777 -400.430216) (xy 350.771279 -400.430216) (xy 350.825227 -400.437972) (xy 350.877522 -400.453327)
			(xy 350.927099 -400.475969) (xy 350.972949 -400.505435) (xy 351.01414 -400.541126) (xy 351.049831 -400.582317)
			(xy 351.079297 -400.628167) (xy 351.101939 -400.677744) (xy 351.117294 -400.730039) (xy 351.12505 -400.783987)
			(xy 351.125536 -400.811238) (xy 351.125536 -401.674838) (xy 351.562416 -401.674838) (xy 351.562416 -400.811238)
			(xy 351.562902 -400.783987) (xy 351.570658 -400.730039) (xy 351.586013 -400.677744) (xy 351.608655 -400.628167)
			(xy 351.638121 -400.582317) (xy 351.673812 -400.541126) (xy 351.715003 -400.505435) (xy 351.760853 -400.475969)
			(xy 351.81043 -400.453327) (xy 351.862725 -400.437972) (xy 351.916673 -400.430216) (xy 351.971175 -400.430216)
			(xy 352.025123 -400.437972) (xy 352.077418 -400.453327) (xy 352.126995 -400.475969) (xy 352.172845 -400.505435)
			(xy 352.214036 -400.541126) (xy 352.249727 -400.582317) (xy 352.279193 -400.628167) (xy 352.301835 -400.677744)
			(xy 352.31719 -400.730039) (xy 352.324946 -400.783987) (xy 352.325432 -400.811238) (xy 352.325432 -401.674838)
			(xy 352.762312 -401.674838) (xy 352.762312 -400.811238) (xy 352.762798 -400.783969) (xy 352.77056 -400.729985)
			(xy 352.785925 -400.677655) (xy 352.808582 -400.628045) (xy 352.838068 -400.582164) (xy 352.873783 -400.540947)
			(xy 352.915 -400.505232) (xy 352.960881 -400.475746) (xy 353.010491 -400.453089) (xy 353.062821 -400.437724)
			(xy 353.116805 -400.429962) (xy 353.171343 -400.429962) (xy 353.225327 -400.437724) (xy 353.277657 -400.453089)
			(xy 353.327267 -400.475746) (xy 353.373148 -400.505232) (xy 353.414365 -400.540947) (xy 353.45008 -400.582164)
			(xy 353.479566 -400.628045) (xy 353.502223 -400.677655) (xy 353.517588 -400.729985) (xy 353.52535 -400.783969)
			(xy 353.525836 -400.811238) (xy 353.525836 -401.674838) (xy 353.962208 -401.674838) (xy 353.962208 -400.811238)
			(xy 353.962694 -400.783969) (xy 353.970456 -400.729985) (xy 353.985821 -400.677655) (xy 354.008478 -400.628045)
			(xy 354.037964 -400.582164) (xy 354.073679 -400.540947) (xy 354.114896 -400.505232) (xy 354.160777 -400.475746)
			(xy 354.210387 -400.453089) (xy 354.262717 -400.437724) (xy 354.316701 -400.429962) (xy 354.371239 -400.429962)
			(xy 354.425223 -400.437724) (xy 354.477553 -400.453089) (xy 354.527163 -400.475746) (xy 354.573044 -400.505232)
			(xy 354.614261 -400.540947) (xy 354.649976 -400.582164) (xy 354.679462 -400.628045) (xy 354.702119 -400.677655)
			(xy 354.717484 -400.729985) (xy 354.725246 -400.783969) (xy 354.725732 -400.811238) (xy 354.725732 -401.674838)
			(xy 370.534692 -401.674838) (xy 370.534692 -400.811238) (xy 370.535178 -400.783969) (xy 370.54294 -400.729985)
			(xy 370.558305 -400.677655) (xy 370.580962 -400.628045) (xy 370.610448 -400.582164) (xy 370.646163 -400.540947)
			(xy 370.68738 -400.505232) (xy 370.733261 -400.475746) (xy 370.782871 -400.453089) (xy 370.835201 -400.437724)
			(xy 370.889185 -400.429962) (xy 370.943723 -400.429962) (xy 370.997707 -400.437724) (xy 371.050037 -400.453089)
			(xy 371.099647 -400.475746) (xy 371.145528 -400.505232) (xy 371.186745 -400.540947) (xy 371.22246 -400.582164)
			(xy 371.251946 -400.628045) (xy 371.274603 -400.677655) (xy 371.289968 -400.729985) (xy 371.29773 -400.783969)
			(xy 371.298216 -400.811238) (xy 371.298216 -401.674838) (xy 371.734588 -401.674838) (xy 371.734588 -400.811238)
			(xy 371.735074 -400.783969) (xy 371.742836 -400.729985) (xy 371.758201 -400.677655) (xy 371.780858 -400.628045)
			(xy 371.810344 -400.582164) (xy 371.846059 -400.540947) (xy 371.887276 -400.505232) (xy 371.933157 -400.475746)
			(xy 371.982767 -400.453089) (xy 372.035097 -400.437724) (xy 372.089081 -400.429962) (xy 372.143619 -400.429962)
			(xy 372.197603 -400.437724) (xy 372.249933 -400.453089) (xy 372.299543 -400.475746) (xy 372.345424 -400.505232)
			(xy 372.386641 -400.540947) (xy 372.422356 -400.582164) (xy 372.451842 -400.628045) (xy 372.474499 -400.677655)
			(xy 372.489864 -400.729985) (xy 372.497626 -400.783969) (xy 372.498112 -400.811238) (xy 372.498112 -401.674838)
			(xy 372.934992 -401.674838) (xy 372.934992 -400.811238) (xy 372.935478 -400.783987) (xy 372.943234 -400.730039)
			(xy 372.958589 -400.677744) (xy 372.981231 -400.628167) (xy 373.010697 -400.582317) (xy 373.046388 -400.541126)
			(xy 373.087579 -400.505435) (xy 373.133429 -400.475969) (xy 373.183006 -400.453327) (xy 373.235301 -400.437972)
			(xy 373.289249 -400.430216) (xy 373.343751 -400.430216) (xy 373.397699 -400.437972) (xy 373.449994 -400.453327)
			(xy 373.499571 -400.475969) (xy 373.545421 -400.505435) (xy 373.586612 -400.541126) (xy 373.622303 -400.582317)
			(xy 373.651769 -400.628167) (xy 373.674411 -400.677744) (xy 373.689766 -400.730039) (xy 373.697522 -400.783987)
			(xy 373.698008 -400.811238) (xy 373.698008 -401.674838) (xy 374.134888 -401.674838) (xy 374.134888 -400.811238)
			(xy 374.135374 -400.783987) (xy 374.14313 -400.730039) (xy 374.158485 -400.677744) (xy 374.181127 -400.628167)
			(xy 374.210593 -400.582317) (xy 374.246284 -400.541126) (xy 374.287475 -400.505435) (xy 374.333325 -400.475969)
			(xy 374.382902 -400.453327) (xy 374.435197 -400.437972) (xy 374.489145 -400.430216) (xy 374.543647 -400.430216)
			(xy 374.597595 -400.437972) (xy 374.64989 -400.453327) (xy 374.699467 -400.475969) (xy 374.745317 -400.505435)
			(xy 374.786508 -400.541126) (xy 374.822199 -400.582317) (xy 374.851665 -400.628167) (xy 374.874307 -400.677744)
			(xy 374.889662 -400.730039) (xy 374.897418 -400.783987) (xy 374.897904 -400.811238) (xy 374.897904 -401.674838)
			(xy 375.334784 -401.674838) (xy 375.334784 -400.811238) (xy 375.33527 -400.783969) (xy 375.343032 -400.729985)
			(xy 375.358397 -400.677655) (xy 375.381054 -400.628045) (xy 375.41054 -400.582164) (xy 375.446255 -400.540947)
			(xy 375.487472 -400.505232) (xy 375.533353 -400.475746) (xy 375.582963 -400.453089) (xy 375.635293 -400.437724)
			(xy 375.689277 -400.429962) (xy 375.743815 -400.429962) (xy 375.797799 -400.437724) (xy 375.850129 -400.453089)
			(xy 375.899739 -400.475746) (xy 375.94562 -400.505232) (xy 375.986837 -400.540947) (xy 376.022552 -400.582164)
			(xy 376.052038 -400.628045) (xy 376.074695 -400.677655) (xy 376.09006 -400.729985) (xy 376.097822 -400.783969)
			(xy 376.098308 -400.811238) (xy 376.098308 -401.674838) (xy 376.53468 -401.674838) (xy 376.53468 -400.811238)
			(xy 376.535166 -400.783969) (xy 376.542928 -400.729985) (xy 376.558293 -400.677655) (xy 376.58095 -400.628045)
			(xy 376.610436 -400.582164) (xy 376.646151 -400.540947) (xy 376.687368 -400.505232) (xy 376.733249 -400.475746)
			(xy 376.782859 -400.453089) (xy 376.835189 -400.437724) (xy 376.889173 -400.429962) (xy 376.943711 -400.429962)
			(xy 376.997695 -400.437724) (xy 377.050025 -400.453089) (xy 377.099635 -400.475746) (xy 377.145516 -400.505232)
			(xy 377.186733 -400.540947) (xy 377.222448 -400.582164) (xy 377.251934 -400.628045) (xy 377.274591 -400.677655)
			(xy 377.289956 -400.729985) (xy 377.297718 -400.783969) (xy 377.298204 -400.811238) (xy 377.298204 -401.674838)
			(xy 377.735084 -401.674838) (xy 377.735084 -400.811238) (xy 377.73557 -400.783987) (xy 377.743326 -400.730039)
			(xy 377.758681 -400.677744) (xy 377.781323 -400.628167) (xy 377.810789 -400.582317) (xy 377.84648 -400.541126)
			(xy 377.887671 -400.505435) (xy 377.933521 -400.475969) (xy 377.983098 -400.453327) (xy 378.035393 -400.437972)
			(xy 378.089341 -400.430216) (xy 378.143843 -400.430216) (xy 378.197791 -400.437972) (xy 378.250086 -400.453327)
			(xy 378.299663 -400.475969) (xy 378.345513 -400.505435) (xy 378.386704 -400.541126) (xy 378.422395 -400.582317)
			(xy 378.451861 -400.628167) (xy 378.474503 -400.677744) (xy 378.489858 -400.730039) (xy 378.497614 -400.783987)
			(xy 378.4981 -400.811238) (xy 378.4981 -401.674838) (xy 378.93498 -401.674838) (xy 378.93498 -400.811238)
			(xy 378.935466 -400.783987) (xy 378.943222 -400.730039) (xy 378.958577 -400.677744) (xy 378.981219 -400.628167)
			(xy 379.010685 -400.582317) (xy 379.046376 -400.541126) (xy 379.087567 -400.505435) (xy 379.133417 -400.475969)
			(xy 379.182994 -400.453327) (xy 379.235289 -400.437972) (xy 379.289237 -400.430216) (xy 379.343739 -400.430216)
			(xy 379.397687 -400.437972) (xy 379.449982 -400.453327) (xy 379.499559 -400.475969) (xy 379.545409 -400.505435)
			(xy 379.5866 -400.541126) (xy 379.622291 -400.582317) (xy 379.651757 -400.628167) (xy 379.674399 -400.677744)
			(xy 379.689754 -400.730039) (xy 379.69751 -400.783987) (xy 379.697996 -400.811238) (xy 379.697996 -401.674838)
			(xy 380.134876 -401.674838) (xy 380.134876 -400.811238) (xy 380.135362 -400.783969) (xy 380.143124 -400.729985)
			(xy 380.158489 -400.677655) (xy 380.181146 -400.628045) (xy 380.210632 -400.582164) (xy 380.246347 -400.540947)
			(xy 380.287564 -400.505232) (xy 380.333445 -400.475746) (xy 380.383055 -400.453089) (xy 380.435385 -400.437724)
			(xy 380.489369 -400.429962) (xy 380.543907 -400.429962) (xy 380.597891 -400.437724) (xy 380.650221 -400.453089)
			(xy 380.699831 -400.475746) (xy 380.745712 -400.505232) (xy 380.786929 -400.540947) (xy 380.822644 -400.582164)
			(xy 380.85213 -400.628045) (xy 380.874787 -400.677655) (xy 380.890152 -400.729985) (xy 380.897914 -400.783969)
			(xy 380.8984 -400.811238) (xy 380.8984 -401.674838) (xy 381.334772 -401.674838) (xy 381.334772 -400.811238)
			(xy 381.335258 -400.783969) (xy 381.34302 -400.729985) (xy 381.358385 -400.677655) (xy 381.381042 -400.628045)
			(xy 381.410528 -400.582164) (xy 381.446243 -400.540947) (xy 381.48746 -400.505232) (xy 381.533341 -400.475746)
			(xy 381.582951 -400.453089) (xy 381.635281 -400.437724) (xy 381.689265 -400.429962) (xy 381.743803 -400.429962)
			(xy 381.797787 -400.437724) (xy 381.850117 -400.453089) (xy 381.899727 -400.475746) (xy 381.945608 -400.505232)
			(xy 381.986825 -400.540947) (xy 382.02254 -400.582164) (xy 382.052026 -400.628045) (xy 382.074683 -400.677655)
			(xy 382.090048 -400.729985) (xy 382.09781 -400.783969) (xy 382.098296 -400.811238) (xy 382.098296 -401.674838)
			(xy 382.535176 -401.674838) (xy 382.535176 -400.811238) (xy 382.535662 -400.783987) (xy 382.543418 -400.730039)
			(xy 382.558773 -400.677744) (xy 382.581415 -400.628167) (xy 382.610881 -400.582317) (xy 382.646572 -400.541126)
			(xy 382.687763 -400.505435) (xy 382.733613 -400.475969) (xy 382.78319 -400.453327) (xy 382.835485 -400.437972)
			(xy 382.889433 -400.430216) (xy 382.943935 -400.430216) (xy 382.997883 -400.437972) (xy 383.050178 -400.453327)
			(xy 383.099755 -400.475969) (xy 383.145605 -400.505435) (xy 383.186796 -400.541126) (xy 383.222487 -400.582317)
			(xy 383.251953 -400.628167) (xy 383.274595 -400.677744) (xy 383.28995 -400.730039) (xy 383.297706 -400.783987)
			(xy 383.298192 -400.811238) (xy 383.298192 -401.674838) (xy 383.735072 -401.674838) (xy 383.735072 -400.811238)
			(xy 383.735558 -400.783987) (xy 383.743314 -400.730039) (xy 383.758669 -400.677744) (xy 383.781311 -400.628167)
			(xy 383.810777 -400.582317) (xy 383.846468 -400.541126) (xy 383.887659 -400.505435) (xy 383.933509 -400.475969)
			(xy 383.983086 -400.453327) (xy 384.035381 -400.437972) (xy 384.089329 -400.430216) (xy 384.143831 -400.430216)
			(xy 384.197779 -400.437972) (xy 384.250074 -400.453327) (xy 384.299651 -400.475969) (xy 384.345501 -400.505435)
			(xy 384.386692 -400.541126) (xy 384.422383 -400.582317) (xy 384.451849 -400.628167) (xy 384.474491 -400.677744)
			(xy 384.489846 -400.730039) (xy 384.497602 -400.783987) (xy 384.498088 -400.811238) (xy 384.498088 -401.674838)
			(xy 384.934968 -401.674838) (xy 384.934968 -400.811238) (xy 384.935454 -400.783987) (xy 384.94321 -400.730039)
			(xy 384.958565 -400.677744) (xy 384.981207 -400.628167) (xy 385.010673 -400.582317) (xy 385.046364 -400.541126)
			(xy 385.087555 -400.505435) (xy 385.133405 -400.475969) (xy 385.182982 -400.453327) (xy 385.235277 -400.437972)
			(xy 385.289225 -400.430216) (xy 385.343727 -400.430216) (xy 385.397675 -400.437972) (xy 385.44997 -400.453327)
			(xy 385.499547 -400.475969) (xy 385.545397 -400.505435) (xy 385.586588 -400.541126) (xy 385.622279 -400.582317)
			(xy 385.651745 -400.628167) (xy 385.674387 -400.677744) (xy 385.689742 -400.730039) (xy 385.697498 -400.783987)
			(xy 385.697984 -400.811238) (xy 385.697984 -401.674838) (xy 386.134864 -401.674838) (xy 386.134864 -400.811238)
			(xy 386.13535 -400.783987) (xy 386.143106 -400.730039) (xy 386.158461 -400.677744) (xy 386.181103 -400.628167)
			(xy 386.210569 -400.582317) (xy 386.24626 -400.541126) (xy 386.287451 -400.505435) (xy 386.333301 -400.475969)
			(xy 386.382878 -400.453327) (xy 386.435173 -400.437972) (xy 386.489121 -400.430216) (xy 386.543623 -400.430216)
			(xy 386.597571 -400.437972) (xy 386.649866 -400.453327) (xy 386.699443 -400.475969) (xy 386.745293 -400.505435)
			(xy 386.786484 -400.541126) (xy 386.822175 -400.582317) (xy 386.851641 -400.628167) (xy 386.874283 -400.677744)
			(xy 386.889638 -400.730039) (xy 386.897394 -400.783987) (xy 386.89788 -400.811238) (xy 386.89788 -401.674838)
			(xy 387.33476 -401.674838) (xy 387.33476 -400.811238) (xy 387.335246 -400.783969) (xy 387.343008 -400.729985)
			(xy 387.358373 -400.677655) (xy 387.38103 -400.628045) (xy 387.410516 -400.582164) (xy 387.446231 -400.540947)
			(xy 387.487448 -400.505232) (xy 387.533329 -400.475746) (xy 387.582939 -400.453089) (xy 387.635269 -400.437724)
			(xy 387.689253 -400.429962) (xy 387.743791 -400.429962) (xy 387.797775 -400.437724) (xy 387.850105 -400.453089)
			(xy 387.899715 -400.475746) (xy 387.945596 -400.505232) (xy 387.986813 -400.540947) (xy 388.022528 -400.582164)
			(xy 388.052014 -400.628045) (xy 388.074671 -400.677655) (xy 388.090036 -400.729985) (xy 388.097798 -400.783969)
			(xy 388.098284 -400.811238) (xy 388.098284 -401.674838) (xy 388.534656 -401.674838) (xy 388.534656 -400.811238)
			(xy 388.535142 -400.783969) (xy 388.542904 -400.729985) (xy 388.558269 -400.677655) (xy 388.580926 -400.628045)
			(xy 388.610412 -400.582164) (xy 388.646127 -400.540947) (xy 388.687344 -400.505232) (xy 388.733225 -400.475746)
			(xy 388.782835 -400.453089) (xy 388.835165 -400.437724) (xy 388.889149 -400.429962) (xy 388.943687 -400.429962)
			(xy 388.997671 -400.437724) (xy 389.050001 -400.453089) (xy 389.099611 -400.475746) (xy 389.145492 -400.505232)
			(xy 389.186709 -400.540947) (xy 389.222424 -400.582164) (xy 389.25191 -400.628045) (xy 389.274567 -400.677655)
			(xy 389.289932 -400.729985) (xy 389.297694 -400.783969) (xy 389.29818 -400.811238) (xy 389.29818 -401.674838)
			(xy 403.06244 -401.674838) (xy 403.06244 -400.811238) (xy 403.062926 -400.783969) (xy 403.070688 -400.729985)
			(xy 403.086053 -400.677655) (xy 403.10871 -400.628045) (xy 403.138196 -400.582164) (xy 403.173911 -400.540947)
			(xy 403.215128 -400.505232) (xy 403.261009 -400.475746) (xy 403.310619 -400.453089) (xy 403.362949 -400.437724)
			(xy 403.416933 -400.429962) (xy 403.471471 -400.429962) (xy 403.525455 -400.437724) (xy 403.577785 -400.453089)
			(xy 403.627395 -400.475746) (xy 403.673276 -400.505232) (xy 403.714493 -400.540947) (xy 403.750208 -400.582164)
			(xy 403.779694 -400.628045) (xy 403.802351 -400.677655) (xy 403.817716 -400.729985) (xy 403.825478 -400.783969)
			(xy 403.825964 -400.811238) (xy 403.825964 -401.674838) (xy 404.262336 -401.674838) (xy 404.262336 -400.811238)
			(xy 404.262822 -400.783969) (xy 404.270584 -400.729985) (xy 404.285949 -400.677655) (xy 404.308606 -400.628045)
			(xy 404.338092 -400.582164) (xy 404.373807 -400.540947) (xy 404.415024 -400.505232) (xy 404.460905 -400.475746)
			(xy 404.510515 -400.453089) (xy 404.562845 -400.437724) (xy 404.616829 -400.429962) (xy 404.671367 -400.429962)
			(xy 404.725351 -400.437724) (xy 404.777681 -400.453089) (xy 404.827291 -400.475746) (xy 404.873172 -400.505232)
			(xy 404.914389 -400.540947) (xy 404.950104 -400.582164) (xy 404.97959 -400.628045) (xy 405.002247 -400.677655)
			(xy 405.017612 -400.729985) (xy 405.025374 -400.783969) (xy 405.02586 -400.811238) (xy 405.02586 -401.674838)
			(xy 405.46274 -401.674838) (xy 405.46274 -400.811238) (xy 405.463226 -400.783987) (xy 405.470982 -400.730039)
			(xy 405.486337 -400.677744) (xy 405.508979 -400.628167) (xy 405.538445 -400.582317) (xy 405.574136 -400.541126)
			(xy 405.615327 -400.505435) (xy 405.661177 -400.475969) (xy 405.710754 -400.453327) (xy 405.763049 -400.437972)
			(xy 405.816997 -400.430216) (xy 405.871499 -400.430216) (xy 405.925447 -400.437972) (xy 405.977742 -400.453327)
			(xy 406.027319 -400.475969) (xy 406.073169 -400.505435) (xy 406.11436 -400.541126) (xy 406.150051 -400.582317)
			(xy 406.179517 -400.628167) (xy 406.202159 -400.677744) (xy 406.217514 -400.730039) (xy 406.22527 -400.783987)
			(xy 406.225756 -400.811238) (xy 406.225756 -401.674838) (xy 406.662636 -401.674838) (xy 406.662636 -400.811238)
			(xy 406.663122 -400.783987) (xy 406.670878 -400.730039) (xy 406.686233 -400.677744) (xy 406.708875 -400.628167)
			(xy 406.738341 -400.582317) (xy 406.774032 -400.541126) (xy 406.815223 -400.505435) (xy 406.861073 -400.475969)
			(xy 406.91065 -400.453327) (xy 406.962945 -400.437972) (xy 407.016893 -400.430216) (xy 407.071395 -400.430216)
			(xy 407.125343 -400.437972) (xy 407.177638 -400.453327) (xy 407.227215 -400.475969) (xy 407.273065 -400.505435)
			(xy 407.314256 -400.541126) (xy 407.349947 -400.582317) (xy 407.379413 -400.628167) (xy 407.402055 -400.677744)
			(xy 407.41741 -400.730039) (xy 407.425166 -400.783987) (xy 407.425652 -400.811238) (xy 407.425652 -401.674838)
			(xy 407.862532 -401.674838) (xy 407.862532 -400.811238) (xy 407.863018 -400.783969) (xy 407.87078 -400.729985)
			(xy 407.886145 -400.677655) (xy 407.908802 -400.628045) (xy 407.938288 -400.582164) (xy 407.974003 -400.540947)
			(xy 408.01522 -400.505232) (xy 408.061101 -400.475746) (xy 408.110711 -400.453089) (xy 408.163041 -400.437724)
			(xy 408.217025 -400.429962) (xy 408.271563 -400.429962) (xy 408.325547 -400.437724) (xy 408.377877 -400.453089)
			(xy 408.427487 -400.475746) (xy 408.473368 -400.505232) (xy 408.514585 -400.540947) (xy 408.5503 -400.582164)
			(xy 408.579786 -400.628045) (xy 408.602443 -400.677655) (xy 408.617808 -400.729985) (xy 408.62557 -400.783969)
			(xy 408.626056 -400.811238) (xy 408.626056 -401.674838) (xy 409.062428 -401.674838) (xy 409.062428 -400.811238)
			(xy 409.062914 -400.783969) (xy 409.070676 -400.729985) (xy 409.086041 -400.677655) (xy 409.108698 -400.628045)
			(xy 409.138184 -400.582164) (xy 409.173899 -400.540947) (xy 409.215116 -400.505232) (xy 409.260997 -400.475746)
			(xy 409.310607 -400.453089) (xy 409.362937 -400.437724) (xy 409.416921 -400.429962) (xy 409.471459 -400.429962)
			(xy 409.525443 -400.437724) (xy 409.577773 -400.453089) (xy 409.627383 -400.475746) (xy 409.673264 -400.505232)
			(xy 409.714481 -400.540947) (xy 409.750196 -400.582164) (xy 409.779682 -400.628045) (xy 409.802339 -400.677655)
			(xy 409.817704 -400.729985) (xy 409.825466 -400.783969) (xy 409.825952 -400.811238) (xy 409.825952 -401.674838)
			(xy 410.262832 -401.674838) (xy 410.262832 -400.811238) (xy 410.263318 -400.783987) (xy 410.271074 -400.730039)
			(xy 410.286429 -400.677744) (xy 410.309071 -400.628167) (xy 410.338537 -400.582317) (xy 410.374228 -400.541126)
			(xy 410.415419 -400.505435) (xy 410.461269 -400.475969) (xy 410.510846 -400.453327) (xy 410.563141 -400.437972)
			(xy 410.617089 -400.430216) (xy 410.671591 -400.430216) (xy 410.725539 -400.437972) (xy 410.777834 -400.453327)
			(xy 410.827411 -400.475969) (xy 410.873261 -400.505435) (xy 410.914452 -400.541126) (xy 410.950143 -400.582317)
			(xy 410.979609 -400.628167) (xy 411.002251 -400.677744) (xy 411.017606 -400.730039) (xy 411.025362 -400.783987)
			(xy 411.025848 -400.811238) (xy 411.025848 -401.674838) (xy 411.462728 -401.674838) (xy 411.462728 -400.811238)
			(xy 411.463214 -400.783987) (xy 411.47097 -400.730039) (xy 411.486325 -400.677744) (xy 411.508967 -400.628167)
			(xy 411.538433 -400.582317) (xy 411.574124 -400.541126) (xy 411.615315 -400.505435) (xy 411.661165 -400.475969)
			(xy 411.710742 -400.453327) (xy 411.763037 -400.437972) (xy 411.816985 -400.430216) (xy 411.871487 -400.430216)
			(xy 411.925435 -400.437972) (xy 411.97773 -400.453327) (xy 412.027307 -400.475969) (xy 412.073157 -400.505435)
			(xy 412.114348 -400.541126) (xy 412.150039 -400.582317) (xy 412.179505 -400.628167) (xy 412.202147 -400.677744)
			(xy 412.217502 -400.730039) (xy 412.225258 -400.783987) (xy 412.225744 -400.811238) (xy 412.225744 -401.674838)
			(xy 412.662624 -401.674838) (xy 412.662624 -400.811238) (xy 412.66311 -400.783969) (xy 412.670872 -400.729985)
			(xy 412.686237 -400.677655) (xy 412.708894 -400.628045) (xy 412.73838 -400.582164) (xy 412.774095 -400.540947)
			(xy 412.815312 -400.505232) (xy 412.861193 -400.475746) (xy 412.910803 -400.453089) (xy 412.963133 -400.437724)
			(xy 413.017117 -400.429962) (xy 413.071655 -400.429962) (xy 413.125639 -400.437724) (xy 413.177969 -400.453089)
			(xy 413.227579 -400.475746) (xy 413.27346 -400.505232) (xy 413.314677 -400.540947) (xy 413.350392 -400.582164)
			(xy 413.379878 -400.628045) (xy 413.402535 -400.677655) (xy 413.4179 -400.729985) (xy 413.425662 -400.783969)
			(xy 413.426148 -400.811238) (xy 413.426148 -401.674838) (xy 413.86252 -401.674838) (xy 413.86252 -400.811238)
			(xy 413.863006 -400.783969) (xy 413.870768 -400.729985) (xy 413.886133 -400.677655) (xy 413.90879 -400.628045)
			(xy 413.938276 -400.582164) (xy 413.973991 -400.540947) (xy 414.015208 -400.505232) (xy 414.061089 -400.475746)
			(xy 414.110699 -400.453089) (xy 414.163029 -400.437724) (xy 414.217013 -400.429962) (xy 414.271551 -400.429962)
			(xy 414.325535 -400.437724) (xy 414.377865 -400.453089) (xy 414.427475 -400.475746) (xy 414.473356 -400.505232)
			(xy 414.514573 -400.540947) (xy 414.550288 -400.582164) (xy 414.579774 -400.628045) (xy 414.602431 -400.677655)
			(xy 414.617796 -400.729985) (xy 414.625558 -400.783969) (xy 414.626044 -400.811238) (xy 414.626044 -401.674838)
			(xy 415.062924 -401.674838) (xy 415.062924 -400.811238) (xy 415.06341 -400.783987) (xy 415.071166 -400.730039)
			(xy 415.086521 -400.677744) (xy 415.109163 -400.628167) (xy 415.138629 -400.582317) (xy 415.17432 -400.541126)
			(xy 415.215511 -400.505435) (xy 415.261361 -400.475969) (xy 415.310938 -400.453327) (xy 415.363233 -400.437972)
			(xy 415.417181 -400.430216) (xy 415.471683 -400.430216) (xy 415.525631 -400.437972) (xy 415.577926 -400.453327)
			(xy 415.627503 -400.475969) (xy 415.673353 -400.505435) (xy 415.714544 -400.541126) (xy 415.750235 -400.582317)
			(xy 415.779701 -400.628167) (xy 415.802343 -400.677744) (xy 415.817698 -400.730039) (xy 415.825454 -400.783987)
			(xy 415.82594 -400.811238) (xy 415.82594 -401.674838) (xy 416.26282 -401.674838) (xy 416.26282 -400.811238)
			(xy 416.263306 -400.783987) (xy 416.271062 -400.730039) (xy 416.286417 -400.677744) (xy 416.309059 -400.628167)
			(xy 416.338525 -400.582317) (xy 416.374216 -400.541126) (xy 416.415407 -400.505435) (xy 416.461257 -400.475969)
			(xy 416.510834 -400.453327) (xy 416.563129 -400.437972) (xy 416.617077 -400.430216) (xy 416.671579 -400.430216)
			(xy 416.725527 -400.437972) (xy 416.777822 -400.453327) (xy 416.827399 -400.475969) (xy 416.873249 -400.505435)
			(xy 416.91444 -400.541126) (xy 416.950131 -400.582317) (xy 416.979597 -400.628167) (xy 417.002239 -400.677744)
			(xy 417.017594 -400.730039) (xy 417.02535 -400.783987) (xy 417.025836 -400.811238) (xy 417.025836 -401.674838)
			(xy 417.462716 -401.674838) (xy 417.462716 -400.811238) (xy 417.463202 -400.783987) (xy 417.470958 -400.730039)
			(xy 417.486313 -400.677744) (xy 417.508955 -400.628167) (xy 417.538421 -400.582317) (xy 417.574112 -400.541126)
			(xy 417.615303 -400.505435) (xy 417.661153 -400.475969) (xy 417.71073 -400.453327) (xy 417.763025 -400.437972)
			(xy 417.816973 -400.430216) (xy 417.871475 -400.430216) (xy 417.925423 -400.437972) (xy 417.977718 -400.453327)
			(xy 418.027295 -400.475969) (xy 418.073145 -400.505435) (xy 418.114336 -400.541126) (xy 418.150027 -400.582317)
			(xy 418.179493 -400.628167) (xy 418.202135 -400.677744) (xy 418.21749 -400.730039) (xy 418.225246 -400.783987)
			(xy 418.225732 -400.811238) (xy 418.225732 -401.674838) (xy 418.662612 -401.674838) (xy 418.662612 -400.811238)
			(xy 418.663098 -400.783987) (xy 418.670854 -400.730039) (xy 418.686209 -400.677744) (xy 418.708851 -400.628167)
			(xy 418.738317 -400.582317) (xy 418.774008 -400.541126) (xy 418.815199 -400.505435) (xy 418.861049 -400.475969)
			(xy 418.910626 -400.453327) (xy 418.962921 -400.437972) (xy 419.016869 -400.430216) (xy 419.071371 -400.430216)
			(xy 419.125319 -400.437972) (xy 419.177614 -400.453327) (xy 419.227191 -400.475969) (xy 419.273041 -400.505435)
			(xy 419.314232 -400.541126) (xy 419.349923 -400.582317) (xy 419.379389 -400.628167) (xy 419.402031 -400.677744)
			(xy 419.417386 -400.730039) (xy 419.425142 -400.783987) (xy 419.425628 -400.811238) (xy 419.425628 -401.674838)
			(xy 419.862508 -401.674838) (xy 419.862508 -400.811238) (xy 419.862994 -400.783969) (xy 419.870756 -400.729985)
			(xy 419.886121 -400.677655) (xy 419.908778 -400.628045) (xy 419.938264 -400.582164) (xy 419.973979 -400.540947)
			(xy 420.015196 -400.505232) (xy 420.061077 -400.475746) (xy 420.110687 -400.453089) (xy 420.163017 -400.437724)
			(xy 420.217001 -400.429962) (xy 420.271539 -400.429962) (xy 420.325523 -400.437724) (xy 420.377853 -400.453089)
			(xy 420.427463 -400.475746) (xy 420.473344 -400.505232) (xy 420.514561 -400.540947) (xy 420.550276 -400.582164)
			(xy 420.579762 -400.628045) (xy 420.602419 -400.677655) (xy 420.617784 -400.729985) (xy 420.625546 -400.783969)
			(xy 420.626032 -400.811238) (xy 420.626032 -401.674838) (xy 421.062404 -401.674838) (xy 421.062404 -400.811238)
			(xy 421.06289 -400.783969) (xy 421.070652 -400.729985) (xy 421.086017 -400.677655) (xy 421.108674 -400.628045)
			(xy 421.13816 -400.582164) (xy 421.173875 -400.540947) (xy 421.215092 -400.505232) (xy 421.260973 -400.475746)
			(xy 421.310583 -400.453089) (xy 421.362913 -400.437724) (xy 421.416897 -400.429962) (xy 421.471435 -400.429962)
			(xy 421.525419 -400.437724) (xy 421.577749 -400.453089) (xy 421.627359 -400.475746) (xy 421.67324 -400.505232)
			(xy 421.714457 -400.540947) (xy 421.750172 -400.582164) (xy 421.779658 -400.628045) (xy 421.802315 -400.677655)
			(xy 421.81768 -400.729985) (xy 421.825442 -400.783969) (xy 421.825928 -400.811238) (xy 421.825928 -401.674838)
			(xy 421.825442 -401.702107) (xy 421.81768 -401.756091) (xy 421.802315 -401.808421) (xy 421.779658 -401.858031)
			(xy 421.750172 -401.903912) (xy 421.714457 -401.945129) (xy 421.67324 -401.980844) (xy 421.627359 -402.01033)
			(xy 421.577749 -402.032987) (xy 421.525419 -402.048352) (xy 421.471435 -402.056114) (xy 421.416897 -402.056114)
			(xy 421.362913 -402.048352) (xy 421.310583 -402.032987) (xy 421.260973 -402.01033) (xy 421.215092 -401.980844)
			(xy 421.173875 -401.945129) (xy 421.13816 -401.903912) (xy 421.108674 -401.858031) (xy 421.086017 -401.808421)
			(xy 421.070652 -401.756091) (xy 421.06289 -401.702107) (xy 421.062404 -401.674838) (xy 420.626032 -401.674838)
			(xy 420.625546 -401.702107) (xy 420.617784 -401.756091) (xy 420.602419 -401.808421) (xy 420.579762 -401.858031)
			(xy 420.550276 -401.903912) (xy 420.514561 -401.945129) (xy 420.473344 -401.980844) (xy 420.427463 -402.01033)
			(xy 420.377853 -402.032987) (xy 420.325523 -402.048352) (xy 420.271539 -402.056114) (xy 420.217001 -402.056114)
			(xy 420.163017 -402.048352) (xy 420.110687 -402.032987) (xy 420.061077 -402.01033) (xy 420.015196 -401.980844)
			(xy 419.973979 -401.945129) (xy 419.938264 -401.903912) (xy 419.908778 -401.858031) (xy 419.886121 -401.808421)
			(xy 419.870756 -401.756091) (xy 419.862994 -401.702107) (xy 419.862508 -401.674838) (xy 419.425628 -401.674838)
			(xy 419.425142 -401.702089) (xy 419.417386 -401.756037) (xy 419.402031 -401.808332) (xy 419.379389 -401.857909)
			(xy 419.349923 -401.903759) (xy 419.314232 -401.94495) (xy 419.273041 -401.980641) (xy 419.227191 -402.010107)
			(xy 419.177614 -402.032749) (xy 419.125319 -402.048104) (xy 419.071371 -402.05586) (xy 419.016869 -402.05586)
			(xy 418.962921 -402.048104) (xy 418.910626 -402.032749) (xy 418.861049 -402.010107) (xy 418.815199 -401.980641)
			(xy 418.774008 -401.94495) (xy 418.738317 -401.903759) (xy 418.708851 -401.857909) (xy 418.686209 -401.808332)
			(xy 418.670854 -401.756037) (xy 418.663098 -401.702089) (xy 418.662612 -401.674838) (xy 418.225732 -401.674838)
			(xy 418.225246 -401.702089) (xy 418.21749 -401.756037) (xy 418.202135 -401.808332) (xy 418.179493 -401.857909)
			(xy 418.150027 -401.903759) (xy 418.114336 -401.94495) (xy 418.073145 -401.980641) (xy 418.027295 -402.010107)
			(xy 417.977718 -402.032749) (xy 417.925423 -402.048104) (xy 417.871475 -402.05586) (xy 417.816973 -402.05586)
			(xy 417.763025 -402.048104) (xy 417.71073 -402.032749) (xy 417.661153 -402.010107) (xy 417.615303 -401.980641)
			(xy 417.574112 -401.94495) (xy 417.538421 -401.903759) (xy 417.508955 -401.857909) (xy 417.486313 -401.808332)
			(xy 417.470958 -401.756037) (xy 417.463202 -401.702089) (xy 417.462716 -401.674838) (xy 417.025836 -401.674838)
			(xy 417.02535 -401.702089) (xy 417.017594 -401.756037) (xy 417.002239 -401.808332) (xy 416.979597 -401.857909)
			(xy 416.950131 -401.903759) (xy 416.91444 -401.94495) (xy 416.873249 -401.980641) (xy 416.827399 -402.010107)
			(xy 416.777822 -402.032749) (xy 416.725527 -402.048104) (xy 416.671579 -402.05586) (xy 416.617077 -402.05586)
			(xy 416.563129 -402.048104) (xy 416.510834 -402.032749) (xy 416.461257 -402.010107) (xy 416.415407 -401.980641)
			(xy 416.374216 -401.94495) (xy 416.338525 -401.903759) (xy 416.309059 -401.857909) (xy 416.286417 -401.808332)
			(xy 416.271062 -401.756037) (xy 416.263306 -401.702089) (xy 416.26282 -401.674838) (xy 415.82594 -401.674838)
			(xy 415.825454 -401.702089) (xy 415.817698 -401.756037) (xy 415.802343 -401.808332) (xy 415.779701 -401.857909)
			(xy 415.750235 -401.903759) (xy 415.714544 -401.94495) (xy 415.673353 -401.980641) (xy 415.627503 -402.010107)
			(xy 415.577926 -402.032749) (xy 415.525631 -402.048104) (xy 415.471683 -402.05586) (xy 415.417181 -402.05586)
			(xy 415.363233 -402.048104) (xy 415.310938 -402.032749) (xy 415.261361 -402.010107) (xy 415.215511 -401.980641)
			(xy 415.17432 -401.94495) (xy 415.138629 -401.903759) (xy 415.109163 -401.857909) (xy 415.086521 -401.808332)
			(xy 415.071166 -401.756037) (xy 415.06341 -401.702089) (xy 415.062924 -401.674838) (xy 414.626044 -401.674838)
			(xy 414.625558 -401.702107) (xy 414.617796 -401.756091) (xy 414.602431 -401.808421) (xy 414.579774 -401.858031)
			(xy 414.550288 -401.903912) (xy 414.514573 -401.945129) (xy 414.473356 -401.980844) (xy 414.427475 -402.01033)
			(xy 414.377865 -402.032987) (xy 414.325535 -402.048352) (xy 414.271551 -402.056114) (xy 414.217013 -402.056114)
			(xy 414.163029 -402.048352) (xy 414.110699 -402.032987) (xy 414.061089 -402.01033) (xy 414.015208 -401.980844)
			(xy 413.973991 -401.945129) (xy 413.938276 -401.903912) (xy 413.90879 -401.858031) (xy 413.886133 -401.808421)
			(xy 413.870768 -401.756091) (xy 413.863006 -401.702107) (xy 413.86252 -401.674838) (xy 413.426148 -401.674838)
			(xy 413.425662 -401.702107) (xy 413.4179 -401.756091) (xy 413.402535 -401.808421) (xy 413.379878 -401.858031)
			(xy 413.350392 -401.903912) (xy 413.314677 -401.945129) (xy 413.27346 -401.980844) (xy 413.227579 -402.01033)
			(xy 413.177969 -402.032987) (xy 413.125639 -402.048352) (xy 413.071655 -402.056114) (xy 413.017117 -402.056114)
			(xy 412.963133 -402.048352) (xy 412.910803 -402.032987) (xy 412.861193 -402.01033) (xy 412.815312 -401.980844)
			(xy 412.774095 -401.945129) (xy 412.73838 -401.903912) (xy 412.708894 -401.858031) (xy 412.686237 -401.808421)
			(xy 412.670872 -401.756091) (xy 412.66311 -401.702107) (xy 412.662624 -401.674838) (xy 412.225744 -401.674838)
			(xy 412.225258 -401.702089) (xy 412.217502 -401.756037) (xy 412.202147 -401.808332) (xy 412.179505 -401.857909)
			(xy 412.150039 -401.903759) (xy 412.114348 -401.94495) (xy 412.073157 -401.980641) (xy 412.027307 -402.010107)
			(xy 411.97773 -402.032749) (xy 411.925435 -402.048104) (xy 411.871487 -402.05586) (xy 411.816985 -402.05586)
			(xy 411.763037 -402.048104) (xy 411.710742 -402.032749) (xy 411.661165 -402.010107) (xy 411.615315 -401.980641)
			(xy 411.574124 -401.94495) (xy 411.538433 -401.903759) (xy 411.508967 -401.857909) (xy 411.486325 -401.808332)
			(xy 411.47097 -401.756037) (xy 411.463214 -401.702089) (xy 411.462728 -401.674838) (xy 411.025848 -401.674838)
			(xy 411.025362 -401.702089) (xy 411.017606 -401.756037) (xy 411.002251 -401.808332) (xy 410.979609 -401.857909)
			(xy 410.950143 -401.903759) (xy 410.914452 -401.94495) (xy 410.873261 -401.980641) (xy 410.827411 -402.010107)
			(xy 410.777834 -402.032749) (xy 410.725539 -402.048104) (xy 410.671591 -402.05586) (xy 410.617089 -402.05586)
			(xy 410.563141 -402.048104) (xy 410.510846 -402.032749) (xy 410.461269 -402.010107) (xy 410.415419 -401.980641)
			(xy 410.374228 -401.94495) (xy 410.338537 -401.903759) (xy 410.309071 -401.857909) (xy 410.286429 -401.808332)
			(xy 410.271074 -401.756037) (xy 410.263318 -401.702089) (xy 410.262832 -401.674838) (xy 409.825952 -401.674838)
			(xy 409.825466 -401.702107) (xy 409.817704 -401.756091) (xy 409.802339 -401.808421) (xy 409.779682 -401.858031)
			(xy 409.750196 -401.903912) (xy 409.714481 -401.945129) (xy 409.673264 -401.980844) (xy 409.627383 -402.01033)
			(xy 409.577773 -402.032987) (xy 409.525443 -402.048352) (xy 409.471459 -402.056114) (xy 409.416921 -402.056114)
			(xy 409.362937 -402.048352) (xy 409.310607 -402.032987) (xy 409.260997 -402.01033) (xy 409.215116 -401.980844)
			(xy 409.173899 -401.945129) (xy 409.138184 -401.903912) (xy 409.108698 -401.858031) (xy 409.086041 -401.808421)
			(xy 409.070676 -401.756091) (xy 409.062914 -401.702107) (xy 409.062428 -401.674838) (xy 408.626056 -401.674838)
			(xy 408.62557 -401.702107) (xy 408.617808 -401.756091) (xy 408.602443 -401.808421) (xy 408.579786 -401.858031)
			(xy 408.5503 -401.903912) (xy 408.514585 -401.945129) (xy 408.473368 -401.980844) (xy 408.427487 -402.01033)
			(xy 408.377877 -402.032987) (xy 408.325547 -402.048352) (xy 408.271563 -402.056114) (xy 408.217025 -402.056114)
			(xy 408.163041 -402.048352) (xy 408.110711 -402.032987) (xy 408.061101 -402.01033) (xy 408.01522 -401.980844)
			(xy 407.974003 -401.945129) (xy 407.938288 -401.903912) (xy 407.908802 -401.858031) (xy 407.886145 -401.808421)
			(xy 407.87078 -401.756091) (xy 407.863018 -401.702107) (xy 407.862532 -401.674838) (xy 407.425652 -401.674838)
			(xy 407.425166 -401.702089) (xy 407.41741 -401.756037) (xy 407.402055 -401.808332) (xy 407.379413 -401.857909)
			(xy 407.349947 -401.903759) (xy 407.314256 -401.94495) (xy 407.273065 -401.980641) (xy 407.227215 -402.010107)
			(xy 407.177638 -402.032749) (xy 407.125343 -402.048104) (xy 407.071395 -402.05586) (xy 407.016893 -402.05586)
			(xy 406.962945 -402.048104) (xy 406.91065 -402.032749) (xy 406.861073 -402.010107) (xy 406.815223 -401.980641)
			(xy 406.774032 -401.94495) (xy 406.738341 -401.903759) (xy 406.708875 -401.857909) (xy 406.686233 -401.808332)
			(xy 406.670878 -401.756037) (xy 406.663122 -401.702089) (xy 406.662636 -401.674838) (xy 406.225756 -401.674838)
			(xy 406.22527 -401.702089) (xy 406.217514 -401.756037) (xy 406.202159 -401.808332) (xy 406.179517 -401.857909)
			(xy 406.150051 -401.903759) (xy 406.11436 -401.94495) (xy 406.073169 -401.980641) (xy 406.027319 -402.010107)
			(xy 405.977742 -402.032749) (xy 405.925447 -402.048104) (xy 405.871499 -402.05586) (xy 405.816997 -402.05586)
			(xy 405.763049 -402.048104) (xy 405.710754 -402.032749) (xy 405.661177 -402.010107) (xy 405.615327 -401.980641)
			(xy 405.574136 -401.94495) (xy 405.538445 -401.903759) (xy 405.508979 -401.857909) (xy 405.486337 -401.808332)
			(xy 405.470982 -401.756037) (xy 405.463226 -401.702089) (xy 405.46274 -401.674838) (xy 405.02586 -401.674838)
			(xy 405.025374 -401.702107) (xy 405.017612 -401.756091) (xy 405.002247 -401.808421) (xy 404.97959 -401.858031)
			(xy 404.950104 -401.903912) (xy 404.914389 -401.945129) (xy 404.873172 -401.980844) (xy 404.827291 -402.01033)
			(xy 404.777681 -402.032987) (xy 404.725351 -402.048352) (xy 404.671367 -402.056114) (xy 404.616829 -402.056114)
			(xy 404.562845 -402.048352) (xy 404.510515 -402.032987) (xy 404.460905 -402.01033) (xy 404.415024 -401.980844)
			(xy 404.373807 -401.945129) (xy 404.338092 -401.903912) (xy 404.308606 -401.858031) (xy 404.285949 -401.808421)
			(xy 404.270584 -401.756091) (xy 404.262822 -401.702107) (xy 404.262336 -401.674838) (xy 403.825964 -401.674838)
			(xy 403.825478 -401.702107) (xy 403.817716 -401.756091) (xy 403.802351 -401.808421) (xy 403.779694 -401.858031)
			(xy 403.750208 -401.903912) (xy 403.714493 -401.945129) (xy 403.673276 -401.980844) (xy 403.627395 -402.01033)
			(xy 403.577785 -402.032987) (xy 403.525455 -402.048352) (xy 403.471471 -402.056114) (xy 403.416933 -402.056114)
			(xy 403.362949 -402.048352) (xy 403.310619 -402.032987) (xy 403.261009 -402.01033) (xy 403.215128 -401.980844)
			(xy 403.173911 -401.945129) (xy 403.138196 -401.903912) (xy 403.10871 -401.858031) (xy 403.086053 -401.808421)
			(xy 403.070688 -401.756091) (xy 403.062926 -401.702107) (xy 403.06244 -401.674838) (xy 389.29818 -401.674838)
			(xy 389.297694 -401.702107) (xy 389.289932 -401.756091) (xy 389.274567 -401.808421) (xy 389.25191 -401.858031)
			(xy 389.222424 -401.903912) (xy 389.186709 -401.945129) (xy 389.145492 -401.980844) (xy 389.099611 -402.01033)
			(xy 389.050001 -402.032987) (xy 388.997671 -402.048352) (xy 388.943687 -402.056114) (xy 388.889149 -402.056114)
			(xy 388.835165 -402.048352) (xy 388.782835 -402.032987) (xy 388.733225 -402.01033) (xy 388.687344 -401.980844)
			(xy 388.646127 -401.945129) (xy 388.610412 -401.903912) (xy 388.580926 -401.858031) (xy 388.558269 -401.808421)
			(xy 388.542904 -401.756091) (xy 388.535142 -401.702107) (xy 388.534656 -401.674838) (xy 388.098284 -401.674838)
			(xy 388.097798 -401.702107) (xy 388.090036 -401.756091) (xy 388.074671 -401.808421) (xy 388.052014 -401.858031)
			(xy 388.022528 -401.903912) (xy 387.986813 -401.945129) (xy 387.945596 -401.980844) (xy 387.899715 -402.01033)
			(xy 387.850105 -402.032987) (xy 387.797775 -402.048352) (xy 387.743791 -402.056114) (xy 387.689253 -402.056114)
			(xy 387.635269 -402.048352) (xy 387.582939 -402.032987) (xy 387.533329 -402.01033) (xy 387.487448 -401.980844)
			(xy 387.446231 -401.945129) (xy 387.410516 -401.903912) (xy 387.38103 -401.858031) (xy 387.358373 -401.808421)
			(xy 387.343008 -401.756091) (xy 387.335246 -401.702107) (xy 387.33476 -401.674838) (xy 386.89788 -401.674838)
			(xy 386.897394 -401.702089) (xy 386.889638 -401.756037) (xy 386.874283 -401.808332) (xy 386.851641 -401.857909)
			(xy 386.822175 -401.903759) (xy 386.786484 -401.94495) (xy 386.745293 -401.980641) (xy 386.699443 -402.010107)
			(xy 386.649866 -402.032749) (xy 386.597571 -402.048104) (xy 386.543623 -402.05586) (xy 386.489121 -402.05586)
			(xy 386.435173 -402.048104) (xy 386.382878 -402.032749) (xy 386.333301 -402.010107) (xy 386.287451 -401.980641)
			(xy 386.24626 -401.94495) (xy 386.210569 -401.903759) (xy 386.181103 -401.857909) (xy 386.158461 -401.808332)
			(xy 386.143106 -401.756037) (xy 386.13535 -401.702089) (xy 386.134864 -401.674838) (xy 385.697984 -401.674838)
			(xy 385.697498 -401.702089) (xy 385.689742 -401.756037) (xy 385.674387 -401.808332) (xy 385.651745 -401.857909)
			(xy 385.622279 -401.903759) (xy 385.586588 -401.94495) (xy 385.545397 -401.980641) (xy 385.499547 -402.010107)
			(xy 385.44997 -402.032749) (xy 385.397675 -402.048104) (xy 385.343727 -402.05586) (xy 385.289225 -402.05586)
			(xy 385.235277 -402.048104) (xy 385.182982 -402.032749) (xy 385.133405 -402.010107) (xy 385.087555 -401.980641)
			(xy 385.046364 -401.94495) (xy 385.010673 -401.903759) (xy 384.981207 -401.857909) (xy 384.958565 -401.808332)
			(xy 384.94321 -401.756037) (xy 384.935454 -401.702089) (xy 384.934968 -401.674838) (xy 384.498088 -401.674838)
			(xy 384.497602 -401.702089) (xy 384.489846 -401.756037) (xy 384.474491 -401.808332) (xy 384.451849 -401.857909)
			(xy 384.422383 -401.903759) (xy 384.386692 -401.94495) (xy 384.345501 -401.980641) (xy 384.299651 -402.010107)
			(xy 384.250074 -402.032749) (xy 384.197779 -402.048104) (xy 384.143831 -402.05586) (xy 384.089329 -402.05586)
			(xy 384.035381 -402.048104) (xy 383.983086 -402.032749) (xy 383.933509 -402.010107) (xy 383.887659 -401.980641)
			(xy 383.846468 -401.94495) (xy 383.810777 -401.903759) (xy 383.781311 -401.857909) (xy 383.758669 -401.808332)
			(xy 383.743314 -401.756037) (xy 383.735558 -401.702089) (xy 383.735072 -401.674838) (xy 383.298192 -401.674838)
			(xy 383.297706 -401.702089) (xy 383.28995 -401.756037) (xy 383.274595 -401.808332) (xy 383.251953 -401.857909)
			(xy 383.222487 -401.903759) (xy 383.186796 -401.94495) (xy 383.145605 -401.980641) (xy 383.099755 -402.010107)
			(xy 383.050178 -402.032749) (xy 382.997883 -402.048104) (xy 382.943935 -402.05586) (xy 382.889433 -402.05586)
			(xy 382.835485 -402.048104) (xy 382.78319 -402.032749) (xy 382.733613 -402.010107) (xy 382.687763 -401.980641)
			(xy 382.646572 -401.94495) (xy 382.610881 -401.903759) (xy 382.581415 -401.857909) (xy 382.558773 -401.808332)
			(xy 382.543418 -401.756037) (xy 382.535662 -401.702089) (xy 382.535176 -401.674838) (xy 382.098296 -401.674838)
			(xy 382.09781 -401.702107) (xy 382.090048 -401.756091) (xy 382.074683 -401.808421) (xy 382.052026 -401.858031)
			(xy 382.02254 -401.903912) (xy 381.986825 -401.945129) (xy 381.945608 -401.980844) (xy 381.899727 -402.01033)
			(xy 381.850117 -402.032987) (xy 381.797787 -402.048352) (xy 381.743803 -402.056114) (xy 381.689265 -402.056114)
			(xy 381.635281 -402.048352) (xy 381.582951 -402.032987) (xy 381.533341 -402.01033) (xy 381.48746 -401.980844)
			(xy 381.446243 -401.945129) (xy 381.410528 -401.903912) (xy 381.381042 -401.858031) (xy 381.358385 -401.808421)
			(xy 381.34302 -401.756091) (xy 381.335258 -401.702107) (xy 381.334772 -401.674838) (xy 380.8984 -401.674838)
			(xy 380.897914 -401.702107) (xy 380.890152 -401.756091) (xy 380.874787 -401.808421) (xy 380.85213 -401.858031)
			(xy 380.822644 -401.903912) (xy 380.786929 -401.945129) (xy 380.745712 -401.980844) (xy 380.699831 -402.01033)
			(xy 380.650221 -402.032987) (xy 380.597891 -402.048352) (xy 380.543907 -402.056114) (xy 380.489369 -402.056114)
			(xy 380.435385 -402.048352) (xy 380.383055 -402.032987) (xy 380.333445 -402.01033) (xy 380.287564 -401.980844)
			(xy 380.246347 -401.945129) (xy 380.210632 -401.903912) (xy 380.181146 -401.858031) (xy 380.158489 -401.808421)
			(xy 380.143124 -401.756091) (xy 380.135362 -401.702107) (xy 380.134876 -401.674838) (xy 379.697996 -401.674838)
			(xy 379.69751 -401.702089) (xy 379.689754 -401.756037) (xy 379.674399 -401.808332) (xy 379.651757 -401.857909)
			(xy 379.622291 -401.903759) (xy 379.5866 -401.94495) (xy 379.545409 -401.980641) (xy 379.499559 -402.010107)
			(xy 379.449982 -402.032749) (xy 379.397687 -402.048104) (xy 379.343739 -402.05586) (xy 379.289237 -402.05586)
			(xy 379.235289 -402.048104) (xy 379.182994 -402.032749) (xy 379.133417 -402.010107) (xy 379.087567 -401.980641)
			(xy 379.046376 -401.94495) (xy 379.010685 -401.903759) (xy 378.981219 -401.857909) (xy 378.958577 -401.808332)
			(xy 378.943222 -401.756037) (xy 378.935466 -401.702089) (xy 378.93498 -401.674838) (xy 378.4981 -401.674838)
			(xy 378.497614 -401.702089) (xy 378.489858 -401.756037) (xy 378.474503 -401.808332) (xy 378.451861 -401.857909)
			(xy 378.422395 -401.903759) (xy 378.386704 -401.94495) (xy 378.345513 -401.980641) (xy 378.299663 -402.010107)
			(xy 378.250086 -402.032749) (xy 378.197791 -402.048104) (xy 378.143843 -402.05586) (xy 378.089341 -402.05586)
			(xy 378.035393 -402.048104) (xy 377.983098 -402.032749) (xy 377.933521 -402.010107) (xy 377.887671 -401.980641)
			(xy 377.84648 -401.94495) (xy 377.810789 -401.903759) (xy 377.781323 -401.857909) (xy 377.758681 -401.808332)
			(xy 377.743326 -401.756037) (xy 377.73557 -401.702089) (xy 377.735084 -401.674838) (xy 377.298204 -401.674838)
			(xy 377.297718 -401.702107) (xy 377.289956 -401.756091) (xy 377.274591 -401.808421) (xy 377.251934 -401.858031)
			(xy 377.222448 -401.903912) (xy 377.186733 -401.945129) (xy 377.145516 -401.980844) (xy 377.099635 -402.01033)
			(xy 377.050025 -402.032987) (xy 376.997695 -402.048352) (xy 376.943711 -402.056114) (xy 376.889173 -402.056114)
			(xy 376.835189 -402.048352) (xy 376.782859 -402.032987) (xy 376.733249 -402.01033) (xy 376.687368 -401.980844)
			(xy 376.646151 -401.945129) (xy 376.610436 -401.903912) (xy 376.58095 -401.858031) (xy 376.558293 -401.808421)
			(xy 376.542928 -401.756091) (xy 376.535166 -401.702107) (xy 376.53468 -401.674838) (xy 376.098308 -401.674838)
			(xy 376.097822 -401.702107) (xy 376.09006 -401.756091) (xy 376.074695 -401.808421) (xy 376.052038 -401.858031)
			(xy 376.022552 -401.903912) (xy 375.986837 -401.945129) (xy 375.94562 -401.980844) (xy 375.899739 -402.01033)
			(xy 375.850129 -402.032987) (xy 375.797799 -402.048352) (xy 375.743815 -402.056114) (xy 375.689277 -402.056114)
			(xy 375.635293 -402.048352) (xy 375.582963 -402.032987) (xy 375.533353 -402.01033) (xy 375.487472 -401.980844)
			(xy 375.446255 -401.945129) (xy 375.41054 -401.903912) (xy 375.381054 -401.858031) (xy 375.358397 -401.808421)
			(xy 375.343032 -401.756091) (xy 375.33527 -401.702107) (xy 375.334784 -401.674838) (xy 374.897904 -401.674838)
			(xy 374.897418 -401.702089) (xy 374.889662 -401.756037) (xy 374.874307 -401.808332) (xy 374.851665 -401.857909)
			(xy 374.822199 -401.903759) (xy 374.786508 -401.94495) (xy 374.745317 -401.980641) (xy 374.699467 -402.010107)
			(xy 374.64989 -402.032749) (xy 374.597595 -402.048104) (xy 374.543647 -402.05586) (xy 374.489145 -402.05586)
			(xy 374.435197 -402.048104) (xy 374.382902 -402.032749) (xy 374.333325 -402.010107) (xy 374.287475 -401.980641)
			(xy 374.246284 -401.94495) (xy 374.210593 -401.903759) (xy 374.181127 -401.857909) (xy 374.158485 -401.808332)
			(xy 374.14313 -401.756037) (xy 374.135374 -401.702089) (xy 374.134888 -401.674838) (xy 373.698008 -401.674838)
			(xy 373.697522 -401.702089) (xy 373.689766 -401.756037) (xy 373.674411 -401.808332) (xy 373.651769 -401.857909)
			(xy 373.622303 -401.903759) (xy 373.586612 -401.94495) (xy 373.545421 -401.980641) (xy 373.499571 -402.010107)
			(xy 373.449994 -402.032749) (xy 373.397699 -402.048104) (xy 373.343751 -402.05586) (xy 373.289249 -402.05586)
			(xy 373.235301 -402.048104) (xy 373.183006 -402.032749) (xy 373.133429 -402.010107) (xy 373.087579 -401.980641)
			(xy 373.046388 -401.94495) (xy 373.010697 -401.903759) (xy 372.981231 -401.857909) (xy 372.958589 -401.808332)
			(xy 372.943234 -401.756037) (xy 372.935478 -401.702089) (xy 372.934992 -401.674838) (xy 372.498112 -401.674838)
			(xy 372.497626 -401.702107) (xy 372.489864 -401.756091) (xy 372.474499 -401.808421) (xy 372.451842 -401.858031)
			(xy 372.422356 -401.903912) (xy 372.386641 -401.945129) (xy 372.345424 -401.980844) (xy 372.299543 -402.01033)
			(xy 372.249933 -402.032987) (xy 372.197603 -402.048352) (xy 372.143619 -402.056114) (xy 372.089081 -402.056114)
			(xy 372.035097 -402.048352) (xy 371.982767 -402.032987) (xy 371.933157 -402.01033) (xy 371.887276 -401.980844)
			(xy 371.846059 -401.945129) (xy 371.810344 -401.903912) (xy 371.780858 -401.858031) (xy 371.758201 -401.808421)
			(xy 371.742836 -401.756091) (xy 371.735074 -401.702107) (xy 371.734588 -401.674838) (xy 371.298216 -401.674838)
			(xy 371.29773 -401.702107) (xy 371.289968 -401.756091) (xy 371.274603 -401.808421) (xy 371.251946 -401.858031)
			(xy 371.22246 -401.903912) (xy 371.186745 -401.945129) (xy 371.145528 -401.980844) (xy 371.099647 -402.01033)
			(xy 371.050037 -402.032987) (xy 370.997707 -402.048352) (xy 370.943723 -402.056114) (xy 370.889185 -402.056114)
			(xy 370.835201 -402.048352) (xy 370.782871 -402.032987) (xy 370.733261 -402.01033) (xy 370.68738 -401.980844)
			(xy 370.646163 -401.945129) (xy 370.610448 -401.903912) (xy 370.580962 -401.858031) (xy 370.558305 -401.808421)
			(xy 370.54294 -401.756091) (xy 370.535178 -401.702107) (xy 370.534692 -401.674838) (xy 354.725732 -401.674838)
			(xy 354.725246 -401.702107) (xy 354.717484 -401.756091) (xy 354.702119 -401.808421) (xy 354.679462 -401.858031)
			(xy 354.649976 -401.903912) (xy 354.614261 -401.945129) (xy 354.573044 -401.980844) (xy 354.527163 -402.01033)
			(xy 354.477553 -402.032987) (xy 354.425223 -402.048352) (xy 354.371239 -402.056114) (xy 354.316701 -402.056114)
			(xy 354.262717 -402.048352) (xy 354.210387 -402.032987) (xy 354.160777 -402.01033) (xy 354.114896 -401.980844)
			(xy 354.073679 -401.945129) (xy 354.037964 -401.903912) (xy 354.008478 -401.858031) (xy 353.985821 -401.808421)
			(xy 353.970456 -401.756091) (xy 353.962694 -401.702107) (xy 353.962208 -401.674838) (xy 353.525836 -401.674838)
			(xy 353.52535 -401.702107) (xy 353.517588 -401.756091) (xy 353.502223 -401.808421) (xy 353.479566 -401.858031)
			(xy 353.45008 -401.903912) (xy 353.414365 -401.945129) (xy 353.373148 -401.980844) (xy 353.327267 -402.01033)
			(xy 353.277657 -402.032987) (xy 353.225327 -402.048352) (xy 353.171343 -402.056114) (xy 353.116805 -402.056114)
			(xy 353.062821 -402.048352) (xy 353.010491 -402.032987) (xy 352.960881 -402.01033) (xy 352.915 -401.980844)
			(xy 352.873783 -401.945129) (xy 352.838068 -401.903912) (xy 352.808582 -401.858031) (xy 352.785925 -401.808421)
			(xy 352.77056 -401.756091) (xy 352.762798 -401.702107) (xy 352.762312 -401.674838) (xy 352.325432 -401.674838)
			(xy 352.324946 -401.702089) (xy 352.31719 -401.756037) (xy 352.301835 -401.808332) (xy 352.279193 -401.857909)
			(xy 352.249727 -401.903759) (xy 352.214036 -401.94495) (xy 352.172845 -401.980641) (xy 352.126995 -402.010107)
			(xy 352.077418 -402.032749) (xy 352.025123 -402.048104) (xy 351.971175 -402.05586) (xy 351.916673 -402.05586)
			(xy 351.862725 -402.048104) (xy 351.81043 -402.032749) (xy 351.760853 -402.010107) (xy 351.715003 -401.980641)
			(xy 351.673812 -401.94495) (xy 351.638121 -401.903759) (xy 351.608655 -401.857909) (xy 351.586013 -401.808332)
			(xy 351.570658 -401.756037) (xy 351.562902 -401.702089) (xy 351.562416 -401.674838) (xy 351.125536 -401.674838)
			(xy 351.12505 -401.702089) (xy 351.117294 -401.756037) (xy 351.101939 -401.808332) (xy 351.079297 -401.857909)
			(xy 351.049831 -401.903759) (xy 351.01414 -401.94495) (xy 350.972949 -401.980641) (xy 350.927099 -402.010107)
			(xy 350.877522 -402.032749) (xy 350.825227 -402.048104) (xy 350.771279 -402.05586) (xy 350.716777 -402.05586)
			(xy 350.662829 -402.048104) (xy 350.610534 -402.032749) (xy 350.560957 -402.010107) (xy 350.515107 -401.980641)
			(xy 350.473916 -401.94495) (xy 350.438225 -401.903759) (xy 350.408759 -401.857909) (xy 350.386117 -401.808332)
			(xy 350.370762 -401.756037) (xy 350.363006 -401.702089) (xy 350.36252 -401.674838) (xy 349.92564 -401.674838)
			(xy 349.925154 -401.702089) (xy 349.917398 -401.756037) (xy 349.902043 -401.808332) (xy 349.879401 -401.857909)
			(xy 349.849935 -401.903759) (xy 349.814244 -401.94495) (xy 349.773053 -401.980641) (xy 349.727203 -402.010107)
			(xy 349.677626 -402.032749) (xy 349.625331 -402.048104) (xy 349.571383 -402.05586) (xy 349.516881 -402.05586)
			(xy 349.462933 -402.048104) (xy 349.410638 -402.032749) (xy 349.361061 -402.010107) (xy 349.315211 -401.980641)
			(xy 349.27402 -401.94495) (xy 349.238329 -401.903759) (xy 349.208863 -401.857909) (xy 349.186221 -401.808332)
			(xy 349.170866 -401.756037) (xy 349.16311 -401.702089) (xy 349.162624 -401.674838) (xy 348.725744 -401.674838)
			(xy 348.725258 -401.702089) (xy 348.717502 -401.756037) (xy 348.702147 -401.808332) (xy 348.679505 -401.857909)
			(xy 348.650039 -401.903759) (xy 348.614348 -401.94495) (xy 348.573157 -401.980641) (xy 348.527307 -402.010107)
			(xy 348.47773 -402.032749) (xy 348.425435 -402.048104) (xy 348.371487 -402.05586) (xy 348.316985 -402.05586)
			(xy 348.263037 -402.048104) (xy 348.210742 -402.032749) (xy 348.161165 -402.010107) (xy 348.115315 -401.980641)
			(xy 348.074124 -401.94495) (xy 348.038433 -401.903759) (xy 348.008967 -401.857909) (xy 347.986325 -401.808332)
			(xy 347.97097 -401.756037) (xy 347.963214 -401.702089) (xy 347.962728 -401.674838) (xy 347.525848 -401.674838)
			(xy 347.525362 -401.702107) (xy 347.5176 -401.756091) (xy 347.502235 -401.808421) (xy 347.479578 -401.858031)
			(xy 347.450092 -401.903912) (xy 347.414377 -401.945129) (xy 347.37316 -401.980844) (xy 347.327279 -402.01033)
			(xy 347.277669 -402.032987) (xy 347.225339 -402.048352) (xy 347.171355 -402.056114) (xy 347.116817 -402.056114)
			(xy 347.062833 -402.048352) (xy 347.010503 -402.032987) (xy 346.960893 -402.01033) (xy 346.915012 -401.980844)
			(xy 346.873795 -401.945129) (xy 346.83808 -401.903912) (xy 346.808594 -401.858031) (xy 346.785937 -401.808421)
			(xy 346.770572 -401.756091) (xy 346.76281 -401.702107) (xy 346.762324 -401.674838) (xy 346.325952 -401.674838)
			(xy 346.325466 -401.702107) (xy 346.317704 -401.756091) (xy 346.302339 -401.808421) (xy 346.279682 -401.858031)
			(xy 346.250196 -401.903912) (xy 346.214481 -401.945129) (xy 346.173264 -401.980844) (xy 346.127383 -402.01033)
			(xy 346.077773 -402.032987) (xy 346.025443 -402.048352) (xy 345.971459 -402.056114) (xy 345.916921 -402.056114)
			(xy 345.862937 -402.048352) (xy 345.810607 -402.032987) (xy 345.760997 -402.01033) (xy 345.715116 -401.980844)
			(xy 345.673899 -401.945129) (xy 345.638184 -401.903912) (xy 345.608698 -401.858031) (xy 345.586041 -401.808421)
			(xy 345.570676 -401.756091) (xy 345.562914 -401.702107) (xy 345.562428 -401.674838) (xy 345.125548 -401.674838)
			(xy 345.125062 -401.702089) (xy 345.117306 -401.756037) (xy 345.101951 -401.808332) (xy 345.079309 -401.857909)
			(xy 345.049843 -401.903759) (xy 345.014152 -401.94495) (xy 344.972961 -401.980641) (xy 344.927111 -402.010107)
			(xy 344.877534 -402.032749) (xy 344.825239 -402.048104) (xy 344.771291 -402.05586) (xy 344.716789 -402.05586)
			(xy 344.662841 -402.048104) (xy 344.610546 -402.032749) (xy 344.560969 -402.010107) (xy 344.515119 -401.980641)
			(xy 344.473928 -401.94495) (xy 344.438237 -401.903759) (xy 344.408771 -401.857909) (xy 344.386129 -401.808332)
			(xy 344.370774 -401.756037) (xy 344.363018 -401.702089) (xy 344.362532 -401.674838) (xy 343.925652 -401.674838)
			(xy 343.925166 -401.702089) (xy 343.91741 -401.756037) (xy 343.902055 -401.808332) (xy 343.879413 -401.857909)
			(xy 343.849947 -401.903759) (xy 343.814256 -401.94495) (xy 343.773065 -401.980641) (xy 343.727215 -402.010107)
			(xy 343.677638 -402.032749) (xy 343.625343 -402.048104) (xy 343.571395 -402.05586) (xy 343.516893 -402.05586)
			(xy 343.462945 -402.048104) (xy 343.41065 -402.032749) (xy 343.361073 -402.010107) (xy 343.315223 -401.980641)
			(xy 343.274032 -401.94495) (xy 343.238341 -401.903759) (xy 343.208875 -401.857909) (xy 343.186233 -401.808332)
			(xy 343.170878 -401.756037) (xy 343.163122 -401.702089) (xy 343.162636 -401.674838) (xy 342.725756 -401.674838)
			(xy 342.72527 -401.702107) (xy 342.717508 -401.756091) (xy 342.702143 -401.808421) (xy 342.679486 -401.858031)
			(xy 342.65 -401.903912) (xy 342.614285 -401.945129) (xy 342.573068 -401.980844) (xy 342.527187 -402.01033)
			(xy 342.477577 -402.032987) (xy 342.425247 -402.048352) (xy 342.371263 -402.056114) (xy 342.316725 -402.056114)
			(xy 342.262741 -402.048352) (xy 342.210411 -402.032987) (xy 342.160801 -402.01033) (xy 342.11492 -401.980844)
			(xy 342.073703 -401.945129) (xy 342.037988 -401.903912) (xy 342.008502 -401.858031) (xy 341.985845 -401.808421)
			(xy 341.97048 -401.756091) (xy 341.962718 -401.702107) (xy 341.962232 -401.674838) (xy 341.52586 -401.674838)
			(xy 341.525374 -401.702107) (xy 341.517612 -401.756091) (xy 341.502247 -401.808421) (xy 341.47959 -401.858031)
			(xy 341.450104 -401.903912) (xy 341.414389 -401.945129) (xy 341.373172 -401.980844) (xy 341.327291 -402.01033)
			(xy 341.277681 -402.032987) (xy 341.225351 -402.048352) (xy 341.171367 -402.056114) (xy 341.116829 -402.056114)
			(xy 341.062845 -402.048352) (xy 341.010515 -402.032987) (xy 340.960905 -402.01033) (xy 340.915024 -401.980844)
			(xy 340.873807 -401.945129) (xy 340.838092 -401.903912) (xy 340.808606 -401.858031) (xy 340.785949 -401.808421)
			(xy 340.770584 -401.756091) (xy 340.762822 -401.702107) (xy 340.762336 -401.674838) (xy 340.325456 -401.674838)
			(xy 340.32497 -401.702089) (xy 340.317214 -401.756037) (xy 340.301859 -401.808332) (xy 340.279217 -401.857909)
			(xy 340.249751 -401.903759) (xy 340.21406 -401.94495) (xy 340.172869 -401.980641) (xy 340.127019 -402.010107)
			(xy 340.077442 -402.032749) (xy 340.025147 -402.048104) (xy 339.971199 -402.05586) (xy 339.916697 -402.05586)
			(xy 339.862749 -402.048104) (xy 339.810454 -402.032749) (xy 339.760877 -402.010107) (xy 339.715027 -401.980641)
			(xy 339.673836 -401.94495) (xy 339.638145 -401.903759) (xy 339.608679 -401.857909) (xy 339.586037 -401.808332)
			(xy 339.570682 -401.756037) (xy 339.562926 -401.702089) (xy 339.56244 -401.674838) (xy 339.12556 -401.674838)
			(xy 339.125074 -401.702089) (xy 339.117318 -401.756037) (xy 339.101963 -401.808332) (xy 339.079321 -401.857909)
			(xy 339.049855 -401.903759) (xy 339.014164 -401.94495) (xy 338.972973 -401.980641) (xy 338.927123 -402.010107)
			(xy 338.877546 -402.032749) (xy 338.825251 -402.048104) (xy 338.771303 -402.05586) (xy 338.716801 -402.05586)
			(xy 338.662853 -402.048104) (xy 338.610558 -402.032749) (xy 338.560981 -402.010107) (xy 338.515131 -401.980641)
			(xy 338.47394 -401.94495) (xy 338.438249 -401.903759) (xy 338.408783 -401.857909) (xy 338.386141 -401.808332)
			(xy 338.370786 -401.756037) (xy 338.36303 -401.702089) (xy 338.362544 -401.674838) (xy 337.925664 -401.674838)
			(xy 337.925178 -401.702107) (xy 337.917416 -401.756091) (xy 337.902051 -401.808421) (xy 337.879394 -401.858031)
			(xy 337.849908 -401.903912) (xy 337.814193 -401.945129) (xy 337.772976 -401.980844) (xy 337.727095 -402.01033)
			(xy 337.677485 -402.032987) (xy 337.625155 -402.048352) (xy 337.571171 -402.056114) (xy 337.516633 -402.056114)
			(xy 337.462649 -402.048352) (xy 337.410319 -402.032987) (xy 337.360709 -402.01033) (xy 337.314828 -401.980844)
			(xy 337.273611 -401.945129) (xy 337.237896 -401.903912) (xy 337.20841 -401.858031) (xy 337.185753 -401.808421)
			(xy 337.170388 -401.756091) (xy 337.162626 -401.702107) (xy 337.16214 -401.674838) (xy 336.725768 -401.674838)
			(xy 336.725282 -401.702107) (xy 336.71752 -401.756091) (xy 336.702155 -401.808421) (xy 336.679498 -401.858031)
			(xy 336.650012 -401.903912) (xy 336.614297 -401.945129) (xy 336.57308 -401.980844) (xy 336.527199 -402.01033)
			(xy 336.477589 -402.032987) (xy 336.425259 -402.048352) (xy 336.371275 -402.056114) (xy 336.316737 -402.056114)
			(xy 336.262753 -402.048352) (xy 336.210423 -402.032987) (xy 336.160813 -402.01033) (xy 336.114932 -401.980844)
			(xy 336.073715 -401.945129) (xy 336.038 -401.903912) (xy 336.008514 -401.858031) (xy 335.985857 -401.808421)
			(xy 335.970492 -401.756091) (xy 335.96273 -401.702107) (xy 335.962244 -401.674838) (xy 322.197984 -401.674838)
			(xy 322.197498 -401.702107) (xy 322.189736 -401.756091) (xy 322.174371 -401.808421) (xy 322.151714 -401.858031)
			(xy 322.122228 -401.903912) (xy 322.086513 -401.945129) (xy 322.045296 -401.980844) (xy 321.999415 -402.01033)
			(xy 321.949805 -402.032987) (xy 321.897475 -402.048352) (xy 321.843491 -402.056114) (xy 321.788953 -402.056114)
			(xy 321.734969 -402.048352) (xy 321.682639 -402.032987) (xy 321.633029 -402.01033) (xy 321.587148 -401.980844)
			(xy 321.545931 -401.945129) (xy 321.510216 -401.903912) (xy 321.48073 -401.858031) (xy 321.458073 -401.808421)
			(xy 321.442708 -401.756091) (xy 321.434946 -401.702107) (xy 321.43446 -401.674838) (xy 320.998088 -401.674838)
			(xy 320.997602 -401.702107) (xy 320.98984 -401.756091) (xy 320.974475 -401.808421) (xy 320.951818 -401.858031)
			(xy 320.922332 -401.903912) (xy 320.886617 -401.945129) (xy 320.8454 -401.980844) (xy 320.799519 -402.01033)
			(xy 320.749909 -402.032987) (xy 320.697579 -402.048352) (xy 320.643595 -402.056114) (xy 320.589057 -402.056114)
			(xy 320.535073 -402.048352) (xy 320.482743 -402.032987) (xy 320.433133 -402.01033) (xy 320.387252 -401.980844)
			(xy 320.346035 -401.945129) (xy 320.31032 -401.903912) (xy 320.280834 -401.858031) (xy 320.258177 -401.808421)
			(xy 320.242812 -401.756091) (xy 320.23505 -401.702107) (xy 320.234564 -401.674838) (xy 319.797684 -401.674838)
			(xy 319.797198 -401.702089) (xy 319.789442 -401.756037) (xy 319.774087 -401.808332) (xy 319.751445 -401.857909)
			(xy 319.721979 -401.903759) (xy 319.686288 -401.94495) (xy 319.645097 -401.980641) (xy 319.599247 -402.010107)
			(xy 319.54967 -402.032749) (xy 319.497375 -402.048104) (xy 319.443427 -402.05586) (xy 319.388925 -402.05586)
			(xy 319.334977 -402.048104) (xy 319.282682 -402.032749) (xy 319.233105 -402.010107) (xy 319.187255 -401.980641)
			(xy 319.146064 -401.94495) (xy 319.110373 -401.903759) (xy 319.080907 -401.857909) (xy 319.058265 -401.808332)
			(xy 319.04291 -401.756037) (xy 319.035154 -401.702089) (xy 319.034668 -401.674838) (xy 318.597788 -401.674838)
			(xy 318.597302 -401.702089) (xy 318.589546 -401.756037) (xy 318.574191 -401.808332) (xy 318.551549 -401.857909)
			(xy 318.522083 -401.903759) (xy 318.486392 -401.94495) (xy 318.445201 -401.980641) (xy 318.399351 -402.010107)
			(xy 318.349774 -402.032749) (xy 318.297479 -402.048104) (xy 318.243531 -402.05586) (xy 318.189029 -402.05586)
			(xy 318.135081 -402.048104) (xy 318.082786 -402.032749) (xy 318.033209 -402.010107) (xy 317.987359 -401.980641)
			(xy 317.946168 -401.94495) (xy 317.910477 -401.903759) (xy 317.881011 -401.857909) (xy 317.858369 -401.808332)
			(xy 317.843014 -401.756037) (xy 317.835258 -401.702089) (xy 317.834772 -401.674838) (xy 317.397892 -401.674838)
			(xy 317.397406 -401.702089) (xy 317.38965 -401.756037) (xy 317.374295 -401.808332) (xy 317.351653 -401.857909)
			(xy 317.322187 -401.903759) (xy 317.286496 -401.94495) (xy 317.245305 -401.980641) (xy 317.199455 -402.010107)
			(xy 317.149878 -402.032749) (xy 317.097583 -402.048104) (xy 317.043635 -402.05586) (xy 316.989133 -402.05586)
			(xy 316.935185 -402.048104) (xy 316.88289 -402.032749) (xy 316.833313 -402.010107) (xy 316.787463 -401.980641)
			(xy 316.746272 -401.94495) (xy 316.710581 -401.903759) (xy 316.681115 -401.857909) (xy 316.658473 -401.808332)
			(xy 316.643118 -401.756037) (xy 316.635362 -401.702089) (xy 316.634876 -401.674838) (xy 316.197996 -401.674838)
			(xy 316.19751 -401.702089) (xy 316.189754 -401.756037) (xy 316.174399 -401.808332) (xy 316.151757 -401.857909)
			(xy 316.122291 -401.903759) (xy 316.0866 -401.94495) (xy 316.045409 -401.980641) (xy 315.999559 -402.010107)
			(xy 315.949982 -402.032749) (xy 315.897687 -402.048104) (xy 315.843739 -402.05586) (xy 315.789237 -402.05586)
			(xy 315.735289 -402.048104) (xy 315.682994 -402.032749) (xy 315.633417 -402.010107) (xy 315.587567 -401.980641)
			(xy 315.546376 -401.94495) (xy 315.510685 -401.903759) (xy 315.481219 -401.857909) (xy 315.458577 -401.808332)
			(xy 315.443222 -401.756037) (xy 315.435466 -401.702089) (xy 315.43498 -401.674838) (xy 314.9981 -401.674838)
			(xy 314.997614 -401.702107) (xy 314.989852 -401.756091) (xy 314.974487 -401.808421) (xy 314.95183 -401.858031)
			(xy 314.922344 -401.903912) (xy 314.886629 -401.945129) (xy 314.845412 -401.980844) (xy 314.799531 -402.01033)
			(xy 314.749921 -402.032987) (xy 314.697591 -402.048352) (xy 314.643607 -402.056114) (xy 314.589069 -402.056114)
			(xy 314.535085 -402.048352) (xy 314.482755 -402.032987) (xy 314.433145 -402.01033) (xy 314.387264 -401.980844)
			(xy 314.346047 -401.945129) (xy 314.310332 -401.903912) (xy 314.280846 -401.858031) (xy 314.258189 -401.808421)
			(xy 314.242824 -401.756091) (xy 314.235062 -401.702107) (xy 314.234576 -401.674838) (xy 313.798204 -401.674838)
			(xy 313.797718 -401.702107) (xy 313.789956 -401.756091) (xy 313.774591 -401.808421) (xy 313.751934 -401.858031)
			(xy 313.722448 -401.903912) (xy 313.686733 -401.945129) (xy 313.645516 -401.980844) (xy 313.599635 -402.01033)
			(xy 313.550025 -402.032987) (xy 313.497695 -402.048352) (xy 313.443711 -402.056114) (xy 313.389173 -402.056114)
			(xy 313.335189 -402.048352) (xy 313.282859 -402.032987) (xy 313.233249 -402.01033) (xy 313.187368 -401.980844)
			(xy 313.146151 -401.945129) (xy 313.110436 -401.903912) (xy 313.08095 -401.858031) (xy 313.058293 -401.808421)
			(xy 313.042928 -401.756091) (xy 313.035166 -401.702107) (xy 313.03468 -401.674838) (xy 312.5978 -401.674838)
			(xy 312.597314 -401.702089) (xy 312.589558 -401.756037) (xy 312.574203 -401.808332) (xy 312.551561 -401.857909)
			(xy 312.522095 -401.903759) (xy 312.486404 -401.94495) (xy 312.445213 -401.980641) (xy 312.399363 -402.010107)
			(xy 312.349786 -402.032749) (xy 312.297491 -402.048104) (xy 312.243543 -402.05586) (xy 312.189041 -402.05586)
			(xy 312.135093 -402.048104) (xy 312.082798 -402.032749) (xy 312.033221 -402.010107) (xy 311.987371 -401.980641)
			(xy 311.94618 -401.94495) (xy 311.910489 -401.903759) (xy 311.881023 -401.857909) (xy 311.858381 -401.808332)
			(xy 311.843026 -401.756037) (xy 311.83527 -401.702089) (xy 311.834784 -401.674838) (xy 311.397904 -401.674838)
			(xy 311.397418 -401.702089) (xy 311.389662 -401.756037) (xy 311.374307 -401.808332) (xy 311.351665 -401.857909)
			(xy 311.322199 -401.903759) (xy 311.286508 -401.94495) (xy 311.245317 -401.980641) (xy 311.199467 -402.010107)
			(xy 311.14989 -402.032749) (xy 311.097595 -402.048104) (xy 311.043647 -402.05586) (xy 310.989145 -402.05586)
			(xy 310.935197 -402.048104) (xy 310.882902 -402.032749) (xy 310.833325 -402.010107) (xy 310.787475 -401.980641)
			(xy 310.746284 -401.94495) (xy 310.710593 -401.903759) (xy 310.681127 -401.857909) (xy 310.658485 -401.808332)
			(xy 310.64313 -401.756037) (xy 310.635374 -401.702089) (xy 310.634888 -401.674838) (xy 310.198008 -401.674838)
			(xy 310.197522 -401.702107) (xy 310.18976 -401.756091) (xy 310.174395 -401.808421) (xy 310.151738 -401.858031)
			(xy 310.122252 -401.903912) (xy 310.086537 -401.945129) (xy 310.04532 -401.980844) (xy 309.999439 -402.01033)
			(xy 309.949829 -402.032987) (xy 309.897499 -402.048352) (xy 309.843515 -402.056114) (xy 309.788977 -402.056114)
			(xy 309.734993 -402.048352) (xy 309.682663 -402.032987) (xy 309.633053 -402.01033) (xy 309.587172 -401.980844)
			(xy 309.545955 -401.945129) (xy 309.51024 -401.903912) (xy 309.480754 -401.858031) (xy 309.458097 -401.808421)
			(xy 309.442732 -401.756091) (xy 309.43497 -401.702107) (xy 309.434484 -401.674838) (xy 308.998112 -401.674838)
			(xy 308.997626 -401.702107) (xy 308.989864 -401.756091) (xy 308.974499 -401.808421) (xy 308.951842 -401.858031)
			(xy 308.922356 -401.903912) (xy 308.886641 -401.945129) (xy 308.845424 -401.980844) (xy 308.799543 -402.01033)
			(xy 308.749933 -402.032987) (xy 308.697603 -402.048352) (xy 308.643619 -402.056114) (xy 308.589081 -402.056114)
			(xy 308.535097 -402.048352) (xy 308.482767 -402.032987) (xy 308.433157 -402.01033) (xy 308.387276 -401.980844)
			(xy 308.346059 -401.945129) (xy 308.310344 -401.903912) (xy 308.280858 -401.858031) (xy 308.258201 -401.808421)
			(xy 308.242836 -401.756091) (xy 308.235074 -401.702107) (xy 308.234588 -401.674838) (xy 307.797708 -401.674838)
			(xy 307.797222 -401.702089) (xy 307.789466 -401.756037) (xy 307.774111 -401.808332) (xy 307.751469 -401.857909)
			(xy 307.722003 -401.903759) (xy 307.686312 -401.94495) (xy 307.645121 -401.980641) (xy 307.599271 -402.010107)
			(xy 307.549694 -402.032749) (xy 307.497399 -402.048104) (xy 307.443451 -402.05586) (xy 307.388949 -402.05586)
			(xy 307.335001 -402.048104) (xy 307.282706 -402.032749) (xy 307.233129 -402.010107) (xy 307.187279 -401.980641)
			(xy 307.146088 -401.94495) (xy 307.110397 -401.903759) (xy 307.080931 -401.857909) (xy 307.058289 -401.808332)
			(xy 307.042934 -401.756037) (xy 307.035178 -401.702089) (xy 307.034692 -401.674838) (xy 306.597812 -401.674838)
			(xy 306.597326 -401.702089) (xy 306.58957 -401.756037) (xy 306.574215 -401.808332) (xy 306.551573 -401.857909)
			(xy 306.522107 -401.903759) (xy 306.486416 -401.94495) (xy 306.445225 -401.980641) (xy 306.399375 -402.010107)
			(xy 306.349798 -402.032749) (xy 306.297503 -402.048104) (xy 306.243555 -402.05586) (xy 306.189053 -402.05586)
			(xy 306.135105 -402.048104) (xy 306.08281 -402.032749) (xy 306.033233 -402.010107) (xy 305.987383 -401.980641)
			(xy 305.946192 -401.94495) (xy 305.910501 -401.903759) (xy 305.881035 -401.857909) (xy 305.858393 -401.808332)
			(xy 305.843038 -401.756037) (xy 305.835282 -401.702089) (xy 305.834796 -401.674838) (xy 305.397916 -401.674838)
			(xy 305.39743 -401.702107) (xy 305.389668 -401.756091) (xy 305.374303 -401.808421) (xy 305.351646 -401.858031)
			(xy 305.32216 -401.903912) (xy 305.286445 -401.945129) (xy 305.245228 -401.980844) (xy 305.199347 -402.01033)
			(xy 305.149737 -402.032987) (xy 305.097407 -402.048352) (xy 305.043423 -402.056114) (xy 304.988885 -402.056114)
			(xy 304.934901 -402.048352) (xy 304.882571 -402.032987) (xy 304.832961 -402.01033) (xy 304.78708 -401.980844)
			(xy 304.745863 -401.945129) (xy 304.710148 -401.903912) (xy 304.680662 -401.858031) (xy 304.658005 -401.808421)
			(xy 304.64264 -401.756091) (xy 304.634878 -401.702107) (xy 304.634392 -401.674838) (xy 304.19802 -401.674838)
			(xy 304.197534 -401.702107) (xy 304.189772 -401.756091) (xy 304.174407 -401.808421) (xy 304.15175 -401.858031)
			(xy 304.122264 -401.903912) (xy 304.086549 -401.945129) (xy 304.045332 -401.980844) (xy 303.999451 -402.01033)
			(xy 303.949841 -402.032987) (xy 303.897511 -402.048352) (xy 303.843527 -402.056114) (xy 303.788989 -402.056114)
			(xy 303.735005 -402.048352) (xy 303.682675 -402.032987) (xy 303.633065 -402.01033) (xy 303.587184 -401.980844)
			(xy 303.545967 -401.945129) (xy 303.510252 -401.903912) (xy 303.480766 -401.858031) (xy 303.458109 -401.808421)
			(xy 303.442744 -401.756091) (xy 303.434982 -401.702107) (xy 303.434496 -401.674838) (xy 296.287698 -401.674838)
			(xy 296.287698 -408.915108) (xy 296.288284 -408.926869) (xy 296.298731 -408.947942) (xy 296.307764 -408.955494)
			(xy 296.381678 -409.011628) (xy 296.404792 -409.0162) (xy 296.416476 -409.012898) (xy 296.510172 -408.987549)
			(xy 296.699411 -408.94427) (xy 296.890404 -408.909537) (xy 297.082765 -408.883422) (xy 297.276105 -408.865976)
			(xy 297.470033 -408.857236) (xy 297.567096 -408.856688) (xy 297.567604 -408.856688) (xy 297.660521 -408.857188)
			(xy 297.846184 -408.865183) (xy 298.031331 -408.881158) (xy 298.21562 -408.905085) (xy 298.398708 -408.936917)
			(xy 298.580257 -408.976597) (xy 298.759931 -409.02405) (xy 298.937397 -409.07919) (xy 299.112327 -409.141914)
			(xy 299.284396 -409.212105) (xy 299.453286 -409.289635) (xy 299.618684 -409.374358) (xy 299.780284 -409.466119)
			(xy 299.937787 -409.564747) (xy 300.090901 -409.67006) (xy 300.239342 -409.781863) (xy 300.382835 -409.899949)
			(xy 300.521116 -410.024098) (xy 300.653927 -410.154082) (xy 300.781023 -410.28966) (xy 300.902169 -410.430579)
			(xy 301.017139 -410.576581) (xy 301.125722 -410.727393) (xy 301.227716 -410.882737) (xy 301.322933 -411.042326)
			(xy 301.411195 -411.205863) (xy 301.49234 -411.373045) (xy 301.566218 -411.543565) (xy 301.63269 -411.717104)
			(xy 301.691636 -411.893343) (xy 301.742944 -412.071954) (xy 301.786521 -412.252608) (xy 301.822285 -412.434969)
			(xy 301.85017 -412.6187) (xy 301.870126 -412.80346) (xy 301.87467 -412.873752) (xy 303.412875 -412.873752)
			(xy 303.412875 -412.819248) (xy 303.420632 -412.7653) (xy 303.435988 -412.713004) (xy 303.458629 -412.663426)
			(xy 303.488096 -412.617575) (xy 303.523789 -412.576384) (xy 303.56498 -412.540693) (xy 303.610831 -412.511226)
			(xy 303.66041 -412.488585) (xy 303.712706 -412.473231) (xy 303.766654 -412.465475) (xy 303.793906 -412.465012)
			(xy 304.657506 -412.465012) (xy 304.684758 -412.465458) (xy 304.738708 -412.473216) (xy 304.791005 -412.488572)
			(xy 304.840584 -412.511215) (xy 304.886436 -412.540683) (xy 304.927628 -412.576376) (xy 304.963321 -412.617569)
			(xy 304.992788 -412.663421) (xy 305.01543 -412.713001) (xy 305.030785 -412.765298) (xy 305.038542 -412.819248)
			(xy 305.038542 -412.873752) (xy 305.038542 -412.873754) (xy 306.476075 -412.873754) (xy 306.476075 -412.819246)
			(xy 306.483833 -412.765294) (xy 306.499191 -412.712996) (xy 306.521835 -412.663415) (xy 306.551306 -412.617562)
			(xy 306.587003 -412.57637) (xy 306.628199 -412.540679) (xy 306.674055 -412.511213) (xy 306.723639 -412.488575)
			(xy 306.775939 -412.473223) (xy 306.829892 -412.465472) (xy 306.857146 -412.465012) (xy 307.720746 -412.465012)
			(xy 307.747997 -412.465461) (xy 307.801942 -412.473223) (xy 307.854234 -412.488583) (xy 307.903808 -412.511228)
			(xy 307.949655 -412.540697) (xy 307.990842 -412.576391) (xy 308.02653 -412.617582) (xy 308.055994 -412.663432)
			(xy 308.078633 -412.713009) (xy 308.093987 -412.765303) (xy 308.101742 -412.819249) (xy 308.101742 -412.873749)
			(xy 309.539398 -412.873749) (xy 309.539398 -412.819251) (xy 309.547154 -412.765307) (xy 309.562508 -412.713016)
			(xy 309.585146 -412.663443) (xy 309.61461 -412.617596) (xy 309.650298 -412.576408) (xy 309.691484 -412.540718)
			(xy 309.73733 -412.511253) (xy 309.786903 -412.488612) (xy 309.839194 -412.473257) (xy 309.893137 -412.465499)
			(xy 309.920386 -412.465012) (xy 310.783986 -412.465012) (xy 310.811241 -412.465434) (xy 310.865196 -412.47319)
			(xy 310.917499 -412.488545) (xy 310.967083 -412.511188) (xy 311.012941 -412.540657) (xy 311.054137 -412.576353)
			(xy 311.089834 -412.617548) (xy 311.119305 -412.663405) (xy 311.14195 -412.712988) (xy 311.157307 -412.76529)
			(xy 311.165065 -412.819245) (xy 311.165065 -412.873753) (xy 312.602575 -412.873753) (xy 312.602575 -412.819247)
			(xy 312.610333 -412.765297) (xy 312.625689 -412.713) (xy 312.648332 -412.663421) (xy 312.677801 -412.617569)
			(xy 312.713496 -412.576377) (xy 312.754689 -412.540686) (xy 312.800543 -412.51122) (xy 312.850124 -412.48858)
			(xy 312.902422 -412.473227) (xy 312.956373 -412.465474) (xy 312.983626 -412.465012) (xy 313.847226 -412.465012)
			(xy 313.874477 -412.46546) (xy 313.928425 -412.47322) (xy 313.98072 -412.488578) (xy 314.030296 -412.511222)
			(xy 314.076146 -412.54069) (xy 314.117335 -412.576383) (xy 314.153026 -412.617575) (xy 314.182491 -412.663427)
			(xy 314.205131 -412.713005) (xy 314.220486 -412.7653) (xy 314.228242 -412.819249) (xy 314.228242 -412.873748)
			(xy 315.665898 -412.873748) (xy 315.665898 -412.819252) (xy 315.673653 -412.76531) (xy 315.689006 -412.713021)
			(xy 315.711643 -412.663448) (xy 315.741105 -412.617602) (xy 315.776791 -412.576415) (xy 315.817975 -412.540725)
			(xy 315.863818 -412.51126) (xy 315.913389 -412.488618) (xy 315.965677 -412.473261) (xy 316.019618 -412.465501)
			(xy 316.046866 -412.465012) (xy 316.910466 -412.465012) (xy 316.937722 -412.465433) (xy 316.991679 -412.473186)
			(xy 317.043984 -412.48854) (xy 317.093571 -412.511182) (xy 317.139431 -412.54065) (xy 317.18063 -412.576346)
			(xy 317.216329 -412.617542) (xy 317.245802 -412.663399) (xy 317.268448 -412.712984) (xy 317.283807 -412.765287)
			(xy 317.291565 -412.819244) (xy 317.291565 -412.873752) (xy 318.729075 -412.873752) (xy 318.729075 -412.819248)
			(xy 318.736832 -412.7653) (xy 318.752188 -412.713004) (xy 318.774829 -412.663426) (xy 318.804296 -412.617575)
			(xy 318.839989 -412.576384) (xy 318.88118 -412.540693) (xy 318.927031 -412.511226) (xy 318.97661 -412.488585)
			(xy 319.028906 -412.473231) (xy 319.082854 -412.465475) (xy 319.110106 -412.465012) (xy 319.973706 -412.465012)
			(xy 320.000958 -412.465458) (xy 320.054908 -412.473216) (xy 320.107205 -412.488572) (xy 320.156784 -412.511215)
			(xy 320.202636 -412.540683) (xy 320.243828 -412.576376) (xy 320.279521 -412.617569) (xy 320.308988 -412.663421)
			(xy 320.33163 -412.713001) (xy 320.346985 -412.765298) (xy 320.354742 -412.819248) (xy 320.354742 -412.873752)
			(xy 320.354742 -412.873754) (xy 321.792275 -412.873754) (xy 321.792275 -412.819246) (xy 321.800033 -412.765294)
			(xy 321.815391 -412.712996) (xy 321.838035 -412.663415) (xy 321.867506 -412.617562) (xy 321.903203 -412.57637)
			(xy 321.944399 -412.540679) (xy 321.990255 -412.511213) (xy 322.039839 -412.488575) (xy 322.092139 -412.473223)
			(xy 322.146092 -412.465472) (xy 322.173346 -412.465012) (xy 323.036946 -412.465012) (xy 323.064197 -412.465461)
			(xy 323.118142 -412.473223) (xy 323.170434 -412.488583) (xy 323.220008 -412.511228) (xy 323.265855 -412.540697)
			(xy 323.307042 -412.576391) (xy 323.34273 -412.617582) (xy 323.372194 -412.663432) (xy 323.394833 -412.713009)
			(xy 323.410187 -412.765303) (xy 323.417942 -412.819249) (xy 323.417942 -412.873749) (xy 324.855598 -412.873749)
			(xy 324.855598 -412.819251) (xy 324.863354 -412.765307) (xy 324.878708 -412.713016) (xy 324.901346 -412.663443)
			(xy 324.93081 -412.617596) (xy 324.966498 -412.576408) (xy 325.007684 -412.540718) (xy 325.05353 -412.511253)
			(xy 325.103103 -412.488612) (xy 325.155394 -412.473257) (xy 325.209337 -412.465499) (xy 325.236586 -412.465012)
			(xy 326.100186 -412.465012) (xy 326.127441 -412.465434) (xy 326.181396 -412.47319) (xy 326.233699 -412.488545)
			(xy 326.283283 -412.511188) (xy 326.329141 -412.540657) (xy 326.370337 -412.576353) (xy 326.406034 -412.617548)
			(xy 326.435505 -412.663405) (xy 326.45815 -412.712988) (xy 326.473507 -412.76529) (xy 326.481265 -412.819245)
			(xy 326.481265 -412.873753) (xy 327.918775 -412.873753) (xy 327.918775 -412.819247) (xy 327.926533 -412.765297)
			(xy 327.941889 -412.713) (xy 327.964532 -412.663421) (xy 327.994001 -412.617569) (xy 328.029696 -412.576377)
			(xy 328.070889 -412.540686) (xy 328.116743 -412.51122) (xy 328.166324 -412.48858) (xy 328.218622 -412.473227)
			(xy 328.272573 -412.465474) (xy 328.299826 -412.465012) (xy 329.163426 -412.465012) (xy 329.190677 -412.46546)
			(xy 329.244625 -412.47322) (xy 329.29692 -412.488578) (xy 329.346496 -412.511222) (xy 329.392346 -412.54069)
			(xy 329.433535 -412.576383) (xy 329.469226 -412.617575) (xy 329.498691 -412.663427) (xy 329.521331 -412.713005)
			(xy 329.536686 -412.7653) (xy 329.544442 -412.819249) (xy 329.544442 -412.873748) (xy 330.982098 -412.873748)
			(xy 330.982098 -412.819252) (xy 330.989853 -412.76531) (xy 331.005206 -412.713021) (xy 331.027843 -412.663448)
			(xy 331.057305 -412.617602) (xy 331.092991 -412.576415) (xy 331.134175 -412.540725) (xy 331.180018 -412.51126)
			(xy 331.229589 -412.488618) (xy 331.281877 -412.473261) (xy 331.335818 -412.465501) (xy 331.363066 -412.465012)
			(xy 332.226666 -412.465012) (xy 332.253922 -412.465433) (xy 332.307879 -412.473186) (xy 332.360184 -412.48854)
			(xy 332.409771 -412.511182) (xy 332.455631 -412.54065) (xy 332.49683 -412.576346) (xy 332.532529 -412.617542)
			(xy 332.562002 -412.663399) (xy 332.584648 -412.712984) (xy 332.600007 -412.765287) (xy 332.607765 -412.819244)
			(xy 332.607765 -412.873752) (xy 334.045275 -412.873752) (xy 334.045275 -412.819248) (xy 334.053032 -412.7653)
			(xy 334.068388 -412.713004) (xy 334.091029 -412.663426) (xy 334.120496 -412.617575) (xy 334.156189 -412.576384)
			(xy 334.19738 -412.540693) (xy 334.243231 -412.511226) (xy 334.29281 -412.488585) (xy 334.345106 -412.473231)
			(xy 334.399054 -412.465475) (xy 334.426306 -412.465012) (xy 335.289906 -412.465012) (xy 335.317158 -412.465458)
			(xy 335.371108 -412.473216) (xy 335.423405 -412.488572) (xy 335.472984 -412.511215) (xy 335.518836 -412.540683)
			(xy 335.560028 -412.576376) (xy 335.595721 -412.617569) (xy 335.625188 -412.663421) (xy 335.64783 -412.713001)
			(xy 335.663185 -412.765298) (xy 335.670942 -412.819248) (xy 335.670942 -412.873752) (xy 335.670942 -412.873754)
			(xy 337.108475 -412.873754) (xy 337.108475 -412.819246) (xy 337.116233 -412.765294) (xy 337.131591 -412.712996)
			(xy 337.154235 -412.663415) (xy 337.183706 -412.617562) (xy 337.219403 -412.57637) (xy 337.260599 -412.540679)
			(xy 337.306455 -412.511213) (xy 337.356039 -412.488575) (xy 337.408339 -412.473223) (xy 337.462292 -412.465472)
			(xy 337.489546 -412.465012) (xy 338.353146 -412.465012) (xy 338.380397 -412.465461) (xy 338.434342 -412.473223)
			(xy 338.486634 -412.488583) (xy 338.536208 -412.511228) (xy 338.582055 -412.540697) (xy 338.623242 -412.576391)
			(xy 338.65893 -412.617582) (xy 338.688394 -412.663432) (xy 338.711033 -412.713009) (xy 338.726387 -412.765303)
			(xy 338.734142 -412.819249) (xy 338.734142 -412.873749) (xy 340.171798 -412.873749) (xy 340.171798 -412.819251)
			(xy 340.179554 -412.765307) (xy 340.194908 -412.713016) (xy 340.217546 -412.663443) (xy 340.24701 -412.617596)
			(xy 340.282698 -412.576408) (xy 340.323884 -412.540718) (xy 340.36973 -412.511253) (xy 340.419303 -412.488612)
			(xy 340.471594 -412.473257) (xy 340.525537 -412.465499) (xy 340.552786 -412.465012) (xy 341.416386 -412.465012)
			(xy 341.443641 -412.465434) (xy 341.497596 -412.47319) (xy 341.549899 -412.488545) (xy 341.599483 -412.511188)
			(xy 341.645341 -412.540657) (xy 341.686537 -412.576353) (xy 341.722234 -412.617548) (xy 341.751705 -412.663405)
			(xy 341.77435 -412.712988) (xy 341.789707 -412.76529) (xy 341.797465 -412.819245) (xy 341.797465 -412.873753)
			(xy 343.234975 -412.873753) (xy 343.234975 -412.819247) (xy 343.242733 -412.765297) (xy 343.258089 -412.713)
			(xy 343.280732 -412.663421) (xy 343.310201 -412.617569) (xy 343.345896 -412.576377) (xy 343.387089 -412.540686)
			(xy 343.432943 -412.51122) (xy 343.482524 -412.48858) (xy 343.534822 -412.473227) (xy 343.588773 -412.465474)
			(xy 343.616026 -412.465012) (xy 344.479626 -412.465012) (xy 344.506877 -412.46546) (xy 344.560825 -412.47322)
			(xy 344.61312 -412.488578) (xy 344.662696 -412.511222) (xy 344.708546 -412.54069) (xy 344.749735 -412.576383)
			(xy 344.785426 -412.617575) (xy 344.814891 -412.663427) (xy 344.837531 -412.713005) (xy 344.852886 -412.7653)
			(xy 344.860642 -412.819249) (xy 344.860642 -412.873748) (xy 346.298298 -412.873748) (xy 346.298298 -412.819252)
			(xy 346.306053 -412.76531) (xy 346.321406 -412.713021) (xy 346.344043 -412.663448) (xy 346.373505 -412.617602)
			(xy 346.409191 -412.576415) (xy 346.450375 -412.540725) (xy 346.496218 -412.51126) (xy 346.545789 -412.488618)
			(xy 346.598077 -412.473261) (xy 346.652018 -412.465501) (xy 346.679266 -412.465012) (xy 347.542866 -412.465012)
			(xy 347.570122 -412.465433) (xy 347.624079 -412.473186) (xy 347.676384 -412.48854) (xy 347.725971 -412.511182)
			(xy 347.771831 -412.54065) (xy 347.81303 -412.576346) (xy 347.848729 -412.617542) (xy 347.878202 -412.663399)
			(xy 347.900848 -412.712984) (xy 347.916207 -412.765287) (xy 347.923965 -412.819244) (xy 347.923965 -412.873752)
			(xy 349.361475 -412.873752) (xy 349.361475 -412.819248) (xy 349.369232 -412.7653) (xy 349.384588 -412.713004)
			(xy 349.407229 -412.663426) (xy 349.436696 -412.617575) (xy 349.472389 -412.576384) (xy 349.51358 -412.540693)
			(xy 349.559431 -412.511226) (xy 349.60901 -412.488585) (xy 349.661306 -412.473231) (xy 349.715254 -412.465475)
			(xy 349.742506 -412.465012) (xy 350.606106 -412.465012) (xy 350.633358 -412.465458) (xy 350.687308 -412.473216)
			(xy 350.739605 -412.488572) (xy 350.789184 -412.511215) (xy 350.835036 -412.540683) (xy 350.876228 -412.576376)
			(xy 350.911921 -412.617569) (xy 350.941388 -412.663421) (xy 350.96403 -412.713001) (xy 350.979385 -412.765298)
			(xy 350.987142 -412.819248) (xy 350.987142 -412.873752) (xy 370.513075 -412.873752) (xy 370.513075 -412.819248)
			(xy 370.520832 -412.7653) (xy 370.536187 -412.713005) (xy 370.558829 -412.663427) (xy 370.588295 -412.617576)
			(xy 370.623987 -412.576386) (xy 370.665178 -412.540694) (xy 370.711029 -412.511228) (xy 370.760607 -412.488587)
			(xy 370.812902 -412.473231) (xy 370.86685 -412.465475) (xy 370.894102 -412.465012) (xy 371.757702 -412.465012)
			(xy 371.784955 -412.465458) (xy 371.838905 -412.473215) (xy 371.891202 -412.488571) (xy 371.940782 -412.511214)
			(xy 371.986634 -412.540682) (xy 372.027826 -412.576375) (xy 372.06352 -412.617567) (xy 372.092987 -412.66342)
			(xy 372.115629 -412.713) (xy 372.130985 -412.765297) (xy 372.138742 -412.819247) (xy 372.138742 -412.873753)
			(xy 373.576275 -412.873753) (xy 373.576275 -412.819247) (xy 373.584033 -412.765295) (xy 373.59939 -412.712996)
			(xy 373.622035 -412.663416) (xy 373.651505 -412.617563) (xy 373.687201 -412.576372) (xy 373.728397 -412.54068)
			(xy 373.774253 -412.511215) (xy 373.823836 -412.488576) (xy 373.876136 -412.473224) (xy 373.930089 -412.465472)
			(xy 373.957342 -412.465012) (xy 374.820942 -412.465012) (xy 374.848193 -412.465461) (xy 374.902139 -412.473222)
			(xy 374.954431 -412.488582) (xy 375.004006 -412.511227) (xy 375.049853 -412.540696) (xy 375.091041 -412.576389)
			(xy 375.126729 -412.61758) (xy 375.156193 -412.663431) (xy 375.178833 -412.713008) (xy 375.194186 -412.765302)
			(xy 375.201942 -412.819249) (xy 375.201942 -412.873749) (xy 376.639598 -412.873749) (xy 376.639598 -412.819251)
			(xy 376.647354 -412.765308) (xy 376.662707 -412.713017) (xy 376.685346 -412.663444) (xy 376.714809 -412.617597)
			(xy 376.750497 -412.576409) (xy 376.791682 -412.54072) (xy 376.837528 -412.511254) (xy 376.8871 -412.488613)
			(xy 376.93939 -412.473258) (xy 376.993333 -412.465499) (xy 377.020582 -412.465012) (xy 377.884182 -412.465012)
			(xy 377.911437 -412.465434) (xy 377.965393 -412.473189) (xy 378.017696 -412.488544) (xy 378.067281 -412.511187)
			(xy 378.113139 -412.540656) (xy 378.154336 -412.576352) (xy 378.190033 -412.617547) (xy 378.219504 -412.663403)
			(xy 378.242149 -412.712987) (xy 378.257507 -412.765289) (xy 378.265265 -412.819245) (xy 378.265265 -412.873752)
			(xy 379.702775 -412.873752) (xy 379.702775 -412.819248) (xy 379.710532 -412.765298) (xy 379.725889 -412.713001)
			(xy 379.748532 -412.663422) (xy 379.778 -412.61757) (xy 379.813694 -412.576379) (xy 379.854888 -412.540687)
			(xy 379.900741 -412.511221) (xy 379.950321 -412.488581) (xy 380.002619 -412.473228) (xy 380.05657 -412.465474)
			(xy 380.083822 -412.465012) (xy 380.947422 -412.465012) (xy 380.974674 -412.465459) (xy 381.028622 -412.473219)
			(xy 381.080917 -412.488577) (xy 381.130494 -412.51122) (xy 381.176344 -412.540689) (xy 381.217534 -412.576382)
			(xy 381.253225 -412.617574) (xy 381.28269 -412.663426) (xy 381.305331 -412.713004) (xy 381.320686 -412.7653)
			(xy 381.328442 -412.819248) (xy 381.328442 -412.873748) (xy 382.766098 -412.873748) (xy 382.766098 -412.819252)
			(xy 382.773853 -412.76531) (xy 382.789206 -412.713022) (xy 382.811843 -412.663449) (xy 382.841304 -412.617603)
			(xy 382.876989 -412.576416) (xy 382.918173 -412.540727) (xy 382.964016 -412.511261) (xy 383.013586 -412.488619)
			(xy 383.065873 -412.473261) (xy 383.119814 -412.465501) (xy 383.147062 -412.465012) (xy 384.010662 -412.465012)
			(xy 384.037918 -412.465432) (xy 384.091876 -412.473185) (xy 384.144181 -412.488539) (xy 384.193769 -412.51118)
			(xy 384.239629 -412.540649) (xy 384.280829 -412.576345) (xy 384.316528 -412.61754) (xy 384.346001 -412.663398)
			(xy 384.368648 -412.712983) (xy 384.384007 -412.765287) (xy 384.391765 -412.819244) (xy 384.391765 -412.873752)
			(xy 385.829275 -412.873752) (xy 385.829275 -412.819248) (xy 385.837032 -412.7653) (xy 385.852387 -412.713005)
			(xy 385.875029 -412.663427) (xy 385.904495 -412.617576) (xy 385.940187 -412.576386) (xy 385.981378 -412.540694)
			(xy 386.027229 -412.511228) (xy 386.076807 -412.488587) (xy 386.129102 -412.473231) (xy 386.18305 -412.465475)
			(xy 386.210302 -412.465012) (xy 387.073902 -412.465012) (xy 387.101155 -412.465458) (xy 387.155105 -412.473215)
			(xy 387.207402 -412.488571) (xy 387.256982 -412.511214) (xy 387.302834 -412.540682) (xy 387.344026 -412.576375)
			(xy 387.37972 -412.617567) (xy 387.409187 -412.66342) (xy 387.431829 -412.713) (xy 387.447185 -412.765297)
			(xy 387.454942 -412.819247) (xy 387.454942 -412.873753) (xy 388.892475 -412.873753) (xy 388.892475 -412.819247)
			(xy 388.900233 -412.765295) (xy 388.91559 -412.712996) (xy 388.938235 -412.663416) (xy 388.967705 -412.617563)
			(xy 389.003401 -412.576372) (xy 389.044597 -412.54068) (xy 389.090453 -412.511215) (xy 389.140036 -412.488576)
			(xy 389.192336 -412.473224) (xy 389.246289 -412.465472) (xy 389.273542 -412.465012) (xy 390.137142 -412.465012)
			(xy 390.164393 -412.465461) (xy 390.218339 -412.473222) (xy 390.270631 -412.488582) (xy 390.320206 -412.511227)
			(xy 390.366053 -412.540696) (xy 390.407241 -412.576389) (xy 390.442929 -412.61758) (xy 390.472393 -412.663431)
			(xy 390.495033 -412.713008) (xy 390.510386 -412.765302) (xy 390.518142 -412.819249) (xy 390.518142 -412.873749)
			(xy 391.955798 -412.873749) (xy 391.955798 -412.819251) (xy 391.963554 -412.765308) (xy 391.978907 -412.713017)
			(xy 392.001546 -412.663444) (xy 392.031009 -412.617597) (xy 392.066697 -412.576409) (xy 392.107882 -412.54072)
			(xy 392.153728 -412.511254) (xy 392.2033 -412.488613) (xy 392.25559 -412.473258) (xy 392.309533 -412.465499)
			(xy 392.336782 -412.465012) (xy 393.200382 -412.465012) (xy 393.227637 -412.465434) (xy 393.281593 -412.473189)
			(xy 393.333896 -412.488544) (xy 393.383481 -412.511187) (xy 393.429339 -412.540656) (xy 393.470536 -412.576352)
			(xy 393.506233 -412.617547) (xy 393.535704 -412.663403) (xy 393.558349 -412.712987) (xy 393.573707 -412.765289)
			(xy 393.581465 -412.819245) (xy 393.581465 -412.873752) (xy 395.018975 -412.873752) (xy 395.018975 -412.819248)
			(xy 395.026732 -412.765298) (xy 395.042089 -412.713001) (xy 395.064732 -412.663422) (xy 395.0942 -412.61757)
			(xy 395.129894 -412.576379) (xy 395.171088 -412.540687) (xy 395.216941 -412.511221) (xy 395.266521 -412.488581)
			(xy 395.318819 -412.473228) (xy 395.37277 -412.465474) (xy 395.400022 -412.465012) (xy 396.263622 -412.465012)
			(xy 396.290874 -412.465459) (xy 396.344822 -412.473219) (xy 396.397117 -412.488577) (xy 396.446694 -412.51122)
			(xy 396.492544 -412.540689) (xy 396.533734 -412.576382) (xy 396.569425 -412.617574) (xy 396.59889 -412.663426)
			(xy 396.621531 -412.713004) (xy 396.636886 -412.7653) (xy 396.644642 -412.819248) (xy 396.644642 -412.873748)
			(xy 398.082298 -412.873748) (xy 398.082298 -412.819252) (xy 398.090053 -412.76531) (xy 398.105406 -412.713022)
			(xy 398.128043 -412.663449) (xy 398.157504 -412.617603) (xy 398.193189 -412.576416) (xy 398.234373 -412.540727)
			(xy 398.280216 -412.511261) (xy 398.329786 -412.488619) (xy 398.382073 -412.473261) (xy 398.436014 -412.465501)
			(xy 398.463262 -412.465012) (xy 399.326862 -412.465012) (xy 399.354118 -412.465432) (xy 399.408076 -412.473185)
			(xy 399.460381 -412.488539) (xy 399.509969 -412.51118) (xy 399.555829 -412.540649) (xy 399.597029 -412.576345)
			(xy 399.632728 -412.61754) (xy 399.662201 -412.663398) (xy 399.684848 -412.712983) (xy 399.700207 -412.765287)
			(xy 399.707965 -412.819244) (xy 399.707965 -412.873752) (xy 401.145475 -412.873752) (xy 401.145475 -412.819248)
			(xy 401.153232 -412.7653) (xy 401.168587 -412.713005) (xy 401.191229 -412.663427) (xy 401.220695 -412.617576)
			(xy 401.256387 -412.576386) (xy 401.297578 -412.540694) (xy 401.343429 -412.511228) (xy 401.393007 -412.488587)
			(xy 401.445302 -412.473231) (xy 401.49925 -412.465475) (xy 401.526502 -412.465012) (xy 402.390102 -412.465012)
			(xy 402.417355 -412.465458) (xy 402.471305 -412.473215) (xy 402.523602 -412.488571) (xy 402.573182 -412.511214)
			(xy 402.619034 -412.540682) (xy 402.660226 -412.576375) (xy 402.69592 -412.617567) (xy 402.725387 -412.66342)
			(xy 402.748029 -412.713) (xy 402.763385 -412.765297) (xy 402.771142 -412.819247) (xy 402.771142 -412.873753)
			(xy 404.208675 -412.873753) (xy 404.208675 -412.819247) (xy 404.216433 -412.765295) (xy 404.23179 -412.712996)
			(xy 404.254435 -412.663416) (xy 404.283905 -412.617563) (xy 404.319601 -412.576372) (xy 404.360797 -412.54068)
			(xy 404.406653 -412.511215) (xy 404.456236 -412.488576) (xy 404.508536 -412.473224) (xy 404.562489 -412.465472)
			(xy 404.589742 -412.465012) (xy 405.453342 -412.465012) (xy 405.480593 -412.465461) (xy 405.534539 -412.473222)
			(xy 405.586831 -412.488582) (xy 405.636406 -412.511227) (xy 405.682253 -412.540696) (xy 405.723441 -412.576389)
			(xy 405.759129 -412.61758) (xy 405.788593 -412.663431) (xy 405.811233 -412.713008) (xy 405.826586 -412.765302)
			(xy 405.834342 -412.819249) (xy 405.834342 -412.873749) (xy 407.271998 -412.873749) (xy 407.271998 -412.819251)
			(xy 407.279754 -412.765308) (xy 407.295107 -412.713017) (xy 407.317746 -412.663444) (xy 407.347209 -412.617597)
			(xy 407.382897 -412.576409) (xy 407.424082 -412.54072) (xy 407.469928 -412.511254) (xy 407.5195 -412.488613)
			(xy 407.57179 -412.473258) (xy 407.625733 -412.465499) (xy 407.652982 -412.465012) (xy 408.516582 -412.465012)
			(xy 408.543837 -412.465434) (xy 408.597793 -412.473189) (xy 408.650096 -412.488544) (xy 408.699681 -412.511187)
			(xy 408.745539 -412.540656) (xy 408.786736 -412.576352) (xy 408.822433 -412.617547) (xy 408.851904 -412.663403)
			(xy 408.874549 -412.712987) (xy 408.889907 -412.765289) (xy 408.897665 -412.819245) (xy 408.897665 -412.873752)
			(xy 410.335175 -412.873752) (xy 410.335175 -412.819248) (xy 410.342932 -412.765298) (xy 410.358289 -412.713001)
			(xy 410.380932 -412.663422) (xy 410.4104 -412.61757) (xy 410.446094 -412.576379) (xy 410.487288 -412.540687)
			(xy 410.533141 -412.511221) (xy 410.582721 -412.488581) (xy 410.635019 -412.473228) (xy 410.68897 -412.465474)
			(xy 410.716222 -412.465012) (xy 411.579822 -412.465012) (xy 411.607074 -412.465459) (xy 411.661022 -412.473219)
			(xy 411.713317 -412.488577) (xy 411.762894 -412.51122) (xy 411.808744 -412.540689) (xy 411.849934 -412.576382)
			(xy 411.885625 -412.617574) (xy 411.91509 -412.663426) (xy 411.937731 -412.713004) (xy 411.953086 -412.7653)
			(xy 411.960842 -412.819248) (xy 411.960842 -412.873748) (xy 413.398498 -412.873748) (xy 413.398498 -412.819252)
			(xy 413.406253 -412.76531) (xy 413.421606 -412.713022) (xy 413.444243 -412.663449) (xy 413.473704 -412.617603)
			(xy 413.509389 -412.576416) (xy 413.550573 -412.540727) (xy 413.596416 -412.511261) (xy 413.645986 -412.488619)
			(xy 413.698273 -412.473261) (xy 413.752214 -412.465501) (xy 413.779462 -412.465012) (xy 414.643062 -412.465012)
			(xy 414.670318 -412.465432) (xy 414.724276 -412.473185) (xy 414.776581 -412.488539) (xy 414.826169 -412.51118)
			(xy 414.872029 -412.540649) (xy 414.913229 -412.576345) (xy 414.948928 -412.61754) (xy 414.978401 -412.663398)
			(xy 415.001048 -412.712983) (xy 415.016407 -412.765287) (xy 415.024165 -412.819244) (xy 415.024165 -412.873752)
			(xy 416.461675 -412.873752) (xy 416.461675 -412.819248) (xy 416.469432 -412.7653) (xy 416.484787 -412.713005)
			(xy 416.507429 -412.663427) (xy 416.536895 -412.617576) (xy 416.572587 -412.576386) (xy 416.613778 -412.540694)
			(xy 416.659629 -412.511228) (xy 416.709207 -412.488587) (xy 416.761502 -412.473231) (xy 416.81545 -412.465475)
			(xy 416.842702 -412.465012) (xy 417.706302 -412.465012) (xy 417.733555 -412.465458) (xy 417.787505 -412.473215)
			(xy 417.839802 -412.488571) (xy 417.889382 -412.511214) (xy 417.935234 -412.540682) (xy 417.976426 -412.576375)
			(xy 418.01212 -412.617567) (xy 418.041587 -412.66342) (xy 418.064229 -412.713) (xy 418.079585 -412.765297)
			(xy 418.087342 -412.819247) (xy 418.087342 -412.873753) (xy 418.079585 -412.927703) (xy 418.064229 -412.98)
			(xy 418.041587 -413.02958) (xy 418.01212 -413.075433) (xy 417.976426 -413.116625) (xy 417.935234 -413.152318)
			(xy 417.889382 -413.181786) (xy 417.839802 -413.204429) (xy 417.787505 -413.219785) (xy 417.733555 -413.227542)
			(xy 417.706302 -413.228028) (xy 416.842702 -413.228028) (xy 416.81545 -413.227525) (xy 416.761502 -413.219769)
			(xy 416.709207 -413.204413) (xy 416.659629 -413.181772) (xy 416.613778 -413.152306) (xy 416.572587 -413.116614)
			(xy 416.536895 -413.075424) (xy 416.507429 -413.029573) (xy 416.484787 -412.979995) (xy 416.469432 -412.9277)
			(xy 416.461675 -412.873752) (xy 415.024165 -412.873752) (xy 415.024165 -412.873756) (xy 415.016407 -412.927713)
			(xy 415.001048 -412.980017) (xy 414.978401 -413.029602) (xy 414.948928 -413.07546) (xy 414.913229 -413.116655)
			(xy 414.872029 -413.152351) (xy 414.826169 -413.18182) (xy 414.776581 -413.204461) (xy 414.724276 -413.219815)
			(xy 414.670318 -413.227568) (xy 414.643062 -413.228028) (xy 413.779462 -413.228028) (xy 413.752214 -413.227499)
			(xy 413.698273 -413.219739) (xy 413.645986 -413.204381) (xy 413.596416 -413.181739) (xy 413.550573 -413.152273)
			(xy 413.509389 -413.116584) (xy 413.473704 -413.075397) (xy 413.444243 -413.029551) (xy 413.421606 -412.979978)
			(xy 413.406253 -412.92769) (xy 413.398498 -412.873748) (xy 411.960842 -412.873748) (xy 411.960842 -412.873752)
			(xy 411.953086 -412.9277) (xy 411.937731 -412.979996) (xy 411.91509 -413.029574) (xy 411.885625 -413.075426)
			(xy 411.849934 -413.116618) (xy 411.808744 -413.152311) (xy 411.762894 -413.18178) (xy 411.713317 -413.204423)
			(xy 411.661022 -413.219781) (xy 411.607074 -413.227541) (xy 411.579822 -413.228028) (xy 410.716222 -413.228028)
			(xy 410.68897 -413.227526) (xy 410.635019 -413.219772) (xy 410.582721 -413.204419) (xy 410.533141 -413.181779)
			(xy 410.487288 -413.152313) (xy 410.446094 -413.116621) (xy 410.4104 -413.07543) (xy 410.380932 -413.029578)
			(xy 410.358289 -412.979999) (xy 410.342932 -412.927702) (xy 410.335175 -412.873752) (xy 408.897665 -412.873752)
			(xy 408.897665 -412.873755) (xy 408.889907 -412.927711) (xy 408.874549 -412.980013) (xy 408.851904 -413.029597)
			(xy 408.822433 -413.075453) (xy 408.786736 -413.116648) (xy 408.745539 -413.152344) (xy 408.699681 -413.181813)
			(xy 408.650096 -413.204456) (xy 408.597793 -413.219811) (xy 408.543837 -413.227566) (xy 408.516582 -413.228028)
			(xy 407.652982 -413.228028) (xy 407.625733 -413.227501) (xy 407.57179 -413.219742) (xy 407.5195 -413.204387)
			(xy 407.469928 -413.181746) (xy 407.424082 -413.15228) (xy 407.382897 -413.116591) (xy 407.347209 -413.075403)
			(xy 407.317746 -413.029556) (xy 407.295107 -412.979983) (xy 407.279754 -412.927692) (xy 407.271998 -412.873749)
			(xy 405.834342 -412.873749) (xy 405.834342 -412.873751) (xy 405.826586 -412.927698) (xy 405.811233 -412.979992)
			(xy 405.788593 -413.029569) (xy 405.759129 -413.07542) (xy 405.723441 -413.116611) (xy 405.682253 -413.152304)
			(xy 405.636406 -413.181773) (xy 405.586831 -413.204418) (xy 405.534539 -413.219778) (xy 405.480593 -413.227539)
			(xy 405.453342 -413.228028) (xy 404.589742 -413.228028) (xy 404.562489 -413.227528) (xy 404.508536 -413.219776)
			(xy 404.456236 -413.204424) (xy 404.406653 -413.181785) (xy 404.360797 -413.15232) (xy 404.319601 -413.116628)
			(xy 404.283905 -413.075437) (xy 404.254435 -413.029584) (xy 404.23179 -412.980004) (xy 404.216433 -412.927705)
			(xy 404.208675 -412.873753) (xy 402.771142 -412.873753) (xy 402.763385 -412.927703) (xy 402.748029 -412.98)
			(xy 402.725387 -413.02958) (xy 402.69592 -413.075433) (xy 402.660226 -413.116625) (xy 402.619034 -413.152318)
			(xy 402.573182 -413.181786) (xy 402.523602 -413.204429) (xy 402.471305 -413.219785) (xy 402.417355 -413.227542)
			(xy 402.390102 -413.228028) (xy 401.526502 -413.228028) (xy 401.49925 -413.227525) (xy 401.445302 -413.219769)
			(xy 401.393007 -413.204413) (xy 401.343429 -413.181772) (xy 401.297578 -413.152306) (xy 401.256387 -413.116614)
			(xy 401.220695 -413.075424) (xy 401.191229 -413.029573) (xy 401.168587 -412.979995) (xy 401.153232 -412.9277)
			(xy 401.145475 -412.873752) (xy 399.707965 -412.873752) (xy 399.707965 -412.873756) (xy 399.700207 -412.927713)
			(xy 399.684848 -412.980017) (xy 399.662201 -413.029602) (xy 399.632728 -413.07546) (xy 399.597029 -413.116655)
			(xy 399.555829 -413.152351) (xy 399.509969 -413.18182) (xy 399.460381 -413.204461) (xy 399.408076 -413.219815)
			(xy 399.354118 -413.227568) (xy 399.326862 -413.228028) (xy 398.463262 -413.228028) (xy 398.436014 -413.227499)
			(xy 398.382073 -413.219739) (xy 398.329786 -413.204381) (xy 398.280216 -413.181739) (xy 398.234373 -413.152273)
			(xy 398.193189 -413.116584) (xy 398.157504 -413.075397) (xy 398.128043 -413.029551) (xy 398.105406 -412.979978)
			(xy 398.090053 -412.92769) (xy 398.082298 -412.873748) (xy 396.644642 -412.873748) (xy 396.644642 -412.873752)
			(xy 396.636886 -412.9277) (xy 396.621531 -412.979996) (xy 396.59889 -413.029574) (xy 396.569425 -413.075426)
			(xy 396.533734 -413.116618) (xy 396.492544 -413.152311) (xy 396.446694 -413.18178) (xy 396.397117 -413.204423)
			(xy 396.344822 -413.219781) (xy 396.290874 -413.227541) (xy 396.263622 -413.228028) (xy 395.400022 -413.228028)
			(xy 395.37277 -413.227526) (xy 395.318819 -413.219772) (xy 395.266521 -413.204419) (xy 395.216941 -413.181779)
			(xy 395.171088 -413.152313) (xy 395.129894 -413.116621) (xy 395.0942 -413.07543) (xy 395.064732 -413.029578)
			(xy 395.042089 -412.979999) (xy 395.026732 -412.927702) (xy 395.018975 -412.873752) (xy 393.581465 -412.873752)
			(xy 393.581465 -412.873755) (xy 393.573707 -412.927711) (xy 393.558349 -412.980013) (xy 393.535704 -413.029597)
			(xy 393.506233 -413.075453) (xy 393.470536 -413.116648) (xy 393.429339 -413.152344) (xy 393.383481 -413.181813)
			(xy 393.333896 -413.204456) (xy 393.281593 -413.219811) (xy 393.227637 -413.227566) (xy 393.200382 -413.228028)
			(xy 392.336782 -413.228028) (xy 392.309533 -413.227501) (xy 392.25559 -413.219742) (xy 392.2033 -413.204387)
			(xy 392.153728 -413.181746) (xy 392.107882 -413.15228) (xy 392.066697 -413.116591) (xy 392.031009 -413.075403)
			(xy 392.001546 -413.029556) (xy 391.978907 -412.979983) (xy 391.963554 -412.927692) (xy 391.955798 -412.873749)
			(xy 390.518142 -412.873749) (xy 390.518142 -412.873751) (xy 390.510386 -412.927698) (xy 390.495033 -412.979992)
			(xy 390.472393 -413.029569) (xy 390.442929 -413.07542) (xy 390.407241 -413.116611) (xy 390.366053 -413.152304)
			(xy 390.320206 -413.181773) (xy 390.270631 -413.204418) (xy 390.218339 -413.219778) (xy 390.164393 -413.227539)
			(xy 390.137142 -413.228028) (xy 389.273542 -413.228028) (xy 389.246289 -413.227528) (xy 389.192336 -413.219776)
			(xy 389.140036 -413.204424) (xy 389.090453 -413.181785) (xy 389.044597 -413.15232) (xy 389.003401 -413.116628)
			(xy 388.967705 -413.075437) (xy 388.938235 -413.029584) (xy 388.91559 -412.980004) (xy 388.900233 -412.927705)
			(xy 388.892475 -412.873753) (xy 387.454942 -412.873753) (xy 387.447185 -412.927703) (xy 387.431829 -412.98)
			(xy 387.409187 -413.02958) (xy 387.37972 -413.075433) (xy 387.344026 -413.116625) (xy 387.302834 -413.152318)
			(xy 387.256982 -413.181786) (xy 387.207402 -413.204429) (xy 387.155105 -413.219785) (xy 387.101155 -413.227542)
			(xy 387.073902 -413.228028) (xy 386.210302 -413.228028) (xy 386.18305 -413.227525) (xy 386.129102 -413.219769)
			(xy 386.076807 -413.204413) (xy 386.027229 -413.181772) (xy 385.981378 -413.152306) (xy 385.940187 -413.116614)
			(xy 385.904495 -413.075424) (xy 385.875029 -413.029573) (xy 385.852387 -412.979995) (xy 385.837032 -412.9277)
			(xy 385.829275 -412.873752) (xy 384.391765 -412.873752) (xy 384.391765 -412.873756) (xy 384.384007 -412.927713)
			(xy 384.368648 -412.980017) (xy 384.346001 -413.029602) (xy 384.316528 -413.07546) (xy 384.280829 -413.116655)
			(xy 384.239629 -413.152351) (xy 384.193769 -413.18182) (xy 384.144181 -413.204461) (xy 384.091876 -413.219815)
			(xy 384.037918 -413.227568) (xy 384.010662 -413.228028) (xy 383.147062 -413.228028) (xy 383.119814 -413.227499)
			(xy 383.065873 -413.219739) (xy 383.013586 -413.204381) (xy 382.964016 -413.181739) (xy 382.918173 -413.152273)
			(xy 382.876989 -413.116584) (xy 382.841304 -413.075397) (xy 382.811843 -413.029551) (xy 382.789206 -412.979978)
			(xy 382.773853 -412.92769) (xy 382.766098 -412.873748) (xy 381.328442 -412.873748) (xy 381.328442 -412.873752)
			(xy 381.320686 -412.9277) (xy 381.305331 -412.979996) (xy 381.28269 -413.029574) (xy 381.253225 -413.075426)
			(xy 381.217534 -413.116618) (xy 381.176344 -413.152311) (xy 381.130494 -413.18178) (xy 381.080917 -413.204423)
			(xy 381.028622 -413.219781) (xy 380.974674 -413.227541) (xy 380.947422 -413.228028) (xy 380.083822 -413.228028)
			(xy 380.05657 -413.227526) (xy 380.002619 -413.219772) (xy 379.950321 -413.204419) (xy 379.900741 -413.181779)
			(xy 379.854888 -413.152313) (xy 379.813694 -413.116621) (xy 379.778 -413.07543) (xy 379.748532 -413.029578)
			(xy 379.725889 -412.979999) (xy 379.710532 -412.927702) (xy 379.702775 -412.873752) (xy 378.265265 -412.873752)
			(xy 378.265265 -412.873755) (xy 378.257507 -412.927711) (xy 378.242149 -412.980013) (xy 378.219504 -413.029597)
			(xy 378.190033 -413.075453) (xy 378.154336 -413.116648) (xy 378.113139 -413.152344) (xy 378.067281 -413.181813)
			(xy 378.017696 -413.204456) (xy 377.965393 -413.219811) (xy 377.911437 -413.227566) (xy 377.884182 -413.228028)
			(xy 377.020582 -413.228028) (xy 376.993333 -413.227501) (xy 376.93939 -413.219742) (xy 376.8871 -413.204387)
			(xy 376.837528 -413.181746) (xy 376.791682 -413.15228) (xy 376.750497 -413.116591) (xy 376.714809 -413.075403)
			(xy 376.685346 -413.029556) (xy 376.662707 -412.979983) (xy 376.647354 -412.927692) (xy 376.639598 -412.873749)
			(xy 375.201942 -412.873749) (xy 375.201942 -412.873751) (xy 375.194186 -412.927698) (xy 375.178833 -412.979992)
			(xy 375.156193 -413.029569) (xy 375.126729 -413.07542) (xy 375.091041 -413.116611) (xy 375.049853 -413.152304)
			(xy 375.004006 -413.181773) (xy 374.954431 -413.204418) (xy 374.902139 -413.219778) (xy 374.848193 -413.227539)
			(xy 374.820942 -413.228028) (xy 373.957342 -413.228028) (xy 373.930089 -413.227528) (xy 373.876136 -413.219776)
			(xy 373.823836 -413.204424) (xy 373.774253 -413.181785) (xy 373.728397 -413.15232) (xy 373.687201 -413.116628)
			(xy 373.651505 -413.075437) (xy 373.622035 -413.029584) (xy 373.59939 -412.980004) (xy 373.584033 -412.927705)
			(xy 373.576275 -412.873753) (xy 372.138742 -412.873753) (xy 372.130985 -412.927703) (xy 372.115629 -412.98)
			(xy 372.092987 -413.02958) (xy 372.06352 -413.075433) (xy 372.027826 -413.116625) (xy 371.986634 -413.152318)
			(xy 371.940782 -413.181786) (xy 371.891202 -413.204429) (xy 371.838905 -413.219785) (xy 371.784955 -413.227542)
			(xy 371.757702 -413.228028) (xy 370.894102 -413.228028) (xy 370.86685 -413.227525) (xy 370.812902 -413.219769)
			(xy 370.760607 -413.204413) (xy 370.711029 -413.181772) (xy 370.665178 -413.152306) (xy 370.623987 -413.116614)
			(xy 370.588295 -413.075424) (xy 370.558829 -413.029573) (xy 370.536187 -412.979995) (xy 370.520832 -412.9277)
			(xy 370.513075 -412.873752) (xy 350.987142 -412.873752) (xy 350.979385 -412.927702) (xy 350.96403 -412.979999)
			(xy 350.941388 -413.029579) (xy 350.911921 -413.075431) (xy 350.876228 -413.116624) (xy 350.835036 -413.152317)
			(xy 350.789184 -413.181785) (xy 350.739605 -413.204428) (xy 350.687308 -413.219784) (xy 350.633358 -413.227542)
			(xy 350.606106 -413.228028) (xy 349.742506 -413.228028) (xy 349.715254 -413.227525) (xy 349.661306 -413.219769)
			(xy 349.60901 -413.204415) (xy 349.559431 -413.181774) (xy 349.51358 -413.152307) (xy 349.472389 -413.116616)
			(xy 349.436696 -413.075425) (xy 349.407229 -413.029574) (xy 349.384588 -412.979996) (xy 349.369232 -412.9277)
			(xy 349.361475 -412.873752) (xy 347.923965 -412.873752) (xy 347.923965 -412.873756) (xy 347.916207 -412.927713)
			(xy 347.900848 -412.980016) (xy 347.878202 -413.029601) (xy 347.848729 -413.075458) (xy 347.81303 -413.116654)
			(xy 347.771831 -413.15235) (xy 347.725971 -413.181818) (xy 347.676384 -413.20446) (xy 347.624079 -413.219814)
			(xy 347.570122 -413.227567) (xy 347.542866 -413.228028) (xy 346.679266 -413.228028) (xy 346.652018 -413.227499)
			(xy 346.598077 -413.219739) (xy 346.545789 -413.204382) (xy 346.496218 -413.18174) (xy 346.450375 -413.152275)
			(xy 346.409191 -413.116585) (xy 346.373505 -413.075398) (xy 346.344043 -413.029552) (xy 346.321406 -412.979979)
			(xy 346.306053 -412.92769) (xy 346.298298 -412.873748) (xy 344.860642 -412.873748) (xy 344.860642 -412.873751)
			(xy 344.852886 -412.9277) (xy 344.837531 -412.979995) (xy 344.814891 -413.029573) (xy 344.785426 -413.075425)
			(xy 344.749735 -413.116617) (xy 344.708546 -413.15231) (xy 344.662696 -413.181778) (xy 344.61312 -413.204422)
			(xy 344.560825 -413.21978) (xy 344.506877 -413.22754) (xy 344.479626 -413.228028) (xy 343.616026 -413.228028)
			(xy 343.588773 -413.227526) (xy 343.534822 -413.219773) (xy 343.482524 -413.20442) (xy 343.432943 -413.18178)
			(xy 343.387089 -413.152314) (xy 343.345896 -413.116623) (xy 343.310201 -413.075431) (xy 343.280732 -413.029579)
			(xy 343.258089 -412.98) (xy 343.242733 -412.927703) (xy 343.234975 -412.873753) (xy 341.797465 -412.873753)
			(xy 341.797465 -412.873755) (xy 341.789707 -412.92771) (xy 341.77435 -412.980012) (xy 341.751705 -413.029595)
			(xy 341.722234 -413.075452) (xy 341.686537 -413.116647) (xy 341.645341 -413.152343) (xy 341.599483 -413.181812)
			(xy 341.549899 -413.204455) (xy 341.497596 -413.21981) (xy 341.443641 -413.227566) (xy 341.416386 -413.228028)
			(xy 340.552786 -413.228028) (xy 340.525537 -413.227501) (xy 340.471594 -413.219743) (xy 340.419303 -413.204388)
			(xy 340.36973 -413.181747) (xy 340.323884 -413.152282) (xy 340.282698 -413.116592) (xy 340.24701 -413.075404)
			(xy 340.217546 -413.029557) (xy 340.194908 -412.979984) (xy 340.179554 -412.927693) (xy 340.171798 -412.873749)
			(xy 338.734142 -412.873749) (xy 338.734142 -412.873751) (xy 338.726387 -412.927697) (xy 338.711033 -412.979991)
			(xy 338.688394 -413.029568) (xy 338.65893 -413.075418) (xy 338.623242 -413.116609) (xy 338.582055 -413.152303)
			(xy 338.536208 -413.181772) (xy 338.486634 -413.204417) (xy 338.434342 -413.219777) (xy 338.380397 -413.227539)
			(xy 338.353146 -413.228028) (xy 337.489546 -413.228028) (xy 337.462292 -413.227528) (xy 337.408339 -413.219777)
			(xy 337.356039 -413.204425) (xy 337.306455 -413.181787) (xy 337.260599 -413.152321) (xy 337.219403 -413.11663)
			(xy 337.183706 -413.075438) (xy 337.154235 -413.029585) (xy 337.131591 -412.980004) (xy 337.116233 -412.927706)
			(xy 337.108475 -412.873754) (xy 335.670942 -412.873754) (xy 335.663185 -412.927702) (xy 335.64783 -412.979999)
			(xy 335.625188 -413.029579) (xy 335.595721 -413.075431) (xy 335.560028 -413.116624) (xy 335.518836 -413.152317)
			(xy 335.472984 -413.181785) (xy 335.423405 -413.204428) (xy 335.371108 -413.219784) (xy 335.317158 -413.227542)
			(xy 335.289906 -413.228028) (xy 334.426306 -413.228028) (xy 334.399054 -413.227525) (xy 334.345106 -413.219769)
			(xy 334.29281 -413.204415) (xy 334.243231 -413.181774) (xy 334.19738 -413.152307) (xy 334.156189 -413.116616)
			(xy 334.120496 -413.075425) (xy 334.091029 -413.029574) (xy 334.068388 -412.979996) (xy 334.053032 -412.9277)
			(xy 334.045275 -412.873752) (xy 332.607765 -412.873752) (xy 332.607765 -412.873756) (xy 332.600007 -412.927713)
			(xy 332.584648 -412.980016) (xy 332.562002 -413.029601) (xy 332.532529 -413.075458) (xy 332.49683 -413.116654)
			(xy 332.455631 -413.15235) (xy 332.409771 -413.181818) (xy 332.360184 -413.20446) (xy 332.307879 -413.219814)
			(xy 332.253922 -413.227567) (xy 332.226666 -413.228028) (xy 331.363066 -413.228028) (xy 331.335818 -413.227499)
			(xy 331.281877 -413.219739) (xy 331.229589 -413.204382) (xy 331.180018 -413.18174) (xy 331.134175 -413.152275)
			(xy 331.092991 -413.116585) (xy 331.057305 -413.075398) (xy 331.027843 -413.029552) (xy 331.005206 -412.979979)
			(xy 330.989853 -412.92769) (xy 330.982098 -412.873748) (xy 329.544442 -412.873748) (xy 329.544442 -412.873751)
			(xy 329.536686 -412.9277) (xy 329.521331 -412.979995) (xy 329.498691 -413.029573) (xy 329.469226 -413.075425)
			(xy 329.433535 -413.116617) (xy 329.392346 -413.15231) (xy 329.346496 -413.181778) (xy 329.29692 -413.204422)
			(xy 329.244625 -413.21978) (xy 329.190677 -413.22754) (xy 329.163426 -413.228028) (xy 328.299826 -413.228028)
			(xy 328.272573 -413.227526) (xy 328.218622 -413.219773) (xy 328.166324 -413.20442) (xy 328.116743 -413.18178)
			(xy 328.070889 -413.152314) (xy 328.029696 -413.116623) (xy 327.994001 -413.075431) (xy 327.964532 -413.029579)
			(xy 327.941889 -412.98) (xy 327.926533 -412.927703) (xy 327.918775 -412.873753) (xy 326.481265 -412.873753)
			(xy 326.481265 -412.873755) (xy 326.473507 -412.92771) (xy 326.45815 -412.980012) (xy 326.435505 -413.029595)
			(xy 326.406034 -413.075452) (xy 326.370337 -413.116647) (xy 326.329141 -413.152343) (xy 326.283283 -413.181812)
			(xy 326.233699 -413.204455) (xy 326.181396 -413.21981) (xy 326.127441 -413.227566) (xy 326.100186 -413.228028)
			(xy 325.236586 -413.228028) (xy 325.209337 -413.227501) (xy 325.155394 -413.219743) (xy 325.103103 -413.204388)
			(xy 325.05353 -413.181747) (xy 325.007684 -413.152282) (xy 324.966498 -413.116592) (xy 324.93081 -413.075404)
			(xy 324.901346 -413.029557) (xy 324.878708 -412.979984) (xy 324.863354 -412.927693) (xy 324.855598 -412.873749)
			(xy 323.417942 -412.873749) (xy 323.417942 -412.873751) (xy 323.410187 -412.927697) (xy 323.394833 -412.979991)
			(xy 323.372194 -413.029568) (xy 323.34273 -413.075418) (xy 323.307042 -413.116609) (xy 323.265855 -413.152303)
			(xy 323.220008 -413.181772) (xy 323.170434 -413.204417) (xy 323.118142 -413.219777) (xy 323.064197 -413.227539)
			(xy 323.036946 -413.228028) (xy 322.173346 -413.228028) (xy 322.146092 -413.227528) (xy 322.092139 -413.219777)
			(xy 322.039839 -413.204425) (xy 321.990255 -413.181787) (xy 321.944399 -413.152321) (xy 321.903203 -413.11663)
			(xy 321.867506 -413.075438) (xy 321.838035 -413.029585) (xy 321.815391 -412.980004) (xy 321.800033 -412.927706)
			(xy 321.792275 -412.873754) (xy 320.354742 -412.873754) (xy 320.346985 -412.927702) (xy 320.33163 -412.979999)
			(xy 320.308988 -413.029579) (xy 320.279521 -413.075431) (xy 320.243828 -413.116624) (xy 320.202636 -413.152317)
			(xy 320.156784 -413.181785) (xy 320.107205 -413.204428) (xy 320.054908 -413.219784) (xy 320.000958 -413.227542)
			(xy 319.973706 -413.228028) (xy 319.110106 -413.228028) (xy 319.082854 -413.227525) (xy 319.028906 -413.219769)
			(xy 318.97661 -413.204415) (xy 318.927031 -413.181774) (xy 318.88118 -413.152307) (xy 318.839989 -413.116616)
			(xy 318.804296 -413.075425) (xy 318.774829 -413.029574) (xy 318.752188 -412.979996) (xy 318.736832 -412.9277)
			(xy 318.729075 -412.873752) (xy 317.291565 -412.873752) (xy 317.291565 -412.873756) (xy 317.283807 -412.927713)
			(xy 317.268448 -412.980016) (xy 317.245802 -413.029601) (xy 317.216329 -413.075458) (xy 317.18063 -413.116654)
			(xy 317.139431 -413.15235) (xy 317.093571 -413.181818) (xy 317.043984 -413.20446) (xy 316.991679 -413.219814)
			(xy 316.937722 -413.227567) (xy 316.910466 -413.228028) (xy 316.046866 -413.228028) (xy 316.019618 -413.227499)
			(xy 315.965677 -413.219739) (xy 315.913389 -413.204382) (xy 315.863818 -413.18174) (xy 315.817975 -413.152275)
			(xy 315.776791 -413.116585) (xy 315.741105 -413.075398) (xy 315.711643 -413.029552) (xy 315.689006 -412.979979)
			(xy 315.673653 -412.92769) (xy 315.665898 -412.873748) (xy 314.228242 -412.873748) (xy 314.228242 -412.873751)
			(xy 314.220486 -412.9277) (xy 314.205131 -412.979995) (xy 314.182491 -413.029573) (xy 314.153026 -413.075425)
			(xy 314.117335 -413.116617) (xy 314.076146 -413.15231) (xy 314.030296 -413.181778) (xy 313.98072 -413.204422)
			(xy 313.928425 -413.21978) (xy 313.874477 -413.22754) (xy 313.847226 -413.228028) (xy 312.983626 -413.228028)
			(xy 312.956373 -413.227526) (xy 312.902422 -413.219773) (xy 312.850124 -413.20442) (xy 312.800543 -413.18178)
			(xy 312.754689 -413.152314) (xy 312.713496 -413.116623) (xy 312.677801 -413.075431) (xy 312.648332 -413.029579)
			(xy 312.625689 -412.98) (xy 312.610333 -412.927703) (xy 312.602575 -412.873753) (xy 311.165065 -412.873753)
			(xy 311.165065 -412.873755) (xy 311.157307 -412.92771) (xy 311.14195 -412.980012) (xy 311.119305 -413.029595)
			(xy 311.089834 -413.075452) (xy 311.054137 -413.116647) (xy 311.012941 -413.152343) (xy 310.967083 -413.181812)
			(xy 310.917499 -413.204455) (xy 310.865196 -413.21981) (xy 310.811241 -413.227566) (xy 310.783986 -413.228028)
			(xy 309.920386 -413.228028) (xy 309.893137 -413.227501) (xy 309.839194 -413.219743) (xy 309.786903 -413.204388)
			(xy 309.73733 -413.181747) (xy 309.691484 -413.152282) (xy 309.650298 -413.116592) (xy 309.61461 -413.075404)
			(xy 309.585146 -413.029557) (xy 309.562508 -412.979984) (xy 309.547154 -412.927693) (xy 309.539398 -412.873749)
			(xy 308.101742 -412.873749) (xy 308.101742 -412.873751) (xy 308.093987 -412.927697) (xy 308.078633 -412.979991)
			(xy 308.055994 -413.029568) (xy 308.02653 -413.075418) (xy 307.990842 -413.116609) (xy 307.949655 -413.152303)
			(xy 307.903808 -413.181772) (xy 307.854234 -413.204417) (xy 307.801942 -413.219777) (xy 307.747997 -413.227539)
			(xy 307.720746 -413.228028) (xy 306.857146 -413.228028) (xy 306.829892 -413.227528) (xy 306.775939 -413.219777)
			(xy 306.723639 -413.204425) (xy 306.674055 -413.181787) (xy 306.628199 -413.152321) (xy 306.587003 -413.11663)
			(xy 306.551306 -413.075438) (xy 306.521835 -413.029585) (xy 306.499191 -412.980004) (xy 306.483833 -412.927706)
			(xy 306.476075 -412.873754) (xy 305.038542 -412.873754) (xy 305.030785 -412.927702) (xy 305.01543 -412.979999)
			(xy 304.992788 -413.029579) (xy 304.963321 -413.075431) (xy 304.927628 -413.116624) (xy 304.886436 -413.152317)
			(xy 304.840584 -413.181785) (xy 304.791005 -413.204428) (xy 304.738708 -413.219784) (xy 304.684758 -413.227542)
			(xy 304.657506 -413.228028) (xy 303.793906 -413.228028) (xy 303.766654 -413.227525) (xy 303.712706 -413.219769)
			(xy 303.66041 -413.204415) (xy 303.610831 -413.181774) (xy 303.56498 -413.152307) (xy 303.523789 -413.116616)
			(xy 303.488096 -413.075425) (xy 303.458629 -413.029574) (xy 303.435988 -412.979996) (xy 303.420632 -412.9277)
			(xy 303.412875 -412.873752) (xy 301.87467 -412.873752) (xy 301.882114 -412.988908) (xy 301.886112 -413.1747)
			(xy 301.884113 -413.267605) (xy 422.67809 -413.267605) (xy 422.67809 -413.081771) (xy 422.686085 -412.896108)
			(xy 422.70206 -412.710962) (xy 422.725986 -412.526674) (xy 422.757818 -412.343586) (xy 422.797498 -412.162037)
			(xy 422.844951 -411.982363) (xy 422.900091 -411.804897) (xy 422.962814 -411.629968) (xy 423.033005 -411.457899)
			(xy 423.110534 -411.28901) (xy 423.195257 -411.123612) (xy 423.287018 -410.962012) (xy 423.385646 -410.80451)
			(xy 423.490959 -410.651396) (xy 423.602761 -410.502956) (xy 423.720846 -410.359462) (xy 423.844996 -410.221182)
			(xy 423.974979 -410.088371) (xy 424.110556 -409.961275) (xy 424.251476 -409.84013) (xy 424.397476 -409.725159)
			(xy 424.548288 -409.616576) (xy 424.703632 -409.514583) (xy 424.86322 -409.419366) (xy 425.026757 -409.331104)
			(xy 425.193939 -409.249959) (xy 425.364458 -409.176082) (xy 425.537997 -409.109609) (xy 425.714236 -409.050664)
			(xy 425.892847 -408.999356) (xy 426.0735 -408.955779) (xy 426.255861 -408.920015) (xy 426.439591 -408.892129)
			(xy 426.624351 -408.872174) (xy 426.809798 -408.860186) (xy 426.99559 -408.856188) (xy 427.181382 -408.860186)
			(xy 427.366829 -408.872174) (xy 427.551589 -408.892129) (xy 427.735319 -408.920015) (xy 427.91768 -408.955779)
			(xy 428.098333 -408.999356) (xy 428.276944 -409.050664) (xy 428.453183 -409.109609) (xy 428.626722 -409.176082)
			(xy 428.797241 -409.249959) (xy 428.964423 -409.331104) (xy 429.12796 -409.419366) (xy 429.287548 -409.514583)
			(xy 429.442892 -409.616576) (xy 429.593704 -409.725159) (xy 429.739704 -409.84013) (xy 429.880624 -409.961275)
			(xy 430.016201 -410.088371) (xy 430.146184 -410.221182) (xy 430.270334 -410.359462) (xy 430.388419 -410.502956)
			(xy 430.500221 -410.651396) (xy 430.605534 -410.80451) (xy 430.704162 -410.962012) (xy 430.795923 -411.123612)
			(xy 430.880646 -411.28901) (xy 430.958175 -411.457899) (xy 431.028366 -411.629968) (xy 431.091089 -411.804897)
			(xy 431.146229 -411.982363) (xy 431.193682 -412.162037) (xy 431.233362 -412.343586) (xy 431.265194 -412.526674)
			(xy 431.28912 -412.710962) (xy 431.305095 -412.896108) (xy 431.31309 -413.081771) (xy 431.31359 -413.174688)
			(xy 431.31309 -413.267605) (xy 431.305095 -413.453268) (xy 431.28912 -413.638414) (xy 431.265194 -413.822702)
			(xy 431.233362 -414.00579) (xy 431.193682 -414.187339) (xy 431.146229 -414.367013) (xy 431.091089 -414.544479)
			(xy 431.028366 -414.719408) (xy 430.958175 -414.891477) (xy 430.880646 -415.060366) (xy 430.795923 -415.225764)
			(xy 430.704162 -415.387364) (xy 430.605534 -415.544866) (xy 430.500221 -415.69798) (xy 430.388419 -415.84642)
			(xy 430.270334 -415.989914) (xy 430.146184 -416.128194) (xy 430.016201 -416.261005) (xy 429.880624 -416.388101)
			(xy 429.739704 -416.509246) (xy 429.593704 -416.624217) (xy 429.442892 -416.7328) (xy 429.287548 -416.834793)
			(xy 429.12796 -416.93001) (xy 428.964423 -417.018272) (xy 428.797241 -417.099417) (xy 428.626722 -417.173294)
			(xy 428.453183 -417.239767) (xy 428.276944 -417.298712) (xy 428.098333 -417.35002) (xy 427.91768 -417.393597)
			(xy 427.735319 -417.429361) (xy 427.551589 -417.457247) (xy 427.366829 -417.477202) (xy 427.181382 -417.48919)
			(xy 426.99559 -417.493188) (xy 426.809798 -417.48919) (xy 426.624351 -417.477202) (xy 426.439591 -417.457247)
			(xy 426.255861 -417.429361) (xy 426.0735 -417.393597) (xy 425.892847 -417.35002) (xy 425.714236 -417.298712)
			(xy 425.537997 -417.239767) (xy 425.364458 -417.173294) (xy 425.193939 -417.099417) (xy 425.026757 -417.018272)
			(xy 424.86322 -416.93001) (xy 424.703632 -416.834793) (xy 424.548288 -416.7328) (xy 424.397476 -416.624217)
			(xy 424.251476 -416.509246) (xy 424.110556 -416.388101) (xy 423.974979 -416.261005) (xy 423.844996 -416.128194)
			(xy 423.720846 -415.989914) (xy 423.602761 -415.84642) (xy 423.490959 -415.69798) (xy 423.385646 -415.544866)
			(xy 423.287018 -415.387364) (xy 423.195257 -415.225764) (xy 423.110534 -415.060366) (xy 423.033005 -414.891477)
			(xy 422.962814 -414.719408) (xy 422.900091 -414.544479) (xy 422.844951 -414.367013) (xy 422.797498 -414.187339)
			(xy 422.757818 -414.00579) (xy 422.725986 -413.822702) (xy 422.70206 -413.638414) (xy 422.686085 -413.453268)
			(xy 422.67809 -413.267605) (xy 301.884113 -413.267605) (xy 301.882114 -413.360492) (xy 301.870126 -413.54594)
			(xy 301.85017 -413.7307) (xy 301.822285 -413.914431) (xy 301.786521 -414.096792) (xy 301.742944 -414.277446)
			(xy 301.691636 -414.456057) (xy 301.63269 -414.632296) (xy 301.566218 -414.805835) (xy 301.49234 -414.976355)
			(xy 301.411195 -415.143537) (xy 301.322933 -415.307074) (xy 301.259284 -415.413753) (xy 304.944475 -415.413753)
			(xy 304.944475 -415.359247) (xy 304.952233 -415.305297) (xy 304.967589 -415.253) (xy 304.990232 -415.203421)
			(xy 305.019701 -415.157569) (xy 305.055396 -415.116377) (xy 305.096589 -415.080686) (xy 305.142443 -415.05122)
			(xy 305.192024 -415.02858) (xy 305.244322 -415.013227) (xy 305.298273 -415.005474) (xy 305.325526 -415.005012)
			(xy 306.189126 -415.005012) (xy 306.216377 -415.00546) (xy 306.270325 -415.01322) (xy 306.32262 -415.028578)
			(xy 306.372196 -415.051222) (xy 306.418046 -415.08069) (xy 306.459235 -415.116383) (xy 306.494926 -415.157575)
			(xy 306.524391 -415.203427) (xy 306.547031 -415.253005) (xy 306.562386 -415.3053) (xy 306.570142 -415.359249)
			(xy 306.570142 -415.413748) (xy 308.007798 -415.413748) (xy 308.007798 -415.359252) (xy 308.015553 -415.30531)
			(xy 308.030906 -415.253021) (xy 308.053543 -415.203448) (xy 308.083005 -415.157602) (xy 308.118691 -415.116415)
			(xy 308.159875 -415.080725) (xy 308.205718 -415.05126) (xy 308.255289 -415.028618) (xy 308.307577 -415.013261)
			(xy 308.361518 -415.005501) (xy 308.388766 -415.005012) (xy 309.252366 -415.005012) (xy 309.279622 -415.005433)
			(xy 309.333579 -415.013186) (xy 309.385884 -415.02854) (xy 309.435471 -415.051182) (xy 309.481331 -415.08065)
			(xy 309.52253 -415.116346) (xy 309.558229 -415.157542) (xy 309.587702 -415.203399) (xy 309.610348 -415.252984)
			(xy 309.625707 -415.305287) (xy 309.633465 -415.359244) (xy 309.633465 -415.413752) (xy 311.070975 -415.413752)
			(xy 311.070975 -415.359248) (xy 311.078732 -415.3053) (xy 311.094088 -415.253004) (xy 311.116729 -415.203426)
			(xy 311.146196 -415.157575) (xy 311.181889 -415.116384) (xy 311.22308 -415.080693) (xy 311.268931 -415.051226)
			(xy 311.31851 -415.028585) (xy 311.370806 -415.013231) (xy 311.424754 -415.005475) (xy 311.452006 -415.005012)
			(xy 312.315606 -415.005012) (xy 312.342858 -415.005458) (xy 312.396808 -415.013216) (xy 312.449105 -415.028572)
			(xy 312.498684 -415.051215) (xy 312.544536 -415.080683) (xy 312.585728 -415.116376) (xy 312.621421 -415.157569)
			(xy 312.650888 -415.203421) (xy 312.67353 -415.253001) (xy 312.688885 -415.305298) (xy 312.696642 -415.359248)
			(xy 312.696642 -415.413752) (xy 312.696642 -415.413754) (xy 314.134175 -415.413754) (xy 314.134175 -415.359246)
			(xy 314.141933 -415.305294) (xy 314.157291 -415.252996) (xy 314.179935 -415.203415) (xy 314.209406 -415.157562)
			(xy 314.245103 -415.11637) (xy 314.286299 -415.080679) (xy 314.332155 -415.051213) (xy 314.381739 -415.028575)
			(xy 314.434039 -415.013223) (xy 314.487992 -415.005472) (xy 314.515246 -415.005012) (xy 315.378846 -415.005012)
			(xy 315.406097 -415.005461) (xy 315.460042 -415.013223) (xy 315.512334 -415.028583) (xy 315.561908 -415.051228)
			(xy 315.607755 -415.080697) (xy 315.648942 -415.116391) (xy 315.68463 -415.157582) (xy 315.714094 -415.203432)
			(xy 315.736733 -415.253009) (xy 315.752087 -415.305303) (xy 315.759842 -415.359249) (xy 315.759842 -415.413749)
			(xy 317.197498 -415.413749) (xy 317.197498 -415.359251) (xy 317.205254 -415.305307) (xy 317.220608 -415.253016)
			(xy 317.243246 -415.203443) (xy 317.27271 -415.157596) (xy 317.308398 -415.116408) (xy 317.349584 -415.080718)
			(xy 317.39543 -415.051253) (xy 317.445003 -415.028612) (xy 317.497294 -415.013257) (xy 317.551237 -415.005499)
			(xy 317.578486 -415.005012) (xy 318.442086 -415.005012) (xy 318.469341 -415.005434) (xy 318.523296 -415.01319)
			(xy 318.575599 -415.028545) (xy 318.625183 -415.051188) (xy 318.671041 -415.080657) (xy 318.712237 -415.116353)
			(xy 318.747934 -415.157548) (xy 318.777405 -415.203405) (xy 318.80005 -415.252988) (xy 318.815407 -415.30529)
			(xy 318.823165 -415.359245) (xy 318.823165 -415.413753) (xy 320.260675 -415.413753) (xy 320.260675 -415.359247)
			(xy 320.268433 -415.305297) (xy 320.283789 -415.253) (xy 320.306432 -415.203421) (xy 320.335901 -415.157569)
			(xy 320.371596 -415.116377) (xy 320.412789 -415.080686) (xy 320.458643 -415.05122) (xy 320.508224 -415.02858)
			(xy 320.560522 -415.013227) (xy 320.614473 -415.005474) (xy 320.641726 -415.005012) (xy 321.505326 -415.005012)
			(xy 321.532577 -415.00546) (xy 321.586525 -415.01322) (xy 321.63882 -415.028578) (xy 321.688396 -415.051222)
			(xy 321.734246 -415.08069) (xy 321.775435 -415.116383) (xy 321.811126 -415.157575) (xy 321.840591 -415.203427)
			(xy 321.863231 -415.253005) (xy 321.878586 -415.3053) (xy 321.886342 -415.359249) (xy 321.886342 -415.413748)
			(xy 323.323998 -415.413748) (xy 323.323998 -415.359252) (xy 323.331753 -415.30531) (xy 323.347106 -415.253021)
			(xy 323.369743 -415.203448) (xy 323.399205 -415.157602) (xy 323.434891 -415.116415) (xy 323.476075 -415.080725)
			(xy 323.521918 -415.05126) (xy 323.571489 -415.028618) (xy 323.623777 -415.013261) (xy 323.677718 -415.005501)
			(xy 323.704966 -415.005012) (xy 324.568566 -415.005012) (xy 324.595822 -415.005433) (xy 324.649779 -415.013186)
			(xy 324.702084 -415.02854) (xy 324.751671 -415.051182) (xy 324.797531 -415.08065) (xy 324.83873 -415.116346)
			(xy 324.874429 -415.157542) (xy 324.903902 -415.203399) (xy 324.926548 -415.252984) (xy 324.941907 -415.305287)
			(xy 324.949665 -415.359244) (xy 324.949665 -415.413752) (xy 326.387175 -415.413752) (xy 326.387175 -415.359248)
			(xy 326.394932 -415.3053) (xy 326.410288 -415.253004) (xy 326.432929 -415.203426) (xy 326.462396 -415.157575)
			(xy 326.498089 -415.116384) (xy 326.53928 -415.080693) (xy 326.585131 -415.051226) (xy 326.63471 -415.028585)
			(xy 326.687006 -415.013231) (xy 326.740954 -415.005475) (xy 326.768206 -415.005012) (xy 327.631806 -415.005012)
			(xy 327.659058 -415.005458) (xy 327.713008 -415.013216) (xy 327.765305 -415.028572) (xy 327.814884 -415.051215)
			(xy 327.860736 -415.080683) (xy 327.901928 -415.116376) (xy 327.937621 -415.157569) (xy 327.967088 -415.203421)
			(xy 327.98973 -415.253001) (xy 328.005085 -415.305298) (xy 328.012842 -415.359248) (xy 328.012842 -415.413752)
			(xy 328.012842 -415.413754) (xy 329.450375 -415.413754) (xy 329.450375 -415.359246) (xy 329.458133 -415.305294)
			(xy 329.473491 -415.252996) (xy 329.496135 -415.203415) (xy 329.525606 -415.157562) (xy 329.561303 -415.11637)
			(xy 329.602499 -415.080679) (xy 329.648355 -415.051213) (xy 329.697939 -415.028575) (xy 329.750239 -415.013223)
			(xy 329.804192 -415.005472) (xy 329.831446 -415.005012) (xy 330.695046 -415.005012) (xy 330.722297 -415.005461)
			(xy 330.776242 -415.013223) (xy 330.828534 -415.028583) (xy 330.878108 -415.051228) (xy 330.923955 -415.080697)
			(xy 330.965142 -415.116391) (xy 331.00083 -415.157582) (xy 331.030294 -415.203432) (xy 331.052933 -415.253009)
			(xy 331.068287 -415.305303) (xy 331.076042 -415.359249) (xy 331.076042 -415.413749) (xy 332.513698 -415.413749)
			(xy 332.513698 -415.359251) (xy 332.521454 -415.305307) (xy 332.536808 -415.253016) (xy 332.559446 -415.203443)
			(xy 332.58891 -415.157596) (xy 332.624598 -415.116408) (xy 332.665784 -415.080718) (xy 332.71163 -415.051253)
			(xy 332.761203 -415.028612) (xy 332.813494 -415.013257) (xy 332.867437 -415.005499) (xy 332.894686 -415.005012)
			(xy 333.758286 -415.005012) (xy 333.785541 -415.005434) (xy 333.839496 -415.01319) (xy 333.891799 -415.028545)
			(xy 333.941383 -415.051188) (xy 333.987241 -415.080657) (xy 334.028437 -415.116353) (xy 334.064134 -415.157548)
			(xy 334.093605 -415.203405) (xy 334.11625 -415.252988) (xy 334.131607 -415.30529) (xy 334.139365 -415.359245)
			(xy 334.139365 -415.413753) (xy 335.576875 -415.413753) (xy 335.576875 -415.359247) (xy 335.584633 -415.305297)
			(xy 335.599989 -415.253) (xy 335.622632 -415.203421) (xy 335.652101 -415.157569) (xy 335.687796 -415.116377)
			(xy 335.728989 -415.080686) (xy 335.774843 -415.05122) (xy 335.824424 -415.02858) (xy 335.876722 -415.013227)
			(xy 335.930673 -415.005474) (xy 335.957926 -415.005012) (xy 336.821526 -415.005012) (xy 336.848777 -415.00546)
			(xy 336.902725 -415.01322) (xy 336.95502 -415.028578) (xy 337.004596 -415.051222) (xy 337.050446 -415.08069)
			(xy 337.091635 -415.116383) (xy 337.127326 -415.157575) (xy 337.156791 -415.203427) (xy 337.179431 -415.253005)
			(xy 337.194786 -415.3053) (xy 337.202542 -415.359249) (xy 337.202542 -415.413748) (xy 338.640198 -415.413748)
			(xy 338.640198 -415.359252) (xy 338.647953 -415.30531) (xy 338.663306 -415.253021) (xy 338.685943 -415.203448)
			(xy 338.715405 -415.157602) (xy 338.751091 -415.116415) (xy 338.792275 -415.080725) (xy 338.838118 -415.05126)
			(xy 338.887689 -415.028618) (xy 338.939977 -415.013261) (xy 338.993918 -415.005501) (xy 339.021166 -415.005012)
			(xy 339.884766 -415.005012) (xy 339.912022 -415.005433) (xy 339.965979 -415.013186) (xy 340.018284 -415.02854)
			(xy 340.067871 -415.051182) (xy 340.113731 -415.08065) (xy 340.15493 -415.116346) (xy 340.190629 -415.157542)
			(xy 340.220102 -415.203399) (xy 340.242748 -415.252984) (xy 340.258107 -415.305287) (xy 340.265865 -415.359244)
			(xy 340.265865 -415.413752) (xy 341.703375 -415.413752) (xy 341.703375 -415.359248) (xy 341.711132 -415.3053)
			(xy 341.726488 -415.253004) (xy 341.749129 -415.203426) (xy 341.778596 -415.157575) (xy 341.814289 -415.116384)
			(xy 341.85548 -415.080693) (xy 341.901331 -415.051226) (xy 341.95091 -415.028585) (xy 342.003206 -415.013231)
			(xy 342.057154 -415.005475) (xy 342.084406 -415.005012) (xy 342.948006 -415.005012) (xy 342.975258 -415.005458)
			(xy 343.029208 -415.013216) (xy 343.081505 -415.028572) (xy 343.131084 -415.051215) (xy 343.176936 -415.080683)
			(xy 343.218128 -415.116376) (xy 343.253821 -415.157569) (xy 343.283288 -415.203421) (xy 343.30593 -415.253001)
			(xy 343.321285 -415.305298) (xy 343.329042 -415.359248) (xy 343.329042 -415.413752) (xy 343.329042 -415.413754)
			(xy 344.766575 -415.413754) (xy 344.766575 -415.359246) (xy 344.774333 -415.305294) (xy 344.789691 -415.252996)
			(xy 344.812335 -415.203415) (xy 344.841806 -415.157562) (xy 344.877503 -415.11637) (xy 344.918699 -415.080679)
			(xy 344.964555 -415.051213) (xy 345.014139 -415.028575) (xy 345.066439 -415.013223) (xy 345.120392 -415.005472)
			(xy 345.147646 -415.005012) (xy 346.011246 -415.005012) (xy 346.038497 -415.005461) (xy 346.092442 -415.013223)
			(xy 346.144734 -415.028583) (xy 346.194308 -415.051228) (xy 346.240155 -415.080697) (xy 346.281342 -415.116391)
			(xy 346.31703 -415.157582) (xy 346.346494 -415.203432) (xy 346.369133 -415.253009) (xy 346.384487 -415.305303)
			(xy 346.392242 -415.359249) (xy 346.392242 -415.413749) (xy 347.829898 -415.413749) (xy 347.829898 -415.359251)
			(xy 347.837654 -415.305307) (xy 347.853008 -415.253016) (xy 347.875646 -415.203443) (xy 347.90511 -415.157596)
			(xy 347.940798 -415.116408) (xy 347.981984 -415.080718) (xy 348.02783 -415.051253) (xy 348.077403 -415.028612)
			(xy 348.129694 -415.013257) (xy 348.183637 -415.005499) (xy 348.210886 -415.005012) (xy 349.074486 -415.005012)
			(xy 349.101741 -415.005434) (xy 349.155696 -415.01319) (xy 349.207999 -415.028545) (xy 349.257583 -415.051188)
			(xy 349.303441 -415.080657) (xy 349.344637 -415.116353) (xy 349.380334 -415.157548) (xy 349.409805 -415.203405)
			(xy 349.43245 -415.252988) (xy 349.447807 -415.30529) (xy 349.455565 -415.359245) (xy 349.455565 -415.413753)
			(xy 350.893075 -415.413753) (xy 350.893075 -415.359247) (xy 350.900833 -415.305297) (xy 350.916189 -415.253)
			(xy 350.938832 -415.203421) (xy 350.968301 -415.157569) (xy 351.003996 -415.116377) (xy 351.045189 -415.080686)
			(xy 351.091043 -415.05122) (xy 351.140624 -415.02858) (xy 351.192922 -415.013227) (xy 351.246873 -415.005474)
			(xy 351.274126 -415.005012) (xy 352.137726 -415.005012) (xy 352.164977 -415.00546) (xy 352.218925 -415.01322)
			(xy 352.27122 -415.028578) (xy 352.320796 -415.051222) (xy 352.366646 -415.08069) (xy 352.407835 -415.116383)
			(xy 352.443526 -415.157575) (xy 352.472991 -415.203427) (xy 352.495631 -415.253005) (xy 352.510986 -415.3053)
			(xy 352.518742 -415.359249) (xy 352.518742 -415.413751) (xy 352.518742 -415.413752) (xy 372.044675 -415.413752)
			(xy 372.044675 -415.359248) (xy 372.052432 -415.305298) (xy 372.067789 -415.253001) (xy 372.090432 -415.203422)
			(xy 372.1199 -415.15757) (xy 372.155594 -415.116379) (xy 372.196788 -415.080687) (xy 372.242641 -415.051221)
			(xy 372.292221 -415.028581) (xy 372.344519 -415.013228) (xy 372.39847 -415.005474) (xy 372.425722 -415.005012)
			(xy 373.289322 -415.005012) (xy 373.316574 -415.005459) (xy 373.370522 -415.013219) (xy 373.422817 -415.028577)
			(xy 373.472394 -415.05122) (xy 373.518244 -415.080689) (xy 373.559434 -415.116382) (xy 373.595125 -415.157574)
			(xy 373.62459 -415.203426) (xy 373.647231 -415.253004) (xy 373.662586 -415.3053) (xy 373.670342 -415.359248)
			(xy 373.670342 -415.413748) (xy 375.107998 -415.413748) (xy 375.107998 -415.359252) (xy 375.115753 -415.30531)
			(xy 375.131106 -415.253022) (xy 375.153743 -415.203449) (xy 375.183204 -415.157603) (xy 375.218889 -415.116416)
			(xy 375.260073 -415.080727) (xy 375.305916 -415.051261) (xy 375.355486 -415.028619) (xy 375.407773 -415.013261)
			(xy 375.461714 -415.005501) (xy 375.488962 -415.005012) (xy 376.352562 -415.005012) (xy 376.379818 -415.005432)
			(xy 376.433776 -415.013185) (xy 376.486081 -415.028539) (xy 376.535669 -415.05118) (xy 376.581529 -415.080649)
			(xy 376.622729 -415.116345) (xy 376.658428 -415.15754) (xy 376.687901 -415.203398) (xy 376.710548 -415.252983)
			(xy 376.725907 -415.305287) (xy 376.733665 -415.359244) (xy 376.733665 -415.413752) (xy 378.171175 -415.413752)
			(xy 378.171175 -415.359248) (xy 378.178932 -415.3053) (xy 378.194287 -415.253005) (xy 378.216929 -415.203427)
			(xy 378.246395 -415.157576) (xy 378.282087 -415.116386) (xy 378.323278 -415.080694) (xy 378.369129 -415.051228)
			(xy 378.418707 -415.028587) (xy 378.471002 -415.013231) (xy 378.52495 -415.005475) (xy 378.552202 -415.005012)
			(xy 379.415802 -415.005012) (xy 379.443055 -415.005458) (xy 379.497005 -415.013215) (xy 379.549302 -415.028571)
			(xy 379.598882 -415.051214) (xy 379.644734 -415.080682) (xy 379.685926 -415.116375) (xy 379.72162 -415.157567)
			(xy 379.751087 -415.20342) (xy 379.773729 -415.253) (xy 379.789085 -415.305297) (xy 379.796842 -415.359247)
			(xy 379.796842 -415.413753) (xy 381.234375 -415.413753) (xy 381.234375 -415.359247) (xy 381.242133 -415.305295)
			(xy 381.25749 -415.252996) (xy 381.280135 -415.203416) (xy 381.309605 -415.157563) (xy 381.345301 -415.116372)
			(xy 381.386497 -415.08068) (xy 381.432353 -415.051215) (xy 381.481936 -415.028576) (xy 381.534236 -415.013224)
			(xy 381.588189 -415.005472) (xy 381.615442 -415.005012) (xy 382.479042 -415.005012) (xy 382.506293 -415.005461)
			(xy 382.560239 -415.013222) (xy 382.612531 -415.028582) (xy 382.662106 -415.051227) (xy 382.707953 -415.080696)
			(xy 382.749141 -415.116389) (xy 382.784829 -415.15758) (xy 382.814293 -415.203431) (xy 382.836933 -415.253008)
			(xy 382.852286 -415.305302) (xy 382.860042 -415.359249) (xy 382.860042 -415.413749) (xy 384.297698 -415.413749)
			(xy 384.297698 -415.359251) (xy 384.305454 -415.305308) (xy 384.320807 -415.253017) (xy 384.343446 -415.203444)
			(xy 384.372909 -415.157597) (xy 384.408597 -415.116409) (xy 384.449782 -415.08072) (xy 384.495628 -415.051254)
			(xy 384.5452 -415.028613) (xy 384.59749 -415.013258) (xy 384.651433 -415.005499) (xy 384.678682 -415.005012)
			(xy 385.542282 -415.005012) (xy 385.569537 -415.005434) (xy 385.623493 -415.013189) (xy 385.675796 -415.028544)
			(xy 385.725381 -415.051187) (xy 385.771239 -415.080656) (xy 385.812436 -415.116352) (xy 385.848133 -415.157547)
			(xy 385.877604 -415.203403) (xy 385.900249 -415.252987) (xy 385.915607 -415.305289) (xy 385.923365 -415.359245)
			(xy 385.923365 -415.413752) (xy 387.360875 -415.413752) (xy 387.360875 -415.359248) (xy 387.368632 -415.305298)
			(xy 387.383989 -415.253001) (xy 387.406632 -415.203422) (xy 387.4361 -415.15757) (xy 387.471794 -415.116379)
			(xy 387.512988 -415.080687) (xy 387.558841 -415.051221) (xy 387.608421 -415.028581) (xy 387.660719 -415.013228)
			(xy 387.71467 -415.005474) (xy 387.741922 -415.005012) (xy 388.605522 -415.005012) (xy 388.632774 -415.005459)
			(xy 388.686722 -415.013219) (xy 388.739017 -415.028577) (xy 388.788594 -415.05122) (xy 388.834444 -415.080689)
			(xy 388.875634 -415.116382) (xy 388.911325 -415.157574) (xy 388.94079 -415.203426) (xy 388.963431 -415.253004)
			(xy 388.978786 -415.3053) (xy 388.986542 -415.359248) (xy 388.986542 -415.413748) (xy 390.424198 -415.413748)
			(xy 390.424198 -415.359252) (xy 390.431953 -415.30531) (xy 390.447306 -415.253022) (xy 390.469943 -415.203449)
			(xy 390.499404 -415.157603) (xy 390.535089 -415.116416) (xy 390.576273 -415.080727) (xy 390.622116 -415.051261)
			(xy 390.671686 -415.028619) (xy 390.723973 -415.013261) (xy 390.777914 -415.005501) (xy 390.805162 -415.005012)
			(xy 391.668762 -415.005012) (xy 391.696018 -415.005432) (xy 391.749976 -415.013185) (xy 391.802281 -415.028539)
			(xy 391.851869 -415.05118) (xy 391.897729 -415.080649) (xy 391.938929 -415.116345) (xy 391.974628 -415.15754)
			(xy 392.004101 -415.203398) (xy 392.026748 -415.252983) (xy 392.042107 -415.305287) (xy 392.049865 -415.359244)
			(xy 392.049865 -415.413752) (xy 393.487375 -415.413752) (xy 393.487375 -415.359248) (xy 393.495132 -415.3053)
			(xy 393.510487 -415.253005) (xy 393.533129 -415.203427) (xy 393.562595 -415.157576) (xy 393.598287 -415.116386)
			(xy 393.639478 -415.080694) (xy 393.685329 -415.051228) (xy 393.734907 -415.028587) (xy 393.787202 -415.013231)
			(xy 393.84115 -415.005475) (xy 393.868402 -415.005012) (xy 394.732002 -415.005012) (xy 394.759255 -415.005458)
			(xy 394.813205 -415.013215) (xy 394.865502 -415.028571) (xy 394.915082 -415.051214) (xy 394.960934 -415.080682)
			(xy 395.002126 -415.116375) (xy 395.03782 -415.157567) (xy 395.067287 -415.20342) (xy 395.089929 -415.253)
			(xy 395.105285 -415.305297) (xy 395.113042 -415.359247) (xy 395.113042 -415.413753) (xy 396.550575 -415.413753)
			(xy 396.550575 -415.359247) (xy 396.558333 -415.305295) (xy 396.57369 -415.252996) (xy 396.596335 -415.203416)
			(xy 396.625805 -415.157563) (xy 396.661501 -415.116372) (xy 396.702697 -415.08068) (xy 396.748553 -415.051215)
			(xy 396.798136 -415.028576) (xy 396.850436 -415.013224) (xy 396.904389 -415.005472) (xy 396.931642 -415.005012)
			(xy 397.795242 -415.005012) (xy 397.822493 -415.005461) (xy 397.876439 -415.013222) (xy 397.928731 -415.028582)
			(xy 397.978306 -415.051227) (xy 398.024153 -415.080696) (xy 398.065341 -415.116389) (xy 398.101029 -415.15758)
			(xy 398.130493 -415.203431) (xy 398.153133 -415.253008) (xy 398.168486 -415.305302) (xy 398.176242 -415.359249)
			(xy 398.176242 -415.413749) (xy 399.613898 -415.413749) (xy 399.613898 -415.359251) (xy 399.621654 -415.305308)
			(xy 399.637007 -415.253017) (xy 399.659646 -415.203444) (xy 399.689109 -415.157597) (xy 399.724797 -415.116409)
			(xy 399.765982 -415.08072) (xy 399.811828 -415.051254) (xy 399.8614 -415.028613) (xy 399.91369 -415.013258)
			(xy 399.967633 -415.005499) (xy 399.994882 -415.005012) (xy 400.858482 -415.005012) (xy 400.885737 -415.005434)
			(xy 400.939693 -415.013189) (xy 400.991996 -415.028544) (xy 401.041581 -415.051187) (xy 401.087439 -415.080656)
			(xy 401.128636 -415.116352) (xy 401.164333 -415.157547) (xy 401.193804 -415.203403) (xy 401.216449 -415.252987)
			(xy 401.231807 -415.305289) (xy 401.239565 -415.359245) (xy 401.239565 -415.413752) (xy 402.677075 -415.413752)
			(xy 402.677075 -415.359248) (xy 402.684832 -415.305298) (xy 402.700189 -415.253001) (xy 402.722832 -415.203422)
			(xy 402.7523 -415.15757) (xy 402.787994 -415.116379) (xy 402.829188 -415.080687) (xy 402.875041 -415.051221)
			(xy 402.924621 -415.028581) (xy 402.976919 -415.013228) (xy 403.03087 -415.005474) (xy 403.058122 -415.005012)
			(xy 403.921722 -415.005012) (xy 403.948974 -415.005459) (xy 404.002922 -415.013219) (xy 404.055217 -415.028577)
			(xy 404.104794 -415.05122) (xy 404.150644 -415.080689) (xy 404.191834 -415.116382) (xy 404.227525 -415.157574)
			(xy 404.25699 -415.203426) (xy 404.279631 -415.253004) (xy 404.294986 -415.3053) (xy 404.302742 -415.359248)
			(xy 404.302742 -415.413748) (xy 405.740398 -415.413748) (xy 405.740398 -415.359252) (xy 405.748153 -415.30531)
			(xy 405.763506 -415.253022) (xy 405.786143 -415.203449) (xy 405.815604 -415.157603) (xy 405.851289 -415.116416)
			(xy 405.892473 -415.080727) (xy 405.938316 -415.051261) (xy 405.987886 -415.028619) (xy 406.040173 -415.013261)
			(xy 406.094114 -415.005501) (xy 406.121362 -415.005012) (xy 406.984962 -415.005012) (xy 407.012218 -415.005432)
			(xy 407.066176 -415.013185) (xy 407.118481 -415.028539) (xy 407.168069 -415.05118) (xy 407.213929 -415.080649)
			(xy 407.255129 -415.116345) (xy 407.290828 -415.15754) (xy 407.320301 -415.203398) (xy 407.342948 -415.252983)
			(xy 407.358307 -415.305287) (xy 407.366065 -415.359244) (xy 407.366065 -415.413752) (xy 408.803575 -415.413752)
			(xy 408.803575 -415.359248) (xy 408.811332 -415.3053) (xy 408.826687 -415.253005) (xy 408.849329 -415.203427)
			(xy 408.878795 -415.157576) (xy 408.914487 -415.116386) (xy 408.955678 -415.080694) (xy 409.001529 -415.051228)
			(xy 409.051107 -415.028587) (xy 409.103402 -415.013231) (xy 409.15735 -415.005475) (xy 409.184602 -415.005012)
			(xy 410.048202 -415.005012) (xy 410.075455 -415.005458) (xy 410.129405 -415.013215) (xy 410.181702 -415.028571)
			(xy 410.231282 -415.051214) (xy 410.277134 -415.080682) (xy 410.318326 -415.116375) (xy 410.35402 -415.157567)
			(xy 410.383487 -415.20342) (xy 410.406129 -415.253) (xy 410.421485 -415.305297) (xy 410.429242 -415.359247)
			(xy 410.429242 -415.413753) (xy 411.866775 -415.413753) (xy 411.866775 -415.359247) (xy 411.874533 -415.305295)
			(xy 411.88989 -415.252996) (xy 411.912535 -415.203416) (xy 411.942005 -415.157563) (xy 411.977701 -415.116372)
			(xy 412.018897 -415.08068) (xy 412.064753 -415.051215) (xy 412.114336 -415.028576) (xy 412.166636 -415.013224)
			(xy 412.220589 -415.005472) (xy 412.247842 -415.005012) (xy 413.111442 -415.005012) (xy 413.138693 -415.005461)
			(xy 413.192639 -415.013222) (xy 413.244931 -415.028582) (xy 413.294506 -415.051227) (xy 413.340353 -415.080696)
			(xy 413.381541 -415.116389) (xy 413.417229 -415.15758) (xy 413.446693 -415.203431) (xy 413.469333 -415.253008)
			(xy 413.484686 -415.305302) (xy 413.492442 -415.359249) (xy 413.492442 -415.413749) (xy 414.930098 -415.413749)
			(xy 414.930098 -415.359251) (xy 414.937854 -415.305308) (xy 414.953207 -415.253017) (xy 414.975846 -415.203444)
			(xy 415.005309 -415.157597) (xy 415.040997 -415.116409) (xy 415.082182 -415.08072) (xy 415.128028 -415.051254)
			(xy 415.1776 -415.028613) (xy 415.22989 -415.013258) (xy 415.283833 -415.005499) (xy 415.311082 -415.005012)
			(xy 416.174682 -415.005012) (xy 416.201937 -415.005434) (xy 416.255893 -415.013189) (xy 416.308196 -415.028544)
			(xy 416.357781 -415.051187) (xy 416.403639 -415.080656) (xy 416.444836 -415.116352) (xy 416.480533 -415.157547)
			(xy 416.510004 -415.203403) (xy 416.532649 -415.252987) (xy 416.548007 -415.305289) (xy 416.555765 -415.359245)
			(xy 416.555765 -415.413752) (xy 417.993275 -415.413752) (xy 417.993275 -415.359248) (xy 418.001032 -415.305298)
			(xy 418.016389 -415.253001) (xy 418.039032 -415.203422) (xy 418.0685 -415.15757) (xy 418.104194 -415.116379)
			(xy 418.145388 -415.080687) (xy 418.191241 -415.051221) (xy 418.240821 -415.028581) (xy 418.293119 -415.013228)
			(xy 418.34707 -415.005474) (xy 418.374322 -415.005012) (xy 419.237922 -415.005012) (xy 419.265174 -415.005459)
			(xy 419.319122 -415.013219) (xy 419.371417 -415.028577) (xy 419.420994 -415.05122) (xy 419.466844 -415.080689)
			(xy 419.508034 -415.116382) (xy 419.543725 -415.157574) (xy 419.57319 -415.203426) (xy 419.595831 -415.253004)
			(xy 419.611186 -415.3053) (xy 419.618942 -415.359248) (xy 419.618942 -415.413752) (xy 419.611186 -415.4677)
			(xy 419.595831 -415.519996) (xy 419.57319 -415.569574) (xy 419.543725 -415.615426) (xy 419.508034 -415.656618)
			(xy 419.466844 -415.692311) (xy 419.420994 -415.72178) (xy 419.371417 -415.744423) (xy 419.319122 -415.759781)
			(xy 419.265174 -415.767541) (xy 419.237922 -415.768028) (xy 418.374322 -415.768028) (xy 418.34707 -415.767526)
			(xy 418.293119 -415.759772) (xy 418.240821 -415.744419) (xy 418.191241 -415.721779) (xy 418.145388 -415.692313)
			(xy 418.104194 -415.656621) (xy 418.0685 -415.61543) (xy 418.039032 -415.569578) (xy 418.016389 -415.519999)
			(xy 418.001032 -415.467702) (xy 417.993275 -415.413752) (xy 416.555765 -415.413752) (xy 416.555765 -415.413755)
			(xy 416.548007 -415.467711) (xy 416.532649 -415.520013) (xy 416.510004 -415.569597) (xy 416.480533 -415.615453)
			(xy 416.444836 -415.656648) (xy 416.403639 -415.692344) (xy 416.357781 -415.721813) (xy 416.308196 -415.744456)
			(xy 416.255893 -415.759811) (xy 416.201937 -415.767566) (xy 416.174682 -415.768028) (xy 415.311082 -415.768028)
			(xy 415.283833 -415.767501) (xy 415.22989 -415.759742) (xy 415.1776 -415.744387) (xy 415.128028 -415.721746)
			(xy 415.082182 -415.69228) (xy 415.040997 -415.656591) (xy 415.005309 -415.615403) (xy 414.975846 -415.569556)
			(xy 414.953207 -415.519983) (xy 414.937854 -415.467692) (xy 414.930098 -415.413749) (xy 413.492442 -415.413749)
			(xy 413.492442 -415.413751) (xy 413.484686 -415.467698) (xy 413.469333 -415.519992) (xy 413.446693 -415.569569)
			(xy 413.417229 -415.61542) (xy 413.381541 -415.656611) (xy 413.340353 -415.692304) (xy 413.294506 -415.721773)
			(xy 413.244931 -415.744418) (xy 413.192639 -415.759778) (xy 413.138693 -415.767539) (xy 413.111442 -415.768028)
			(xy 412.247842 -415.768028) (xy 412.220589 -415.767528) (xy 412.166636 -415.759776) (xy 412.114336 -415.744424)
			(xy 412.064753 -415.721785) (xy 412.018897 -415.69232) (xy 411.977701 -415.656628) (xy 411.942005 -415.615437)
			(xy 411.912535 -415.569584) (xy 411.88989 -415.520004) (xy 411.874533 -415.467705) (xy 411.866775 -415.413753)
			(xy 410.429242 -415.413753) (xy 410.421485 -415.467703) (xy 410.406129 -415.52) (xy 410.383487 -415.56958)
			(xy 410.35402 -415.615433) (xy 410.318326 -415.656625) (xy 410.277134 -415.692318) (xy 410.231282 -415.721786)
			(xy 410.181702 -415.744429) (xy 410.129405 -415.759785) (xy 410.075455 -415.767542) (xy 410.048202 -415.768028)
			(xy 409.184602 -415.768028) (xy 409.15735 -415.767525) (xy 409.103402 -415.759769) (xy 409.051107 -415.744413)
			(xy 409.001529 -415.721772) (xy 408.955678 -415.692306) (xy 408.914487 -415.656614) (xy 408.878795 -415.615424)
			(xy 408.849329 -415.569573) (xy 408.826687 -415.519995) (xy 408.811332 -415.4677) (xy 408.803575 -415.413752)
			(xy 407.366065 -415.413752) (xy 407.366065 -415.413756) (xy 407.358307 -415.467713) (xy 407.342948 -415.520017)
			(xy 407.320301 -415.569602) (xy 407.290828 -415.61546) (xy 407.255129 -415.656655) (xy 407.213929 -415.692351)
			(xy 407.168069 -415.72182) (xy 407.118481 -415.744461) (xy 407.066176 -415.759815) (xy 407.012218 -415.767568)
			(xy 406.984962 -415.768028) (xy 406.121362 -415.768028) (xy 406.094114 -415.767499) (xy 406.040173 -415.759739)
			(xy 405.987886 -415.744381) (xy 405.938316 -415.721739) (xy 405.892473 -415.692273) (xy 405.851289 -415.656584)
			(xy 405.815604 -415.615397) (xy 405.786143 -415.569551) (xy 405.763506 -415.519978) (xy 405.748153 -415.46769)
			(xy 405.740398 -415.413748) (xy 404.302742 -415.413748) (xy 404.302742 -415.413752) (xy 404.294986 -415.4677)
			(xy 404.279631 -415.519996) (xy 404.25699 -415.569574) (xy 404.227525 -415.615426) (xy 404.191834 -415.656618)
			(xy 404.150644 -415.692311) (xy 404.104794 -415.72178) (xy 404.055217 -415.744423) (xy 404.002922 -415.759781)
			(xy 403.948974 -415.767541) (xy 403.921722 -415.768028) (xy 403.058122 -415.768028) (xy 403.03087 -415.767526)
			(xy 402.976919 -415.759772) (xy 402.924621 -415.744419) (xy 402.875041 -415.721779) (xy 402.829188 -415.692313)
			(xy 402.787994 -415.656621) (xy 402.7523 -415.61543) (xy 402.722832 -415.569578) (xy 402.700189 -415.519999)
			(xy 402.684832 -415.467702) (xy 402.677075 -415.413752) (xy 401.239565 -415.413752) (xy 401.239565 -415.413755)
			(xy 401.231807 -415.467711) (xy 401.216449 -415.520013) (xy 401.193804 -415.569597) (xy 401.164333 -415.615453)
			(xy 401.128636 -415.656648) (xy 401.087439 -415.692344) (xy 401.041581 -415.721813) (xy 400.991996 -415.744456)
			(xy 400.939693 -415.759811) (xy 400.885737 -415.767566) (xy 400.858482 -415.768028) (xy 399.994882 -415.768028)
			(xy 399.967633 -415.767501) (xy 399.91369 -415.759742) (xy 399.8614 -415.744387) (xy 399.811828 -415.721746)
			(xy 399.765982 -415.69228) (xy 399.724797 -415.656591) (xy 399.689109 -415.615403) (xy 399.659646 -415.569556)
			(xy 399.637007 -415.519983) (xy 399.621654 -415.467692) (xy 399.613898 -415.413749) (xy 398.176242 -415.413749)
			(xy 398.176242 -415.413751) (xy 398.168486 -415.467698) (xy 398.153133 -415.519992) (xy 398.130493 -415.569569)
			(xy 398.101029 -415.61542) (xy 398.065341 -415.656611) (xy 398.024153 -415.692304) (xy 397.978306 -415.721773)
			(xy 397.928731 -415.744418) (xy 397.876439 -415.759778) (xy 397.822493 -415.767539) (xy 397.795242 -415.768028)
			(xy 396.931642 -415.768028) (xy 396.904389 -415.767528) (xy 396.850436 -415.759776) (xy 396.798136 -415.744424)
			(xy 396.748553 -415.721785) (xy 396.702697 -415.69232) (xy 396.661501 -415.656628) (xy 396.625805 -415.615437)
			(xy 396.596335 -415.569584) (xy 396.57369 -415.520004) (xy 396.558333 -415.467705) (xy 396.550575 -415.413753)
			(xy 395.113042 -415.413753) (xy 395.105285 -415.467703) (xy 395.089929 -415.52) (xy 395.067287 -415.56958)
			(xy 395.03782 -415.615433) (xy 395.002126 -415.656625) (xy 394.960934 -415.692318) (xy 394.915082 -415.721786)
			(xy 394.865502 -415.744429) (xy 394.813205 -415.759785) (xy 394.759255 -415.767542) (xy 394.732002 -415.768028)
			(xy 393.868402 -415.768028) (xy 393.84115 -415.767525) (xy 393.787202 -415.759769) (xy 393.734907 -415.744413)
			(xy 393.685329 -415.721772) (xy 393.639478 -415.692306) (xy 393.598287 -415.656614) (xy 393.562595 -415.615424)
			(xy 393.533129 -415.569573) (xy 393.510487 -415.519995) (xy 393.495132 -415.4677) (xy 393.487375 -415.413752)
			(xy 392.049865 -415.413752) (xy 392.049865 -415.413756) (xy 392.042107 -415.467713) (xy 392.026748 -415.520017)
			(xy 392.004101 -415.569602) (xy 391.974628 -415.61546) (xy 391.938929 -415.656655) (xy 391.897729 -415.692351)
			(xy 391.851869 -415.72182) (xy 391.802281 -415.744461) (xy 391.749976 -415.759815) (xy 391.696018 -415.767568)
			(xy 391.668762 -415.768028) (xy 390.805162 -415.768028) (xy 390.777914 -415.767499) (xy 390.723973 -415.759739)
			(xy 390.671686 -415.744381) (xy 390.622116 -415.721739) (xy 390.576273 -415.692273) (xy 390.535089 -415.656584)
			(xy 390.499404 -415.615397) (xy 390.469943 -415.569551) (xy 390.447306 -415.519978) (xy 390.431953 -415.46769)
			(xy 390.424198 -415.413748) (xy 388.986542 -415.413748) (xy 388.986542 -415.413752) (xy 388.978786 -415.4677)
			(xy 388.963431 -415.519996) (xy 388.94079 -415.569574) (xy 388.911325 -415.615426) (xy 388.875634 -415.656618)
			(xy 388.834444 -415.692311) (xy 388.788594 -415.72178) (xy 388.739017 -415.744423) (xy 388.686722 -415.759781)
			(xy 388.632774 -415.767541) (xy 388.605522 -415.768028) (xy 387.741922 -415.768028) (xy 387.71467 -415.767526)
			(xy 387.660719 -415.759772) (xy 387.608421 -415.744419) (xy 387.558841 -415.721779) (xy 387.512988 -415.692313)
			(xy 387.471794 -415.656621) (xy 387.4361 -415.61543) (xy 387.406632 -415.569578) (xy 387.383989 -415.519999)
			(xy 387.368632 -415.467702) (xy 387.360875 -415.413752) (xy 385.923365 -415.413752) (xy 385.923365 -415.413755)
			(xy 385.915607 -415.467711) (xy 385.900249 -415.520013) (xy 385.877604 -415.569597) (xy 385.848133 -415.615453)
			(xy 385.812436 -415.656648) (xy 385.771239 -415.692344) (xy 385.725381 -415.721813) (xy 385.675796 -415.744456)
			(xy 385.623493 -415.759811) (xy 385.569537 -415.767566) (xy 385.542282 -415.768028) (xy 384.678682 -415.768028)
			(xy 384.651433 -415.767501) (xy 384.59749 -415.759742) (xy 384.5452 -415.744387) (xy 384.495628 -415.721746)
			(xy 384.449782 -415.69228) (xy 384.408597 -415.656591) (xy 384.372909 -415.615403) (xy 384.343446 -415.569556)
			(xy 384.320807 -415.519983) (xy 384.305454 -415.467692) (xy 384.297698 -415.413749) (xy 382.860042 -415.413749)
			(xy 382.860042 -415.413751) (xy 382.852286 -415.467698) (xy 382.836933 -415.519992) (xy 382.814293 -415.569569)
			(xy 382.784829 -415.61542) (xy 382.749141 -415.656611) (xy 382.707953 -415.692304) (xy 382.662106 -415.721773)
			(xy 382.612531 -415.744418) (xy 382.560239 -415.759778) (xy 382.506293 -415.767539) (xy 382.479042 -415.768028)
			(xy 381.615442 -415.768028) (xy 381.588189 -415.767528) (xy 381.534236 -415.759776) (xy 381.481936 -415.744424)
			(xy 381.432353 -415.721785) (xy 381.386497 -415.69232) (xy 381.345301 -415.656628) (xy 381.309605 -415.615437)
			(xy 381.280135 -415.569584) (xy 381.25749 -415.520004) (xy 381.242133 -415.467705) (xy 381.234375 -415.413753)
			(xy 379.796842 -415.413753) (xy 379.789085 -415.467703) (xy 379.773729 -415.52) (xy 379.751087 -415.56958)
			(xy 379.72162 -415.615433) (xy 379.685926 -415.656625) (xy 379.644734 -415.692318) (xy 379.598882 -415.721786)
			(xy 379.549302 -415.744429) (xy 379.497005 -415.759785) (xy 379.443055 -415.767542) (xy 379.415802 -415.768028)
			(xy 378.552202 -415.768028) (xy 378.52495 -415.767525) (xy 378.471002 -415.759769) (xy 378.418707 -415.744413)
			(xy 378.369129 -415.721772) (xy 378.323278 -415.692306) (xy 378.282087 -415.656614) (xy 378.246395 -415.615424)
			(xy 378.216929 -415.569573) (xy 378.194287 -415.519995) (xy 378.178932 -415.4677) (xy 378.171175 -415.413752)
			(xy 376.733665 -415.413752) (xy 376.733665 -415.413756) (xy 376.725907 -415.467713) (xy 376.710548 -415.520017)
			(xy 376.687901 -415.569602) (xy 376.658428 -415.61546) (xy 376.622729 -415.656655) (xy 376.581529 -415.692351)
			(xy 376.535669 -415.72182) (xy 376.486081 -415.744461) (xy 376.433776 -415.759815) (xy 376.379818 -415.767568)
			(xy 376.352562 -415.768028) (xy 375.488962 -415.768028) (xy 375.461714 -415.767499) (xy 375.407773 -415.759739)
			(xy 375.355486 -415.744381) (xy 375.305916 -415.721739) (xy 375.260073 -415.692273) (xy 375.218889 -415.656584)
			(xy 375.183204 -415.615397) (xy 375.153743 -415.569551) (xy 375.131106 -415.519978) (xy 375.115753 -415.46769)
			(xy 375.107998 -415.413748) (xy 373.670342 -415.413748) (xy 373.670342 -415.413752) (xy 373.662586 -415.4677)
			(xy 373.647231 -415.519996) (xy 373.62459 -415.569574) (xy 373.595125 -415.615426) (xy 373.559434 -415.656618)
			(xy 373.518244 -415.692311) (xy 373.472394 -415.72178) (xy 373.422817 -415.744423) (xy 373.370522 -415.759781)
			(xy 373.316574 -415.767541) (xy 373.289322 -415.768028) (xy 372.425722 -415.768028) (xy 372.39847 -415.767526)
			(xy 372.344519 -415.759772) (xy 372.292221 -415.744419) (xy 372.242641 -415.721779) (xy 372.196788 -415.692313)
			(xy 372.155594 -415.656621) (xy 372.1199 -415.61543) (xy 372.090432 -415.569578) (xy 372.067789 -415.519999)
			(xy 372.052432 -415.467702) (xy 372.044675 -415.413752) (xy 352.518742 -415.413752) (xy 352.510986 -415.4677)
			(xy 352.495631 -415.519995) (xy 352.472991 -415.569573) (xy 352.443526 -415.615425) (xy 352.407835 -415.656617)
			(xy 352.366646 -415.69231) (xy 352.320796 -415.721778) (xy 352.27122 -415.744422) (xy 352.218925 -415.75978)
			(xy 352.164977 -415.76754) (xy 352.137726 -415.768028) (xy 351.274126 -415.768028) (xy 351.246873 -415.767526)
			(xy 351.192922 -415.759773) (xy 351.140624 -415.74442) (xy 351.091043 -415.72178) (xy 351.045189 -415.692314)
			(xy 351.003996 -415.656623) (xy 350.968301 -415.615431) (xy 350.938832 -415.569579) (xy 350.916189 -415.52)
			(xy 350.900833 -415.467703) (xy 350.893075 -415.413753) (xy 349.455565 -415.413753) (xy 349.455565 -415.413755)
			(xy 349.447807 -415.46771) (xy 349.43245 -415.520012) (xy 349.409805 -415.569595) (xy 349.380334 -415.615452)
			(xy 349.344637 -415.656647) (xy 349.303441 -415.692343) (xy 349.257583 -415.721812) (xy 349.207999 -415.744455)
			(xy 349.155696 -415.75981) (xy 349.101741 -415.767566) (xy 349.074486 -415.768028) (xy 348.210886 -415.768028)
			(xy 348.183637 -415.767501) (xy 348.129694 -415.759743) (xy 348.077403 -415.744388) (xy 348.02783 -415.721747)
			(xy 347.981984 -415.692282) (xy 347.940798 -415.656592) (xy 347.90511 -415.615404) (xy 347.875646 -415.569557)
			(xy 347.853008 -415.519984) (xy 347.837654 -415.467693) (xy 347.829898 -415.413749) (xy 346.392242 -415.413749)
			(xy 346.392242 -415.413751) (xy 346.384487 -415.467697) (xy 346.369133 -415.519991) (xy 346.346494 -415.569568)
			(xy 346.31703 -415.615418) (xy 346.281342 -415.656609) (xy 346.240155 -415.692303) (xy 346.194308 -415.721772)
			(xy 346.144734 -415.744417) (xy 346.092442 -415.759777) (xy 346.038497 -415.767539) (xy 346.011246 -415.768028)
			(xy 345.147646 -415.768028) (xy 345.120392 -415.767528) (xy 345.066439 -415.759777) (xy 345.014139 -415.744425)
			(xy 344.964555 -415.721787) (xy 344.918699 -415.692321) (xy 344.877503 -415.65663) (xy 344.841806 -415.615438)
			(xy 344.812335 -415.569585) (xy 344.789691 -415.520004) (xy 344.774333 -415.467706) (xy 344.766575 -415.413754)
			(xy 343.329042 -415.413754) (xy 343.321285 -415.467702) (xy 343.30593 -415.519999) (xy 343.283288 -415.569579)
			(xy 343.253821 -415.615431) (xy 343.218128 -415.656624) (xy 343.176936 -415.692317) (xy 343.131084 -415.721785)
			(xy 343.081505 -415.744428) (xy 343.029208 -415.759784) (xy 342.975258 -415.767542) (xy 342.948006 -415.768028)
			(xy 342.084406 -415.768028) (xy 342.057154 -415.767525) (xy 342.003206 -415.759769) (xy 341.95091 -415.744415)
			(xy 341.901331 -415.721774) (xy 341.85548 -415.692307) (xy 341.814289 -415.656616) (xy 341.778596 -415.615425)
			(xy 341.749129 -415.569574) (xy 341.726488 -415.519996) (xy 341.711132 -415.4677) (xy 341.703375 -415.413752)
			(xy 340.265865 -415.413752) (xy 340.265865 -415.413756) (xy 340.258107 -415.467713) (xy 340.242748 -415.520016)
			(xy 340.220102 -415.569601) (xy 340.190629 -415.615458) (xy 340.15493 -415.656654) (xy 340.113731 -415.69235)
			(xy 340.067871 -415.721818) (xy 340.018284 -415.74446) (xy 339.965979 -415.759814) (xy 339.912022 -415.767567)
			(xy 339.884766 -415.768028) (xy 339.021166 -415.768028) (xy 338.993918 -415.767499) (xy 338.939977 -415.759739)
			(xy 338.887689 -415.744382) (xy 338.838118 -415.72174) (xy 338.792275 -415.692275) (xy 338.751091 -415.656585)
			(xy 338.715405 -415.615398) (xy 338.685943 -415.569552) (xy 338.663306 -415.519979) (xy 338.647953 -415.46769)
			(xy 338.640198 -415.413748) (xy 337.202542 -415.413748) (xy 337.202542 -415.413751) (xy 337.194786 -415.4677)
			(xy 337.179431 -415.519995) (xy 337.156791 -415.569573) (xy 337.127326 -415.615425) (xy 337.091635 -415.656617)
			(xy 337.050446 -415.69231) (xy 337.004596 -415.721778) (xy 336.95502 -415.744422) (xy 336.902725 -415.75978)
			(xy 336.848777 -415.76754) (xy 336.821526 -415.768028) (xy 335.957926 -415.768028) (xy 335.930673 -415.767526)
			(xy 335.876722 -415.759773) (xy 335.824424 -415.74442) (xy 335.774843 -415.72178) (xy 335.728989 -415.692314)
			(xy 335.687796 -415.656623) (xy 335.652101 -415.615431) (xy 335.622632 -415.569579) (xy 335.599989 -415.52)
			(xy 335.584633 -415.467703) (xy 335.576875 -415.413753) (xy 334.139365 -415.413753) (xy 334.139365 -415.413755)
			(xy 334.131607 -415.46771) (xy 334.11625 -415.520012) (xy 334.093605 -415.569595) (xy 334.064134 -415.615452)
			(xy 334.028437 -415.656647) (xy 333.987241 -415.692343) (xy 333.941383 -415.721812) (xy 333.891799 -415.744455)
			(xy 333.839496 -415.75981) (xy 333.785541 -415.767566) (xy 333.758286 -415.768028) (xy 332.894686 -415.768028)
			(xy 332.867437 -415.767501) (xy 332.813494 -415.759743) (xy 332.761203 -415.744388) (xy 332.71163 -415.721747)
			(xy 332.665784 -415.692282) (xy 332.624598 -415.656592) (xy 332.58891 -415.615404) (xy 332.559446 -415.569557)
			(xy 332.536808 -415.519984) (xy 332.521454 -415.467693) (xy 332.513698 -415.413749) (xy 331.076042 -415.413749)
			(xy 331.076042 -415.413751) (xy 331.068287 -415.467697) (xy 331.052933 -415.519991) (xy 331.030294 -415.569568)
			(xy 331.00083 -415.615418) (xy 330.965142 -415.656609) (xy 330.923955 -415.692303) (xy 330.878108 -415.721772)
			(xy 330.828534 -415.744417) (xy 330.776242 -415.759777) (xy 330.722297 -415.767539) (xy 330.695046 -415.768028)
			(xy 329.831446 -415.768028) (xy 329.804192 -415.767528) (xy 329.750239 -415.759777) (xy 329.697939 -415.744425)
			(xy 329.648355 -415.721787) (xy 329.602499 -415.692321) (xy 329.561303 -415.65663) (xy 329.525606 -415.615438)
			(xy 329.496135 -415.569585) (xy 329.473491 -415.520004) (xy 329.458133 -415.467706) (xy 329.450375 -415.413754)
			(xy 328.012842 -415.413754) (xy 328.005085 -415.467702) (xy 327.98973 -415.519999) (xy 327.967088 -415.569579)
			(xy 327.937621 -415.615431) (xy 327.901928 -415.656624) (xy 327.860736 -415.692317) (xy 327.814884 -415.721785)
			(xy 327.765305 -415.744428) (xy 327.713008 -415.759784) (xy 327.659058 -415.767542) (xy 327.631806 -415.768028)
			(xy 326.768206 -415.768028) (xy 326.740954 -415.767525) (xy 326.687006 -415.759769) (xy 326.63471 -415.744415)
			(xy 326.585131 -415.721774) (xy 326.53928 -415.692307) (xy 326.498089 -415.656616) (xy 326.462396 -415.615425)
			(xy 326.432929 -415.569574) (xy 326.410288 -415.519996) (xy 326.394932 -415.4677) (xy 326.387175 -415.413752)
			(xy 324.949665 -415.413752) (xy 324.949665 -415.413756) (xy 324.941907 -415.467713) (xy 324.926548 -415.520016)
			(xy 324.903902 -415.569601) (xy 324.874429 -415.615458) (xy 324.83873 -415.656654) (xy 324.797531 -415.69235)
			(xy 324.751671 -415.721818) (xy 324.702084 -415.74446) (xy 324.649779 -415.759814) (xy 324.595822 -415.767567)
			(xy 324.568566 -415.768028) (xy 323.704966 -415.768028) (xy 323.677718 -415.767499) (xy 323.623777 -415.759739)
			(xy 323.571489 -415.744382) (xy 323.521918 -415.72174) (xy 323.476075 -415.692275) (xy 323.434891 -415.656585)
			(xy 323.399205 -415.615398) (xy 323.369743 -415.569552) (xy 323.347106 -415.519979) (xy 323.331753 -415.46769)
			(xy 323.323998 -415.413748) (xy 321.886342 -415.413748) (xy 321.886342 -415.413751) (xy 321.878586 -415.4677)
			(xy 321.863231 -415.519995) (xy 321.840591 -415.569573) (xy 321.811126 -415.615425) (xy 321.775435 -415.656617)
			(xy 321.734246 -415.69231) (xy 321.688396 -415.721778) (xy 321.63882 -415.744422) (xy 321.586525 -415.75978)
			(xy 321.532577 -415.76754) (xy 321.505326 -415.768028) (xy 320.641726 -415.768028) (xy 320.614473 -415.767526)
			(xy 320.560522 -415.759773) (xy 320.508224 -415.74442) (xy 320.458643 -415.72178) (xy 320.412789 -415.692314)
			(xy 320.371596 -415.656623) (xy 320.335901 -415.615431) (xy 320.306432 -415.569579) (xy 320.283789 -415.52)
			(xy 320.268433 -415.467703) (xy 320.260675 -415.413753) (xy 318.823165 -415.413753) (xy 318.823165 -415.413755)
			(xy 318.815407 -415.46771) (xy 318.80005 -415.520012) (xy 318.777405 -415.569595) (xy 318.747934 -415.615452)
			(xy 318.712237 -415.656647) (xy 318.671041 -415.692343) (xy 318.625183 -415.721812) (xy 318.575599 -415.744455)
			(xy 318.523296 -415.75981) (xy 318.469341 -415.767566) (xy 318.442086 -415.768028) (xy 317.578486 -415.768028)
			(xy 317.551237 -415.767501) (xy 317.497294 -415.759743) (xy 317.445003 -415.744388) (xy 317.39543 -415.721747)
			(xy 317.349584 -415.692282) (xy 317.308398 -415.656592) (xy 317.27271 -415.615404) (xy 317.243246 -415.569557)
			(xy 317.220608 -415.519984) (xy 317.205254 -415.467693) (xy 317.197498 -415.413749) (xy 315.759842 -415.413749)
			(xy 315.759842 -415.413751) (xy 315.752087 -415.467697) (xy 315.736733 -415.519991) (xy 315.714094 -415.569568)
			(xy 315.68463 -415.615418) (xy 315.648942 -415.656609) (xy 315.607755 -415.692303) (xy 315.561908 -415.721772)
			(xy 315.512334 -415.744417) (xy 315.460042 -415.759777) (xy 315.406097 -415.767539) (xy 315.378846 -415.768028)
			(xy 314.515246 -415.768028) (xy 314.487992 -415.767528) (xy 314.434039 -415.759777) (xy 314.381739 -415.744425)
			(xy 314.332155 -415.721787) (xy 314.286299 -415.692321) (xy 314.245103 -415.65663) (xy 314.209406 -415.615438)
			(xy 314.179935 -415.569585) (xy 314.157291 -415.520004) (xy 314.141933 -415.467706) (xy 314.134175 -415.413754)
			(xy 312.696642 -415.413754) (xy 312.688885 -415.467702) (xy 312.67353 -415.519999) (xy 312.650888 -415.569579)
			(xy 312.621421 -415.615431) (xy 312.585728 -415.656624) (xy 312.544536 -415.692317) (xy 312.498684 -415.721785)
			(xy 312.449105 -415.744428) (xy 312.396808 -415.759784) (xy 312.342858 -415.767542) (xy 312.315606 -415.768028)
			(xy 311.452006 -415.768028) (xy 311.424754 -415.767525) (xy 311.370806 -415.759769) (xy 311.31851 -415.744415)
			(xy 311.268931 -415.721774) (xy 311.22308 -415.692307) (xy 311.181889 -415.656616) (xy 311.146196 -415.615425)
			(xy 311.116729 -415.569574) (xy 311.094088 -415.519996) (xy 311.078732 -415.4677) (xy 311.070975 -415.413752)
			(xy 309.633465 -415.413752) (xy 309.633465 -415.413756) (xy 309.625707 -415.467713) (xy 309.610348 -415.520016)
			(xy 309.587702 -415.569601) (xy 309.558229 -415.615458) (xy 309.52253 -415.656654) (xy 309.481331 -415.69235)
			(xy 309.435471 -415.721818) (xy 309.385884 -415.74446) (xy 309.333579 -415.759814) (xy 309.279622 -415.767567)
			(xy 309.252366 -415.768028) (xy 308.388766 -415.768028) (xy 308.361518 -415.767499) (xy 308.307577 -415.759739)
			(xy 308.255289 -415.744382) (xy 308.205718 -415.72174) (xy 308.159875 -415.692275) (xy 308.118691 -415.656585)
			(xy 308.083005 -415.615398) (xy 308.053543 -415.569552) (xy 308.030906 -415.519979) (xy 308.015553 -415.46769)
			(xy 308.007798 -415.413748) (xy 306.570142 -415.413748) (xy 306.570142 -415.413751) (xy 306.562386 -415.4677)
			(xy 306.547031 -415.519995) (xy 306.524391 -415.569573) (xy 306.494926 -415.615425) (xy 306.459235 -415.656617)
			(xy 306.418046 -415.69231) (xy 306.372196 -415.721778) (xy 306.32262 -415.744422) (xy 306.270325 -415.75978)
			(xy 306.216377 -415.76754) (xy 306.189126 -415.768028) (xy 305.325526 -415.768028) (xy 305.298273 -415.767526)
			(xy 305.244322 -415.759773) (xy 305.192024 -415.74442) (xy 305.142443 -415.72178) (xy 305.096589 -415.692314)
			(xy 305.055396 -415.656623) (xy 305.019701 -415.615431) (xy 304.990232 -415.569579) (xy 304.967589 -415.52)
			(xy 304.952233 -415.467703) (xy 304.944475 -415.413753) (xy 301.259284 -415.413753) (xy 301.227716 -415.466663)
			(xy 301.125722 -415.622007) (xy 301.017139 -415.772819) (xy 300.902169 -415.918821) (xy 300.781023 -416.05974)
			(xy 300.653927 -416.195318) (xy 300.521116 -416.325302) (xy 300.382835 -416.449451) (xy 300.239342 -416.567537)
			(xy 300.090901 -416.67934) (xy 299.937787 -416.784653) (xy 299.780284 -416.883281) (xy 299.618684 -416.975042)
			(xy 299.453286 -417.059765) (xy 299.284396 -417.137295) (xy 299.112327 -417.207486) (xy 298.937397 -417.27021)
			(xy 298.759931 -417.32535) (xy 298.580257 -417.372803) (xy 298.398708 -417.412483) (xy 298.21562 -417.444315)
			(xy 298.031331 -417.468242) (xy 297.846184 -417.484217) (xy 297.660521 -417.492212) (xy 297.567604 -417.492688)
			(xy 297.567096 -417.492688) (xy 297.470033 -417.492144) (xy 297.276104 -417.483409) (xy 297.082764 -417.465966)
			(xy 296.890402 -417.43985) (xy 296.69941 -417.405115) (xy 296.510171 -417.361829) (xy 296.416476 -417.336478)
			(xy 296.404792 -417.333176) (xy 296.381678 -417.337748) (xy 296.307764 -417.393882) (xy 296.298784 -417.401478)
			(xy 296.288341 -417.422523) (xy 296.287698 -417.434268) (xy 296.287698 -418.439456) (xy 304.944423 -418.439456)
			(xy 304.944423 -418.384944) (xy 304.952181 -418.330986) (xy 304.96754 -418.278681) (xy 304.990186 -418.229095)
			(xy 305.019659 -418.183237) (xy 305.055359 -418.14204) (xy 305.096558 -418.106344) (xy 305.142418 -418.076874)
			(xy 305.192006 -418.054231) (xy 305.244311 -418.038876) (xy 305.29827 -418.031121) (xy 305.325526 -418.03066)
			(xy 306.189126 -418.03066) (xy 306.216374 -418.031212) (xy 306.270314 -418.038971) (xy 306.322601 -418.054327)
			(xy 306.372171 -418.076968) (xy 306.418014 -418.106432) (xy 306.459198 -418.142121) (xy 306.494884 -418.183307)
			(xy 306.524345 -418.229152) (xy 306.546982 -418.278723) (xy 306.562335 -418.331011) (xy 306.57009 -418.384952)
			(xy 306.57009 -418.439448) (xy 306.570089 -418.439452) (xy 308.007746 -418.439452) (xy 308.007746 -418.384948)
			(xy 308.015502 -418.330999) (xy 308.030857 -418.278702) (xy 308.053497 -418.229123) (xy 308.082963 -418.183271)
			(xy 308.118654 -418.142078) (xy 308.159843 -418.106383) (xy 308.205693 -418.076914) (xy 308.25527 -418.054269)
			(xy 308.307565 -418.038909) (xy 308.361514 -418.031148) (xy 308.388766 -418.03066) (xy 309.252366 -418.03066)
			(xy 309.279618 -418.031185) (xy 309.333568 -418.038937) (xy 309.385866 -418.054289) (xy 309.435446 -418.076928)
			(xy 309.4813 -418.106392) (xy 309.522493 -418.142083) (xy 309.558187 -418.183273) (xy 309.587656 -418.229124)
			(xy 309.610299 -418.278702) (xy 309.625655 -418.330999) (xy 309.633413 -418.384948) (xy 309.633413 -418.439452)
			(xy 309.633413 -418.439455) (xy 311.070923 -418.439455) (xy 311.070923 -418.384945) (xy 311.078681 -418.330989)
			(xy 311.094038 -418.278686) (xy 311.116683 -418.229101) (xy 311.146154 -418.183244) (xy 311.181852 -418.142047)
			(xy 311.223049 -418.106351) (xy 311.268906 -418.07688) (xy 311.318491 -418.054236) (xy 311.370794 -418.038879)
			(xy 311.424751 -418.031123) (xy 311.452006 -418.03066) (xy 312.315606 -418.03066) (xy 312.342855 -418.031211)
			(xy 312.396797 -418.038967) (xy 312.449087 -418.054321) (xy 312.498659 -418.076961) (xy 312.544505 -418.106425)
			(xy 312.585691 -418.142113) (xy 312.621379 -418.1833) (xy 312.650842 -418.229146) (xy 312.673481 -418.278719)
			(xy 312.688834 -418.331009) (xy 312.69659 -418.384951) (xy 312.69659 -418.439449) (xy 312.696589 -418.439457)
			(xy 314.134123 -418.439457) (xy 314.134123 -418.384943) (xy 314.141882 -418.330983) (xy 314.157242 -418.278677)
			(xy 314.179889 -418.22909) (xy 314.209364 -418.183231) (xy 314.245066 -418.142033) (xy 314.286267 -418.106337)
			(xy 314.33213 -418.076867) (xy 314.38172 -418.054225) (xy 314.434028 -418.038872) (xy 314.487989 -418.03112)
			(xy 314.515246 -418.03066) (xy 315.378846 -418.03066) (xy 315.406093 -418.031213) (xy 315.460031 -418.038975)
			(xy 315.512316 -418.054332) (xy 315.561883 -418.076974) (xy 315.607724 -418.106439) (xy 315.648905 -418.142128)
			(xy 315.684588 -418.183313) (xy 315.714048 -418.229157) (xy 315.736684 -418.278727) (xy 315.752035 -418.331014)
			(xy 315.75979 -418.384953) (xy 315.75979 -418.439447) (xy 315.759789 -418.439453) (xy 317.197446 -418.439453)
			(xy 317.197446 -418.384947) (xy 317.205203 -418.330996) (xy 317.220558 -418.278698) (xy 317.2432 -418.229118)
			(xy 317.272668 -418.183264) (xy 317.308361 -418.142071) (xy 317.349553 -418.106376) (xy 317.395405 -418.076907)
			(xy 317.444985 -418.054263) (xy 317.497282 -418.038906) (xy 317.551233 -418.031147) (xy 317.578486 -418.03066)
			(xy 318.442086 -418.03066) (xy 318.469337 -418.031186) (xy 318.523285 -418.038941) (xy 318.57558 -418.054295)
			(xy 318.625158 -418.076934) (xy 318.671009 -418.106399) (xy 318.7122 -418.14209) (xy 318.747892 -418.18328)
			(xy 318.777359 -418.22913) (xy 318.800001 -418.278707) (xy 318.815356 -418.331001) (xy 318.823113 -418.384949)
			(xy 318.823113 -418.439451) (xy 318.823112 -418.439456) (xy 320.260623 -418.439456) (xy 320.260623 -418.384944)
			(xy 320.268381 -418.330986) (xy 320.28374 -418.278681) (xy 320.306386 -418.229095) (xy 320.335859 -418.183237)
			(xy 320.371559 -418.14204) (xy 320.412758 -418.106344) (xy 320.458618 -418.076874) (xy 320.508206 -418.054231)
			(xy 320.560511 -418.038876) (xy 320.61447 -418.031121) (xy 320.641726 -418.03066) (xy 321.505326 -418.03066)
			(xy 321.532574 -418.031212) (xy 321.586514 -418.038971) (xy 321.638801 -418.054327) (xy 321.688371 -418.076968)
			(xy 321.734214 -418.106432) (xy 321.775398 -418.142121) (xy 321.811084 -418.183307) (xy 321.840545 -418.229152)
			(xy 321.863182 -418.278723) (xy 321.878535 -418.331011) (xy 321.88629 -418.384952) (xy 321.88629 -418.439448)
			(xy 321.886289 -418.439452) (xy 323.323946 -418.439452) (xy 323.323946 -418.384948) (xy 323.331702 -418.330999)
			(xy 323.347057 -418.278702) (xy 323.369697 -418.229123) (xy 323.399163 -418.183271) (xy 323.434854 -418.142078)
			(xy 323.476043 -418.106383) (xy 323.521893 -418.076914) (xy 323.57147 -418.054269) (xy 323.623765 -418.038909)
			(xy 323.677714 -418.031148) (xy 323.704966 -418.03066) (xy 324.568566 -418.03066) (xy 324.595818 -418.031185)
			(xy 324.649768 -418.038937) (xy 324.702066 -418.054289) (xy 324.751646 -418.076928) (xy 324.7975 -418.106392)
			(xy 324.838693 -418.142083) (xy 324.874387 -418.183273) (xy 324.903856 -418.229124) (xy 324.926499 -418.278702)
			(xy 324.941855 -418.330999) (xy 324.949613 -418.384948) (xy 324.949613 -418.439452) (xy 324.949613 -418.439455)
			(xy 326.387123 -418.439455) (xy 326.387123 -418.384945) (xy 326.394881 -418.330989) (xy 326.410238 -418.278686)
			(xy 326.432883 -418.229101) (xy 326.462354 -418.183244) (xy 326.498052 -418.142047) (xy 326.539249 -418.106351)
			(xy 326.585106 -418.07688) (xy 326.634691 -418.054236) (xy 326.686994 -418.038879) (xy 326.740951 -418.031123)
			(xy 326.768206 -418.03066) (xy 327.631806 -418.03066) (xy 327.659055 -418.031211) (xy 327.712997 -418.038967)
			(xy 327.765287 -418.054321) (xy 327.814859 -418.076961) (xy 327.860705 -418.106425) (xy 327.901891 -418.142113)
			(xy 327.937579 -418.1833) (xy 327.967042 -418.229146) (xy 327.989681 -418.278719) (xy 328.005034 -418.331009)
			(xy 328.01279 -418.384951) (xy 328.01279 -418.439449) (xy 328.012789 -418.439457) (xy 329.450323 -418.439457)
			(xy 329.450323 -418.384943) (xy 329.458082 -418.330983) (xy 329.473442 -418.278677) (xy 329.496089 -418.22909)
			(xy 329.525564 -418.183231) (xy 329.561266 -418.142033) (xy 329.602467 -418.106337) (xy 329.64833 -418.076867)
			(xy 329.69792 -418.054225) (xy 329.750228 -418.038872) (xy 329.804189 -418.03112) (xy 329.831446 -418.03066)
			(xy 330.695046 -418.03066) (xy 330.722293 -418.031213) (xy 330.776231 -418.038975) (xy 330.828516 -418.054332)
			(xy 330.878083 -418.076974) (xy 330.923924 -418.106439) (xy 330.965105 -418.142128) (xy 331.000788 -418.183313)
			(xy 331.030248 -418.229157) (xy 331.052884 -418.278727) (xy 331.068235 -418.331014) (xy 331.07599 -418.384953)
			(xy 331.07599 -418.439447) (xy 331.075989 -418.439453) (xy 332.513646 -418.439453) (xy 332.513646 -418.384947)
			(xy 332.521403 -418.330996) (xy 332.536758 -418.278698) (xy 332.5594 -418.229118) (xy 332.588868 -418.183264)
			(xy 332.624561 -418.142071) (xy 332.665753 -418.106376) (xy 332.711605 -418.076907) (xy 332.761185 -418.054263)
			(xy 332.813482 -418.038906) (xy 332.867433 -418.031147) (xy 332.894686 -418.03066) (xy 333.758286 -418.03066)
			(xy 333.785537 -418.031186) (xy 333.839485 -418.038941) (xy 333.89178 -418.054295) (xy 333.941358 -418.076934)
			(xy 333.987209 -418.106399) (xy 334.0284 -418.14209) (xy 334.064092 -418.18328) (xy 334.093559 -418.22913)
			(xy 334.116201 -418.278707) (xy 334.131556 -418.331001) (xy 334.139313 -418.384949) (xy 334.139313 -418.439451)
			(xy 334.139312 -418.439456) (xy 335.576823 -418.439456) (xy 335.576823 -418.384944) (xy 335.584581 -418.330986)
			(xy 335.59994 -418.278681) (xy 335.622586 -418.229095) (xy 335.652059 -418.183237) (xy 335.687759 -418.14204)
			(xy 335.728958 -418.106344) (xy 335.774818 -418.076874) (xy 335.824406 -418.054231) (xy 335.876711 -418.038876)
			(xy 335.93067 -418.031121) (xy 335.957926 -418.03066) (xy 336.821526 -418.03066) (xy 336.848774 -418.031212)
			(xy 336.902714 -418.038971) (xy 336.955001 -418.054327) (xy 337.004571 -418.076968) (xy 337.050414 -418.106432)
			(xy 337.091598 -418.142121) (xy 337.127284 -418.183307) (xy 337.156745 -418.229152) (xy 337.179382 -418.278723)
			(xy 337.194735 -418.331011) (xy 337.20249 -418.384952) (xy 337.20249 -418.439448) (xy 337.202489 -418.439452)
			(xy 338.640146 -418.439452) (xy 338.640146 -418.384948) (xy 338.647902 -418.330999) (xy 338.663257 -418.278702)
			(xy 338.685897 -418.229123) (xy 338.715363 -418.183271) (xy 338.751054 -418.142078) (xy 338.792243 -418.106383)
			(xy 338.838093 -418.076914) (xy 338.88767 -418.054269) (xy 338.939965 -418.038909) (xy 338.993914 -418.031148)
			(xy 339.021166 -418.03066) (xy 339.884766 -418.03066) (xy 339.912018 -418.031185) (xy 339.965968 -418.038937)
			(xy 340.018266 -418.054289) (xy 340.067846 -418.076928) (xy 340.1137 -418.106392) (xy 340.154893 -418.142083)
			(xy 340.190587 -418.183273) (xy 340.220056 -418.229124) (xy 340.242699 -418.278702) (xy 340.258055 -418.330999)
			(xy 340.265813 -418.384948) (xy 340.265813 -418.439452) (xy 340.265813 -418.439455) (xy 341.703323 -418.439455)
			(xy 341.703323 -418.384945) (xy 341.711081 -418.330989) (xy 341.726438 -418.278686) (xy 341.749083 -418.229101)
			(xy 341.778554 -418.183244) (xy 341.814252 -418.142047) (xy 341.855449 -418.106351) (xy 341.901306 -418.07688)
			(xy 341.950891 -418.054236) (xy 342.003194 -418.038879) (xy 342.057151 -418.031123) (xy 342.084406 -418.03066)
			(xy 342.948006 -418.03066) (xy 342.975255 -418.031211) (xy 343.029197 -418.038967) (xy 343.081487 -418.054321)
			(xy 343.131059 -418.076961) (xy 343.176905 -418.106425) (xy 343.218091 -418.142113) (xy 343.253779 -418.1833)
			(xy 343.283242 -418.229146) (xy 343.305881 -418.278719) (xy 343.321234 -418.331009) (xy 343.32899 -418.384951)
			(xy 343.32899 -418.439449) (xy 343.328989 -418.439457) (xy 344.766523 -418.439457) (xy 344.766523 -418.384943)
			(xy 344.774282 -418.330983) (xy 344.789642 -418.278677) (xy 344.812289 -418.22909) (xy 344.841764 -418.183231)
			(xy 344.877466 -418.142033) (xy 344.918667 -418.106337) (xy 344.96453 -418.076867) (xy 345.01412 -418.054225)
			(xy 345.066428 -418.038872) (xy 345.120389 -418.03112) (xy 345.147646 -418.03066) (xy 346.011246 -418.03066)
			(xy 346.038493 -418.031213) (xy 346.092431 -418.038975) (xy 346.144716 -418.054332) (xy 346.194283 -418.076974)
			(xy 346.240124 -418.106439) (xy 346.281305 -418.142128) (xy 346.316988 -418.183313) (xy 346.346448 -418.229157)
			(xy 346.369084 -418.278727) (xy 346.384435 -418.331014) (xy 346.39219 -418.384953) (xy 346.39219 -418.439447)
			(xy 346.392189 -418.439453) (xy 347.829846 -418.439453) (xy 347.829846 -418.384947) (xy 347.837603 -418.330996)
			(xy 347.852958 -418.278698) (xy 347.8756 -418.229118) (xy 347.905068 -418.183264) (xy 347.940761 -418.142071)
			(xy 347.981953 -418.106376) (xy 348.027805 -418.076907) (xy 348.077385 -418.054263) (xy 348.129682 -418.038906)
			(xy 348.183633 -418.031147) (xy 348.210886 -418.03066) (xy 349.074486 -418.03066) (xy 349.101737 -418.031186)
			(xy 349.155685 -418.038941) (xy 349.20798 -418.054295) (xy 349.257558 -418.076934) (xy 349.303409 -418.106399)
			(xy 349.3446 -418.14209) (xy 349.380292 -418.18328) (xy 349.409759 -418.22913) (xy 349.432401 -418.278707)
			(xy 349.447756 -418.331001) (xy 349.455513 -418.384949) (xy 349.455513 -418.439451) (xy 349.455512 -418.439456)
			(xy 350.893023 -418.439456) (xy 350.893023 -418.384944) (xy 350.900781 -418.330986) (xy 350.91614 -418.278681)
			(xy 350.938786 -418.229095) (xy 350.968259 -418.183237) (xy 351.003959 -418.14204) (xy 351.045158 -418.106344)
			(xy 351.091018 -418.076874) (xy 351.140606 -418.054231) (xy 351.192911 -418.038876) (xy 351.24687 -418.031121)
			(xy 351.274126 -418.03066) (xy 352.137726 -418.03066) (xy 352.164974 -418.031212) (xy 352.218914 -418.038971)
			(xy 352.271201 -418.054327) (xy 352.320771 -418.076968) (xy 352.366614 -418.106432) (xy 352.407798 -418.142121)
			(xy 352.443484 -418.183307) (xy 352.472945 -418.229152) (xy 352.495582 -418.278723) (xy 352.510935 -418.331011)
			(xy 352.51869 -418.384952) (xy 352.51869 -418.439448) (xy 352.510935 -418.493389) (xy 352.495582 -418.545677)
			(xy 352.472945 -418.595248) (xy 352.443484 -418.641093) (xy 352.407798 -418.682279) (xy 352.366614 -418.717968)
			(xy 352.320771 -418.747432) (xy 352.271201 -418.770073) (xy 352.218914 -418.785429) (xy 352.164974 -418.793188)
			(xy 352.137726 -418.793676) (xy 351.274126 -418.793676) (xy 351.24687 -418.793279) (xy 351.192911 -418.785524)
			(xy 351.140606 -418.770169) (xy 351.091018 -418.747526) (xy 351.045158 -418.718056) (xy 351.003959 -418.68236)
			(xy 350.968259 -418.641163) (xy 350.938786 -418.595305) (xy 350.91614 -418.545719) (xy 350.900781 -418.493414)
			(xy 350.893023 -418.439456) (xy 349.455512 -418.439456) (xy 349.447756 -418.493399) (xy 349.432401 -418.545693)
			(xy 349.409759 -418.59527) (xy 349.380292 -418.64112) (xy 349.3446 -418.68231) (xy 349.303409 -418.718001)
			(xy 349.257558 -418.747466) (xy 349.20798 -418.770105) (xy 349.155685 -418.785459) (xy 349.101737 -418.793214)
			(xy 349.074486 -418.793676) (xy 348.210886 -418.793676) (xy 348.183633 -418.793253) (xy 348.129682 -418.785494)
			(xy 348.077385 -418.770137) (xy 348.027805 -418.747493) (xy 347.981953 -418.718024) (xy 347.940761 -418.682329)
			(xy 347.905068 -418.641136) (xy 347.8756 -418.595282) (xy 347.852958 -418.545702) (xy 347.837603 -418.493404)
			(xy 347.829846 -418.439453) (xy 346.392189 -418.439453) (xy 346.384435 -418.493386) (xy 346.369084 -418.545673)
			(xy 346.346448 -418.595243) (xy 346.316988 -418.641087) (xy 346.281305 -418.682272) (xy 346.240124 -418.717961)
			(xy 346.194283 -418.747426) (xy 346.144716 -418.770068) (xy 346.092431 -418.785425) (xy 346.038493 -418.793187)
			(xy 346.011246 -418.793676) (xy 345.147646 -418.793676) (xy 345.120389 -418.79328) (xy 345.066428 -418.785528)
			(xy 345.01412 -418.770175) (xy 344.96453 -418.747533) (xy 344.918667 -418.718063) (xy 344.877466 -418.682367)
			(xy 344.841764 -418.641169) (xy 344.812289 -418.59531) (xy 344.789642 -418.545723) (xy 344.774282 -418.493417)
			(xy 344.766523 -418.439457) (xy 343.328989 -418.439457) (xy 343.321234 -418.493391) (xy 343.305881 -418.545681)
			(xy 343.283242 -418.595254) (xy 343.253779 -418.6411) (xy 343.218091 -418.682287) (xy 343.176905 -418.717975)
			(xy 343.131059 -418.747439) (xy 343.081487 -418.770079) (xy 343.029197 -418.785433) (xy 342.975255 -418.793189)
			(xy 342.948006 -418.793676) (xy 342.084406 -418.793676) (xy 342.057151 -418.793277) (xy 342.003194 -418.785521)
			(xy 341.950891 -418.770164) (xy 341.901306 -418.74752) (xy 341.855449 -418.718049) (xy 341.814252 -418.682353)
			(xy 341.778554 -418.641156) (xy 341.749083 -418.595299) (xy 341.726438 -418.545714) (xy 341.711081 -418.493411)
			(xy 341.703323 -418.439455) (xy 340.265813 -418.439455) (xy 340.258055 -418.493402) (xy 340.242699 -418.545698)
			(xy 340.220056 -418.595276) (xy 340.190587 -418.641127) (xy 340.154893 -418.682317) (xy 340.1137 -418.718008)
			(xy 340.067846 -418.747472) (xy 340.018266 -418.770111) (xy 339.965968 -418.785463) (xy 339.912018 -418.793215)
			(xy 339.884766 -418.793676) (xy 339.021166 -418.793676) (xy 338.993914 -418.793252) (xy 338.939965 -418.785491)
			(xy 338.88767 -418.770131) (xy 338.838093 -418.747486) (xy 338.792243 -418.718017) (xy 338.751054 -418.682322)
			(xy 338.715363 -418.641129) (xy 338.685897 -418.595277) (xy 338.663257 -418.545698) (xy 338.647902 -418.493401)
			(xy 338.640146 -418.439452) (xy 337.202489 -418.439452) (xy 337.194735 -418.493389) (xy 337.179382 -418.545677)
			(xy 337.156745 -418.595248) (xy 337.127284 -418.641093) (xy 337.091598 -418.682279) (xy 337.050414 -418.717968)
			(xy 337.004571 -418.747432) (xy 336.955001 -418.770073) (xy 336.902714 -418.785429) (xy 336.848774 -418.793188)
			(xy 336.821526 -418.793676) (xy 335.957926 -418.793676) (xy 335.93067 -418.793279) (xy 335.876711 -418.785524)
			(xy 335.824406 -418.770169) (xy 335.774818 -418.747526) (xy 335.728958 -418.718056) (xy 335.687759 -418.68236)
			(xy 335.652059 -418.641163) (xy 335.622586 -418.595305) (xy 335.59994 -418.545719) (xy 335.584581 -418.493414)
			(xy 335.576823 -418.439456) (xy 334.139312 -418.439456) (xy 334.131556 -418.493399) (xy 334.116201 -418.545693)
			(xy 334.093559 -418.59527) (xy 334.064092 -418.64112) (xy 334.0284 -418.68231) (xy 333.987209 -418.718001)
			(xy 333.941358 -418.747466) (xy 333.89178 -418.770105) (xy 333.839485 -418.785459) (xy 333.785537 -418.793214)
			(xy 333.758286 -418.793676) (xy 332.894686 -418.793676) (xy 332.867433 -418.793253) (xy 332.813482 -418.785494)
			(xy 332.761185 -418.770137) (xy 332.711605 -418.747493) (xy 332.665753 -418.718024) (xy 332.624561 -418.682329)
			(xy 332.588868 -418.641136) (xy 332.5594 -418.595282) (xy 332.536758 -418.545702) (xy 332.521403 -418.493404)
			(xy 332.513646 -418.439453) (xy 331.075989 -418.439453) (xy 331.068235 -418.493386) (xy 331.052884 -418.545673)
			(xy 331.030248 -418.595243) (xy 331.000788 -418.641087) (xy 330.965105 -418.682272) (xy 330.923924 -418.717961)
			(xy 330.878083 -418.747426) (xy 330.828516 -418.770068) (xy 330.776231 -418.785425) (xy 330.722293 -418.793187)
			(xy 330.695046 -418.793676) (xy 329.831446 -418.793676) (xy 329.804189 -418.79328) (xy 329.750228 -418.785528)
			(xy 329.69792 -418.770175) (xy 329.64833 -418.747533) (xy 329.602467 -418.718063) (xy 329.561266 -418.682367)
			(xy 329.525564 -418.641169) (xy 329.496089 -418.59531) (xy 329.473442 -418.545723) (xy 329.458082 -418.493417)
			(xy 329.450323 -418.439457) (xy 328.012789 -418.439457) (xy 328.005034 -418.493391) (xy 327.989681 -418.545681)
			(xy 327.967042 -418.595254) (xy 327.937579 -418.6411) (xy 327.901891 -418.682287) (xy 327.860705 -418.717975)
			(xy 327.814859 -418.747439) (xy 327.765287 -418.770079) (xy 327.712997 -418.785433) (xy 327.659055 -418.793189)
			(xy 327.631806 -418.793676) (xy 326.768206 -418.793676) (xy 326.740951 -418.793277) (xy 326.686994 -418.785521)
			(xy 326.634691 -418.770164) (xy 326.585106 -418.74752) (xy 326.539249 -418.718049) (xy 326.498052 -418.682353)
			(xy 326.462354 -418.641156) (xy 326.432883 -418.595299) (xy 326.410238 -418.545714) (xy 326.394881 -418.493411)
			(xy 326.387123 -418.439455) (xy 324.949613 -418.439455) (xy 324.941855 -418.493402) (xy 324.926499 -418.545698)
			(xy 324.903856 -418.595276) (xy 324.874387 -418.641127) (xy 324.838693 -418.682317) (xy 324.7975 -418.718008)
			(xy 324.751646 -418.747472) (xy 324.702066 -418.770111) (xy 324.649768 -418.785463) (xy 324.595818 -418.793215)
			(xy 324.568566 -418.793676) (xy 323.704966 -418.793676) (xy 323.677714 -418.793252) (xy 323.623765 -418.785491)
			(xy 323.57147 -418.770131) (xy 323.521893 -418.747486) (xy 323.476043 -418.718017) (xy 323.434854 -418.682322)
			(xy 323.399163 -418.641129) (xy 323.369697 -418.595277) (xy 323.347057 -418.545698) (xy 323.331702 -418.493401)
			(xy 323.323946 -418.439452) (xy 321.886289 -418.439452) (xy 321.878535 -418.493389) (xy 321.863182 -418.545677)
			(xy 321.840545 -418.595248) (xy 321.811084 -418.641093) (xy 321.775398 -418.682279) (xy 321.734214 -418.717968)
			(xy 321.688371 -418.747432) (xy 321.638801 -418.770073) (xy 321.586514 -418.785429) (xy 321.532574 -418.793188)
			(xy 321.505326 -418.793676) (xy 320.641726 -418.793676) (xy 320.61447 -418.793279) (xy 320.560511 -418.785524)
			(xy 320.508206 -418.770169) (xy 320.458618 -418.747526) (xy 320.412758 -418.718056) (xy 320.371559 -418.68236)
			(xy 320.335859 -418.641163) (xy 320.306386 -418.595305) (xy 320.28374 -418.545719) (xy 320.268381 -418.493414)
			(xy 320.260623 -418.439456) (xy 318.823112 -418.439456) (xy 318.815356 -418.493399) (xy 318.800001 -418.545693)
			(xy 318.777359 -418.59527) (xy 318.747892 -418.64112) (xy 318.7122 -418.68231) (xy 318.671009 -418.718001)
			(xy 318.625158 -418.747466) (xy 318.57558 -418.770105) (xy 318.523285 -418.785459) (xy 318.469337 -418.793214)
			(xy 318.442086 -418.793676) (xy 317.578486 -418.793676) (xy 317.551233 -418.793253) (xy 317.497282 -418.785494)
			(xy 317.444985 -418.770137) (xy 317.395405 -418.747493) (xy 317.349553 -418.718024) (xy 317.308361 -418.682329)
			(xy 317.272668 -418.641136) (xy 317.2432 -418.595282) (xy 317.220558 -418.545702) (xy 317.205203 -418.493404)
			(xy 317.197446 -418.439453) (xy 315.759789 -418.439453) (xy 315.752035 -418.493386) (xy 315.736684 -418.545673)
			(xy 315.714048 -418.595243) (xy 315.684588 -418.641087) (xy 315.648905 -418.682272) (xy 315.607724 -418.717961)
			(xy 315.561883 -418.747426) (xy 315.512316 -418.770068) (xy 315.460031 -418.785425) (xy 315.406093 -418.793187)
			(xy 315.378846 -418.793676) (xy 314.515246 -418.793676) (xy 314.487989 -418.79328) (xy 314.434028 -418.785528)
			(xy 314.38172 -418.770175) (xy 314.33213 -418.747533) (xy 314.286267 -418.718063) (xy 314.245066 -418.682367)
			(xy 314.209364 -418.641169) (xy 314.179889 -418.59531) (xy 314.157242 -418.545723) (xy 314.141882 -418.493417)
			(xy 314.134123 -418.439457) (xy 312.696589 -418.439457) (xy 312.688834 -418.493391) (xy 312.673481 -418.545681)
			(xy 312.650842 -418.595254) (xy 312.621379 -418.6411) (xy 312.585691 -418.682287) (xy 312.544505 -418.717975)
			(xy 312.498659 -418.747439) (xy 312.449087 -418.770079) (xy 312.396797 -418.785433) (xy 312.342855 -418.793189)
			(xy 312.315606 -418.793676) (xy 311.452006 -418.793676) (xy 311.424751 -418.793277) (xy 311.370794 -418.785521)
			(xy 311.318491 -418.770164) (xy 311.268906 -418.74752) (xy 311.223049 -418.718049) (xy 311.181852 -418.682353)
			(xy 311.146154 -418.641156) (xy 311.116683 -418.595299) (xy 311.094038 -418.545714) (xy 311.078681 -418.493411)
			(xy 311.070923 -418.439455) (xy 309.633413 -418.439455) (xy 309.625655 -418.493402) (xy 309.610299 -418.545698)
			(xy 309.587656 -418.595276) (xy 309.558187 -418.641127) (xy 309.522493 -418.682317) (xy 309.4813 -418.718008)
			(xy 309.435446 -418.747472) (xy 309.385866 -418.770111) (xy 309.333568 -418.785463) (xy 309.279618 -418.793215)
			(xy 309.252366 -418.793676) (xy 308.388766 -418.793676) (xy 308.361514 -418.793252) (xy 308.307565 -418.785491)
			(xy 308.25527 -418.770131) (xy 308.205693 -418.747486) (xy 308.159843 -418.718017) (xy 308.118654 -418.682322)
			(xy 308.082963 -418.641129) (xy 308.053497 -418.595277) (xy 308.030857 -418.545698) (xy 308.015502 -418.493401)
			(xy 308.007746 -418.439452) (xy 306.570089 -418.439452) (xy 306.562335 -418.493389) (xy 306.546982 -418.545677)
			(xy 306.524345 -418.595248) (xy 306.494884 -418.641093) (xy 306.459198 -418.682279) (xy 306.418014 -418.717968)
			(xy 306.372171 -418.747432) (xy 306.322601 -418.770073) (xy 306.270314 -418.785429) (xy 306.216374 -418.793188)
			(xy 306.189126 -418.793676) (xy 305.325526 -418.793676) (xy 305.29827 -418.793279) (xy 305.244311 -418.785524)
			(xy 305.192006 -418.770169) (xy 305.142418 -418.747526) (xy 305.096558 -418.718056) (xy 305.055359 -418.68236)
			(xy 305.019659 -418.641163) (xy 304.990186 -418.595305) (xy 304.96754 -418.545719) (xy 304.952181 -418.493414)
			(xy 304.944423 -418.439456) (xy 296.287698 -418.439456) (xy 296.287698 -418.603684) (xy 296.288137 -418.613747)
			(xy 296.295872 -418.63233) (xy 296.302684 -418.639752) (xy 298.642387 -420.979455) (xy 303.412823 -420.979455)
			(xy 303.412823 -420.924945) (xy 303.420581 -420.870989) (xy 303.435938 -420.818686) (xy 303.458583 -420.769101)
			(xy 303.488054 -420.723244) (xy 303.523752 -420.682047) (xy 303.564949 -420.646351) (xy 303.610806 -420.61688)
			(xy 303.660391 -420.594236) (xy 303.712694 -420.578879) (xy 303.766651 -420.571123) (xy 303.793906 -420.57066)
			(xy 304.657506 -420.57066) (xy 304.684755 -420.571211) (xy 304.738697 -420.578967) (xy 304.790987 -420.594321)
			(xy 304.840559 -420.616961) (xy 304.886405 -420.646425) (xy 304.927591 -420.682113) (xy 304.963279 -420.7233)
			(xy 304.992742 -420.769146) (xy 305.015381 -420.818719) (xy 305.030734 -420.871009) (xy 305.03849 -420.924951)
			(xy 305.03849 -420.979449) (xy 305.038489 -420.979457) (xy 306.476023 -420.979457) (xy 306.476023 -420.924943)
			(xy 306.483782 -420.870983) (xy 306.499142 -420.818677) (xy 306.521789 -420.76909) (xy 306.551264 -420.723231)
			(xy 306.586966 -420.682033) (xy 306.628167 -420.646337) (xy 306.67403 -420.616867) (xy 306.72362 -420.594225)
			(xy 306.775928 -420.578872) (xy 306.829889 -420.57112) (xy 306.857146 -420.57066) (xy 307.720746 -420.57066)
			(xy 307.747993 -420.571213) (xy 307.801931 -420.578975) (xy 307.854216 -420.594332) (xy 307.903783 -420.616974)
			(xy 307.949624 -420.646439) (xy 307.990805 -420.682128) (xy 308.026488 -420.723313) (xy 308.055948 -420.769157)
			(xy 308.078584 -420.818727) (xy 308.093935 -420.871014) (xy 308.10169 -420.924953) (xy 308.10169 -420.979447)
			(xy 308.101689 -420.979453) (xy 309.539346 -420.979453) (xy 309.539346 -420.924947) (xy 309.547103 -420.870996)
			(xy 309.562458 -420.818698) (xy 309.5851 -420.769118) (xy 309.614568 -420.723264) (xy 309.650261 -420.682071)
			(xy 309.691453 -420.646376) (xy 309.737305 -420.616907) (xy 309.786885 -420.594263) (xy 309.839182 -420.578906)
			(xy 309.893133 -420.571147) (xy 309.920386 -420.57066) (xy 310.783986 -420.57066) (xy 310.811237 -420.571186)
			(xy 310.865185 -420.578941) (xy 310.91748 -420.594295) (xy 310.967058 -420.616934) (xy 311.012909 -420.646399)
			(xy 311.0541 -420.68209) (xy 311.089792 -420.72328) (xy 311.119259 -420.76913) (xy 311.141901 -420.818707)
			(xy 311.157256 -420.871001) (xy 311.165013 -420.924949) (xy 311.165013 -420.979451) (xy 311.165012 -420.979456)
			(xy 312.602523 -420.979456) (xy 312.602523 -420.924944) (xy 312.610281 -420.870986) (xy 312.62564 -420.818681)
			(xy 312.648286 -420.769095) (xy 312.677759 -420.723237) (xy 312.713459 -420.68204) (xy 312.754658 -420.646344)
			(xy 312.800518 -420.616874) (xy 312.850106 -420.594231) (xy 312.902411 -420.578876) (xy 312.95637 -420.571121)
			(xy 312.983626 -420.57066) (xy 313.847226 -420.57066) (xy 313.874474 -420.571212) (xy 313.928414 -420.578971)
			(xy 313.980701 -420.594327) (xy 314.030271 -420.616968) (xy 314.076114 -420.646432) (xy 314.117298 -420.682121)
			(xy 314.152984 -420.723307) (xy 314.182445 -420.769152) (xy 314.205082 -420.818723) (xy 314.220435 -420.871011)
			(xy 314.22819 -420.924952) (xy 314.22819 -420.979448) (xy 314.228189 -420.979452) (xy 315.665846 -420.979452)
			(xy 315.665846 -420.924948) (xy 315.673602 -420.870999) (xy 315.688957 -420.818702) (xy 315.711597 -420.769123)
			(xy 315.741063 -420.723271) (xy 315.776754 -420.682078) (xy 315.817943 -420.646383) (xy 315.863793 -420.616914)
			(xy 315.91337 -420.594269) (xy 315.965665 -420.578909) (xy 316.019614 -420.571148) (xy 316.046866 -420.57066)
			(xy 316.910466 -420.57066) (xy 316.937718 -420.571185) (xy 316.991668 -420.578937) (xy 317.043966 -420.594289)
			(xy 317.093546 -420.616928) (xy 317.1394 -420.646392) (xy 317.180593 -420.682083) (xy 317.216287 -420.723273)
			(xy 317.245756 -420.769124) (xy 317.268399 -420.818702) (xy 317.283755 -420.870999) (xy 317.291513 -420.924948)
			(xy 317.291513 -420.979452) (xy 317.291513 -420.979455) (xy 318.729023 -420.979455) (xy 318.729023 -420.924945)
			(xy 318.736781 -420.870989) (xy 318.752138 -420.818686) (xy 318.774783 -420.769101) (xy 318.804254 -420.723244)
			(xy 318.839952 -420.682047) (xy 318.881149 -420.646351) (xy 318.927006 -420.61688) (xy 318.976591 -420.594236)
			(xy 319.028894 -420.578879) (xy 319.082851 -420.571123) (xy 319.110106 -420.57066) (xy 319.973706 -420.57066)
			(xy 320.000955 -420.571211) (xy 320.054897 -420.578967) (xy 320.107187 -420.594321) (xy 320.156759 -420.616961)
			(xy 320.202605 -420.646425) (xy 320.243791 -420.682113) (xy 320.279479 -420.7233) (xy 320.308942 -420.769146)
			(xy 320.331581 -420.818719) (xy 320.346934 -420.871009) (xy 320.35469 -420.924951) (xy 320.35469 -420.979449)
			(xy 320.354689 -420.979457) (xy 321.792223 -420.979457) (xy 321.792223 -420.924943) (xy 321.799982 -420.870983)
			(xy 321.815342 -420.818677) (xy 321.837989 -420.76909) (xy 321.867464 -420.723231) (xy 321.903166 -420.682033)
			(xy 321.944367 -420.646337) (xy 321.99023 -420.616867) (xy 322.03982 -420.594225) (xy 322.092128 -420.578872)
			(xy 322.146089 -420.57112) (xy 322.173346 -420.57066) (xy 323.036946 -420.57066) (xy 323.064193 -420.571213)
			(xy 323.118131 -420.578975) (xy 323.170416 -420.594332) (xy 323.219983 -420.616974) (xy 323.265824 -420.646439)
			(xy 323.307005 -420.682128) (xy 323.342688 -420.723313) (xy 323.372148 -420.769157) (xy 323.394784 -420.818727)
			(xy 323.410135 -420.871014) (xy 323.41789 -420.924953) (xy 323.41789 -420.979447) (xy 323.417889 -420.979453)
			(xy 324.855546 -420.979453) (xy 324.855546 -420.924947) (xy 324.863303 -420.870996) (xy 324.878658 -420.818698)
			(xy 324.9013 -420.769118) (xy 324.930768 -420.723264) (xy 324.966461 -420.682071) (xy 325.007653 -420.646376)
			(xy 325.053505 -420.616907) (xy 325.103085 -420.594263) (xy 325.155382 -420.578906) (xy 325.209333 -420.571147)
			(xy 325.236586 -420.57066) (xy 326.100186 -420.57066) (xy 326.127437 -420.571186) (xy 326.181385 -420.578941)
			(xy 326.23368 -420.594295) (xy 326.283258 -420.616934) (xy 326.329109 -420.646399) (xy 326.3703 -420.68209)
			(xy 326.405992 -420.72328) (xy 326.435459 -420.76913) (xy 326.458101 -420.818707) (xy 326.473456 -420.871001)
			(xy 326.481213 -420.924949) (xy 326.481213 -420.979451) (xy 326.481212 -420.979456) (xy 327.918723 -420.979456)
			(xy 327.918723 -420.924944) (xy 327.926481 -420.870986) (xy 327.94184 -420.818681) (xy 327.964486 -420.769095)
			(xy 327.993959 -420.723237) (xy 328.029659 -420.68204) (xy 328.070858 -420.646344) (xy 328.116718 -420.616874)
			(xy 328.166306 -420.594231) (xy 328.218611 -420.578876) (xy 328.27257 -420.571121) (xy 328.299826 -420.57066)
			(xy 329.163426 -420.57066) (xy 329.190674 -420.571212) (xy 329.244614 -420.578971) (xy 329.296901 -420.594327)
			(xy 329.346471 -420.616968) (xy 329.392314 -420.646432) (xy 329.433498 -420.682121) (xy 329.469184 -420.723307)
			(xy 329.498645 -420.769152) (xy 329.521282 -420.818723) (xy 329.536635 -420.871011) (xy 329.54439 -420.924952)
			(xy 329.54439 -420.979448) (xy 329.544389 -420.979452) (xy 330.982046 -420.979452) (xy 330.982046 -420.924948)
			(xy 330.989802 -420.870999) (xy 331.005157 -420.818702) (xy 331.027797 -420.769123) (xy 331.057263 -420.723271)
			(xy 331.092954 -420.682078) (xy 331.134143 -420.646383) (xy 331.179993 -420.616914) (xy 331.22957 -420.594269)
			(xy 331.281865 -420.578909) (xy 331.335814 -420.571148) (xy 331.363066 -420.57066) (xy 332.226666 -420.57066)
			(xy 332.253918 -420.571185) (xy 332.307868 -420.578937) (xy 332.360166 -420.594289) (xy 332.409746 -420.616928)
			(xy 332.4556 -420.646392) (xy 332.496793 -420.682083) (xy 332.532487 -420.723273) (xy 332.561956 -420.769124)
			(xy 332.584599 -420.818702) (xy 332.599955 -420.870999) (xy 332.607713 -420.924948) (xy 332.607713 -420.979452)
			(xy 332.607713 -420.979455) (xy 334.045223 -420.979455) (xy 334.045223 -420.924945) (xy 334.052981 -420.870989)
			(xy 334.068338 -420.818686) (xy 334.090983 -420.769101) (xy 334.120454 -420.723244) (xy 334.156152 -420.682047)
			(xy 334.197349 -420.646351) (xy 334.243206 -420.61688) (xy 334.292791 -420.594236) (xy 334.345094 -420.578879)
			(xy 334.399051 -420.571123) (xy 334.426306 -420.57066) (xy 335.289906 -420.57066) (xy 335.317155 -420.571211)
			(xy 335.371097 -420.578967) (xy 335.423387 -420.594321) (xy 335.472959 -420.616961) (xy 335.518805 -420.646425)
			(xy 335.559991 -420.682113) (xy 335.595679 -420.7233) (xy 335.625142 -420.769146) (xy 335.647781 -420.818719)
			(xy 335.663134 -420.871009) (xy 335.67089 -420.924951) (xy 335.67089 -420.979449) (xy 335.670889 -420.979457)
			(xy 337.108423 -420.979457) (xy 337.108423 -420.924943) (xy 337.116182 -420.870983) (xy 337.131542 -420.818677)
			(xy 337.154189 -420.76909) (xy 337.183664 -420.723231) (xy 337.219366 -420.682033) (xy 337.260567 -420.646337)
			(xy 337.30643 -420.616867) (xy 337.35602 -420.594225) (xy 337.408328 -420.578872) (xy 337.462289 -420.57112)
			(xy 337.489546 -420.57066) (xy 338.353146 -420.57066) (xy 338.380393 -420.571213) (xy 338.434331 -420.578975)
			(xy 338.486616 -420.594332) (xy 338.536183 -420.616974) (xy 338.582024 -420.646439) (xy 338.623205 -420.682128)
			(xy 338.658888 -420.723313) (xy 338.688348 -420.769157) (xy 338.710984 -420.818727) (xy 338.726335 -420.871014)
			(xy 338.73409 -420.924953) (xy 338.73409 -420.979447) (xy 338.734089 -420.979453) (xy 340.171746 -420.979453)
			(xy 340.171746 -420.924947) (xy 340.179503 -420.870996) (xy 340.194858 -420.818698) (xy 340.2175 -420.769118)
			(xy 340.246968 -420.723264) (xy 340.282661 -420.682071) (xy 340.323853 -420.646376) (xy 340.369705 -420.616907)
			(xy 340.419285 -420.594263) (xy 340.471582 -420.578906) (xy 340.525533 -420.571147) (xy 340.552786 -420.57066)
			(xy 341.416386 -420.57066) (xy 341.443637 -420.571186) (xy 341.497585 -420.578941) (xy 341.54988 -420.594295)
			(xy 341.599458 -420.616934) (xy 341.645309 -420.646399) (xy 341.6865 -420.68209) (xy 341.722192 -420.72328)
			(xy 341.751659 -420.76913) (xy 341.774301 -420.818707) (xy 341.789656 -420.871001) (xy 341.797413 -420.924949)
			(xy 341.797413 -420.979451) (xy 341.797412 -420.979456) (xy 343.234923 -420.979456) (xy 343.234923 -420.924944)
			(xy 343.242681 -420.870986) (xy 343.25804 -420.818681) (xy 343.280686 -420.769095) (xy 343.310159 -420.723237)
			(xy 343.345859 -420.68204) (xy 343.387058 -420.646344) (xy 343.432918 -420.616874) (xy 343.482506 -420.594231)
			(xy 343.534811 -420.578876) (xy 343.58877 -420.571121) (xy 343.616026 -420.57066) (xy 344.479626 -420.57066)
			(xy 344.506874 -420.571212) (xy 344.560814 -420.578971) (xy 344.613101 -420.594327) (xy 344.662671 -420.616968)
			(xy 344.708514 -420.646432) (xy 344.749698 -420.682121) (xy 344.785384 -420.723307) (xy 344.814845 -420.769152)
			(xy 344.837482 -420.818723) (xy 344.852835 -420.871011) (xy 344.86059 -420.924952) (xy 344.86059 -420.979448)
			(xy 344.860589 -420.979452) (xy 346.298246 -420.979452) (xy 346.298246 -420.924948) (xy 346.306002 -420.870999)
			(xy 346.321357 -420.818702) (xy 346.343997 -420.769123) (xy 346.373463 -420.723271) (xy 346.409154 -420.682078)
			(xy 346.450343 -420.646383) (xy 346.496193 -420.616914) (xy 346.54577 -420.594269) (xy 346.598065 -420.578909)
			(xy 346.652014 -420.571148) (xy 346.679266 -420.57066) (xy 347.542866 -420.57066) (xy 347.570118 -420.571185)
			(xy 347.624068 -420.578937) (xy 347.676366 -420.594289) (xy 347.725946 -420.616928) (xy 347.7718 -420.646392)
			(xy 347.812993 -420.682083) (xy 347.848687 -420.723273) (xy 347.878156 -420.769124) (xy 347.900799 -420.818702)
			(xy 347.916155 -420.870999) (xy 347.923913 -420.924948) (xy 347.923913 -420.979452) (xy 347.923913 -420.979455)
			(xy 349.361423 -420.979455) (xy 349.361423 -420.924945) (xy 349.369181 -420.870989) (xy 349.384538 -420.818686)
			(xy 349.407183 -420.769101) (xy 349.436654 -420.723244) (xy 349.472352 -420.682047) (xy 349.513549 -420.646351)
			(xy 349.559406 -420.61688) (xy 349.608991 -420.594236) (xy 349.661294 -420.578879) (xy 349.715251 -420.571123)
			(xy 349.742506 -420.57066) (xy 350.606106 -420.57066) (xy 350.633355 -420.571211) (xy 350.687297 -420.578967)
			(xy 350.739587 -420.594321) (xy 350.789159 -420.616961) (xy 350.835005 -420.646425) (xy 350.876191 -420.682113)
			(xy 350.911879 -420.7233) (xy 350.941342 -420.769146) (xy 350.963981 -420.818719) (xy 350.979334 -420.871009)
			(xy 350.98709 -420.924951) (xy 350.98709 -420.979449) (xy 350.979334 -421.033391) (xy 350.963981 -421.085681)
			(xy 350.941342 -421.135254) (xy 350.911879 -421.1811) (xy 350.876191 -421.222287) (xy 350.835005 -421.257975)
			(xy 350.789159 -421.287439) (xy 350.739587 -421.310079) (xy 350.687297 -421.325433) (xy 350.633355 -421.333189)
			(xy 350.606106 -421.333676) (xy 349.742506 -421.333676) (xy 349.715251 -421.333277) (xy 349.661294 -421.325521)
			(xy 349.608991 -421.310164) (xy 349.559406 -421.28752) (xy 349.513549 -421.258049) (xy 349.472352 -421.222353)
			(xy 349.436654 -421.181156) (xy 349.407183 -421.135299) (xy 349.384538 -421.085714) (xy 349.369181 -421.033411)
			(xy 349.361423 -420.979455) (xy 347.923913 -420.979455) (xy 347.916155 -421.033402) (xy 347.900799 -421.085698)
			(xy 347.878156 -421.135276) (xy 347.848687 -421.181127) (xy 347.812993 -421.222317) (xy 347.7718 -421.258008)
			(xy 347.725946 -421.287472) (xy 347.676366 -421.310111) (xy 347.624068 -421.325463) (xy 347.570118 -421.333215)
			(xy 347.542866 -421.333676) (xy 346.679266 -421.333676) (xy 346.652014 -421.333252) (xy 346.598065 -421.325491)
			(xy 346.54577 -421.310131) (xy 346.496193 -421.287486) (xy 346.450343 -421.258017) (xy 346.409154 -421.222322)
			(xy 346.373463 -421.181129) (xy 346.343997 -421.135277) (xy 346.321357 -421.085698) (xy 346.306002 -421.033401)
			(xy 346.298246 -420.979452) (xy 344.860589 -420.979452) (xy 344.852835 -421.033389) (xy 344.837482 -421.085677)
			(xy 344.814845 -421.135248) (xy 344.785384 -421.181093) (xy 344.749698 -421.222279) (xy 344.708514 -421.257968)
			(xy 344.662671 -421.287432) (xy 344.613101 -421.310073) (xy 344.560814 -421.325429) (xy 344.506874 -421.333188)
			(xy 344.479626 -421.333676) (xy 343.616026 -421.333676) (xy 343.58877 -421.333279) (xy 343.534811 -421.325524)
			(xy 343.482506 -421.310169) (xy 343.432918 -421.287526) (xy 343.387058 -421.258056) (xy 343.345859 -421.22236)
			(xy 343.310159 -421.181163) (xy 343.280686 -421.135305) (xy 343.25804 -421.085719) (xy 343.242681 -421.033414)
			(xy 343.234923 -420.979456) (xy 341.797412 -420.979456) (xy 341.789656 -421.033399) (xy 341.774301 -421.085693)
			(xy 341.751659 -421.13527) (xy 341.722192 -421.18112) (xy 341.6865 -421.22231) (xy 341.645309 -421.258001)
			(xy 341.599458 -421.287466) (xy 341.54988 -421.310105) (xy 341.497585 -421.325459) (xy 341.443637 -421.333214)
			(xy 341.416386 -421.333676) (xy 340.552786 -421.333676) (xy 340.525533 -421.333253) (xy 340.471582 -421.325494)
			(xy 340.419285 -421.310137) (xy 340.369705 -421.287493) (xy 340.323853 -421.258024) (xy 340.282661 -421.222329)
			(xy 340.246968 -421.181136) (xy 340.2175 -421.135282) (xy 340.194858 -421.085702) (xy 340.179503 -421.033404)
			(xy 340.171746 -420.979453) (xy 338.734089 -420.979453) (xy 338.726335 -421.033386) (xy 338.710984 -421.085673)
			(xy 338.688348 -421.135243) (xy 338.658888 -421.181087) (xy 338.623205 -421.222272) (xy 338.582024 -421.257961)
			(xy 338.536183 -421.287426) (xy 338.486616 -421.310068) (xy 338.434331 -421.325425) (xy 338.380393 -421.333187)
			(xy 338.353146 -421.333676) (xy 337.489546 -421.333676) (xy 337.462289 -421.33328) (xy 337.408328 -421.325528)
			(xy 337.35602 -421.310175) (xy 337.30643 -421.287533) (xy 337.260567 -421.258063) (xy 337.219366 -421.222367)
			(xy 337.183664 -421.181169) (xy 337.154189 -421.13531) (xy 337.131542 -421.085723) (xy 337.116182 -421.033417)
			(xy 337.108423 -420.979457) (xy 335.670889 -420.979457) (xy 335.663134 -421.033391) (xy 335.647781 -421.085681)
			(xy 335.625142 -421.135254) (xy 335.595679 -421.1811) (xy 335.559991 -421.222287) (xy 335.518805 -421.257975)
			(xy 335.472959 -421.287439) (xy 335.423387 -421.310079) (xy 335.371097 -421.325433) (xy 335.317155 -421.333189)
			(xy 335.289906 -421.333676) (xy 334.426306 -421.333676) (xy 334.399051 -421.333277) (xy 334.345094 -421.325521)
			(xy 334.292791 -421.310164) (xy 334.243206 -421.28752) (xy 334.197349 -421.258049) (xy 334.156152 -421.222353)
			(xy 334.120454 -421.181156) (xy 334.090983 -421.135299) (xy 334.068338 -421.085714) (xy 334.052981 -421.033411)
			(xy 334.045223 -420.979455) (xy 332.607713 -420.979455) (xy 332.599955 -421.033402) (xy 332.584599 -421.085698)
			(xy 332.561956 -421.135276) (xy 332.532487 -421.181127) (xy 332.496793 -421.222317) (xy 332.4556 -421.258008)
			(xy 332.409746 -421.287472) (xy 332.360166 -421.310111) (xy 332.307868 -421.325463) (xy 332.253918 -421.333215)
			(xy 332.226666 -421.333676) (xy 331.363066 -421.333676) (xy 331.335814 -421.333252) (xy 331.281865 -421.325491)
			(xy 331.22957 -421.310131) (xy 331.179993 -421.287486) (xy 331.134143 -421.258017) (xy 331.092954 -421.222322)
			(xy 331.057263 -421.181129) (xy 331.027797 -421.135277) (xy 331.005157 -421.085698) (xy 330.989802 -421.033401)
			(xy 330.982046 -420.979452) (xy 329.544389 -420.979452) (xy 329.536635 -421.033389) (xy 329.521282 -421.085677)
			(xy 329.498645 -421.135248) (xy 329.469184 -421.181093) (xy 329.433498 -421.222279) (xy 329.392314 -421.257968)
			(xy 329.346471 -421.287432) (xy 329.296901 -421.310073) (xy 329.244614 -421.325429) (xy 329.190674 -421.333188)
			(xy 329.163426 -421.333676) (xy 328.299826 -421.333676) (xy 328.27257 -421.333279) (xy 328.218611 -421.325524)
			(xy 328.166306 -421.310169) (xy 328.116718 -421.287526) (xy 328.070858 -421.258056) (xy 328.029659 -421.22236)
			(xy 327.993959 -421.181163) (xy 327.964486 -421.135305) (xy 327.94184 -421.085719) (xy 327.926481 -421.033414)
			(xy 327.918723 -420.979456) (xy 326.481212 -420.979456) (xy 326.473456 -421.033399) (xy 326.458101 -421.085693)
			(xy 326.435459 -421.13527) (xy 326.405992 -421.18112) (xy 326.3703 -421.22231) (xy 326.329109 -421.258001)
			(xy 326.283258 -421.287466) (xy 326.23368 -421.310105) (xy 326.181385 -421.325459) (xy 326.127437 -421.333214)
			(xy 326.100186 -421.333676) (xy 325.236586 -421.333676) (xy 325.209333 -421.333253) (xy 325.155382 -421.325494)
			(xy 325.103085 -421.310137) (xy 325.053505 -421.287493) (xy 325.007653 -421.258024) (xy 324.966461 -421.222329)
			(xy 324.930768 -421.181136) (xy 324.9013 -421.135282) (xy 324.878658 -421.085702) (xy 324.863303 -421.033404)
			(xy 324.855546 -420.979453) (xy 323.417889 -420.979453) (xy 323.410135 -421.033386) (xy 323.394784 -421.085673)
			(xy 323.372148 -421.135243) (xy 323.342688 -421.181087) (xy 323.307005 -421.222272) (xy 323.265824 -421.257961)
			(xy 323.219983 -421.287426) (xy 323.170416 -421.310068) (xy 323.118131 -421.325425) (xy 323.064193 -421.333187)
			(xy 323.036946 -421.333676) (xy 322.173346 -421.333676) (xy 322.146089 -421.33328) (xy 322.092128 -421.325528)
			(xy 322.03982 -421.310175) (xy 321.99023 -421.287533) (xy 321.944367 -421.258063) (xy 321.903166 -421.222367)
			(xy 321.867464 -421.181169) (xy 321.837989 -421.13531) (xy 321.815342 -421.085723) (xy 321.799982 -421.033417)
			(xy 321.792223 -420.979457) (xy 320.354689 -420.979457) (xy 320.346934 -421.033391) (xy 320.331581 -421.085681)
			(xy 320.308942 -421.135254) (xy 320.279479 -421.1811) (xy 320.243791 -421.222287) (xy 320.202605 -421.257975)
			(xy 320.156759 -421.287439) (xy 320.107187 -421.310079) (xy 320.054897 -421.325433) (xy 320.000955 -421.333189)
			(xy 319.973706 -421.333676) (xy 319.110106 -421.333676) (xy 319.082851 -421.333277) (xy 319.028894 -421.325521)
			(xy 318.976591 -421.310164) (xy 318.927006 -421.28752) (xy 318.881149 -421.258049) (xy 318.839952 -421.222353)
			(xy 318.804254 -421.181156) (xy 318.774783 -421.135299) (xy 318.752138 -421.085714) (xy 318.736781 -421.033411)
			(xy 318.729023 -420.979455) (xy 317.291513 -420.979455) (xy 317.283755 -421.033402) (xy 317.268399 -421.085698)
			(xy 317.245756 -421.135276) (xy 317.216287 -421.181127) (xy 317.180593 -421.222317) (xy 317.1394 -421.258008)
			(xy 317.093546 -421.287472) (xy 317.043966 -421.310111) (xy 316.991668 -421.325463) (xy 316.937718 -421.333215)
			(xy 316.910466 -421.333676) (xy 316.046866 -421.333676) (xy 316.019614 -421.333252) (xy 315.965665 -421.325491)
			(xy 315.91337 -421.310131) (xy 315.863793 -421.287486) (xy 315.817943 -421.258017) (xy 315.776754 -421.222322)
			(xy 315.741063 -421.181129) (xy 315.711597 -421.135277) (xy 315.688957 -421.085698) (xy 315.673602 -421.033401)
			(xy 315.665846 -420.979452) (xy 314.228189 -420.979452) (xy 314.220435 -421.033389) (xy 314.205082 -421.085677)
			(xy 314.182445 -421.135248) (xy 314.152984 -421.181093) (xy 314.117298 -421.222279) (xy 314.076114 -421.257968)
			(xy 314.030271 -421.287432) (xy 313.980701 -421.310073) (xy 313.928414 -421.325429) (xy 313.874474 -421.333188)
			(xy 313.847226 -421.333676) (xy 312.983626 -421.333676) (xy 312.95637 -421.333279) (xy 312.902411 -421.325524)
			(xy 312.850106 -421.310169) (xy 312.800518 -421.287526) (xy 312.754658 -421.258056) (xy 312.713459 -421.22236)
			(xy 312.677759 -421.181163) (xy 312.648286 -421.135305) (xy 312.62564 -421.085719) (xy 312.610281 -421.033414)
			(xy 312.602523 -420.979456) (xy 311.165012 -420.979456) (xy 311.157256 -421.033399) (xy 311.141901 -421.085693)
			(xy 311.119259 -421.13527) (xy 311.089792 -421.18112) (xy 311.0541 -421.22231) (xy 311.012909 -421.258001)
			(xy 310.967058 -421.287466) (xy 310.91748 -421.310105) (xy 310.865185 -421.325459) (xy 310.811237 -421.333214)
			(xy 310.783986 -421.333676) (xy 309.920386 -421.333676) (xy 309.893133 -421.333253) (xy 309.839182 -421.325494)
			(xy 309.786885 -421.310137) (xy 309.737305 -421.287493) (xy 309.691453 -421.258024) (xy 309.650261 -421.222329)
			(xy 309.614568 -421.181136) (xy 309.5851 -421.135282) (xy 309.562458 -421.085702) (xy 309.547103 -421.033404)
			(xy 309.539346 -420.979453) (xy 308.101689 -420.979453) (xy 308.093935 -421.033386) (xy 308.078584 -421.085673)
			(xy 308.055948 -421.135243) (xy 308.026488 -421.181087) (xy 307.990805 -421.222272) (xy 307.949624 -421.257961)
			(xy 307.903783 -421.287426) (xy 307.854216 -421.310068) (xy 307.801931 -421.325425) (xy 307.747993 -421.333187)
			(xy 307.720746 -421.333676) (xy 306.857146 -421.333676) (xy 306.829889 -421.33328) (xy 306.775928 -421.325528)
			(xy 306.72362 -421.310175) (xy 306.67403 -421.287533) (xy 306.628167 -421.258063) (xy 306.586966 -421.222367)
			(xy 306.551264 -421.181169) (xy 306.521789 -421.13531) (xy 306.499142 -421.085723) (xy 306.483782 -421.033417)
			(xy 306.476023 -420.979457) (xy 305.038489 -420.979457) (xy 305.030734 -421.033391) (xy 305.015381 -421.085681)
			(xy 304.992742 -421.135254) (xy 304.963279 -421.1811) (xy 304.927591 -421.222287) (xy 304.886405 -421.257975)
			(xy 304.840559 -421.287439) (xy 304.790987 -421.310079) (xy 304.738697 -421.325433) (xy 304.684755 -421.333189)
			(xy 304.657506 -421.333676) (xy 303.793906 -421.333676) (xy 303.766651 -421.333277) (xy 303.712694 -421.325521)
			(xy 303.660391 -421.310164) (xy 303.610806 -421.28752) (xy 303.564949 -421.258049) (xy 303.523752 -421.222353)
			(xy 303.488054 -421.181156) (xy 303.458583 -421.135299) (xy 303.435938 -421.085714) (xy 303.420581 -421.033411)
			(xy 303.412823 -420.979455) (xy 298.642387 -420.979455) (xy 299.516292 -421.85336) (xy 299.523688 -421.860212)
			(xy 299.542287 -421.867956) (xy 299.55236 -421.868346) (xy 302.00854 -421.868346)
		)
		(stroke
			(width 0)
			(type solid)
		)
		(fill yes)
		(layer "In8.Cu")
		(net "P0V9_CPU0_RT_2D")
	)
	(gr_poly
		(pts
			(xy 102.608888 -413.510476) (xy 102.615238 -413.497522) (xy 102.628255 -413.47246) (xy 102.660557 -413.426138)
			(xy 102.699336 -413.385085) (xy 102.743744 -413.350198) (xy 102.792811 -413.32224) (xy 102.845463 -413.301822)
			(xy 102.90055 -413.289389) (xy 102.956868 -413.285215) (xy 103.013186 -413.289389) (xy 103.068273 -413.301822)
			(xy 103.120925 -413.32224) (xy 103.169992 -413.350198) (xy 103.2144 -413.385085) (xy 103.253179 -413.426138)
			(xy 103.285481 -413.47246) (xy 103.298498 -413.497522) (xy 103.304848 -413.510476) (xy 103.329486 -413.525716)
			(xy 105.527602 -413.525716) (xy 105.537481 -413.525259) (xy 105.555785 -413.517822) (xy 105.563162 -413.511238)
			(xy 105.621074 -413.454342) (xy 105.628948 -413.436308) (xy 105.629202 -413.426402) (xy 105.630213 -413.399517)
			(xy 105.638859 -413.346416) (xy 105.654881 -413.295057) (xy 105.677959 -413.246458) (xy 105.707636 -413.201584)
			(xy 105.743324 -413.161325) (xy 105.784315 -413.126479) (xy 105.829794 -413.097738) (xy 105.878861 -413.075673)
			(xy 105.930541 -413.06072) (xy 105.98381 -413.053176) (xy 106.01071 -413.052768) (xy 106.87431 -413.052768)
			(xy 106.901206 -413.053229) (xy 106.954466 -413.060784) (xy 107.006137 -413.075744) (xy 107.055196 -413.097811)
			(xy 107.100669 -413.126549) (xy 107.141656 -413.161387) (xy 107.177345 -413.201636) (xy 107.207028 -413.246498)
			(xy 107.230118 -413.295084) (xy 107.246156 -413.346431) (xy 107.254824 -413.39952) (xy 107.255818 -413.426402)
			(xy 107.256072 -413.436308) (xy 107.263946 -413.454342) (xy 107.321858 -413.511238) (xy 107.329239 -413.517821)
			(xy 107.347538 -413.525272) (xy 107.357418 -413.525716) (xy 116.035582 -413.525716) (xy 116.041932 -413.523938)
			(xy 116.065758 -413.518078) (xy 116.114426 -413.511829) (xy 116.13896 -413.511492) (xy 116.163491 -413.511873)
			(xy 116.212155 -413.518114) (xy 116.235988 -413.523938) (xy 116.242338 -413.525716) (xy 163.420044 -413.525716)
			(xy 163.430111 -413.525285) (xy 163.448705 -413.517562) (xy 163.456112 -413.51073) (xy 164.537644 -412.429198)
			(xy 164.543589 -412.422812) (xy 164.551112 -412.407085) (xy 164.552862 -412.389739) (xy 164.551106 -412.381192)
			(xy 164.551106 -412.380938) (xy 164.54588 -412.35844) (xy 164.540274 -412.312592) (xy 164.53993 -412.289498)
			(xy 164.53993 -412.28899) (xy 164.540438 -412.26078) (xy 164.548745 -412.204976) (xy 164.565177 -412.151003)
			(xy 164.589375 -412.100036) (xy 164.620813 -412.053187) (xy 164.658804 -412.011477) (xy 164.702522 -411.975814)
			(xy 164.751014 -411.946975) (xy 164.803223 -411.925589) (xy 164.830506 -411.918404) (xy 164.847524 -411.91434)
			(xy 164.869114 -411.886908) (xy 164.869114 -402.37283) (xy 164.868679 -402.362765) (xy 164.860948 -402.344178)
			(xy 164.854128 -402.336762) (xy 162.454844 -399.937478) (xy 162.445494 -399.928984) (xy 162.42136 -399.921632)
			(xy 162.40887 -399.923508) (xy 162.391714 -399.926717) (xy 162.35698 -399.930152) (xy 162.339528 -399.930366)
			(xy 162.311542 -399.929848) (xy 162.25626 -399.921095) (xy 162.203028 -399.903801) (xy 162.153156 -399.878392)
			(xy 162.107875 -399.845493) (xy 162.068298 -399.805914) (xy 162.035401 -399.760632) (xy 162.009994 -399.710759)
			(xy 161.992702 -399.657526) (xy 161.983951 -399.602244) (xy 161.98342 -399.574258) (xy 161.983648 -399.556807)
			(xy 161.987087 -399.522074) (xy 161.990278 -399.504916) (xy 161.992087 -399.492426) (xy 161.984768 -399.468305)
			(xy 161.976308 -399.458942) (xy 160.570672 -398.053306) (xy 160.553416 -398.035264) (xy 160.525665 -397.993769)
			(xy 160.506559 -397.947651) (xy 160.496836 -397.898688) (xy 160.49625 -397.873728) (xy 160.49625 -394.253466)
			(xy 160.495895 -394.244767) (xy 160.490073 -394.228371) (xy 160.47911 -394.214861) (xy 160.471866 -394.210032)
			(xy 160.451483 -394.197058) (xy 160.414364 -394.166131) (xy 160.382141 -394.13013) (xy 160.3555 -394.089823)
			(xy 160.33501 -394.046069) (xy 160.321105 -393.999798) (xy 160.314082 -393.951996) (xy 160.313624 -393.927838)
			(xy 160.314026 -393.90444) (xy 160.320612 -393.85811) (xy 160.333658 -393.813169) (xy 160.352905 -393.770514)
			(xy 160.377968 -393.730995) (xy 160.392872 -393.712954) (xy 160.399222 -393.705334) (xy 160.405572 -393.687046)
			(xy 160.401 -393.606782) (xy 160.399978 -393.597069) (xy 160.39161 -393.579439) (xy 160.384744 -393.572492)
			(xy 160.365873 -393.554365) (xy 160.332769 -393.513842) (xy 160.305507 -393.469178) (xy 160.2846 -393.42121)
			(xy 160.270439 -393.370836) (xy 160.263289 -393.319001) (xy 160.262824 -393.292838) (xy 160.262824 -392.428984)
			(xy 160.263262 -392.402655) (xy 160.270497 -392.350496) (xy 160.28484 -392.29983) (xy 160.30602 -392.251619)
			(xy 160.333633 -392.206782) (xy 160.367153 -392.166171) (xy 160.386268 -392.14806) (xy 160.393126 -392.14171)
			(xy 160.401508 -392.124946) (xy 160.408874 -392.047476) (xy 160.409367 -392.038302) (xy 160.404557 -392.020585)
			(xy 160.399476 -392.012932) (xy 160.399222 -392.012678) (xy 160.385066 -391.992833) (xy 160.362582 -391.949584)
			(xy 160.347265 -391.903309) (xy 160.339507 -391.855186) (xy 160.339024 -391.830814) (xy 160.339524 -391.80591)
			(xy 160.347624 -391.756764) (xy 160.363594 -391.709585) (xy 160.387012 -391.665624) (xy 160.417256 -391.626048)
			(xy 160.453524 -391.591907) (xy 160.473898 -391.577576) (xy 160.483925 -391.570052) (xy 160.49566 -391.547934)
			(xy 160.49625 -391.535412) (xy 160.49625 -389.18642) (xy 160.496058 -389.179751) (xy 160.49259 -389.166874)
			(xy 160.489392 -389.16102) (xy 160.35147 -388.922006) (xy 160.339571 -388.899338) (xy 160.322695 -388.851007)
			(xy 160.314133 -388.800536) (xy 160.313624 -388.77494) (xy 160.313624 -388.774432) (xy 160.314051 -388.751262)
			(xy 160.321045 -388.705453) (xy 160.334878 -388.661226) (xy 160.355232 -388.619596) (xy 160.381641 -388.581518)
			(xy 160.413498 -388.547865) (xy 160.450072 -388.51941) (xy 160.470088 -388.507732) (xy 160.48228 -388.501128)
			(xy 160.49625 -388.477252) (xy 160.49625 -388.097776) (xy 160.495819 -388.086959) (xy 160.487004 -388.067211)
			(xy 160.479232 -388.059676) (xy 160.422336 -388.00913) (xy 160.414031 -388.002375) (xy 160.393642 -387.995912)
			(xy 160.382966 -387.996684) (xy 160.382458 -387.996684) (xy 160.373414 -387.997733) (xy 160.35524 -387.998879)
			(xy 160.346136 -387.99897) (xy 160.322142 -387.998526) (xy 160.274744 -387.991024) (xy 160.229104 -387.976198)
			(xy 160.186346 -387.954414) (xy 160.147523 -387.926208) (xy 160.11359 -387.892276) (xy 160.085385 -387.853452)
			(xy 160.063601 -387.810694) (xy 160.048776 -387.765054) (xy 160.041273 -387.717656) (xy 160.040828 -387.693662)
			(xy 160.040828 -387.693154) (xy 160.041426 -387.666537) (xy 160.050696 -387.614115) (xy 160.068912 -387.564094)
			(xy 160.081722 -387.540754) (xy 160.08681 -387.530798) (xy 160.088749 -387.50855) (xy 160.081105 -387.487567)
			(xy 160.073594 -387.479286) (xy 159.344106 -386.749798) (xy 159.336708 -386.742951) (xy 159.31811 -386.735214)
			(xy 159.308038 -386.734812) (xy 159.179514 -386.734812) (xy 159.167576 -386.73786) (xy 159.161988 -386.740908)
			(xy 159.137914 -386.75312) (xy 159.086785 -386.770423) (xy 159.033528 -386.77921) (xy 159.00654 -386.77977)
			(xy 159.006286 -386.77977) (xy 158.971234 -386.777992) (xy 158.959911 -386.777408) (xy 158.938553 -386.784929)
			(xy 158.930086 -386.79247) (xy 158.21533 -387.507226) (xy 158.21025 -387.539992) (xy 158.21787 -387.55447)
			(xy 158.228439 -387.576088) (xy 158.243381 -387.621828) (xy 158.250945 -387.669349) (xy 158.251398 -387.693408)
			(xy 158.251398 -387.693662) (xy 158.250955 -387.717657) (xy 158.243453 -387.765056) (xy 158.228627 -387.810698)
			(xy 158.206844 -387.853459) (xy 158.178639 -387.892285) (xy 158.144706 -387.92622) (xy 158.105883 -387.954429)
			(xy 158.063124 -387.976217) (xy 158.017484 -387.991046) (xy 157.970085 -387.998552) (xy 157.94609 -387.99897)
			(xy 157.945836 -387.99897) (xy 157.92178 -387.998494) (xy 157.874267 -387.99091) (xy 157.828527 -387.975985)
			(xy 157.806898 -387.965442) (xy 157.79242 -387.957822) (xy 157.759654 -387.962902) (xy 157.223714 -388.498842)
			(xy 157.22346 -388.499096) (xy 157.220666 -388.50189) (xy 157.220666 -388.544054) (xy 157.235398 -388.558786)
			(xy 157.25177 -388.575866) (xy 157.279576 -388.614142) (xy 157.29077 -388.634986) (xy 157.291278 -388.636002)
			(xy 157.371584 -388.77494) (xy 157.913324 -388.77494) (xy 157.913324 -388.774432) (xy 157.913791 -388.750453)
			(xy 157.921286 -388.703083) (xy 157.936095 -388.657469) (xy 157.957855 -388.614731) (xy 157.986031 -388.575922)
			(xy 158.019929 -388.541996) (xy 158.058714 -388.513788) (xy 158.101434 -388.491993) (xy 158.147036 -388.477145)
			(xy 158.194399 -388.469611) (xy 158.218378 -388.469124) (xy 158.218886 -388.469124) (xy 158.242823 -388.469534)
			(xy 158.290112 -388.476998) (xy 158.335657 -388.491748) (xy 158.378345 -388.51342) (xy 158.41713 -388.541485)
			(xy 158.451064 -388.575256) (xy 158.479314 -388.613907) (xy 158.490666 -388.634986) (xy 158.491174 -388.636002)
			(xy 158.57148 -388.77494) (xy 159.113728 -388.77494) (xy 159.113728 -388.774432) (xy 159.114168 -388.750438)
			(xy 159.121671 -388.70304) (xy 159.136497 -388.6574) (xy 159.158282 -388.614641) (xy 159.186488 -388.575818)
			(xy 159.220421 -388.541885) (xy 159.259245 -388.51368) (xy 159.302004 -388.491896) (xy 159.347644 -388.47707)
			(xy 159.395042 -388.469568) (xy 159.419036 -388.469124) (xy 159.442972 -388.469574) (xy 159.490258 -388.477031)
			(xy 159.535803 -388.491773) (xy 159.578491 -388.513439) (xy 159.617277 -388.541498) (xy 159.651211 -388.575264)
			(xy 159.679463 -388.613909) (xy 159.690816 -388.634986) (xy 159.691324 -388.636002) (xy 160.083754 -389.314944)
			(xy 160.096562 -389.338285) (xy 160.114788 -389.388304) (xy 160.124055 -389.440726) (xy 160.124648 -389.467344)
			(xy 160.124179 -389.491322) (xy 160.116676 -389.538687) (xy 160.10186 -389.584296) (xy 160.080097 -389.627029)
			(xy 160.051921 -389.665835) (xy 160.018025 -389.699758) (xy 159.979243 -389.727966) (xy 159.936528 -389.749764)
			(xy 159.89093 -389.764617) (xy 159.843571 -389.772159) (xy 159.819594 -389.772652) (xy 159.819086 -389.772652)
			(xy 159.795513 -389.772242) (xy 159.748927 -389.765) (xy 159.70401 -389.750675) (xy 159.661833 -389.729608)
			(xy 159.6234 -389.702302) (xy 159.589627 -389.669406) (xy 159.561319 -389.631705) (xy 159.549846 -389.611108)
			(xy 159.549338 -389.610346) (xy 159.151574 -388.922006) (xy 159.139699 -388.899329) (xy 159.122848 -388.850996)
			(xy 159.114274 -388.800533) (xy 159.113728 -388.77494) (xy 158.57148 -388.77494) (xy 158.883604 -389.314944)
			(xy 158.896319 -389.338271) (xy 158.91442 -389.388214) (xy 158.923643 -389.44053) (xy 158.924244 -389.46709)
			(xy 158.924244 -389.467344) (xy 158.923778 -389.491335) (xy 158.916267 -389.538724) (xy 158.901435 -389.584356)
			(xy 158.879649 -389.627106) (xy 158.851445 -389.665923) (xy 158.817517 -389.69985) (xy 158.778699 -389.728054)
			(xy 158.735949 -389.749838) (xy 158.690317 -389.764668) (xy 158.642927 -389.772179) (xy 158.618936 -389.772652)
			(xy 158.595364 -389.772202) (xy 158.54878 -389.764967) (xy 158.503864 -389.750649) (xy 158.461687 -389.729589)
			(xy 158.423253 -389.702289) (xy 158.389479 -389.669399) (xy 158.361169 -389.631703) (xy 158.349696 -389.611108)
			(xy 158.349188 -389.610346) (xy 157.951424 -388.922006) (xy 157.939511 -388.899337) (xy 157.922572 -388.851012)
			(xy 157.913912 -388.800542) (xy 157.913324 -388.77494) (xy 157.371584 -388.77494) (xy 157.683708 -389.314944)
			(xy 157.696467 -389.338252) (xy 157.7146 -389.388194) (xy 157.723797 -389.440524) (xy 157.724348 -389.46709)
			(xy 157.724348 -389.467344) (xy 157.723874 -389.491334) (xy 157.716363 -389.538723) (xy 157.701532 -389.584354)
			(xy 157.679747 -389.627103) (xy 157.651543 -389.665919) (xy 157.617616 -389.699846) (xy 157.5788 -389.728049)
			(xy 157.53605 -389.749834) (xy 157.490419 -389.764664) (xy 157.44303 -389.772174) (xy 157.41904 -389.772652)
			(xy 157.39547 -389.772209) (xy 157.348892 -389.764953) (xy 157.303983 -389.750623) (xy 157.261811 -389.729559)
			(xy 157.223379 -389.702263) (xy 157.1896 -389.669382) (xy 157.161277 -389.6317) (xy 157.1498 -389.611108)
			(xy 157.149292 -389.610346) (xy 156.751528 -388.922006) (xy 156.739596 -388.899345) (xy 156.722649 -388.85102)
			(xy 156.714009 -388.800544) (xy 156.713428 -388.77494) (xy 156.713428 -388.774432) (xy 156.713585 -388.763146)
			(xy 156.715361 -388.740644) (xy 156.716984 -388.729474) (xy 156.716984 -388.728966) (xy 156.718254 -388.72033)
			(xy 156.714698 -388.703312) (xy 156.671264 -388.631938) (xy 156.657548 -388.620762) (xy 156.648912 -388.617968)
			(xy 156.629629 -388.611123) (xy 156.592927 -388.593034) (xy 156.57576 -388.5819) (xy 156.569355 -388.577865)
			(xy 156.554879 -388.573463) (xy 156.547312 -388.573264) (xy 156.142944 -388.573264) (xy 156.134052 -388.573598)
			(xy 156.117341 -388.579681) (xy 156.103729 -388.591125) (xy 156.099002 -388.598664) (xy 156.094834 -388.606537)
			(xy 156.091726 -388.624069) (xy 156.094812 -388.641603) (xy 156.099002 -388.649464) (xy 156.483558 -389.314944)
			(xy 156.49634 -389.338295) (xy 156.514531 -389.388318) (xy 156.523813 -389.440731) (xy 156.524452 -389.467344)
			(xy 156.523979 -389.491322) (xy 156.516476 -389.538686) (xy 156.50166 -389.584295) (xy 156.479897 -389.627028)
			(xy 156.451722 -389.665833) (xy 156.417827 -389.699757) (xy 156.379045 -389.727964) (xy 156.33633 -389.749763)
			(xy 156.290733 -389.764616) (xy 156.243375 -389.772159) (xy 156.219398 -389.772652) (xy 156.21889 -389.772652)
			(xy 156.195318 -389.772213) (xy 156.148735 -389.764964) (xy 156.103821 -389.750638) (xy 156.061643 -389.729578)
			(xy 156.023204 -389.702284) (xy 155.989419 -389.669404) (xy 155.96109 -389.631721) (xy 155.94965 -389.611108)
			(xy 155.949142 -389.610346) (xy 155.551378 -388.922006) (xy 155.539479 -388.899338) (xy 155.522602 -388.851007)
			(xy 155.51404 -388.800536) (xy 155.513532 -388.77494) (xy 155.513532 -388.774432) (xy 155.513624 -388.76315)
			(xy 155.515277 -388.740648) (xy 155.516834 -388.729474) (xy 155.516834 -388.728966) (xy 155.517693 -388.720255)
			(xy 155.514174 -388.70312) (xy 155.509976 -388.695438) (xy 155.471114 -388.631938) (xy 155.457398 -388.620762)
			(xy 155.448762 -388.617968) (xy 155.429543 -388.611114) (xy 155.392971 -388.593021) (xy 155.375864 -388.5819)
			(xy 155.369459 -388.577865) (xy 155.354983 -388.573461) (xy 155.347416 -388.573264) (xy 154.943048 -388.573264)
			(xy 154.934156 -388.573597) (xy 154.917444 -388.579679) (xy 154.90383 -388.591123) (xy 154.899106 -388.598664)
			(xy 154.894937 -388.606537) (xy 154.891829 -388.624069) (xy 154.894916 -388.641604) (xy 154.899106 -388.649464)
			(xy 155.283662 -389.314944) (xy 155.296444 -389.338295) (xy 155.314634 -389.388318) (xy 155.323917 -389.440731)
			(xy 155.324556 -389.467344) (xy 155.324083 -389.491322) (xy 155.31658 -389.538686) (xy 155.301765 -389.584296)
			(xy 155.280002 -389.627029) (xy 155.251826 -389.665834) (xy 155.217931 -389.699758) (xy 155.179149 -389.727967)
			(xy 155.136435 -389.749766) (xy 155.090838 -389.764619) (xy 155.043479 -389.772163) (xy 155.019502 -389.772652)
			(xy 155.018994 -389.772652) (xy 154.995422 -389.772213) (xy 154.948839 -389.764964) (xy 154.903924 -389.75064)
			(xy 154.861745 -389.72958) (xy 154.823306 -389.702285) (xy 154.789521 -389.669406) (xy 154.761192 -389.631723)
			(xy 154.749754 -389.611108) (xy 154.749246 -389.610346) (xy 154.351482 -388.922006) (xy 154.339583 -388.899338)
			(xy 154.322706 -388.851007) (xy 154.314144 -388.800536) (xy 154.313636 -388.77494) (xy 154.313636 -388.774432)
			(xy 154.313728 -388.76315) (xy 154.315381 -388.740648) (xy 154.316938 -388.729474) (xy 154.316938 -388.728966)
			(xy 154.318208 -388.72033) (xy 154.314652 -388.703312) (xy 154.271218 -388.631938) (xy 154.257502 -388.620762)
			(xy 154.248866 -388.617968) (xy 154.225084 -388.609411) (xy 154.180492 -388.585624) (xy 154.140422 -388.554826)
			(xy 154.105963 -388.517855) (xy 154.078056 -388.47572) (xy 154.067256 -388.452868) (xy 154.063446 -388.444232)
			(xy 153.543762 -387.924548) (xy 153.526503 -387.906507) (xy 153.498746 -387.865013) (xy 153.479634 -387.818895)
			(xy 153.469903 -387.769931) (xy 153.46934 -387.74497) (xy 153.46934 -386.02158) (xy 153.469143 -386.014913)
			(xy 153.465666 -386.002041) (xy 153.462482 -385.99618) (xy 153.151586 -385.457954) (xy 153.139691 -385.435285)
			(xy 153.122822 -385.386954) (xy 153.114269 -385.336483) (xy 153.11374 -385.310888) (xy 153.11374 -385.31038)
			(xy 153.114263 -385.284776) (xy 153.122805 -385.234286) (xy 153.139647 -385.185927) (xy 153.164318 -385.141053)
			(xy 153.196125 -385.100922) (xy 153.23418 -385.066657) (xy 153.277415 -385.039217) (xy 153.324621 -385.019371)
			(xy 153.374475 -385.007674) (xy 153.399998 -385.00558) (xy 153.409172 -385.004644) (xy 153.425979 -384.997092)
			(xy 153.432764 -384.990848) (xy 153.454354 -384.969258) (xy 153.461199 -384.961859) (xy 153.468925 -384.943261)
			(xy 153.46934 -384.93319) (xy 153.46934 -383.644394) (xy 153.468852 -383.634384) (xy 153.461192 -383.615888)
			(xy 153.447041 -383.601727) (xy 153.428549 -383.594055) (xy 153.41854 -383.593594) (xy 141.145768 -383.593594)
			(xy 141.1357 -383.594023) (xy 141.117104 -383.601744) (xy 141.1097 -383.60858) (xy 140.49121 -384.22707)
			(xy 140.484374 -384.234472) (xy 140.476663 -384.25307) (xy 140.476224 -384.263138) (xy 140.476224 -385.310888)
			(xy 147.113752 -385.310888) (xy 147.113752 -385.31038) (xy 147.114244 -385.28639) (xy 147.121752 -385.239002)
			(xy 147.13658 -385.193371) (xy 147.158362 -385.150621) (xy 147.186563 -385.111804) (xy 147.220489 -385.077876)
			(xy 147.259304 -385.049673) (xy 147.302052 -385.027887) (xy 147.347682 -385.013057) (xy 147.39507 -385.005546)
			(xy 147.41906 -385.005072) (xy 147.442995 -385.005531) (xy 147.49028 -385.01299) (xy 147.535823 -385.027733)
			(xy 147.57851 -385.049398) (xy 147.617295 -385.077455) (xy 147.651231 -385.111217) (xy 147.679485 -385.149859)
			(xy 147.69084 -385.170934) (xy 147.691348 -385.17195) (xy 147.771654 -385.310888) (xy 148.313648 -385.310888)
			(xy 148.313648 -385.31038) (xy 148.314144 -385.28639) (xy 148.321652 -385.239002) (xy 148.336479 -385.193372)
			(xy 148.358261 -385.150622) (xy 148.386462 -385.111805) (xy 148.420387 -385.077878) (xy 148.459201 -385.049674)
			(xy 148.501949 -385.027888) (xy 148.547579 -385.013057) (xy 148.594966 -385.005546) (xy 148.618956 -385.005072)
			(xy 148.642891 -385.005534) (xy 148.690176 -385.012993) (xy 148.735719 -385.027735) (xy 148.778405 -385.049399)
			(xy 148.817191 -385.077456) (xy 148.851126 -385.111218) (xy 148.879381 -385.149859) (xy 148.890736 -385.170934)
			(xy 148.891244 -385.17195) (xy 148.97155 -385.310888) (xy 149.513544 -385.310888) (xy 149.513544 -385.31038)
			(xy 149.514044 -385.286391) (xy 149.521552 -385.239003) (xy 149.536379 -385.193373) (xy 149.558161 -385.150623)
			(xy 149.586361 -385.111807) (xy 149.620286 -385.077879) (xy 149.659099 -385.049675) (xy 149.701847 -385.02789)
			(xy 149.747476 -385.013058) (xy 149.794863 -385.005546) (xy 149.818852 -385.005072) (xy 149.842787 -385.005537)
			(xy 149.890071 -385.012995) (xy 149.935614 -385.027737) (xy 149.978301 -385.049401) (xy 150.017087 -385.077457)
			(xy 150.051022 -385.111218) (xy 150.079277 -385.149859) (xy 150.090632 -385.170934) (xy 150.09114 -385.17195)
			(xy 150.171446 -385.310888) (xy 150.71344 -385.310888) (xy 150.71344 -385.31038) (xy 150.713843 -385.286399)
			(xy 150.721346 -385.239026) (xy 150.736164 -385.193409) (xy 150.757932 -385.15067) (xy 150.786115 -385.111861)
			(xy 150.820019 -385.077936) (xy 150.858812 -385.049729) (xy 150.901537 -385.027935) (xy 150.947145 -385.013089)
			(xy 150.994513 -385.005558) (xy 151.018494 -385.005072) (xy 151.019002 -385.005072) (xy 151.042935 -385.005578)
			(xy 151.090218 -385.013028) (xy 151.13576 -385.027763) (xy 151.178447 -385.04942) (xy 151.217233 -385.077469)
			(xy 151.25117 -385.111225) (xy 151.279426 -385.149861) (xy 151.290782 -385.170934) (xy 151.29129 -385.17195)
			(xy 151.371596 -385.310888) (xy 151.913336 -385.310888) (xy 151.913336 -385.31038) (xy 151.913743 -385.286399)
			(xy 151.921246 -385.239027) (xy 151.936063 -385.19341) (xy 151.957831 -385.150672) (xy 151.986013 -385.111862)
			(xy 152.019918 -385.077937) (xy 152.058709 -385.04973) (xy 152.101434 -385.027936) (xy 152.147041 -385.01309)
			(xy 152.194409 -385.005558) (xy 152.21839 -385.005072) (xy 152.218898 -385.005072) (xy 152.242834 -385.0055)
			(xy 152.290121 -385.012965) (xy 152.335664 -385.027713) (xy 152.378351 -385.049383) (xy 152.417136 -385.077445)
			(xy 152.45107 -385.111212) (xy 152.479324 -385.149857) (xy 152.490678 -385.170934) (xy 152.491186 -385.17195)
			(xy 152.883616 -385.850892) (xy 152.89635 -385.874209) (xy 152.914443 -385.924158) (xy 152.923659 -385.976477)
			(xy 152.924256 -386.003038) (xy 152.924256 -386.003292) (xy 152.92373 -386.027281) (xy 152.916227 -386.074667)
			(xy 152.901403 -386.120297) (xy 152.879625 -386.163047) (xy 152.851428 -386.201863) (xy 152.817506 -386.235791)
			(xy 152.778694 -386.263996) (xy 152.735949 -386.285782) (xy 152.690322 -386.300614) (xy 152.642937 -386.308126)
			(xy 152.618948 -386.3086) (xy 152.595375 -386.308168) (xy 152.548789 -386.300933) (xy 152.503871 -386.286614)
			(xy 152.461693 -386.265552) (xy 152.423259 -386.238248) (xy 152.389486 -386.205354) (xy 152.361179 -386.167654)
			(xy 152.349708 -386.147056) (xy 152.3492 -386.146294) (xy 151.951436 -385.457954) (xy 151.939505 -385.435294)
			(xy 151.922572 -385.386964) (xy 151.913919 -385.336491) (xy 151.913336 -385.310888) (xy 151.371596 -385.310888)
			(xy 151.68372 -385.850892) (xy 151.696454 -385.874209) (xy 151.714548 -385.924158) (xy 151.723763 -385.976476)
			(xy 151.72436 -386.003038) (xy 151.72436 -386.003292) (xy 151.723954 -386.027287) (xy 151.716447 -386.074687)
			(xy 151.701617 -386.120329) (xy 151.679828 -386.163088) (xy 151.651618 -386.201912) (xy 151.617682 -386.235844)
			(xy 151.578854 -386.264049) (xy 151.536092 -386.285832) (xy 151.490448 -386.300657) (xy 151.443047 -386.308157)
			(xy 151.419052 -386.3086) (xy 151.395479 -386.308164) (xy 151.348893 -386.300931) (xy 151.303976 -386.286612)
			(xy 151.261797 -386.265551) (xy 151.223364 -386.238247) (xy 151.189591 -386.205354) (xy 151.161283 -386.167653)
			(xy 151.149812 -386.147056) (xy 151.149304 -386.146294) (xy 150.75154 -385.457954) (xy 150.739609 -385.435293)
			(xy 150.722676 -385.386964) (xy 150.714023 -385.336491) (xy 150.71344 -385.310888) (xy 150.171446 -385.310888)
			(xy 150.48357 -385.850892) (xy 150.496397 -385.874223) (xy 150.514616 -385.924247) (xy 150.523875 -385.976673)
			(xy 150.524464 -386.003292) (xy 150.524031 -386.027273) (xy 150.516533 -386.074644) (xy 150.501719 -386.12026)
			(xy 150.479955 -386.162998) (xy 150.451775 -386.201808) (xy 150.417874 -386.235733) (xy 150.379084 -386.263941)
			(xy 150.336361 -386.285735) (xy 150.290756 -386.300581) (xy 150.24339 -386.308114) (xy 150.21941 -386.3086)
			(xy 150.218902 -386.3086) (xy 150.195328 -386.308205) (xy 150.14874 -386.300963) (xy 150.103821 -386.286638)
			(xy 150.061643 -386.26557) (xy 150.02321 -386.23826) (xy 149.989438 -386.205361) (xy 149.961133 -386.167656)
			(xy 149.949662 -386.147056) (xy 149.949154 -386.146294) (xy 149.55139 -385.457954) (xy 149.539534 -385.435267)
			(xy 149.522675 -385.386939) (xy 149.514094 -385.336479) (xy 149.513544 -385.310888) (xy 148.97155 -385.310888)
			(xy 149.283674 -385.850892) (xy 149.296501 -385.874223) (xy 149.31472 -385.924247) (xy 149.323979 -385.976673)
			(xy 149.324568 -386.003292) (xy 149.324131 -386.027272) (xy 149.316633 -386.074643) (xy 149.301819 -386.120259)
			(xy 149.280055 -386.162997) (xy 149.251876 -386.201806) (xy 149.217975 -386.235732) (xy 149.179187 -386.263939)
			(xy 149.136464 -386.285734) (xy 149.090859 -386.300581) (xy 149.043494 -386.308113) (xy 149.019514 -386.3086)
			(xy 149.019006 -386.3086) (xy 148.995432 -386.308201) (xy 148.948844 -386.300961) (xy 148.903926 -386.286636)
			(xy 148.861747 -386.265568) (xy 148.823314 -386.238259) (xy 148.789542 -386.20536) (xy 148.761237 -386.167655)
			(xy 148.749766 -386.147056) (xy 148.749258 -386.146294) (xy 148.351494 -385.457954) (xy 148.339638 -385.435267)
			(xy 148.322779 -385.386939) (xy 148.314198 -385.336479) (xy 148.313648 -385.310888) (xy 147.771654 -385.310888)
			(xy 148.083778 -385.850892) (xy 148.096606 -385.874223) (xy 148.114824 -385.924247) (xy 148.124083 -385.976673)
			(xy 148.124672 -386.003292) (xy 148.124231 -386.027272) (xy 148.116733 -386.074643) (xy 148.10192 -386.120258)
			(xy 148.080156 -386.162996) (xy 148.051978 -386.201805) (xy 148.018077 -386.235731) (xy 147.979289 -386.263938)
			(xy 147.936567 -386.285733) (xy 147.890963 -386.30058) (xy 147.843598 -386.308113) (xy 147.819618 -386.3086)
			(xy 147.81911 -386.3086) (xy 147.795536 -386.308198) (xy 147.748948 -386.300958) (xy 147.70403 -386.286634)
			(xy 147.661852 -386.265566) (xy 147.623418 -386.238258) (xy 147.589647 -386.20536) (xy 147.561341 -386.167655)
			(xy 147.54987 -386.147056) (xy 147.549362 -386.146294) (xy 147.151598 -385.457954) (xy 147.139742 -385.435267)
			(xy 147.122883 -385.386939) (xy 147.114302 -385.336479) (xy 147.113752 -385.310888) (xy 140.476224 -385.310888)
			(xy 140.476224 -385.991862) (xy 140.475607 -386.016816) (xy 140.46586 -386.065764) (xy 140.446752 -386.111871)
			(xy 140.419018 -386.153365) (xy 140.401802 -386.17144) (xy 138.783568 -387.789674) (xy 140.529056 -387.789674)
			(xy 140.529056 -386.926074) (xy 140.529542 -386.898823) (xy 140.537298 -386.844875) (xy 140.552653 -386.79258)
			(xy 140.575295 -386.743003) (xy 140.604761 -386.697153) (xy 140.640452 -386.655962) (xy 140.681643 -386.620271)
			(xy 140.727493 -386.590805) (xy 140.77707 -386.568163) (xy 140.829365 -386.552808) (xy 140.883313 -386.545052)
			(xy 140.937815 -386.545052) (xy 140.991763 -386.552808) (xy 141.044058 -386.568163) (xy 141.093635 -386.590805)
			(xy 141.139485 -386.620271) (xy 141.180676 -386.655962) (xy 141.216367 -386.697153) (xy 141.245833 -386.743003)
			(xy 141.268475 -386.79258) (xy 141.28383 -386.844875) (xy 141.291586 -386.898823) (xy 141.292072 -386.926074)
			(xy 141.292072 -387.789674) (xy 141.291586 -387.816925) (xy 141.28383 -387.870873) (xy 141.268475 -387.923168)
			(xy 141.245833 -387.972745) (xy 141.216367 -388.018595) (xy 141.180676 -388.059786) (xy 141.139485 -388.095477)
			(xy 141.093635 -388.124943) (xy 141.044058 -388.147585) (xy 140.991763 -388.16294) (xy 140.937815 -388.170696)
			(xy 140.883313 -388.170696) (xy 140.829365 -388.16294) (xy 140.77707 -388.147585) (xy 140.727493 -388.124943)
			(xy 140.681643 -388.095477) (xy 140.640452 -388.059786) (xy 140.604761 -388.018595) (xy 140.575295 -387.972745)
			(xy 140.552653 -387.923168) (xy 140.537298 -387.870873) (xy 140.529542 -387.816925) (xy 140.529056 -387.789674)
			(xy 138.783568 -387.789674) (xy 138.768074 -387.805168) (xy 138.750033 -387.822427) (xy 138.708539 -387.850185)
			(xy 138.662421 -387.8693) (xy 138.613457 -387.879034) (xy 138.588496 -387.87959) (xy 136.99109 -387.87959)
			(xy 136.98102 -387.880014) (xy 136.962418 -387.88773) (xy 136.955022 -387.894576) (xy 136.711436 -388.138162)
			(xy 136.693394 -388.155419) (xy 136.651899 -388.183171) (xy 136.605781 -388.202279) (xy 136.556818 -388.212007)
			(xy 136.531858 -388.212584) (xy 128.302004 -388.212584) (xy 128.277051 -388.211963) (xy 128.228108 -388.202209)
			(xy 128.182008 -388.183095) (xy 128.140521 -388.155356) (xy 128.122426 -388.138162) (xy 127.976376 -387.992112)
			(xy 127.969239 -387.985617) (xy 127.95151 -387.978035) (xy 127.932235 -387.977512) (xy 127.923036 -387.980428)
			(xy 127.897732 -387.989036) (xy 127.845109 -387.998364) (xy 127.818388 -387.99897) (xy 127.794397 -387.998523)
			(xy 127.747005 -387.991014) (xy 127.701371 -387.976184) (xy 127.658619 -387.954398) (xy 127.619802 -387.926191)
			(xy 127.585876 -387.892259) (xy 127.557676 -387.853438) (xy 127.535897 -387.810683) (xy 127.521074 -387.765047)
			(xy 127.513573 -387.717654) (xy 127.51308 -387.693662) (xy 127.513627 -387.666935) (xy 127.522945 -387.614299)
			(xy 127.531622 -387.589014) (xy 127.534558 -387.579817) (xy 127.53405 -387.560533) (xy 127.526448 -387.542804)
			(xy 127.519938 -387.535674) (xy 126.826264 -386.842) (xy 126.818863 -386.835159) (xy 126.800265 -386.827438)
			(xy 126.790196 -386.827014) (xy 126.22657 -386.827014) (xy 126.216503 -386.827443) (xy 126.197907 -386.835167)
			(xy 126.190502 -386.842) (xy 124.636784 -388.395718) (xy 124.633736 -388.398512) (xy 124.625806 -388.407072)
			(xy 124.617987 -388.429033) (xy 124.61875 -388.440676) (xy 124.62256 -388.473188) (xy 124.624387 -388.484863)
			(xy 124.637103 -388.504746) (xy 124.646944 -388.511288) (xy 124.671382 -388.526533) (xy 124.714566 -388.564635)
			(xy 124.749865 -388.610139) (xy 124.76353 -388.635494) (xy 124.764038 -388.636764) (xy 124.830221 -388.751286)
			(xy 125.385922 -388.751286) (xy 125.393254 -388.703735) (xy 125.407948 -388.657921) (xy 125.429641 -388.614977)
			(xy 125.457796 -388.575963) (xy 125.491718 -388.541844) (xy 125.530569 -388.513464) (xy 125.573387 -388.491523)
			(xy 125.619115 -388.476565) (xy 125.666623 -388.468959) (xy 125.714735 -388.468892) (xy 125.762263 -388.476368)
			(xy 125.808032 -388.4912) (xy 125.850911 -388.513022) (xy 125.88984 -388.541295) (xy 125.923856 -388.57532)
			(xy 125.952119 -388.614256) (xy 125.963426 -388.635494) (xy 125.963934 -388.636764) (xy 126.030115 -388.751284)
			(xy 126.586167 -388.751284) (xy 126.593498 -388.703742) (xy 126.60819 -388.657936) (xy 126.629879 -388.615)
			(xy 126.658029 -388.575993) (xy 126.691945 -388.54188) (xy 126.730788 -388.513504) (xy 126.773598 -388.491567)
			(xy 126.819318 -388.47661) (xy 126.866816 -388.469004) (xy 126.91492 -388.468936) (xy 126.96244 -388.476408)
			(xy 127.008202 -388.491235) (xy 127.051074 -388.513051) (xy 127.089997 -388.541317) (xy 127.124009 -388.575333)
			(xy 127.15227 -388.61426) (xy 127.163576 -388.635494) (xy 127.164084 -388.636764) (xy 127.257251 -388.797979)
			(xy 127.786112 -388.797979) (xy 127.786361 -388.747044) (xy 127.795054 -388.696856) (xy 127.811952 -388.648805)
			(xy 127.836585 -388.604222) (xy 127.868271 -388.564342) (xy 127.906133 -388.530271) (xy 127.949122 -388.502951)
			(xy 127.996047 -388.48314) (xy 128.045608 -388.471387) (xy 128.096432 -388.468016) (xy 128.147111 -388.473122)
			(xy 128.196241 -388.486563) (xy 128.242461 -388.507967) (xy 128.284491 -388.53674) (xy 128.321166 -388.572086)
			(xy 128.351471 -388.613026) (xy 128.363472 -388.635494) (xy 128.36398 -388.636764) (xy 128.457146 -388.797978)
			(xy 128.986016 -388.797978) (xy 128.986265 -388.747044) (xy 128.994958 -388.696856) (xy 129.011855 -388.648806)
			(xy 129.036488 -388.604224) (xy 129.068174 -388.564345) (xy 129.106035 -388.530274) (xy 129.149024 -388.502955)
			(xy 129.195948 -388.483144) (xy 129.245508 -388.47139) (xy 129.296331 -388.46802) (xy 129.347009 -388.473125)
			(xy 129.396138 -388.486566) (xy 129.442358 -388.507969) (xy 129.484387 -388.536742) (xy 129.521062 -388.572087)
			(xy 129.551367 -388.613026) (xy 129.563368 -388.635494) (xy 129.563876 -388.636764) (xy 129.630058 -388.751285)
			(xy 130.18603 -388.751285) (xy 130.193361 -388.703736) (xy 130.208055 -388.657924) (xy 130.229747 -388.614981)
			(xy 130.257901 -388.575968) (xy 130.291823 -388.54185) (xy 130.330672 -388.51347) (xy 130.373489 -388.49153)
			(xy 130.419216 -388.476572) (xy 130.466722 -388.468966) (xy 130.514833 -388.468899) (xy 130.56236 -388.476374)
			(xy 130.608128 -388.491205) (xy 130.651005 -388.513026) (xy 130.689933 -388.541298) (xy 130.723949 -388.575322)
			(xy 130.752211 -388.614256) (xy 130.763518 -388.635494) (xy 130.764026 -388.636764) (xy 130.830208 -388.751285)
			(xy 131.385933 -388.751285) (xy 131.393265 -388.703737) (xy 131.407958 -388.657925) (xy 131.42965 -388.614982)
			(xy 131.457804 -388.57597) (xy 131.491725 -388.541853) (xy 131.530573 -388.513474) (xy 131.57339 -388.491534)
			(xy 131.619116 -388.476576) (xy 131.666621 -388.46897) (xy 131.714731 -388.468903) (xy 131.762258 -388.476377)
			(xy 131.808025 -388.491208) (xy 131.850902 -388.513029) (xy 131.88983 -388.5413) (xy 131.923845 -388.575323)
			(xy 131.952107 -388.614257) (xy 131.963414 -388.635494) (xy 131.963922 -388.636764) (xy 132.057087 -388.797977)
			(xy 132.586219 -388.797977) (xy 132.586468 -388.747044) (xy 132.595161 -388.696857) (xy 132.612058 -388.648807)
			(xy 132.636691 -388.604226) (xy 132.668376 -388.564348) (xy 132.706237 -388.530277) (xy 132.749225 -388.502958)
			(xy 132.796148 -388.483147) (xy 132.845708 -388.471394) (xy 132.89653 -388.468023) (xy 132.947207 -388.473129)
			(xy 132.996336 -388.486569) (xy 133.042555 -388.507972) (xy 133.084584 -388.536744) (xy 133.121258 -388.572088)
			(xy 133.151563 -388.613026) (xy 133.163564 -388.635494) (xy 133.164072 -388.636764) (xy 133.243924 -388.77494)
			(xy 147.113752 -388.77494) (xy 147.113752 -388.774432) (xy 147.114292 -388.750444) (xy 147.121792 -388.703057)
			(xy 147.136613 -388.657427) (xy 147.158389 -388.614677) (xy 147.186584 -388.57586) (xy 147.220505 -388.541931)
			(xy 147.259315 -388.513726) (xy 147.30206 -388.49194) (xy 147.347687 -388.477109) (xy 147.395072 -388.469598)
			(xy 147.41906 -388.469124) (xy 147.442996 -388.469555) (xy 147.490284 -388.477016) (xy 147.535829 -388.491761)
			(xy 147.578517 -388.51343) (xy 147.617303 -388.541492) (xy 147.651236 -388.57526) (xy 147.679488 -388.613908)
			(xy 147.69084 -388.634986) (xy 147.691348 -388.636002) (xy 147.771654 -388.77494) (xy 148.313648 -388.77494)
			(xy 148.313648 -388.774432) (xy 148.314192 -388.750444) (xy 148.321692 -388.703057) (xy 148.336512 -388.657428)
			(xy 148.358288 -388.614678) (xy 148.386483 -388.575861) (xy 148.420403 -388.541933) (xy 148.459213 -388.513728)
			(xy 148.501957 -388.491941) (xy 148.547583 -388.47711) (xy 148.594968 -388.469598) (xy 148.618956 -388.469124)
			(xy 148.642892 -388.469558) (xy 148.69018 -388.477018) (xy 148.735725 -388.491763) (xy 148.778413 -388.513431)
			(xy 148.817198 -388.541493) (xy 148.851132 -388.575261) (xy 148.879383 -388.613908) (xy 148.890736 -388.634986)
			(xy 148.891244 -388.636002) (xy 148.97155 -388.77494) (xy 149.513544 -388.77494) (xy 149.513544 -388.774432)
			(xy 149.514092 -388.750444) (xy 149.521592 -388.703058) (xy 149.536412 -388.657429) (xy 149.558187 -388.614679)
			(xy 149.586382 -388.575862) (xy 149.620301 -388.541934) (xy 149.659111 -388.513729) (xy 149.701855 -388.491943)
			(xy 149.74748 -388.477111) (xy 149.794864 -388.469598) (xy 149.818852 -388.469124) (xy 149.842788 -388.469561)
			(xy 149.890076 -388.477021) (xy 149.935621 -388.491765) (xy 149.978308 -388.513433) (xy 150.017094 -388.541494)
			(xy 150.051028 -388.575261) (xy 150.079279 -388.613908) (xy 150.090632 -388.634986) (xy 150.09114 -388.636002)
			(xy 150.171446 -388.77494) (xy 150.71344 -388.77494) (xy 150.71344 -388.774432) (xy 150.713891 -388.750452)
			(xy 150.721386 -388.703081) (xy 150.736197 -388.657465) (xy 150.757958 -388.614726) (xy 150.786136 -388.575917)
			(xy 150.820035 -388.54199) (xy 150.858823 -388.513783) (xy 150.901545 -388.491988) (xy 150.947149 -388.477142)
			(xy 150.994514 -388.46961) (xy 151.018494 -388.469124) (xy 151.019002 -388.469124) (xy 151.042937 -388.469602)
			(xy 151.090222 -388.477054) (xy 151.135766 -388.491791) (xy 151.178454 -388.513452) (xy 151.21724 -388.541507)
			(xy 151.251175 -388.575268) (xy 151.279429 -388.61391) (xy 151.290782 -388.634986) (xy 151.29129 -388.636002)
			(xy 151.371596 -388.77494) (xy 151.913336 -388.77494) (xy 151.913336 -388.774432) (xy 151.913791 -388.750452)
			(xy 151.921286 -388.703082) (xy 151.936096 -388.657466) (xy 151.957858 -388.614728) (xy 151.986034 -388.575918)
			(xy 152.019934 -388.541992) (xy 152.058721 -388.513784) (xy 152.101442 -388.491989) (xy 152.147046 -388.477143)
			(xy 152.19441 -388.46961) (xy 152.21839 -388.469124) (xy 152.218898 -388.469124) (xy 152.242835 -388.469524)
			(xy 152.290125 -388.476991) (xy 152.335671 -388.491741) (xy 152.378358 -388.513415) (xy 152.417143 -388.541482)
			(xy 152.451076 -388.575255) (xy 152.479326 -388.613906) (xy 152.490678 -388.634986) (xy 152.491186 -388.636002)
			(xy 152.571492 -388.77494) (xy 153.11374 -388.77494) (xy 153.11374 -388.774432) (xy 153.114168 -388.750437)
			(xy 153.121671 -388.703038) (xy 153.136498 -388.657397) (xy 153.158284 -388.614638) (xy 153.186491 -388.575814)
			(xy 153.220426 -388.541881) (xy 153.259251 -388.513676) (xy 153.302012 -388.491892) (xy 153.347654 -388.477068)
			(xy 153.395053 -388.469567) (xy 153.419048 -388.469124) (xy 153.442984 -388.469565) (xy 153.490271 -388.477024)
			(xy 153.535816 -388.491767) (xy 153.578504 -388.513434) (xy 153.61729 -388.541495) (xy 153.651224 -388.575262)
			(xy 153.679475 -388.613908) (xy 153.690828 -388.634986) (xy 153.691336 -388.636002) (xy 154.083766 -389.314944)
			(xy 154.096575 -389.338285) (xy 154.1148 -389.388303) (xy 154.124067 -389.440726) (xy 154.12466 -389.467344)
			(xy 154.124279 -389.491326) (xy 154.116773 -389.5387) (xy 154.101952 -389.584317) (xy 154.080181 -389.627055)
			(xy 154.051995 -389.665865) (xy 154.018088 -389.69979) (xy 153.979294 -389.727996) (xy 153.936567 -389.74979)
			(xy 153.890957 -389.764635) (xy 153.843588 -389.772166) (xy 153.819606 -389.772652) (xy 153.819098 -389.772652)
			(xy 153.795525 -389.772232) (xy 153.74894 -389.764992) (xy 153.704023 -389.750669) (xy 153.661846 -389.729604)
			(xy 153.623413 -389.702299) (xy 153.589639 -389.669405) (xy 153.561331 -389.631705) (xy 153.549858 -389.611108)
			(xy 153.54935 -389.610346) (xy 153.151586 -388.922006) (xy 153.139712 -388.899328) (xy 153.12286 -388.850996)
			(xy 153.114286 -388.800533) (xy 153.11374 -388.77494) (xy 152.571492 -388.77494) (xy 152.883616 -389.314944)
			(xy 152.896332 -389.338271) (xy 152.914432 -389.388214) (xy 152.923655 -389.44053) (xy 152.924256 -389.46709)
			(xy 152.924256 -389.467344) (xy 152.923778 -389.491334) (xy 152.916267 -389.538723) (xy 152.901436 -389.584353)
			(xy 152.879652 -389.627103) (xy 152.851449 -389.665919) (xy 152.817522 -389.699846) (xy 152.778706 -389.72805)
			(xy 152.735957 -389.749835) (xy 152.690327 -389.764666) (xy 152.642938 -389.772178) (xy 152.618948 -389.772652)
			(xy 152.595377 -389.772192) (xy 152.548793 -389.764959) (xy 152.503877 -389.750643) (xy 152.4617 -389.729585)
			(xy 152.423266 -389.702286) (xy 152.389492 -389.669398) (xy 152.361182 -389.631703) (xy 152.349708 -389.611108)
			(xy 152.3492 -389.610346) (xy 151.951436 -388.922006) (xy 151.939523 -388.899336) (xy 151.922584 -388.851012)
			(xy 151.913924 -388.800542) (xy 151.913336 -388.77494) (xy 151.371596 -388.77494) (xy 151.68372 -389.314944)
			(xy 151.696436 -389.33827) (xy 151.714536 -389.388214) (xy 151.723759 -389.44053) (xy 151.72436 -389.46709)
			(xy 151.72436 -389.467344) (xy 151.724002 -389.491341) (xy 151.716487 -389.538742) (xy 151.70165 -389.584385)
			(xy 151.679855 -389.627144) (xy 151.651639 -389.665968) (xy 151.617698 -389.699899) (xy 151.578866 -389.728103)
			(xy 151.5361 -389.749885) (xy 151.490453 -389.764709) (xy 151.443049 -389.772209) (xy 151.419052 -389.772652)
			(xy 151.395481 -389.772189) (xy 151.348897 -389.764957) (xy 151.303982 -389.750641) (xy 151.261804 -389.729583)
			(xy 151.223371 -389.702285) (xy 151.189596 -389.669397) (xy 151.161286 -389.631703) (xy 151.149812 -389.611108)
			(xy 151.149304 -389.610346) (xy 150.75154 -388.922006) (xy 150.739628 -388.899336) (xy 150.722688 -388.851012)
			(xy 150.714028 -388.800542) (xy 150.71344 -388.77494) (xy 150.171446 -388.77494) (xy 150.48357 -389.314944)
			(xy 150.496379 -389.338285) (xy 150.514604 -389.388303) (xy 150.523871 -389.440726) (xy 150.524464 -389.467344)
			(xy 150.524079 -389.491326) (xy 150.516573 -389.538699) (xy 150.501752 -389.584316) (xy 150.479981 -389.627054)
			(xy 150.451796 -389.665863) (xy 150.41789 -389.699788) (xy 150.379096 -389.727994) (xy 150.336369 -389.749788)
			(xy 150.290761 -389.764634) (xy 150.243392 -389.772166) (xy 150.21941 -389.772652) (xy 150.218902 -389.772652)
			(xy 150.195329 -389.772229) (xy 150.148744 -389.76499) (xy 150.103827 -389.750667) (xy 150.06165 -389.729602)
			(xy 150.023217 -389.702298) (xy 149.989444 -389.669404) (xy 149.961135 -389.631705) (xy 149.949662 -389.611108)
			(xy 149.949154 -389.610346) (xy 149.55139 -388.922006) (xy 149.539516 -388.899328) (xy 149.522664 -388.850995)
			(xy 149.51409 -388.800533) (xy 149.513544 -388.77494) (xy 148.97155 -388.77494) (xy 149.283674 -389.314944)
			(xy 149.296483 -389.338284) (xy 149.314708 -389.388303) (xy 149.323975 -389.440726) (xy 149.324568 -389.467344)
			(xy 149.324179 -389.491326) (xy 149.316673 -389.538698) (xy 149.301852 -389.584315) (xy 149.280082 -389.627053)
			(xy 149.251897 -389.665862) (xy 149.217991 -389.699787) (xy 149.179198 -389.727993) (xy 149.136472 -389.749787)
			(xy 149.090864 -389.764633) (xy 149.043495 -389.772165) (xy 149.019514 -389.772652) (xy 149.019006 -389.772652)
			(xy 148.995434 -389.772226) (xy 148.948848 -389.764987) (xy 148.903932 -389.750665) (xy 148.861754 -389.729601)
			(xy 148.823321 -389.702297) (xy 148.789548 -389.669404) (xy 148.761239 -389.631705) (xy 148.749766 -389.611108)
			(xy 148.749258 -389.610346) (xy 148.351494 -388.922006) (xy 148.339621 -388.899328) (xy 148.322768 -388.850995)
			(xy 148.314194 -388.800532) (xy 148.313648 -388.77494) (xy 147.771654 -388.77494) (xy 148.083778 -389.314944)
			(xy 148.096588 -389.338284) (xy 148.114813 -389.388303) (xy 148.124079 -389.440726) (xy 148.124672 -389.467344)
			(xy 148.124279 -389.491326) (xy 148.116773 -389.538698) (xy 148.101953 -389.584314) (xy 148.080183 -389.627052)
			(xy 148.051999 -389.665861) (xy 148.018093 -389.699785) (xy 147.9793 -389.727992) (xy 147.936575 -389.749786)
			(xy 147.890967 -389.764632) (xy 147.843599 -389.772165) (xy 147.819618 -389.772652) (xy 147.81911 -389.772652)
			(xy 147.795538 -389.772223) (xy 147.748952 -389.764984) (xy 147.704036 -389.750663) (xy 147.661859 -389.729599)
			(xy 147.623425 -389.702296) (xy 147.589652 -389.669403) (xy 147.561343 -389.631704) (xy 147.54987 -389.611108)
			(xy 147.549362 -389.610346) (xy 147.151598 -388.922006) (xy 147.139725 -388.899328) (xy 147.122872 -388.850995)
			(xy 147.114298 -388.800532) (xy 147.113752 -388.77494) (xy 133.243924 -388.77494) (xy 133.555994 -389.314944)
			(xy 133.556248 -389.315452) (xy 133.556502 -389.315452) (xy 133.557772 -389.317992) (xy 133.570041 -389.340909)
			(xy 133.587449 -389.389886) (xy 133.596324 -389.441102) (xy 133.596888 -389.46709) (xy 133.596888 -389.467344)
			(xy 133.596479 -389.491325) (xy 133.588974 -389.538695) (xy 133.574154 -389.58431) (xy 133.552386 -389.627047)
			(xy 133.524203 -389.665855) (xy 133.4903 -389.69978) (xy 133.451509 -389.727986) (xy 133.408786 -389.749782)
			(xy 133.36318 -389.764629) (xy 133.315814 -389.772164) (xy 133.291834 -389.772652) (xy 133.291326 -389.772652)
			(xy 133.267662 -389.772192) (xy 133.220902 -389.764885) (xy 133.175827 -389.750458) (xy 133.133515 -389.729255)
			(xy 133.094977 -389.701783) (xy 133.061134 -389.6687) (xy 133.032795 -389.630795) (xy 133.021324 -389.610092)
			(xy 133.02107 -389.60933) (xy 132.623814 -388.922006) (xy 132.611606 -388.898734) (xy 132.594491 -388.849053)
			(xy 132.589778 -388.8232) (xy 132.586219 -388.797977) (xy 132.057087 -388.797977) (xy 132.355844 -389.314944)
			(xy 132.356098 -389.315452) (xy 132.356352 -389.315452) (xy 132.357622 -389.317992) (xy 132.369855 -389.340916)
			(xy 132.387175 -389.389902) (xy 132.395962 -389.441111) (xy 132.396484 -389.46709) (xy 132.396484 -389.467344)
			(xy 132.396078 -389.491338) (xy 132.388564 -389.538733) (xy 132.37373 -389.58437) (xy 132.351938 -389.627124)
			(xy 132.323728 -389.665943) (xy 132.289792 -389.699872) (xy 132.250966 -389.728074) (xy 132.208207 -389.749856)
			(xy 132.162567 -389.76468) (xy 132.11517 -389.772183) (xy 132.091176 -389.772652) (xy 132.067511 -389.772232)
			(xy 132.020749 -389.764918) (xy 131.975673 -389.750483) (xy 131.933361 -389.729274) (xy 131.894823 -389.701796)
			(xy 131.860981 -389.668707) (xy 131.832644 -389.630797) (xy 131.821174 -389.610092) (xy 131.82092 -389.60933)
			(xy 131.423664 -388.922006) (xy 131.411453 -388.898736) (xy 131.39434 -388.849053) (xy 131.389628 -388.8232)
			(xy 131.386145 -388.799395) (xy 131.385933 -388.751285) (xy 130.830208 -388.751285) (xy 131.155948 -389.314944)
			(xy 131.156202 -389.315452) (xy 131.156456 -389.315452) (xy 131.157726 -389.317992) (xy 131.16996 -389.340916)
			(xy 131.187279 -389.389902) (xy 131.196066 -389.441111) (xy 131.196588 -389.46709) (xy 131.196588 -389.467344)
			(xy 131.196178 -389.491337) (xy 131.188665 -389.538733) (xy 131.17383 -389.584369) (xy 131.152039 -389.627123)
			(xy 131.123829 -389.665942) (xy 131.089893 -389.69987) (xy 131.051068 -389.728073) (xy 131.00831 -389.749854)
			(xy 130.96267 -389.76468) (xy 130.915274 -389.772183) (xy 130.89128 -389.772652) (xy 130.867615 -389.772229)
			(xy 130.820853 -389.764915) (xy 130.775777 -389.750481) (xy 130.733465 -389.729272) (xy 130.694927 -389.701795)
			(xy 130.661085 -389.668706) (xy 130.632748 -389.630797) (xy 130.621278 -389.610092) (xy 130.621024 -389.60933)
			(xy 130.223768 -388.922006) (xy 130.211557 -388.898736) (xy 130.194444 -388.849053) (xy 130.189732 -388.8232)
			(xy 130.186241 -388.799396) (xy 130.18603 -388.751285) (xy 129.630058 -388.751285) (xy 129.955798 -389.314944)
			(xy 129.956052 -389.315452) (xy 129.956306 -389.315452) (xy 129.957576 -389.317992) (xy 129.969845 -389.340909)
			(xy 129.987253 -389.389886) (xy 129.996128 -389.441102) (xy 129.996692 -389.46709) (xy 129.996692 -389.467344)
			(xy 129.996279 -389.491325) (xy 129.988774 -389.538695) (xy 129.973955 -389.584309) (xy 129.952187 -389.627046)
			(xy 129.924004 -389.665854) (xy 129.890101 -389.699778) (xy 129.851312 -389.727985) (xy 129.808589 -389.74978)
			(xy 129.762984 -389.764628) (xy 129.715618 -389.772164) (xy 129.691638 -389.772652) (xy 129.69113 -389.772652)
			(xy 129.667466 -389.772188) (xy 129.620707 -389.764882) (xy 129.575632 -389.750456) (xy 129.533319 -389.729254)
			(xy 129.494781 -389.701782) (xy 129.460938 -389.668699) (xy 129.432599 -389.630794) (xy 129.421128 -389.610092)
			(xy 129.420874 -389.60933) (xy 129.023618 -388.922006) (xy 129.01141 -388.898734) (xy 128.994295 -388.849053)
			(xy 128.989582 -388.8232) (xy 128.986016 -388.797978) (xy 128.457146 -388.797978) (xy 128.755902 -389.314944)
			(xy 128.756156 -389.315452) (xy 128.75641 -389.315452) (xy 128.75768 -389.317992) (xy 128.769949 -389.340909)
			(xy 128.787357 -389.389886) (xy 128.796232 -389.441102) (xy 128.796796 -389.46709) (xy 128.796796 -389.467344)
			(xy 128.796379 -389.491324) (xy 128.788874 -389.538694) (xy 128.774055 -389.584308) (xy 128.752287 -389.627045)
			(xy 128.724106 -389.665852) (xy 128.690203 -389.699777) (xy 128.651414 -389.727984) (xy 128.608692 -389.749779)
			(xy 128.563087 -389.764628) (xy 128.515722 -389.772163) (xy 128.491742 -389.772652) (xy 128.491234 -389.772652)
			(xy 128.467571 -389.772185) (xy 128.420811 -389.76488) (xy 128.375736 -389.750454) (xy 128.333424 -389.729252)
			(xy 128.294885 -389.701781) (xy 128.261042 -389.668699) (xy 128.232703 -389.630794) (xy 128.221232 -389.610092)
			(xy 128.220978 -389.60933) (xy 127.823722 -388.922006) (xy 127.811515 -388.898734) (xy 127.794399 -388.849053)
			(xy 127.789686 -388.8232) (xy 127.786112 -388.797979) (xy 127.257251 -388.797979) (xy 127.556006 -389.314944)
			(xy 127.55626 -389.315452) (xy 127.556514 -389.315452) (xy 127.557784 -389.317992) (xy 127.570054 -389.340909)
			(xy 127.587461 -389.389886) (xy 127.596336 -389.441101) (xy 127.5969 -389.46709) (xy 127.5969 -389.467344)
			(xy 127.596479 -389.491324) (xy 127.588974 -389.538694) (xy 127.574156 -389.584307) (xy 127.552388 -389.627044)
			(xy 127.524207 -389.665851) (xy 127.490305 -389.699775) (xy 127.451516 -389.727982) (xy 127.408794 -389.749778)
			(xy 127.36319 -389.764627) (xy 127.315826 -389.772163) (xy 127.291846 -389.772652) (xy 127.291338 -389.772652)
			(xy 127.267675 -389.772182) (xy 127.220915 -389.764877) (xy 127.17584 -389.750452) (xy 127.133528 -389.729251)
			(xy 127.094989 -389.70178) (xy 127.061146 -389.668698) (xy 127.032807 -389.630794) (xy 127.021336 -389.610092)
			(xy 127.021082 -389.60933) (xy 126.623826 -388.922006) (xy 126.611619 -388.898734) (xy 126.594503 -388.849053)
			(xy 126.58979 -388.8232) (xy 126.586378 -388.799387) (xy 126.586167 -388.751284) (xy 126.030115 -388.751284)
			(xy 126.355856 -389.314944) (xy 126.35611 -389.315452) (xy 126.356364 -389.315452) (xy 126.357634 -389.317992)
			(xy 126.369868 -389.340915) (xy 126.387188 -389.389902) (xy 126.395975 -389.441111) (xy 126.396496 -389.46709)
			(xy 126.396496 -389.467344) (xy 126.396078 -389.491337) (xy 126.388565 -389.538731) (xy 126.373731 -389.584367)
			(xy 126.351941 -389.627121) (xy 126.323731 -389.665939) (xy 126.289797 -389.699868) (xy 126.250973 -389.72807)
			(xy 126.208215 -389.749852) (xy 126.162577 -389.764678) (xy 126.115181 -389.772182) (xy 126.091188 -389.772652)
			(xy 126.067523 -389.772222) (xy 126.020762 -389.76491) (xy 125.975686 -389.750477) (xy 125.933374 -389.729269)
			(xy 125.894836 -389.701793) (xy 125.860994 -389.668705) (xy 125.832656 -389.630796) (xy 125.821186 -389.610092)
			(xy 125.820932 -389.60933) (xy 125.423676 -388.922006) (xy 125.411466 -388.898736) (xy 125.394352 -388.849053)
			(xy 125.38964 -388.8232) (xy 125.386134 -388.799398) (xy 125.385922 -388.751286) (xy 124.830221 -388.751286)
			(xy 125.15596 -389.314944) (xy 125.156214 -389.315452) (xy 125.156468 -389.315452) (xy 125.157738 -389.317992)
			(xy 125.169973 -389.340917) (xy 125.187309 -389.389899) (xy 125.196097 -389.44111) (xy 125.1966 -389.46709)
			(xy 125.1966 -389.467344) (xy 125.196126 -389.491333) (xy 125.188614 -389.538719) (xy 125.173783 -389.584346)
			(xy 125.151997 -389.627092) (xy 125.123793 -389.665904) (xy 125.089865 -389.699827) (xy 125.051048 -389.728024)
			(xy 125.008298 -389.749803) (xy 124.962668 -389.764627) (xy 124.915281 -389.77213) (xy 124.891292 -389.772652)
			(xy 124.867628 -389.772207) (xy 124.820866 -389.764906) (xy 124.77579 -389.750479) (xy 124.733478 -389.729273)
			(xy 124.694944 -389.701793) (xy 124.661109 -389.6687) (xy 124.632784 -389.630783) (xy 124.62129 -389.610092)
			(xy 124.621036 -389.60933) (xy 124.22378 -388.922006) (xy 124.211581 -388.89873) (xy 124.19446 -388.849052)
			(xy 124.189744 -388.8232) (xy 124.186351 -388.799838) (xy 124.185973 -388.752634) (xy 124.188982 -388.72922)
			(xy 124.190252 -388.72033) (xy 124.18695 -388.702804) (xy 124.143262 -388.631938) (xy 124.129546 -388.620762)
			(xy 124.12091 -388.617968) (xy 124.096643 -388.609214) (xy 124.051228 -388.584754) (xy 124.01056 -388.553022)
			(xy 123.975792 -388.514916) (xy 123.961398 -388.493508) (xy 123.95654 -388.486553) (xy 123.943213 -388.47607)
			(xy 123.927203 -388.470488) (xy 123.918726 -388.47014) (xy 123.644152 -388.47014) (xy 123.635258 -388.470472)
			(xy 123.618543 -388.476551) (xy 123.604924 -388.487992) (xy 123.60021 -388.49554) (xy 123.556268 -388.57174)
			(xy 123.552189 -388.579583) (xy 123.549083 -388.596973) (xy 123.552035 -388.61439) (xy 123.556014 -388.622286)
			(xy 123.56338 -388.635494) (xy 123.563888 -388.636764) (xy 123.95581 -389.314944) (xy 123.956064 -389.315452)
			(xy 123.956318 -389.315452) (xy 123.957588 -389.317992) (xy 123.969856 -389.340909) (xy 123.987264 -389.389886)
			(xy 123.996131 -389.441102) (xy 123.996704 -389.46709) (xy 123.996704 -389.467344) (xy 123.996231 -389.49132)
			(xy 123.988727 -389.538682) (xy 123.973911 -389.584288) (xy 123.952148 -389.627017) (xy 123.923971 -389.665818)
			(xy 123.890075 -389.699737) (xy 123.851293 -389.72794) (xy 123.808579 -389.749733) (xy 123.762982 -389.764579)
			(xy 123.715626 -389.772115) (xy 123.69165 -389.772652) (xy 123.691142 -389.772652) (xy 123.667476 -389.772211)
			(xy 123.620709 -389.764916) (xy 123.575627 -389.750495) (xy 123.53331 -389.729292) (xy 123.494769 -389.701815)
			(xy 123.460929 -389.668721) (xy 123.432598 -389.630804) (xy 123.42114 -389.610092) (xy 123.420886 -389.60933)
			(xy 123.02363 -388.922006) (xy 123.011433 -388.89873) (xy 122.994315 -388.849051) (xy 122.989594 -388.8232)
			(xy 122.986202 -388.799838) (xy 122.985823 -388.752634) (xy 122.988832 -388.72922) (xy 122.990102 -388.72033)
			(xy 122.9868 -388.702804) (xy 122.943112 -388.631938) (xy 122.929396 -388.620762) (xy 122.921014 -388.617968)
			(xy 122.896747 -388.609215) (xy 122.851331 -388.584755) (xy 122.810663 -388.553023) (xy 122.775895 -388.514917)
			(xy 122.761502 -388.493508) (xy 122.756644 -388.486553) (xy 122.743318 -388.476068) (xy 122.727307 -388.470485)
			(xy 122.71883 -388.47014) (xy 122.444256 -388.47014) (xy 122.435362 -388.470471) (xy 122.418646 -388.47655)
			(xy 122.405026 -388.48799) (xy 122.400314 -388.49554) (xy 122.356372 -388.57174) (xy 122.352292 -388.579583)
			(xy 122.349187 -388.596973) (xy 122.352139 -388.61439) (xy 122.356118 -388.622286) (xy 122.363484 -388.635494)
			(xy 122.363992 -388.636764) (xy 122.755914 -389.314944) (xy 122.756168 -389.315452) (xy 122.756422 -389.315452)
			(xy 122.757692 -389.317992) (xy 122.76996 -389.340909) (xy 122.787368 -389.389886) (xy 122.796234 -389.441102)
			(xy 122.796808 -389.46709) (xy 122.796808 -389.467344) (xy 122.796335 -389.49132) (xy 122.788831 -389.538682)
			(xy 122.774016 -389.584289) (xy 122.752252 -389.627018) (xy 122.724076 -389.66582) (xy 122.69018 -389.699739)
			(xy 122.651397 -389.727942) (xy 122.608683 -389.749735) (xy 122.563087 -389.764582) (xy 122.51573 -389.772119)
			(xy 122.491754 -389.772652) (xy 122.491246 -389.772652) (xy 122.46758 -389.772211) (xy 122.420812 -389.764917)
			(xy 122.37573 -389.750496) (xy 122.333412 -389.729293) (xy 122.294871 -389.701816) (xy 122.26103 -389.668723)
			(xy 122.232699 -389.630806) (xy 122.221244 -389.610092) (xy 122.22099 -389.60933) (xy 121.823734 -388.922006)
			(xy 121.811537 -388.89873) (xy 121.794419 -388.849051) (xy 121.789698 -388.8232) (xy 121.786306 -388.799838)
			(xy 121.785927 -388.752634) (xy 121.788936 -388.72922) (xy 121.790206 -388.72033) (xy 121.786904 -388.702804)
			(xy 121.743216 -388.631938) (xy 121.7295 -388.620762) (xy 121.720864 -388.617968) (xy 121.698073 -388.609814)
			(xy 121.655207 -388.587337) (xy 121.616424 -388.558378) (xy 121.582696 -388.523663) (xy 121.554868 -388.48406)
			(xy 121.543826 -388.46252) (xy 121.54009 -388.455482) (xy 121.529102 -388.443955) (xy 121.522236 -388.439914)
			(xy 121.506022 -388.430811) (xy 121.476184 -388.408626) (xy 121.4628 -388.395718) (xy 120.979946 -387.912864)
			(xy 120.962686 -387.894823) (xy 120.934929 -387.853329) (xy 120.915815 -387.807211) (xy 120.906082 -387.758247)
			(xy 120.905524 -387.733286) (xy 120.905524 -385.959096) (xy 120.905329 -385.952429) (xy 120.901854 -385.939555)
			(xy 120.898666 -385.933696) (xy 120.623838 -385.457954) (xy 120.611944 -385.435284) (xy 120.595078 -385.386953)
			(xy 120.586526 -385.336483) (xy 120.585992 -385.310888) (xy 120.585992 -385.31038) (xy 120.586487 -385.285456)
			(xy 120.594583 -385.236269) (xy 120.610556 -385.18905) (xy 120.633984 -385.145049) (xy 120.664244 -385.105436)
			(xy 120.700534 -385.071262) (xy 120.74189 -385.043432) (xy 120.787216 -385.022685) (xy 120.835309 -385.009571)
			(xy 120.860058 -385.006596) (xy 120.879616 -385.004564) (xy 120.905524 -384.975608) (xy 120.905524 -384.168396)
			(xy 120.905101 -384.158326) (xy 120.897388 -384.13972) (xy 120.890538 -384.132328) (xy 120.70461 -383.9464)
			(xy 120.697212 -383.939552) (xy 120.678614 -383.931814) (xy 120.668542 -383.931414) (xy 111.526066 -383.931414)
			(xy 111.513442 -383.932006) (xy 111.491163 -383.943862) (xy 111.483648 -383.95402) (xy 111.468449 -383.976163)
			(xy 111.43282 -384.016349) (xy 111.391898 -384.051132) (xy 111.346496 -384.07982) (xy 111.297514 -384.101846)
			(xy 111.245923 -384.116772) (xy 111.192747 -384.124302) (xy 111.165894 -384.124708) (xy 111.137047 -384.124179)
			(xy 111.080012 -384.115491) (xy 111.024935 -384.098314) (xy 110.973073 -384.07304) (xy 110.925607 -384.040246)
			(xy 110.904274 -384.020822) (xy 110.896908 -384.013964) (xy 110.87862 -384.006852) (xy 110.797848 -384.008122)
			(xy 110.788075 -384.008704) (xy 110.770037 -384.016267) (xy 110.762796 -384.022854) (xy 110.604554 -384.181096)
			(xy 110.597701 -384.188492) (xy 110.589957 -384.20709) (xy 110.589568 -384.217164) (xy 110.589568 -385.310888)
			(xy 114.586004 -385.310888) (xy 114.586004 -385.31038) (xy 114.586444 -385.286388) (xy 114.593954 -385.238994)
			(xy 114.608785 -385.193359) (xy 114.630572 -385.150605) (xy 114.658779 -385.111786) (xy 114.692711 -385.077858)
			(xy 114.731533 -385.049655) (xy 114.774288 -385.027872) (xy 114.819925 -385.013046) (xy 114.86732 -385.005542)
			(xy 114.891312 -385.005072) (xy 114.915246 -385.00557) (xy 114.962529 -385.013022) (xy 115.008071 -385.027757)
			(xy 115.050758 -385.049416) (xy 115.089544 -385.077467) (xy 115.12348 -385.111224) (xy 115.151736 -385.149861)
			(xy 115.163092 -385.170934) (xy 115.1636 -385.17195) (xy 115.243906 -385.310888) (xy 115.7859 -385.310888)
			(xy 115.7859 -385.31038) (xy 115.786344 -385.286388) (xy 115.793854 -385.238995) (xy 115.808684 -385.19336)
			(xy 115.830471 -385.150606) (xy 115.858677 -385.111788) (xy 115.892609 -385.077859) (xy 115.93143 -385.049656)
			(xy 115.974186 -385.027873) (xy 116.019822 -385.013047) (xy 116.067216 -385.005542) (xy 116.091208 -385.005072)
			(xy 116.115141 -385.005573) (xy 116.162424 -385.013024) (xy 116.207967 -385.027759) (xy 116.250653 -385.049417)
			(xy 116.289439 -385.077468) (xy 116.323376 -385.111224) (xy 116.351632 -385.149861) (xy 116.362988 -385.170934)
			(xy 116.363496 -385.17195) (xy 116.443802 -385.310888) (xy 116.985796 -385.310888) (xy 116.985796 -385.31038)
			(xy 116.986244 -385.286388) (xy 116.993753 -385.238995) (xy 117.008584 -385.193361) (xy 117.03037 -385.150608)
			(xy 117.058576 -385.111789) (xy 117.092507 -385.077861) (xy 117.131328 -385.049658) (xy 117.174083 -385.027875)
			(xy 117.219719 -385.013048) (xy 117.267112 -385.005542) (xy 117.291104 -385.005072) (xy 117.315037 -385.005576)
			(xy 117.36232 -385.013027) (xy 117.407862 -385.027762) (xy 117.450549 -385.049419) (xy 117.489335 -385.077469)
			(xy 117.523272 -385.111225) (xy 117.551528 -385.149861) (xy 117.562884 -385.170934) (xy 117.563392 -385.17195)
			(xy 117.643698 -385.310888) (xy 118.185692 -385.310888) (xy 118.185692 -385.31038) (xy 118.186143 -385.286401)
			(xy 118.193644 -385.239033) (xy 118.208459 -385.19342) (xy 118.230223 -385.150685) (xy 118.258401 -385.111877)
			(xy 118.292299 -385.077953) (xy 118.331085 -385.049745) (xy 118.373804 -385.027949) (xy 118.419405 -385.013099)
			(xy 118.466767 -385.005562) (xy 118.490746 -385.005072) (xy 118.491254 -385.005072) (xy 118.515189 -385.005536)
			(xy 118.562474 -385.012994) (xy 118.608017 -385.027736) (xy 118.650703 -385.0494) (xy 118.689489 -385.077456)
			(xy 118.723424 -385.111218) (xy 118.751679 -385.149859) (xy 118.763034 -385.170934) (xy 118.763542 -385.17195)
			(xy 118.843848 -385.310888) (xy 119.385588 -385.310888) (xy 119.385588 -385.31038) (xy 119.386043 -385.286401)
			(xy 119.393544 -385.239034) (xy 119.408359 -385.193421) (xy 119.430122 -385.150686) (xy 119.458299 -385.111879)
			(xy 119.492198 -385.077954) (xy 119.530983 -385.049747) (xy 119.573701 -385.02795) (xy 119.619302 -385.0131)
			(xy 119.666663 -385.005562) (xy 119.690642 -385.005072) (xy 119.69115 -385.005072) (xy 119.715085 -385.005539)
			(xy 119.762369 -385.012997) (xy 119.807912 -385.027738) (xy 119.850599 -385.049401) (xy 119.889384 -385.077457)
			(xy 119.92332 -385.111218) (xy 119.951575 -385.149859) (xy 119.96293 -385.170934) (xy 119.963438 -385.17195)
			(xy 120.355868 -385.850892) (xy 120.368606 -385.874207) (xy 120.386697 -385.924157) (xy 120.395912 -385.976476)
			(xy 120.396508 -386.003038) (xy 120.396508 -386.003292) (xy 120.396054 -386.027285) (xy 120.388549 -386.07468)
			(xy 120.373721 -386.120318) (xy 120.351937 -386.163074) (xy 120.323732 -386.201896) (xy 120.289802 -386.235827)
			(xy 120.250981 -386.264033) (xy 120.208225 -386.285818) (xy 120.162588 -386.300647) (xy 120.115193 -386.308154)
			(xy 120.0912 -386.3086) (xy 120.067626 -386.308206) (xy 120.021038 -386.300965) (xy 119.976119 -386.286639)
			(xy 119.933941 -386.26557) (xy 119.895508 -386.238261) (xy 119.861736 -386.205361) (xy 119.83343 -386.167656)
			(xy 119.82196 -386.147056) (xy 119.821452 -386.146294) (xy 119.423688 -385.457954) (xy 119.411753 -385.435296)
			(xy 119.394823 -385.386965) (xy 119.386171 -385.336491) (xy 119.385588 -385.310888) (xy 118.843848 -385.310888)
			(xy 119.155972 -385.850892) (xy 119.168711 -385.874207) (xy 119.186801 -385.924157) (xy 119.196016 -385.976476)
			(xy 119.196612 -386.003038) (xy 119.196612 -386.003292) (xy 119.196154 -386.027285) (xy 119.188649 -386.07468)
			(xy 119.173822 -386.120317) (xy 119.152038 -386.163073) (xy 119.123834 -386.201894) (xy 119.089903 -386.235826)
			(xy 119.051083 -386.264032) (xy 119.008328 -386.285817) (xy 118.962691 -386.300646) (xy 118.915297 -386.308154)
			(xy 118.891304 -386.3086) (xy 118.86773 -386.308203) (xy 118.821142 -386.300962) (xy 118.776223 -386.286637)
			(xy 118.734045 -386.265569) (xy 118.695612 -386.23826) (xy 118.66184 -386.205361) (xy 118.633535 -386.167656)
			(xy 118.622064 -386.147056) (xy 118.621556 -386.146294) (xy 118.223792 -385.457954) (xy 118.211857 -385.435295)
			(xy 118.194927 -385.386965) (xy 118.186275 -385.336491) (xy 118.185692 -385.310888) (xy 117.643698 -385.310888)
			(xy 117.955822 -385.850892) (xy 117.968645 -385.874225) (xy 117.986866 -385.924248) (xy 117.996127 -385.976673)
			(xy 117.996716 -386.003292) (xy 117.996231 -386.02727) (xy 117.988734 -386.074636) (xy 117.973924 -386.120248)
			(xy 117.952164 -386.162983) (xy 117.92399 -386.20179) (xy 117.890096 -386.235715) (xy 117.851313 -386.263923)
			(xy 117.808598 -386.28572) (xy 117.762999 -386.300571) (xy 117.71564 -386.30811) (xy 117.691662 -386.3086)
			(xy 117.691154 -386.3086) (xy 117.667582 -386.308163) (xy 117.620995 -386.300929) (xy 117.576078 -386.286611)
			(xy 117.533899 -386.26555) (xy 117.495466 -386.238247) (xy 117.461693 -386.205353) (xy 117.433385 -386.167653)
			(xy 117.421914 -386.147056) (xy 117.421406 -386.146294) (xy 117.023642 -385.457954) (xy 117.011782 -385.435269)
			(xy 116.994926 -385.38694) (xy 116.986346 -385.33648) (xy 116.985796 -385.310888) (xy 116.443802 -385.310888)
			(xy 116.755926 -385.850892) (xy 116.76875 -385.874225) (xy 116.786971 -385.924247) (xy 116.796231 -385.976673)
			(xy 116.79682 -386.003292) (xy 116.796331 -386.02727) (xy 116.788835 -386.074636) (xy 116.774024 -386.120247)
			(xy 116.752265 -386.162982) (xy 116.724092 -386.201789) (xy 116.690197 -386.235713) (xy 116.651416 -386.263922)
			(xy 116.6087 -386.285719) (xy 116.563102 -386.30057) (xy 116.515743 -386.30811) (xy 116.491766 -386.3086)
			(xy 116.491258 -386.3086) (xy 116.467686 -386.308159) (xy 116.4211 -386.300927) (xy 116.376182 -386.286609)
			(xy 116.334004 -386.265548) (xy 116.29557 -386.238246) (xy 116.261797 -386.205353) (xy 116.23349 -386.167653)
			(xy 116.222018 -386.147056) (xy 116.22151 -386.146294) (xy 115.823746 -385.457954) (xy 115.811886 -385.435269)
			(xy 115.79503 -385.38694) (xy 115.78645 -385.33648) (xy 115.7859 -385.310888) (xy 115.243906 -385.310888)
			(xy 115.55603 -385.850892) (xy 115.568854 -385.874225) (xy 115.587075 -385.924247) (xy 115.596335 -385.976673)
			(xy 115.596924 -386.003292) (xy 115.596431 -386.02727) (xy 115.588935 -386.074635) (xy 115.574125 -386.120246)
			(xy 115.552366 -386.16298) (xy 115.524193 -386.201787) (xy 115.490299 -386.235712) (xy 115.451518 -386.26392)
			(xy 115.408803 -386.285718) (xy 115.363206 -386.30057) (xy 115.315847 -386.308109) (xy 115.29187 -386.3086)
			(xy 115.291362 -386.3086) (xy 115.26779 -386.308156) (xy 115.221204 -386.300924) (xy 115.176286 -386.286607)
			(xy 115.134108 -386.265547) (xy 115.095674 -386.238245) (xy 115.061901 -386.205352) (xy 115.033594 -386.167653)
			(xy 115.022122 -386.147056) (xy 115.021614 -386.146294) (xy 114.62385 -385.457954) (xy 114.611991 -385.435269)
			(xy 114.595134 -385.38694) (xy 114.586554 -385.33648) (xy 114.586004 -385.310888) (xy 110.589568 -385.310888)
			(xy 110.589568 -386.934202) (xy 110.588996 -386.959162) (xy 110.579256 -387.008123) (xy 110.56015 -387.054242)
			(xy 110.532413 -387.095748) (xy 110.515146 -387.11378) (xy 109.939074 -387.689852) (xy 109.921033 -387.707112)
			(xy 109.87954 -387.734872) (xy 109.833422 -387.753988) (xy 109.784458 -387.763723) (xy 109.759496 -387.764274)
			(xy 108.794296 -387.764274) (xy 108.765086 -387.79196) (xy 108.763816 -387.812026) (xy 108.761727 -387.839446)
			(xy 108.75066 -387.893313) (xy 108.731978 -387.945034) (xy 108.706066 -387.993537) (xy 108.67346 -388.03782)
			(xy 108.634837 -388.076965) (xy 108.590996 -388.110161) (xy 108.542844 -388.136721) (xy 108.491378 -388.156096)
			(xy 108.437665 -388.167883) (xy 108.382816 -388.17184) (xy 108.327967 -388.167883) (xy 108.274254 -388.156096)
			(xy 108.222788 -388.136721) (xy 108.174636 -388.110161) (xy 108.130795 -388.076965) (xy 108.092172 -388.03782)
			(xy 108.059566 -387.993537) (xy 108.033654 -387.945034) (xy 108.014972 -387.893313) (xy 108.003905 -387.839446)
			(xy 108.001816 -387.812026) (xy 108.000546 -387.79196) (xy 107.971336 -387.764274) (xy 102.595172 -387.764274)
			(xy 102.585103 -387.764702) (xy 102.566504 -387.77242) (xy 102.559104 -387.77926) (xy 102.240334 -388.09803)
			(xy 102.222293 -388.115289) (xy 102.180799 -388.143044) (xy 102.134681 -388.162154) (xy 102.085717 -388.171883)
			(xy 102.060756 -388.172452) (xy 93.805248 -388.172452) (xy 93.78029 -388.171876) (xy 93.731335 -388.162127)
			(xy 93.685223 -388.143013) (xy 93.643726 -388.11527) (xy 93.62567 -388.09803) (xy 93.467936 -387.940296)
			(xy 93.431614 -387.93674) (xy 93.416628 -387.9469) (xy 93.397642 -387.959198) (xy 93.356808 -387.978659)
			(xy 93.313548 -387.99188) (xy 93.268811 -387.99857) (xy 93.246194 -387.99897) (xy 93.222202 -387.998523)
			(xy 93.17481 -387.991016) (xy 93.129175 -387.976186) (xy 93.086423 -387.9544) (xy 93.047605 -387.926193)
			(xy 93.013678 -387.892261) (xy 92.985477 -387.85344) (xy 92.963697 -387.810684) (xy 92.948874 -387.765047)
			(xy 92.941373 -387.717654) (xy 92.940886 -387.693662) (xy 92.941293 -387.671044) (xy 92.947967 -387.626302)
			(xy 92.961178 -387.583038) (xy 92.980637 -387.542201) (xy 92.992956 -387.523228) (xy 93.003116 -387.508242)
			(xy 92.99956 -387.47192) (xy 92.330524 -386.802884) (xy 92.323125 -386.79604) (xy 92.304526 -386.78832)
			(xy 92.294456 -386.787898) (xy 91.857322 -386.787898) (xy 91.847258 -386.788336) (xy 91.828674 -386.79607)
			(xy 91.821254 -386.802884) (xy 91.127834 -387.496304) (xy 91.120696 -387.504248) (xy 91.113049 -387.524162)
			(xy 91.114112 -387.545468) (xy 91.118436 -387.555232) (xy 91.118436 -387.555486) (xy 91.128833 -387.577021)
			(xy 91.143545 -387.622519) (xy 91.150986 -387.669753) (xy 91.151456 -387.693662) (xy 91.150988 -387.717657)
			(xy 91.143487 -387.765056) (xy 91.128664 -387.810698) (xy 91.106883 -387.853459) (xy 91.078681 -387.892287)
			(xy 91.044753 -387.926225) (xy 91.005933 -387.954438) (xy 90.963177 -387.976231) (xy 90.917539 -387.991067)
			(xy 90.870142 -387.998581) (xy 90.846148 -387.99897) (xy 90.82224 -387.998503) (xy 90.775008 -387.99105)
			(xy 90.729513 -387.976333) (xy 90.707972 -387.96595) (xy 90.707718 -387.96595) (xy 90.697983 -387.961498)
			(xy 90.676625 -387.960383) (xy 90.656683 -387.968113) (xy 90.64879 -387.975348) (xy 90.210132 -388.414006)
			(xy 90.202175 -388.421754) (xy 90.185131 -388.435996) (xy 90.176096 -388.442454) (xy 90.175334 -388.442962)
			(xy 90.171016 -388.446264) (xy 90.160348 -388.464044) (xy 90.148918 -388.546848) (xy 90.147954 -388.557041)
			(xy 90.153208 -388.576812) (xy 90.159078 -388.585202) (xy 90.168205 -388.597062) (xy 90.184362 -388.622253)
			(xy 90.191336 -388.635494) (xy 90.191844 -388.636764) (xy 90.258027 -388.751286) (xy 90.813717 -388.751286)
			(xy 90.821049 -388.703734) (xy 90.835743 -388.65792) (xy 90.857436 -388.614974) (xy 90.885592 -388.57596)
			(xy 90.919515 -388.54184) (xy 90.958366 -388.513459) (xy 91.001186 -388.491518) (xy 91.046915 -388.47656)
			(xy 91.094423 -388.468953) (xy 91.142537 -388.468887) (xy 91.190066 -388.476363) (xy 91.235836 -388.491195)
			(xy 91.278716 -388.513018) (xy 91.317645 -388.541292) (xy 91.351662 -388.575318) (xy 91.379925 -388.614255)
			(xy 91.391232 -388.635494) (xy 91.39174 -388.636764) (xy 91.457921 -388.751284) (xy 92.013962 -388.751284)
			(xy 92.021293 -388.703741) (xy 92.035985 -388.657935) (xy 92.057674 -388.614997) (xy 92.085825 -388.575989)
			(xy 92.119742 -388.541876) (xy 92.158586 -388.5135) (xy 92.201397 -388.491562) (xy 92.247118 -388.476605)
			(xy 92.294617 -388.468999) (xy 92.342722 -388.468931) (xy 92.390243 -388.476403) (xy 92.436005 -388.491231)
			(xy 92.478878 -388.513048) (xy 92.517802 -388.541314) (xy 92.551815 -388.575332) (xy 92.580076 -388.61426)
			(xy 92.591382 -388.635494) (xy 92.59189 -388.636764) (xy 92.658071 -388.751284) (xy 93.213865 -388.751284)
			(xy 93.221197 -388.703741) (xy 93.235888 -388.657936) (xy 93.257577 -388.614999) (xy 93.285728 -388.575992)
			(xy 93.319644 -388.541879) (xy 93.358487 -388.513503) (xy 93.401298 -388.491565) (xy 93.447018 -388.476609)
			(xy 93.494517 -388.469002) (xy 93.542621 -388.468934) (xy 93.590141 -388.476406) (xy 93.635903 -388.491234)
			(xy 93.678775 -388.51305) (xy 93.717699 -388.541316) (xy 93.751711 -388.575333) (xy 93.779972 -388.61426)
			(xy 93.791278 -388.635494) (xy 93.791786 -388.636764) (xy 93.884953 -388.797979) (xy 94.413811 -388.797979)
			(xy 94.414059 -388.747044) (xy 94.422753 -388.696855) (xy 94.43965 -388.648804) (xy 94.464283 -388.604221)
			(xy 94.49597 -388.564341) (xy 94.533833 -388.530269) (xy 94.576822 -388.502949) (xy 94.623747 -388.483138)
			(xy 94.673308 -388.471385) (xy 94.724132 -388.468014) (xy 94.774811 -388.47312) (xy 94.823942 -388.486562)
			(xy 94.870162 -388.507966) (xy 94.912192 -388.536739) (xy 94.948868 -388.572086) (xy 94.979173 -388.613025)
			(xy 94.991174 -388.635494) (xy 94.991682 -388.636764) (xy 95.057865 -388.751286) (xy 95.613824 -388.751286)
			(xy 95.621156 -388.703735) (xy 95.63585 -388.657922) (xy 95.657542 -388.614978) (xy 95.685697 -388.575964)
			(xy 95.719619 -388.541846) (xy 95.75847 -388.513466) (xy 95.801288 -388.491525) (xy 95.847015 -388.476567)
			(xy 95.894522 -388.468961) (xy 95.942634 -388.468894) (xy 95.990162 -388.476369) (xy 96.035931 -388.491201)
			(xy 96.07881 -388.513023) (xy 96.117738 -388.541296) (xy 96.151754 -388.57532) (xy 96.180017 -388.614256)
			(xy 96.191324 -388.635494) (xy 96.191832 -388.636764) (xy 96.258014 -388.751285) (xy 96.813728 -388.751285)
			(xy 96.821059 -388.703736) (xy 96.835753 -388.657923) (xy 96.857445 -388.61498) (xy 96.8856 -388.575967)
			(xy 96.919522 -388.541849) (xy 96.958371 -388.513469) (xy 97.001189 -388.491529) (xy 97.046916 -388.476571)
			(xy 97.094422 -388.468964) (xy 97.142533 -388.468898) (xy 97.19006 -388.476372) (xy 97.235829 -388.491204)
			(xy 97.278707 -388.513025) (xy 97.317635 -388.541297) (xy 97.351651 -388.575321) (xy 97.379913 -388.614256)
			(xy 97.39122 -388.635494) (xy 97.391728 -388.636764) (xy 97.484894 -388.797978) (xy 98.014014 -388.797978)
			(xy 98.014263 -388.747044) (xy 98.022956 -388.696856) (xy 98.039853 -388.648805) (xy 98.064486 -388.604223)
			(xy 98.096173 -388.564344) (xy 98.134034 -388.530272) (xy 98.177023 -388.502953) (xy 98.223948 -388.483142)
			(xy 98.273508 -388.471388) (xy 98.324331 -388.468018) (xy 98.37501 -388.473124) (xy 98.424139 -388.486565)
			(xy 98.470359 -388.507968) (xy 98.512389 -388.536741) (xy 98.549064 -388.572087) (xy 98.579369 -388.613026)
			(xy 98.59137 -388.635494) (xy 98.591878 -388.636764) (xy 98.65806 -388.751285) (xy 114.586146 -388.751285)
			(xy 114.593477 -388.703739) (xy 114.60817 -388.657929) (xy 114.629861 -388.614989) (xy 114.658013 -388.575979)
			(xy 114.691932 -388.541863) (xy 114.730779 -388.513485) (xy 114.773593 -388.491546) (xy 114.819317 -388.476589)
			(xy 114.866819 -388.468982) (xy 114.914927 -388.468915) (xy 114.962451 -388.476388) (xy 115.008216 -388.491218)
			(xy 115.051092 -388.513037) (xy 115.090018 -388.541306) (xy 115.124032 -388.575327) (xy 115.152294 -388.614258)
			(xy 115.1636 -388.635494) (xy 115.164108 -388.636764) (xy 115.230289 -388.751284) (xy 115.786049 -388.751284)
			(xy 115.793381 -388.703739) (xy 115.808073 -388.65793) (xy 115.829764 -388.614991) (xy 115.857916 -388.575981)
			(xy 115.891834 -388.541866) (xy 115.93068 -388.513488) (xy 115.973494 -388.49155) (xy 116.019217 -388.476592)
			(xy 116.066719 -388.468986) (xy 116.114826 -388.468918) (xy 116.162349 -388.476392) (xy 116.208114 -388.491221)
			(xy 116.250989 -388.513039) (xy 116.289914 -388.541308) (xy 116.323928 -388.575328) (xy 116.35219 -388.614259)
			(xy 116.363496 -388.635494) (xy 116.364004 -388.636764) (xy 116.430185 -388.751284) (xy 116.985953 -388.751284)
			(xy 116.993284 -388.70374) (xy 117.007977 -388.657932) (xy 117.029667 -388.614992) (xy 117.057819 -388.575983)
			(xy 117.091737 -388.541869) (xy 117.130582 -388.513491) (xy 117.173395 -388.491553) (xy 117.219117 -388.476596)
			(xy 117.266618 -388.468989) (xy 117.314725 -388.468922) (xy 117.362247 -388.476395) (xy 117.408011 -388.491224)
			(xy 117.450886 -388.513042) (xy 117.489811 -388.54131) (xy 117.523824 -388.575329) (xy 117.552086 -388.614259)
			(xy 117.563392 -388.635494) (xy 117.5639 -388.636764) (xy 117.630083 -388.751286) (xy 118.186008 -388.751286)
			(xy 118.19334 -388.703733) (xy 118.208035 -388.657917) (xy 118.229728 -388.61497) (xy 118.257886 -388.575954)
			(xy 118.29181 -388.541833) (xy 118.330663 -388.513451) (xy 118.373484 -388.491509) (xy 118.419215 -388.476551)
			(xy 118.466725 -388.468944) (xy 118.51484 -388.468878) (xy 118.562371 -388.476355) (xy 118.608142 -388.491188)
			(xy 118.651023 -388.513012) (xy 118.689954 -388.541288) (xy 118.723971 -388.575315) (xy 118.752235 -388.614254)
			(xy 118.763542 -388.635494) (xy 118.76405 -388.636764) (xy 118.830233 -388.751286) (xy 119.385912 -388.751286)
			(xy 119.393244 -388.703734) (xy 119.407938 -388.657918) (xy 119.429632 -388.614971) (xy 119.457788 -388.575956)
			(xy 119.491712 -388.541836) (xy 119.530564 -388.513454) (xy 119.573385 -388.491513) (xy 119.619115 -388.476554)
			(xy 119.666624 -388.468948) (xy 119.714739 -388.468882) (xy 119.762269 -388.476358) (xy 119.80804 -388.491191)
			(xy 119.85092 -388.513015) (xy 119.88985 -388.54129) (xy 119.923868 -388.575317) (xy 119.952131 -388.614255)
			(xy 119.963438 -388.635494) (xy 119.963946 -388.636764) (xy 120.030127 -388.751284) (xy 120.586156 -388.751284)
			(xy 120.593488 -388.70374) (xy 120.60818 -388.657933) (xy 120.62987 -388.614994) (xy 120.658021 -388.575986)
			(xy 120.691939 -388.541872) (xy 120.730784 -388.513495) (xy 120.773596 -388.491557) (xy 120.819317 -388.476599)
			(xy 120.866818 -388.468993) (xy 120.914924 -388.468925) (xy 120.962446 -388.476398) (xy 121.008209 -388.491226)
			(xy 121.051083 -388.513044) (xy 121.090007 -388.541311) (xy 121.124021 -388.57533) (xy 121.152282 -388.614259)
			(xy 121.163588 -388.635494) (xy 121.164096 -388.636764) (xy 121.556018 -389.314944) (xy 121.556272 -389.315452)
			(xy 121.556526 -389.315452) (xy 121.557796 -389.317992) (xy 121.570067 -389.340908) (xy 121.587474 -389.389886)
			(xy 121.596348 -389.441101) (xy 121.596912 -389.46709) (xy 121.596912 -389.467344) (xy 121.596479 -389.491324)
			(xy 121.588974 -389.538692) (xy 121.574157 -389.584305) (xy 121.55239 -389.62704) (xy 121.52421 -389.665847)
			(xy 121.49031 -389.699771) (xy 121.451523 -389.727978) (xy 121.408803 -389.749775) (xy 121.3632 -389.764624)
			(xy 121.315837 -389.772162) (xy 121.291858 -389.772652) (xy 121.29135 -389.772652) (xy 121.267687 -389.772172)
			(xy 121.220928 -389.764869) (xy 121.175853 -389.750446) (xy 121.133541 -389.729246) (xy 121.095002 -389.701777)
			(xy 121.061159 -389.668696) (xy 121.032819 -389.630793) (xy 121.021348 -389.610092) (xy 121.021094 -389.60933)
			(xy 120.623838 -388.922006) (xy 120.611625 -388.898737) (xy 120.594514 -388.849054) (xy 120.589802 -388.8232)
			(xy 120.586367 -388.799389) (xy 120.586156 -388.751284) (xy 120.030127 -388.751284) (xy 120.355868 -389.314944)
			(xy 120.356122 -389.315452) (xy 120.356376 -389.315452) (xy 120.357646 -389.317992) (xy 120.369881 -389.340915)
			(xy 120.3872 -389.389902) (xy 120.395987 -389.441111) (xy 120.396508 -389.46709) (xy 120.396508 -389.467344)
			(xy 120.396078 -389.491336) (xy 120.388565 -389.53873) (xy 120.373732 -389.584364) (xy 120.351943 -389.627117)
			(xy 120.323735 -389.665935) (xy 120.289802 -389.699863) (xy 120.250979 -389.728066) (xy 120.208224 -389.749849)
			(xy 120.162587 -389.764676) (xy 120.115192 -389.772181) (xy 120.0912 -389.772652) (xy 120.067536 -389.772213)
			(xy 120.020775 -389.764902) (xy 119.975699 -389.750471) (xy 119.933387 -389.729265) (xy 119.894849 -389.70179)
			(xy 119.861006 -389.668703) (xy 119.832668 -389.630796) (xy 119.821198 -389.610092) (xy 119.820944 -389.60933)
			(xy 119.423688 -388.922006) (xy 119.411479 -388.898735) (xy 119.394364 -388.849053) (xy 119.389652 -388.8232)
			(xy 119.386123 -388.7994) (xy 119.385912 -388.751286) (xy 118.830233 -388.751286) (xy 119.155972 -389.314944)
			(xy 119.156226 -389.315452) (xy 119.15648 -389.315452) (xy 119.15775 -389.317992) (xy 119.169986 -389.340915)
			(xy 119.187304 -389.389901) (xy 119.196091 -389.441111) (xy 119.196612 -389.46709) (xy 119.196612 -389.467344)
			(xy 119.196178 -389.491336) (xy 119.188665 -389.538729) (xy 119.173832 -389.584363) (xy 119.152044 -389.627116)
			(xy 119.123836 -389.665934) (xy 119.089903 -389.699862) (xy 119.051082 -389.728065) (xy 119.008326 -389.749848)
			(xy 118.96269 -389.764675) (xy 118.915296 -389.772181) (xy 118.891304 -389.772652) (xy 118.86764 -389.772209)
			(xy 118.820879 -389.764899) (xy 118.775803 -389.750469) (xy 118.733491 -389.729263) (xy 118.694953 -389.701789)
			(xy 118.66111 -389.668703) (xy 118.632772 -389.630796) (xy 118.621302 -389.610092) (xy 118.621048 -389.60933)
			(xy 118.223792 -388.922006) (xy 118.211583 -388.898735) (xy 118.194468 -388.849053) (xy 118.189756 -388.8232)
			(xy 118.18622 -388.799401) (xy 118.186008 -388.751286) (xy 117.630083 -388.751286) (xy 117.955822 -389.314944)
			(xy 117.956076 -389.315452) (xy 117.95633 -389.315452) (xy 117.9576 -389.317992) (xy 117.969871 -389.340908)
			(xy 117.987278 -389.389886) (xy 117.996152 -389.441101) (xy 117.996716 -389.46709) (xy 117.996716 -389.467344)
			(xy 117.996279 -389.491323) (xy 117.988775 -389.538691) (xy 117.973957 -389.584304) (xy 117.952191 -389.627039)
			(xy 117.924011 -389.665846) (xy 117.890112 -389.69977) (xy 117.851325 -389.727977) (xy 117.808605 -389.749773)
			(xy 117.763004 -389.764624) (xy 117.715641 -389.772162) (xy 117.691662 -389.772652) (xy 117.691154 -389.772652)
			(xy 117.667491 -389.772169) (xy 117.620732 -389.764867) (xy 117.575658 -389.750444) (xy 117.533345 -389.729245)
			(xy 117.494807 -389.701776) (xy 117.460963 -389.668696) (xy 117.432623 -389.630793) (xy 117.421152 -389.610092)
			(xy 117.420898 -389.60933) (xy 117.023642 -388.922006) (xy 117.011429 -388.898737) (xy 116.994318 -388.849054)
			(xy 116.989606 -388.8232) (xy 116.986164 -388.79939) (xy 116.985953 -388.751284) (xy 116.430185 -388.751284)
			(xy 116.755926 -389.314944) (xy 116.75618 -389.315452) (xy 116.756434 -389.315452) (xy 116.757704 -389.317992)
			(xy 116.769975 -389.340908) (xy 116.787382 -389.389886) (xy 116.796256 -389.441101) (xy 116.79682 -389.46709)
			(xy 116.79682 -389.467344) (xy 116.796379 -389.491323) (xy 116.788875 -389.538691) (xy 116.774057 -389.584303)
			(xy 116.752292 -389.627038) (xy 116.724113 -389.665844) (xy 116.690213 -389.699768) (xy 116.651427 -389.727975)
			(xy 116.608708 -389.749772) (xy 116.563107 -389.764623) (xy 116.515745 -389.772162) (xy 116.491766 -389.772652)
			(xy 116.491258 -389.772652) (xy 116.467595 -389.772166) (xy 116.420836 -389.764864) (xy 116.375762 -389.750442)
			(xy 116.33345 -389.729243) (xy 116.294911 -389.701775) (xy 116.261067 -389.668695) (xy 116.232727 -389.630793)
			(xy 116.221256 -389.610092) (xy 116.221002 -389.60933) (xy 115.823746 -388.922006) (xy 115.811534 -388.898737)
			(xy 115.794422 -388.849054) (xy 115.78971 -388.8232) (xy 115.78626 -388.799391) (xy 115.786049 -388.751284)
			(xy 115.230289 -388.751284) (xy 115.55603 -389.314944) (xy 115.556284 -389.315452) (xy 115.556538 -389.315452)
			(xy 115.557808 -389.317992) (xy 115.57008 -389.340908) (xy 115.587486 -389.389886) (xy 115.59636 -389.441101)
			(xy 115.596924 -389.46709) (xy 115.596924 -389.467344) (xy 115.596479 -389.491323) (xy 115.588975 -389.53869)
			(xy 115.574158 -389.584302) (xy 115.552392 -389.627036) (xy 115.524214 -389.665843) (xy 115.490315 -389.699767)
			(xy 115.451529 -389.727974) (xy 115.408811 -389.749771) (xy 115.36321 -389.764622) (xy 115.315849 -389.772161)
			(xy 115.29187 -389.772652) (xy 115.291362 -389.772652) (xy 115.267699 -389.772163) (xy 115.220941 -389.764861)
			(xy 115.175866 -389.750439) (xy 115.133554 -389.729241) (xy 115.095015 -389.701774) (xy 115.061171 -389.668695)
			(xy 115.032831 -389.630793) (xy 115.02136 -389.610092) (xy 115.021106 -389.60933) (xy 114.62385 -388.922006)
			(xy 114.611638 -388.898736) (xy 114.594526 -388.849054) (xy 114.589814 -388.8232) (xy 114.586357 -388.799392)
			(xy 114.586146 -388.751285) (xy 98.65806 -388.751285) (xy 98.9838 -389.314944) (xy 98.984054 -389.315452)
			(xy 98.984308 -389.315452) (xy 98.985578 -389.317992) (xy 98.997808 -389.340918) (xy 99.01513 -389.389903)
			(xy 99.023918 -389.441111) (xy 99.02444 -389.46709) (xy 99.02444 -389.467344) (xy 99.023978 -389.491335)
			(xy 99.016466 -389.538725) (xy 99.001635 -389.584357) (xy 98.979849 -389.627107) (xy 98.951644 -389.665924)
			(xy 98.917715 -389.699852) (xy 98.878897 -389.728055) (xy 98.836146 -389.74984) (xy 98.790513 -389.764669)
			(xy 98.743123 -389.772179) (xy 98.719132 -389.772652) (xy 98.695469 -389.772187) (xy 98.648709 -389.764881)
			(xy 98.603634 -389.750455) (xy 98.561321 -389.729253) (xy 98.522783 -389.701782) (xy 98.48894 -389.668699)
			(xy 98.460601 -389.630794) (xy 98.44913 -389.610092) (xy 98.448876 -389.60933) (xy 98.05162 -388.922006)
			(xy 98.039413 -388.898734) (xy 98.022297 -388.849053) (xy 98.017584 -388.8232) (xy 98.014014 -388.797978)
			(xy 97.484894 -388.797978) (xy 97.78365 -389.314944) (xy 97.783904 -389.315452) (xy 97.784158 -389.315452)
			(xy 97.785428 -389.317992) (xy 97.797701 -389.340907) (xy 97.815106 -389.389885) (xy 97.82398 -389.441101)
			(xy 97.824544 -389.46709) (xy 97.824544 -389.467344) (xy 97.824079 -389.491322) (xy 97.816576 -389.538687)
			(xy 97.80176 -389.584297) (xy 97.779996 -389.62703) (xy 97.75182 -389.665836) (xy 97.717923 -389.69976)
			(xy 97.67914 -389.727967) (xy 97.636425 -389.749765) (xy 97.590827 -389.764618) (xy 97.543468 -389.77216)
			(xy 97.51949 -389.772652) (xy 97.518982 -389.772652) (xy 97.495317 -389.772227) (xy 97.448555 -389.764914)
			(xy 97.40348 -389.75048) (xy 97.361167 -389.729272) (xy 97.322629 -389.701795) (xy 97.288787 -389.668706)
			(xy 97.26045 -389.630797) (xy 97.24898 -389.610092) (xy 97.248726 -389.60933) (xy 96.85147 -388.922006)
			(xy 96.839259 -388.898736) (xy 96.822146 -388.849053) (xy 96.817434 -388.8232) (xy 96.813939 -388.799396)
			(xy 96.813728 -388.751285) (xy 96.258014 -388.751285) (xy 96.583754 -389.314944) (xy 96.584008 -389.315452)
			(xy 96.584262 -389.315452) (xy 96.585532 -389.317992) (xy 96.597806 -389.340907) (xy 96.615211 -389.389885)
			(xy 96.624084 -389.441101) (xy 96.624648 -389.46709) (xy 96.624648 -389.467344) (xy 96.624179 -389.491322)
			(xy 96.616676 -389.538687) (xy 96.60186 -389.584296) (xy 96.580097 -389.627029) (xy 96.551921 -389.665835)
			(xy 96.518025 -389.699758) (xy 96.479243 -389.727966) (xy 96.436528 -389.749764) (xy 96.39093 -389.764617)
			(xy 96.343571 -389.772159) (xy 96.319594 -389.772652) (xy 96.319086 -389.772652) (xy 96.295421 -389.772224)
			(xy 96.24866 -389.764911) (xy 96.203584 -389.750478) (xy 96.161272 -389.72927) (xy 96.122734 -389.701794)
			(xy 96.088892 -389.668705) (xy 96.060554 -389.630796) (xy 96.049084 -389.610092) (xy 96.04883 -389.60933)
			(xy 95.651574 -388.922006) (xy 95.639364 -388.898736) (xy 95.62225 -388.849053) (xy 95.617538 -388.8232)
			(xy 95.614036 -388.799397) (xy 95.613824 -388.751286) (xy 95.057865 -388.751286) (xy 95.383604 -389.314944)
			(xy 95.383858 -389.315452) (xy 95.384112 -389.315452) (xy 95.385382 -389.317992) (xy 95.397612 -389.340918)
			(xy 95.414934 -389.389903) (xy 95.423722 -389.441111) (xy 95.424244 -389.46709) (xy 95.424244 -389.467344)
			(xy 95.423778 -389.491335) (xy 95.416267 -389.538724) (xy 95.401435 -389.584356) (xy 95.379649 -389.627106)
			(xy 95.351445 -389.665923) (xy 95.317517 -389.69985) (xy 95.278699 -389.728054) (xy 95.235949 -389.749838)
			(xy 95.190317 -389.764668) (xy 95.142927 -389.772179) (xy 95.118936 -389.772652) (xy 95.095273 -389.772184)
			(xy 95.048513 -389.764878) (xy 95.003438 -389.750453) (xy 94.961126 -389.729251) (xy 94.922587 -389.701781)
			(xy 94.888744 -389.668698) (xy 94.860405 -389.630794) (xy 94.848934 -389.610092) (xy 94.84868 -389.60933)
			(xy 94.451424 -388.922006) (xy 94.439217 -388.898734) (xy 94.422101 -388.849053) (xy 94.417388 -388.8232)
			(xy 94.413811 -388.797979) (xy 93.884953 -388.797979) (xy 94.183708 -389.314944) (xy 94.183962 -389.315452)
			(xy 94.184216 -389.315452) (xy 94.185486 -389.317992) (xy 94.197717 -389.340917) (xy 94.215038 -389.389902)
			(xy 94.223826 -389.441111) (xy 94.224348 -389.46709) (xy 94.224348 -389.467344) (xy 94.223878 -389.491334)
			(xy 94.216367 -389.538724) (xy 94.201536 -389.584355) (xy 94.17975 -389.627105) (xy 94.151546 -389.665922)
			(xy 94.117618 -389.699849) (xy 94.078802 -389.728052) (xy 94.036051 -389.749837) (xy 93.99042 -389.764668)
			(xy 93.94303 -389.772178) (xy 93.91904 -389.772652) (xy 93.895377 -389.77218) (xy 93.848617 -389.764876)
			(xy 93.803542 -389.750451) (xy 93.76123 -389.72925) (xy 93.722692 -389.70178) (xy 93.688848 -389.668698)
			(xy 93.660509 -389.630794) (xy 93.649038 -389.610092) (xy 93.648784 -389.60933) (xy 93.251528 -388.922006)
			(xy 93.239321 -388.898734) (xy 93.222205 -388.849053) (xy 93.217492 -388.8232) (xy 93.214076 -388.799387)
			(xy 93.213865 -388.751284) (xy 92.658071 -388.751284) (xy 92.983812 -389.314944) (xy 92.984066 -389.315452)
			(xy 92.98432 -389.315452) (xy 92.98559 -389.317992) (xy 92.997821 -389.340917) (xy 93.015142 -389.389902)
			(xy 93.02393 -389.441111) (xy 93.024452 -389.46709) (xy 93.024452 -389.467344) (xy 93.023978 -389.491334)
			(xy 93.016467 -389.538723) (xy 93.001636 -389.584354) (xy 92.979851 -389.627104) (xy 92.951648 -389.66592)
			(xy 92.91772 -389.699848) (xy 92.878904 -389.728051) (xy 92.836154 -389.749836) (xy 92.790523 -389.764667)
			(xy 92.743134 -389.772178) (xy 92.719144 -389.772652) (xy 92.695481 -389.772177) (xy 92.648721 -389.764873)
			(xy 92.603647 -389.750449) (xy 92.561334 -389.729248) (xy 92.522796 -389.701779) (xy 92.488952 -389.668697)
			(xy 92.460613 -389.630794) (xy 92.449142 -389.610092) (xy 92.448888 -389.60933) (xy 92.051632 -388.922006)
			(xy 92.039425 -388.898734) (xy 92.022309 -388.849053) (xy 92.017596 -388.8232) (xy 92.014173 -388.799388)
			(xy 92.013962 -388.751284) (xy 91.457921 -388.751284) (xy 91.783662 -389.314944) (xy 91.783916 -389.315452)
			(xy 91.78417 -389.315452) (xy 91.78544 -389.317992) (xy 91.797714 -389.340906) (xy 91.815119 -389.389885)
			(xy 91.823992 -389.441101) (xy 91.824556 -389.46709) (xy 91.824556 -389.467344) (xy 91.824079 -389.491321)
			(xy 91.816576 -389.538686) (xy 91.801761 -389.584295) (xy 91.779998 -389.627027) (xy 91.751823 -389.665832)
			(xy 91.717928 -389.699755) (xy 91.679147 -389.727963) (xy 91.636433 -389.749762) (xy 91.590837 -389.764616)
			(xy 91.543479 -389.772159) (xy 91.519502 -389.772652) (xy 91.518994 -389.772652) (xy 91.495329 -389.772217)
			(xy 91.448568 -389.764906) (xy 91.403493 -389.750474) (xy 91.36118 -389.729267) (xy 91.322642 -389.701792)
			(xy 91.2888 -389.668704) (xy 91.260462 -389.630796) (xy 91.248992 -389.610092) (xy 91.248738 -389.60933)
			(xy 90.851482 -388.922006) (xy 90.839272 -388.898735) (xy 90.822158 -388.849053) (xy 90.817446 -388.8232)
			(xy 90.813929 -388.799399) (xy 90.813717 -388.751286) (xy 90.258027 -388.751286) (xy 90.583766 -389.314944)
			(xy 90.58402 -389.315452) (xy 90.584274 -389.315452) (xy 90.585544 -389.317992) (xy 90.597813 -389.340909)
			(xy 90.615224 -389.389885) (xy 90.624092 -389.441101) (xy 90.62466 -389.46709) (xy 90.62466 -389.467344)
			(xy 90.624187 -389.491319) (xy 90.616683 -389.538678) (xy 90.601867 -389.584281) (xy 90.580102 -389.627007)
			(xy 90.551925 -389.665805) (xy 90.518028 -389.69972) (xy 90.479246 -389.727917) (xy 90.436531 -389.749705)
			(xy 90.390936 -389.764545) (xy 90.343581 -389.772074) (xy 90.319606 -389.772652) (xy 90.319098 -389.772652)
			(xy 90.295434 -389.772208) (xy 90.248671 -389.764907) (xy 90.203594 -389.750481) (xy 90.161282 -389.729275)
			(xy 90.122747 -389.701796) (xy 90.088912 -389.668702) (xy 90.060586 -389.630785) (xy 90.049096 -389.610092)
			(xy 90.048842 -389.60933) (xy 89.651586 -388.922006) (xy 89.639387 -388.89873) (xy 89.622266 -388.849052)
			(xy 89.61755 -388.8232) (xy 89.614157 -388.799838) (xy 89.613779 -388.752634) (xy 89.616788 -388.72922)
			(xy 89.618058 -388.72033) (xy 89.614756 -388.702804) (xy 89.571068 -388.631938) (xy 89.557352 -388.620762)
			(xy 89.548716 -388.617968) (xy 89.526685 -388.610094) (xy 89.485155 -388.588558) (xy 89.4474 -388.560932)
			(xy 89.414308 -388.527863) (xy 89.400126 -388.509256) (xy 89.392523 -388.499991) (xy 89.371196 -388.489121)
			(xy 89.359232 -388.488428) (xy 89.01938 -388.488428) (xy 89.009634 -388.488858) (xy 88.991558 -388.496146)
			(xy 88.977538 -388.509685) (xy 88.973152 -388.5184) (xy 88.961214 -388.544562) (xy 88.957972 -388.55285)
			(xy 88.956752 -388.57059) (xy 88.961636 -388.587688) (xy 88.966548 -388.595108) (xy 88.97339 -388.604772)
			(xy 88.985725 -388.624987) (xy 88.991186 -388.635494) (xy 88.991694 -388.636764) (xy 89.383616 -389.314944)
			(xy 89.38387 -389.315452) (xy 89.384124 -389.315452) (xy 89.385394 -389.317992) (xy 89.397627 -389.340917)
			(xy 89.41496 -389.3899) (xy 89.423746 -389.44111) (xy 89.424256 -389.46709) (xy 89.424256 -389.467344)
			(xy 89.423782 -389.491334) (xy 89.416271 -389.538724) (xy 89.40144 -389.584355) (xy 89.379655 -389.627105)
			(xy 89.351452 -389.665921) (xy 89.317524 -389.699849) (xy 89.278708 -389.728053) (xy 89.235958 -389.749839)
			(xy 89.190327 -389.76467) (xy 89.142938 -389.772182) (xy 89.118948 -389.772652) (xy 89.095282 -389.772211)
			(xy 89.048514 -389.764917) (xy 89.003432 -389.750496) (xy 88.961113 -389.729294) (xy 88.922572 -389.701817)
			(xy 88.888731 -389.668724) (xy 88.860399 -389.630807) (xy 88.848946 -389.610092) (xy 88.848692 -389.60933)
			(xy 88.451436 -388.922006) (xy 88.439239 -388.89873) (xy 88.42212 -388.849051) (xy 88.4174 -388.8232)
			(xy 88.414008 -388.799838) (xy 88.413629 -388.752634) (xy 88.416638 -388.72922) (xy 88.417908 -388.72033)
			(xy 88.414606 -388.702804) (xy 88.370918 -388.631938) (xy 88.357202 -388.620762) (xy 88.34882 -388.617968)
			(xy 88.326789 -388.610095) (xy 88.285258 -388.588559) (xy 88.247503 -388.560933) (xy 88.214411 -388.527864)
			(xy 88.20023 -388.509256) (xy 88.192627 -388.499991) (xy 88.171301 -388.489119) (xy 88.159336 -388.488428)
			(xy 87.819484 -388.488428) (xy 87.809738 -388.488858) (xy 87.79166 -388.496144) (xy 87.777639 -388.509683)
			(xy 87.773256 -388.5184) (xy 87.761318 -388.544562) (xy 87.758076 -388.552849) (xy 87.756856 -388.57059)
			(xy 87.76174 -388.587688) (xy 87.766652 -388.595108) (xy 87.773494 -388.604772) (xy 87.785829 -388.624987)
			(xy 87.79129 -388.635494) (xy 87.791798 -388.636764) (xy 88.18372 -389.314944) (xy 88.183974 -389.315452)
			(xy 88.184228 -389.315452) (xy 88.185498 -389.317992) (xy 88.197731 -389.340917) (xy 88.215064 -389.3899)
			(xy 88.223849 -389.44111) (xy 88.22436 -389.46709) (xy 88.22436 -389.467344) (xy 88.22391 -389.491334)
			(xy 88.216398 -389.538721) (xy 88.201565 -389.58435) (xy 88.179777 -389.627096) (xy 88.151569 -389.665908)
			(xy 88.117638 -389.699829) (xy 88.078818 -389.728025) (xy 88.036064 -389.7498) (xy 87.990431 -389.76462)
			(xy 87.943042 -389.772118) (xy 87.919052 -389.772652) (xy 87.895385 -389.772212) (xy 87.848618 -389.764918)
			(xy 87.803535 -389.750498) (xy 87.761216 -389.729295) (xy 87.722674 -389.701819) (xy 87.688832 -389.668726)
			(xy 87.6605 -389.630809) (xy 87.64905 -389.610092) (xy 87.648796 -389.60933) (xy 87.25154 -388.922006)
			(xy 87.239343 -388.89873) (xy 87.222224 -388.849051) (xy 87.217504 -388.8232) (xy 87.214112 -388.799838)
			(xy 87.213733 -388.752634) (xy 87.216742 -388.72922) (xy 87.218012 -388.72033) (xy 87.21471 -388.702804)
			(xy 87.171022 -388.631938) (xy 87.157306 -388.620762) (xy 87.14867 -388.617968) (xy 87.124787 -388.60942)
			(xy 87.080029 -388.585553) (xy 87.039828 -388.554619) (xy 87.00529 -388.51747) (xy 86.990936 -388.496556)
			(xy 86.98595 -388.489578) (xy 86.972319 -388.479186) (xy 86.964266 -388.476236) (xy 86.945401 -388.469644)
			(xy 86.909836 -388.451428) (xy 86.877548 -388.427888) (xy 86.863174 -388.414006) (xy 86.426548 -387.97738)
			(xy 86.409287 -387.959339) (xy 86.381527 -387.917846) (xy 86.36241 -387.871728) (xy 86.352673 -387.822764)
			(xy 86.352126 -387.797802) (xy 86.352126 -385.991608) (xy 86.351933 -385.98494) (xy 86.34846 -385.972065)
			(xy 86.345268 -385.966208) (xy 86.051644 -385.457954) (xy 86.039708 -385.435294) (xy 86.022753 -385.38697)
			(xy 86.014104 -385.336493) (xy 86.013544 -385.310888) (xy 86.013544 -385.31038) (xy 86.014031 -385.285559)
			(xy 86.022064 -385.236572) (xy 86.037915 -385.18953) (xy 86.061167 -385.145671) (xy 86.091206 -385.10615)
			(xy 86.127243 -385.072009) (xy 86.168328 -385.044147) (xy 86.213379 -385.023298) (xy 86.261209 -385.01001)
			(xy 86.285832 -385.00685) (xy 86.294737 -385.005559) (xy 86.310876 -384.997628) (xy 86.317328 -384.991356)
			(xy 86.338156 -384.969258) (xy 86.344535 -384.961936) (xy 86.351712 -384.943909) (xy 86.352126 -384.934206)
			(xy 86.352126 -384.21564) (xy 86.351693 -384.205574) (xy 86.343966 -384.186983) (xy 86.33714 -384.179572)
			(xy 86.138512 -383.980944) (xy 86.131116 -383.974091) (xy 86.112518 -383.966345) (xy 86.102444 -383.965958)
			(xy 76.928472 -383.965958) (xy 76.917185 -383.966566) (xy 76.896759 -383.976185) (xy 76.889102 -383.9845)
			(xy 76.870896 -384.00601) (xy 76.82923 -384.043952) (xy 76.782433 -384.075347) (xy 76.731525 -384.099512)
			(xy 76.677615 -384.115921) (xy 76.621876 -384.124215) (xy 76.565524 -384.124215) (xy 76.509785 -384.115921)
			(xy 76.455875 -384.099512) (xy 76.404967 -384.075347) (xy 76.35817 -384.043952) (xy 76.316504 -384.00601)
			(xy 76.298298 -383.9845) (xy 76.290676 -383.976133) (xy 76.270232 -383.966495) (xy 76.258928 -383.965958)
			(xy 74.105516 -383.965958) (xy 74.095454 -383.966398) (xy 74.076877 -383.97414) (xy 74.069448 -383.980944)
			(xy 73.547732 -384.50266) (xy 73.540892 -384.51006) (xy 73.533174 -384.528659) (xy 73.532746 -384.538728)
			(xy 73.532746 -385.310888) (xy 80.013556 -385.310888) (xy 80.013556 -385.31038) (xy 80.014043 -385.286403)
			(xy 80.021543 -385.239038) (xy 80.036355 -385.193429) (xy 80.058116 -385.150695) (xy 80.08629 -385.11189)
			(xy 80.120184 -385.077966) (xy 80.158965 -385.049758) (xy 80.201679 -385.027959) (xy 80.247275 -385.013106)
			(xy 80.294633 -385.005564) (xy 80.31861 -385.005072) (xy 80.319118 -385.005072) (xy 80.343052 -385.005565)
			(xy 80.390335 -385.013018) (xy 80.435877 -385.027754) (xy 80.478564 -385.049413) (xy 80.51735 -385.077465)
			(xy 80.551287 -385.111223) (xy 80.579542 -385.149861) (xy 80.590898 -385.170934) (xy 80.591406 -385.17195)
			(xy 80.671712 -385.310888) (xy 81.213452 -385.310888) (xy 81.213452 -385.31038) (xy 81.213943 -385.286403)
			(xy 81.221443 -385.239039) (xy 81.236255 -385.193429) (xy 81.258015 -385.150697) (xy 81.286189 -385.111891)
			(xy 81.320082 -385.077967) (xy 81.358863 -385.049759) (xy 81.401576 -385.02796) (xy 81.447172 -385.013107)
			(xy 81.494529 -385.005565) (xy 81.518506 -385.005072) (xy 81.519014 -385.005072) (xy 81.542948 -385.005568)
			(xy 81.590231 -385.013021) (xy 81.635773 -385.027756) (xy 81.67846 -385.049415) (xy 81.717246 -385.077466)
			(xy 81.751182 -385.111224) (xy 81.779438 -385.149861) (xy 81.790794 -385.170934) (xy 81.791302 -385.17195)
			(xy 81.871608 -385.310888) (xy 82.413348 -385.310888) (xy 82.413348 -385.31038) (xy 82.413843 -385.286403)
			(xy 82.421343 -385.239039) (xy 82.436155 -385.19343) (xy 82.457915 -385.150698) (xy 82.486088 -385.111892)
			(xy 82.519981 -385.077969) (xy 82.55876 -385.04976) (xy 82.601473 -385.027961) (xy 82.647069 -385.013108)
			(xy 82.694426 -385.005565) (xy 82.718402 -385.005072) (xy 82.71891 -385.005072) (xy 82.742843 -385.005571)
			(xy 82.790127 -385.013023) (xy 82.835669 -385.027758) (xy 82.878355 -385.049416) (xy 82.917142 -385.077467)
			(xy 82.951078 -385.111224) (xy 82.979334 -385.149861) (xy 82.99069 -385.170934) (xy 82.991198 -385.17195)
			(xy 83.071504 -385.310888) (xy 83.613752 -385.310888) (xy 83.613752 -385.31038) (xy 83.614244 -385.28639)
			(xy 83.621752 -385.239002) (xy 83.63658 -385.193371) (xy 83.658362 -385.150621) (xy 83.686563 -385.111804)
			(xy 83.720489 -385.077876) (xy 83.759304 -385.049673) (xy 83.802052 -385.027887) (xy 83.847682 -385.013057)
			(xy 83.89507 -385.005546) (xy 83.91906 -385.005072) (xy 83.942995 -385.005531) (xy 83.99028 -385.01299)
			(xy 84.035823 -385.027733) (xy 84.07851 -385.049398) (xy 84.117295 -385.077455) (xy 84.151231 -385.111217)
			(xy 84.179485 -385.149859) (xy 84.19084 -385.170934) (xy 84.191348 -385.17195) (xy 84.271654 -385.310888)
			(xy 84.813648 -385.310888) (xy 84.813648 -385.31038) (xy 84.814144 -385.28639) (xy 84.821652 -385.239002)
			(xy 84.836479 -385.193372) (xy 84.858261 -385.150622) (xy 84.886462 -385.111805) (xy 84.920387 -385.077878)
			(xy 84.959201 -385.049674) (xy 85.001949 -385.027888) (xy 85.047579 -385.013057) (xy 85.094966 -385.005546)
			(xy 85.118956 -385.005072) (xy 85.142891 -385.005534) (xy 85.190176 -385.012993) (xy 85.235719 -385.027735)
			(xy 85.278405 -385.049399) (xy 85.317191 -385.077456) (xy 85.351126 -385.111218) (xy 85.379381 -385.149859)
			(xy 85.390736 -385.170934) (xy 85.391244 -385.17195) (xy 85.783674 -385.850892) (xy 85.796501 -385.874223)
			(xy 85.81472 -385.924247) (xy 85.823979 -385.976673) (xy 85.824568 -386.003292) (xy 85.824131 -386.027272)
			(xy 85.816633 -386.074643) (xy 85.801819 -386.120259) (xy 85.780055 -386.162997) (xy 85.751876 -386.201806)
			(xy 85.717975 -386.235732) (xy 85.679187 -386.263939) (xy 85.636464 -386.285734) (xy 85.590859 -386.300581)
			(xy 85.543494 -386.308113) (xy 85.519514 -386.3086) (xy 85.519006 -386.3086) (xy 85.495432 -386.308201)
			(xy 85.448844 -386.300961) (xy 85.403926 -386.286636) (xy 85.361747 -386.265568) (xy 85.323314 -386.238259)
			(xy 85.289542 -386.20536) (xy 85.261237 -386.167655) (xy 85.249766 -386.147056) (xy 85.249258 -386.146294)
			(xy 84.851494 -385.457954) (xy 84.839638 -385.435267) (xy 84.822779 -385.386939) (xy 84.814198 -385.336479)
			(xy 84.813648 -385.310888) (xy 84.271654 -385.310888) (xy 84.583778 -385.850892) (xy 84.596606 -385.874223)
			(xy 84.614824 -385.924247) (xy 84.624083 -385.976673) (xy 84.624672 -386.003292) (xy 84.624231 -386.027272)
			(xy 84.616733 -386.074643) (xy 84.60192 -386.120258) (xy 84.580156 -386.162996) (xy 84.551978 -386.201805)
			(xy 84.518077 -386.235731) (xy 84.479289 -386.263938) (xy 84.436567 -386.285733) (xy 84.390963 -386.30058)
			(xy 84.343598 -386.308113) (xy 84.319618 -386.3086) (xy 84.31911 -386.3086) (xy 84.295536 -386.308198)
			(xy 84.248948 -386.300958) (xy 84.20403 -386.286634) (xy 84.161852 -386.265566) (xy 84.123418 -386.238258)
			(xy 84.089647 -386.20536) (xy 84.061341 -386.167655) (xy 84.04987 -386.147056) (xy 84.049362 -386.146294)
			(xy 83.651598 -385.457954) (xy 83.639742 -385.435267) (xy 83.622883 -385.386939) (xy 83.614302 -385.336479)
			(xy 83.613752 -385.310888) (xy 83.071504 -385.310888) (xy 83.383628 -385.850892) (xy 83.396363 -385.874209)
			(xy 83.414456 -385.924157) (xy 83.423671 -385.976476) (xy 83.424268 -386.003038) (xy 83.424268 -386.003292)
			(xy 83.423854 -386.027287) (xy 83.416348 -386.074686) (xy 83.401518 -386.120327) (xy 83.37973 -386.163086)
			(xy 83.351521 -386.201909) (xy 83.317585 -386.235841) (xy 83.278758 -386.264047) (xy 83.235997 -386.28583)
			(xy 83.190355 -386.300655) (xy 83.142955 -386.308157) (xy 83.11896 -386.3086) (xy 83.095388 -386.308158)
			(xy 83.048802 -386.300925) (xy 83.003884 -386.286608) (xy 82.961706 -386.265548) (xy 82.923272 -386.238245)
			(xy 82.889499 -386.205353) (xy 82.861192 -386.167653) (xy 82.84972 -386.147056) (xy 82.849212 -386.146294)
			(xy 82.451448 -385.457954) (xy 82.439517 -385.435293) (xy 82.422585 -385.386964) (xy 82.413931 -385.336491)
			(xy 82.413348 -385.310888) (xy 81.871608 -385.310888) (xy 82.183732 -385.850892) (xy 82.196467 -385.874209)
			(xy 82.21456 -385.924157) (xy 82.223775 -385.976476) (xy 82.224372 -386.003038) (xy 82.224372 -386.003292)
			(xy 82.223954 -386.027287) (xy 82.216448 -386.074685) (xy 82.201618 -386.120326) (xy 82.179831 -386.163085)
			(xy 82.151622 -386.201908) (xy 82.117687 -386.23584) (xy 82.078861 -386.264045) (xy 82.0361 -386.285829)
			(xy 81.990458 -386.300654) (xy 81.943059 -386.308156) (xy 81.919064 -386.3086) (xy 81.895492 -386.308155)
			(xy 81.848906 -386.300923) (xy 81.803989 -386.286606) (xy 81.76181 -386.265546) (xy 81.723376 -386.238244)
			(xy 81.689603 -386.205352) (xy 81.661296 -386.167653) (xy 81.649824 -386.147056) (xy 81.649316 -386.146294)
			(xy 81.251552 -385.457954) (xy 81.239622 -385.435293) (xy 81.222689 -385.386964) (xy 81.214035 -385.336491)
			(xy 81.213452 -385.310888) (xy 80.671712 -385.310888) (xy 80.983836 -385.850892) (xy 80.996572 -385.874209)
			(xy 81.014664 -385.924157) (xy 81.023879 -385.976476) (xy 81.024476 -386.003038) (xy 81.024476 -386.003292)
			(xy 81.024054 -386.027287) (xy 81.016548 -386.074685) (xy 81.001718 -386.120325) (xy 80.979931 -386.163083)
			(xy 80.951723 -386.201907) (xy 80.917788 -386.235839) (xy 80.878963 -386.264044) (xy 80.836203 -386.285828)
			(xy 80.790561 -386.300653) (xy 80.743163 -386.308156) (xy 80.719168 -386.3086) (xy 80.695596 -386.308151)
			(xy 80.64901 -386.30092) (xy 80.604093 -386.286604) (xy 80.561915 -386.265545) (xy 80.523481 -386.238243)
			(xy 80.489707 -386.205351) (xy 80.4614 -386.167653) (xy 80.449928 -386.147056) (xy 80.44942 -386.146294)
			(xy 80.051656 -385.457954) (xy 80.039726 -385.435293) (xy 80.022793 -385.386964) (xy 80.014139 -385.336491)
			(xy 80.013556 -385.310888) (xy 73.532746 -385.310888) (xy 73.532746 -385.705096) (xy 73.532165 -385.730052)
			(xy 73.522409 -385.779002) (xy 73.50329 -385.825109) (xy 73.475543 -385.866598) (xy 73.458324 -385.884674)
			(xy 71.882508 -387.46049) (xy 71.864467 -387.477749) (xy 71.822973 -387.505504) (xy 71.776855 -387.524613)
			(xy 71.727891 -387.534338) (xy 71.70293 -387.534912) (xy 69.882258 -387.534912) (xy 69.872191 -387.535343)
			(xy 69.853599 -387.54307) (xy 69.84619 -387.549898) (xy 69.606414 -387.789674) (xy 73.42886 -387.789674)
			(xy 73.42886 -386.926074) (xy 73.429346 -386.898805) (xy 73.437108 -386.844821) (xy 73.452473 -386.792491)
			(xy 73.47513 -386.742881) (xy 73.504616 -386.697) (xy 73.540331 -386.655783) (xy 73.581548 -386.620068)
			(xy 73.627429 -386.590582) (xy 73.677039 -386.567925) (xy 73.729369 -386.55256) (xy 73.783353 -386.544798)
			(xy 73.837891 -386.544798) (xy 73.891875 -386.55256) (xy 73.944205 -386.567925) (xy 73.993815 -386.590582)
			(xy 74.039696 -386.620068) (xy 74.080913 -386.655783) (xy 74.116628 -386.697) (xy 74.146114 -386.742881)
			(xy 74.168771 -386.792491) (xy 74.184136 -386.844821) (xy 74.191898 -386.898805) (xy 74.192384 -386.926074)
			(xy 74.192384 -387.789674) (xy 74.191898 -387.816943) (xy 74.184136 -387.870927) (xy 74.168771 -387.923257)
			(xy 74.146114 -387.972867) (xy 74.116628 -388.018748) (xy 74.080913 -388.059965) (xy 74.039696 -388.09568)
			(xy 73.993815 -388.125166) (xy 73.944205 -388.147823) (xy 73.891875 -388.163188) (xy 73.837891 -388.17095)
			(xy 73.783353 -388.17095) (xy 73.729369 -388.163188) (xy 73.677039 -388.147823) (xy 73.627429 -388.125166)
			(xy 73.581548 -388.09568) (xy 73.540331 -388.059965) (xy 73.504616 -388.018748) (xy 73.47513 -387.972867)
			(xy 73.452473 -387.923257) (xy 73.437108 -387.870927) (xy 73.429346 -387.816943) (xy 73.42886 -387.789674)
			(xy 69.606414 -387.789674) (xy 69.337936 -388.058152) (xy 69.319894 -388.07541) (xy 69.2784 -388.103163)
			(xy 69.232282 -388.122272) (xy 69.183318 -388.132) (xy 69.158358 -388.132574) (xy 61.12129 -388.132574)
			(xy 61.09633 -388.132002) (xy 61.04737 -388.12226) (xy 61.001251 -388.103153) (xy 60.959747 -388.075416)
			(xy 60.941712 -388.058152) (xy 60.865512 -387.981952) (xy 60.836556 -387.975602) (xy 60.82284 -387.980682)
			(xy 60.797715 -387.989192) (xy 60.745475 -387.998384) (xy 60.718954 -387.99897) (xy 60.718446 -387.99897)
			(xy 60.694452 -387.998527) (xy 60.647053 -387.991026) (xy 60.601411 -387.976201) (xy 60.558652 -387.954417)
			(xy 60.519827 -387.926212) (xy 60.485893 -387.892279) (xy 60.457687 -387.853455) (xy 60.435902 -387.810696)
			(xy 60.421076 -387.765055) (xy 60.413573 -387.717656) (xy 60.413138 -387.693662) (xy 60.413138 -387.693154)
			(xy 60.413732 -387.666634) (xy 60.422932 -387.614398) (xy 60.431426 -387.589268) (xy 60.436506 -387.575552)
			(xy 60.430156 -387.546596) (xy 59.67476 -386.7912) (xy 59.667359 -386.78436) (xy 59.648761 -386.77664)
			(xy 59.638692 -386.776214) (xy 59.42711 -386.776214) (xy 59.423554 -386.776722) (xy 59.412369 -386.778149)
			(xy 59.389871 -386.779672) (xy 59.378596 -386.77977) (xy 59.36732 -386.779688) (xy 59.344821 -386.778166)
			(xy 59.333638 -386.776722) (xy 59.330082 -386.776214) (xy 59.190382 -386.776214) (xy 59.180314 -386.776641)
			(xy 59.161715 -386.784361) (xy 59.154314 -386.7912) (xy 57.56656 -388.378954) (xy 57.559252 -388.387039)
			(xy 57.55161 -388.407429) (xy 57.551828 -388.418324) (xy 57.55767 -388.505446) (xy 57.56783 -388.52475)
			(xy 57.57672 -388.531354) (xy 57.594583 -388.545532) (xy 57.626315 -388.578285) (xy 57.652843 -388.615378)
			(xy 57.663588 -388.635494) (xy 57.664096 -388.636764) (xy 57.730277 -388.751284) (xy 58.28606 -388.751284)
			(xy 58.293391 -388.703741) (xy 58.308083 -388.657934) (xy 58.329773 -388.614996) (xy 58.357924 -388.575988)
			(xy 58.391841 -388.541874) (xy 58.430685 -388.513498) (xy 58.473497 -388.49156) (xy 58.519217 -388.476603)
			(xy 58.566717 -388.468997) (xy 58.614822 -388.468929) (xy 58.662344 -388.476401) (xy 58.708107 -388.491229)
			(xy 58.75098 -388.513046) (xy 58.789904 -388.541313) (xy 58.823917 -388.575331) (xy 58.852178 -388.61426)
			(xy 58.863484 -388.635494) (xy 58.863992 -388.636764) (xy 58.930175 -388.751286) (xy 59.486115 -388.751286)
			(xy 59.493447 -388.703734) (xy 59.508141 -388.657919) (xy 59.529835 -388.614973) (xy 59.557991 -388.575958)
			(xy 59.591914 -388.541839) (xy 59.630766 -388.513457) (xy 59.673585 -388.491516) (xy 59.719315 -388.476558)
			(xy 59.766824 -388.468952) (xy 59.814937 -388.468885) (xy 59.862467 -388.476361) (xy 59.908237 -388.491194)
			(xy 59.951117 -388.513017) (xy 59.990047 -388.541291) (xy 60.024064 -388.575318) (xy 60.052327 -388.614255)
			(xy 60.063634 -388.635494) (xy 60.064142 -388.636764) (xy 60.130325 -388.751286) (xy 60.686019 -388.751286)
			(xy 60.693351 -388.703735) (xy 60.708045 -388.65792) (xy 60.729738 -388.614975) (xy 60.757893 -388.575961)
			(xy 60.791816 -388.541841) (xy 60.830667 -388.513461) (xy 60.873486 -388.49152) (xy 60.919215 -388.476561)
			(xy 60.966723 -388.468955) (xy 61.014836 -388.468889) (xy 61.062365 -388.476364) (xy 61.108135 -388.491197)
			(xy 61.151014 -388.513019) (xy 61.189943 -388.541293) (xy 61.22396 -388.575319) (xy 61.252223 -388.614255)
			(xy 61.26353 -388.635494) (xy 61.264038 -388.636764) (xy 61.330221 -388.751286) (xy 61.885922 -388.751286)
			(xy 61.893254 -388.703735) (xy 61.907948 -388.657921) (xy 61.929641 -388.614977) (xy 61.957796 -388.575963)
			(xy 61.991718 -388.541844) (xy 62.030569 -388.513464) (xy 62.073387 -388.491523) (xy 62.119115 -388.476565)
			(xy 62.166623 -388.468959) (xy 62.214735 -388.468892) (xy 62.262263 -388.476368) (xy 62.308032 -388.4912)
			(xy 62.350911 -388.513022) (xy 62.38984 -388.541295) (xy 62.423856 -388.57532) (xy 62.452119 -388.614256)
			(xy 62.463426 -388.635494) (xy 62.463934 -388.636764) (xy 62.530115 -388.751284) (xy 63.086167 -388.751284)
			(xy 63.093498 -388.703742) (xy 63.10819 -388.657936) (xy 63.129879 -388.615) (xy 63.158029 -388.575993)
			(xy 63.191945 -388.54188) (xy 63.230788 -388.513504) (xy 63.273598 -388.491567) (xy 63.319318 -388.47661)
			(xy 63.366816 -388.469004) (xy 63.41492 -388.468936) (xy 63.46244 -388.476408) (xy 63.508202 -388.491235)
			(xy 63.551074 -388.513051) (xy 63.589997 -388.541317) (xy 63.624009 -388.575333) (xy 63.65227 -388.61426)
			(xy 63.663576 -388.635494) (xy 63.664084 -388.636764) (xy 63.757251 -388.797979) (xy 64.286112 -388.797979)
			(xy 64.286361 -388.747044) (xy 64.295054 -388.696856) (xy 64.311952 -388.648805) (xy 64.336585 -388.604222)
			(xy 64.368271 -388.564342) (xy 64.406133 -388.530271) (xy 64.449122 -388.502951) (xy 64.496047 -388.48314)
			(xy 64.545608 -388.471387) (xy 64.596432 -388.468016) (xy 64.647111 -388.473122) (xy 64.696241 -388.486563)
			(xy 64.742461 -388.507967) (xy 64.784491 -388.53674) (xy 64.821166 -388.572086) (xy 64.851471 -388.613026)
			(xy 64.863472 -388.635494) (xy 64.86398 -388.636764) (xy 64.930163 -388.751286) (xy 65.486126 -388.751286)
			(xy 65.493458 -388.703736) (xy 65.508151 -388.657923) (xy 65.529844 -388.614979) (xy 65.557999 -388.575966)
			(xy 65.59192 -388.541847) (xy 65.63077 -388.513467) (xy 65.673588 -388.491527) (xy 65.719316 -388.476569)
			(xy 65.766822 -388.468962) (xy 65.814934 -388.468896) (xy 65.862461 -388.476371) (xy 65.90823 -388.491202)
			(xy 65.951108 -388.513024) (xy 65.990037 -388.541297) (xy 66.024053 -388.575321) (xy 66.052315 -388.614256)
			(xy 66.063622 -388.635494) (xy 66.06413 -388.636764) (xy 66.130312 -388.751285) (xy 80.01394 -388.751285)
			(xy 80.021272 -388.703738) (xy 80.035965 -388.657927) (xy 80.057656 -388.614986) (xy 80.085809 -388.575975)
			(xy 80.119729 -388.541859) (xy 80.158577 -388.51348) (xy 80.201392 -388.491541) (xy 80.247116 -388.476583)
			(xy 80.29462 -388.468977) (xy 80.342729 -388.46891) (xy 80.390254 -388.476384) (xy 80.43602 -388.491214)
			(xy 80.478896 -388.513033) (xy 80.517823 -388.541304) (xy 80.551837 -388.575325) (xy 80.5801 -388.614258)
			(xy 80.591406 -388.635494) (xy 80.591914 -388.636764) (xy 80.658096 -388.751285) (xy 81.213844 -388.751285)
			(xy 81.221175 -388.703738) (xy 81.235868 -388.657929) (xy 81.257559 -388.614988) (xy 81.285712 -388.575977)
			(xy 81.319631 -388.541862) (xy 81.358478 -388.513483) (xy 81.401293 -388.491544) (xy 81.447017 -388.476587)
			(xy 81.49452 -388.46898) (xy 81.542628 -388.468913) (xy 81.590152 -388.476387) (xy 81.635918 -388.491217)
			(xy 81.678793 -388.513036) (xy 81.717719 -388.541305) (xy 81.751734 -388.575326) (xy 81.779996 -388.614258)
			(xy 81.791302 -388.635494) (xy 81.79181 -388.636764) (xy 81.857992 -388.751285) (xy 82.413748 -388.751285)
			(xy 82.421079 -388.703739) (xy 82.435771 -388.65793) (xy 82.457462 -388.61499) (xy 82.485615 -388.57598)
			(xy 82.519533 -388.541864) (xy 82.55838 -388.513487) (xy 82.601194 -388.491548) (xy 82.646917 -388.47659)
			(xy 82.694419 -388.468984) (xy 82.742527 -388.468917) (xy 82.79005 -388.47639) (xy 82.835815 -388.491219)
			(xy 82.87869 -388.513038) (xy 82.917616 -388.541307) (xy 82.95163 -388.575327) (xy 82.979892 -388.614258)
			(xy 82.991198 -388.635494) (xy 82.991706 -388.636764) (xy 83.057889 -388.751287) (xy 83.613803 -388.751287)
			(xy 83.621135 -388.703732) (xy 83.635829 -388.657915) (xy 83.657524 -388.614967) (xy 83.685682 -388.57595)
			(xy 83.719607 -388.541829) (xy 83.75846 -388.513446) (xy 83.801282 -388.491504) (xy 83.847014 -388.476545)
			(xy 83.894525 -388.468939) (xy 83.942642 -388.468873) (xy 83.990174 -388.47635) (xy 84.035946 -388.491184)
			(xy 84.078828 -388.513009) (xy 84.117759 -388.541285) (xy 84.151777 -388.575314) (xy 84.180041 -388.614254)
			(xy 84.191348 -388.635494) (xy 84.191856 -388.636764) (xy 84.258039 -388.751287) (xy 84.813706 -388.751287)
			(xy 84.821038 -388.703733) (xy 84.835733 -388.657916) (xy 84.857427 -388.614969) (xy 84.885584 -388.575952)
			(xy 84.919509 -388.541831) (xy 84.958362 -388.513449) (xy 85.001183 -388.491508) (xy 85.046914 -388.476549)
			(xy 85.094425 -388.468942) (xy 85.14254 -388.468877) (xy 85.190072 -388.476353) (xy 85.235844 -388.491187)
			(xy 85.278725 -388.513011) (xy 85.317655 -388.541287) (xy 85.351673 -388.575315) (xy 85.379937 -388.614254)
			(xy 85.391244 -388.635494) (xy 85.391752 -388.636764) (xy 85.457933 -388.751284) (xy 86.013951 -388.751284)
			(xy 86.021282 -388.703739) (xy 86.035975 -388.657931) (xy 86.057665 -388.614992) (xy 86.085817 -388.575982)
			(xy 86.119735 -388.541867) (xy 86.158581 -388.51349) (xy 86.201394 -388.491551) (xy 86.247117 -388.476594)
			(xy 86.294619 -388.468988) (xy 86.342725 -388.46892) (xy 86.390248 -388.476393) (xy 86.436013 -388.491222)
			(xy 86.478887 -388.513041) (xy 86.517813 -388.541309) (xy 86.551826 -388.575329) (xy 86.580088 -388.614259)
			(xy 86.591394 -388.635494) (xy 86.591902 -388.636764) (xy 86.983824 -389.314944) (xy 86.984078 -389.315452)
			(xy 86.984332 -389.315452) (xy 86.985602 -389.317992) (xy 86.997834 -389.340917) (xy 87.015155 -389.389902)
			(xy 87.023942 -389.441111) (xy 87.024464 -389.46709) (xy 87.024464 -389.467344) (xy 87.024078 -389.491339)
			(xy 87.016564 -389.538736) (xy 87.001728 -389.584375) (xy 86.979935 -389.62713) (xy 86.951722 -389.66595)
			(xy 86.917783 -389.699879) (xy 86.878955 -389.728081) (xy 86.836193 -389.749861) (xy 86.79055 -389.764684)
			(xy 86.743151 -389.772185) (xy 86.719156 -389.772652) (xy 86.695493 -389.772167) (xy 86.648734 -389.764865)
			(xy 86.60366 -389.750443) (xy 86.561348 -389.729244) (xy 86.522809 -389.701776) (xy 86.488965 -389.668695)
			(xy 86.460625 -389.630793) (xy 86.449154 -389.610092) (xy 86.4489 -389.60933) (xy 86.051644 -388.922006)
			(xy 86.039432 -388.898737) (xy 86.02232 -388.849054) (xy 86.017608 -388.8232) (xy 86.014162 -388.799391)
			(xy 86.013951 -388.751284) (xy 85.457933 -388.751284) (xy 85.783674 -389.314944) (xy 85.783928 -389.315452)
			(xy 85.784182 -389.315452) (xy 85.785452 -389.317992) (xy 85.797727 -389.340906) (xy 85.815131 -389.389885)
			(xy 85.824004 -389.441101) (xy 85.824568 -389.46709) (xy 85.824568 -389.467344) (xy 85.824179 -389.491326)
			(xy 85.816673 -389.538698) (xy 85.801852 -389.584315) (xy 85.780082 -389.627053) (xy 85.751897 -389.665862)
			(xy 85.717991 -389.699787) (xy 85.679198 -389.727993) (xy 85.636472 -389.749787) (xy 85.590864 -389.764633)
			(xy 85.543495 -389.772165) (xy 85.519514 -389.772652) (xy 85.519006 -389.772652) (xy 85.495342 -389.772208)
			(xy 85.448581 -389.764898) (xy 85.403506 -389.750468) (xy 85.361193 -389.729263) (xy 85.322655 -389.701789)
			(xy 85.288813 -389.668703) (xy 85.260474 -389.630795) (xy 85.249004 -389.610092) (xy 85.24875 -389.60933)
			(xy 84.851494 -388.922006) (xy 84.839285 -388.898735) (xy 84.822171 -388.849053) (xy 84.817458 -388.8232)
			(xy 84.813918 -388.799402) (xy 84.813706 -388.751287) (xy 84.258039 -388.751287) (xy 84.583778 -389.314944)
			(xy 84.584032 -389.315452) (xy 84.584286 -389.315452) (xy 84.585556 -389.317992) (xy 84.597831 -389.340906)
			(xy 84.615235 -389.389885) (xy 84.624108 -389.441101) (xy 84.624672 -389.46709) (xy 84.624672 -389.467344)
			(xy 84.624279 -389.491326) (xy 84.616773 -389.538698) (xy 84.601953 -389.584314) (xy 84.580183 -389.627052)
			(xy 84.551999 -389.665861) (xy 84.518093 -389.699785) (xy 84.4793 -389.727992) (xy 84.436575 -389.749786)
			(xy 84.390967 -389.764632) (xy 84.343599 -389.772165) (xy 84.319618 -389.772652) (xy 84.31911 -389.772652)
			(xy 84.295446 -389.772205) (xy 84.248685 -389.764896) (xy 84.20361 -389.750466) (xy 84.161298 -389.729261)
			(xy 84.122759 -389.701788) (xy 84.088917 -389.668702) (xy 84.060578 -389.630795) (xy 84.049108 -389.610092)
			(xy 84.048854 -389.60933) (xy 83.651598 -388.922006) (xy 83.639389 -388.898735) (xy 83.622275 -388.849053)
			(xy 83.617562 -388.8232) (xy 83.614015 -388.799402) (xy 83.613803 -388.751287) (xy 83.057889 -388.751287)
			(xy 83.383628 -389.314944) (xy 83.383882 -389.315452) (xy 83.384136 -389.315452) (xy 83.385406 -389.317992)
			(xy 83.397638 -389.340917) (xy 83.414959 -389.389902) (xy 83.423746 -389.441111) (xy 83.424268 -389.46709)
			(xy 83.424268 -389.467344) (xy 83.423878 -389.491338) (xy 83.416364 -389.538735) (xy 83.401528 -389.584374)
			(xy 83.379736 -389.627129) (xy 83.351523 -389.665949) (xy 83.317585 -389.699878) (xy 83.278757 -389.728079)
			(xy 83.235996 -389.74986) (xy 83.190354 -389.764684) (xy 83.142955 -389.772184) (xy 83.11896 -389.772652)
			(xy 83.095297 -389.772164) (xy 83.048539 -389.764863) (xy 83.003464 -389.75044) (xy 82.961152 -389.729242)
			(xy 82.922613 -389.701775) (xy 82.888769 -389.668695) (xy 82.860429 -389.630793) (xy 82.848958 -389.610092)
			(xy 82.848704 -389.60933) (xy 82.451448 -388.922006) (xy 82.439236 -388.898737) (xy 82.422124 -388.849054)
			(xy 82.417412 -388.8232) (xy 82.413959 -388.799392) (xy 82.413748 -388.751285) (xy 81.857992 -388.751285)
			(xy 82.183732 -389.314944) (xy 82.183986 -389.315452) (xy 82.18424 -389.315452) (xy 82.18551 -389.317992)
			(xy 82.197742 -389.340916) (xy 82.215063 -389.389902) (xy 82.22385 -389.441111) (xy 82.224372 -389.46709)
			(xy 82.224372 -389.467344) (xy 82.223978 -389.491338) (xy 82.216464 -389.538735) (xy 82.201628 -389.584373)
			(xy 82.179836 -389.627128) (xy 82.151624 -389.665948) (xy 82.117687 -389.699876) (xy 82.078859 -389.728078)
			(xy 82.036099 -389.749859) (xy 81.990457 -389.764683) (xy 81.943058 -389.772184) (xy 81.919064 -389.772652)
			(xy 81.895401 -389.772161) (xy 81.848643 -389.76486) (xy 81.803569 -389.750438) (xy 81.761256 -389.729241)
			(xy 81.722717 -389.701774) (xy 81.688873 -389.668694) (xy 81.660533 -389.630793) (xy 81.649062 -389.610092)
			(xy 81.648808 -389.60933) (xy 81.251552 -388.922006) (xy 81.23934 -388.898736) (xy 81.222228 -388.849054)
			(xy 81.217516 -388.8232) (xy 81.214055 -388.799392) (xy 81.213844 -388.751285) (xy 80.658096 -388.751285)
			(xy 80.983836 -389.314944) (xy 80.98409 -389.315452) (xy 80.984344 -389.315452) (xy 80.985614 -389.317992)
			(xy 80.997847 -389.340916) (xy 81.015167 -389.389902) (xy 81.023954 -389.441111) (xy 81.024476 -389.46709)
			(xy 81.024476 -389.467344) (xy 81.024078 -389.491338) (xy 81.016564 -389.538734) (xy 81.001729 -389.584372)
			(xy 80.979937 -389.627127) (xy 80.951725 -389.665946) (xy 80.917788 -389.699875) (xy 80.878962 -389.728077)
			(xy 80.836201 -389.749858) (xy 80.79056 -389.764682) (xy 80.743162 -389.772184) (xy 80.719168 -389.772652)
			(xy 80.695506 -389.772158) (xy 80.648747 -389.764857) (xy 80.603673 -389.750436) (xy 80.561361 -389.729239)
			(xy 80.522822 -389.701773) (xy 80.488978 -389.668694) (xy 80.460637 -389.630793) (xy 80.449166 -389.610092)
			(xy 80.448912 -389.60933) (xy 80.051656 -388.922006) (xy 80.039444 -388.898736) (xy 80.022332 -388.849054)
			(xy 80.01762 -388.8232) (xy 80.014152 -388.799393) (xy 80.01394 -388.751285) (xy 66.130312 -388.751285)
			(xy 66.456052 -389.314944) (xy 66.456306 -389.315452) (xy 66.45656 -389.315452) (xy 66.45783 -389.317992)
			(xy 66.470064 -389.340916) (xy 66.487383 -389.389902) (xy 66.496171 -389.441111) (xy 66.496692 -389.46709)
			(xy 66.496692 -389.467344) (xy 66.496278 -389.491337) (xy 66.488765 -389.538732) (xy 66.47393 -389.584368)
			(xy 66.45214 -389.627122) (xy 66.42393 -389.665941) (xy 66.389995 -389.699869) (xy 66.351171 -389.728071)
			(xy 66.308412 -389.749853) (xy 66.262774 -389.764679) (xy 66.215377 -389.772183) (xy 66.191384 -389.772652)
			(xy 66.167719 -389.772226) (xy 66.120957 -389.764913) (xy 66.075882 -389.750479) (xy 66.033569 -389.729271)
			(xy 65.995032 -389.701794) (xy 65.961189 -389.668706) (xy 65.932852 -389.630796) (xy 65.921382 -389.610092)
			(xy 65.921128 -389.60933) (xy 65.523872 -388.922006) (xy 65.511661 -388.898736) (xy 65.494548 -388.849053)
			(xy 65.489836 -388.8232) (xy 65.486338 -388.799397) (xy 65.486126 -388.751286) (xy 64.930163 -388.751286)
			(xy 65.255902 -389.314944) (xy 65.256156 -389.315452) (xy 65.25641 -389.315452) (xy 65.25768 -389.317992)
			(xy 65.269949 -389.340909) (xy 65.287357 -389.389886) (xy 65.296232 -389.441102) (xy 65.296796 -389.46709)
			(xy 65.296796 -389.467344) (xy 65.296379 -389.491324) (xy 65.288874 -389.538694) (xy 65.274055 -389.584308)
			(xy 65.252287 -389.627045) (xy 65.224106 -389.665852) (xy 65.190203 -389.699777) (xy 65.151414 -389.727984)
			(xy 65.108692 -389.749779) (xy 65.063087 -389.764628) (xy 65.015722 -389.772163) (xy 64.991742 -389.772652)
			(xy 64.991234 -389.772652) (xy 64.967571 -389.772185) (xy 64.920811 -389.76488) (xy 64.875736 -389.750454)
			(xy 64.833424 -389.729252) (xy 64.794885 -389.701781) (xy 64.761042 -389.668699) (xy 64.732703 -389.630794)
			(xy 64.721232 -389.610092) (xy 64.720978 -389.60933) (xy 64.323722 -388.922006) (xy 64.311515 -388.898734)
			(xy 64.294399 -388.849053) (xy 64.289686 -388.8232) (xy 64.286112 -388.797979) (xy 63.757251 -388.797979)
			(xy 64.056006 -389.314944) (xy 64.05626 -389.315452) (xy 64.056514 -389.315452) (xy 64.057784 -389.317992)
			(xy 64.070054 -389.340909) (xy 64.087461 -389.389886) (xy 64.096336 -389.441101) (xy 64.0969 -389.46709)
			(xy 64.0969 -389.467344) (xy 64.096479 -389.491324) (xy 64.088974 -389.538694) (xy 64.074156 -389.584307)
			(xy 64.052388 -389.627044) (xy 64.024207 -389.665851) (xy 63.990305 -389.699775) (xy 63.951516 -389.727982)
			(xy 63.908794 -389.749778) (xy 63.86319 -389.764627) (xy 63.815826 -389.772163) (xy 63.791846 -389.772652)
			(xy 63.791338 -389.772652) (xy 63.767675 -389.772182) (xy 63.720915 -389.764877) (xy 63.67584 -389.750452)
			(xy 63.633528 -389.729251) (xy 63.594989 -389.70178) (xy 63.561146 -389.668698) (xy 63.532807 -389.630794)
			(xy 63.521336 -389.610092) (xy 63.521082 -389.60933) (xy 63.123826 -388.922006) (xy 63.111619 -388.898734)
			(xy 63.094503 -388.849053) (xy 63.08979 -388.8232) (xy 63.086378 -388.799387) (xy 63.086167 -388.751284)
			(xy 62.530115 -388.751284) (xy 62.855856 -389.314944) (xy 62.85611 -389.315452) (xy 62.856364 -389.315452)
			(xy 62.857634 -389.317992) (xy 62.869868 -389.340915) (xy 62.887188 -389.389902) (xy 62.895975 -389.441111)
			(xy 62.896496 -389.46709) (xy 62.896496 -389.467344) (xy 62.896078 -389.491337) (xy 62.888565 -389.538731)
			(xy 62.873731 -389.584367) (xy 62.851941 -389.627121) (xy 62.823731 -389.665939) (xy 62.789797 -389.699868)
			(xy 62.750973 -389.72807) (xy 62.708215 -389.749852) (xy 62.662577 -389.764678) (xy 62.615181 -389.772182)
			(xy 62.591188 -389.772652) (xy 62.567523 -389.772222) (xy 62.520762 -389.76491) (xy 62.475686 -389.750477)
			(xy 62.433374 -389.729269) (xy 62.394836 -389.701793) (xy 62.360994 -389.668705) (xy 62.332656 -389.630796)
			(xy 62.321186 -389.610092) (xy 62.320932 -389.60933) (xy 61.923676 -388.922006) (xy 61.911466 -388.898736)
			(xy 61.894352 -388.849053) (xy 61.88964 -388.8232) (xy 61.886134 -388.799398) (xy 61.885922 -388.751286)
			(xy 61.330221 -388.751286) (xy 61.65596 -389.314944) (xy 61.656214 -389.315452) (xy 61.656468 -389.315452)
			(xy 61.657738 -389.317992) (xy 61.669973 -389.340915) (xy 61.687292 -389.389902) (xy 61.696079 -389.441111)
			(xy 61.6966 -389.46709) (xy 61.6966 -389.467344) (xy 61.696178 -389.491337) (xy 61.688665 -389.538731)
			(xy 61.673831 -389.584366) (xy 61.652041 -389.627119) (xy 61.623832 -389.665938) (xy 61.589898 -389.699866)
			(xy 61.551075 -389.728069) (xy 61.508318 -389.749851) (xy 61.46268 -389.764677) (xy 61.415285 -389.772182)
			(xy 61.391292 -389.772652) (xy 61.367627 -389.772219) (xy 61.320866 -389.764907) (xy 61.27579 -389.750475)
			(xy 61.233478 -389.729268) (xy 61.19494 -389.701792) (xy 61.161098 -389.668705) (xy 61.13276 -389.630796)
			(xy 61.12129 -389.610092) (xy 61.121036 -389.60933) (xy 60.72378 -388.922006) (xy 60.71157 -388.898735)
			(xy 60.694456 -388.849053) (xy 60.689744 -388.8232) (xy 60.686231 -388.799399) (xy 60.686019 -388.751286)
			(xy 60.130325 -388.751286) (xy 60.456064 -389.314944) (xy 60.456318 -389.315452) (xy 60.456572 -389.315452)
			(xy 60.457842 -389.317992) (xy 60.470077 -389.340915) (xy 60.487396 -389.389902) (xy 60.496183 -389.441111)
			(xy 60.496704 -389.46709) (xy 60.496704 -389.467344) (xy 60.496278 -389.491337) (xy 60.488765 -389.53873)
			(xy 60.473931 -389.584365) (xy 60.452142 -389.627118) (xy 60.423933 -389.665937) (xy 60.39 -389.699865)
			(xy 60.351177 -389.728067) (xy 60.308421 -389.74985) (xy 60.262783 -389.764676) (xy 60.215389 -389.772182)
			(xy 60.191396 -389.772652) (xy 60.167731 -389.772216) (xy 60.12097 -389.764905) (xy 60.075895 -389.750473)
			(xy 60.033582 -389.729266) (xy 59.995044 -389.701791) (xy 59.961202 -389.668704) (xy 59.932864 -389.630796)
			(xy 59.921394 -389.610092) (xy 59.92114 -389.60933) (xy 59.523884 -388.922006) (xy 59.511674 -388.898735)
			(xy 59.49456 -388.849053) (xy 59.489848 -388.8232) (xy 59.486327 -388.799399) (xy 59.486115 -388.751286)
			(xy 58.930175 -388.751286) (xy 59.255914 -389.314944) (xy 59.256168 -389.315452) (xy 59.256422 -389.315452)
			(xy 59.257692 -389.317992) (xy 59.269962 -389.340908) (xy 59.287369 -389.389886) (xy 59.296244 -389.441101)
			(xy 59.296808 -389.46709) (xy 59.296808 -389.467344) (xy 59.296379 -389.491324) (xy 59.288874 -389.538693)
			(xy 59.274056 -389.584306) (xy 59.252289 -389.627041) (xy 59.224109 -389.665848) (xy 59.190208 -389.699772)
			(xy 59.15142 -389.72798) (xy 59.1087 -389.749776) (xy 59.063097 -389.764625) (xy 59.015733 -389.772162)
			(xy 58.991754 -389.772652) (xy 58.991246 -389.772652) (xy 58.967583 -389.772176) (xy 58.920824 -389.764872)
			(xy 58.875749 -389.750448) (xy 58.833437 -389.729248) (xy 58.794898 -389.701778) (xy 58.761054 -389.668697)
			(xy 58.732715 -389.630794) (xy 58.721244 -389.610092) (xy 58.72099 -389.60933) (xy 58.323734 -388.922006)
			(xy 58.311528 -388.898734) (xy 58.294411 -388.849053) (xy 58.289698 -388.8232) (xy 58.286271 -388.799389)
			(xy 58.28606 -388.751284) (xy 57.730277 -388.751284) (xy 58.056018 -389.314944) (xy 58.056272 -389.315452)
			(xy 58.056526 -389.315452) (xy 58.057796 -389.317992) (xy 58.070064 -389.340909) (xy 58.087471 -389.389886)
			(xy 58.096338 -389.441102) (xy 58.096912 -389.46709) (xy 58.096912 -389.467344) (xy 58.096439 -389.49132)
			(xy 58.088935 -389.538683) (xy 58.07412 -389.584289) (xy 58.052356 -389.627019) (xy 58.02418 -389.665821)
			(xy 57.990284 -389.699741) (xy 57.951502 -389.727944) (xy 57.908787 -389.749738) (xy 57.863191 -389.764585)
			(xy 57.815834 -389.772122) (xy 57.791858 -389.772652) (xy 57.79135 -389.772652) (xy 57.767683 -389.772212)
			(xy 57.720916 -389.764918) (xy 57.675833 -389.750497) (xy 57.633515 -389.729295) (xy 57.594973 -389.701818)
			(xy 57.561132 -389.668725) (xy 57.5328 -389.630808) (xy 57.521348 -389.610092) (xy 57.521094 -389.60933)
			(xy 57.123838 -388.922006) (xy 57.111641 -388.89873) (xy 57.094522 -388.849051) (xy 57.089802 -388.8232)
			(xy 57.08641 -388.799838) (xy 57.086031 -388.752634) (xy 57.08904 -388.72922) (xy 57.09031 -388.72033)
			(xy 57.087008 -388.702804) (xy 57.04332 -388.631938) (xy 57.029604 -388.620762) (xy 57.020968 -388.617968)
			(xy 56.994552 -388.607554) (xy 56.984646 -388.603236) (xy 56.532526 -388.603236) (xy 56.523635 -388.603572)
			(xy 56.506925 -388.609657) (xy 56.493313 -388.621099) (xy 56.488584 -388.628636) (xy 56.48443 -388.636509)
			(xy 56.481347 -388.654031) (xy 56.484451 -388.67155) (xy 56.488584 -388.679436) (xy 56.855868 -389.314944)
			(xy 56.856122 -389.315452) (xy 56.856376 -389.315452) (xy 56.857646 -389.317992) (xy 56.869881 -389.340917)
			(xy 56.887216 -389.389899) (xy 56.896004 -389.44111) (xy 56.896508 -389.46709) (xy 56.896508 -389.467344)
			(xy 56.896034 -389.491333) (xy 56.888523 -389.538719) (xy 56.873691 -389.584347) (xy 56.851905 -389.627094)
			(xy 56.823701 -389.665907) (xy 56.789773 -389.69983) (xy 56.750956 -389.728028) (xy 56.708207 -389.749808)
			(xy 56.662576 -389.764633) (xy 56.615189 -389.772138) (xy 56.5912 -389.772652) (xy 56.567535 -389.772208)
			(xy 56.520773 -389.764908) (xy 56.475696 -389.750482) (xy 56.433383 -389.729276) (xy 56.394848 -389.701797)
			(xy 56.361012 -389.668703) (xy 56.332686 -389.630786) (xy 56.321198 -389.610092) (xy 56.320944 -389.60933)
			(xy 55.923688 -388.922006) (xy 55.911489 -388.89873) (xy 55.894368 -388.849052) (xy 55.889652 -388.8232)
			(xy 55.886259 -388.799838) (xy 55.885881 -388.752634) (xy 55.88889 -388.72922) (xy 55.89016 -388.72033)
			(xy 55.886858 -388.702804) (xy 55.84317 -388.631938) (xy 55.829454 -388.620762) (xy 55.821072 -388.617968)
			(xy 55.794656 -388.607554) (xy 55.78475 -388.603236) (xy 55.33263 -388.603236) (xy 55.323738 -388.603571)
			(xy 55.307028 -388.609655) (xy 55.293415 -388.621097) (xy 55.288688 -388.628636) (xy 55.284533 -388.636509)
			(xy 55.28145 -388.654031) (xy 55.284555 -388.67155) (xy 55.288688 -388.679436) (xy 55.655972 -389.314944)
			(xy 55.656226 -389.315452) (xy 55.65648 -389.315452) (xy 55.65775 -389.317992) (xy 55.669984 -389.340917)
			(xy 55.68732 -389.389899) (xy 55.696107 -389.44111) (xy 55.696612 -389.46709) (xy 55.696612 -389.467344)
			(xy 55.696138 -389.491333) (xy 55.688627 -389.53872) (xy 55.673795 -389.584348) (xy 55.652009 -389.627095)
			(xy 55.623805 -389.665908) (xy 55.589877 -389.699831) (xy 55.551061 -389.72803) (xy 55.508311 -389.749811)
			(xy 55.462681 -389.764636) (xy 55.415293 -389.772141) (xy 55.391304 -389.772652) (xy 55.367639 -389.772208)
			(xy 55.320876 -389.764908) (xy 55.275799 -389.750483) (xy 55.233486 -389.729277) (xy 55.19495 -389.701799)
			(xy 55.161114 -389.668705) (xy 55.132787 -389.630788) (xy 55.121302 -389.610092) (xy 55.121048 -389.60933)
			(xy 54.723792 -388.922006) (xy 54.711593 -388.89873) (xy 54.694471 -388.849052) (xy 54.689756 -388.8232)
			(xy 54.686363 -388.799838) (xy 54.685985 -388.752634) (xy 54.688994 -388.72922) (xy 54.690264 -388.72033)
			(xy 54.686962 -388.702804) (xy 54.643274 -388.631938) (xy 54.629558 -388.620762) (xy 54.620922 -388.617968)
			(xy 54.594506 -388.607554) (xy 54.5846 -388.603236) (xy 54.548278 -388.603236) (xy 54.523322 -388.602623)
			(xy 54.474369 -388.592882) (xy 54.428257 -388.573781) (xy 54.386756 -388.546051) (xy 54.3687 -388.528814)
			(xy 53.92166 -388.081774) (xy 53.904399 -388.063733) (xy 53.876638 -388.02224) (xy 53.857522 -387.976122)
			(xy 53.847786 -387.927158) (xy 53.847238 -387.902196) (xy 53.847238 -386.031232) (xy 53.847048 -386.024563)
			(xy 53.843582 -386.011684) (xy 53.84038 -386.005832) (xy 53.523896 -385.457954) (xy 53.511962 -385.435293)
			(xy 53.495009 -385.386969) (xy 53.486362 -385.336493) (xy 53.485796 -385.310888) (xy 53.485796 -385.31038)
			(xy 53.486245 -385.286375) (xy 53.493762 -385.238958) (xy 53.508608 -385.193302) (xy 53.530416 -385.150531)
			(xy 53.55865 -385.111702) (xy 53.592613 -385.077769) (xy 53.631469 -385.049571) (xy 53.674259 -385.027801)
			(xy 53.719929 -385.012997) (xy 53.767353 -385.005523) (xy 53.791358 -385.005072) (xy 53.795676 -385.005072)
			(xy 53.831998 -384.969258) (xy 53.838954 -384.961835) (xy 53.846833 -384.943099) (xy 53.847238 -384.932936)
			(xy 53.847238 -384.033776) (xy 53.847812 -384.008817) (xy 53.857556 -383.959858) (xy 53.876665 -383.913742)
			(xy 53.904405 -383.872241) (xy 53.92166 -383.854198) (xy 54.17058 -383.605278) (xy 54.177425 -383.597879)
			(xy 54.185155 -383.579281) (xy 54.185566 -383.56921) (xy 54.185566 -375.978674) (xy 54.185137 -375.968607)
			(xy 54.177413 -375.950012) (xy 54.17058 -375.942606) (xy 51.999642 -373.771668) (xy 51.992244 -373.764823)
			(xy 51.973645 -373.757099) (xy 51.963574 -373.756682) (xy 49.455832 -373.756682) (xy 49.444411 -373.757308)
			(xy 49.423822 -373.767197) (xy 49.416208 -373.775732) (xy 49.366678 -373.837454) (xy 49.36002 -373.846781)
			(xy 49.354876 -373.869078) (xy 49.356772 -373.88038) (xy 49.361028 -373.900752) (xy 49.365607 -373.94212)
			(xy 49.365916 -373.96293) (xy 49.36545 -373.990198) (xy 49.357685 -374.04418) (xy 49.342315 -374.096506)
			(xy 49.319655 -374.146112) (xy 49.290166 -374.191989) (xy 49.254448 -374.233202) (xy 49.213228 -374.268912)
			(xy 49.167346 -374.298392) (xy 49.117735 -374.321042) (xy 49.065405 -374.336401) (xy 49.011423 -374.344156)
			(xy 48.984154 -374.344692) (xy 48.120554 -374.344692) (xy 48.093286 -374.344202) (xy 48.039306 -374.336436)
			(xy 47.98698 -374.321067) (xy 47.937374 -374.298408) (xy 47.891496 -374.268922) (xy 47.850282 -374.233207)
			(xy 47.814569 -374.191991) (xy 47.785084 -374.146112) (xy 47.762428 -374.096505) (xy 47.747061 -374.044179)
			(xy 47.739296 -373.990198) (xy 47.738792 -373.96293) (xy 47.739094 -373.94212) (xy 47.743671 -373.900751)
			(xy 47.747936 -373.88038) (xy 47.749835 -373.869078) (xy 47.744691 -373.846779) (xy 47.73803 -373.837454)
			(xy 47.6885 -373.775732) (xy 47.680867 -373.767221) (xy 47.66029 -373.757334) (xy 47.648876 -373.756682)
			(xy 38.613334 -373.756682) (xy 38.603995 -373.75716) (xy 38.586585 -373.763944) (xy 38.572735 -373.776487)
			(xy 38.568122 -373.784622) (xy 38.518846 -373.88292) (xy 38.519354 -373.88927) (xy 38.520211 -373.896258)
			(xy 38.525228 -373.909407) (xy 38.52926 -373.915178) (xy 38.584001 -373.989411) (xy 38.687856 -374.141862)
			(xy 38.785106 -374.29861) (xy 38.875573 -374.459367) (xy 38.959093 -374.623841) (xy 39.035513 -374.791732)
			(xy 39.104694 -374.962733) (xy 39.166509 -375.136532) (xy 39.220846 -375.312812) (xy 39.267606 -375.491252)
			(xy 39.306702 -375.671526) (xy 39.338065 -375.853306) (xy 39.361636 -376.036258) (xy 39.377373 -376.220051)
			(xy 39.385247 -376.404348) (xy 39.385748 -376.49658) (xy 39.385248 -376.589497) (xy 39.377253 -376.77516)
			(xy 39.372361 -376.83186) (xy 41.04894 -376.83186) (xy 41.04894 -375.96826) (xy 41.049426 -375.940991)
			(xy 41.057188 -375.887007) (xy 41.072553 -375.834677) (xy 41.09521 -375.785067) (xy 41.124696 -375.739186)
			(xy 41.160411 -375.697969) (xy 41.201628 -375.662254) (xy 41.247509 -375.632768) (xy 41.297119 -375.610111)
			(xy 41.349449 -375.594746) (xy 41.403433 -375.586984) (xy 41.457971 -375.586984) (xy 41.511955 -375.594746)
			(xy 41.564285 -375.610111) (xy 41.613895 -375.632768) (xy 41.659776 -375.662254) (xy 41.700993 -375.697969)
			(xy 41.736708 -375.739186) (xy 41.766194 -375.785067) (xy 41.788851 -375.834677) (xy 41.804216 -375.887007)
			(xy 41.811978 -375.940991) (xy 41.812464 -375.96826) (xy 41.812464 -376.83186) (xy 41.811978 -376.859129)
			(xy 41.804216 -376.913113) (xy 41.788851 -376.965443) (xy 41.766194 -377.015053) (xy 41.736708 -377.060934)
			(xy 41.700993 -377.102151) (xy 41.659776 -377.137866) (xy 41.613895 -377.167352) (xy 41.564285 -377.190009)
			(xy 41.511955 -377.205374) (xy 41.457971 -377.213136) (xy 41.403433 -377.213136) (xy 41.349449 -377.205374)
			(xy 41.297119 -377.190009) (xy 41.247509 -377.167352) (xy 41.201628 -377.137866) (xy 41.160411 -377.102151)
			(xy 41.124696 -377.060934) (xy 41.09521 -377.015053) (xy 41.072553 -376.965443) (xy 41.057188 -376.913113)
			(xy 41.049426 -376.859129) (xy 41.04894 -376.83186) (xy 39.372361 -376.83186) (xy 39.361278 -376.960306)
			(xy 39.337352 -377.144594) (xy 39.30552 -377.327682) (xy 39.26584 -377.509231) (xy 39.218387 -377.688905)
			(xy 39.163247 -377.866371) (xy 39.100524 -378.0413) (xy 39.030333 -378.213369) (xy 38.952804 -378.382258)
			(xy 38.868081 -378.547656) (xy 38.77632 -378.709256) (xy 38.677692 -378.866758) (xy 38.572379 -379.019872)
			(xy 38.460577 -379.168312) (xy 38.342492 -379.311806) (xy 38.218342 -379.450086) (xy 38.088359 -379.582897)
			(xy 37.952782 -379.709993) (xy 37.811862 -379.831138) (xy 37.665862 -379.946109) (xy 37.51505 -380.054692)
			(xy 37.359706 -380.156685) (xy 37.200118 -380.251902) (xy 37.036581 -380.340164) (xy 36.869399 -380.421309)
			(xy 36.69888 -380.495186) (xy 36.525341 -380.561659) (xy 36.349102 -380.620604) (xy 36.170491 -380.671912)
			(xy 35.989838 -380.715489) (xy 35.807477 -380.751253) (xy 35.623747 -380.779139) (xy 35.438987 -380.799094)
			(xy 35.25354 -380.811082) (xy 35.067748 -380.81508) (xy 34.881956 -380.811082) (xy 34.696509 -380.799094)
			(xy 34.511749 -380.779139) (xy 34.328019 -380.751253) (xy 34.145658 -380.715489) (xy 33.965005 -380.671912)
			(xy 33.786394 -380.620604) (xy 33.610155 -380.561659) (xy 33.436616 -380.495186) (xy 33.266097 -380.421309)
			(xy 33.098915 -380.340164) (xy 32.935378 -380.251902) (xy 32.77579 -380.156685) (xy 32.620446 -380.054692)
			(xy 32.469634 -379.946109) (xy 32.323634 -379.831138) (xy 32.182714 -379.709993) (xy 32.047137 -379.582897)
			(xy 31.917154 -379.450086) (xy 31.793004 -379.311806) (xy 31.674919 -379.168312) (xy 31.563117 -379.019872)
			(xy 31.457804 -378.866758) (xy 31.359176 -378.709256) (xy 31.267415 -378.547656) (xy 31.182692 -378.382258)
			(xy 31.105163 -378.213369) (xy 31.034972 -378.0413) (xy 30.972249 -377.866371) (xy 30.917109 -377.688905)
			(xy 30.869656 -377.509231) (xy 30.829976 -377.327682) (xy 30.798144 -377.144594) (xy 30.774218 -376.960306)
			(xy 30.758243 -376.77516) (xy 30.750248 -376.589497) (xy 30.749748 -376.49658) (xy 30.750244 -376.403871)
			(xy 30.758204 -376.218623) (xy 30.774108 -376.033887) (xy 30.797928 -375.850004) (xy 30.829619 -375.667314)
			(xy 30.869123 -375.486152) (xy 30.916367 -375.306853) (xy 30.971264 -375.129747) (xy 31.033713 -374.955161)
			(xy 31.103599 -374.783416) (xy 31.180792 -374.61483) (xy 31.265151 -374.449712) (xy 31.35652 -374.288368)
			(xy 31.45473 -374.131095) (xy 31.559601 -373.978182) (xy 31.614872 -373.903748) (xy 31.61665 -373.88292)
			(xy 31.567374 -373.784622) (xy 31.562804 -373.776448) (xy 31.548962 -373.76386) (xy 31.531516 -373.757101)
			(xy 31.522162 -373.756682) (xy 8.497062 -373.756682) (xy 8.486994 -373.757111) (xy 8.468398 -373.764834)
			(xy 8.460994 -373.771668) (xy 7.408164 -374.824498) (xy 7.40131 -374.831893) (xy 7.393565 -374.850492)
			(xy 7.393178 -374.860566) (xy 7.393178 -379.238256) (xy 7.393611 -379.248322) (xy 7.401337 -379.266914)
			(xy 7.408164 -379.274324) (xy 10.5029 -382.36906) (xy 41.04894 -382.36906) (xy 41.04894 -381.50546)
			(xy 41.049426 -381.478191) (xy 41.057188 -381.424207) (xy 41.072553 -381.371877) (xy 41.09521 -381.322267)
			(xy 41.124696 -381.276386) (xy 41.160411 -381.235169) (xy 41.201628 -381.199454) (xy 41.247509 -381.169968)
			(xy 41.297119 -381.147311) (xy 41.349449 -381.131946) (xy 41.403433 -381.124184) (xy 41.457971 -381.124184)
			(xy 41.511955 -381.131946) (xy 41.564285 -381.147311) (xy 41.613895 -381.169968) (xy 41.659776 -381.199454)
			(xy 41.700993 -381.235169) (xy 41.736708 -381.276386) (xy 41.766194 -381.322267) (xy 41.788851 -381.371877)
			(xy 41.804216 -381.424207) (xy 41.811978 -381.478191) (xy 41.812464 -381.50546) (xy 41.812464 -382.36906)
			(xy 41.811978 -382.396329) (xy 41.804216 -382.450313) (xy 41.788851 -382.502643) (xy 41.766194 -382.552253)
			(xy 41.736708 -382.598134) (xy 41.700993 -382.639351) (xy 41.659776 -382.675066) (xy 41.613895 -382.704552)
			(xy 41.564285 -382.727209) (xy 41.511955 -382.742574) (xy 41.457971 -382.750336) (xy 41.403433 -382.750336)
			(xy 41.349449 -382.742574) (xy 41.297119 -382.727209) (xy 41.247509 -382.704552) (xy 41.201628 -382.675066)
			(xy 41.160411 -382.639351) (xy 41.124696 -382.598134) (xy 41.09521 -382.552253) (xy 41.072553 -382.502643)
			(xy 41.057188 -382.450313) (xy 41.049426 -382.396329) (xy 41.04894 -382.36906) (xy 10.5029 -382.36906)
			(xy 12.091162 -383.957322) (xy 12.10183 -383.961132) (xy 12.128078 -383.971075) (xy 12.177565 -383.997561)
			(xy 12.222637 -384.03101) (xy 12.262323 -384.070702) (xy 12.295767 -384.115778) (xy 12.322246 -384.165268)
			(xy 12.332208 -384.19151) (xy 12.336018 -384.202178) (xy 12.513056 -384.379216) (xy 12.532106 -384.386836)
			(xy 12.542266 -384.386582) (xy 12.54887 -384.386582) (xy 12.576125 -384.387043) (xy 12.630079 -384.394796)
			(xy 12.682381 -384.41015) (xy 12.731966 -384.43279) (xy 12.777824 -384.462257) (xy 12.819021 -384.497951)
			(xy 12.854719 -384.539144) (xy 12.884191 -384.584999) (xy 12.906836 -384.634581) (xy 12.922195 -384.686882)
			(xy 12.929954 -384.740836) (xy 12.930378 -384.76809) (xy 12.930378 -384.774694) (xy 12.930124 -384.784854)
			(xy 12.937744 -384.803904) (xy 13.444728 -385.310888) (xy 47.485808 -385.310888) (xy 47.485808 -385.31038)
			(xy 47.486243 -385.2864) (xy 47.493745 -385.239031) (xy 47.508561 -385.193417) (xy 47.530326 -385.15068)
			(xy 47.558505 -385.111872) (xy 47.592406 -385.077947) (xy 47.631194 -385.04974) (xy 47.673915 -385.027944)
			(xy 47.719518 -385.013096) (xy 47.766882 -385.00556) (xy 47.790862 -385.005072) (xy 47.79137 -385.005072)
			(xy 47.815305 -385.005523) (xy 47.862591 -385.012984) (xy 47.908134 -385.027728) (xy 47.950821 -385.049394)
			(xy 47.989606 -385.077452) (xy 48.023541 -385.111216) (xy 48.051795 -385.149858) (xy 48.06315 -385.170934)
			(xy 48.063658 -385.17195) (xy 48.143964 -385.310888) (xy 48.685704 -385.310888) (xy 48.685704 -385.31038)
			(xy 48.686143 -385.2864) (xy 48.693645 -385.239031) (xy 48.70846 -385.193417) (xy 48.730225 -385.150681)
			(xy 48.758404 -385.111873) (xy 48.792304 -385.077949) (xy 48.831092 -385.049741) (xy 48.873812 -385.027945)
			(xy 48.919415 -385.013097) (xy 48.966779 -385.005561) (xy 48.990758 -385.005072) (xy 48.991266 -385.005072)
			(xy 49.015201 -385.005526) (xy 49.062486 -385.012986) (xy 49.10803 -385.02773) (xy 49.150716 -385.049395)
			(xy 49.189502 -385.077453) (xy 49.223437 -385.111216) (xy 49.251691 -385.149859) (xy 49.263046 -385.170934)
			(xy 49.263554 -385.17195) (xy 49.34386 -385.310888) (xy 49.8856 -385.310888) (xy 49.8856 -385.31038)
			(xy 49.886043 -385.286401) (xy 49.893545 -385.239032) (xy 49.90836 -385.193418) (xy 49.930124 -385.150682)
			(xy 49.958303 -385.111875) (xy 49.992203 -385.07795) (xy 50.030989 -385.049743) (xy 50.073709 -385.027946)
			(xy 50.119312 -385.013097) (xy 50.166675 -385.005561) (xy 50.190654 -385.005072) (xy 50.191162 -385.005072)
			(xy 50.215097 -385.005529) (xy 50.262382 -385.012989) (xy 50.307925 -385.027732) (xy 50.350612 -385.049397)
			(xy 50.389397 -385.077454) (xy 50.423333 -385.111217) (xy 50.451587 -385.149859) (xy 50.462942 -385.170934)
			(xy 50.46345 -385.17195) (xy 50.543756 -385.310888) (xy 51.086004 -385.310888) (xy 51.086004 -385.31038)
			(xy 51.086444 -385.286388) (xy 51.093954 -385.238994) (xy 51.108785 -385.193359) (xy 51.130572 -385.150605)
			(xy 51.158779 -385.111786) (xy 51.192711 -385.077858) (xy 51.231533 -385.049655) (xy 51.274288 -385.027872)
			(xy 51.319925 -385.013046) (xy 51.36732 -385.005542) (xy 51.391312 -385.005072) (xy 51.415246 -385.00557)
			(xy 51.462529 -385.013022) (xy 51.508071 -385.027757) (xy 51.550758 -385.049416) (xy 51.589544 -385.077467)
			(xy 51.62348 -385.111224) (xy 51.651736 -385.149861) (xy 51.663092 -385.170934) (xy 51.6636 -385.17195)
			(xy 51.743906 -385.310888) (xy 52.2859 -385.310888) (xy 52.2859 -385.31038) (xy 52.286344 -385.286388)
			(xy 52.293854 -385.238995) (xy 52.308684 -385.19336) (xy 52.330471 -385.150606) (xy 52.358677 -385.111788)
			(xy 52.392609 -385.077859) (xy 52.43143 -385.049656) (xy 52.474186 -385.027873) (xy 52.519822 -385.013047)
			(xy 52.567216 -385.005542) (xy 52.591208 -385.005072) (xy 52.615141 -385.005573) (xy 52.662424 -385.013024)
			(xy 52.707967 -385.027759) (xy 52.750653 -385.049417) (xy 52.789439 -385.077468) (xy 52.823376 -385.111224)
			(xy 52.851632 -385.149861) (xy 52.862988 -385.170934) (xy 52.863496 -385.17195) (xy 53.255926 -385.850892)
			(xy 53.26875 -385.874225) (xy 53.286971 -385.924247) (xy 53.296231 -385.976673) (xy 53.29682 -386.003292)
			(xy 53.296331 -386.02727) (xy 53.288835 -386.074636) (xy 53.274024 -386.120247) (xy 53.252265 -386.162982)
			(xy 53.224092 -386.201789) (xy 53.190197 -386.235713) (xy 53.151416 -386.263922) (xy 53.1087 -386.285719)
			(xy 53.063102 -386.30057) (xy 53.015743 -386.30811) (xy 52.991766 -386.3086) (xy 52.991258 -386.3086)
			(xy 52.967686 -386.308159) (xy 52.9211 -386.300927) (xy 52.876182 -386.286609) (xy 52.834004 -386.265548)
			(xy 52.79557 -386.238246) (xy 52.761797 -386.205353) (xy 52.73349 -386.167653) (xy 52.722018 -386.147056)
			(xy 52.72151 -386.146294) (xy 52.323746 -385.457954) (xy 52.311886 -385.435269) (xy 52.29503 -385.38694)
			(xy 52.28645 -385.33648) (xy 52.2859 -385.310888) (xy 51.743906 -385.310888) (xy 52.05603 -385.850892)
			(xy 52.068854 -385.874225) (xy 52.087075 -385.924247) (xy 52.096335 -385.976673) (xy 52.096924 -386.003292)
			(xy 52.096431 -386.02727) (xy 52.088935 -386.074635) (xy 52.074125 -386.120246) (xy 52.052366 -386.16298)
			(xy 52.024193 -386.201787) (xy 51.990299 -386.235712) (xy 51.951518 -386.26392) (xy 51.908803 -386.285718)
			(xy 51.863206 -386.30057) (xy 51.815847 -386.308109) (xy 51.79187 -386.3086) (xy 51.791362 -386.3086)
			(xy 51.76779 -386.308156) (xy 51.721204 -386.300924) (xy 51.676286 -386.286607) (xy 51.634108 -386.265547)
			(xy 51.595674 -386.238245) (xy 51.561901 -386.205352) (xy 51.533594 -386.167653) (xy 51.522122 -386.147056)
			(xy 51.521614 -386.146294) (xy 51.12385 -385.457954) (xy 51.111991 -385.435269) (xy 51.095134 -385.38694)
			(xy 51.086554 -385.33648) (xy 51.086004 -385.310888) (xy 50.543756 -385.310888) (xy 50.85588 -385.850892)
			(xy 50.868619 -385.874207) (xy 50.886709 -385.924157) (xy 50.895924 -385.976476) (xy 50.89652 -386.003038)
			(xy 50.89652 -386.003292) (xy 50.89603 -386.027282) (xy 50.888526 -386.074673) (xy 50.8737 -386.120306)
			(xy 50.851918 -386.163057) (xy 50.823717 -386.201876) (xy 50.789791 -386.235804) (xy 50.750974 -386.264008)
			(xy 50.708224 -386.285792) (xy 50.662592 -386.300621) (xy 50.615202 -386.308128) (xy 50.591212 -386.3086)
			(xy 50.567638 -386.308197) (xy 50.521051 -386.300957) (xy 50.476132 -386.286633) (xy 50.433954 -386.265566)
			(xy 50.395521 -386.238258) (xy 50.361749 -386.205359) (xy 50.333443 -386.167655) (xy 50.321972 -386.147056)
			(xy 50.321464 -386.146294) (xy 49.9237 -385.457954) (xy 49.911766 -385.435295) (xy 49.894835 -385.386965)
			(xy 49.886183 -385.336491) (xy 49.8856 -385.310888) (xy 49.34386 -385.310888) (xy 49.655984 -385.850892)
			(xy 49.668715 -385.874211) (xy 49.68681 -385.924158) (xy 49.696027 -385.976477) (xy 49.696624 -386.003038)
			(xy 49.696624 -386.003292) (xy 49.69613 -386.027282) (xy 49.688626 -386.074672) (xy 49.6738 -386.120305)
			(xy 49.652019 -386.163056) (xy 49.623818 -386.201874) (xy 49.589892 -386.235803) (xy 49.551077 -386.264007)
			(xy 49.508327 -386.285791) (xy 49.462695 -386.30062) (xy 49.415306 -386.308128) (xy 49.391316 -386.3086)
			(xy 49.367742 -386.308193) (xy 49.321155 -386.300954) (xy 49.276236 -386.286631) (xy 49.234058 -386.265564)
			(xy 49.195625 -386.238257) (xy 49.161853 -386.205359) (xy 49.133547 -386.167655) (xy 49.122076 -386.147056)
			(xy 49.121568 -386.146294) (xy 48.723804 -385.457954) (xy 48.71187 -385.435295) (xy 48.694939 -385.386965)
			(xy 48.686287 -385.336491) (xy 48.685704 -385.310888) (xy 48.143964 -385.310888) (xy 48.456088 -385.850892)
			(xy 48.46882 -385.874211) (xy 48.486915 -385.924158) (xy 48.496131 -385.976477) (xy 48.496728 -386.003038)
			(xy 48.496728 -386.003292) (xy 48.49623 -386.027282) (xy 48.488726 -386.074672) (xy 48.473901 -386.120304)
			(xy 48.45212 -386.163055) (xy 48.42392 -386.201873) (xy 48.389994 -386.235801) (xy 48.351179 -386.264005)
			(xy 48.30843 -386.28579) (xy 48.262799 -386.300619) (xy 48.21541 -386.308128) (xy 48.19142 -386.3086)
			(xy 48.167847 -386.30819) (xy 48.121259 -386.300952) (xy 48.076341 -386.286629) (xy 48.034162 -386.265563)
			(xy 47.995729 -386.238256) (xy 47.961957 -386.205358) (xy 47.933651 -386.167655) (xy 47.92218 -386.147056)
			(xy 47.921672 -386.146294) (xy 47.523908 -385.457954) (xy 47.511974 -385.435295) (xy 47.495043 -385.386965)
			(xy 47.486391 -385.336491) (xy 47.485808 -385.310888) (xy 13.444728 -385.310888) (xy 14.714728 -386.580888)
			(xy 14.721586 -386.584444) (xy 14.746548 -386.598055) (xy 14.792392 -386.63168) (xy 14.832595 -386.67188)
			(xy 14.866225 -386.71772) (xy 14.879828 -386.742686) (xy 14.883384 -386.749544) (xy 15.923514 -387.789674)
			(xy 40.901112 -387.789674) (xy 40.901112 -386.926074) (xy 40.901598 -386.898805) (xy 40.90936 -386.844821)
			(xy 40.924725 -386.792491) (xy 40.947382 -386.742881) (xy 40.976868 -386.697) (xy 41.012583 -386.655783)
			(xy 41.0538 -386.620068) (xy 41.099681 -386.590582) (xy 41.149291 -386.567925) (xy 41.201621 -386.55256)
			(xy 41.255605 -386.544798) (xy 41.310143 -386.544798) (xy 41.364127 -386.55256) (xy 41.416457 -386.567925)
			(xy 41.466067 -386.590582) (xy 41.511948 -386.620068) (xy 41.553165 -386.655783) (xy 41.58888 -386.697)
			(xy 41.618366 -386.742881) (xy 41.641023 -386.792491) (xy 41.656388 -386.844821) (xy 41.66415 -386.898805)
			(xy 41.664636 -386.926074) (xy 41.664636 -387.789674) (xy 41.66415 -387.816943) (xy 41.656388 -387.870927)
			(xy 41.641023 -387.923257) (xy 41.618366 -387.972867) (xy 41.58888 -388.018748) (xy 41.553165 -388.059965)
			(xy 41.511948 -388.09568) (xy 41.466067 -388.125166) (xy 41.416457 -388.147823) (xy 41.364127 -388.163188)
			(xy 41.310143 -388.17095) (xy 41.255605 -388.17095) (xy 41.201621 -388.163188) (xy 41.149291 -388.147823)
			(xy 41.099681 -388.125166) (xy 41.0538 -388.09568) (xy 41.012583 -388.059965) (xy 40.976868 -388.018748)
			(xy 40.947382 -387.972867) (xy 40.924725 -387.923257) (xy 40.90936 -387.870927) (xy 40.901598 -387.816943)
			(xy 40.901112 -387.789674) (xy 15.923514 -387.789674) (xy 16.31061 -388.17677) (xy 16.319287 -388.18461)
			(xy 16.341407 -388.192121) (xy 16.364571 -388.189104) (xy 16.374618 -388.18312) (xy 16.374872 -388.18312)
			(xy 16.397919 -388.16834) (xy 16.447434 -388.144974) (xy 16.499837 -388.129115) (xy 16.553999 -388.121104)
			(xy 16.581374 -388.120636) (xy 16.607993 -388.121109) (xy 16.660689 -388.128681) (xy 16.71177 -388.143676)
			(xy 16.760199 -388.165787) (xy 16.804987 -388.194566) (xy 16.845224 -388.229425) (xy 16.880091 -388.269655)
			(xy 16.908878 -388.314438) (xy 16.930999 -388.362862) (xy 16.946003 -388.413941) (xy 16.953586 -388.466635)
			(xy 16.953992 -388.493254) (xy 16.953505 -388.520628) (xy 16.945486 -388.574784) (xy 16.929628 -388.627185)
			(xy 16.906272 -388.6767) (xy 16.891508 -388.699756) (xy 16.891508 -388.70001) (xy 16.885482 -388.710051)
			(xy 16.882414 -388.733239) (xy 16.889953 -388.755381) (xy 16.897858 -388.764018) (xy 16.931816 -388.797976)
			(xy 47.486325 -388.797976) (xy 47.486573 -388.747043) (xy 47.495267 -388.696858) (xy 47.512163 -388.648809)
			(xy 47.536795 -388.604229) (xy 47.56848 -388.564351) (xy 47.60634 -388.530281) (xy 47.649327 -388.502963)
			(xy 47.696249 -388.483153) (xy 47.745807 -388.471399) (xy 47.796628 -388.468029) (xy 47.847305 -388.473134)
			(xy 47.896432 -388.486573) (xy 47.942651 -388.507975) (xy 47.984679 -388.536747) (xy 48.021353 -388.57209)
			(xy 48.051657 -388.613027) (xy 48.063658 -388.635494) (xy 48.064166 -388.636764) (xy 48.15733 -388.797975)
			(xy 48.686228 -388.797975) (xy 48.686477 -388.747043) (xy 48.69517 -388.696859) (xy 48.712067 -388.648811)
			(xy 48.736698 -388.604231) (xy 48.768383 -388.564354) (xy 48.806242 -388.530284) (xy 48.849228 -388.502966)
			(xy 48.89615 -388.483156) (xy 48.945707 -388.471403) (xy 48.996528 -388.468032) (xy 49.047203 -388.473137)
			(xy 49.09633 -388.486576) (xy 49.142548 -388.507978) (xy 49.184575 -388.536748) (xy 49.221249 -388.572091)
			(xy 49.251553 -388.613027) (xy 49.263554 -388.635494) (xy 49.264062 -388.636764) (xy 49.330245 -388.751287)
			(xy 49.885901 -388.751287) (xy 49.893233 -388.703732) (xy 49.907928 -388.657914) (xy 49.929622 -388.614966)
			(xy 49.95778 -388.575949) (xy 49.991706 -388.541827) (xy 50.03056 -388.513445) (xy 50.073382 -388.491502)
			(xy 50.119114 -388.476543) (xy 50.166626 -388.468937) (xy 50.214742 -388.468871) (xy 50.262274 -388.476348)
			(xy 50.308047 -388.491183) (xy 50.350929 -388.513008) (xy 50.389861 -388.541284) (xy 50.423879 -388.575313)
			(xy 50.452143 -388.614254) (xy 50.46345 -388.635494) (xy 50.463958 -388.636764) (xy 50.53014 -388.751285)
			(xy 51.086146 -388.751285) (xy 51.093477 -388.703739) (xy 51.10817 -388.657929) (xy 51.129861 -388.614989)
			(xy 51.158013 -388.575979) (xy 51.191932 -388.541863) (xy 51.230779 -388.513485) (xy 51.273593 -388.491546)
			(xy 51.319317 -388.476589) (xy 51.366819 -388.468982) (xy 51.414927 -388.468915) (xy 51.462451 -388.476388)
			(xy 51.508216 -388.491218) (xy 51.551092 -388.513037) (xy 51.590018 -388.541306) (xy 51.624032 -388.575327)
			(xy 51.652294 -388.614258) (xy 51.6636 -388.635494) (xy 51.664108 -388.636764) (xy 51.730289 -388.751284)
			(xy 52.286049 -388.751284) (xy 52.293381 -388.703739) (xy 52.308073 -388.65793) (xy 52.329764 -388.614991)
			(xy 52.357916 -388.575981) (xy 52.391834 -388.541866) (xy 52.43068 -388.513488) (xy 52.473494 -388.49155)
			(xy 52.519217 -388.476592) (xy 52.566719 -388.468986) (xy 52.614826 -388.468918) (xy 52.662349 -388.476392)
			(xy 52.708114 -388.491221) (xy 52.750989 -388.513039) (xy 52.789914 -388.541308) (xy 52.823928 -388.575328)
			(xy 52.85219 -388.614259) (xy 52.863496 -388.635494) (xy 52.864004 -388.636764) (xy 52.930187 -388.751287)
			(xy 53.486104 -388.751287) (xy 53.493436 -388.703733) (xy 53.508131 -388.657915) (xy 53.529825 -388.614968)
			(xy 53.557983 -388.575951) (xy 53.591908 -388.54183) (xy 53.630761 -388.513448) (xy 53.673583 -388.491506)
			(xy 53.719314 -388.476547) (xy 53.766825 -388.468941) (xy 53.814941 -388.468875) (xy 53.862473 -388.476351)
			(xy 53.908245 -388.491185) (xy 53.951126 -388.51301) (xy 53.990057 -388.541286) (xy 54.024075 -388.575314)
			(xy 54.052339 -388.614254) (xy 54.063646 -388.635494) (xy 54.064154 -388.636764) (xy 54.456076 -389.314944)
			(xy 54.45633 -389.315452) (xy 54.456584 -389.315452) (xy 54.457854 -389.317992) (xy 54.47009 -389.340915)
			(xy 54.487408 -389.389901) (xy 54.496195 -389.441111) (xy 54.496716 -389.46709) (xy 54.496716 -389.467344)
			(xy 54.496278 -389.491336) (xy 54.488766 -389.538728) (xy 54.473933 -389.584362) (xy 54.452144 -389.627115)
			(xy 54.423937 -389.665932) (xy 54.390005 -389.69986) (xy 54.351184 -389.728063) (xy 54.308429 -389.749846)
			(xy 54.262793 -389.764674) (xy 54.2154 -389.772181) (xy 54.191408 -389.772652) (xy 54.167744 -389.772206)
			(xy 54.120983 -389.764897) (xy 54.075908 -389.750467) (xy 54.033595 -389.729262) (xy 53.995057 -389.701788)
			(xy 53.961215 -389.668702) (xy 53.932876 -389.630795) (xy 53.921406 -389.610092) (xy 53.921152 -389.60933)
			(xy 53.523896 -388.922006) (xy 53.511687 -388.898735) (xy 53.494573 -388.849053) (xy 53.48986 -388.8232)
			(xy 53.486316 -388.799402) (xy 53.486104 -388.751287) (xy 52.930187 -388.751287) (xy 53.255926 -389.314944)
			(xy 53.25618 -389.315452) (xy 53.256434 -389.315452) (xy 53.257704 -389.317992) (xy 53.269975 -389.340908)
			(xy 53.287382 -389.389886) (xy 53.296256 -389.441101) (xy 53.29682 -389.46709) (xy 53.29682 -389.467344)
			(xy 53.296379 -389.491323) (xy 53.288875 -389.538691) (xy 53.274057 -389.584303) (xy 53.252292 -389.627038)
			(xy 53.224113 -389.665844) (xy 53.190213 -389.699768) (xy 53.151427 -389.727975) (xy 53.108708 -389.749772)
			(xy 53.063107 -389.764623) (xy 53.015745 -389.772162) (xy 52.991766 -389.772652) (xy 52.991258 -389.772652)
			(xy 52.967595 -389.772166) (xy 52.920836 -389.764864) (xy 52.875762 -389.750442) (xy 52.83345 -389.729243)
			(xy 52.794911 -389.701775) (xy 52.761067 -389.668695) (xy 52.732727 -389.630793) (xy 52.721256 -389.610092)
			(xy 52.721002 -389.60933) (xy 52.323746 -388.922006) (xy 52.311534 -388.898737) (xy 52.294422 -388.849054)
			(xy 52.28971 -388.8232) (xy 52.28626 -388.799391) (xy 52.286049 -388.751284) (xy 51.730289 -388.751284)
			(xy 52.05603 -389.314944) (xy 52.056284 -389.315452) (xy 52.056538 -389.315452) (xy 52.057808 -389.317992)
			(xy 52.07008 -389.340908) (xy 52.087486 -389.389886) (xy 52.09636 -389.441101) (xy 52.096924 -389.46709)
			(xy 52.096924 -389.467344) (xy 52.096479 -389.491323) (xy 52.088975 -389.53869) (xy 52.074158 -389.584302)
			(xy 52.052392 -389.627036) (xy 52.024214 -389.665843) (xy 51.990315 -389.699767) (xy 51.951529 -389.727974)
			(xy 51.908811 -389.749771) (xy 51.86321 -389.764622) (xy 51.815849 -389.772161) (xy 51.79187 -389.772652)
			(xy 51.791362 -389.772652) (xy 51.767699 -389.772163) (xy 51.720941 -389.764861) (xy 51.675866 -389.750439)
			(xy 51.633554 -389.729241) (xy 51.595015 -389.701774) (xy 51.561171 -389.668695) (xy 51.532831 -389.630793)
			(xy 51.52136 -389.610092) (xy 51.521106 -389.60933) (xy 51.12385 -388.922006) (xy 51.111638 -388.898736)
			(xy 51.094526 -388.849054) (xy 51.089814 -388.8232) (xy 51.086357 -388.799392) (xy 51.086146 -388.751285)
			(xy 50.53014 -388.751285) (xy 50.85588 -389.314944) (xy 50.856134 -389.315452) (xy 50.856388 -389.315452)
			(xy 50.857658 -389.317992) (xy 50.869894 -389.340914) (xy 50.887212 -389.389901) (xy 50.895999 -389.441111)
			(xy 50.89652 -389.46709) (xy 50.89652 -389.467344) (xy 50.896078 -389.491336) (xy 50.888566 -389.538728)
			(xy 50.873733 -389.584362) (xy 50.851945 -389.627113) (xy 50.823738 -389.665931) (xy 50.789807 -389.699859)
			(xy 50.750986 -389.728062) (xy 50.708232 -389.749845) (xy 50.662597 -389.764673) (xy 50.615204 -389.772181)
			(xy 50.591212 -389.772652) (xy 50.567548 -389.772203) (xy 50.520787 -389.764894) (xy 50.475712 -389.750465)
			(xy 50.4334 -389.72926) (xy 50.394862 -389.701787) (xy 50.361019 -389.668702) (xy 50.33268 -389.630795)
			(xy 50.32121 -389.610092) (xy 50.320956 -389.60933) (xy 49.9237 -388.922006) (xy 49.911491 -388.898735)
			(xy 49.894377 -388.849053) (xy 49.889664 -388.8232) (xy 49.886113 -388.799403) (xy 49.885901 -388.751287)
			(xy 49.330245 -388.751287) (xy 49.655984 -389.314944) (xy 49.656238 -389.315452) (xy 49.656492 -389.315452)
			(xy 49.657762 -389.317992) (xy 49.669999 -389.340914) (xy 49.687316 -389.389901) (xy 49.696103 -389.441111)
			(xy 49.696624 -389.46709) (xy 49.696624 -389.467344) (xy 49.696178 -389.491336) (xy 49.688666 -389.538727)
			(xy 49.673833 -389.584361) (xy 49.652046 -389.627112) (xy 49.623839 -389.66593) (xy 49.589908 -389.699858)
			(xy 49.551088 -389.72806) (xy 49.508335 -389.749844) (xy 49.4627 -389.764672) (xy 49.415308 -389.77218)
			(xy 49.391316 -389.772652) (xy 49.367652 -389.7722) (xy 49.320892 -389.764892) (xy 49.275816 -389.750463)
			(xy 49.233504 -389.729259) (xy 49.194966 -389.701786) (xy 49.161123 -389.668701) (xy 49.132784 -389.630795)
			(xy 49.121314 -389.610092) (xy 49.12106 -389.60933) (xy 48.723804 -388.922006) (xy 48.711596 -388.898735)
			(xy 48.694481 -388.849053) (xy 48.689768 -388.8232) (xy 48.686228 -388.797975) (xy 48.15733 -388.797975)
			(xy 48.456088 -389.314944) (xy 48.456342 -389.315452) (xy 48.456596 -389.315452) (xy 48.457866 -389.317992)
			(xy 48.470103 -389.340914) (xy 48.48742 -389.389901) (xy 48.496207 -389.441111) (xy 48.496728 -389.46709)
			(xy 48.496728 -389.467344) (xy 48.496278 -389.491335) (xy 48.488766 -389.538727) (xy 48.473934 -389.58436)
			(xy 48.452147 -389.627111) (xy 48.423941 -389.665928) (xy 48.39001 -389.699856) (xy 48.351191 -389.728059)
			(xy 48.308437 -389.749843) (xy 48.262803 -389.764672) (xy 48.215411 -389.77218) (xy 48.19142 -389.772652)
			(xy 48.167756 -389.772196) (xy 48.120996 -389.764889) (xy 48.075921 -389.750461) (xy 48.033608 -389.729257)
			(xy 47.99507 -389.701785) (xy 47.961227 -389.668701) (xy 47.932888 -389.630795) (xy 47.921418 -389.610092)
			(xy 47.921164 -389.60933) (xy 47.523908 -388.922006) (xy 47.5117 -388.898735) (xy 47.494585 -388.849053)
			(xy 47.489872 -388.8232) (xy 47.486325 -388.797976) (xy 16.931816 -388.797976) (xy 19.609816 -391.475976)
			(xy 19.644106 -391.480548) (xy 19.658838 -391.471912) (xy 19.685972 -391.457099) (xy 19.744089 -391.436045)
			(xy 19.80497 -391.425346) (xy 19.835876 -391.424668) (xy 19.836384 -391.424668) (xy 19.864369 -391.425216)
			(xy 19.919649 -391.433969) (xy 19.97288 -391.451261) (xy 20.02275 -391.476668) (xy 20.068032 -391.509564)
			(xy 20.10761 -391.549138) (xy 20.140511 -391.594416) (xy 20.165923 -391.644283) (xy 20.183222 -391.697512)
			(xy 20.191981 -391.752791) (xy 20.192492 -391.780776) (xy 20.192492 -391.781284) (xy 20.191808 -391.812189)
			(xy 20.181099 -391.873067) (xy 20.160053 -391.931185) (xy 20.145248 -391.958322) (xy 20.136612 -391.973054)
			(xy 20.141184 -392.007344) (xy 21.426678 -393.292838) (xy 47.435008 -393.292838) (xy 47.435008 -392.429238)
			(xy 47.435494 -392.401987) (xy 47.44325 -392.348039) (xy 47.458605 -392.295744) (xy 47.481247 -392.246167)
			(xy 47.510713 -392.200317) (xy 47.546404 -392.159126) (xy 47.587595 -392.123435) (xy 47.633445 -392.093969)
			(xy 47.683022 -392.071327) (xy 47.735317 -392.055972) (xy 47.789265 -392.048216) (xy 47.843767 -392.048216)
			(xy 47.897715 -392.055972) (xy 47.95001 -392.071327) (xy 47.999587 -392.093969) (xy 48.045437 -392.123435)
			(xy 48.086628 -392.159126) (xy 48.122319 -392.200317) (xy 48.151785 -392.246167) (xy 48.174427 -392.295744)
			(xy 48.189782 -392.348039) (xy 48.197538 -392.401987) (xy 48.198024 -392.429238) (xy 48.198024 -393.292838)
			(xy 48.634904 -393.292838) (xy 48.634904 -392.429238) (xy 48.63539 -392.401987) (xy 48.643146 -392.348039)
			(xy 48.658501 -392.295744) (xy 48.681143 -392.246167) (xy 48.710609 -392.200317) (xy 48.7463 -392.159126)
			(xy 48.787491 -392.123435) (xy 48.833341 -392.093969) (xy 48.882918 -392.071327) (xy 48.935213 -392.055972)
			(xy 48.989161 -392.048216) (xy 49.043663 -392.048216) (xy 49.097611 -392.055972) (xy 49.149906 -392.071327)
			(xy 49.199483 -392.093969) (xy 49.245333 -392.123435) (xy 49.286524 -392.159126) (xy 49.322215 -392.200317)
			(xy 49.351681 -392.246167) (xy 49.374323 -392.295744) (xy 49.389678 -392.348039) (xy 49.397434 -392.401987)
			(xy 49.39792 -392.429238) (xy 49.39792 -393.292838) (xy 49.8348 -393.292838) (xy 49.8348 -392.429238)
			(xy 49.835286 -392.401969) (xy 49.843048 -392.347985) (xy 49.858413 -392.295655) (xy 49.88107 -392.246045)
			(xy 49.910556 -392.200164) (xy 49.946271 -392.158947) (xy 49.987488 -392.123232) (xy 50.033369 -392.093746)
			(xy 50.082979 -392.071089) (xy 50.135309 -392.055724) (xy 50.189293 -392.047962) (xy 50.243831 -392.047962)
			(xy 50.297815 -392.055724) (xy 50.350145 -392.071089) (xy 50.399755 -392.093746) (xy 50.445636 -392.123232)
			(xy 50.486853 -392.158947) (xy 50.522568 -392.200164) (xy 50.552054 -392.246045) (xy 50.574711 -392.295655)
			(xy 50.590076 -392.347985) (xy 50.597838 -392.401969) (xy 50.598324 -392.429238) (xy 50.598324 -393.292838)
			(xy 51.034696 -393.292838) (xy 51.034696 -392.429238) (xy 51.035182 -392.401969) (xy 51.042944 -392.347985)
			(xy 51.058309 -392.295655) (xy 51.080966 -392.246045) (xy 51.110452 -392.200164) (xy 51.146167 -392.158947)
			(xy 51.187384 -392.123232) (xy 51.233265 -392.093746) (xy 51.282875 -392.071089) (xy 51.335205 -392.055724)
			(xy 51.389189 -392.047962) (xy 51.443727 -392.047962) (xy 51.497711 -392.055724) (xy 51.550041 -392.071089)
			(xy 51.599651 -392.093746) (xy 51.645532 -392.123232) (xy 51.686749 -392.158947) (xy 51.722464 -392.200164)
			(xy 51.75195 -392.246045) (xy 51.774607 -392.295655) (xy 51.789972 -392.347985) (xy 51.797734 -392.401969)
			(xy 51.79822 -392.429238) (xy 51.79822 -393.292838) (xy 52.2351 -393.292838) (xy 52.2351 -392.429238)
			(xy 52.235586 -392.401987) (xy 52.243342 -392.348039) (xy 52.258697 -392.295744) (xy 52.281339 -392.246167)
			(xy 52.310805 -392.200317) (xy 52.346496 -392.159126) (xy 52.387687 -392.123435) (xy 52.433537 -392.093969)
			(xy 52.483114 -392.071327) (xy 52.535409 -392.055972) (xy 52.589357 -392.048216) (xy 52.643859 -392.048216)
			(xy 52.697807 -392.055972) (xy 52.750102 -392.071327) (xy 52.799679 -392.093969) (xy 52.845529 -392.123435)
			(xy 52.88672 -392.159126) (xy 52.922411 -392.200317) (xy 52.951877 -392.246167) (xy 52.974519 -392.295744)
			(xy 52.989874 -392.348039) (xy 52.99763 -392.401987) (xy 52.998116 -392.429238) (xy 52.998116 -393.292838)
			(xy 53.434996 -393.292838) (xy 53.434996 -392.429238) (xy 53.435482 -392.401987) (xy 53.443238 -392.348039)
			(xy 53.458593 -392.295744) (xy 53.481235 -392.246167) (xy 53.510701 -392.200317) (xy 53.546392 -392.159126)
			(xy 53.587583 -392.123435) (xy 53.633433 -392.093969) (xy 53.68301 -392.071327) (xy 53.735305 -392.055972)
			(xy 53.789253 -392.048216) (xy 53.843755 -392.048216) (xy 53.897703 -392.055972) (xy 53.949998 -392.071327)
			(xy 53.999575 -392.093969) (xy 54.045425 -392.123435) (xy 54.086616 -392.159126) (xy 54.122307 -392.200317)
			(xy 54.151773 -392.246167) (xy 54.174415 -392.295744) (xy 54.18977 -392.348039) (xy 54.197526 -392.401987)
			(xy 54.198012 -392.429238) (xy 54.198012 -393.292838) (xy 54.634892 -393.292838) (xy 54.634892 -392.429238)
			(xy 54.635378 -392.401969) (xy 54.64314 -392.347985) (xy 54.658505 -392.295655) (xy 54.681162 -392.246045)
			(xy 54.710648 -392.200164) (xy 54.746363 -392.158947) (xy 54.78758 -392.123232) (xy 54.833461 -392.093746)
			(xy 54.883071 -392.071089) (xy 54.935401 -392.055724) (xy 54.989385 -392.047962) (xy 55.043923 -392.047962)
			(xy 55.097907 -392.055724) (xy 55.150237 -392.071089) (xy 55.199847 -392.093746) (xy 55.245728 -392.123232)
			(xy 55.286945 -392.158947) (xy 55.32266 -392.200164) (xy 55.352146 -392.246045) (xy 55.374803 -392.295655)
			(xy 55.390168 -392.347985) (xy 55.39793 -392.401969) (xy 55.398416 -392.429238) (xy 55.398416 -393.292838)
			(xy 55.834788 -393.292838) (xy 55.834788 -392.429238) (xy 55.835274 -392.401969) (xy 55.843036 -392.347985)
			(xy 55.858401 -392.295655) (xy 55.881058 -392.246045) (xy 55.910544 -392.200164) (xy 55.946259 -392.158947)
			(xy 55.987476 -392.123232) (xy 56.033357 -392.093746) (xy 56.082967 -392.071089) (xy 56.135297 -392.055724)
			(xy 56.189281 -392.047962) (xy 56.243819 -392.047962) (xy 56.297803 -392.055724) (xy 56.350133 -392.071089)
			(xy 56.399743 -392.093746) (xy 56.445624 -392.123232) (xy 56.486841 -392.158947) (xy 56.522556 -392.200164)
			(xy 56.552042 -392.246045) (xy 56.574699 -392.295655) (xy 56.590064 -392.347985) (xy 56.597826 -392.401969)
			(xy 56.598312 -392.429238) (xy 56.598312 -393.292838) (xy 57.035192 -393.292838) (xy 57.035192 -392.429238)
			(xy 57.035678 -392.401987) (xy 57.043434 -392.348039) (xy 57.058789 -392.295744) (xy 57.081431 -392.246167)
			(xy 57.110897 -392.200317) (xy 57.146588 -392.159126) (xy 57.187779 -392.123435) (xy 57.233629 -392.093969)
			(xy 57.283206 -392.071327) (xy 57.335501 -392.055972) (xy 57.389449 -392.048216) (xy 57.443951 -392.048216)
			(xy 57.497899 -392.055972) (xy 57.550194 -392.071327) (xy 57.599771 -392.093969) (xy 57.645621 -392.123435)
			(xy 57.686812 -392.159126) (xy 57.722503 -392.200317) (xy 57.751969 -392.246167) (xy 57.774611 -392.295744)
			(xy 57.789966 -392.348039) (xy 57.797722 -392.401987) (xy 57.798208 -392.429238) (xy 57.798208 -393.292838)
			(xy 58.235088 -393.292838) (xy 58.235088 -392.429238) (xy 58.235574 -392.401987) (xy 58.24333 -392.348039)
			(xy 58.258685 -392.295744) (xy 58.281327 -392.246167) (xy 58.310793 -392.200317) (xy 58.346484 -392.159126)
			(xy 58.387675 -392.123435) (xy 58.433525 -392.093969) (xy 58.483102 -392.071327) (xy 58.535397 -392.055972)
			(xy 58.589345 -392.048216) (xy 58.643847 -392.048216) (xy 58.697795 -392.055972) (xy 58.75009 -392.071327)
			(xy 58.799667 -392.093969) (xy 58.845517 -392.123435) (xy 58.886708 -392.159126) (xy 58.922399 -392.200317)
			(xy 58.951865 -392.246167) (xy 58.974507 -392.295744) (xy 58.989862 -392.348039) (xy 58.997618 -392.401987)
			(xy 58.998104 -392.429238) (xy 58.998104 -393.292838) (xy 59.434984 -393.292838) (xy 59.434984 -392.429238)
			(xy 59.43547 -392.401969) (xy 59.443232 -392.347985) (xy 59.458597 -392.295655) (xy 59.481254 -392.246045)
			(xy 59.51074 -392.200164) (xy 59.546455 -392.158947) (xy 59.587672 -392.123232) (xy 59.633553 -392.093746)
			(xy 59.683163 -392.071089) (xy 59.735493 -392.055724) (xy 59.789477 -392.047962) (xy 59.844015 -392.047962)
			(xy 59.897999 -392.055724) (xy 59.950329 -392.071089) (xy 59.999939 -392.093746) (xy 60.04582 -392.123232)
			(xy 60.087037 -392.158947) (xy 60.122752 -392.200164) (xy 60.152238 -392.246045) (xy 60.174895 -392.295655)
			(xy 60.19026 -392.347985) (xy 60.198022 -392.401969) (xy 60.198508 -392.429238) (xy 60.198508 -393.292838)
			(xy 60.63488 -393.292838) (xy 60.63488 -392.429238) (xy 60.635366 -392.401969) (xy 60.643128 -392.347985)
			(xy 60.658493 -392.295655) (xy 60.68115 -392.246045) (xy 60.710636 -392.200164) (xy 60.746351 -392.158947)
			(xy 60.787568 -392.123232) (xy 60.833449 -392.093746) (xy 60.883059 -392.071089) (xy 60.935389 -392.055724)
			(xy 60.989373 -392.047962) (xy 61.043911 -392.047962) (xy 61.097895 -392.055724) (xy 61.150225 -392.071089)
			(xy 61.199835 -392.093746) (xy 61.245716 -392.123232) (xy 61.286933 -392.158947) (xy 61.322648 -392.200164)
			(xy 61.352134 -392.246045) (xy 61.374791 -392.295655) (xy 61.390156 -392.347985) (xy 61.397918 -392.401969)
			(xy 61.398404 -392.429238) (xy 61.398404 -393.292838) (xy 61.834776 -393.292838) (xy 61.834776 -392.429238)
			(xy 61.835262 -392.401969) (xy 61.843024 -392.347985) (xy 61.858389 -392.295655) (xy 61.881046 -392.246045)
			(xy 61.910532 -392.200164) (xy 61.946247 -392.158947) (xy 61.987464 -392.123232) (xy 62.033345 -392.093746)
			(xy 62.082955 -392.071089) (xy 62.135285 -392.055724) (xy 62.189269 -392.047962) (xy 62.243807 -392.047962)
			(xy 62.297791 -392.055724) (xy 62.350121 -392.071089) (xy 62.399731 -392.093746) (xy 62.445612 -392.123232)
			(xy 62.486829 -392.158947) (xy 62.522544 -392.200164) (xy 62.55203 -392.246045) (xy 62.574687 -392.295655)
			(xy 62.590052 -392.347985) (xy 62.597814 -392.401969) (xy 62.5983 -392.429238) (xy 62.5983 -393.292838)
			(xy 63.034672 -393.292838) (xy 63.034672 -392.429238) (xy 63.035158 -392.401969) (xy 63.04292 -392.347985)
			(xy 63.058285 -392.295655) (xy 63.080942 -392.246045) (xy 63.110428 -392.200164) (xy 63.146143 -392.158947)
			(xy 63.18736 -392.123232) (xy 63.233241 -392.093746) (xy 63.282851 -392.071089) (xy 63.335181 -392.055724)
			(xy 63.389165 -392.047962) (xy 63.443703 -392.047962) (xy 63.497687 -392.055724) (xy 63.550017 -392.071089)
			(xy 63.599627 -392.093746) (xy 63.645508 -392.123232) (xy 63.686725 -392.158947) (xy 63.72244 -392.200164)
			(xy 63.751926 -392.246045) (xy 63.774583 -392.295655) (xy 63.789948 -392.347985) (xy 63.79771 -392.401969)
			(xy 63.798196 -392.429238) (xy 63.798196 -393.292838) (xy 64.235076 -393.292838) (xy 64.235076 -392.429238)
			(xy 64.235562 -392.401987) (xy 64.243318 -392.348039) (xy 64.258673 -392.295744) (xy 64.281315 -392.246167)
			(xy 64.310781 -392.200317) (xy 64.346472 -392.159126) (xy 64.387663 -392.123435) (xy 64.433513 -392.093969)
			(xy 64.48309 -392.071327) (xy 64.535385 -392.055972) (xy 64.589333 -392.048216) (xy 64.643835 -392.048216)
			(xy 64.697783 -392.055972) (xy 64.750078 -392.071327) (xy 64.799655 -392.093969) (xy 64.845505 -392.123435)
			(xy 64.886696 -392.159126) (xy 64.922387 -392.200317) (xy 64.951853 -392.246167) (xy 64.974495 -392.295744)
			(xy 64.98985 -392.348039) (xy 64.997606 -392.401987) (xy 64.998092 -392.429238) (xy 64.998092 -393.292838)
			(xy 65.434972 -393.292838) (xy 65.434972 -392.429238) (xy 65.435458 -392.401987) (xy 65.443214 -392.348039)
			(xy 65.458569 -392.295744) (xy 65.481211 -392.246167) (xy 65.510677 -392.200317) (xy 65.546368 -392.159126)
			(xy 65.587559 -392.123435) (xy 65.633409 -392.093969) (xy 65.682986 -392.071327) (xy 65.735281 -392.055972)
			(xy 65.789229 -392.048216) (xy 65.843731 -392.048216) (xy 65.897679 -392.055972) (xy 65.949974 -392.071327)
			(xy 65.999551 -392.093969) (xy 66.045401 -392.123435) (xy 66.086592 -392.159126) (xy 66.122283 -392.200317)
			(xy 66.151749 -392.246167) (xy 66.174391 -392.295744) (xy 66.189746 -392.348039) (xy 66.197502 -392.401987)
			(xy 66.197988 -392.429238) (xy 66.197988 -393.292838) (xy 79.962756 -393.292838) (xy 79.962756 -392.429238)
			(xy 79.963242 -392.401987) (xy 79.970998 -392.348039) (xy 79.986353 -392.295744) (xy 80.008995 -392.246167)
			(xy 80.038461 -392.200317) (xy 80.074152 -392.159126) (xy 80.115343 -392.123435) (xy 80.161193 -392.093969)
			(xy 80.21077 -392.071327) (xy 80.263065 -392.055972) (xy 80.317013 -392.048216) (xy 80.371515 -392.048216)
			(xy 80.425463 -392.055972) (xy 80.477758 -392.071327) (xy 80.527335 -392.093969) (xy 80.573185 -392.123435)
			(xy 80.614376 -392.159126) (xy 80.650067 -392.200317) (xy 80.679533 -392.246167) (xy 80.702175 -392.295744)
			(xy 80.71753 -392.348039) (xy 80.725286 -392.401987) (xy 80.725772 -392.429238) (xy 80.725772 -393.292838)
			(xy 81.162652 -393.292838) (xy 81.162652 -392.429238) (xy 81.163138 -392.401987) (xy 81.170894 -392.348039)
			(xy 81.186249 -392.295744) (xy 81.208891 -392.246167) (xy 81.238357 -392.200317) (xy 81.274048 -392.159126)
			(xy 81.315239 -392.123435) (xy 81.361089 -392.093969) (xy 81.410666 -392.071327) (xy 81.462961 -392.055972)
			(xy 81.516909 -392.048216) (xy 81.571411 -392.048216) (xy 81.625359 -392.055972) (xy 81.677654 -392.071327)
			(xy 81.727231 -392.093969) (xy 81.773081 -392.123435) (xy 81.814272 -392.159126) (xy 81.849963 -392.200317)
			(xy 81.879429 -392.246167) (xy 81.902071 -392.295744) (xy 81.917426 -392.348039) (xy 81.925182 -392.401987)
			(xy 81.925668 -392.429238) (xy 81.925668 -393.292838) (xy 82.362548 -393.292838) (xy 82.362548 -392.429238)
			(xy 82.363034 -392.401969) (xy 82.370796 -392.347985) (xy 82.386161 -392.295655) (xy 82.408818 -392.246045)
			(xy 82.438304 -392.200164) (xy 82.474019 -392.158947) (xy 82.515236 -392.123232) (xy 82.561117 -392.093746)
			(xy 82.610727 -392.071089) (xy 82.663057 -392.055724) (xy 82.717041 -392.047962) (xy 82.771579 -392.047962)
			(xy 82.825563 -392.055724) (xy 82.877893 -392.071089) (xy 82.927503 -392.093746) (xy 82.973384 -392.123232)
			(xy 83.014601 -392.158947) (xy 83.050316 -392.200164) (xy 83.079802 -392.246045) (xy 83.102459 -392.295655)
			(xy 83.117824 -392.347985) (xy 83.125586 -392.401969) (xy 83.126072 -392.429238) (xy 83.126072 -393.292838)
			(xy 83.562444 -393.292838) (xy 83.562444 -392.429238) (xy 83.56293 -392.401969) (xy 83.570692 -392.347985)
			(xy 83.586057 -392.295655) (xy 83.608714 -392.246045) (xy 83.6382 -392.200164) (xy 83.673915 -392.158947)
			(xy 83.715132 -392.123232) (xy 83.761013 -392.093746) (xy 83.810623 -392.071089) (xy 83.862953 -392.055724)
			(xy 83.916937 -392.047962) (xy 83.971475 -392.047962) (xy 84.025459 -392.055724) (xy 84.077789 -392.071089)
			(xy 84.127399 -392.093746) (xy 84.17328 -392.123232) (xy 84.214497 -392.158947) (xy 84.250212 -392.200164)
			(xy 84.279698 -392.246045) (xy 84.302355 -392.295655) (xy 84.31772 -392.347985) (xy 84.325482 -392.401969)
			(xy 84.325968 -392.429238) (xy 84.325968 -393.292838) (xy 84.762848 -393.292838) (xy 84.762848 -392.429238)
			(xy 84.763334 -392.401987) (xy 84.77109 -392.348039) (xy 84.786445 -392.295744) (xy 84.809087 -392.246167)
			(xy 84.838553 -392.200317) (xy 84.874244 -392.159126) (xy 84.915435 -392.123435) (xy 84.961285 -392.093969)
			(xy 85.010862 -392.071327) (xy 85.063157 -392.055972) (xy 85.117105 -392.048216) (xy 85.171607 -392.048216)
			(xy 85.225555 -392.055972) (xy 85.27785 -392.071327) (xy 85.327427 -392.093969) (xy 85.373277 -392.123435)
			(xy 85.414468 -392.159126) (xy 85.450159 -392.200317) (xy 85.479625 -392.246167) (xy 85.502267 -392.295744)
			(xy 85.517622 -392.348039) (xy 85.525378 -392.401987) (xy 85.525864 -392.429238) (xy 85.525864 -393.292838)
			(xy 85.962744 -393.292838) (xy 85.962744 -392.429238) (xy 85.96323 -392.401987) (xy 85.970986 -392.348039)
			(xy 85.986341 -392.295744) (xy 86.008983 -392.246167) (xy 86.038449 -392.200317) (xy 86.07414 -392.159126)
			(xy 86.115331 -392.123435) (xy 86.161181 -392.093969) (xy 86.210758 -392.071327) (xy 86.263053 -392.055972)
			(xy 86.317001 -392.048216) (xy 86.371503 -392.048216) (xy 86.425451 -392.055972) (xy 86.477746 -392.071327)
			(xy 86.527323 -392.093969) (xy 86.573173 -392.123435) (xy 86.614364 -392.159126) (xy 86.650055 -392.200317)
			(xy 86.679521 -392.246167) (xy 86.702163 -392.295744) (xy 86.717518 -392.348039) (xy 86.725274 -392.401987)
			(xy 86.72576 -392.429238) (xy 86.72576 -393.292838) (xy 87.16264 -393.292838) (xy 87.16264 -392.429238)
			(xy 87.163126 -392.401969) (xy 87.170888 -392.347985) (xy 87.186253 -392.295655) (xy 87.20891 -392.246045)
			(xy 87.238396 -392.200164) (xy 87.274111 -392.158947) (xy 87.315328 -392.123232) (xy 87.361209 -392.093746)
			(xy 87.410819 -392.071089) (xy 87.463149 -392.055724) (xy 87.517133 -392.047962) (xy 87.571671 -392.047962)
			(xy 87.625655 -392.055724) (xy 87.677985 -392.071089) (xy 87.727595 -392.093746) (xy 87.773476 -392.123232)
			(xy 87.814693 -392.158947) (xy 87.850408 -392.200164) (xy 87.879894 -392.246045) (xy 87.902551 -392.295655)
			(xy 87.917916 -392.347985) (xy 87.925678 -392.401969) (xy 87.926164 -392.429238) (xy 87.926164 -393.292838)
			(xy 88.362536 -393.292838) (xy 88.362536 -392.429238) (xy 88.363022 -392.401969) (xy 88.370784 -392.347985)
			(xy 88.386149 -392.295655) (xy 88.408806 -392.246045) (xy 88.438292 -392.200164) (xy 88.474007 -392.158947)
			(xy 88.515224 -392.123232) (xy 88.561105 -392.093746) (xy 88.610715 -392.071089) (xy 88.663045 -392.055724)
			(xy 88.717029 -392.047962) (xy 88.771567 -392.047962) (xy 88.825551 -392.055724) (xy 88.877881 -392.071089)
			(xy 88.927491 -392.093746) (xy 88.973372 -392.123232) (xy 89.014589 -392.158947) (xy 89.050304 -392.200164)
			(xy 89.07979 -392.246045) (xy 89.102447 -392.295655) (xy 89.117812 -392.347985) (xy 89.125574 -392.401969)
			(xy 89.12606 -392.429238) (xy 89.12606 -393.292838) (xy 89.56294 -393.292838) (xy 89.56294 -392.429238)
			(xy 89.563426 -392.401987) (xy 89.571182 -392.348039) (xy 89.586537 -392.295744) (xy 89.609179 -392.246167)
			(xy 89.638645 -392.200317) (xy 89.674336 -392.159126) (xy 89.715527 -392.123435) (xy 89.761377 -392.093969)
			(xy 89.810954 -392.071327) (xy 89.863249 -392.055972) (xy 89.917197 -392.048216) (xy 89.971699 -392.048216)
			(xy 90.025647 -392.055972) (xy 90.077942 -392.071327) (xy 90.127519 -392.093969) (xy 90.173369 -392.123435)
			(xy 90.21456 -392.159126) (xy 90.250251 -392.200317) (xy 90.279717 -392.246167) (xy 90.302359 -392.295744)
			(xy 90.317714 -392.348039) (xy 90.32547 -392.401987) (xy 90.325956 -392.429238) (xy 90.325956 -393.292838)
			(xy 90.762836 -393.292838) (xy 90.762836 -392.429238) (xy 90.763322 -392.401987) (xy 90.771078 -392.348039)
			(xy 90.786433 -392.295744) (xy 90.809075 -392.246167) (xy 90.838541 -392.200317) (xy 90.874232 -392.159126)
			(xy 90.915423 -392.123435) (xy 90.961273 -392.093969) (xy 91.01085 -392.071327) (xy 91.063145 -392.055972)
			(xy 91.117093 -392.048216) (xy 91.171595 -392.048216) (xy 91.225543 -392.055972) (xy 91.277838 -392.071327)
			(xy 91.327415 -392.093969) (xy 91.373265 -392.123435) (xy 91.414456 -392.159126) (xy 91.450147 -392.200317)
			(xy 91.479613 -392.246167) (xy 91.502255 -392.295744) (xy 91.51761 -392.348039) (xy 91.525366 -392.401987)
			(xy 91.525852 -392.429238) (xy 91.525852 -393.292838) (xy 91.962732 -393.292838) (xy 91.962732 -392.429238)
			(xy 91.963218 -392.401969) (xy 91.97098 -392.347985) (xy 91.986345 -392.295655) (xy 92.009002 -392.246045)
			(xy 92.038488 -392.200164) (xy 92.074203 -392.158947) (xy 92.11542 -392.123232) (xy 92.161301 -392.093746)
			(xy 92.210911 -392.071089) (xy 92.263241 -392.055724) (xy 92.317225 -392.047962) (xy 92.371763 -392.047962)
			(xy 92.425747 -392.055724) (xy 92.478077 -392.071089) (xy 92.527687 -392.093746) (xy 92.573568 -392.123232)
			(xy 92.614785 -392.158947) (xy 92.6505 -392.200164) (xy 92.679986 -392.246045) (xy 92.702643 -392.295655)
			(xy 92.718008 -392.347985) (xy 92.72577 -392.401969) (xy 92.726256 -392.429238) (xy 92.726256 -393.292838)
			(xy 93.162628 -393.292838) (xy 93.162628 -392.429238) (xy 93.163114 -392.401969) (xy 93.170876 -392.347985)
			(xy 93.186241 -392.295655) (xy 93.208898 -392.246045) (xy 93.238384 -392.200164) (xy 93.274099 -392.158947)
			(xy 93.315316 -392.123232) (xy 93.361197 -392.093746) (xy 93.410807 -392.071089) (xy 93.463137 -392.055724)
			(xy 93.517121 -392.047962) (xy 93.571659 -392.047962) (xy 93.625643 -392.055724) (xy 93.677973 -392.071089)
			(xy 93.727583 -392.093746) (xy 93.773464 -392.123232) (xy 93.814681 -392.158947) (xy 93.850396 -392.200164)
			(xy 93.879882 -392.246045) (xy 93.902539 -392.295655) (xy 93.917904 -392.347985) (xy 93.925666 -392.401969)
			(xy 93.926152 -392.429238) (xy 93.926152 -393.292838) (xy 94.362524 -393.292838) (xy 94.362524 -392.429238)
			(xy 94.36301 -392.401969) (xy 94.370772 -392.347985) (xy 94.386137 -392.295655) (xy 94.408794 -392.246045)
			(xy 94.43828 -392.200164) (xy 94.473995 -392.158947) (xy 94.515212 -392.123232) (xy 94.561093 -392.093746)
			(xy 94.610703 -392.071089) (xy 94.663033 -392.055724) (xy 94.717017 -392.047962) (xy 94.771555 -392.047962)
			(xy 94.825539 -392.055724) (xy 94.877869 -392.071089) (xy 94.927479 -392.093746) (xy 94.97336 -392.123232)
			(xy 95.014577 -392.158947) (xy 95.050292 -392.200164) (xy 95.079778 -392.246045) (xy 95.102435 -392.295655)
			(xy 95.1178 -392.347985) (xy 95.125562 -392.401969) (xy 95.126048 -392.429238) (xy 95.126048 -393.292838)
			(xy 95.56242 -393.292838) (xy 95.56242 -392.429238) (xy 95.562906 -392.401969) (xy 95.570668 -392.347985)
			(xy 95.586033 -392.295655) (xy 95.60869 -392.246045) (xy 95.638176 -392.200164) (xy 95.673891 -392.158947)
			(xy 95.715108 -392.123232) (xy 95.760989 -392.093746) (xy 95.810599 -392.071089) (xy 95.862929 -392.055724)
			(xy 95.916913 -392.047962) (xy 95.971451 -392.047962) (xy 96.025435 -392.055724) (xy 96.077765 -392.071089)
			(xy 96.127375 -392.093746) (xy 96.173256 -392.123232) (xy 96.214473 -392.158947) (xy 96.250188 -392.200164)
			(xy 96.279674 -392.246045) (xy 96.302331 -392.295655) (xy 96.317696 -392.347985) (xy 96.325458 -392.401969)
			(xy 96.325944 -392.429238) (xy 96.325944 -393.292838) (xy 96.762824 -393.292838) (xy 96.762824 -392.429238)
			(xy 96.76331 -392.401987) (xy 96.771066 -392.348039) (xy 96.786421 -392.295744) (xy 96.809063 -392.246167)
			(xy 96.838529 -392.200317) (xy 96.87422 -392.159126) (xy 96.915411 -392.123435) (xy 96.961261 -392.093969)
			(xy 97.010838 -392.071327) (xy 97.063133 -392.055972) (xy 97.117081 -392.048216) (xy 97.171583 -392.048216)
			(xy 97.225531 -392.055972) (xy 97.277826 -392.071327) (xy 97.327403 -392.093969) (xy 97.373253 -392.123435)
			(xy 97.414444 -392.159126) (xy 97.450135 -392.200317) (xy 97.479601 -392.246167) (xy 97.502243 -392.295744)
			(xy 97.517598 -392.348039) (xy 97.525354 -392.401987) (xy 97.52584 -392.429238) (xy 97.52584 -393.292838)
			(xy 97.96272 -393.292838) (xy 97.96272 -392.429238) (xy 97.963206 -392.401987) (xy 97.970962 -392.348039)
			(xy 97.986317 -392.295744) (xy 98.008959 -392.246167) (xy 98.038425 -392.200317) (xy 98.074116 -392.159126)
			(xy 98.115307 -392.123435) (xy 98.161157 -392.093969) (xy 98.210734 -392.071327) (xy 98.263029 -392.055972)
			(xy 98.316977 -392.048216) (xy 98.371479 -392.048216) (xy 98.425427 -392.055972) (xy 98.477722 -392.071327)
			(xy 98.527299 -392.093969) (xy 98.573149 -392.123435) (xy 98.61434 -392.159126) (xy 98.650031 -392.200317)
			(xy 98.679497 -392.246167) (xy 98.702139 -392.295744) (xy 98.717494 -392.348039) (xy 98.72525 -392.401987)
			(xy 98.725736 -392.429238) (xy 98.725736 -393.292838) (xy 114.534696 -393.292838) (xy 114.534696 -392.429238)
			(xy 114.535182 -392.401969) (xy 114.542944 -392.347985) (xy 114.558309 -392.295655) (xy 114.580966 -392.246045)
			(xy 114.610452 -392.200164) (xy 114.646167 -392.158947) (xy 114.687384 -392.123232) (xy 114.733265 -392.093746)
			(xy 114.782875 -392.071089) (xy 114.835205 -392.055724) (xy 114.889189 -392.047962) (xy 114.943727 -392.047962)
			(xy 114.997711 -392.055724) (xy 115.050041 -392.071089) (xy 115.099651 -392.093746) (xy 115.145532 -392.123232)
			(xy 115.186749 -392.158947) (xy 115.222464 -392.200164) (xy 115.25195 -392.246045) (xy 115.274607 -392.295655)
			(xy 115.289972 -392.347985) (xy 115.297734 -392.401969) (xy 115.29822 -392.429238) (xy 115.29822 -393.292838)
			(xy 115.734592 -393.292838) (xy 115.734592 -392.429238) (xy 115.735078 -392.401969) (xy 115.74284 -392.347985)
			(xy 115.758205 -392.295655) (xy 115.780862 -392.246045) (xy 115.810348 -392.200164) (xy 115.846063 -392.158947)
			(xy 115.88728 -392.123232) (xy 115.933161 -392.093746) (xy 115.982771 -392.071089) (xy 116.035101 -392.055724)
			(xy 116.089085 -392.047962) (xy 116.143623 -392.047962) (xy 116.197607 -392.055724) (xy 116.249937 -392.071089)
			(xy 116.299547 -392.093746) (xy 116.345428 -392.123232) (xy 116.386645 -392.158947) (xy 116.42236 -392.200164)
			(xy 116.451846 -392.246045) (xy 116.474503 -392.295655) (xy 116.489868 -392.347985) (xy 116.49763 -392.401969)
			(xy 116.498116 -392.429238) (xy 116.498116 -393.292838) (xy 116.934996 -393.292838) (xy 116.934996 -392.429238)
			(xy 116.935482 -392.401987) (xy 116.943238 -392.348039) (xy 116.958593 -392.295744) (xy 116.981235 -392.246167)
			(xy 117.010701 -392.200317) (xy 117.046392 -392.159126) (xy 117.087583 -392.123435) (xy 117.133433 -392.093969)
			(xy 117.18301 -392.071327) (xy 117.235305 -392.055972) (xy 117.289253 -392.048216) (xy 117.343755 -392.048216)
			(xy 117.397703 -392.055972) (xy 117.449998 -392.071327) (xy 117.499575 -392.093969) (xy 117.545425 -392.123435)
			(xy 117.586616 -392.159126) (xy 117.622307 -392.200317) (xy 117.651773 -392.246167) (xy 117.674415 -392.295744)
			(xy 117.68977 -392.348039) (xy 117.697526 -392.401987) (xy 117.698012 -392.429238) (xy 117.698012 -393.292838)
			(xy 118.134892 -393.292838) (xy 118.134892 -392.429238) (xy 118.135378 -392.401987) (xy 118.143134 -392.348039)
			(xy 118.158489 -392.295744) (xy 118.181131 -392.246167) (xy 118.210597 -392.200317) (xy 118.246288 -392.159126)
			(xy 118.287479 -392.123435) (xy 118.333329 -392.093969) (xy 118.382906 -392.071327) (xy 118.435201 -392.055972)
			(xy 118.489149 -392.048216) (xy 118.543651 -392.048216) (xy 118.597599 -392.055972) (xy 118.649894 -392.071327)
			(xy 118.699471 -392.093969) (xy 118.745321 -392.123435) (xy 118.786512 -392.159126) (xy 118.822203 -392.200317)
			(xy 118.851669 -392.246167) (xy 118.874311 -392.295744) (xy 118.889666 -392.348039) (xy 118.897422 -392.401987)
			(xy 118.897908 -392.429238) (xy 118.897908 -393.292838) (xy 119.334788 -393.292838) (xy 119.334788 -392.429238)
			(xy 119.335274 -392.401969) (xy 119.343036 -392.347985) (xy 119.358401 -392.295655) (xy 119.381058 -392.246045)
			(xy 119.410544 -392.200164) (xy 119.446259 -392.158947) (xy 119.487476 -392.123232) (xy 119.533357 -392.093746)
			(xy 119.582967 -392.071089) (xy 119.635297 -392.055724) (xy 119.689281 -392.047962) (xy 119.743819 -392.047962)
			(xy 119.797803 -392.055724) (xy 119.850133 -392.071089) (xy 119.899743 -392.093746) (xy 119.945624 -392.123232)
			(xy 119.986841 -392.158947) (xy 120.022556 -392.200164) (xy 120.052042 -392.246045) (xy 120.074699 -392.295655)
			(xy 120.090064 -392.347985) (xy 120.097826 -392.401969) (xy 120.098312 -392.429238) (xy 120.098312 -393.292838)
			(xy 120.534684 -393.292838) (xy 120.534684 -392.429238) (xy 120.53517 -392.401969) (xy 120.542932 -392.347985)
			(xy 120.558297 -392.295655) (xy 120.580954 -392.246045) (xy 120.61044 -392.200164) (xy 120.646155 -392.158947)
			(xy 120.687372 -392.123232) (xy 120.733253 -392.093746) (xy 120.782863 -392.071089) (xy 120.835193 -392.055724)
			(xy 120.889177 -392.047962) (xy 120.943715 -392.047962) (xy 120.997699 -392.055724) (xy 121.050029 -392.071089)
			(xy 121.099639 -392.093746) (xy 121.14552 -392.123232) (xy 121.186737 -392.158947) (xy 121.222452 -392.200164)
			(xy 121.251938 -392.246045) (xy 121.274595 -392.295655) (xy 121.28996 -392.347985) (xy 121.297722 -392.401969)
			(xy 121.298208 -392.429238) (xy 121.298208 -393.292838) (xy 121.735088 -393.292838) (xy 121.735088 -392.429238)
			(xy 121.735574 -392.401987) (xy 121.74333 -392.348039) (xy 121.758685 -392.295744) (xy 121.781327 -392.246167)
			(xy 121.810793 -392.200317) (xy 121.846484 -392.159126) (xy 121.887675 -392.123435) (xy 121.933525 -392.093969)
			(xy 121.983102 -392.071327) (xy 122.035397 -392.055972) (xy 122.089345 -392.048216) (xy 122.143847 -392.048216)
			(xy 122.197795 -392.055972) (xy 122.25009 -392.071327) (xy 122.299667 -392.093969) (xy 122.345517 -392.123435)
			(xy 122.386708 -392.159126) (xy 122.422399 -392.200317) (xy 122.451865 -392.246167) (xy 122.474507 -392.295744)
			(xy 122.489862 -392.348039) (xy 122.497618 -392.401987) (xy 122.498104 -392.429238) (xy 122.498104 -393.292838)
			(xy 122.934984 -393.292838) (xy 122.934984 -392.429238) (xy 122.93547 -392.401987) (xy 122.943226 -392.348039)
			(xy 122.958581 -392.295744) (xy 122.981223 -392.246167) (xy 123.010689 -392.200317) (xy 123.04638 -392.159126)
			(xy 123.087571 -392.123435) (xy 123.133421 -392.093969) (xy 123.182998 -392.071327) (xy 123.235293 -392.055972)
			(xy 123.289241 -392.048216) (xy 123.343743 -392.048216) (xy 123.397691 -392.055972) (xy 123.449986 -392.071327)
			(xy 123.499563 -392.093969) (xy 123.545413 -392.123435) (xy 123.586604 -392.159126) (xy 123.622295 -392.200317)
			(xy 123.651761 -392.246167) (xy 123.674403 -392.295744) (xy 123.689758 -392.348039) (xy 123.697514 -392.401987)
			(xy 123.698 -392.429238) (xy 123.698 -393.292838) (xy 124.13488 -393.292838) (xy 124.13488 -392.429238)
			(xy 124.135366 -392.401969) (xy 124.143128 -392.347985) (xy 124.158493 -392.295655) (xy 124.18115 -392.246045)
			(xy 124.210636 -392.200164) (xy 124.246351 -392.158947) (xy 124.287568 -392.123232) (xy 124.333449 -392.093746)
			(xy 124.383059 -392.071089) (xy 124.435389 -392.055724) (xy 124.489373 -392.047962) (xy 124.543911 -392.047962)
			(xy 124.597895 -392.055724) (xy 124.650225 -392.071089) (xy 124.699835 -392.093746) (xy 124.745716 -392.123232)
			(xy 124.786933 -392.158947) (xy 124.822648 -392.200164) (xy 124.852134 -392.246045) (xy 124.874791 -392.295655)
			(xy 124.890156 -392.347985) (xy 124.897918 -392.401969) (xy 124.898404 -392.429238) (xy 124.898404 -393.292838)
			(xy 125.334776 -393.292838) (xy 125.334776 -392.429238) (xy 125.335262 -392.401969) (xy 125.343024 -392.347985)
			(xy 125.358389 -392.295655) (xy 125.381046 -392.246045) (xy 125.410532 -392.200164) (xy 125.446247 -392.158947)
			(xy 125.487464 -392.123232) (xy 125.533345 -392.093746) (xy 125.582955 -392.071089) (xy 125.635285 -392.055724)
			(xy 125.689269 -392.047962) (xy 125.743807 -392.047962) (xy 125.797791 -392.055724) (xy 125.850121 -392.071089)
			(xy 125.899731 -392.093746) (xy 125.945612 -392.123232) (xy 125.986829 -392.158947) (xy 126.022544 -392.200164)
			(xy 126.05203 -392.246045) (xy 126.074687 -392.295655) (xy 126.090052 -392.347985) (xy 126.097814 -392.401969)
			(xy 126.0983 -392.429238) (xy 126.0983 -393.292838) (xy 126.53518 -393.292838) (xy 126.53518 -392.429238)
			(xy 126.535666 -392.401987) (xy 126.543422 -392.348039) (xy 126.558777 -392.295744) (xy 126.581419 -392.246167)
			(xy 126.610885 -392.200317) (xy 126.646576 -392.159126) (xy 126.687767 -392.123435) (xy 126.733617 -392.093969)
			(xy 126.783194 -392.071327) (xy 126.835489 -392.055972) (xy 126.889437 -392.048216) (xy 126.943939 -392.048216)
			(xy 126.997887 -392.055972) (xy 127.050182 -392.071327) (xy 127.099759 -392.093969) (xy 127.145609 -392.123435)
			(xy 127.1868 -392.159126) (xy 127.222491 -392.200317) (xy 127.251957 -392.246167) (xy 127.274599 -392.295744)
			(xy 127.289954 -392.348039) (xy 127.29771 -392.401987) (xy 127.298196 -392.429238) (xy 127.298196 -393.292838)
			(xy 127.735076 -393.292838) (xy 127.735076 -392.429238) (xy 127.735562 -392.401987) (xy 127.743318 -392.348039)
			(xy 127.758673 -392.295744) (xy 127.781315 -392.246167) (xy 127.810781 -392.200317) (xy 127.846472 -392.159126)
			(xy 127.887663 -392.123435) (xy 127.933513 -392.093969) (xy 127.98309 -392.071327) (xy 128.035385 -392.055972)
			(xy 128.089333 -392.048216) (xy 128.143835 -392.048216) (xy 128.197783 -392.055972) (xy 128.250078 -392.071327)
			(xy 128.299655 -392.093969) (xy 128.345505 -392.123435) (xy 128.386696 -392.159126) (xy 128.422387 -392.200317)
			(xy 128.451853 -392.246167) (xy 128.474495 -392.295744) (xy 128.48985 -392.348039) (xy 128.497606 -392.401987)
			(xy 128.498092 -392.429238) (xy 128.498092 -393.292838) (xy 128.934972 -393.292838) (xy 128.934972 -392.429238)
			(xy 128.935458 -392.401987) (xy 128.943214 -392.348039) (xy 128.958569 -392.295744) (xy 128.981211 -392.246167)
			(xy 129.010677 -392.200317) (xy 129.046368 -392.159126) (xy 129.087559 -392.123435) (xy 129.133409 -392.093969)
			(xy 129.182986 -392.071327) (xy 129.235281 -392.055972) (xy 129.289229 -392.048216) (xy 129.343731 -392.048216)
			(xy 129.397679 -392.055972) (xy 129.449974 -392.071327) (xy 129.499551 -392.093969) (xy 129.545401 -392.123435)
			(xy 129.586592 -392.159126) (xy 129.622283 -392.200317) (xy 129.651749 -392.246167) (xy 129.674391 -392.295744)
			(xy 129.689746 -392.348039) (xy 129.697502 -392.401987) (xy 129.697988 -392.429238) (xy 129.697988 -393.292838)
			(xy 130.134868 -393.292838) (xy 130.134868 -392.429238) (xy 130.135354 -392.401987) (xy 130.14311 -392.348039)
			(xy 130.158465 -392.295744) (xy 130.181107 -392.246167) (xy 130.210573 -392.200317) (xy 130.246264 -392.159126)
			(xy 130.287455 -392.123435) (xy 130.333305 -392.093969) (xy 130.382882 -392.071327) (xy 130.435177 -392.055972)
			(xy 130.489125 -392.048216) (xy 130.543627 -392.048216) (xy 130.597575 -392.055972) (xy 130.64987 -392.071327)
			(xy 130.699447 -392.093969) (xy 130.745297 -392.123435) (xy 130.786488 -392.159126) (xy 130.822179 -392.200317)
			(xy 130.851645 -392.246167) (xy 130.874287 -392.295744) (xy 130.889642 -392.348039) (xy 130.897398 -392.401987)
			(xy 130.897884 -392.429238) (xy 130.897884 -393.292838) (xy 131.334764 -393.292838) (xy 131.334764 -392.429238)
			(xy 131.33525 -392.401969) (xy 131.343012 -392.347985) (xy 131.358377 -392.295655) (xy 131.381034 -392.246045)
			(xy 131.41052 -392.200164) (xy 131.446235 -392.158947) (xy 131.487452 -392.123232) (xy 131.533333 -392.093746)
			(xy 131.582943 -392.071089) (xy 131.635273 -392.055724) (xy 131.689257 -392.047962) (xy 131.743795 -392.047962)
			(xy 131.797779 -392.055724) (xy 131.850109 -392.071089) (xy 131.899719 -392.093746) (xy 131.9456 -392.123232)
			(xy 131.986817 -392.158947) (xy 132.022532 -392.200164) (xy 132.052018 -392.246045) (xy 132.074675 -392.295655)
			(xy 132.09004 -392.347985) (xy 132.097802 -392.401969) (xy 132.098288 -392.429238) (xy 132.098288 -393.292838)
			(xy 132.53466 -393.292838) (xy 132.53466 -392.429238) (xy 132.535146 -392.401969) (xy 132.542908 -392.347985)
			(xy 132.558273 -392.295655) (xy 132.58093 -392.246045) (xy 132.610416 -392.200164) (xy 132.646131 -392.158947)
			(xy 132.687348 -392.123232) (xy 132.733229 -392.093746) (xy 132.782839 -392.071089) (xy 132.835169 -392.055724)
			(xy 132.889153 -392.047962) (xy 132.943691 -392.047962) (xy 132.997675 -392.055724) (xy 133.050005 -392.071089)
			(xy 133.099615 -392.093746) (xy 133.145496 -392.123232) (xy 133.186713 -392.158947) (xy 133.222428 -392.200164)
			(xy 133.251914 -392.246045) (xy 133.274571 -392.295655) (xy 133.289936 -392.347985) (xy 133.297698 -392.401969)
			(xy 133.298184 -392.429238) (xy 133.298184 -393.292838) (xy 147.062444 -393.292838) (xy 147.062444 -392.429238)
			(xy 147.06293 -392.401969) (xy 147.070692 -392.347985) (xy 147.086057 -392.295655) (xy 147.108714 -392.246045)
			(xy 147.1382 -392.200164) (xy 147.173915 -392.158947) (xy 147.215132 -392.123232) (xy 147.261013 -392.093746)
			(xy 147.310623 -392.071089) (xy 147.362953 -392.055724) (xy 147.416937 -392.047962) (xy 147.471475 -392.047962)
			(xy 147.525459 -392.055724) (xy 147.577789 -392.071089) (xy 147.627399 -392.093746) (xy 147.67328 -392.123232)
			(xy 147.714497 -392.158947) (xy 147.750212 -392.200164) (xy 147.779698 -392.246045) (xy 147.802355 -392.295655)
			(xy 147.81772 -392.347985) (xy 147.825482 -392.401969) (xy 147.825968 -392.429238) (xy 147.825968 -393.292838)
			(xy 148.26234 -393.292838) (xy 148.26234 -392.429238) (xy 148.262826 -392.401969) (xy 148.270588 -392.347985)
			(xy 148.285953 -392.295655) (xy 148.30861 -392.246045) (xy 148.338096 -392.200164) (xy 148.373811 -392.158947)
			(xy 148.415028 -392.123232) (xy 148.460909 -392.093746) (xy 148.510519 -392.071089) (xy 148.562849 -392.055724)
			(xy 148.616833 -392.047962) (xy 148.671371 -392.047962) (xy 148.725355 -392.055724) (xy 148.777685 -392.071089)
			(xy 148.827295 -392.093746) (xy 148.873176 -392.123232) (xy 148.914393 -392.158947) (xy 148.950108 -392.200164)
			(xy 148.979594 -392.246045) (xy 149.002251 -392.295655) (xy 149.017616 -392.347985) (xy 149.025378 -392.401969)
			(xy 149.025864 -392.429238) (xy 149.025864 -393.292838) (xy 149.462744 -393.292838) (xy 149.462744 -392.429238)
			(xy 149.46323 -392.401987) (xy 149.470986 -392.348039) (xy 149.486341 -392.295744) (xy 149.508983 -392.246167)
			(xy 149.538449 -392.200317) (xy 149.57414 -392.159126) (xy 149.615331 -392.123435) (xy 149.661181 -392.093969)
			(xy 149.710758 -392.071327) (xy 149.763053 -392.055972) (xy 149.817001 -392.048216) (xy 149.871503 -392.048216)
			(xy 149.925451 -392.055972) (xy 149.977746 -392.071327) (xy 150.027323 -392.093969) (xy 150.073173 -392.123435)
			(xy 150.114364 -392.159126) (xy 150.150055 -392.200317) (xy 150.179521 -392.246167) (xy 150.202163 -392.295744)
			(xy 150.217518 -392.348039) (xy 150.225274 -392.401987) (xy 150.22576 -392.429238) (xy 150.22576 -393.292838)
			(xy 150.66264 -393.292838) (xy 150.66264 -392.429238) (xy 150.663126 -392.401987) (xy 150.670882 -392.348039)
			(xy 150.686237 -392.295744) (xy 150.708879 -392.246167) (xy 150.738345 -392.200317) (xy 150.774036 -392.159126)
			(xy 150.815227 -392.123435) (xy 150.861077 -392.093969) (xy 150.910654 -392.071327) (xy 150.962949 -392.055972)
			(xy 151.016897 -392.048216) (xy 151.071399 -392.048216) (xy 151.125347 -392.055972) (xy 151.177642 -392.071327)
			(xy 151.227219 -392.093969) (xy 151.273069 -392.123435) (xy 151.31426 -392.159126) (xy 151.349951 -392.200317)
			(xy 151.379417 -392.246167) (xy 151.402059 -392.295744) (xy 151.417414 -392.348039) (xy 151.42517 -392.401987)
			(xy 151.425656 -392.429238) (xy 151.425656 -393.292838) (xy 151.862536 -393.292838) (xy 151.862536 -392.429238)
			(xy 151.863022 -392.401969) (xy 151.870784 -392.347985) (xy 151.886149 -392.295655) (xy 151.908806 -392.246045)
			(xy 151.938292 -392.200164) (xy 151.974007 -392.158947) (xy 152.015224 -392.123232) (xy 152.061105 -392.093746)
			(xy 152.110715 -392.071089) (xy 152.163045 -392.055724) (xy 152.217029 -392.047962) (xy 152.271567 -392.047962)
			(xy 152.325551 -392.055724) (xy 152.377881 -392.071089) (xy 152.427491 -392.093746) (xy 152.473372 -392.123232)
			(xy 152.514589 -392.158947) (xy 152.550304 -392.200164) (xy 152.57979 -392.246045) (xy 152.602447 -392.295655)
			(xy 152.617812 -392.347985) (xy 152.625574 -392.401969) (xy 152.62606 -392.429238) (xy 152.62606 -393.292838)
			(xy 153.062432 -393.292838) (xy 153.062432 -392.429238) (xy 153.062918 -392.401969) (xy 153.07068 -392.347985)
			(xy 153.086045 -392.295655) (xy 153.108702 -392.246045) (xy 153.138188 -392.200164) (xy 153.173903 -392.158947)
			(xy 153.21512 -392.123232) (xy 153.261001 -392.093746) (xy 153.310611 -392.071089) (xy 153.362941 -392.055724)
			(xy 153.416925 -392.047962) (xy 153.471463 -392.047962) (xy 153.525447 -392.055724) (xy 153.577777 -392.071089)
			(xy 153.627387 -392.093746) (xy 153.673268 -392.123232) (xy 153.714485 -392.158947) (xy 153.7502 -392.200164)
			(xy 153.779686 -392.246045) (xy 153.802343 -392.295655) (xy 153.817708 -392.347985) (xy 153.82547 -392.401969)
			(xy 153.825956 -392.429238) (xy 153.825956 -393.292838) (xy 154.262836 -393.292838) (xy 154.262836 -392.429238)
			(xy 154.263322 -392.401987) (xy 154.271078 -392.348039) (xy 154.286433 -392.295744) (xy 154.309075 -392.246167)
			(xy 154.338541 -392.200317) (xy 154.374232 -392.159126) (xy 154.415423 -392.123435) (xy 154.461273 -392.093969)
			(xy 154.51085 -392.071327) (xy 154.563145 -392.055972) (xy 154.617093 -392.048216) (xy 154.671595 -392.048216)
			(xy 154.725543 -392.055972) (xy 154.777838 -392.071327) (xy 154.827415 -392.093969) (xy 154.873265 -392.123435)
			(xy 154.914456 -392.159126) (xy 154.950147 -392.200317) (xy 154.979613 -392.246167) (xy 155.002255 -392.295744)
			(xy 155.01761 -392.348039) (xy 155.025366 -392.401987) (xy 155.025852 -392.429238) (xy 155.025852 -393.292838)
			(xy 155.462732 -393.292838) (xy 155.462732 -392.429238) (xy 155.463218 -392.401987) (xy 155.470974 -392.348039)
			(xy 155.486329 -392.295744) (xy 155.508971 -392.246167) (xy 155.538437 -392.200317) (xy 155.574128 -392.159126)
			(xy 155.615319 -392.123435) (xy 155.661169 -392.093969) (xy 155.710746 -392.071327) (xy 155.763041 -392.055972)
			(xy 155.816989 -392.048216) (xy 155.871491 -392.048216) (xy 155.925439 -392.055972) (xy 155.977734 -392.071327)
			(xy 156.027311 -392.093969) (xy 156.073161 -392.123435) (xy 156.114352 -392.159126) (xy 156.150043 -392.200317)
			(xy 156.179509 -392.246167) (xy 156.202151 -392.295744) (xy 156.217506 -392.348039) (xy 156.225262 -392.401987)
			(xy 156.225748 -392.429238) (xy 156.225748 -393.292838) (xy 156.662628 -393.292838) (xy 156.662628 -392.429238)
			(xy 156.663114 -392.401969) (xy 156.670876 -392.347985) (xy 156.686241 -392.295655) (xy 156.708898 -392.246045)
			(xy 156.738384 -392.200164) (xy 156.774099 -392.158947) (xy 156.815316 -392.123232) (xy 156.861197 -392.093746)
			(xy 156.910807 -392.071089) (xy 156.963137 -392.055724) (xy 157.017121 -392.047962) (xy 157.071659 -392.047962)
			(xy 157.125643 -392.055724) (xy 157.177973 -392.071089) (xy 157.227583 -392.093746) (xy 157.273464 -392.123232)
			(xy 157.314681 -392.158947) (xy 157.350396 -392.200164) (xy 157.379882 -392.246045) (xy 157.402539 -392.295655)
			(xy 157.417904 -392.347985) (xy 157.425666 -392.401969) (xy 157.426152 -392.429238) (xy 157.426152 -393.292838)
			(xy 157.862524 -393.292838) (xy 157.862524 -392.429238) (xy 157.86301 -392.401969) (xy 157.870772 -392.347985)
			(xy 157.886137 -392.295655) (xy 157.908794 -392.246045) (xy 157.93828 -392.200164) (xy 157.973995 -392.158947)
			(xy 158.015212 -392.123232) (xy 158.061093 -392.093746) (xy 158.110703 -392.071089) (xy 158.163033 -392.055724)
			(xy 158.217017 -392.047962) (xy 158.271555 -392.047962) (xy 158.325539 -392.055724) (xy 158.377869 -392.071089)
			(xy 158.427479 -392.093746) (xy 158.47336 -392.123232) (xy 158.514577 -392.158947) (xy 158.550292 -392.200164)
			(xy 158.579778 -392.246045) (xy 158.602435 -392.295655) (xy 158.6178 -392.347985) (xy 158.625562 -392.401969)
			(xy 158.626048 -392.429238) (xy 158.626048 -393.292838) (xy 159.062928 -393.292838) (xy 159.062928 -392.429238)
			(xy 159.063414 -392.401987) (xy 159.07117 -392.348039) (xy 159.086525 -392.295744) (xy 159.109167 -392.246167)
			(xy 159.138633 -392.200317) (xy 159.174324 -392.159126) (xy 159.215515 -392.123435) (xy 159.261365 -392.093969)
			(xy 159.310942 -392.071327) (xy 159.363237 -392.055972) (xy 159.417185 -392.048216) (xy 159.471687 -392.048216)
			(xy 159.525635 -392.055972) (xy 159.57793 -392.071327) (xy 159.627507 -392.093969) (xy 159.673357 -392.123435)
			(xy 159.714548 -392.159126) (xy 159.750239 -392.200317) (xy 159.779705 -392.246167) (xy 159.802347 -392.295744)
			(xy 159.817702 -392.348039) (xy 159.825458 -392.401987) (xy 159.825944 -392.429238) (xy 159.825944 -393.292838)
			(xy 159.825458 -393.320089) (xy 159.817702 -393.374037) (xy 159.802347 -393.426332) (xy 159.779705 -393.475909)
			(xy 159.750239 -393.521759) (xy 159.714548 -393.56295) (xy 159.673357 -393.598641) (xy 159.627507 -393.628107)
			(xy 159.57793 -393.650749) (xy 159.525635 -393.666104) (xy 159.471687 -393.67386) (xy 159.417185 -393.67386)
			(xy 159.363237 -393.666104) (xy 159.310942 -393.650749) (xy 159.261365 -393.628107) (xy 159.215515 -393.598641)
			(xy 159.174324 -393.56295) (xy 159.138633 -393.521759) (xy 159.109167 -393.475909) (xy 159.086525 -393.426332)
			(xy 159.07117 -393.374037) (xy 159.063414 -393.320089) (xy 159.062928 -393.292838) (xy 158.626048 -393.292838)
			(xy 158.625562 -393.320107) (xy 158.6178 -393.374091) (xy 158.602435 -393.426421) (xy 158.579778 -393.476031)
			(xy 158.550292 -393.521912) (xy 158.514577 -393.563129) (xy 158.47336 -393.598844) (xy 158.427479 -393.62833)
			(xy 158.377869 -393.650987) (xy 158.325539 -393.666352) (xy 158.271555 -393.674114) (xy 158.217017 -393.674114)
			(xy 158.163033 -393.666352) (xy 158.110703 -393.650987) (xy 158.061093 -393.62833) (xy 158.015212 -393.598844)
			(xy 157.973995 -393.563129) (xy 157.93828 -393.521912) (xy 157.908794 -393.476031) (xy 157.886137 -393.426421)
			(xy 157.870772 -393.374091) (xy 157.86301 -393.320107) (xy 157.862524 -393.292838) (xy 157.426152 -393.292838)
			(xy 157.425666 -393.320107) (xy 157.417904 -393.374091) (xy 157.402539 -393.426421) (xy 157.379882 -393.476031)
			(xy 157.350396 -393.521912) (xy 157.314681 -393.563129) (xy 157.273464 -393.598844) (xy 157.227583 -393.62833)
			(xy 157.177973 -393.650987) (xy 157.125643 -393.666352) (xy 157.071659 -393.674114) (xy 157.017121 -393.674114)
			(xy 156.963137 -393.666352) (xy 156.910807 -393.650987) (xy 156.861197 -393.62833) (xy 156.815316 -393.598844)
			(xy 156.774099 -393.563129) (xy 156.738384 -393.521912) (xy 156.708898 -393.476031) (xy 156.686241 -393.426421)
			(xy 156.670876 -393.374091) (xy 156.663114 -393.320107) (xy 156.662628 -393.292838) (xy 156.225748 -393.292838)
			(xy 156.225262 -393.320089) (xy 156.217506 -393.374037) (xy 156.202151 -393.426332) (xy 156.179509 -393.475909)
			(xy 156.150043 -393.521759) (xy 156.114352 -393.56295) (xy 156.073161 -393.598641) (xy 156.027311 -393.628107)
			(xy 155.977734 -393.650749) (xy 155.925439 -393.666104) (xy 155.871491 -393.67386) (xy 155.816989 -393.67386)
			(xy 155.763041 -393.666104) (xy 155.710746 -393.650749) (xy 155.661169 -393.628107) (xy 155.615319 -393.598641)
			(xy 155.574128 -393.56295) (xy 155.538437 -393.521759) (xy 155.508971 -393.475909) (xy 155.486329 -393.426332)
			(xy 155.470974 -393.374037) (xy 155.463218 -393.320089) (xy 155.462732 -393.292838) (xy 155.025852 -393.292838)
			(xy 155.025366 -393.320089) (xy 155.01761 -393.374037) (xy 155.002255 -393.426332) (xy 154.979613 -393.475909)
			(xy 154.950147 -393.521759) (xy 154.914456 -393.56295) (xy 154.873265 -393.598641) (xy 154.827415 -393.628107)
			(xy 154.777838 -393.650749) (xy 154.725543 -393.666104) (xy 154.671595 -393.67386) (xy 154.617093 -393.67386)
			(xy 154.563145 -393.666104) (xy 154.51085 -393.650749) (xy 154.461273 -393.628107) (xy 154.415423 -393.598641)
			(xy 154.374232 -393.56295) (xy 154.338541 -393.521759) (xy 154.309075 -393.475909) (xy 154.286433 -393.426332)
			(xy 154.271078 -393.374037) (xy 154.263322 -393.320089) (xy 154.262836 -393.292838) (xy 153.825956 -393.292838)
			(xy 153.82547 -393.320107) (xy 153.817708 -393.374091) (xy 153.802343 -393.426421) (xy 153.779686 -393.476031)
			(xy 153.7502 -393.521912) (xy 153.714485 -393.563129) (xy 153.673268 -393.598844) (xy 153.627387 -393.62833)
			(xy 153.577777 -393.650987) (xy 153.525447 -393.666352) (xy 153.471463 -393.674114) (xy 153.416925 -393.674114)
			(xy 153.362941 -393.666352) (xy 153.310611 -393.650987) (xy 153.261001 -393.62833) (xy 153.21512 -393.598844)
			(xy 153.173903 -393.563129) (xy 153.138188 -393.521912) (xy 153.108702 -393.476031) (xy 153.086045 -393.426421)
			(xy 153.07068 -393.374091) (xy 153.062918 -393.320107) (xy 153.062432 -393.292838) (xy 152.62606 -393.292838)
			(xy 152.625574 -393.320107) (xy 152.617812 -393.374091) (xy 152.602447 -393.426421) (xy 152.57979 -393.476031)
			(xy 152.550304 -393.521912) (xy 152.514589 -393.563129) (xy 152.473372 -393.598844) (xy 152.427491 -393.62833)
			(xy 152.377881 -393.650987) (xy 152.325551 -393.666352) (xy 152.271567 -393.674114) (xy 152.217029 -393.674114)
			(xy 152.163045 -393.666352) (xy 152.110715 -393.650987) (xy 152.061105 -393.62833) (xy 152.015224 -393.598844)
			(xy 151.974007 -393.563129) (xy 151.938292 -393.521912) (xy 151.908806 -393.476031) (xy 151.886149 -393.426421)
			(xy 151.870784 -393.374091) (xy 151.863022 -393.320107) (xy 151.862536 -393.292838) (xy 151.425656 -393.292838)
			(xy 151.42517 -393.320089) (xy 151.417414 -393.374037) (xy 151.402059 -393.426332) (xy 151.379417 -393.475909)
			(xy 151.349951 -393.521759) (xy 151.31426 -393.56295) (xy 151.273069 -393.598641) (xy 151.227219 -393.628107)
			(xy 151.177642 -393.650749) (xy 151.125347 -393.666104) (xy 151.071399 -393.67386) (xy 151.016897 -393.67386)
			(xy 150.962949 -393.666104) (xy 150.910654 -393.650749) (xy 150.861077 -393.628107) (xy 150.815227 -393.598641)
			(xy 150.774036 -393.56295) (xy 150.738345 -393.521759) (xy 150.708879 -393.475909) (xy 150.686237 -393.426332)
			(xy 150.670882 -393.374037) (xy 150.663126 -393.320089) (xy 150.66264 -393.292838) (xy 150.22576 -393.292838)
			(xy 150.225274 -393.320089) (xy 150.217518 -393.374037) (xy 150.202163 -393.426332) (xy 150.179521 -393.475909)
			(xy 150.150055 -393.521759) (xy 150.114364 -393.56295) (xy 150.073173 -393.598641) (xy 150.027323 -393.628107)
			(xy 149.977746 -393.650749) (xy 149.925451 -393.666104) (xy 149.871503 -393.67386) (xy 149.817001 -393.67386)
			(xy 149.763053 -393.666104) (xy 149.710758 -393.650749) (xy 149.661181 -393.628107) (xy 149.615331 -393.598641)
			(xy 149.57414 -393.56295) (xy 149.538449 -393.521759) (xy 149.508983 -393.475909) (xy 149.486341 -393.426332)
			(xy 149.470986 -393.374037) (xy 149.46323 -393.320089) (xy 149.462744 -393.292838) (xy 149.025864 -393.292838)
			(xy 149.025378 -393.320107) (xy 149.017616 -393.374091) (xy 149.002251 -393.426421) (xy 148.979594 -393.476031)
			(xy 148.950108 -393.521912) (xy 148.914393 -393.563129) (xy 148.873176 -393.598844) (xy 148.827295 -393.62833)
			(xy 148.777685 -393.650987) (xy 148.725355 -393.666352) (xy 148.671371 -393.674114) (xy 148.616833 -393.674114)
			(xy 148.562849 -393.666352) (xy 148.510519 -393.650987) (xy 148.460909 -393.62833) (xy 148.415028 -393.598844)
			(xy 148.373811 -393.563129) (xy 148.338096 -393.521912) (xy 148.30861 -393.476031) (xy 148.285953 -393.426421)
			(xy 148.270588 -393.374091) (xy 148.262826 -393.320107) (xy 148.26234 -393.292838) (xy 147.825968 -393.292838)
			(xy 147.825482 -393.320107) (xy 147.81772 -393.374091) (xy 147.802355 -393.426421) (xy 147.779698 -393.476031)
			(xy 147.750212 -393.521912) (xy 147.714497 -393.563129) (xy 147.67328 -393.598844) (xy 147.627399 -393.62833)
			(xy 147.577789 -393.650987) (xy 147.525459 -393.666352) (xy 147.471475 -393.674114) (xy 147.416937 -393.674114)
			(xy 147.362953 -393.666352) (xy 147.310623 -393.650987) (xy 147.261013 -393.62833) (xy 147.215132 -393.598844)
			(xy 147.173915 -393.563129) (xy 147.1382 -393.521912) (xy 147.108714 -393.476031) (xy 147.086057 -393.426421)
			(xy 147.070692 -393.374091) (xy 147.06293 -393.320107) (xy 147.062444 -393.292838) (xy 133.298184 -393.292838)
			(xy 133.297698 -393.320107) (xy 133.289936 -393.374091) (xy 133.274571 -393.426421) (xy 133.251914 -393.476031)
			(xy 133.222428 -393.521912) (xy 133.186713 -393.563129) (xy 133.145496 -393.598844) (xy 133.099615 -393.62833)
			(xy 133.050005 -393.650987) (xy 132.997675 -393.666352) (xy 132.943691 -393.674114) (xy 132.889153 -393.674114)
			(xy 132.835169 -393.666352) (xy 132.782839 -393.650987) (xy 132.733229 -393.62833) (xy 132.687348 -393.598844)
			(xy 132.646131 -393.563129) (xy 132.610416 -393.521912) (xy 132.58093 -393.476031) (xy 132.558273 -393.426421)
			(xy 132.542908 -393.374091) (xy 132.535146 -393.320107) (xy 132.53466 -393.292838) (xy 132.098288 -393.292838)
			(xy 132.097802 -393.320107) (xy 132.09004 -393.374091) (xy 132.074675 -393.426421) (xy 132.052018 -393.476031)
			(xy 132.022532 -393.521912) (xy 131.986817 -393.563129) (xy 131.9456 -393.598844) (xy 131.899719 -393.62833)
			(xy 131.850109 -393.650987) (xy 131.797779 -393.666352) (xy 131.743795 -393.674114) (xy 131.689257 -393.674114)
			(xy 131.635273 -393.666352) (xy 131.582943 -393.650987) (xy 131.533333 -393.62833) (xy 131.487452 -393.598844)
			(xy 131.446235 -393.563129) (xy 131.41052 -393.521912) (xy 131.381034 -393.476031) (xy 131.358377 -393.426421)
			(xy 131.343012 -393.374091) (xy 131.33525 -393.320107) (xy 131.334764 -393.292838) (xy 130.897884 -393.292838)
			(xy 130.897398 -393.320089) (xy 130.889642 -393.374037) (xy 130.874287 -393.426332) (xy 130.851645 -393.475909)
			(xy 130.822179 -393.521759) (xy 130.786488 -393.56295) (xy 130.745297 -393.598641) (xy 130.699447 -393.628107)
			(xy 130.64987 -393.650749) (xy 130.597575 -393.666104) (xy 130.543627 -393.67386) (xy 130.489125 -393.67386)
			(xy 130.435177 -393.666104) (xy 130.382882 -393.650749) (xy 130.333305 -393.628107) (xy 130.287455 -393.598641)
			(xy 130.246264 -393.56295) (xy 130.210573 -393.521759) (xy 130.181107 -393.475909) (xy 130.158465 -393.426332)
			(xy 130.14311 -393.374037) (xy 130.135354 -393.320089) (xy 130.134868 -393.292838) (xy 129.697988 -393.292838)
			(xy 129.697502 -393.320089) (xy 129.689746 -393.374037) (xy 129.674391 -393.426332) (xy 129.651749 -393.475909)
			(xy 129.622283 -393.521759) (xy 129.586592 -393.56295) (xy 129.545401 -393.598641) (xy 129.499551 -393.628107)
			(xy 129.449974 -393.650749) (xy 129.397679 -393.666104) (xy 129.343731 -393.67386) (xy 129.289229 -393.67386)
			(xy 129.235281 -393.666104) (xy 129.182986 -393.650749) (xy 129.133409 -393.628107) (xy 129.087559 -393.598641)
			(xy 129.046368 -393.56295) (xy 129.010677 -393.521759) (xy 128.981211 -393.475909) (xy 128.958569 -393.426332)
			(xy 128.943214 -393.374037) (xy 128.935458 -393.320089) (xy 128.934972 -393.292838) (xy 128.498092 -393.292838)
			(xy 128.497606 -393.320089) (xy 128.48985 -393.374037) (xy 128.474495 -393.426332) (xy 128.451853 -393.475909)
			(xy 128.422387 -393.521759) (xy 128.386696 -393.56295) (xy 128.345505 -393.598641) (xy 128.299655 -393.628107)
			(xy 128.250078 -393.650749) (xy 128.197783 -393.666104) (xy 128.143835 -393.67386) (xy 128.089333 -393.67386)
			(xy 128.035385 -393.666104) (xy 127.98309 -393.650749) (xy 127.933513 -393.628107) (xy 127.887663 -393.598641)
			(xy 127.846472 -393.56295) (xy 127.810781 -393.521759) (xy 127.781315 -393.475909) (xy 127.758673 -393.426332)
			(xy 127.743318 -393.374037) (xy 127.735562 -393.320089) (xy 127.735076 -393.292838) (xy 127.298196 -393.292838)
			(xy 127.29771 -393.320089) (xy 127.289954 -393.374037) (xy 127.274599 -393.426332) (xy 127.251957 -393.475909)
			(xy 127.222491 -393.521759) (xy 127.1868 -393.56295) (xy 127.145609 -393.598641) (xy 127.099759 -393.628107)
			(xy 127.050182 -393.650749) (xy 126.997887 -393.666104) (xy 126.943939 -393.67386) (xy 126.889437 -393.67386)
			(xy 126.835489 -393.666104) (xy 126.783194 -393.650749) (xy 126.733617 -393.628107) (xy 126.687767 -393.598641)
			(xy 126.646576 -393.56295) (xy 126.610885 -393.521759) (xy 126.581419 -393.475909) (xy 126.558777 -393.426332)
			(xy 126.543422 -393.374037) (xy 126.535666 -393.320089) (xy 126.53518 -393.292838) (xy 126.0983 -393.292838)
			(xy 126.097814 -393.320107) (xy 126.090052 -393.374091) (xy 126.074687 -393.426421) (xy 126.05203 -393.476031)
			(xy 126.022544 -393.521912) (xy 125.986829 -393.563129) (xy 125.945612 -393.598844) (xy 125.899731 -393.62833)
			(xy 125.850121 -393.650987) (xy 125.797791 -393.666352) (xy 125.743807 -393.674114) (xy 125.689269 -393.674114)
			(xy 125.635285 -393.666352) (xy 125.582955 -393.650987) (xy 125.533345 -393.62833) (xy 125.487464 -393.598844)
			(xy 125.446247 -393.563129) (xy 125.410532 -393.521912) (xy 125.381046 -393.476031) (xy 125.358389 -393.426421)
			(xy 125.343024 -393.374091) (xy 125.335262 -393.320107) (xy 125.334776 -393.292838) (xy 124.898404 -393.292838)
			(xy 124.897918 -393.320107) (xy 124.890156 -393.374091) (xy 124.874791 -393.426421) (xy 124.852134 -393.476031)
			(xy 124.822648 -393.521912) (xy 124.786933 -393.563129) (xy 124.745716 -393.598844) (xy 124.699835 -393.62833)
			(xy 124.650225 -393.650987) (xy 124.597895 -393.666352) (xy 124.543911 -393.674114) (xy 124.489373 -393.674114)
			(xy 124.435389 -393.666352) (xy 124.383059 -393.650987) (xy 124.333449 -393.62833) (xy 124.287568 -393.598844)
			(xy 124.246351 -393.563129) (xy 124.210636 -393.521912) (xy 124.18115 -393.476031) (xy 124.158493 -393.426421)
			(xy 124.143128 -393.374091) (xy 124.135366 -393.320107) (xy 124.13488 -393.292838) (xy 123.698 -393.292838)
			(xy 123.697514 -393.320089) (xy 123.689758 -393.374037) (xy 123.674403 -393.426332) (xy 123.651761 -393.475909)
			(xy 123.622295 -393.521759) (xy 123.586604 -393.56295) (xy 123.545413 -393.598641) (xy 123.499563 -393.628107)
			(xy 123.449986 -393.650749) (xy 123.397691 -393.666104) (xy 123.343743 -393.67386) (xy 123.289241 -393.67386)
			(xy 123.235293 -393.666104) (xy 123.182998 -393.650749) (xy 123.133421 -393.628107) (xy 123.087571 -393.598641)
			(xy 123.04638 -393.56295) (xy 123.010689 -393.521759) (xy 122.981223 -393.475909) (xy 122.958581 -393.426332)
			(xy 122.943226 -393.374037) (xy 122.93547 -393.320089) (xy 122.934984 -393.292838) (xy 122.498104 -393.292838)
			(xy 122.497618 -393.320089) (xy 122.489862 -393.374037) (xy 122.474507 -393.426332) (xy 122.451865 -393.475909)
			(xy 122.422399 -393.521759) (xy 122.386708 -393.56295) (xy 122.345517 -393.598641) (xy 122.299667 -393.628107)
			(xy 122.25009 -393.650749) (xy 122.197795 -393.666104) (xy 122.143847 -393.67386) (xy 122.089345 -393.67386)
			(xy 122.035397 -393.666104) (xy 121.983102 -393.650749) (xy 121.933525 -393.628107) (xy 121.887675 -393.598641)
			(xy 121.846484 -393.56295) (xy 121.810793 -393.521759) (xy 121.781327 -393.475909) (xy 121.758685 -393.426332)
			(xy 121.74333 -393.374037) (xy 121.735574 -393.320089) (xy 121.735088 -393.292838) (xy 121.298208 -393.292838)
			(xy 121.297722 -393.320107) (xy 121.28996 -393.374091) (xy 121.274595 -393.426421) (xy 121.251938 -393.476031)
			(xy 121.222452 -393.521912) (xy 121.186737 -393.563129) (xy 121.14552 -393.598844) (xy 121.099639 -393.62833)
			(xy 121.050029 -393.650987) (xy 120.997699 -393.666352) (xy 120.943715 -393.674114) (xy 120.889177 -393.674114)
			(xy 120.835193 -393.666352) (xy 120.782863 -393.650987) (xy 120.733253 -393.62833) (xy 120.687372 -393.598844)
			(xy 120.646155 -393.563129) (xy 120.61044 -393.521912) (xy 120.580954 -393.476031) (xy 120.558297 -393.426421)
			(xy 120.542932 -393.374091) (xy 120.53517 -393.320107) (xy 120.534684 -393.292838) (xy 120.098312 -393.292838)
			(xy 120.097826 -393.320107) (xy 120.090064 -393.374091) (xy 120.074699 -393.426421) (xy 120.052042 -393.476031)
			(xy 120.022556 -393.521912) (xy 119.986841 -393.563129) (xy 119.945624 -393.598844) (xy 119.899743 -393.62833)
			(xy 119.850133 -393.650987) (xy 119.797803 -393.666352) (xy 119.743819 -393.674114) (xy 119.689281 -393.674114)
			(xy 119.635297 -393.666352) (xy 119.582967 -393.650987) (xy 119.533357 -393.62833) (xy 119.487476 -393.598844)
			(xy 119.446259 -393.563129) (xy 119.410544 -393.521912) (xy 119.381058 -393.476031) (xy 119.358401 -393.426421)
			(xy 119.343036 -393.374091) (xy 119.335274 -393.320107) (xy 119.334788 -393.292838) (xy 118.897908 -393.292838)
			(xy 118.897422 -393.320089) (xy 118.889666 -393.374037) (xy 118.874311 -393.426332) (xy 118.851669 -393.475909)
			(xy 118.822203 -393.521759) (xy 118.786512 -393.56295) (xy 118.745321 -393.598641) (xy 118.699471 -393.628107)
			(xy 118.649894 -393.650749) (xy 118.597599 -393.666104) (xy 118.543651 -393.67386) (xy 118.489149 -393.67386)
			(xy 118.435201 -393.666104) (xy 118.382906 -393.650749) (xy 118.333329 -393.628107) (xy 118.287479 -393.598641)
			(xy 118.246288 -393.56295) (xy 118.210597 -393.521759) (xy 118.181131 -393.475909) (xy 118.158489 -393.426332)
			(xy 118.143134 -393.374037) (xy 118.135378 -393.320089) (xy 118.134892 -393.292838) (xy 117.698012 -393.292838)
			(xy 117.697526 -393.320089) (xy 117.68977 -393.374037) (xy 117.674415 -393.426332) (xy 117.651773 -393.475909)
			(xy 117.622307 -393.521759) (xy 117.586616 -393.56295) (xy 117.545425 -393.598641) (xy 117.499575 -393.628107)
			(xy 117.449998 -393.650749) (xy 117.397703 -393.666104) (xy 117.343755 -393.67386) (xy 117.289253 -393.67386)
			(xy 117.235305 -393.666104) (xy 117.18301 -393.650749) (xy 117.133433 -393.628107) (xy 117.087583 -393.598641)
			(xy 117.046392 -393.56295) (xy 117.010701 -393.521759) (xy 116.981235 -393.475909) (xy 116.958593 -393.426332)
			(xy 116.943238 -393.374037) (xy 116.935482 -393.320089) (xy 116.934996 -393.292838) (xy 116.498116 -393.292838)
			(xy 116.49763 -393.320107) (xy 116.489868 -393.374091) (xy 116.474503 -393.426421) (xy 116.451846 -393.476031)
			(xy 116.42236 -393.521912) (xy 116.386645 -393.563129) (xy 116.345428 -393.598844) (xy 116.299547 -393.62833)
			(xy 116.249937 -393.650987) (xy 116.197607 -393.666352) (xy 116.143623 -393.674114) (xy 116.089085 -393.674114)
			(xy 116.035101 -393.666352) (xy 115.982771 -393.650987) (xy 115.933161 -393.62833) (xy 115.88728 -393.598844)
			(xy 115.846063 -393.563129) (xy 115.810348 -393.521912) (xy 115.780862 -393.476031) (xy 115.758205 -393.426421)
			(xy 115.74284 -393.374091) (xy 115.735078 -393.320107) (xy 115.734592 -393.292838) (xy 115.29822 -393.292838)
			(xy 115.297734 -393.320107) (xy 115.289972 -393.374091) (xy 115.274607 -393.426421) (xy 115.25195 -393.476031)
			(xy 115.222464 -393.521912) (xy 115.186749 -393.563129) (xy 115.145532 -393.598844) (xy 115.099651 -393.62833)
			(xy 115.050041 -393.650987) (xy 114.997711 -393.666352) (xy 114.943727 -393.674114) (xy 114.889189 -393.674114)
			(xy 114.835205 -393.666352) (xy 114.782875 -393.650987) (xy 114.733265 -393.62833) (xy 114.687384 -393.598844)
			(xy 114.646167 -393.563129) (xy 114.610452 -393.521912) (xy 114.580966 -393.476031) (xy 114.558309 -393.426421)
			(xy 114.542944 -393.374091) (xy 114.535182 -393.320107) (xy 114.534696 -393.292838) (xy 98.725736 -393.292838)
			(xy 98.72525 -393.320089) (xy 98.717494 -393.374037) (xy 98.702139 -393.426332) (xy 98.679497 -393.475909)
			(xy 98.650031 -393.521759) (xy 98.61434 -393.56295) (xy 98.573149 -393.598641) (xy 98.527299 -393.628107)
			(xy 98.477722 -393.650749) (xy 98.425427 -393.666104) (xy 98.371479 -393.67386) (xy 98.316977 -393.67386)
			(xy 98.263029 -393.666104) (xy 98.210734 -393.650749) (xy 98.161157 -393.628107) (xy 98.115307 -393.598641)
			(xy 98.074116 -393.56295) (xy 98.038425 -393.521759) (xy 98.008959 -393.475909) (xy 97.986317 -393.426332)
			(xy 97.970962 -393.374037) (xy 97.963206 -393.320089) (xy 97.96272 -393.292838) (xy 97.52584 -393.292838)
			(xy 97.525354 -393.320089) (xy 97.517598 -393.374037) (xy 97.502243 -393.426332) (xy 97.479601 -393.475909)
			(xy 97.450135 -393.521759) (xy 97.414444 -393.56295) (xy 97.373253 -393.598641) (xy 97.327403 -393.628107)
			(xy 97.277826 -393.650749) (xy 97.225531 -393.666104) (xy 97.171583 -393.67386) (xy 97.117081 -393.67386)
			(xy 97.063133 -393.666104) (xy 97.010838 -393.650749) (xy 96.961261 -393.628107) (xy 96.915411 -393.598641)
			(xy 96.87422 -393.56295) (xy 96.838529 -393.521759) (xy 96.809063 -393.475909) (xy 96.786421 -393.426332)
			(xy 96.771066 -393.374037) (xy 96.76331 -393.320089) (xy 96.762824 -393.292838) (xy 96.325944 -393.292838)
			(xy 96.325458 -393.320107) (xy 96.317696 -393.374091) (xy 96.302331 -393.426421) (xy 96.279674 -393.476031)
			(xy 96.250188 -393.521912) (xy 96.214473 -393.563129) (xy 96.173256 -393.598844) (xy 96.127375 -393.62833)
			(xy 96.077765 -393.650987) (xy 96.025435 -393.666352) (xy 95.971451 -393.674114) (xy 95.916913 -393.674114)
			(xy 95.862929 -393.666352) (xy 95.810599 -393.650987) (xy 95.760989 -393.62833) (xy 95.715108 -393.598844)
			(xy 95.673891 -393.563129) (xy 95.638176 -393.521912) (xy 95.60869 -393.476031) (xy 95.586033 -393.426421)
			(xy 95.570668 -393.374091) (xy 95.562906 -393.320107) (xy 95.56242 -393.292838) (xy 95.126048 -393.292838)
			(xy 95.125562 -393.320107) (xy 95.1178 -393.374091) (xy 95.102435 -393.426421) (xy 95.079778 -393.476031)
			(xy 95.050292 -393.521912) (xy 95.014577 -393.563129) (xy 94.97336 -393.598844) (xy 94.927479 -393.62833)
			(xy 94.877869 -393.650987) (xy 94.825539 -393.666352) (xy 94.771555 -393.674114) (xy 94.717017 -393.674114)
			(xy 94.663033 -393.666352) (xy 94.610703 -393.650987) (xy 94.561093 -393.62833) (xy 94.515212 -393.598844)
			(xy 94.473995 -393.563129) (xy 94.43828 -393.521912) (xy 94.408794 -393.476031) (xy 94.386137 -393.426421)
			(xy 94.370772 -393.374091) (xy 94.36301 -393.320107) (xy 94.362524 -393.292838) (xy 93.926152 -393.292838)
			(xy 93.925666 -393.320107) (xy 93.917904 -393.374091) (xy 93.902539 -393.426421) (xy 93.879882 -393.476031)
			(xy 93.850396 -393.521912) (xy 93.814681 -393.563129) (xy 93.773464 -393.598844) (xy 93.727583 -393.62833)
			(xy 93.677973 -393.650987) (xy 93.625643 -393.666352) (xy 93.571659 -393.674114) (xy 93.517121 -393.674114)
			(xy 93.463137 -393.666352) (xy 93.410807 -393.650987) (xy 93.361197 -393.62833) (xy 93.315316 -393.598844)
			(xy 93.274099 -393.563129) (xy 93.238384 -393.521912) (xy 93.208898 -393.476031) (xy 93.186241 -393.426421)
			(xy 93.170876 -393.374091) (xy 93.163114 -393.320107) (xy 93.162628 -393.292838) (xy 92.726256 -393.292838)
			(xy 92.72577 -393.320107) (xy 92.718008 -393.374091) (xy 92.702643 -393.426421) (xy 92.679986 -393.476031)
			(xy 92.6505 -393.521912) (xy 92.614785 -393.563129) (xy 92.573568 -393.598844) (xy 92.527687 -393.62833)
			(xy 92.478077 -393.650987) (xy 92.425747 -393.666352) (xy 92.371763 -393.674114) (xy 92.317225 -393.674114)
			(xy 92.263241 -393.666352) (xy 92.210911 -393.650987) (xy 92.161301 -393.62833) (xy 92.11542 -393.598844)
			(xy 92.074203 -393.563129) (xy 92.038488 -393.521912) (xy 92.009002 -393.476031) (xy 91.986345 -393.426421)
			(xy 91.97098 -393.374091) (xy 91.963218 -393.320107) (xy 91.962732 -393.292838) (xy 91.525852 -393.292838)
			(xy 91.525366 -393.320089) (xy 91.51761 -393.374037) (xy 91.502255 -393.426332) (xy 91.479613 -393.475909)
			(xy 91.450147 -393.521759) (xy 91.414456 -393.56295) (xy 91.373265 -393.598641) (xy 91.327415 -393.628107)
			(xy 91.277838 -393.650749) (xy 91.225543 -393.666104) (xy 91.171595 -393.67386) (xy 91.117093 -393.67386)
			(xy 91.063145 -393.666104) (xy 91.01085 -393.650749) (xy 90.961273 -393.628107) (xy 90.915423 -393.598641)
			(xy 90.874232 -393.56295) (xy 90.838541 -393.521759) (xy 90.809075 -393.475909) (xy 90.786433 -393.426332)
			(xy 90.771078 -393.374037) (xy 90.763322 -393.320089) (xy 90.762836 -393.292838) (xy 90.325956 -393.292838)
			(xy 90.32547 -393.320089) (xy 90.317714 -393.374037) (xy 90.302359 -393.426332) (xy 90.279717 -393.475909)
			(xy 90.250251 -393.521759) (xy 90.21456 -393.56295) (xy 90.173369 -393.598641) (xy 90.127519 -393.628107)
			(xy 90.077942 -393.650749) (xy 90.025647 -393.666104) (xy 89.971699 -393.67386) (xy 89.917197 -393.67386)
			(xy 89.863249 -393.666104) (xy 89.810954 -393.650749) (xy 89.761377 -393.628107) (xy 89.715527 -393.598641)
			(xy 89.674336 -393.56295) (xy 89.638645 -393.521759) (xy 89.609179 -393.475909) (xy 89.586537 -393.426332)
			(xy 89.571182 -393.374037) (xy 89.563426 -393.320089) (xy 89.56294 -393.292838) (xy 89.12606 -393.292838)
			(xy 89.125574 -393.320107) (xy 89.117812 -393.374091) (xy 89.102447 -393.426421) (xy 89.07979 -393.476031)
			(xy 89.050304 -393.521912) (xy 89.014589 -393.563129) (xy 88.973372 -393.598844) (xy 88.927491 -393.62833)
			(xy 88.877881 -393.650987) (xy 88.825551 -393.666352) (xy 88.771567 -393.674114) (xy 88.717029 -393.674114)
			(xy 88.663045 -393.666352) (xy 88.610715 -393.650987) (xy 88.561105 -393.62833) (xy 88.515224 -393.598844)
			(xy 88.474007 -393.563129) (xy 88.438292 -393.521912) (xy 88.408806 -393.476031) (xy 88.386149 -393.426421)
			(xy 88.370784 -393.374091) (xy 88.363022 -393.320107) (xy 88.362536 -393.292838) (xy 87.926164 -393.292838)
			(xy 87.925678 -393.320107) (xy 87.917916 -393.374091) (xy 87.902551 -393.426421) (xy 87.879894 -393.476031)
			(xy 87.850408 -393.521912) (xy 87.814693 -393.563129) (xy 87.773476 -393.598844) (xy 87.727595 -393.62833)
			(xy 87.677985 -393.650987) (xy 87.625655 -393.666352) (xy 87.571671 -393.674114) (xy 87.517133 -393.674114)
			(xy 87.463149 -393.666352) (xy 87.410819 -393.650987) (xy 87.361209 -393.62833) (xy 87.315328 -393.598844)
			(xy 87.274111 -393.563129) (xy 87.238396 -393.521912) (xy 87.20891 -393.476031) (xy 87.186253 -393.426421)
			(xy 87.170888 -393.374091) (xy 87.163126 -393.320107) (xy 87.16264 -393.292838) (xy 86.72576 -393.292838)
			(xy 86.725274 -393.320089) (xy 86.717518 -393.374037) (xy 86.702163 -393.426332) (xy 86.679521 -393.475909)
			(xy 86.650055 -393.521759) (xy 86.614364 -393.56295) (xy 86.573173 -393.598641) (xy 86.527323 -393.628107)
			(xy 86.477746 -393.650749) (xy 86.425451 -393.666104) (xy 86.371503 -393.67386) (xy 86.317001 -393.67386)
			(xy 86.263053 -393.666104) (xy 86.210758 -393.650749) (xy 86.161181 -393.628107) (xy 86.115331 -393.598641)
			(xy 86.07414 -393.56295) (xy 86.038449 -393.521759) (xy 86.008983 -393.475909) (xy 85.986341 -393.426332)
			(xy 85.970986 -393.374037) (xy 85.96323 -393.320089) (xy 85.962744 -393.292838) (xy 85.525864 -393.292838)
			(xy 85.525378 -393.320089) (xy 85.517622 -393.374037) (xy 85.502267 -393.426332) (xy 85.479625 -393.475909)
			(xy 85.450159 -393.521759) (xy 85.414468 -393.56295) (xy 85.373277 -393.598641) (xy 85.327427 -393.628107)
			(xy 85.27785 -393.650749) (xy 85.225555 -393.666104) (xy 85.171607 -393.67386) (xy 85.117105 -393.67386)
			(xy 85.063157 -393.666104) (xy 85.010862 -393.650749) (xy 84.961285 -393.628107) (xy 84.915435 -393.598641)
			(xy 84.874244 -393.56295) (xy 84.838553 -393.521759) (xy 84.809087 -393.475909) (xy 84.786445 -393.426332)
			(xy 84.77109 -393.374037) (xy 84.763334 -393.320089) (xy 84.762848 -393.292838) (xy 84.325968 -393.292838)
			(xy 84.325482 -393.320107) (xy 84.31772 -393.374091) (xy 84.302355 -393.426421) (xy 84.279698 -393.476031)
			(xy 84.250212 -393.521912) (xy 84.214497 -393.563129) (xy 84.17328 -393.598844) (xy 84.127399 -393.62833)
			(xy 84.077789 -393.650987) (xy 84.025459 -393.666352) (xy 83.971475 -393.674114) (xy 83.916937 -393.674114)
			(xy 83.862953 -393.666352) (xy 83.810623 -393.650987) (xy 83.761013 -393.62833) (xy 83.715132 -393.598844)
			(xy 83.673915 -393.563129) (xy 83.6382 -393.521912) (xy 83.608714 -393.476031) (xy 83.586057 -393.426421)
			(xy 83.570692 -393.374091) (xy 83.56293 -393.320107) (xy 83.562444 -393.292838) (xy 83.126072 -393.292838)
			(xy 83.125586 -393.320107) (xy 83.117824 -393.374091) (xy 83.102459 -393.426421) (xy 83.079802 -393.476031)
			(xy 83.050316 -393.521912) (xy 83.014601 -393.563129) (xy 82.973384 -393.598844) (xy 82.927503 -393.62833)
			(xy 82.877893 -393.650987) (xy 82.825563 -393.666352) (xy 82.771579 -393.674114) (xy 82.717041 -393.674114)
			(xy 82.663057 -393.666352) (xy 82.610727 -393.650987) (xy 82.561117 -393.62833) (xy 82.515236 -393.598844)
			(xy 82.474019 -393.563129) (xy 82.438304 -393.521912) (xy 82.408818 -393.476031) (xy 82.386161 -393.426421)
			(xy 82.370796 -393.374091) (xy 82.363034 -393.320107) (xy 82.362548 -393.292838) (xy 81.925668 -393.292838)
			(xy 81.925182 -393.320089) (xy 81.917426 -393.374037) (xy 81.902071 -393.426332) (xy 81.879429 -393.475909)
			(xy 81.849963 -393.521759) (xy 81.814272 -393.56295) (xy 81.773081 -393.598641) (xy 81.727231 -393.628107)
			(xy 81.677654 -393.650749) (xy 81.625359 -393.666104) (xy 81.571411 -393.67386) (xy 81.516909 -393.67386)
			(xy 81.462961 -393.666104) (xy 81.410666 -393.650749) (xy 81.361089 -393.628107) (xy 81.315239 -393.598641)
			(xy 81.274048 -393.56295) (xy 81.238357 -393.521759) (xy 81.208891 -393.475909) (xy 81.186249 -393.426332)
			(xy 81.170894 -393.374037) (xy 81.163138 -393.320089) (xy 81.162652 -393.292838) (xy 80.725772 -393.292838)
			(xy 80.725286 -393.320089) (xy 80.71753 -393.374037) (xy 80.702175 -393.426332) (xy 80.679533 -393.475909)
			(xy 80.650067 -393.521759) (xy 80.614376 -393.56295) (xy 80.573185 -393.598641) (xy 80.527335 -393.628107)
			(xy 80.477758 -393.650749) (xy 80.425463 -393.666104) (xy 80.371515 -393.67386) (xy 80.317013 -393.67386)
			(xy 80.263065 -393.666104) (xy 80.21077 -393.650749) (xy 80.161193 -393.628107) (xy 80.115343 -393.598641)
			(xy 80.074152 -393.56295) (xy 80.038461 -393.521759) (xy 80.008995 -393.475909) (xy 79.986353 -393.426332)
			(xy 79.970998 -393.374037) (xy 79.963242 -393.320089) (xy 79.962756 -393.292838) (xy 66.197988 -393.292838)
			(xy 66.197502 -393.320089) (xy 66.189746 -393.374037) (xy 66.174391 -393.426332) (xy 66.151749 -393.475909)
			(xy 66.122283 -393.521759) (xy 66.086592 -393.56295) (xy 66.045401 -393.598641) (xy 65.999551 -393.628107)
			(xy 65.949974 -393.650749) (xy 65.897679 -393.666104) (xy 65.843731 -393.67386) (xy 65.789229 -393.67386)
			(xy 65.735281 -393.666104) (xy 65.682986 -393.650749) (xy 65.633409 -393.628107) (xy 65.587559 -393.598641)
			(xy 65.546368 -393.56295) (xy 65.510677 -393.521759) (xy 65.481211 -393.475909) (xy 65.458569 -393.426332)
			(xy 65.443214 -393.374037) (xy 65.435458 -393.320089) (xy 65.434972 -393.292838) (xy 64.998092 -393.292838)
			(xy 64.997606 -393.320089) (xy 64.98985 -393.374037) (xy 64.974495 -393.426332) (xy 64.951853 -393.475909)
			(xy 64.922387 -393.521759) (xy 64.886696 -393.56295) (xy 64.845505 -393.598641) (xy 64.799655 -393.628107)
			(xy 64.750078 -393.650749) (xy 64.697783 -393.666104) (xy 64.643835 -393.67386) (xy 64.589333 -393.67386)
			(xy 64.535385 -393.666104) (xy 64.48309 -393.650749) (xy 64.433513 -393.628107) (xy 64.387663 -393.598641)
			(xy 64.346472 -393.56295) (xy 64.310781 -393.521759) (xy 64.281315 -393.475909) (xy 64.258673 -393.426332)
			(xy 64.243318 -393.374037) (xy 64.235562 -393.320089) (xy 64.235076 -393.292838) (xy 63.798196 -393.292838)
			(xy 63.79771 -393.320107) (xy 63.789948 -393.374091) (xy 63.774583 -393.426421) (xy 63.751926 -393.476031)
			(xy 63.72244 -393.521912) (xy 63.686725 -393.563129) (xy 63.645508 -393.598844) (xy 63.599627 -393.62833)
			(xy 63.550017 -393.650987) (xy 63.497687 -393.666352) (xy 63.443703 -393.674114) (xy 63.389165 -393.674114)
			(xy 63.335181 -393.666352) (xy 63.282851 -393.650987) (xy 63.233241 -393.62833) (xy 63.18736 -393.598844)
			(xy 63.146143 -393.563129) (xy 63.110428 -393.521912) (xy 63.080942 -393.476031) (xy 63.058285 -393.426421)
			(xy 63.04292 -393.374091) (xy 63.035158 -393.320107) (xy 63.034672 -393.292838) (xy 62.5983 -393.292838)
			(xy 62.597814 -393.320107) (xy 62.590052 -393.374091) (xy 62.574687 -393.426421) (xy 62.55203 -393.476031)
			(xy 62.522544 -393.521912) (xy 62.486829 -393.563129) (xy 62.445612 -393.598844) (xy 62.399731 -393.62833)
			(xy 62.350121 -393.650987) (xy 62.297791 -393.666352) (xy 62.243807 -393.674114) (xy 62.189269 -393.674114)
			(xy 62.135285 -393.666352) (xy 62.082955 -393.650987) (xy 62.033345 -393.62833) (xy 61.987464 -393.598844)
			(xy 61.946247 -393.563129) (xy 61.910532 -393.521912) (xy 61.881046 -393.476031) (xy 61.858389 -393.426421)
			(xy 61.843024 -393.374091) (xy 61.835262 -393.320107) (xy 61.834776 -393.292838) (xy 61.398404 -393.292838)
			(xy 61.397918 -393.320107) (xy 61.390156 -393.374091) (xy 61.374791 -393.426421) (xy 61.352134 -393.476031)
			(xy 61.322648 -393.521912) (xy 61.286933 -393.563129) (xy 61.245716 -393.598844) (xy 61.199835 -393.62833)
			(xy 61.150225 -393.650987) (xy 61.097895 -393.666352) (xy 61.043911 -393.674114) (xy 60.989373 -393.674114)
			(xy 60.935389 -393.666352) (xy 60.883059 -393.650987) (xy 60.833449 -393.62833) (xy 60.787568 -393.598844)
			(xy 60.746351 -393.563129) (xy 60.710636 -393.521912) (xy 60.68115 -393.476031) (xy 60.658493 -393.426421)
			(xy 60.643128 -393.374091) (xy 60.635366 -393.320107) (xy 60.63488 -393.292838) (xy 60.198508 -393.292838)
			(xy 60.198022 -393.320107) (xy 60.19026 -393.374091) (xy 60.174895 -393.426421) (xy 60.152238 -393.476031)
			(xy 60.122752 -393.521912) (xy 60.087037 -393.563129) (xy 60.04582 -393.598844) (xy 59.999939 -393.62833)
			(xy 59.950329 -393.650987) (xy 59.897999 -393.666352) (xy 59.844015 -393.674114) (xy 59.789477 -393.674114)
			(xy 59.735493 -393.666352) (xy 59.683163 -393.650987) (xy 59.633553 -393.62833) (xy 59.587672 -393.598844)
			(xy 59.546455 -393.563129) (xy 59.51074 -393.521912) (xy 59.481254 -393.476031) (xy 59.458597 -393.426421)
			(xy 59.443232 -393.374091) (xy 59.43547 -393.320107) (xy 59.434984 -393.292838) (xy 58.998104 -393.292838)
			(xy 58.997618 -393.320089) (xy 58.989862 -393.374037) (xy 58.974507 -393.426332) (xy 58.951865 -393.475909)
			(xy 58.922399 -393.521759) (xy 58.886708 -393.56295) (xy 58.845517 -393.598641) (xy 58.799667 -393.628107)
			(xy 58.75009 -393.650749) (xy 58.697795 -393.666104) (xy 58.643847 -393.67386) (xy 58.589345 -393.67386)
			(xy 58.535397 -393.666104) (xy 58.483102 -393.650749) (xy 58.433525 -393.628107) (xy 58.387675 -393.598641)
			(xy 58.346484 -393.56295) (xy 58.310793 -393.521759) (xy 58.281327 -393.475909) (xy 58.258685 -393.426332)
			(xy 58.24333 -393.374037) (xy 58.235574 -393.320089) (xy 58.235088 -393.292838) (xy 57.798208 -393.292838)
			(xy 57.797722 -393.320089) (xy 57.789966 -393.374037) (xy 57.774611 -393.426332) (xy 57.751969 -393.475909)
			(xy 57.722503 -393.521759) (xy 57.686812 -393.56295) (xy 57.645621 -393.598641) (xy 57.599771 -393.628107)
			(xy 57.550194 -393.650749) (xy 57.497899 -393.666104) (xy 57.443951 -393.67386) (xy 57.389449 -393.67386)
			(xy 57.335501 -393.666104) (xy 57.283206 -393.650749) (xy 57.233629 -393.628107) (xy 57.187779 -393.598641)
			(xy 57.146588 -393.56295) (xy 57.110897 -393.521759) (xy 57.081431 -393.475909) (xy 57.058789 -393.426332)
			(xy 57.043434 -393.374037) (xy 57.035678 -393.320089) (xy 57.035192 -393.292838) (xy 56.598312 -393.292838)
			(xy 56.597826 -393.320107) (xy 56.590064 -393.374091) (xy 56.574699 -393.426421) (xy 56.552042 -393.476031)
			(xy 56.522556 -393.521912) (xy 56.486841 -393.563129) (xy 56.445624 -393.598844) (xy 56.399743 -393.62833)
			(xy 56.350133 -393.650987) (xy 56.297803 -393.666352) (xy 56.243819 -393.674114) (xy 56.189281 -393.674114)
			(xy 56.135297 -393.666352) (xy 56.082967 -393.650987) (xy 56.033357 -393.62833) (xy 55.987476 -393.598844)
			(xy 55.946259 -393.563129) (xy 55.910544 -393.521912) (xy 55.881058 -393.476031) (xy 55.858401 -393.426421)
			(xy 55.843036 -393.374091) (xy 55.835274 -393.320107) (xy 55.834788 -393.292838) (xy 55.398416 -393.292838)
			(xy 55.39793 -393.320107) (xy 55.390168 -393.374091) (xy 55.374803 -393.426421) (xy 55.352146 -393.476031)
			(xy 55.32266 -393.521912) (xy 55.286945 -393.563129) (xy 55.245728 -393.598844) (xy 55.199847 -393.62833)
			(xy 55.150237 -393.650987) (xy 55.097907 -393.666352) (xy 55.043923 -393.674114) (xy 54.989385 -393.674114)
			(xy 54.935401 -393.666352) (xy 54.883071 -393.650987) (xy 54.833461 -393.62833) (xy 54.78758 -393.598844)
			(xy 54.746363 -393.563129) (xy 54.710648 -393.521912) (xy 54.681162 -393.476031) (xy 54.658505 -393.426421)
			(xy 54.64314 -393.374091) (xy 54.635378 -393.320107) (xy 54.634892 -393.292838) (xy 54.198012 -393.292838)
			(xy 54.197526 -393.320089) (xy 54.18977 -393.374037) (xy 54.174415 -393.426332) (xy 54.151773 -393.475909)
			(xy 54.122307 -393.521759) (xy 54.086616 -393.56295) (xy 54.045425 -393.598641) (xy 53.999575 -393.628107)
			(xy 53.949998 -393.650749) (xy 53.897703 -393.666104) (xy 53.843755 -393.67386) (xy 53.789253 -393.67386)
			(xy 53.735305 -393.666104) (xy 53.68301 -393.650749) (xy 53.633433 -393.628107) (xy 53.587583 -393.598641)
			(xy 53.546392 -393.56295) (xy 53.510701 -393.521759) (xy 53.481235 -393.475909) (xy 53.458593 -393.426332)
			(xy 53.443238 -393.374037) (xy 53.435482 -393.320089) (xy 53.434996 -393.292838) (xy 52.998116 -393.292838)
			(xy 52.99763 -393.320089) (xy 52.989874 -393.374037) (xy 52.974519 -393.426332) (xy 52.951877 -393.475909)
			(xy 52.922411 -393.521759) (xy 52.88672 -393.56295) (xy 52.845529 -393.598641) (xy 52.799679 -393.628107)
			(xy 52.750102 -393.650749) (xy 52.697807 -393.666104) (xy 52.643859 -393.67386) (xy 52.589357 -393.67386)
			(xy 52.535409 -393.666104) (xy 52.483114 -393.650749) (xy 52.433537 -393.628107) (xy 52.387687 -393.598641)
			(xy 52.346496 -393.56295) (xy 52.310805 -393.521759) (xy 52.281339 -393.475909) (xy 52.258697 -393.426332)
			(xy 52.243342 -393.374037) (xy 52.235586 -393.320089) (xy 52.2351 -393.292838) (xy 51.79822 -393.292838)
			(xy 51.797734 -393.320107) (xy 51.789972 -393.374091) (xy 51.774607 -393.426421) (xy 51.75195 -393.476031)
			(xy 51.722464 -393.521912) (xy 51.686749 -393.563129) (xy 51.645532 -393.598844) (xy 51.599651 -393.62833)
			(xy 51.550041 -393.650987) (xy 51.497711 -393.666352) (xy 51.443727 -393.674114) (xy 51.389189 -393.674114)
			(xy 51.335205 -393.666352) (xy 51.282875 -393.650987) (xy 51.233265 -393.62833) (xy 51.187384 -393.598844)
			(xy 51.146167 -393.563129) (xy 51.110452 -393.521912) (xy 51.080966 -393.476031) (xy 51.058309 -393.426421)
			(xy 51.042944 -393.374091) (xy 51.035182 -393.320107) (xy 51.034696 -393.292838) (xy 50.598324 -393.292838)
			(xy 50.597838 -393.320107) (xy 50.590076 -393.374091) (xy 50.574711 -393.426421) (xy 50.552054 -393.476031)
			(xy 50.522568 -393.521912) (xy 50.486853 -393.563129) (xy 50.445636 -393.598844) (xy 50.399755 -393.62833)
			(xy 50.350145 -393.650987) (xy 50.297815 -393.666352) (xy 50.243831 -393.674114) (xy 50.189293 -393.674114)
			(xy 50.135309 -393.666352) (xy 50.082979 -393.650987) (xy 50.033369 -393.62833) (xy 49.987488 -393.598844)
			(xy 49.946271 -393.563129) (xy 49.910556 -393.521912) (xy 49.88107 -393.476031) (xy 49.858413 -393.426421)
			(xy 49.843048 -393.374091) (xy 49.835286 -393.320107) (xy 49.8348 -393.292838) (xy 49.39792 -393.292838)
			(xy 49.397434 -393.320089) (xy 49.389678 -393.374037) (xy 49.374323 -393.426332) (xy 49.351681 -393.475909)
			(xy 49.322215 -393.521759) (xy 49.286524 -393.56295) (xy 49.245333 -393.598641) (xy 49.199483 -393.628107)
			(xy 49.149906 -393.650749) (xy 49.097611 -393.666104) (xy 49.043663 -393.67386) (xy 48.989161 -393.67386)
			(xy 48.935213 -393.666104) (xy 48.882918 -393.650749) (xy 48.833341 -393.628107) (xy 48.787491 -393.598641)
			(xy 48.7463 -393.56295) (xy 48.710609 -393.521759) (xy 48.681143 -393.475909) (xy 48.658501 -393.426332)
			(xy 48.643146 -393.374037) (xy 48.63539 -393.320089) (xy 48.634904 -393.292838) (xy 48.198024 -393.292838)
			(xy 48.197538 -393.320089) (xy 48.189782 -393.374037) (xy 48.174427 -393.426332) (xy 48.151785 -393.475909)
			(xy 48.122319 -393.521759) (xy 48.086628 -393.56295) (xy 48.045437 -393.598641) (xy 47.999587 -393.628107)
			(xy 47.95001 -393.650749) (xy 47.897715 -393.666104) (xy 47.843767 -393.67386) (xy 47.789265 -393.67386)
			(xy 47.735317 -393.666104) (xy 47.683022 -393.650749) (xy 47.633445 -393.628107) (xy 47.587595 -393.598641)
			(xy 47.546404 -393.56295) (xy 47.510713 -393.521759) (xy 47.481247 -393.475909) (xy 47.458605 -393.426332)
			(xy 47.44325 -393.374037) (xy 47.435494 -393.320089) (xy 47.435008 -393.292838) (xy 21.426678 -393.292838)
			(xy 33.019445 -404.885605) (xy 37.250362 -404.885605) (xy 37.250362 -404.699771) (xy 37.258357 -404.514108)
			(xy 37.274332 -404.328962) (xy 37.298258 -404.144674) (xy 37.33009 -403.961586) (xy 37.36977 -403.780037)
			(xy 37.417223 -403.600363) (xy 37.472363 -403.422897) (xy 37.535086 -403.247968) (xy 37.605277 -403.075899)
			(xy 37.682806 -402.90701) (xy 37.767529 -402.741612) (xy 37.85929 -402.580012) (xy 37.957918 -402.42251)
			(xy 38.063231 -402.269396) (xy 38.175033 -402.120956) (xy 38.293118 -401.977462) (xy 38.417268 -401.839182)
			(xy 38.547251 -401.706371) (xy 38.682828 -401.579275) (xy 38.823748 -401.45813) (xy 38.969748 -401.343159)
			(xy 39.12056 -401.234576) (xy 39.275904 -401.132583) (xy 39.435492 -401.037366) (xy 39.599029 -400.949104)
			(xy 39.766211 -400.867959) (xy 39.93673 -400.794082) (xy 40.110269 -400.727609) (xy 40.286508 -400.668664)
			(xy 40.465119 -400.617356) (xy 40.645772 -400.573779) (xy 40.828133 -400.538015) (xy 41.011863 -400.510129)
			(xy 41.196623 -400.490174) (xy 41.38207 -400.478186) (xy 41.567862 -400.474188) (xy 41.753654 -400.478186)
			(xy 41.939101 -400.490174) (xy 42.108501 -400.50847) (xy 103.35895 -400.50847) (xy 103.359461 -400.476693)
			(xy 103.367388 -400.413634) (xy 103.383113 -400.352055) (xy 103.406392 -400.292917) (xy 103.436862 -400.237142)
			(xy 103.474047 -400.1856) (xy 103.495348 -400.162014) (xy 103.50159 -400.154785) (xy 103.508577 -400.137022)
			(xy 103.508569 -400.117934) (xy 103.501566 -400.100177) (xy 103.495348 -400.092926) (xy 103.474038 -400.069346)
			(xy 103.436845 -400.017807) (xy 103.406369 -399.962033) (xy 103.383087 -399.902893) (xy 103.367362 -399.841311)
			(xy 103.359439 -399.778249) (xy 103.35895 -399.74647) (xy 103.359451 -399.714541) (xy 103.367455 -399.651186)
			(xy 103.383336 -399.589334) (xy 103.406844 -399.52996) (xy 103.437608 -399.474001) (xy 103.475142 -399.422339)
			(xy 103.518856 -399.375788) (xy 103.56806 -399.335083) (xy 103.621977 -399.300866) (xy 103.679758 -399.273677)
			(xy 103.740491 -399.253944) (xy 103.803218 -399.241978) (xy 103.86695 -399.237968) (xy 103.930682 -399.241978)
			(xy 103.993409 -399.253944) (xy 104.054142 -399.273677) (xy 104.111923 -399.300866) (xy 104.16584 -399.335083)
			(xy 104.215044 -399.375788) (xy 104.258758 -399.422339) (xy 104.296292 -399.474001) (xy 104.327056 -399.52996)
			(xy 104.350564 -399.589334) (xy 104.366445 -399.651186) (xy 104.374449 -399.714541) (xy 104.37495 -399.74647)
			(xy 104.374464 -399.778248) (xy 104.366532 -399.841308) (xy 104.350802 -399.902887) (xy 104.327518 -399.962025)
			(xy 104.297044 -400.0178) (xy 104.259855 -400.06934) (xy 104.238552 -400.092926) (xy 104.232369 -400.1002)
			(xy 104.225372 -400.117942) (xy 104.225363 -400.137014) (xy 104.232345 -400.154763) (xy 104.238552 -400.162014)
			(xy 104.259833 -400.185619) (xy 104.29703 -400.237152) (xy 104.32751 -400.292922) (xy 104.350797 -400.352057)
			(xy 104.366528 -400.413634) (xy 104.374457 -400.476693) (xy 104.37495 -400.50847) (xy 104.374449 -400.540399)
			(xy 104.366445 -400.603754) (xy 104.350564 -400.665606) (xy 104.327056 -400.72498) (xy 104.296292 -400.780939)
			(xy 104.258758 -400.832601) (xy 104.215044 -400.879152) (xy 104.16584 -400.919857) (xy 104.111923 -400.954074)
			(xy 104.054142 -400.981263) (xy 103.993409 -401.000996) (xy 103.930682 -401.012962) (xy 103.86695 -401.016972)
			(xy 103.803218 -401.012962) (xy 103.740491 -401.000996) (xy 103.679758 -400.981263) (xy 103.621977 -400.954074)
			(xy 103.56806 -400.919857) (xy 103.518856 -400.879152) (xy 103.475142 -400.832601) (xy 103.437608 -400.780939)
			(xy 103.406844 -400.72498) (xy 103.383336 -400.665606) (xy 103.367455 -400.603754) (xy 103.359451 -400.540399)
			(xy 103.35895 -400.50847) (xy 42.108501 -400.50847) (xy 42.123861 -400.510129) (xy 42.307591 -400.538015)
			(xy 42.489952 -400.573779) (xy 42.670605 -400.617356) (xy 42.849216 -400.668664) (xy 43.025455 -400.727609)
			(xy 43.198994 -400.794082) (xy 43.369513 -400.867959) (xy 43.536695 -400.949104) (xy 43.700232 -401.037366)
			(xy 43.85982 -401.132583) (xy 44.015164 -401.234576) (xy 44.165976 -401.343159) (xy 44.311976 -401.45813)
			(xy 44.452896 -401.579275) (xy 44.588473 -401.706371) (xy 44.718456 -401.839182) (xy 44.842606 -401.977462)
			(xy 44.960691 -402.120956) (xy 45.072493 -402.269396) (xy 45.177806 -402.42251) (xy 45.276434 -402.580012)
			(xy 45.368195 -402.741612) (xy 45.452918 -402.90701) (xy 45.530447 -403.075899) (xy 45.600638 -403.247968)
			(xy 45.663361 -403.422897) (xy 45.718501 -403.600363) (xy 45.765954 -403.780037) (xy 45.805634 -403.961586)
			(xy 45.837466 -404.144674) (xy 45.861392 -404.328962) (xy 45.875438 -404.491748) (xy 47.413198 -404.491748)
			(xy 47.413198 -404.437252) (xy 47.420953 -404.38331) (xy 47.436306 -404.331021) (xy 47.458943 -404.281449)
			(xy 47.488404 -404.235603) (xy 47.52409 -404.194416) (xy 47.565274 -404.158726) (xy 47.611117 -404.12926)
			(xy 47.660687 -404.106618) (xy 47.712975 -404.091261) (xy 47.766916 -404.083501) (xy 47.794164 -404.083012)
			(xy 48.657764 -404.083012) (xy 48.68502 -404.083432) (xy 48.738978 -404.091186) (xy 48.791283 -404.106539)
			(xy 48.84087 -404.129181) (xy 48.88673 -404.15865) (xy 48.927929 -404.194345) (xy 48.963629 -404.235541)
			(xy 48.993102 -404.281398) (xy 49.015748 -404.330984) (xy 49.031107 -404.383287) (xy 49.038865 -404.437244)
			(xy 49.038865 -404.491752) (xy 50.476375 -404.491752) (xy 50.476375 -404.437248) (xy 50.484132 -404.3833)
			(xy 50.499487 -404.331005) (xy 50.522129 -404.281427) (xy 50.551596 -404.235576) (xy 50.587288 -404.194385)
			(xy 50.628479 -404.158693) (xy 50.67433 -404.129227) (xy 50.723908 -404.106586) (xy 50.776204 -404.091231)
			(xy 50.830152 -404.083475) (xy 50.857404 -404.083012) (xy 51.721004 -404.083012) (xy 51.748256 -404.083458)
			(xy 51.802207 -404.091215) (xy 51.854504 -404.106572) (xy 51.904083 -404.129214) (xy 51.949935 -404.158682)
			(xy 51.991127 -404.194376) (xy 52.02682 -404.235568) (xy 52.056288 -404.281421) (xy 52.07893 -404.331)
			(xy 52.094285 -404.383297) (xy 52.102042 -404.437248) (xy 52.102042 -404.491752) (xy 52.102042 -404.491753)
			(xy 53.539575 -404.491753) (xy 53.539575 -404.437247) (xy 53.547333 -404.383295) (xy 53.562691 -404.330996)
			(xy 53.585335 -404.281416) (xy 53.614806 -404.235563) (xy 53.650502 -404.194371) (xy 53.691698 -404.158679)
			(xy 53.737554 -404.129214) (xy 53.787137 -404.106575) (xy 53.839438 -404.091224) (xy 53.893391 -404.083472)
			(xy 53.920644 -404.083012) (xy 54.784244 -404.083012) (xy 54.811495 -404.083461) (xy 54.86544 -404.091223)
			(xy 54.917733 -404.106583) (xy 54.967307 -404.129227) (xy 55.013154 -404.158696) (xy 55.054341 -404.19439)
			(xy 55.09003 -404.235581) (xy 55.119494 -404.281432) (xy 55.142133 -404.331009) (xy 55.157487 -404.383303)
			(xy 55.165242 -404.437249) (xy 55.165242 -404.491749) (xy 56.602898 -404.491749) (xy 56.602898 -404.437251)
			(xy 56.610654 -404.383308) (xy 56.626007 -404.331017) (xy 56.648646 -404.281443) (xy 56.678109 -404.235596)
			(xy 56.713797 -404.194409) (xy 56.754983 -404.158719) (xy 56.800829 -404.129254) (xy 56.850402 -404.106613)
			(xy 56.902692 -404.091257) (xy 56.956635 -404.083499) (xy 56.983884 -404.083012) (xy 57.847484 -404.083012)
			(xy 57.874739 -404.083434) (xy 57.928695 -404.091189) (xy 57.980997 -404.106545) (xy 58.030582 -404.129188)
			(xy 58.07644 -404.158657) (xy 58.117636 -404.194352) (xy 58.153334 -404.235548) (xy 58.182805 -404.281404)
			(xy 58.20545 -404.330988) (xy 58.220807 -404.38329) (xy 58.228565 -404.437245) (xy 58.228565 -404.491753)
			(xy 59.666075 -404.491753) (xy 59.666075 -404.437247) (xy 59.673833 -404.383297) (xy 59.689189 -404.331)
			(xy 59.711832 -404.281421) (xy 59.741301 -404.235569) (xy 59.776995 -404.194378) (xy 59.818188 -404.158686)
			(xy 59.864042 -404.129221) (xy 59.913623 -404.106581) (xy 59.965921 -404.091227) (xy 60.019871 -404.083474)
			(xy 60.047124 -404.083012) (xy 60.910724 -404.083012) (xy 60.937976 -404.083459) (xy 60.991924 -404.091219)
			(xy 61.044218 -404.106577) (xy 61.093795 -404.129221) (xy 61.139645 -404.158689) (xy 61.180834 -404.194383)
			(xy 61.216525 -404.235575) (xy 61.245991 -404.281426) (xy 61.268631 -404.331004) (xy 61.283986 -404.3833)
			(xy 61.291742 -404.437248) (xy 61.291742 -404.491748) (xy 62.729398 -404.491748) (xy 62.729398 -404.437252)
			(xy 62.737153 -404.38331) (xy 62.752506 -404.331021) (xy 62.775143 -404.281449) (xy 62.804604 -404.235603)
			(xy 62.84029 -404.194416) (xy 62.881474 -404.158726) (xy 62.927317 -404.12926) (xy 62.976887 -404.106618)
			(xy 63.029175 -404.091261) (xy 63.083116 -404.083501) (xy 63.110364 -404.083012) (xy 63.973964 -404.083012)
			(xy 64.00122 -404.083432) (xy 64.055178 -404.091186) (xy 64.107483 -404.106539) (xy 64.15707 -404.129181)
			(xy 64.20293 -404.15865) (xy 64.244129 -404.194345) (xy 64.279829 -404.235541) (xy 64.309302 -404.281398)
			(xy 64.331948 -404.330984) (xy 64.347307 -404.383287) (xy 64.355065 -404.437244) (xy 64.355065 -404.491752)
			(xy 65.792575 -404.491752) (xy 65.792575 -404.437248) (xy 65.800332 -404.3833) (xy 65.815687 -404.331005)
			(xy 65.838329 -404.281427) (xy 65.867796 -404.235576) (xy 65.903488 -404.194385) (xy 65.944679 -404.158693)
			(xy 65.99053 -404.129227) (xy 66.040108 -404.106586) (xy 66.092404 -404.091231) (xy 66.146352 -404.083475)
			(xy 66.173604 -404.083012) (xy 67.037204 -404.083012) (xy 67.064456 -404.083458) (xy 67.118407 -404.091215)
			(xy 67.170704 -404.106572) (xy 67.220283 -404.129214) (xy 67.266135 -404.158682) (xy 67.307327 -404.194376)
			(xy 67.34302 -404.235568) (xy 67.372488 -404.281421) (xy 67.39513 -404.331) (xy 67.410485 -404.383297)
			(xy 67.418242 -404.437248) (xy 67.418242 -404.491752) (xy 67.418242 -404.491753) (xy 68.855775 -404.491753)
			(xy 68.855775 -404.437247) (xy 68.863533 -404.383295) (xy 68.878891 -404.330996) (xy 68.901535 -404.281416)
			(xy 68.931006 -404.235563) (xy 68.966702 -404.194371) (xy 69.007898 -404.158679) (xy 69.053754 -404.129214)
			(xy 69.103337 -404.106575) (xy 69.155638 -404.091224) (xy 69.209591 -404.083472) (xy 69.236844 -404.083012)
			(xy 70.100444 -404.083012) (xy 70.127695 -404.083461) (xy 70.18164 -404.091223) (xy 70.233933 -404.106583)
			(xy 70.283507 -404.129227) (xy 70.329354 -404.158696) (xy 70.370541 -404.19439) (xy 70.40623 -404.235581)
			(xy 70.435694 -404.281432) (xy 70.458333 -404.331009) (xy 70.473687 -404.383303) (xy 70.481442 -404.437249)
			(xy 70.481442 -404.491749) (xy 71.919098 -404.491749) (xy 71.919098 -404.437251) (xy 71.926854 -404.383308)
			(xy 71.942207 -404.331017) (xy 71.964846 -404.281443) (xy 71.994309 -404.235596) (xy 72.029997 -404.194409)
			(xy 72.071183 -404.158719) (xy 72.117029 -404.129254) (xy 72.166602 -404.106613) (xy 72.218892 -404.091257)
			(xy 72.272835 -404.083499) (xy 72.300084 -404.083012) (xy 73.163684 -404.083012) (xy 73.190939 -404.083434)
			(xy 73.244895 -404.091189) (xy 73.297197 -404.106545) (xy 73.346782 -404.129188) (xy 73.39264 -404.158657)
			(xy 73.433836 -404.194352) (xy 73.469534 -404.235548) (xy 73.499005 -404.281404) (xy 73.52165 -404.330988)
			(xy 73.537007 -404.38329) (xy 73.544765 -404.437245) (xy 73.544765 -404.491753) (xy 74.982275 -404.491753)
			(xy 74.982275 -404.437247) (xy 74.990033 -404.383297) (xy 75.005389 -404.331) (xy 75.028032 -404.281421)
			(xy 75.057501 -404.235569) (xy 75.093195 -404.194378) (xy 75.134388 -404.158686) (xy 75.180242 -404.129221)
			(xy 75.229823 -404.106581) (xy 75.282121 -404.091227) (xy 75.336071 -404.083474) (xy 75.363324 -404.083012)
			(xy 76.226924 -404.083012) (xy 76.254176 -404.083459) (xy 76.308124 -404.091219) (xy 76.360418 -404.106577)
			(xy 76.409995 -404.129221) (xy 76.455845 -404.158689) (xy 76.497034 -404.194383) (xy 76.532725 -404.235575)
			(xy 76.562191 -404.281426) (xy 76.584831 -404.331004) (xy 76.600186 -404.3833) (xy 76.607942 -404.437248)
			(xy 76.607942 -404.491748) (xy 78.045598 -404.491748) (xy 78.045598 -404.437252) (xy 78.053353 -404.38331)
			(xy 78.068706 -404.331021) (xy 78.091343 -404.281449) (xy 78.120804 -404.235603) (xy 78.15649 -404.194416)
			(xy 78.197674 -404.158726) (xy 78.243517 -404.12926) (xy 78.293087 -404.106618) (xy 78.345375 -404.091261)
			(xy 78.399316 -404.083501) (xy 78.426564 -404.083012) (xy 79.290164 -404.083012) (xy 79.31742 -404.083432)
			(xy 79.371378 -404.091186) (xy 79.423683 -404.106539) (xy 79.47327 -404.129181) (xy 79.51913 -404.15865)
			(xy 79.560329 -404.194345) (xy 79.596029 -404.235541) (xy 79.625502 -404.281398) (xy 79.648148 -404.330984)
			(xy 79.663507 -404.383287) (xy 79.671265 -404.437244) (xy 79.671265 -404.491752) (xy 81.108775 -404.491752)
			(xy 81.108775 -404.437248) (xy 81.116532 -404.3833) (xy 81.131887 -404.331005) (xy 81.154529 -404.281427)
			(xy 81.183996 -404.235576) (xy 81.219688 -404.194385) (xy 81.260879 -404.158693) (xy 81.30673 -404.129227)
			(xy 81.356308 -404.106586) (xy 81.408604 -404.091231) (xy 81.462552 -404.083475) (xy 81.489804 -404.083012)
			(xy 82.353404 -404.083012) (xy 82.380656 -404.083458) (xy 82.434607 -404.091215) (xy 82.486904 -404.106572)
			(xy 82.536483 -404.129214) (xy 82.582335 -404.158682) (xy 82.623527 -404.194376) (xy 82.65922 -404.235568)
			(xy 82.688688 -404.281421) (xy 82.71133 -404.331) (xy 82.726685 -404.383297) (xy 82.734442 -404.437248)
			(xy 82.734442 -404.491752) (xy 82.734442 -404.491753) (xy 84.171975 -404.491753) (xy 84.171975 -404.437247)
			(xy 84.179733 -404.383295) (xy 84.195091 -404.330996) (xy 84.217735 -404.281416) (xy 84.247206 -404.235563)
			(xy 84.282902 -404.194371) (xy 84.324098 -404.158679) (xy 84.369954 -404.129214) (xy 84.419537 -404.106575)
			(xy 84.471838 -404.091224) (xy 84.525791 -404.083472) (xy 84.553044 -404.083012) (xy 85.416644 -404.083012)
			(xy 85.443895 -404.083461) (xy 85.49784 -404.091223) (xy 85.550133 -404.106583) (xy 85.599707 -404.129227)
			(xy 85.645554 -404.158696) (xy 85.686741 -404.19439) (xy 85.72243 -404.235581) (xy 85.751894 -404.281432)
			(xy 85.774533 -404.331009) (xy 85.789887 -404.383303) (xy 85.797642 -404.437249) (xy 85.797642 -404.491749)
			(xy 87.235298 -404.491749) (xy 87.235298 -404.437251) (xy 87.243054 -404.383308) (xy 87.258407 -404.331017)
			(xy 87.281046 -404.281443) (xy 87.310509 -404.235596) (xy 87.346197 -404.194409) (xy 87.387383 -404.158719)
			(xy 87.433229 -404.129254) (xy 87.482802 -404.106613) (xy 87.535092 -404.091257) (xy 87.589035 -404.083499)
			(xy 87.616284 -404.083012) (xy 88.479884 -404.083012) (xy 88.507139 -404.083434) (xy 88.561095 -404.091189)
			(xy 88.613397 -404.106545) (xy 88.662982 -404.129188) (xy 88.70884 -404.158657) (xy 88.750036 -404.194352)
			(xy 88.785734 -404.235548) (xy 88.815205 -404.281404) (xy 88.83785 -404.330988) (xy 88.853207 -404.38329)
			(xy 88.860965 -404.437245) (xy 88.860965 -404.491753) (xy 90.298475 -404.491753) (xy 90.298475 -404.437247)
			(xy 90.306233 -404.383297) (xy 90.321589 -404.331) (xy 90.344232 -404.281421) (xy 90.373701 -404.235569)
			(xy 90.409395 -404.194378) (xy 90.450588 -404.158686) (xy 90.496442 -404.129221) (xy 90.546023 -404.106581)
			(xy 90.598321 -404.091227) (xy 90.652271 -404.083474) (xy 90.679524 -404.083012) (xy 91.543124 -404.083012)
			(xy 91.570376 -404.083459) (xy 91.624324 -404.091219) (xy 91.676618 -404.106577) (xy 91.726195 -404.129221)
			(xy 91.772045 -404.158689) (xy 91.813234 -404.194383) (xy 91.848925 -404.235575) (xy 91.878391 -404.281426)
			(xy 91.901031 -404.331004) (xy 91.916386 -404.3833) (xy 91.924142 -404.437248) (xy 91.924142 -404.491748)
			(xy 93.361798 -404.491748) (xy 93.361798 -404.437252) (xy 93.369553 -404.38331) (xy 93.384906 -404.331021)
			(xy 93.407543 -404.281449) (xy 93.437004 -404.235603) (xy 93.47269 -404.194416) (xy 93.513874 -404.158726)
			(xy 93.559717 -404.12926) (xy 93.609287 -404.106618) (xy 93.661575 -404.091261) (xy 93.715516 -404.083501)
			(xy 93.742764 -404.083012) (xy 94.606364 -404.083012) (xy 94.63362 -404.083432) (xy 94.687578 -404.091186)
			(xy 94.739883 -404.106539) (xy 94.78947 -404.129181) (xy 94.83533 -404.15865) (xy 94.876529 -404.194345)
			(xy 94.912229 -404.235541) (xy 94.941702 -404.281398) (xy 94.964348 -404.330984) (xy 94.979707 -404.383287)
			(xy 94.987465 -404.437244) (xy 94.987465 -404.491752) (xy 114.513075 -404.491752) (xy 114.513075 -404.437248)
			(xy 114.520832 -404.3833) (xy 114.536188 -404.331004) (xy 114.558829 -404.281426) (xy 114.588296 -404.235575)
			(xy 114.623989 -404.194384) (xy 114.66518 -404.158693) (xy 114.711031 -404.129226) (xy 114.76061 -404.106585)
			(xy 114.812906 -404.091231) (xy 114.866854 -404.083475) (xy 114.894106 -404.083012) (xy 115.757706 -404.083012)
			(xy 115.784958 -404.083458) (xy 115.838908 -404.091216) (xy 115.891205 -404.106572) (xy 115.940784 -404.129215)
			(xy 115.986636 -404.158683) (xy 116.027828 -404.194376) (xy 116.063521 -404.235569) (xy 116.092988 -404.281421)
			(xy 116.11563 -404.331001) (xy 116.130985 -404.383298) (xy 116.138742 -404.437248) (xy 116.138742 -404.491752)
			(xy 116.138742 -404.491754) (xy 117.576275 -404.491754) (xy 117.576275 -404.437246) (xy 117.584033 -404.383294)
			(xy 117.599391 -404.330996) (xy 117.622035 -404.281415) (xy 117.651506 -404.235562) (xy 117.687203 -404.19437)
			(xy 117.728399 -404.158679) (xy 117.774255 -404.129213) (xy 117.823839 -404.106575) (xy 117.876139 -404.091223)
			(xy 117.930092 -404.083472) (xy 117.957346 -404.083012) (xy 118.820946 -404.083012) (xy 118.848197 -404.083461)
			(xy 118.902142 -404.091223) (xy 118.954434 -404.106583) (xy 119.004008 -404.129228) (xy 119.049855 -404.158697)
			(xy 119.091042 -404.194391) (xy 119.12673 -404.235582) (xy 119.156194 -404.281432) (xy 119.178833 -404.331009)
			(xy 119.194187 -404.383303) (xy 119.201942 -404.437249) (xy 119.201942 -404.491749) (xy 120.639598 -404.491749)
			(xy 120.639598 -404.437251) (xy 120.647354 -404.383307) (xy 120.662708 -404.331016) (xy 120.685346 -404.281443)
			(xy 120.71481 -404.235596) (xy 120.750498 -404.194408) (xy 120.791684 -404.158718) (xy 120.83753 -404.129253)
			(xy 120.887103 -404.106612) (xy 120.939394 -404.091257) (xy 120.993337 -404.083499) (xy 121.020586 -404.083012)
			(xy 121.884186 -404.083012) (xy 121.911441 -404.083434) (xy 121.965396 -404.09119) (xy 122.017699 -404.106545)
			(xy 122.067283 -404.129188) (xy 122.113141 -404.158657) (xy 122.154337 -404.194353) (xy 122.190034 -404.235548)
			(xy 122.219505 -404.281405) (xy 122.24215 -404.330988) (xy 122.257507 -404.38329) (xy 122.265265 -404.437245)
			(xy 122.265265 -404.491753) (xy 123.702775 -404.491753) (xy 123.702775 -404.437247) (xy 123.710533 -404.383297)
			(xy 123.725889 -404.331) (xy 123.748532 -404.281421) (xy 123.778001 -404.235569) (xy 123.813696 -404.194377)
			(xy 123.854889 -404.158686) (xy 123.900743 -404.12922) (xy 123.950324 -404.10658) (xy 124.002622 -404.091227)
			(xy 124.056573 -404.083474) (xy 124.083826 -404.083012) (xy 124.947426 -404.083012) (xy 124.974677 -404.08346)
			(xy 125.028625 -404.09122) (xy 125.08092 -404.106578) (xy 125.130496 -404.129222) (xy 125.176346 -404.15869)
			(xy 125.217535 -404.194383) (xy 125.253226 -404.235575) (xy 125.282691 -404.281427) (xy 125.305331 -404.331005)
			(xy 125.320686 -404.3833) (xy 125.328442 -404.437249) (xy 125.328442 -404.491748) (xy 126.766098 -404.491748)
			(xy 126.766098 -404.437252) (xy 126.773853 -404.38331) (xy 126.789206 -404.331021) (xy 126.811843 -404.281448)
			(xy 126.841305 -404.235602) (xy 126.876991 -404.194415) (xy 126.918175 -404.158725) (xy 126.964018 -404.12926)
			(xy 127.013589 -404.106618) (xy 127.065877 -404.091261) (xy 127.119818 -404.083501) (xy 127.147066 -404.083012)
			(xy 128.010666 -404.083012) (xy 128.037922 -404.083433) (xy 128.091879 -404.091186) (xy 128.144184 -404.10654)
			(xy 128.193771 -404.129182) (xy 128.239631 -404.15865) (xy 128.28083 -404.194346) (xy 128.316529 -404.235542)
			(xy 128.346002 -404.281399) (xy 128.368648 -404.330984) (xy 128.384007 -404.383287) (xy 128.391765 -404.437244)
			(xy 128.391765 -404.491752) (xy 129.829275 -404.491752) (xy 129.829275 -404.437248) (xy 129.837032 -404.3833)
			(xy 129.852388 -404.331004) (xy 129.875029 -404.281426) (xy 129.904496 -404.235575) (xy 129.940189 -404.194384)
			(xy 129.98138 -404.158693) (xy 130.027231 -404.129226) (xy 130.07681 -404.106585) (xy 130.129106 -404.091231)
			(xy 130.183054 -404.083475) (xy 130.210306 -404.083012) (xy 131.073906 -404.083012) (xy 131.101158 -404.083458)
			(xy 131.155108 -404.091216) (xy 131.207405 -404.106572) (xy 131.256984 -404.129215) (xy 131.302836 -404.158683)
			(xy 131.344028 -404.194376) (xy 131.379721 -404.235569) (xy 131.409188 -404.281421) (xy 131.43183 -404.331001)
			(xy 131.447185 -404.383298) (xy 131.454942 -404.437248) (xy 131.454942 -404.491752) (xy 131.454942 -404.491754)
			(xy 132.892475 -404.491754) (xy 132.892475 -404.437246) (xy 132.900233 -404.383294) (xy 132.915591 -404.330996)
			(xy 132.938235 -404.281415) (xy 132.967706 -404.235562) (xy 133.003403 -404.19437) (xy 133.044599 -404.158679)
			(xy 133.090455 -404.129213) (xy 133.140039 -404.106575) (xy 133.192339 -404.091223) (xy 133.246292 -404.083472)
			(xy 133.273546 -404.083012) (xy 134.137146 -404.083012) (xy 134.164397 -404.083461) (xy 134.218342 -404.091223)
			(xy 134.270634 -404.106583) (xy 134.320208 -404.129228) (xy 134.366055 -404.158697) (xy 134.407242 -404.194391)
			(xy 134.44293 -404.235582) (xy 134.472394 -404.281432) (xy 134.495033 -404.331009) (xy 134.510387 -404.383303)
			(xy 134.518142 -404.437249) (xy 134.518142 -404.491749) (xy 135.955798 -404.491749) (xy 135.955798 -404.437251)
			(xy 135.963554 -404.383307) (xy 135.978908 -404.331016) (xy 136.001546 -404.281443) (xy 136.03101 -404.235596)
			(xy 136.066698 -404.194408) (xy 136.107884 -404.158718) (xy 136.15373 -404.129253) (xy 136.203303 -404.106612)
			(xy 136.255594 -404.091257) (xy 136.309537 -404.083499) (xy 136.336786 -404.083012) (xy 137.200386 -404.083012)
			(xy 137.227641 -404.083434) (xy 137.281596 -404.09119) (xy 137.333899 -404.106545) (xy 137.383483 -404.129188)
			(xy 137.429341 -404.158657) (xy 137.470537 -404.194353) (xy 137.506234 -404.235548) (xy 137.535705 -404.281405)
			(xy 137.55835 -404.330988) (xy 137.573707 -404.38329) (xy 137.581465 -404.437245) (xy 137.581465 -404.491753)
			(xy 139.018975 -404.491753) (xy 139.018975 -404.437247) (xy 139.026733 -404.383297) (xy 139.042089 -404.331)
			(xy 139.064732 -404.281421) (xy 139.094201 -404.235569) (xy 139.129896 -404.194377) (xy 139.171089 -404.158686)
			(xy 139.216943 -404.12922) (xy 139.266524 -404.10658) (xy 139.318822 -404.091227) (xy 139.372773 -404.083474)
			(xy 139.400026 -404.083012) (xy 140.263626 -404.083012) (xy 140.290877 -404.08346) (xy 140.344825 -404.09122)
			(xy 140.39712 -404.106578) (xy 140.446696 -404.129222) (xy 140.492546 -404.15869) (xy 140.533735 -404.194383)
			(xy 140.569426 -404.235575) (xy 140.598891 -404.281427) (xy 140.621531 -404.331005) (xy 140.636886 -404.3833)
			(xy 140.644642 -404.437249) (xy 140.644642 -404.491748) (xy 142.082298 -404.491748) (xy 142.082298 -404.437252)
			(xy 142.090053 -404.38331) (xy 142.105406 -404.331021) (xy 142.128043 -404.281448) (xy 142.157505 -404.235602)
			(xy 142.193191 -404.194415) (xy 142.234375 -404.158725) (xy 142.280218 -404.12926) (xy 142.329789 -404.106618)
			(xy 142.382077 -404.091261) (xy 142.436018 -404.083501) (xy 142.463266 -404.083012) (xy 143.326866 -404.083012)
			(xy 143.354122 -404.083433) (xy 143.408079 -404.091186) (xy 143.460384 -404.10654) (xy 143.509971 -404.129182)
			(xy 143.555831 -404.15865) (xy 143.59703 -404.194346) (xy 143.632729 -404.235542) (xy 143.662202 -404.281399)
			(xy 143.684848 -404.330984) (xy 143.700207 -404.383287) (xy 143.707965 -404.437244) (xy 143.707965 -404.491752)
			(xy 145.145475 -404.491752) (xy 145.145475 -404.437248) (xy 145.153232 -404.3833) (xy 145.168588 -404.331004)
			(xy 145.191229 -404.281426) (xy 145.220696 -404.235575) (xy 145.256389 -404.194384) (xy 145.29758 -404.158693)
			(xy 145.343431 -404.129226) (xy 145.39301 -404.106585) (xy 145.445306 -404.091231) (xy 145.499254 -404.083475)
			(xy 145.526506 -404.083012) (xy 146.390106 -404.083012) (xy 146.417358 -404.083458) (xy 146.471308 -404.091216)
			(xy 146.523605 -404.106572) (xy 146.573184 -404.129215) (xy 146.619036 -404.158683) (xy 146.660228 -404.194376)
			(xy 146.695921 -404.235569) (xy 146.725388 -404.281421) (xy 146.74803 -404.331001) (xy 146.763385 -404.383298)
			(xy 146.771142 -404.437248) (xy 146.771142 -404.491752) (xy 146.771142 -404.491754) (xy 148.208675 -404.491754)
			(xy 148.208675 -404.437246) (xy 148.216433 -404.383294) (xy 148.231791 -404.330996) (xy 148.254435 -404.281415)
			(xy 148.283906 -404.235562) (xy 148.319603 -404.19437) (xy 148.360799 -404.158679) (xy 148.406655 -404.129213)
			(xy 148.456239 -404.106575) (xy 148.508539 -404.091223) (xy 148.562492 -404.083472) (xy 148.589746 -404.083012)
			(xy 149.453346 -404.083012) (xy 149.480597 -404.083461) (xy 149.534542 -404.091223) (xy 149.586834 -404.106583)
			(xy 149.636408 -404.129228) (xy 149.682255 -404.158697) (xy 149.723442 -404.194391) (xy 149.75913 -404.235582)
			(xy 149.788594 -404.281432) (xy 149.811233 -404.331009) (xy 149.826587 -404.383303) (xy 149.834342 -404.437249)
			(xy 149.834342 -404.491749) (xy 151.271998 -404.491749) (xy 151.271998 -404.437251) (xy 151.279754 -404.383307)
			(xy 151.295108 -404.331016) (xy 151.317746 -404.281443) (xy 151.34721 -404.235596) (xy 151.382898 -404.194408)
			(xy 151.424084 -404.158718) (xy 151.46993 -404.129253) (xy 151.519503 -404.106612) (xy 151.571794 -404.091257)
			(xy 151.625737 -404.083499) (xy 151.652986 -404.083012) (xy 152.516586 -404.083012) (xy 152.543841 -404.083434)
			(xy 152.597796 -404.09119) (xy 152.650099 -404.106545) (xy 152.699683 -404.129188) (xy 152.745541 -404.158657)
			(xy 152.786737 -404.194353) (xy 152.822434 -404.235548) (xy 152.851905 -404.281405) (xy 152.87455 -404.330988)
			(xy 152.889907 -404.38329) (xy 152.897665 -404.437245) (xy 152.897665 -404.491753) (xy 154.335175 -404.491753)
			(xy 154.335175 -404.437247) (xy 154.342933 -404.383297) (xy 154.358289 -404.331) (xy 154.380932 -404.281421)
			(xy 154.410401 -404.235569) (xy 154.446096 -404.194377) (xy 154.487289 -404.158686) (xy 154.533143 -404.12922)
			(xy 154.582724 -404.10658) (xy 154.635022 -404.091227) (xy 154.688973 -404.083474) (xy 154.716226 -404.083012)
			(xy 155.579826 -404.083012) (xy 155.607077 -404.08346) (xy 155.661025 -404.09122) (xy 155.71332 -404.106578)
			(xy 155.762896 -404.129222) (xy 155.808746 -404.15869) (xy 155.849935 -404.194383) (xy 155.885626 -404.235575)
			(xy 155.915091 -404.281427) (xy 155.937731 -404.331005) (xy 155.953086 -404.3833) (xy 155.960842 -404.437249)
			(xy 155.960842 -404.491748) (xy 157.398498 -404.491748) (xy 157.398498 -404.437252) (xy 157.406253 -404.38331)
			(xy 157.421606 -404.331021) (xy 157.444243 -404.281448) (xy 157.473705 -404.235602) (xy 157.509391 -404.194415)
			(xy 157.550575 -404.158725) (xy 157.596418 -404.12926) (xy 157.645989 -404.106618) (xy 157.698277 -404.091261)
			(xy 157.752218 -404.083501) (xy 157.779466 -404.083012) (xy 158.643066 -404.083012) (xy 158.670322 -404.083433)
			(xy 158.724279 -404.091186) (xy 158.776584 -404.10654) (xy 158.826171 -404.129182) (xy 158.872031 -404.15865)
			(xy 158.91323 -404.194346) (xy 158.948929 -404.235542) (xy 158.978402 -404.281399) (xy 159.001048 -404.330984)
			(xy 159.016407 -404.383287) (xy 159.024165 -404.437244) (xy 159.024165 -404.491752) (xy 160.461675 -404.491752)
			(xy 160.461675 -404.437248) (xy 160.469432 -404.3833) (xy 160.484788 -404.331004) (xy 160.507429 -404.281426)
			(xy 160.536896 -404.235575) (xy 160.572589 -404.194384) (xy 160.61378 -404.158693) (xy 160.659631 -404.129226)
			(xy 160.70921 -404.106585) (xy 160.761506 -404.091231) (xy 160.815454 -404.083475) (xy 160.842706 -404.083012)
			(xy 161.706306 -404.083012) (xy 161.733558 -404.083458) (xy 161.787508 -404.091216) (xy 161.839805 -404.106572)
			(xy 161.889384 -404.129215) (xy 161.935236 -404.158683) (xy 161.976428 -404.194376) (xy 162.012121 -404.235569)
			(xy 162.041588 -404.281421) (xy 162.06423 -404.331001) (xy 162.079585 -404.383298) (xy 162.087342 -404.437248)
			(xy 162.087342 -404.491752) (xy 162.079585 -404.545702) (xy 162.06423 -404.597999) (xy 162.041588 -404.647579)
			(xy 162.012121 -404.693431) (xy 161.976428 -404.734624) (xy 161.935236 -404.770317) (xy 161.889384 -404.799785)
			(xy 161.839805 -404.822428) (xy 161.787508 -404.837784) (xy 161.733558 -404.845542) (xy 161.706306 -404.846028)
			(xy 160.842706 -404.846028) (xy 160.815454 -404.845525) (xy 160.761506 -404.837769) (xy 160.70921 -404.822415)
			(xy 160.659631 -404.799774) (xy 160.61378 -404.770307) (xy 160.572589 -404.734616) (xy 160.536896 -404.693425)
			(xy 160.507429 -404.647574) (xy 160.484788 -404.597996) (xy 160.469432 -404.5457) (xy 160.461675 -404.491752)
			(xy 159.024165 -404.491752) (xy 159.024165 -404.491756) (xy 159.016407 -404.545713) (xy 159.001048 -404.598016)
			(xy 158.978402 -404.647601) (xy 158.948929 -404.693458) (xy 158.91323 -404.734654) (xy 158.872031 -404.77035)
			(xy 158.826171 -404.799818) (xy 158.776584 -404.82246) (xy 158.724279 -404.837814) (xy 158.670322 -404.845567)
			(xy 158.643066 -404.846028) (xy 157.779466 -404.846028) (xy 157.752218 -404.845499) (xy 157.698277 -404.837739)
			(xy 157.645989 -404.822382) (xy 157.596418 -404.79974) (xy 157.550575 -404.770275) (xy 157.509391 -404.734585)
			(xy 157.473705 -404.693398) (xy 157.444243 -404.647552) (xy 157.421606 -404.597979) (xy 157.406253 -404.54569)
			(xy 157.398498 -404.491748) (xy 155.960842 -404.491748) (xy 155.960842 -404.491751) (xy 155.953086 -404.5457)
			(xy 155.937731 -404.597995) (xy 155.915091 -404.647573) (xy 155.885626 -404.693425) (xy 155.849935 -404.734617)
			(xy 155.808746 -404.77031) (xy 155.762896 -404.799778) (xy 155.71332 -404.822422) (xy 155.661025 -404.83778)
			(xy 155.607077 -404.84554) (xy 155.579826 -404.846028) (xy 154.716226 -404.846028) (xy 154.688973 -404.845526)
			(xy 154.635022 -404.837773) (xy 154.582724 -404.82242) (xy 154.533143 -404.79978) (xy 154.487289 -404.770314)
			(xy 154.446096 -404.734623) (xy 154.410401 -404.693431) (xy 154.380932 -404.647579) (xy 154.358289 -404.598)
			(xy 154.342933 -404.545703) (xy 154.335175 -404.491753) (xy 152.897665 -404.491753) (xy 152.897665 -404.491755)
			(xy 152.889907 -404.54571) (xy 152.87455 -404.598012) (xy 152.851905 -404.647595) (xy 152.822434 -404.693452)
			(xy 152.786737 -404.734647) (xy 152.745541 -404.770343) (xy 152.699683 -404.799812) (xy 152.650099 -404.822455)
			(xy 152.597796 -404.83781) (xy 152.543841 -404.845566) (xy 152.516586 -404.846028) (xy 151.652986 -404.846028)
			(xy 151.625737 -404.845501) (xy 151.571794 -404.837743) (xy 151.519503 -404.822388) (xy 151.46993 -404.799747)
			(xy 151.424084 -404.770282) (xy 151.382898 -404.734592) (xy 151.34721 -404.693404) (xy 151.317746 -404.647557)
			(xy 151.295108 -404.597984) (xy 151.279754 -404.545693) (xy 151.271998 -404.491749) (xy 149.834342 -404.491749)
			(xy 149.834342 -404.491751) (xy 149.826587 -404.545697) (xy 149.811233 -404.597991) (xy 149.788594 -404.647568)
			(xy 149.75913 -404.693418) (xy 149.723442 -404.734609) (xy 149.682255 -404.770303) (xy 149.636408 -404.799772)
			(xy 149.586834 -404.822417) (xy 149.534542 -404.837777) (xy 149.480597 -404.845539) (xy 149.453346 -404.846028)
			(xy 148.589746 -404.846028) (xy 148.562492 -404.845528) (xy 148.508539 -404.837777) (xy 148.456239 -404.822425)
			(xy 148.406655 -404.799787) (xy 148.360799 -404.770321) (xy 148.319603 -404.73463) (xy 148.283906 -404.693438)
			(xy 148.254435 -404.647585) (xy 148.231791 -404.598004) (xy 148.216433 -404.545706) (xy 148.208675 -404.491754)
			(xy 146.771142 -404.491754) (xy 146.763385 -404.545702) (xy 146.74803 -404.597999) (xy 146.725388 -404.647579)
			(xy 146.695921 -404.693431) (xy 146.660228 -404.734624) (xy 146.619036 -404.770317) (xy 146.573184 -404.799785)
			(xy 146.523605 -404.822428) (xy 146.471308 -404.837784) (xy 146.417358 -404.845542) (xy 146.390106 -404.846028)
			(xy 145.526506 -404.846028) (xy 145.499254 -404.845525) (xy 145.445306 -404.837769) (xy 145.39301 -404.822415)
			(xy 145.343431 -404.799774) (xy 145.29758 -404.770307) (xy 145.256389 -404.734616) (xy 145.220696 -404.693425)
			(xy 145.191229 -404.647574) (xy 145.168588 -404.597996) (xy 145.153232 -404.5457) (xy 145.145475 -404.491752)
			(xy 143.707965 -404.491752) (xy 143.707965 -404.491756) (xy 143.700207 -404.545713) (xy 143.684848 -404.598016)
			(xy 143.662202 -404.647601) (xy 143.632729 -404.693458) (xy 143.59703 -404.734654) (xy 143.555831 -404.77035)
			(xy 143.509971 -404.799818) (xy 143.460384 -404.82246) (xy 143.408079 -404.837814) (xy 143.354122 -404.845567)
			(xy 143.326866 -404.846028) (xy 142.463266 -404.846028) (xy 142.436018 -404.845499) (xy 142.382077 -404.837739)
			(xy 142.329789 -404.822382) (xy 142.280218 -404.79974) (xy 142.234375 -404.770275) (xy 142.193191 -404.734585)
			(xy 142.157505 -404.693398) (xy 142.128043 -404.647552) (xy 142.105406 -404.597979) (xy 142.090053 -404.54569)
			(xy 142.082298 -404.491748) (xy 140.644642 -404.491748) (xy 140.644642 -404.491751) (xy 140.636886 -404.5457)
			(xy 140.621531 -404.597995) (xy 140.598891 -404.647573) (xy 140.569426 -404.693425) (xy 140.533735 -404.734617)
			(xy 140.492546 -404.77031) (xy 140.446696 -404.799778) (xy 140.39712 -404.822422) (xy 140.344825 -404.83778)
			(xy 140.290877 -404.84554) (xy 140.263626 -404.846028) (xy 139.400026 -404.846028) (xy 139.372773 -404.845526)
			(xy 139.318822 -404.837773) (xy 139.266524 -404.82242) (xy 139.216943 -404.79978) (xy 139.171089 -404.770314)
			(xy 139.129896 -404.734623) (xy 139.094201 -404.693431) (xy 139.064732 -404.647579) (xy 139.042089 -404.598)
			(xy 139.026733 -404.545703) (xy 139.018975 -404.491753) (xy 137.581465 -404.491753) (xy 137.581465 -404.491755)
			(xy 137.573707 -404.54571) (xy 137.55835 -404.598012) (xy 137.535705 -404.647595) (xy 137.506234 -404.693452)
			(xy 137.470537 -404.734647) (xy 137.429341 -404.770343) (xy 137.383483 -404.799812) (xy 137.333899 -404.822455)
			(xy 137.281596 -404.83781) (xy 137.227641 -404.845566) (xy 137.200386 -404.846028) (xy 136.336786 -404.846028)
			(xy 136.309537 -404.845501) (xy 136.255594 -404.837743) (xy 136.203303 -404.822388) (xy 136.15373 -404.799747)
			(xy 136.107884 -404.770282) (xy 136.066698 -404.734592) (xy 136.03101 -404.693404) (xy 136.001546 -404.647557)
			(xy 135.978908 -404.597984) (xy 135.963554 -404.545693) (xy 135.955798 -404.491749) (xy 134.518142 -404.491749)
			(xy 134.518142 -404.491751) (xy 134.510387 -404.545697) (xy 134.495033 -404.597991) (xy 134.472394 -404.647568)
			(xy 134.44293 -404.693418) (xy 134.407242 -404.734609) (xy 134.366055 -404.770303) (xy 134.320208 -404.799772)
			(xy 134.270634 -404.822417) (xy 134.218342 -404.837777) (xy 134.164397 -404.845539) (xy 134.137146 -404.846028)
			(xy 133.273546 -404.846028) (xy 133.246292 -404.845528) (xy 133.192339 -404.837777) (xy 133.140039 -404.822425)
			(xy 133.090455 -404.799787) (xy 133.044599 -404.770321) (xy 133.003403 -404.73463) (xy 132.967706 -404.693438)
			(xy 132.938235 -404.647585) (xy 132.915591 -404.598004) (xy 132.900233 -404.545706) (xy 132.892475 -404.491754)
			(xy 131.454942 -404.491754) (xy 131.447185 -404.545702) (xy 131.43183 -404.597999) (xy 131.409188 -404.647579)
			(xy 131.379721 -404.693431) (xy 131.344028 -404.734624) (xy 131.302836 -404.770317) (xy 131.256984 -404.799785)
			(xy 131.207405 -404.822428) (xy 131.155108 -404.837784) (xy 131.101158 -404.845542) (xy 131.073906 -404.846028)
			(xy 130.210306 -404.846028) (xy 130.183054 -404.845525) (xy 130.129106 -404.837769) (xy 130.07681 -404.822415)
			(xy 130.027231 -404.799774) (xy 129.98138 -404.770307) (xy 129.940189 -404.734616) (xy 129.904496 -404.693425)
			(xy 129.875029 -404.647574) (xy 129.852388 -404.597996) (xy 129.837032 -404.5457) (xy 129.829275 -404.491752)
			(xy 128.391765 -404.491752) (xy 128.391765 -404.491756) (xy 128.384007 -404.545713) (xy 128.368648 -404.598016)
			(xy 128.346002 -404.647601) (xy 128.316529 -404.693458) (xy 128.28083 -404.734654) (xy 128.239631 -404.77035)
			(xy 128.193771 -404.799818) (xy 128.144184 -404.82246) (xy 128.091879 -404.837814) (xy 128.037922 -404.845567)
			(xy 128.010666 -404.846028) (xy 127.147066 -404.846028) (xy 127.119818 -404.845499) (xy 127.065877 -404.837739)
			(xy 127.013589 -404.822382) (xy 126.964018 -404.79974) (xy 126.918175 -404.770275) (xy 126.876991 -404.734585)
			(xy 126.841305 -404.693398) (xy 126.811843 -404.647552) (xy 126.789206 -404.597979) (xy 126.773853 -404.54569)
			(xy 126.766098 -404.491748) (xy 125.328442 -404.491748) (xy 125.328442 -404.491751) (xy 125.320686 -404.5457)
			(xy 125.305331 -404.597995) (xy 125.282691 -404.647573) (xy 125.253226 -404.693425) (xy 125.217535 -404.734617)
			(xy 125.176346 -404.77031) (xy 125.130496 -404.799778) (xy 125.08092 -404.822422) (xy 125.028625 -404.83778)
			(xy 124.974677 -404.84554) (xy 124.947426 -404.846028) (xy 124.083826 -404.846028) (xy 124.056573 -404.845526)
			(xy 124.002622 -404.837773) (xy 123.950324 -404.82242) (xy 123.900743 -404.79978) (xy 123.854889 -404.770314)
			(xy 123.813696 -404.734623) (xy 123.778001 -404.693431) (xy 123.748532 -404.647579) (xy 123.725889 -404.598)
			(xy 123.710533 -404.545703) (xy 123.702775 -404.491753) (xy 122.265265 -404.491753) (xy 122.265265 -404.491755)
			(xy 122.257507 -404.54571) (xy 122.24215 -404.598012) (xy 122.219505 -404.647595) (xy 122.190034 -404.693452)
			(xy 122.154337 -404.734647) (xy 122.113141 -404.770343) (xy 122.067283 -404.799812) (xy 122.017699 -404.822455)
			(xy 121.965396 -404.83781) (xy 121.911441 -404.845566) (xy 121.884186 -404.846028) (xy 121.020586 -404.846028)
			(xy 120.993337 -404.845501) (xy 120.939394 -404.837743) (xy 120.887103 -404.822388) (xy 120.83753 -404.799747)
			(xy 120.791684 -404.770282) (xy 120.750498 -404.734592) (xy 120.71481 -404.693404) (xy 120.685346 -404.647557)
			(xy 120.662708 -404.597984) (xy 120.647354 -404.545693) (xy 120.639598 -404.491749) (xy 119.201942 -404.491749)
			(xy 119.201942 -404.491751) (xy 119.194187 -404.545697) (xy 119.178833 -404.597991) (xy 119.156194 -404.647568)
			(xy 119.12673 -404.693418) (xy 119.091042 -404.734609) (xy 119.049855 -404.770303) (xy 119.004008 -404.799772)
			(xy 118.954434 -404.822417) (xy 118.902142 -404.837777) (xy 118.848197 -404.845539) (xy 118.820946 -404.846028)
			(xy 117.957346 -404.846028) (xy 117.930092 -404.845528) (xy 117.876139 -404.837777) (xy 117.823839 -404.822425)
			(xy 117.774255 -404.799787) (xy 117.728399 -404.770321) (xy 117.687203 -404.73463) (xy 117.651506 -404.693438)
			(xy 117.622035 -404.647585) (xy 117.599391 -404.598004) (xy 117.584033 -404.545706) (xy 117.576275 -404.491754)
			(xy 116.138742 -404.491754) (xy 116.130985 -404.545702) (xy 116.11563 -404.597999) (xy 116.092988 -404.647579)
			(xy 116.063521 -404.693431) (xy 116.027828 -404.734624) (xy 115.986636 -404.770317) (xy 115.940784 -404.799785)
			(xy 115.891205 -404.822428) (xy 115.838908 -404.837784) (xy 115.784958 -404.845542) (xy 115.757706 -404.846028)
			(xy 114.894106 -404.846028) (xy 114.866854 -404.845525) (xy 114.812906 -404.837769) (xy 114.76061 -404.822415)
			(xy 114.711031 -404.799774) (xy 114.66518 -404.770307) (xy 114.623989 -404.734616) (xy 114.588296 -404.693425)
			(xy 114.558829 -404.647574) (xy 114.536188 -404.597996) (xy 114.520832 -404.5457) (xy 114.513075 -404.491752)
			(xy 94.987465 -404.491752) (xy 94.987465 -404.491756) (xy 94.979707 -404.545713) (xy 94.964348 -404.598016)
			(xy 94.941702 -404.647602) (xy 94.912229 -404.693459) (xy 94.876529 -404.734655) (xy 94.83533 -404.77035)
			(xy 94.78947 -404.799819) (xy 94.739883 -404.822461) (xy 94.687578 -404.837814) (xy 94.63362 -404.845568)
			(xy 94.606364 -404.846028) (xy 93.742764 -404.846028) (xy 93.715516 -404.845499) (xy 93.661575 -404.837739)
			(xy 93.609287 -404.822382) (xy 93.559717 -404.79974) (xy 93.513874 -404.770274) (xy 93.47269 -404.734584)
			(xy 93.437004 -404.693397) (xy 93.407543 -404.647551) (xy 93.384906 -404.597979) (xy 93.369553 -404.54569)
			(xy 93.361798 -404.491748) (xy 91.924142 -404.491748) (xy 91.924142 -404.491752) (xy 91.916386 -404.5457)
			(xy 91.901031 -404.597996) (xy 91.878391 -404.647574) (xy 91.848925 -404.693425) (xy 91.813234 -404.734617)
			(xy 91.772045 -404.770311) (xy 91.726195 -404.799779) (xy 91.676618 -404.822423) (xy 91.624324 -404.837781)
			(xy 91.570376 -404.845541) (xy 91.543124 -404.846028) (xy 90.679524 -404.846028) (xy 90.652271 -404.845526)
			(xy 90.598321 -404.837773) (xy 90.546023 -404.822419) (xy 90.496442 -404.799779) (xy 90.450588 -404.770314)
			(xy 90.409395 -404.734622) (xy 90.373701 -404.693431) (xy 90.344232 -404.647579) (xy 90.321589 -404.598)
			(xy 90.306233 -404.545703) (xy 90.298475 -404.491753) (xy 88.860965 -404.491753) (xy 88.860965 -404.491755)
			(xy 88.853207 -404.54571) (xy 88.83785 -404.598012) (xy 88.815205 -404.647596) (xy 88.785734 -404.693452)
			(xy 88.750036 -404.734648) (xy 88.70884 -404.770343) (xy 88.662982 -404.799812) (xy 88.613397 -404.822455)
			(xy 88.561095 -404.837811) (xy 88.507139 -404.845566) (xy 88.479884 -404.846028) (xy 87.616284 -404.846028)
			(xy 87.589035 -404.845501) (xy 87.535092 -404.837743) (xy 87.482802 -404.822387) (xy 87.433229 -404.799746)
			(xy 87.387383 -404.770281) (xy 87.346197 -404.734591) (xy 87.310509 -404.693404) (xy 87.281046 -404.647557)
			(xy 87.258407 -404.597983) (xy 87.243054 -404.545692) (xy 87.235298 -404.491749) (xy 85.797642 -404.491749)
			(xy 85.797642 -404.491751) (xy 85.789887 -404.545697) (xy 85.774533 -404.597991) (xy 85.751894 -404.647568)
			(xy 85.72243 -404.693419) (xy 85.686741 -404.73461) (xy 85.645554 -404.770304) (xy 85.599707 -404.799773)
			(xy 85.550133 -404.822417) (xy 85.49784 -404.837777) (xy 85.443895 -404.845539) (xy 85.416644 -404.846028)
			(xy 84.553044 -404.846028) (xy 84.525791 -404.845528) (xy 84.471838 -404.837776) (xy 84.419537 -404.822425)
			(xy 84.369954 -404.799786) (xy 84.324098 -404.770321) (xy 84.282902 -404.734629) (xy 84.247206 -404.693437)
			(xy 84.217735 -404.647584) (xy 84.195091 -404.598004) (xy 84.179733 -404.545705) (xy 84.171975 -404.491753)
			(xy 82.734442 -404.491753) (xy 82.726685 -404.545703) (xy 82.71133 -404.598) (xy 82.688688 -404.647579)
			(xy 82.65922 -404.693432) (xy 82.623527 -404.734624) (xy 82.582335 -404.770318) (xy 82.536483 -404.799786)
			(xy 82.486904 -404.822428) (xy 82.434607 -404.837785) (xy 82.380656 -404.845542) (xy 82.353404 -404.846028)
			(xy 81.489804 -404.846028) (xy 81.462552 -404.845525) (xy 81.408604 -404.837769) (xy 81.356308 -404.822414)
			(xy 81.30673 -404.799773) (xy 81.260879 -404.770307) (xy 81.219688 -404.734615) (xy 81.183996 -404.693424)
			(xy 81.154529 -404.647573) (xy 81.131887 -404.597995) (xy 81.116532 -404.5457) (xy 81.108775 -404.491752)
			(xy 79.671265 -404.491752) (xy 79.671265 -404.491756) (xy 79.663507 -404.545713) (xy 79.648148 -404.598016)
			(xy 79.625502 -404.647602) (xy 79.596029 -404.693459) (xy 79.560329 -404.734655) (xy 79.51913 -404.77035)
			(xy 79.47327 -404.799819) (xy 79.423683 -404.822461) (xy 79.371378 -404.837814) (xy 79.31742 -404.845568)
			(xy 79.290164 -404.846028) (xy 78.426564 -404.846028) (xy 78.399316 -404.845499) (xy 78.345375 -404.837739)
			(xy 78.293087 -404.822382) (xy 78.243517 -404.79974) (xy 78.197674 -404.770274) (xy 78.15649 -404.734584)
			(xy 78.120804 -404.693397) (xy 78.091343 -404.647551) (xy 78.068706 -404.597979) (xy 78.053353 -404.54569)
			(xy 78.045598 -404.491748) (xy 76.607942 -404.491748) (xy 76.607942 -404.491752) (xy 76.600186 -404.5457)
			(xy 76.584831 -404.597996) (xy 76.562191 -404.647574) (xy 76.532725 -404.693425) (xy 76.497034 -404.734617)
			(xy 76.455845 -404.770311) (xy 76.409995 -404.799779) (xy 76.360418 -404.822423) (xy 76.308124 -404.837781)
			(xy 76.254176 -404.845541) (xy 76.226924 -404.846028) (xy 75.363324 -404.846028) (xy 75.336071 -404.845526)
			(xy 75.282121 -404.837773) (xy 75.229823 -404.822419) (xy 75.180242 -404.799779) (xy 75.134388 -404.770314)
			(xy 75.093195 -404.734622) (xy 75.057501 -404.693431) (xy 75.028032 -404.647579) (xy 75.005389 -404.598)
			(xy 74.990033 -404.545703) (xy 74.982275 -404.491753) (xy 73.544765 -404.491753) (xy 73.544765 -404.491755)
			(xy 73.537007 -404.54571) (xy 73.52165 -404.598012) (xy 73.499005 -404.647596) (xy 73.469534 -404.693452)
			(xy 73.433836 -404.734648) (xy 73.39264 -404.770343) (xy 73.346782 -404.799812) (xy 73.297197 -404.822455)
			(xy 73.244895 -404.837811) (xy 73.190939 -404.845566) (xy 73.163684 -404.846028) (xy 72.300084 -404.846028)
			(xy 72.272835 -404.845501) (xy 72.218892 -404.837743) (xy 72.166602 -404.822387) (xy 72.117029 -404.799746)
			(xy 72.071183 -404.770281) (xy 72.029997 -404.734591) (xy 71.994309 -404.693404) (xy 71.964846 -404.647557)
			(xy 71.942207 -404.597983) (xy 71.926854 -404.545692) (xy 71.919098 -404.491749) (xy 70.481442 -404.491749)
			(xy 70.481442 -404.491751) (xy 70.473687 -404.545697) (xy 70.458333 -404.597991) (xy 70.435694 -404.647568)
			(xy 70.40623 -404.693419) (xy 70.370541 -404.73461) (xy 70.329354 -404.770304) (xy 70.283507 -404.799773)
			(xy 70.233933 -404.822417) (xy 70.18164 -404.837777) (xy 70.127695 -404.845539) (xy 70.100444 -404.846028)
			(xy 69.236844 -404.846028) (xy 69.209591 -404.845528) (xy 69.155638 -404.837776) (xy 69.103337 -404.822425)
			(xy 69.053754 -404.799786) (xy 69.007898 -404.770321) (xy 68.966702 -404.734629) (xy 68.931006 -404.693437)
			(xy 68.901535 -404.647584) (xy 68.878891 -404.598004) (xy 68.863533 -404.545705) (xy 68.855775 -404.491753)
			(xy 67.418242 -404.491753) (xy 67.410485 -404.545703) (xy 67.39513 -404.598) (xy 67.372488 -404.647579)
			(xy 67.34302 -404.693432) (xy 67.307327 -404.734624) (xy 67.266135 -404.770318) (xy 67.220283 -404.799786)
			(xy 67.170704 -404.822428) (xy 67.118407 -404.837785) (xy 67.064456 -404.845542) (xy 67.037204 -404.846028)
			(xy 66.173604 -404.846028) (xy 66.146352 -404.845525) (xy 66.092404 -404.837769) (xy 66.040108 -404.822414)
			(xy 65.99053 -404.799773) (xy 65.944679 -404.770307) (xy 65.903488 -404.734615) (xy 65.867796 -404.693424)
			(xy 65.838329 -404.647573) (xy 65.815687 -404.597995) (xy 65.800332 -404.5457) (xy 65.792575 -404.491752)
			(xy 64.355065 -404.491752) (xy 64.355065 -404.491756) (xy 64.347307 -404.545713) (xy 64.331948 -404.598016)
			(xy 64.309302 -404.647602) (xy 64.279829 -404.693459) (xy 64.244129 -404.734655) (xy 64.20293 -404.77035)
			(xy 64.15707 -404.799819) (xy 64.107483 -404.822461) (xy 64.055178 -404.837814) (xy 64.00122 -404.845568)
			(xy 63.973964 -404.846028) (xy 63.110364 -404.846028) (xy 63.083116 -404.845499) (xy 63.029175 -404.837739)
			(xy 62.976887 -404.822382) (xy 62.927317 -404.79974) (xy 62.881474 -404.770274) (xy 62.84029 -404.734584)
			(xy 62.804604 -404.693397) (xy 62.775143 -404.647551) (xy 62.752506 -404.597979) (xy 62.737153 -404.54569)
			(xy 62.729398 -404.491748) (xy 61.291742 -404.491748) (xy 61.291742 -404.491752) (xy 61.283986 -404.5457)
			(xy 61.268631 -404.597996) (xy 61.245991 -404.647574) (xy 61.216525 -404.693425) (xy 61.180834 -404.734617)
			(xy 61.139645 -404.770311) (xy 61.093795 -404.799779) (xy 61.044218 -404.822423) (xy 60.991924 -404.837781)
			(xy 60.937976 -404.845541) (xy 60.910724 -404.846028) (xy 60.047124 -404.846028) (xy 60.019871 -404.845526)
			(xy 59.965921 -404.837773) (xy 59.913623 -404.822419) (xy 59.864042 -404.799779) (xy 59.818188 -404.770314)
			(xy 59.776995 -404.734622) (xy 59.741301 -404.693431) (xy 59.711832 -404.647579) (xy 59.689189 -404.598)
			(xy 59.673833 -404.545703) (xy 59.666075 -404.491753) (xy 58.228565 -404.491753) (xy 58.228565 -404.491755)
			(xy 58.220807 -404.54571) (xy 58.20545 -404.598012) (xy 58.182805 -404.647596) (xy 58.153334 -404.693452)
			(xy 58.117636 -404.734648) (xy 58.07644 -404.770343) (xy 58.030582 -404.799812) (xy 57.980997 -404.822455)
			(xy 57.928695 -404.837811) (xy 57.874739 -404.845566) (xy 57.847484 -404.846028) (xy 56.983884 -404.846028)
			(xy 56.956635 -404.845501) (xy 56.902692 -404.837743) (xy 56.850402 -404.822387) (xy 56.800829 -404.799746)
			(xy 56.754983 -404.770281) (xy 56.713797 -404.734591) (xy 56.678109 -404.693404) (xy 56.648646 -404.647557)
			(xy 56.626007 -404.597983) (xy 56.610654 -404.545692) (xy 56.602898 -404.491749) (xy 55.165242 -404.491749)
			(xy 55.165242 -404.491751) (xy 55.157487 -404.545697) (xy 55.142133 -404.597991) (xy 55.119494 -404.647568)
			(xy 55.09003 -404.693419) (xy 55.054341 -404.73461) (xy 55.013154 -404.770304) (xy 54.967307 -404.799773)
			(xy 54.917733 -404.822417) (xy 54.86544 -404.837777) (xy 54.811495 -404.845539) (xy 54.784244 -404.846028)
			(xy 53.920644 -404.846028) (xy 53.893391 -404.845528) (xy 53.839438 -404.837776) (xy 53.787137 -404.822425)
			(xy 53.737554 -404.799786) (xy 53.691698 -404.770321) (xy 53.650502 -404.734629) (xy 53.614806 -404.693437)
			(xy 53.585335 -404.647584) (xy 53.562691 -404.598004) (xy 53.547333 -404.545705) (xy 53.539575 -404.491753)
			(xy 52.102042 -404.491753) (xy 52.094285 -404.545703) (xy 52.07893 -404.598) (xy 52.056288 -404.647579)
			(xy 52.02682 -404.693432) (xy 51.991127 -404.734624) (xy 51.949935 -404.770318) (xy 51.904083 -404.799786)
			(xy 51.854504 -404.822428) (xy 51.802207 -404.837785) (xy 51.748256 -404.845542) (xy 51.721004 -404.846028)
			(xy 50.857404 -404.846028) (xy 50.830152 -404.845525) (xy 50.776204 -404.837769) (xy 50.723908 -404.822414)
			(xy 50.67433 -404.799773) (xy 50.628479 -404.770307) (xy 50.587288 -404.734615) (xy 50.551596 -404.693424)
			(xy 50.522129 -404.647573) (xy 50.499487 -404.597995) (xy 50.484132 -404.5457) (xy 50.476375 -404.491752)
			(xy 49.038865 -404.491752) (xy 49.038865 -404.491756) (xy 49.031107 -404.545713) (xy 49.015748 -404.598016)
			(xy 48.993102 -404.647602) (xy 48.963629 -404.693459) (xy 48.927929 -404.734655) (xy 48.88673 -404.77035)
			(xy 48.84087 -404.799819) (xy 48.791283 -404.822461) (xy 48.738978 -404.837814) (xy 48.68502 -404.845568)
			(xy 48.657764 -404.846028) (xy 47.794164 -404.846028) (xy 47.766916 -404.845499) (xy 47.712975 -404.837739)
			(xy 47.660687 -404.822382) (xy 47.611117 -404.79974) (xy 47.565274 -404.770274) (xy 47.52409 -404.734584)
			(xy 47.488404 -404.693397) (xy 47.458943 -404.647551) (xy 47.436306 -404.597979) (xy 47.420953 -404.54569)
			(xy 47.413198 -404.491748) (xy 45.875438 -404.491748) (xy 45.877367 -404.514108) (xy 45.885362 -404.699771)
			(xy 45.885862 -404.792688) (xy 45.885362 -404.885605) (xy 45.877367 -405.071268) (xy 45.861392 -405.256414)
			(xy 45.837466 -405.440702) (xy 45.805634 -405.62379) (xy 45.802444 -405.638385) (xy 104.009796 -405.638385)
			(xy 104.013672 -405.584006) (xy 104.025246 -405.530732) (xy 104.044281 -405.479646) (xy 104.070391 -405.431789)
			(xy 104.103044 -405.388132) (xy 104.121966 -405.368506) (xy 104.732582 -404.757636) (xy 104.75423 -404.736857)
			(xy 104.802784 -404.701606) (xy 104.856253 -404.67438) (xy 104.91332 -404.655848) (xy 104.972583 -404.646465)
			(xy 105.002584 -404.645876) (xy 105.029856 -404.646316) (xy 105.083846 -404.654077) (xy 105.136181 -404.669444)
			(xy 105.185797 -404.692102) (xy 105.231683 -404.721592) (xy 105.272904 -404.757312) (xy 105.308622 -404.798535)
			(xy 105.338108 -404.844422) (xy 105.360764 -404.894039) (xy 105.376127 -404.946376) (xy 105.383885 -405.000366)
			(xy 105.384346 -405.027638) (xy 105.383744 -405.057639) (xy 105.374371 -405.116904) (xy 105.355845 -405.173974)
			(xy 105.328623 -405.227445) (xy 105.29971 -405.267273) (xy 106.824184 -405.267273) (xy 106.824184 -405.212727)
			(xy 106.831947 -405.158735) (xy 106.847315 -405.106398) (xy 106.869976 -405.05678) (xy 106.899467 -405.010893)
			(xy 106.935189 -404.969671) (xy 106.976414 -404.933951) (xy 107.022303 -404.904463) (xy 107.071922 -404.881806)
			(xy 107.12426 -404.866441) (xy 107.178252 -404.858682) (xy 107.205526 -404.85822) (xy 108.069126 -404.85822)
			(xy 108.096393 -404.858744) (xy 108.150371 -404.866508) (xy 108.202695 -404.881875) (xy 108.2523 -404.904532)
			(xy 108.298175 -404.934017) (xy 108.339388 -404.969731) (xy 108.375098 -405.010946) (xy 108.404581 -405.056823)
			(xy 108.427234 -405.106429) (xy 108.442597 -405.158754) (xy 108.450358 -405.212733) (xy 108.450358 -405.267267)
			(xy 108.442597 -405.321246) (xy 108.427234 -405.373571) (xy 108.404581 -405.423177) (xy 108.375098 -405.469054)
			(xy 108.339388 -405.510269) (xy 108.298175 -405.545983) (xy 108.2523 -405.575468) (xy 108.202695 -405.598125)
			(xy 108.150371 -405.613492) (xy 108.096393 -405.621256) (xy 108.069126 -405.621744) (xy 107.205526 -405.621744)
			(xy 107.178252 -405.621318) (xy 107.12426 -405.613559) (xy 107.071922 -405.598194) (xy 107.022303 -405.575537)
			(xy 106.976414 -405.546049) (xy 106.935189 -405.510329) (xy 106.899467 -405.469107) (xy 106.869976 -405.42322)
			(xy 106.847315 -405.373602) (xy 106.831947 -405.321265) (xy 106.824184 -405.267273) (xy 105.29971 -405.267273)
			(xy 105.293374 -405.276001) (xy 105.272586 -405.29764) (xy 104.661716 -405.908256) (xy 104.642167 -405.927256)
			(xy 104.598511 -405.959909) (xy 104.550654 -405.986019) (xy 104.499568 -406.005054) (xy 104.446294 -406.016628)
			(xy 104.391915 -406.020504) (xy 104.337538 -406.016603) (xy 104.284269 -406.005006) (xy 104.233192 -405.985949)
			(xy 104.185346 -405.959818) (xy 104.141704 -405.927145) (xy 104.103155 -405.888596) (xy 104.070482 -405.844954)
			(xy 104.044351 -405.797108) (xy 104.025294 -405.746031) (xy 104.013697 -405.692762) (xy 104.009796 -405.638385)
			(xy 45.802444 -405.638385) (xy 45.765954 -405.805339) (xy 45.718501 -405.985013) (xy 45.663361 -406.162479)
			(xy 45.600638 -406.337408) (xy 45.530447 -406.509477) (xy 45.452918 -406.678366) (xy 45.368195 -406.843764)
			(xy 45.276434 -407.005364) (xy 45.259912 -407.031749) (xy 48.944798 -407.031749) (xy 48.944798 -406.977251)
			(xy 48.952554 -406.923308) (xy 48.967907 -406.871017) (xy 48.990546 -406.821443) (xy 49.020009 -406.775596)
			(xy 49.055697 -406.734409) (xy 49.096883 -406.698719) (xy 49.142729 -406.669254) (xy 49.192302 -406.646613)
			(xy 49.244592 -406.631257) (xy 49.298535 -406.623499) (xy 49.325784 -406.623012) (xy 50.189384 -406.623012)
			(xy 50.216639 -406.623434) (xy 50.270595 -406.631189) (xy 50.322897 -406.646545) (xy 50.372482 -406.669188)
			(xy 50.41834 -406.698657) (xy 50.459536 -406.734352) (xy 50.495234 -406.775548) (xy 50.524705 -406.821404)
			(xy 50.54735 -406.870988) (xy 50.562707 -406.92329) (xy 50.570465 -406.977245) (xy 50.570465 -407.031753)
			(xy 52.007975 -407.031753) (xy 52.007975 -406.977247) (xy 52.015733 -406.923297) (xy 52.031089 -406.871)
			(xy 52.053732 -406.821421) (xy 52.083201 -406.775569) (xy 52.118895 -406.734378) (xy 52.160088 -406.698686)
			(xy 52.205942 -406.669221) (xy 52.255523 -406.646581) (xy 52.307821 -406.631227) (xy 52.361771 -406.623474)
			(xy 52.389024 -406.623012) (xy 53.252624 -406.623012) (xy 53.279876 -406.623459) (xy 53.333824 -406.631219)
			(xy 53.386118 -406.646577) (xy 53.435695 -406.669221) (xy 53.481545 -406.698689) (xy 53.522734 -406.734383)
			(xy 53.558425 -406.775575) (xy 53.587891 -406.821426) (xy 53.610531 -406.871004) (xy 53.625886 -406.9233)
			(xy 53.633642 -406.977248) (xy 53.633642 -407.031748) (xy 55.071298 -407.031748) (xy 55.071298 -406.977252)
			(xy 55.079053 -406.92331) (xy 55.094406 -406.871021) (xy 55.117043 -406.821449) (xy 55.146504 -406.775603)
			(xy 55.18219 -406.734416) (xy 55.223374 -406.698726) (xy 55.269217 -406.66926) (xy 55.318787 -406.646618)
			(xy 55.371075 -406.631261) (xy 55.425016 -406.623501) (xy 55.452264 -406.623012) (xy 56.315864 -406.623012)
			(xy 56.34312 -406.623432) (xy 56.397078 -406.631186) (xy 56.449383 -406.646539) (xy 56.49897 -406.669181)
			(xy 56.54483 -406.69865) (xy 56.586029 -406.734345) (xy 56.621729 -406.775541) (xy 56.651202 -406.821398)
			(xy 56.673848 -406.870984) (xy 56.689207 -406.923287) (xy 56.696965 -406.977244) (xy 56.696965 -407.031752)
			(xy 58.134475 -407.031752) (xy 58.134475 -406.977248) (xy 58.142232 -406.9233) (xy 58.157587 -406.871005)
			(xy 58.180229 -406.821427) (xy 58.209696 -406.775576) (xy 58.245388 -406.734385) (xy 58.286579 -406.698693)
			(xy 58.33243 -406.669227) (xy 58.382008 -406.646586) (xy 58.434304 -406.631231) (xy 58.488252 -406.623475)
			(xy 58.515504 -406.623012) (xy 59.379104 -406.623012) (xy 59.406356 -406.623458) (xy 59.460307 -406.631215)
			(xy 59.512604 -406.646572) (xy 59.562183 -406.669214) (xy 59.608035 -406.698682) (xy 59.649227 -406.734376)
			(xy 59.68492 -406.775568) (xy 59.714388 -406.821421) (xy 59.73703 -406.871) (xy 59.752385 -406.923297)
			(xy 59.760142 -406.977248) (xy 59.760142 -407.031752) (xy 59.760142 -407.031753) (xy 61.197675 -407.031753)
			(xy 61.197675 -406.977247) (xy 61.205433 -406.923295) (xy 61.220791 -406.870996) (xy 61.243435 -406.821416)
			(xy 61.272906 -406.775563) (xy 61.308602 -406.734371) (xy 61.349798 -406.698679) (xy 61.395654 -406.669214)
			(xy 61.445237 -406.646575) (xy 61.497538 -406.631224) (xy 61.551491 -406.623472) (xy 61.578744 -406.623012)
			(xy 62.442344 -406.623012) (xy 62.469595 -406.623461) (xy 62.52354 -406.631223) (xy 62.575833 -406.646583)
			(xy 62.625407 -406.669227) (xy 62.671254 -406.698696) (xy 62.712441 -406.73439) (xy 62.74813 -406.775581)
			(xy 62.777594 -406.821432) (xy 62.800233 -406.871009) (xy 62.815587 -406.923303) (xy 62.823342 -406.977249)
			(xy 62.823342 -407.031749) (xy 64.260998 -407.031749) (xy 64.260998 -406.977251) (xy 64.268754 -406.923308)
			(xy 64.284107 -406.871017) (xy 64.306746 -406.821443) (xy 64.336209 -406.775596) (xy 64.371897 -406.734409)
			(xy 64.413083 -406.698719) (xy 64.458929 -406.669254) (xy 64.508502 -406.646613) (xy 64.560792 -406.631257)
			(xy 64.614735 -406.623499) (xy 64.641984 -406.623012) (xy 65.505584 -406.623012) (xy 65.532839 -406.623434)
			(xy 65.586795 -406.631189) (xy 65.639097 -406.646545) (xy 65.688682 -406.669188) (xy 65.73454 -406.698657)
			(xy 65.775736 -406.734352) (xy 65.811434 -406.775548) (xy 65.840905 -406.821404) (xy 65.86355 -406.870988)
			(xy 65.878907 -406.92329) (xy 65.886665 -406.977245) (xy 65.886665 -407.031753) (xy 67.324175 -407.031753)
			(xy 67.324175 -406.977247) (xy 67.331933 -406.923297) (xy 67.347289 -406.871) (xy 67.369932 -406.821421)
			(xy 67.399401 -406.775569) (xy 67.435095 -406.734378) (xy 67.476288 -406.698686) (xy 67.522142 -406.669221)
			(xy 67.571723 -406.646581) (xy 67.624021 -406.631227) (xy 67.677971 -406.623474) (xy 67.705224 -406.623012)
			(xy 68.568824 -406.623012) (xy 68.596076 -406.623459) (xy 68.650024 -406.631219) (xy 68.702318 -406.646577)
			(xy 68.751895 -406.669221) (xy 68.797745 -406.698689) (xy 68.838934 -406.734383) (xy 68.874625 -406.775575)
			(xy 68.904091 -406.821426) (xy 68.926731 -406.871004) (xy 68.942086 -406.9233) (xy 68.949842 -406.977248)
			(xy 68.949842 -407.031748) (xy 70.387498 -407.031748) (xy 70.387498 -406.977252) (xy 70.395253 -406.92331)
			(xy 70.410606 -406.871021) (xy 70.433243 -406.821449) (xy 70.462704 -406.775603) (xy 70.49839 -406.734416)
			(xy 70.539574 -406.698726) (xy 70.585417 -406.66926) (xy 70.634987 -406.646618) (xy 70.687275 -406.631261)
			(xy 70.741216 -406.623501) (xy 70.768464 -406.623012) (xy 71.632064 -406.623012) (xy 71.65932 -406.623432)
			(xy 71.713278 -406.631186) (xy 71.765583 -406.646539) (xy 71.81517 -406.669181) (xy 71.86103 -406.69865)
			(xy 71.902229 -406.734345) (xy 71.937929 -406.775541) (xy 71.967402 -406.821398) (xy 71.990048 -406.870984)
			(xy 72.005407 -406.923287) (xy 72.013165 -406.977244) (xy 72.013165 -407.031752) (xy 73.450675 -407.031752)
			(xy 73.450675 -406.977248) (xy 73.458432 -406.9233) (xy 73.473787 -406.871005) (xy 73.496429 -406.821427)
			(xy 73.525896 -406.775576) (xy 73.561588 -406.734385) (xy 73.602779 -406.698693) (xy 73.64863 -406.669227)
			(xy 73.698208 -406.646586) (xy 73.750504 -406.631231) (xy 73.804452 -406.623475) (xy 73.831704 -406.623012)
			(xy 74.695304 -406.623012) (xy 74.722556 -406.623458) (xy 74.776507 -406.631215) (xy 74.828804 -406.646572)
			(xy 74.878383 -406.669214) (xy 74.924235 -406.698682) (xy 74.965427 -406.734376) (xy 75.00112 -406.775568)
			(xy 75.030588 -406.821421) (xy 75.05323 -406.871) (xy 75.068585 -406.923297) (xy 75.076342 -406.977248)
			(xy 75.076342 -407.031752) (xy 75.076342 -407.031753) (xy 76.513875 -407.031753) (xy 76.513875 -406.977247)
			(xy 76.521633 -406.923295) (xy 76.536991 -406.870996) (xy 76.559635 -406.821416) (xy 76.589106 -406.775563)
			(xy 76.624802 -406.734371) (xy 76.665998 -406.698679) (xy 76.711854 -406.669214) (xy 76.761437 -406.646575)
			(xy 76.813738 -406.631224) (xy 76.867691 -406.623472) (xy 76.894944 -406.623012) (xy 77.758544 -406.623012)
			(xy 77.785795 -406.623461) (xy 77.83974 -406.631223) (xy 77.892033 -406.646583) (xy 77.941607 -406.669227)
			(xy 77.987454 -406.698696) (xy 78.028641 -406.73439) (xy 78.06433 -406.775581) (xy 78.093794 -406.821432)
			(xy 78.116433 -406.871009) (xy 78.131787 -406.923303) (xy 78.139542 -406.977249) (xy 78.139542 -407.031749)
			(xy 79.577198 -407.031749) (xy 79.577198 -406.977251) (xy 79.584954 -406.923308) (xy 79.600307 -406.871017)
			(xy 79.622946 -406.821443) (xy 79.652409 -406.775596) (xy 79.688097 -406.734409) (xy 79.729283 -406.698719)
			(xy 79.775129 -406.669254) (xy 79.824702 -406.646613) (xy 79.876992 -406.631257) (xy 79.930935 -406.623499)
			(xy 79.958184 -406.623012) (xy 80.821784 -406.623012) (xy 80.849039 -406.623434) (xy 80.902995 -406.631189)
			(xy 80.955297 -406.646545) (xy 81.004882 -406.669188) (xy 81.05074 -406.698657) (xy 81.091936 -406.734352)
			(xy 81.127634 -406.775548) (xy 81.157105 -406.821404) (xy 81.17975 -406.870988) (xy 81.195107 -406.92329)
			(xy 81.202865 -406.977245) (xy 81.202865 -407.031753) (xy 82.640375 -407.031753) (xy 82.640375 -406.977247)
			(xy 82.648133 -406.923297) (xy 82.663489 -406.871) (xy 82.686132 -406.821421) (xy 82.715601 -406.775569)
			(xy 82.751295 -406.734378) (xy 82.792488 -406.698686) (xy 82.838342 -406.669221) (xy 82.887923 -406.646581)
			(xy 82.940221 -406.631227) (xy 82.994171 -406.623474) (xy 83.021424 -406.623012) (xy 83.885024 -406.623012)
			(xy 83.912276 -406.623459) (xy 83.966224 -406.631219) (xy 84.018518 -406.646577) (xy 84.068095 -406.669221)
			(xy 84.113945 -406.698689) (xy 84.155134 -406.734383) (xy 84.190825 -406.775575) (xy 84.220291 -406.821426)
			(xy 84.242931 -406.871004) (xy 84.258286 -406.9233) (xy 84.266042 -406.977248) (xy 84.266042 -407.031748)
			(xy 85.703698 -407.031748) (xy 85.703698 -406.977252) (xy 85.711453 -406.92331) (xy 85.726806 -406.871021)
			(xy 85.749443 -406.821449) (xy 85.778904 -406.775603) (xy 85.81459 -406.734416) (xy 85.855774 -406.698726)
			(xy 85.901617 -406.66926) (xy 85.951187 -406.646618) (xy 86.003475 -406.631261) (xy 86.057416 -406.623501)
			(xy 86.084664 -406.623012) (xy 86.948264 -406.623012) (xy 86.97552 -406.623432) (xy 87.029478 -406.631186)
			(xy 87.081783 -406.646539) (xy 87.13137 -406.669181) (xy 87.17723 -406.69865) (xy 87.218429 -406.734345)
			(xy 87.254129 -406.775541) (xy 87.283602 -406.821398) (xy 87.306248 -406.870984) (xy 87.321607 -406.923287)
			(xy 87.329365 -406.977244) (xy 87.329365 -407.031752) (xy 88.766875 -407.031752) (xy 88.766875 -406.977248)
			(xy 88.774632 -406.9233) (xy 88.789987 -406.871005) (xy 88.812629 -406.821427) (xy 88.842096 -406.775576)
			(xy 88.877788 -406.734385) (xy 88.918979 -406.698693) (xy 88.96483 -406.669227) (xy 89.014408 -406.646586)
			(xy 89.066704 -406.631231) (xy 89.120652 -406.623475) (xy 89.147904 -406.623012) (xy 90.011504 -406.623012)
			(xy 90.038756 -406.623458) (xy 90.092707 -406.631215) (xy 90.145004 -406.646572) (xy 90.194583 -406.669214)
			(xy 90.240435 -406.698682) (xy 90.281627 -406.734376) (xy 90.31732 -406.775568) (xy 90.346788 -406.821421)
			(xy 90.36943 -406.871) (xy 90.384785 -406.923297) (xy 90.392542 -406.977248) (xy 90.392542 -407.031752)
			(xy 90.392542 -407.031753) (xy 91.830075 -407.031753) (xy 91.830075 -406.977247) (xy 91.837833 -406.923295)
			(xy 91.853191 -406.870996) (xy 91.875835 -406.821416) (xy 91.905306 -406.775563) (xy 91.941002 -406.734371)
			(xy 91.982198 -406.698679) (xy 92.028054 -406.669214) (xy 92.077637 -406.646575) (xy 92.129938 -406.631224)
			(xy 92.183891 -406.623472) (xy 92.211144 -406.623012) (xy 93.074744 -406.623012) (xy 93.101995 -406.623461)
			(xy 93.15594 -406.631223) (xy 93.208233 -406.646583) (xy 93.257807 -406.669227) (xy 93.303654 -406.698696)
			(xy 93.344841 -406.73439) (xy 93.38053 -406.775581) (xy 93.409994 -406.821432) (xy 93.432633 -406.871009)
			(xy 93.447987 -406.923303) (xy 93.455742 -406.977249) (xy 93.455742 -407.031749) (xy 94.893398 -407.031749)
			(xy 94.893398 -406.977251) (xy 94.901154 -406.923308) (xy 94.916507 -406.871017) (xy 94.939146 -406.821443)
			(xy 94.968609 -406.775596) (xy 95.004297 -406.734409) (xy 95.045483 -406.698719) (xy 95.091329 -406.669254)
			(xy 95.140902 -406.646613) (xy 95.193192 -406.631257) (xy 95.247135 -406.623499) (xy 95.274384 -406.623012)
			(xy 96.137984 -406.623012) (xy 96.165239 -406.623434) (xy 96.219195 -406.631189) (xy 96.271497 -406.646545)
			(xy 96.321082 -406.669188) (xy 96.36694 -406.698657) (xy 96.408136 -406.734352) (xy 96.443834 -406.775548)
			(xy 96.473305 -406.821404) (xy 96.49595 -406.870988) (xy 96.511307 -406.92329) (xy 96.519065 -406.977245)
			(xy 96.519065 -407.031753) (xy 116.044675 -407.031753) (xy 116.044675 -406.977247) (xy 116.052433 -406.923297)
			(xy 116.067789 -406.871) (xy 116.090432 -406.821421) (xy 116.119901 -406.775569) (xy 116.155596 -406.734377)
			(xy 116.196789 -406.698686) (xy 116.242643 -406.66922) (xy 116.292224 -406.64658) (xy 116.344522 -406.631227)
			(xy 116.398473 -406.623474) (xy 116.425726 -406.623012) (xy 117.289326 -406.623012) (xy 117.316577 -406.62346)
			(xy 117.370525 -406.63122) (xy 117.42282 -406.646578) (xy 117.472396 -406.669222) (xy 117.518246 -406.69869)
			(xy 117.559435 -406.734383) (xy 117.595126 -406.775575) (xy 117.624591 -406.821427) (xy 117.647231 -406.871005)
			(xy 117.662586 -406.9233) (xy 117.670342 -406.977249) (xy 117.670342 -407.031748) (xy 119.107998 -407.031748)
			(xy 119.107998 -406.977252) (xy 119.115753 -406.92331) (xy 119.131106 -406.871021) (xy 119.153743 -406.821448)
			(xy 119.183205 -406.775602) (xy 119.218891 -406.734415) (xy 119.260075 -406.698725) (xy 119.305918 -406.66926)
			(xy 119.355489 -406.646618) (xy 119.407777 -406.631261) (xy 119.461718 -406.623501) (xy 119.488966 -406.623012)
			(xy 120.352566 -406.623012) (xy 120.379822 -406.623433) (xy 120.433779 -406.631186) (xy 120.486084 -406.64654)
			(xy 120.535671 -406.669182) (xy 120.581531 -406.69865) (xy 120.62273 -406.734346) (xy 120.658429 -406.775542)
			(xy 120.687902 -406.821399) (xy 120.710548 -406.870984) (xy 120.725907 -406.923287) (xy 120.733665 -406.977244)
			(xy 120.733665 -407.031752) (xy 122.171175 -407.031752) (xy 122.171175 -406.977248) (xy 122.178932 -406.9233)
			(xy 122.194288 -406.871004) (xy 122.216929 -406.821426) (xy 122.246396 -406.775575) (xy 122.282089 -406.734384)
			(xy 122.32328 -406.698693) (xy 122.369131 -406.669226) (xy 122.41871 -406.646585) (xy 122.471006 -406.631231)
			(xy 122.524954 -406.623475) (xy 122.552206 -406.623012) (xy 123.415806 -406.623012) (xy 123.443058 -406.623458)
			(xy 123.497008 -406.631216) (xy 123.549305 -406.646572) (xy 123.598884 -406.669215) (xy 123.644736 -406.698683)
			(xy 123.685928 -406.734376) (xy 123.721621 -406.775569) (xy 123.751088 -406.821421) (xy 123.77373 -406.871001)
			(xy 123.789085 -406.923298) (xy 123.796842 -406.977248) (xy 123.796842 -407.031752) (xy 123.796842 -407.031754)
			(xy 125.234375 -407.031754) (xy 125.234375 -406.977246) (xy 125.242133 -406.923294) (xy 125.257491 -406.870996)
			(xy 125.280135 -406.821415) (xy 125.309606 -406.775562) (xy 125.345303 -406.73437) (xy 125.386499 -406.698679)
			(xy 125.432355 -406.669213) (xy 125.481939 -406.646575) (xy 125.534239 -406.631223) (xy 125.588192 -406.623472)
			(xy 125.615446 -406.623012) (xy 126.479046 -406.623012) (xy 126.506297 -406.623461) (xy 126.560242 -406.631223)
			(xy 126.612534 -406.646583) (xy 126.662108 -406.669228) (xy 126.707955 -406.698697) (xy 126.749142 -406.734391)
			(xy 126.78483 -406.775582) (xy 126.814294 -406.821432) (xy 126.836933 -406.871009) (xy 126.852287 -406.923303)
			(xy 126.860042 -406.977249) (xy 126.860042 -407.031749) (xy 128.297698 -407.031749) (xy 128.297698 -406.977251)
			(xy 128.305454 -406.923307) (xy 128.320808 -406.871016) (xy 128.343446 -406.821443) (xy 128.37291 -406.775596)
			(xy 128.408598 -406.734408) (xy 128.449784 -406.698718) (xy 128.49563 -406.669253) (xy 128.545203 -406.646612)
			(xy 128.597494 -406.631257) (xy 128.651437 -406.623499) (xy 128.678686 -406.623012) (xy 129.542286 -406.623012)
			(xy 129.569541 -406.623434) (xy 129.623496 -406.63119) (xy 129.675799 -406.646545) (xy 129.725383 -406.669188)
			(xy 129.771241 -406.698657) (xy 129.812437 -406.734353) (xy 129.848134 -406.775548) (xy 129.877605 -406.821405)
			(xy 129.90025 -406.870988) (xy 129.915607 -406.92329) (xy 129.923365 -406.977245) (xy 129.923365 -407.031753)
			(xy 131.360875 -407.031753) (xy 131.360875 -406.977247) (xy 131.368633 -406.923297) (xy 131.383989 -406.871)
			(xy 131.406632 -406.821421) (xy 131.436101 -406.775569) (xy 131.471796 -406.734377) (xy 131.512989 -406.698686)
			(xy 131.558843 -406.66922) (xy 131.608424 -406.64658) (xy 131.660722 -406.631227) (xy 131.714673 -406.623474)
			(xy 131.741926 -406.623012) (xy 132.605526 -406.623012) (xy 132.632777 -406.62346) (xy 132.686725 -406.63122)
			(xy 132.73902 -406.646578) (xy 132.788596 -406.669222) (xy 132.834446 -406.69869) (xy 132.875635 -406.734383)
			(xy 132.911326 -406.775575) (xy 132.940791 -406.821427) (xy 132.963431 -406.871005) (xy 132.978786 -406.9233)
			(xy 132.986542 -406.977249) (xy 132.986542 -407.031748) (xy 134.424198 -407.031748) (xy 134.424198 -406.977252)
			(xy 134.431953 -406.92331) (xy 134.447306 -406.871021) (xy 134.469943 -406.821448) (xy 134.499405 -406.775602)
			(xy 134.535091 -406.734415) (xy 134.576275 -406.698725) (xy 134.622118 -406.66926) (xy 134.671689 -406.646618)
			(xy 134.723977 -406.631261) (xy 134.777918 -406.623501) (xy 134.805166 -406.623012) (xy 135.668766 -406.623012)
			(xy 135.696022 -406.623433) (xy 135.749979 -406.631186) (xy 135.802284 -406.64654) (xy 135.851871 -406.669182)
			(xy 135.897731 -406.69865) (xy 135.93893 -406.734346) (xy 135.974629 -406.775542) (xy 136.004102 -406.821399)
			(xy 136.026748 -406.870984) (xy 136.042107 -406.923287) (xy 136.049865 -406.977244) (xy 136.049865 -407.031752)
			(xy 137.487375 -407.031752) (xy 137.487375 -406.977248) (xy 137.495132 -406.9233) (xy 137.510488 -406.871004)
			(xy 137.533129 -406.821426) (xy 137.562596 -406.775575) (xy 137.598289 -406.734384) (xy 137.63948 -406.698693)
			(xy 137.685331 -406.669226) (xy 137.73491 -406.646585) (xy 137.787206 -406.631231) (xy 137.841154 -406.623475)
			(xy 137.868406 -406.623012) (xy 138.732006 -406.623012) (xy 138.759258 -406.623458) (xy 138.813208 -406.631216)
			(xy 138.865505 -406.646572) (xy 138.915084 -406.669215) (xy 138.960936 -406.698683) (xy 139.002128 -406.734376)
			(xy 139.037821 -406.775569) (xy 139.067288 -406.821421) (xy 139.08993 -406.871001) (xy 139.105285 -406.923298)
			(xy 139.113042 -406.977248) (xy 139.113042 -407.031752) (xy 139.113042 -407.031754) (xy 140.550575 -407.031754)
			(xy 140.550575 -406.977246) (xy 140.558333 -406.923294) (xy 140.573691 -406.870996) (xy 140.596335 -406.821415)
			(xy 140.625806 -406.775562) (xy 140.661503 -406.73437) (xy 140.702699 -406.698679) (xy 140.748555 -406.669213)
			(xy 140.798139 -406.646575) (xy 140.850439 -406.631223) (xy 140.904392 -406.623472) (xy 140.931646 -406.623012)
			(xy 141.795246 -406.623012) (xy 141.822497 -406.623461) (xy 141.876442 -406.631223) (xy 141.928734 -406.646583)
			(xy 141.978308 -406.669228) (xy 142.024155 -406.698697) (xy 142.065342 -406.734391) (xy 142.10103 -406.775582)
			(xy 142.130494 -406.821432) (xy 142.153133 -406.871009) (xy 142.168487 -406.923303) (xy 142.176242 -406.977249)
			(xy 142.176242 -407.031749) (xy 143.613898 -407.031749) (xy 143.613898 -406.977251) (xy 143.621654 -406.923307)
			(xy 143.637008 -406.871016) (xy 143.659646 -406.821443) (xy 143.68911 -406.775596) (xy 143.724798 -406.734408)
			(xy 143.765984 -406.698718) (xy 143.81183 -406.669253) (xy 143.861403 -406.646612) (xy 143.913694 -406.631257)
			(xy 143.967637 -406.623499) (xy 143.994886 -406.623012) (xy 144.858486 -406.623012) (xy 144.885741 -406.623434)
			(xy 144.939696 -406.63119) (xy 144.991999 -406.646545) (xy 145.041583 -406.669188) (xy 145.087441 -406.698657)
			(xy 145.128637 -406.734353) (xy 145.164334 -406.775548) (xy 145.193805 -406.821405) (xy 145.21645 -406.870988)
			(xy 145.231807 -406.92329) (xy 145.239565 -406.977245) (xy 145.239565 -407.031753) (xy 146.677075 -407.031753)
			(xy 146.677075 -406.977247) (xy 146.684833 -406.923297) (xy 146.700189 -406.871) (xy 146.722832 -406.821421)
			(xy 146.752301 -406.775569) (xy 146.787996 -406.734377) (xy 146.829189 -406.698686) (xy 146.875043 -406.66922)
			(xy 146.924624 -406.64658) (xy 146.976922 -406.631227) (xy 147.030873 -406.623474) (xy 147.058126 -406.623012)
			(xy 147.921726 -406.623012) (xy 147.948977 -406.62346) (xy 148.002925 -406.63122) (xy 148.05522 -406.646578)
			(xy 148.104796 -406.669222) (xy 148.150646 -406.69869) (xy 148.191835 -406.734383) (xy 148.227526 -406.775575)
			(xy 148.256991 -406.821427) (xy 148.279631 -406.871005) (xy 148.294986 -406.9233) (xy 148.302742 -406.977249)
			(xy 148.302742 -407.031748) (xy 149.740398 -407.031748) (xy 149.740398 -406.977252) (xy 149.748153 -406.92331)
			(xy 149.763506 -406.871021) (xy 149.786143 -406.821448) (xy 149.815605 -406.775602) (xy 149.851291 -406.734415)
			(xy 149.892475 -406.698725) (xy 149.938318 -406.66926) (xy 149.987889 -406.646618) (xy 150.040177 -406.631261)
			(xy 150.094118 -406.623501) (xy 150.121366 -406.623012) (xy 150.984966 -406.623012) (xy 151.012222 -406.623433)
			(xy 151.066179 -406.631186) (xy 151.118484 -406.64654) (xy 151.168071 -406.669182) (xy 151.213931 -406.69865)
			(xy 151.25513 -406.734346) (xy 151.290829 -406.775542) (xy 151.320302 -406.821399) (xy 151.342948 -406.870984)
			(xy 151.358307 -406.923287) (xy 151.366065 -406.977244) (xy 151.366065 -407.031752) (xy 152.803575 -407.031752)
			(xy 152.803575 -406.977248) (xy 152.811332 -406.9233) (xy 152.826688 -406.871004) (xy 152.849329 -406.821426)
			(xy 152.878796 -406.775575) (xy 152.914489 -406.734384) (xy 152.95568 -406.698693) (xy 153.001531 -406.669226)
			(xy 153.05111 -406.646585) (xy 153.103406 -406.631231) (xy 153.157354 -406.623475) (xy 153.184606 -406.623012)
			(xy 154.048206 -406.623012) (xy 154.075458 -406.623458) (xy 154.129408 -406.631216) (xy 154.181705 -406.646572)
			(xy 154.231284 -406.669215) (xy 154.277136 -406.698683) (xy 154.318328 -406.734376) (xy 154.354021 -406.775569)
			(xy 154.383488 -406.821421) (xy 154.40613 -406.871001) (xy 154.421485 -406.923298) (xy 154.429242 -406.977248)
			(xy 154.429242 -407.031752) (xy 154.429242 -407.031754) (xy 155.866775 -407.031754) (xy 155.866775 -406.977246)
			(xy 155.874533 -406.923294) (xy 155.889891 -406.870996) (xy 155.912535 -406.821415) (xy 155.942006 -406.775562)
			(xy 155.977703 -406.73437) (xy 156.018899 -406.698679) (xy 156.064755 -406.669213) (xy 156.114339 -406.646575)
			(xy 156.166639 -406.631223) (xy 156.220592 -406.623472) (xy 156.247846 -406.623012) (xy 157.111446 -406.623012)
			(xy 157.138697 -406.623461) (xy 157.192642 -406.631223) (xy 157.244934 -406.646583) (xy 157.294508 -406.669228)
			(xy 157.340355 -406.698697) (xy 157.381542 -406.734391) (xy 157.41723 -406.775582) (xy 157.446694 -406.821432)
			(xy 157.469333 -406.871009) (xy 157.484687 -406.923303) (xy 157.492442 -406.977249) (xy 157.492442 -407.031749)
			(xy 158.930098 -407.031749) (xy 158.930098 -406.977251) (xy 158.937854 -406.923307) (xy 158.953208 -406.871016)
			(xy 158.975846 -406.821443) (xy 159.00531 -406.775596) (xy 159.040998 -406.734408) (xy 159.082184 -406.698718)
			(xy 159.12803 -406.669253) (xy 159.177603 -406.646612) (xy 159.229894 -406.631257) (xy 159.283837 -406.623499)
			(xy 159.311086 -406.623012) (xy 160.174686 -406.623012) (xy 160.201941 -406.623434) (xy 160.255896 -406.63119)
			(xy 160.308199 -406.646545) (xy 160.357783 -406.669188) (xy 160.403641 -406.698657) (xy 160.444837 -406.734353)
			(xy 160.480534 -406.775548) (xy 160.510005 -406.821405) (xy 160.53265 -406.870988) (xy 160.548007 -406.92329)
			(xy 160.555765 -406.977245) (xy 160.555765 -407.031753) (xy 161.993275 -407.031753) (xy 161.993275 -406.977247)
			(xy 162.001033 -406.923297) (xy 162.016389 -406.871) (xy 162.039032 -406.821421) (xy 162.068501 -406.775569)
			(xy 162.104196 -406.734377) (xy 162.145389 -406.698686) (xy 162.191243 -406.66922) (xy 162.240824 -406.64658)
			(xy 162.293122 -406.631227) (xy 162.347073 -406.623474) (xy 162.374326 -406.623012) (xy 163.237926 -406.623012)
			(xy 163.265177 -406.62346) (xy 163.319125 -406.63122) (xy 163.37142 -406.646578) (xy 163.420996 -406.669222)
			(xy 163.466846 -406.69869) (xy 163.508035 -406.734383) (xy 163.543726 -406.775575) (xy 163.573191 -406.821427)
			(xy 163.595831 -406.871005) (xy 163.611186 -406.9233) (xy 163.618942 -406.977249) (xy 163.618942 -407.031751)
			(xy 163.611186 -407.0857) (xy 163.595831 -407.137995) (xy 163.573191 -407.187573) (xy 163.543726 -407.233425)
			(xy 163.508035 -407.274617) (xy 163.466846 -407.31031) (xy 163.420996 -407.339778) (xy 163.37142 -407.362422)
			(xy 163.319125 -407.37778) (xy 163.265177 -407.38554) (xy 163.237926 -407.386028) (xy 162.374326 -407.386028)
			(xy 162.347073 -407.385526) (xy 162.293122 -407.377773) (xy 162.240824 -407.36242) (xy 162.191243 -407.33978)
			(xy 162.145389 -407.310314) (xy 162.104196 -407.274623) (xy 162.068501 -407.233431) (xy 162.039032 -407.187579)
			(xy 162.016389 -407.138) (xy 162.001033 -407.085703) (xy 161.993275 -407.031753) (xy 160.555765 -407.031753)
			(xy 160.555765 -407.031755) (xy 160.548007 -407.08571) (xy 160.53265 -407.138012) (xy 160.510005 -407.187595)
			(xy 160.480534 -407.233452) (xy 160.444837 -407.274647) (xy 160.403641 -407.310343) (xy 160.357783 -407.339812)
			(xy 160.308199 -407.362455) (xy 160.255896 -407.37781) (xy 160.201941 -407.385566) (xy 160.174686 -407.386028)
			(xy 159.311086 -407.386028) (xy 159.283837 -407.385501) (xy 159.229894 -407.377743) (xy 159.177603 -407.362388)
			(xy 159.12803 -407.339747) (xy 159.082184 -407.310282) (xy 159.040998 -407.274592) (xy 159.00531 -407.233404)
			(xy 158.975846 -407.187557) (xy 158.953208 -407.137984) (xy 158.937854 -407.085693) (xy 158.930098 -407.031749)
			(xy 157.492442 -407.031749) (xy 157.492442 -407.031751) (xy 157.484687 -407.085697) (xy 157.469333 -407.137991)
			(xy 157.446694 -407.187568) (xy 157.41723 -407.233418) (xy 157.381542 -407.274609) (xy 157.340355 -407.310303)
			(xy 157.294508 -407.339772) (xy 157.244934 -407.362417) (xy 157.192642 -407.377777) (xy 157.138697 -407.385539)
			(xy 157.111446 -407.386028) (xy 156.247846 -407.386028) (xy 156.220592 -407.385528) (xy 156.166639 -407.377777)
			(xy 156.114339 -407.362425) (xy 156.064755 -407.339787) (xy 156.018899 -407.310321) (xy 155.977703 -407.27463)
			(xy 155.942006 -407.233438) (xy 155.912535 -407.187585) (xy 155.889891 -407.138004) (xy 155.874533 -407.085706)
			(xy 155.866775 -407.031754) (xy 154.429242 -407.031754) (xy 154.421485 -407.085702) (xy 154.40613 -407.137999)
			(xy 154.383488 -407.187579) (xy 154.354021 -407.233431) (xy 154.318328 -407.274624) (xy 154.277136 -407.310317)
			(xy 154.231284 -407.339785) (xy 154.181705 -407.362428) (xy 154.129408 -407.377784) (xy 154.075458 -407.385542)
			(xy 154.048206 -407.386028) (xy 153.184606 -407.386028) (xy 153.157354 -407.385525) (xy 153.103406 -407.377769)
			(xy 153.05111 -407.362415) (xy 153.001531 -407.339774) (xy 152.95568 -407.310307) (xy 152.914489 -407.274616)
			(xy 152.878796 -407.233425) (xy 152.849329 -407.187574) (xy 152.826688 -407.137996) (xy 152.811332 -407.0857)
			(xy 152.803575 -407.031752) (xy 151.366065 -407.031752) (xy 151.366065 -407.031756) (xy 151.358307 -407.085713)
			(xy 151.342948 -407.138016) (xy 151.320302 -407.187601) (xy 151.290829 -407.233458) (xy 151.25513 -407.274654)
			(xy 151.213931 -407.31035) (xy 151.168071 -407.339818) (xy 151.118484 -407.36246) (xy 151.066179 -407.377814)
			(xy 151.012222 -407.385567) (xy 150.984966 -407.386028) (xy 150.121366 -407.386028) (xy 150.094118 -407.385499)
			(xy 150.040177 -407.377739) (xy 149.987889 -407.362382) (xy 149.938318 -407.33974) (xy 149.892475 -407.310275)
			(xy 149.851291 -407.274585) (xy 149.815605 -407.233398) (xy 149.786143 -407.187552) (xy 149.763506 -407.137979)
			(xy 149.748153 -407.08569) (xy 149.740398 -407.031748) (xy 148.302742 -407.031748) (xy 148.302742 -407.031751)
			(xy 148.294986 -407.0857) (xy 148.279631 -407.137995) (xy 148.256991 -407.187573) (xy 148.227526 -407.233425)
			(xy 148.191835 -407.274617) (xy 148.150646 -407.31031) (xy 148.104796 -407.339778) (xy 148.05522 -407.362422)
			(xy 148.002925 -407.37778) (xy 147.948977 -407.38554) (xy 147.921726 -407.386028) (xy 147.058126 -407.386028)
			(xy 147.030873 -407.385526) (xy 146.976922 -407.377773) (xy 146.924624 -407.36242) (xy 146.875043 -407.33978)
			(xy 146.829189 -407.310314) (xy 146.787996 -407.274623) (xy 146.752301 -407.233431) (xy 146.722832 -407.187579)
			(xy 146.700189 -407.138) (xy 146.684833 -407.085703) (xy 146.677075 -407.031753) (xy 145.239565 -407.031753)
			(xy 145.239565 -407.031755) (xy 145.231807 -407.08571) (xy 145.21645 -407.138012) (xy 145.193805 -407.187595)
			(xy 145.164334 -407.233452) (xy 145.128637 -407.274647) (xy 145.087441 -407.310343) (xy 145.041583 -407.339812)
			(xy 144.991999 -407.362455) (xy 144.939696 -407.37781) (xy 144.885741 -407.385566) (xy 144.858486 -407.386028)
			(xy 143.994886 -407.386028) (xy 143.967637 -407.385501) (xy 143.913694 -407.377743) (xy 143.861403 -407.362388)
			(xy 143.81183 -407.339747) (xy 143.765984 -407.310282) (xy 143.724798 -407.274592) (xy 143.68911 -407.233404)
			(xy 143.659646 -407.187557) (xy 143.637008 -407.137984) (xy 143.621654 -407.085693) (xy 143.613898 -407.031749)
			(xy 142.176242 -407.031749) (xy 142.176242 -407.031751) (xy 142.168487 -407.085697) (xy 142.153133 -407.137991)
			(xy 142.130494 -407.187568) (xy 142.10103 -407.233418) (xy 142.065342 -407.274609) (xy 142.024155 -407.310303)
			(xy 141.978308 -407.339772) (xy 141.928734 -407.362417) (xy 141.876442 -407.377777) (xy 141.822497 -407.385539)
			(xy 141.795246 -407.386028) (xy 140.931646 -407.386028) (xy 140.904392 -407.385528) (xy 140.850439 -407.377777)
			(xy 140.798139 -407.362425) (xy 140.748555 -407.339787) (xy 140.702699 -407.310321) (xy 140.661503 -407.27463)
			(xy 140.625806 -407.233438) (xy 140.596335 -407.187585) (xy 140.573691 -407.138004) (xy 140.558333 -407.085706)
			(xy 140.550575 -407.031754) (xy 139.113042 -407.031754) (xy 139.105285 -407.085702) (xy 139.08993 -407.137999)
			(xy 139.067288 -407.187579) (xy 139.037821 -407.233431) (xy 139.002128 -407.274624) (xy 138.960936 -407.310317)
			(xy 138.915084 -407.339785) (xy 138.865505 -407.362428) (xy 138.813208 -407.377784) (xy 138.759258 -407.385542)
			(xy 138.732006 -407.386028) (xy 137.868406 -407.386028) (xy 137.841154 -407.385525) (xy 137.787206 -407.377769)
			(xy 137.73491 -407.362415) (xy 137.685331 -407.339774) (xy 137.63948 -407.310307) (xy 137.598289 -407.274616)
			(xy 137.562596 -407.233425) (xy 137.533129 -407.187574) (xy 137.510488 -407.137996) (xy 137.495132 -407.0857)
			(xy 137.487375 -407.031752) (xy 136.049865 -407.031752) (xy 136.049865 -407.031756) (xy 136.042107 -407.085713)
			(xy 136.026748 -407.138016) (xy 136.004102 -407.187601) (xy 135.974629 -407.233458) (xy 135.93893 -407.274654)
			(xy 135.897731 -407.31035) (xy 135.851871 -407.339818) (xy 135.802284 -407.36246) (xy 135.749979 -407.377814)
			(xy 135.696022 -407.385567) (xy 135.668766 -407.386028) (xy 134.805166 -407.386028) (xy 134.777918 -407.385499)
			(xy 134.723977 -407.377739) (xy 134.671689 -407.362382) (xy 134.622118 -407.33974) (xy 134.576275 -407.310275)
			(xy 134.535091 -407.274585) (xy 134.499405 -407.233398) (xy 134.469943 -407.187552) (xy 134.447306 -407.137979)
			(xy 134.431953 -407.08569) (xy 134.424198 -407.031748) (xy 132.986542 -407.031748) (xy 132.986542 -407.031751)
			(xy 132.978786 -407.0857) (xy 132.963431 -407.137995) (xy 132.940791 -407.187573) (xy 132.911326 -407.233425)
			(xy 132.875635 -407.274617) (xy 132.834446 -407.31031) (xy 132.788596 -407.339778) (xy 132.73902 -407.362422)
			(xy 132.686725 -407.37778) (xy 132.632777 -407.38554) (xy 132.605526 -407.386028) (xy 131.741926 -407.386028)
			(xy 131.714673 -407.385526) (xy 131.660722 -407.377773) (xy 131.608424 -407.36242) (xy 131.558843 -407.33978)
			(xy 131.512989 -407.310314) (xy 131.471796 -407.274623) (xy 131.436101 -407.233431) (xy 131.406632 -407.187579)
			(xy 131.383989 -407.138) (xy 131.368633 -407.085703) (xy 131.360875 -407.031753) (xy 129.923365 -407.031753)
			(xy 129.923365 -407.031755) (xy 129.915607 -407.08571) (xy 129.90025 -407.138012) (xy 129.877605 -407.187595)
			(xy 129.848134 -407.233452) (xy 129.812437 -407.274647) (xy 129.771241 -407.310343) (xy 129.725383 -407.339812)
			(xy 129.675799 -407.362455) (xy 129.623496 -407.37781) (xy 129.569541 -407.385566) (xy 129.542286 -407.386028)
			(xy 128.678686 -407.386028) (xy 128.651437 -407.385501) (xy 128.597494 -407.377743) (xy 128.545203 -407.362388)
			(xy 128.49563 -407.339747) (xy 128.449784 -407.310282) (xy 128.408598 -407.274592) (xy 128.37291 -407.233404)
			(xy 128.343446 -407.187557) (xy 128.320808 -407.137984) (xy 128.305454 -407.085693) (xy 128.297698 -407.031749)
			(xy 126.860042 -407.031749) (xy 126.860042 -407.031751) (xy 126.852287 -407.085697) (xy 126.836933 -407.137991)
			(xy 126.814294 -407.187568) (xy 126.78483 -407.233418) (xy 126.749142 -407.274609) (xy 126.707955 -407.310303)
			(xy 126.662108 -407.339772) (xy 126.612534 -407.362417) (xy 126.560242 -407.377777) (xy 126.506297 -407.385539)
			(xy 126.479046 -407.386028) (xy 125.615446 -407.386028) (xy 125.588192 -407.385528) (xy 125.534239 -407.377777)
			(xy 125.481939 -407.362425) (xy 125.432355 -407.339787) (xy 125.386499 -407.310321) (xy 125.345303 -407.27463)
			(xy 125.309606 -407.233438) (xy 125.280135 -407.187585) (xy 125.257491 -407.138004) (xy 125.242133 -407.085706)
			(xy 125.234375 -407.031754) (xy 123.796842 -407.031754) (xy 123.789085 -407.085702) (xy 123.77373 -407.137999)
			(xy 123.751088 -407.187579) (xy 123.721621 -407.233431) (xy 123.685928 -407.274624) (xy 123.644736 -407.310317)
			(xy 123.598884 -407.339785) (xy 123.549305 -407.362428) (xy 123.497008 -407.377784) (xy 123.443058 -407.385542)
			(xy 123.415806 -407.386028) (xy 122.552206 -407.386028) (xy 122.524954 -407.385525) (xy 122.471006 -407.377769)
			(xy 122.41871 -407.362415) (xy 122.369131 -407.339774) (xy 122.32328 -407.310307) (xy 122.282089 -407.274616)
			(xy 122.246396 -407.233425) (xy 122.216929 -407.187574) (xy 122.194288 -407.137996) (xy 122.178932 -407.0857)
			(xy 122.171175 -407.031752) (xy 120.733665 -407.031752) (xy 120.733665 -407.031756) (xy 120.725907 -407.085713)
			(xy 120.710548 -407.138016) (xy 120.687902 -407.187601) (xy 120.658429 -407.233458) (xy 120.62273 -407.274654)
			(xy 120.581531 -407.31035) (xy 120.535671 -407.339818) (xy 120.486084 -407.36246) (xy 120.433779 -407.377814)
			(xy 120.379822 -407.385567) (xy 120.352566 -407.386028) (xy 119.488966 -407.386028) (xy 119.461718 -407.385499)
			(xy 119.407777 -407.377739) (xy 119.355489 -407.362382) (xy 119.305918 -407.33974) (xy 119.260075 -407.310275)
			(xy 119.218891 -407.274585) (xy 119.183205 -407.233398) (xy 119.153743 -407.187552) (xy 119.131106 -407.137979)
			(xy 119.115753 -407.08569) (xy 119.107998 -407.031748) (xy 117.670342 -407.031748) (xy 117.670342 -407.031751)
			(xy 117.662586 -407.0857) (xy 117.647231 -407.137995) (xy 117.624591 -407.187573) (xy 117.595126 -407.233425)
			(xy 117.559435 -407.274617) (xy 117.518246 -407.31031) (xy 117.472396 -407.339778) (xy 117.42282 -407.362422)
			(xy 117.370525 -407.37778) (xy 117.316577 -407.38554) (xy 117.289326 -407.386028) (xy 116.425726 -407.386028)
			(xy 116.398473 -407.385526) (xy 116.344522 -407.377773) (xy 116.292224 -407.36242) (xy 116.242643 -407.33978)
			(xy 116.196789 -407.310314) (xy 116.155596 -407.274623) (xy 116.119901 -407.233431) (xy 116.090432 -407.187579)
			(xy 116.067789 -407.138) (xy 116.052433 -407.085703) (xy 116.044675 -407.031753) (xy 96.519065 -407.031753)
			(xy 96.519065 -407.031755) (xy 96.511307 -407.08571) (xy 96.49595 -407.138012) (xy 96.473305 -407.187596)
			(xy 96.443834 -407.233452) (xy 96.408136 -407.274648) (xy 96.36694 -407.310343) (xy 96.321082 -407.339812)
			(xy 96.271497 -407.362455) (xy 96.219195 -407.377811) (xy 96.165239 -407.385566) (xy 96.137984 -407.386028)
			(xy 95.274384 -407.386028) (xy 95.247135 -407.385501) (xy 95.193192 -407.377743) (xy 95.140902 -407.362387)
			(xy 95.091329 -407.339746) (xy 95.045483 -407.310281) (xy 95.004297 -407.274591) (xy 94.968609 -407.233404)
			(xy 94.939146 -407.187557) (xy 94.916507 -407.137983) (xy 94.901154 -407.085692) (xy 94.893398 -407.031749)
			(xy 93.455742 -407.031749) (xy 93.455742 -407.031751) (xy 93.447987 -407.085697) (xy 93.432633 -407.137991)
			(xy 93.409994 -407.187568) (xy 93.38053 -407.233419) (xy 93.344841 -407.27461) (xy 93.303654 -407.310304)
			(xy 93.257807 -407.339773) (xy 93.208233 -407.362417) (xy 93.15594 -407.377777) (xy 93.101995 -407.385539)
			(xy 93.074744 -407.386028) (xy 92.211144 -407.386028) (xy 92.183891 -407.385528) (xy 92.129938 -407.377776)
			(xy 92.077637 -407.362425) (xy 92.028054 -407.339786) (xy 91.982198 -407.310321) (xy 91.941002 -407.274629)
			(xy 91.905306 -407.233437) (xy 91.875835 -407.187584) (xy 91.853191 -407.138004) (xy 91.837833 -407.085705)
			(xy 91.830075 -407.031753) (xy 90.392542 -407.031753) (xy 90.384785 -407.085703) (xy 90.36943 -407.138)
			(xy 90.346788 -407.187579) (xy 90.31732 -407.233432) (xy 90.281627 -407.274624) (xy 90.240435 -407.310318)
			(xy 90.194583 -407.339786) (xy 90.145004 -407.362428) (xy 90.092707 -407.377785) (xy 90.038756 -407.385542)
			(xy 90.011504 -407.386028) (xy 89.147904 -407.386028) (xy 89.120652 -407.385525) (xy 89.066704 -407.377769)
			(xy 89.014408 -407.362414) (xy 88.96483 -407.339773) (xy 88.918979 -407.310307) (xy 88.877788 -407.274615)
			(xy 88.842096 -407.233424) (xy 88.812629 -407.187573) (xy 88.789987 -407.137995) (xy 88.774632 -407.0857)
			(xy 88.766875 -407.031752) (xy 87.329365 -407.031752) (xy 87.329365 -407.031756) (xy 87.321607 -407.085713)
			(xy 87.306248 -407.138016) (xy 87.283602 -407.187602) (xy 87.254129 -407.233459) (xy 87.218429 -407.274655)
			(xy 87.17723 -407.31035) (xy 87.13137 -407.339819) (xy 87.081783 -407.362461) (xy 87.029478 -407.377814)
			(xy 86.97552 -407.385568) (xy 86.948264 -407.386028) (xy 86.084664 -407.386028) (xy 86.057416 -407.385499)
			(xy 86.003475 -407.377739) (xy 85.951187 -407.362382) (xy 85.901617 -407.33974) (xy 85.855774 -407.310274)
			(xy 85.81459 -407.274584) (xy 85.778904 -407.233397) (xy 85.749443 -407.187551) (xy 85.726806 -407.137979)
			(xy 85.711453 -407.08569) (xy 85.703698 -407.031748) (xy 84.266042 -407.031748) (xy 84.266042 -407.031752)
			(xy 84.258286 -407.0857) (xy 84.242931 -407.137996) (xy 84.220291 -407.187574) (xy 84.190825 -407.233425)
			(xy 84.155134 -407.274617) (xy 84.113945 -407.310311) (xy 84.068095 -407.339779) (xy 84.018518 -407.362423)
			(xy 83.966224 -407.377781) (xy 83.912276 -407.385541) (xy 83.885024 -407.386028) (xy 83.021424 -407.386028)
			(xy 82.994171 -407.385526) (xy 82.940221 -407.377773) (xy 82.887923 -407.362419) (xy 82.838342 -407.339779)
			(xy 82.792488 -407.310314) (xy 82.751295 -407.274622) (xy 82.715601 -407.233431) (xy 82.686132 -407.187579)
			(xy 82.663489 -407.138) (xy 82.648133 -407.085703) (xy 82.640375 -407.031753) (xy 81.202865 -407.031753)
			(xy 81.202865 -407.031755) (xy 81.195107 -407.08571) (xy 81.17975 -407.138012) (xy 81.157105 -407.187596)
			(xy 81.127634 -407.233452) (xy 81.091936 -407.274648) (xy 81.05074 -407.310343) (xy 81.004882 -407.339812)
			(xy 80.955297 -407.362455) (xy 80.902995 -407.377811) (xy 80.849039 -407.385566) (xy 80.821784 -407.386028)
			(xy 79.958184 -407.386028) (xy 79.930935 -407.385501) (xy 79.876992 -407.377743) (xy 79.824702 -407.362387)
			(xy 79.775129 -407.339746) (xy 79.729283 -407.310281) (xy 79.688097 -407.274591) (xy 79.652409 -407.233404)
			(xy 79.622946 -407.187557) (xy 79.600307 -407.137983) (xy 79.584954 -407.085692) (xy 79.577198 -407.031749)
			(xy 78.139542 -407.031749) (xy 78.139542 -407.031751) (xy 78.131787 -407.085697) (xy 78.116433 -407.137991)
			(xy 78.093794 -407.187568) (xy 78.06433 -407.233419) (xy 78.028641 -407.27461) (xy 77.987454 -407.310304)
			(xy 77.941607 -407.339773) (xy 77.892033 -407.362417) (xy 77.83974 -407.377777) (xy 77.785795 -407.385539)
			(xy 77.758544 -407.386028) (xy 76.894944 -407.386028) (xy 76.867691 -407.385528) (xy 76.813738 -407.377776)
			(xy 76.761437 -407.362425) (xy 76.711854 -407.339786) (xy 76.665998 -407.310321) (xy 76.624802 -407.274629)
			(xy 76.589106 -407.233437) (xy 76.559635 -407.187584) (xy 76.536991 -407.138004) (xy 76.521633 -407.085705)
			(xy 76.513875 -407.031753) (xy 75.076342 -407.031753) (xy 75.068585 -407.085703) (xy 75.05323 -407.138)
			(xy 75.030588 -407.187579) (xy 75.00112 -407.233432) (xy 74.965427 -407.274624) (xy 74.924235 -407.310318)
			(xy 74.878383 -407.339786) (xy 74.828804 -407.362428) (xy 74.776507 -407.377785) (xy 74.722556 -407.385542)
			(xy 74.695304 -407.386028) (xy 73.831704 -407.386028) (xy 73.804452 -407.385525) (xy 73.750504 -407.377769)
			(xy 73.698208 -407.362414) (xy 73.64863 -407.339773) (xy 73.602779 -407.310307) (xy 73.561588 -407.274615)
			(xy 73.525896 -407.233424) (xy 73.496429 -407.187573) (xy 73.473787 -407.137995) (xy 73.458432 -407.0857)
			(xy 73.450675 -407.031752) (xy 72.013165 -407.031752) (xy 72.013165 -407.031756) (xy 72.005407 -407.085713)
			(xy 71.990048 -407.138016) (xy 71.967402 -407.187602) (xy 71.937929 -407.233459) (xy 71.902229 -407.274655)
			(xy 71.86103 -407.31035) (xy 71.81517 -407.339819) (xy 71.765583 -407.362461) (xy 71.713278 -407.377814)
			(xy 71.65932 -407.385568) (xy 71.632064 -407.386028) (xy 70.768464 -407.386028) (xy 70.741216 -407.385499)
			(xy 70.687275 -407.377739) (xy 70.634987 -407.362382) (xy 70.585417 -407.33974) (xy 70.539574 -407.310274)
			(xy 70.49839 -407.274584) (xy 70.462704 -407.233397) (xy 70.433243 -407.187551) (xy 70.410606 -407.137979)
			(xy 70.395253 -407.08569) (xy 70.387498 -407.031748) (xy 68.949842 -407.031748) (xy 68.949842 -407.031752)
			(xy 68.942086 -407.0857) (xy 68.926731 -407.137996) (xy 68.904091 -407.187574) (xy 68.874625 -407.233425)
			(xy 68.838934 -407.274617) (xy 68.797745 -407.310311) (xy 68.751895 -407.339779) (xy 68.702318 -407.362423)
			(xy 68.650024 -407.377781) (xy 68.596076 -407.385541) (xy 68.568824 -407.386028) (xy 67.705224 -407.386028)
			(xy 67.677971 -407.385526) (xy 67.624021 -407.377773) (xy 67.571723 -407.362419) (xy 67.522142 -407.339779)
			(xy 67.476288 -407.310314) (xy 67.435095 -407.274622) (xy 67.399401 -407.233431) (xy 67.369932 -407.187579)
			(xy 67.347289 -407.138) (xy 67.331933 -407.085703) (xy 67.324175 -407.031753) (xy 65.886665 -407.031753)
			(xy 65.886665 -407.031755) (xy 65.878907 -407.08571) (xy 65.86355 -407.138012) (xy 65.840905 -407.187596)
			(xy 65.811434 -407.233452) (xy 65.775736 -407.274648) (xy 65.73454 -407.310343) (xy 65.688682 -407.339812)
			(xy 65.639097 -407.362455) (xy 65.586795 -407.377811) (xy 65.532839 -407.385566) (xy 65.505584 -407.386028)
			(xy 64.641984 -407.386028) (xy 64.614735 -407.385501) (xy 64.560792 -407.377743) (xy 64.508502 -407.362387)
			(xy 64.458929 -407.339746) (xy 64.413083 -407.310281) (xy 64.371897 -407.274591) (xy 64.336209 -407.233404)
			(xy 64.306746 -407.187557) (xy 64.284107 -407.137983) (xy 64.268754 -407.085692) (xy 64.260998 -407.031749)
			(xy 62.823342 -407.031749) (xy 62.823342 -407.031751) (xy 62.815587 -407.085697) (xy 62.800233 -407.137991)
			(xy 62.777594 -407.187568) (xy 62.74813 -407.233419) (xy 62.712441 -407.27461) (xy 62.671254 -407.310304)
			(xy 62.625407 -407.339773) (xy 62.575833 -407.362417) (xy 62.52354 -407.377777) (xy 62.469595 -407.385539)
			(xy 62.442344 -407.386028) (xy 61.578744 -407.386028) (xy 61.551491 -407.385528) (xy 61.497538 -407.377776)
			(xy 61.445237 -407.362425) (xy 61.395654 -407.339786) (xy 61.349798 -407.310321) (xy 61.308602 -407.274629)
			(xy 61.272906 -407.233437) (xy 61.243435 -407.187584) (xy 61.220791 -407.138004) (xy 61.205433 -407.085705)
			(xy 61.197675 -407.031753) (xy 59.760142 -407.031753) (xy 59.752385 -407.085703) (xy 59.73703 -407.138)
			(xy 59.714388 -407.187579) (xy 59.68492 -407.233432) (xy 59.649227 -407.274624) (xy 59.608035 -407.310318)
			(xy 59.562183 -407.339786) (xy 59.512604 -407.362428) (xy 59.460307 -407.377785) (xy 59.406356 -407.385542)
			(xy 59.379104 -407.386028) (xy 58.515504 -407.386028) (xy 58.488252 -407.385525) (xy 58.434304 -407.377769)
			(xy 58.382008 -407.362414) (xy 58.33243 -407.339773) (xy 58.286579 -407.310307) (xy 58.245388 -407.274615)
			(xy 58.209696 -407.233424) (xy 58.180229 -407.187573) (xy 58.157587 -407.137995) (xy 58.142232 -407.0857)
			(xy 58.134475 -407.031752) (xy 56.696965 -407.031752) (xy 56.696965 -407.031756) (xy 56.689207 -407.085713)
			(xy 56.673848 -407.138016) (xy 56.651202 -407.187602) (xy 56.621729 -407.233459) (xy 56.586029 -407.274655)
			(xy 56.54483 -407.31035) (xy 56.49897 -407.339819) (xy 56.449383 -407.362461) (xy 56.397078 -407.377814)
			(xy 56.34312 -407.385568) (xy 56.315864 -407.386028) (xy 55.452264 -407.386028) (xy 55.425016 -407.385499)
			(xy 55.371075 -407.377739) (xy 55.318787 -407.362382) (xy 55.269217 -407.33974) (xy 55.223374 -407.310274)
			(xy 55.18219 -407.274584) (xy 55.146504 -407.233397) (xy 55.117043 -407.187551) (xy 55.094406 -407.137979)
			(xy 55.079053 -407.08569) (xy 55.071298 -407.031748) (xy 53.633642 -407.031748) (xy 53.633642 -407.031752)
			(xy 53.625886 -407.0857) (xy 53.610531 -407.137996) (xy 53.587891 -407.187574) (xy 53.558425 -407.233425)
			(xy 53.522734 -407.274617) (xy 53.481545 -407.310311) (xy 53.435695 -407.339779) (xy 53.386118 -407.362423)
			(xy 53.333824 -407.377781) (xy 53.279876 -407.385541) (xy 53.252624 -407.386028) (xy 52.389024 -407.386028)
			(xy 52.361771 -407.385526) (xy 52.307821 -407.377773) (xy 52.255523 -407.362419) (xy 52.205942 -407.339779)
			(xy 52.160088 -407.310314) (xy 52.118895 -407.274622) (xy 52.083201 -407.233431) (xy 52.053732 -407.187579)
			(xy 52.031089 -407.138) (xy 52.015733 -407.085703) (xy 52.007975 -407.031753) (xy 50.570465 -407.031753)
			(xy 50.570465 -407.031755) (xy 50.562707 -407.08571) (xy 50.54735 -407.138012) (xy 50.524705 -407.187596)
			(xy 50.495234 -407.233452) (xy 50.459536 -407.274648) (xy 50.41834 -407.310343) (xy 50.372482 -407.339812)
			(xy 50.322897 -407.362455) (xy 50.270595 -407.377811) (xy 50.216639 -407.385566) (xy 50.189384 -407.386028)
			(xy 49.325784 -407.386028) (xy 49.298535 -407.385501) (xy 49.244592 -407.377743) (xy 49.192302 -407.362387)
			(xy 49.142729 -407.339746) (xy 49.096883 -407.310281) (xy 49.055697 -407.274591) (xy 49.020009 -407.233404)
			(xy 48.990546 -407.187557) (xy 48.967907 -407.137983) (xy 48.952554 -407.085692) (xy 48.944798 -407.031749)
			(xy 45.259912 -407.031749) (xy 45.177806 -407.162866) (xy 45.072493 -407.31598) (xy 44.960691 -407.46442)
			(xy 44.842606 -407.607914) (xy 44.718456 -407.746194) (xy 44.588473 -407.879005) (xy 44.452896 -408.006101)
			(xy 44.311976 -408.127246) (xy 44.165976 -408.242217) (xy 44.015164 -408.3508) (xy 43.85982 -408.452793)
			(xy 43.700232 -408.54801) (xy 43.536695 -408.636272) (xy 43.369513 -408.717417) (xy 43.198994 -408.791294)
			(xy 43.025455 -408.857767) (xy 42.849216 -408.916712) (xy 42.670605 -408.96802) (xy 42.489952 -409.011597)
			(xy 42.307591 -409.047361) (xy 42.123861 -409.075247) (xy 41.939101 -409.095202) (xy 41.753654 -409.10719)
			(xy 41.567862 -409.111188) (xy 41.38207 -409.10719) (xy 41.196623 -409.095202) (xy 41.011863 -409.075247)
			(xy 40.828133 -409.047361) (xy 40.645772 -409.011597) (xy 40.465119 -408.96802) (xy 40.286508 -408.916712)
			(xy 40.110269 -408.857767) (xy 39.93673 -408.791294) (xy 39.766211 -408.717417) (xy 39.599029 -408.636272)
			(xy 39.435492 -408.54801) (xy 39.275904 -408.452793) (xy 39.12056 -408.3508) (xy 38.969748 -408.242217)
			(xy 38.823748 -408.127246) (xy 38.682828 -408.006101) (xy 38.547251 -407.879005) (xy 38.417268 -407.746194)
			(xy 38.293118 -407.607914) (xy 38.175033 -407.46442) (xy 38.063231 -407.31598) (xy 37.957918 -407.162866)
			(xy 37.85929 -407.005364) (xy 37.767529 -406.843764) (xy 37.682806 -406.678366) (xy 37.605277 -406.509477)
			(xy 37.535086 -406.337408) (xy 37.472363 -406.162479) (xy 37.417223 -405.985013) (xy 37.36977 -405.805339)
			(xy 37.33009 -405.62379) (xy 37.298258 -405.440702) (xy 37.274332 -405.256414) (xy 37.258357 -405.071268)
			(xy 37.250362 -404.885605) (xy 33.019445 -404.885605) (xy 37.697664 -409.563824) (xy 102.192836 -409.563824)
			(xy 102.192836 -408.700224) (xy 102.193322 -408.672955) (xy 102.201084 -408.618971) (xy 102.216449 -408.566641)
			(xy 102.239106 -408.517031) (xy 102.268592 -408.47115) (xy 102.304307 -408.429933) (xy 102.345524 -408.394218)
			(xy 102.391405 -408.364732) (xy 102.441015 -408.342075) (xy 102.493345 -408.32671) (xy 102.547329 -408.318948)
			(xy 102.601867 -408.318948) (xy 102.655851 -408.32671) (xy 102.708181 -408.342075) (xy 102.757791 -408.364732)
			(xy 102.803672 -408.394218) (xy 102.844889 -408.429933) (xy 102.880604 -408.47115) (xy 102.91009 -408.517031)
			(xy 102.932747 -408.566641) (xy 102.948112 -408.618971) (xy 102.955874 -408.672955) (xy 102.95636 -408.700224)
			(xy 102.95636 -409.563824) (xy 102.955874 -409.591093) (xy 102.948112 -409.645077) (xy 102.932747 -409.697407)
			(xy 102.91009 -409.747017) (xy 102.880604 -409.792898) (xy 102.844889 -409.834115) (xy 102.803672 -409.86983)
			(xy 102.757791 -409.899316) (xy 102.748244 -409.903676) (xy 110.559596 -409.903676) (xy 110.559596 -409.040076)
			(xy 110.560082 -409.012825) (xy 110.567838 -408.958877) (xy 110.583193 -408.906582) (xy 110.605835 -408.857005)
			(xy 110.635301 -408.811155) (xy 110.670992 -408.769964) (xy 110.712183 -408.734273) (xy 110.758033 -408.704807)
			(xy 110.80761 -408.682165) (xy 110.859905 -408.66681) (xy 110.913853 -408.659054) (xy 110.968355 -408.659054)
			(xy 111.022303 -408.66681) (xy 111.074598 -408.682165) (xy 111.124175 -408.704807) (xy 111.170025 -408.734273)
			(xy 111.211216 -408.769964) (xy 111.246907 -408.811155) (xy 111.276373 -408.857005) (xy 111.299015 -408.906582)
			(xy 111.31437 -408.958877) (xy 111.322126 -409.012825) (xy 111.322612 -409.040076) (xy 111.322612 -409.903676)
			(xy 111.322126 -409.930927) (xy 111.31437 -409.984875) (xy 111.299015 -410.03717) (xy 111.28975 -410.057456)
			(xy 116.044623 -410.057456) (xy 116.044623 -410.002944) (xy 116.052381 -409.948986) (xy 116.06774 -409.896681)
			(xy 116.090386 -409.847095) (xy 116.119859 -409.801237) (xy 116.155559 -409.76004) (xy 116.196758 -409.724344)
			(xy 116.242618 -409.694874) (xy 116.292206 -409.672231) (xy 116.344511 -409.656876) (xy 116.39847 -409.649121)
			(xy 116.425726 -409.64866) (xy 117.289326 -409.64866) (xy 117.316574 -409.649212) (xy 117.370514 -409.656971)
			(xy 117.422801 -409.672327) (xy 117.472371 -409.694968) (xy 117.518214 -409.724432) (xy 117.559398 -409.760121)
			(xy 117.595084 -409.801307) (xy 117.624545 -409.847152) (xy 117.647182 -409.896723) (xy 117.662535 -409.949011)
			(xy 117.67029 -410.002952) (xy 117.67029 -410.057448) (xy 117.670289 -410.057452) (xy 119.107946 -410.057452)
			(xy 119.107946 -410.002948) (xy 119.115702 -409.948999) (xy 119.131057 -409.896702) (xy 119.153697 -409.847123)
			(xy 119.183163 -409.801271) (xy 119.218854 -409.760078) (xy 119.260043 -409.724383) (xy 119.305893 -409.694914)
			(xy 119.35547 -409.672269) (xy 119.407765 -409.656909) (xy 119.461714 -409.649148) (xy 119.488966 -409.64866)
			(xy 120.352566 -409.64866) (xy 120.379818 -409.649185) (xy 120.433768 -409.656937) (xy 120.486066 -409.672289)
			(xy 120.535646 -409.694928) (xy 120.5815 -409.724392) (xy 120.622693 -409.760083) (xy 120.658387 -409.801273)
			(xy 120.687856 -409.847124) (xy 120.710499 -409.896702) (xy 120.725855 -409.948999) (xy 120.733613 -410.002948)
			(xy 120.733613 -410.057452) (xy 120.733613 -410.057455) (xy 122.171123 -410.057455) (xy 122.171123 -410.002945)
			(xy 122.178881 -409.948989) (xy 122.194238 -409.896686) (xy 122.216883 -409.847101) (xy 122.246354 -409.801244)
			(xy 122.282052 -409.760047) (xy 122.323249 -409.724351) (xy 122.369106 -409.69488) (xy 122.418691 -409.672236)
			(xy 122.470994 -409.656879) (xy 122.524951 -409.649123) (xy 122.552206 -409.64866) (xy 123.415806 -409.64866)
			(xy 123.443055 -409.649211) (xy 123.496997 -409.656967) (xy 123.549287 -409.672321) (xy 123.598859 -409.694961)
			(xy 123.644705 -409.724425) (xy 123.685891 -409.760113) (xy 123.721579 -409.8013) (xy 123.751042 -409.847146)
			(xy 123.773681 -409.896719) (xy 123.789034 -409.949009) (xy 123.79679 -410.002951) (xy 123.79679 -410.057449)
			(xy 123.796789 -410.057457) (xy 125.234323 -410.057457) (xy 125.234323 -410.002943) (xy 125.242082 -409.948983)
			(xy 125.257442 -409.896677) (xy 125.280089 -409.84709) (xy 125.309564 -409.801231) (xy 125.345266 -409.760033)
			(xy 125.386467 -409.724337) (xy 125.43233 -409.694867) (xy 125.48192 -409.672225) (xy 125.534228 -409.656872)
			(xy 125.588189 -409.64912) (xy 125.615446 -409.64866) (xy 126.479046 -409.64866) (xy 126.506293 -409.649213)
			(xy 126.560231 -409.656975) (xy 126.612516 -409.672332) (xy 126.662083 -409.694974) (xy 126.707924 -409.724439)
			(xy 126.749105 -409.760128) (xy 126.784788 -409.801313) (xy 126.814248 -409.847157) (xy 126.836884 -409.896727)
			(xy 126.852235 -409.949014) (xy 126.85999 -410.002953) (xy 126.85999 -410.057447) (xy 126.859989 -410.057453)
			(xy 128.297646 -410.057453) (xy 128.297646 -410.002947) (xy 128.305403 -409.948996) (xy 128.320758 -409.896698)
			(xy 128.3434 -409.847118) (xy 128.372868 -409.801264) (xy 128.408561 -409.760071) (xy 128.449753 -409.724376)
			(xy 128.495605 -409.694907) (xy 128.545185 -409.672263) (xy 128.597482 -409.656906) (xy 128.651433 -409.649147)
			(xy 128.678686 -409.64866) (xy 129.542286 -409.64866) (xy 129.569537 -409.649186) (xy 129.623485 -409.656941)
			(xy 129.67578 -409.672295) (xy 129.725358 -409.694934) (xy 129.771209 -409.724399) (xy 129.8124 -409.76009)
			(xy 129.848092 -409.80128) (xy 129.877559 -409.84713) (xy 129.900201 -409.896707) (xy 129.915556 -409.949001)
			(xy 129.923313 -410.002949) (xy 129.923313 -410.057451) (xy 129.923312 -410.057456) (xy 131.360823 -410.057456)
			(xy 131.360823 -410.002944) (xy 131.368581 -409.948986) (xy 131.38394 -409.896681) (xy 131.406586 -409.847095)
			(xy 131.436059 -409.801237) (xy 131.471759 -409.76004) (xy 131.512958 -409.724344) (xy 131.558818 -409.694874)
			(xy 131.608406 -409.672231) (xy 131.660711 -409.656876) (xy 131.71467 -409.649121) (xy 131.741926 -409.64866)
			(xy 132.605526 -409.64866) (xy 132.632774 -409.649212) (xy 132.686714 -409.656971) (xy 132.739001 -409.672327)
			(xy 132.788571 -409.694968) (xy 132.834414 -409.724432) (xy 132.875598 -409.760121) (xy 132.911284 -409.801307)
			(xy 132.940745 -409.847152) (xy 132.963382 -409.896723) (xy 132.978735 -409.949011) (xy 132.98649 -410.002952)
			(xy 132.98649 -410.057448) (xy 132.986489 -410.057452) (xy 134.424146 -410.057452) (xy 134.424146 -410.002948)
			(xy 134.431902 -409.948999) (xy 134.447257 -409.896702) (xy 134.469897 -409.847123) (xy 134.499363 -409.801271)
			(xy 134.535054 -409.760078) (xy 134.576243 -409.724383) (xy 134.622093 -409.694914) (xy 134.67167 -409.672269)
			(xy 134.723965 -409.656909) (xy 134.777914 -409.649148) (xy 134.805166 -409.64866) (xy 135.668766 -409.64866)
			(xy 135.696018 -409.649185) (xy 135.749968 -409.656937) (xy 135.802266 -409.672289) (xy 135.851846 -409.694928)
			(xy 135.8977 -409.724392) (xy 135.938893 -409.760083) (xy 135.974587 -409.801273) (xy 136.004056 -409.847124)
			(xy 136.026699 -409.896702) (xy 136.042055 -409.948999) (xy 136.049813 -410.002948) (xy 136.049813 -410.057452)
			(xy 136.049813 -410.057455) (xy 137.487323 -410.057455) (xy 137.487323 -410.002945) (xy 137.495081 -409.948989)
			(xy 137.510438 -409.896686) (xy 137.533083 -409.847101) (xy 137.562554 -409.801244) (xy 137.598252 -409.760047)
			(xy 137.639449 -409.724351) (xy 137.685306 -409.69488) (xy 137.734891 -409.672236) (xy 137.787194 -409.656879)
			(xy 137.841151 -409.649123) (xy 137.868406 -409.64866) (xy 138.732006 -409.64866) (xy 138.759255 -409.649211)
			(xy 138.813197 -409.656967) (xy 138.865487 -409.672321) (xy 138.915059 -409.694961) (xy 138.960905 -409.724425)
			(xy 139.002091 -409.760113) (xy 139.037779 -409.8013) (xy 139.067242 -409.847146) (xy 139.089881 -409.896719)
			(xy 139.105234 -409.949009) (xy 139.11299 -410.002951) (xy 139.11299 -410.057449) (xy 139.112989 -410.057457)
			(xy 140.550523 -410.057457) (xy 140.550523 -410.002943) (xy 140.558282 -409.948983) (xy 140.573642 -409.896677)
			(xy 140.596289 -409.84709) (xy 140.625764 -409.801231) (xy 140.661466 -409.760033) (xy 140.702667 -409.724337)
			(xy 140.74853 -409.694867) (xy 140.79812 -409.672225) (xy 140.850428 -409.656872) (xy 140.904389 -409.64912)
			(xy 140.931646 -409.64866) (xy 141.795246 -409.64866) (xy 141.822493 -409.649213) (xy 141.876431 -409.656975)
			(xy 141.928716 -409.672332) (xy 141.978283 -409.694974) (xy 142.024124 -409.724439) (xy 142.065305 -409.760128)
			(xy 142.100988 -409.801313) (xy 142.130448 -409.847157) (xy 142.153084 -409.896727) (xy 142.168435 -409.949014)
			(xy 142.17619 -410.002953) (xy 142.17619 -410.057447) (xy 142.176189 -410.057453) (xy 143.613846 -410.057453)
			(xy 143.613846 -410.002947) (xy 143.621603 -409.948996) (xy 143.636958 -409.896698) (xy 143.6596 -409.847118)
			(xy 143.689068 -409.801264) (xy 143.724761 -409.760071) (xy 143.765953 -409.724376) (xy 143.811805 -409.694907)
			(xy 143.861385 -409.672263) (xy 143.913682 -409.656906) (xy 143.967633 -409.649147) (xy 143.994886 -409.64866)
			(xy 144.858486 -409.64866) (xy 144.885737 -409.649186) (xy 144.939685 -409.656941) (xy 144.99198 -409.672295)
			(xy 145.041558 -409.694934) (xy 145.087409 -409.724399) (xy 145.1286 -409.76009) (xy 145.164292 -409.80128)
			(xy 145.193759 -409.84713) (xy 145.216401 -409.896707) (xy 145.231756 -409.949001) (xy 145.239513 -410.002949)
			(xy 145.239513 -410.057451) (xy 145.239512 -410.057456) (xy 146.677023 -410.057456) (xy 146.677023 -410.002944)
			(xy 146.684781 -409.948986) (xy 146.70014 -409.896681) (xy 146.722786 -409.847095) (xy 146.752259 -409.801237)
			(xy 146.787959 -409.76004) (xy 146.829158 -409.724344) (xy 146.875018 -409.694874) (xy 146.924606 -409.672231)
			(xy 146.976911 -409.656876) (xy 147.03087 -409.649121) (xy 147.058126 -409.64866) (xy 147.921726 -409.64866)
			(xy 147.948974 -409.649212) (xy 148.002914 -409.656971) (xy 148.055201 -409.672327) (xy 148.104771 -409.694968)
			(xy 148.150614 -409.724432) (xy 148.191798 -409.760121) (xy 148.227484 -409.801307) (xy 148.256945 -409.847152)
			(xy 148.279582 -409.896723) (xy 148.294935 -409.949011) (xy 148.30269 -410.002952) (xy 148.30269 -410.057448)
			(xy 148.302689 -410.057452) (xy 149.740346 -410.057452) (xy 149.740346 -410.002948) (xy 149.748102 -409.948999)
			(xy 149.763457 -409.896702) (xy 149.786097 -409.847123) (xy 149.815563 -409.801271) (xy 149.851254 -409.760078)
			(xy 149.892443 -409.724383) (xy 149.938293 -409.694914) (xy 149.98787 -409.672269) (xy 150.040165 -409.656909)
			(xy 150.094114 -409.649148) (xy 150.121366 -409.64866) (xy 150.984966 -409.64866) (xy 151.012218 -409.649185)
			(xy 151.066168 -409.656937) (xy 151.118466 -409.672289) (xy 151.168046 -409.694928) (xy 151.2139 -409.724392)
			(xy 151.255093 -409.760083) (xy 151.290787 -409.801273) (xy 151.320256 -409.847124) (xy 151.342899 -409.896702)
			(xy 151.358255 -409.948999) (xy 151.366013 -410.002948) (xy 151.366013 -410.057452) (xy 151.366013 -410.057455)
			(xy 152.803523 -410.057455) (xy 152.803523 -410.002945) (xy 152.811281 -409.948989) (xy 152.826638 -409.896686)
			(xy 152.849283 -409.847101) (xy 152.878754 -409.801244) (xy 152.914452 -409.760047) (xy 152.955649 -409.724351)
			(xy 153.001506 -409.69488) (xy 153.051091 -409.672236) (xy 153.103394 -409.656879) (xy 153.157351 -409.649123)
			(xy 153.184606 -409.64866) (xy 154.048206 -409.64866) (xy 154.075455 -409.649211) (xy 154.129397 -409.656967)
			(xy 154.181687 -409.672321) (xy 154.231259 -409.694961) (xy 154.277105 -409.724425) (xy 154.318291 -409.760113)
			(xy 154.353979 -409.8013) (xy 154.383442 -409.847146) (xy 154.406081 -409.896719) (xy 154.421434 -409.949009)
			(xy 154.42919 -410.002951) (xy 154.42919 -410.057449) (xy 154.429189 -410.057457) (xy 155.866723 -410.057457)
			(xy 155.866723 -410.002943) (xy 155.874482 -409.948983) (xy 155.889842 -409.896677) (xy 155.912489 -409.84709)
			(xy 155.941964 -409.801231) (xy 155.977666 -409.760033) (xy 156.018867 -409.724337) (xy 156.06473 -409.694867)
			(xy 156.11432 -409.672225) (xy 156.166628 -409.656872) (xy 156.220589 -409.64912) (xy 156.247846 -409.64866)
			(xy 157.111446 -409.64866) (xy 157.138693 -409.649213) (xy 157.192631 -409.656975) (xy 157.244916 -409.672332)
			(xy 157.294483 -409.694974) (xy 157.340324 -409.724439) (xy 157.381505 -409.760128) (xy 157.417188 -409.801313)
			(xy 157.446648 -409.847157) (xy 157.469284 -409.896727) (xy 157.484635 -409.949014) (xy 157.49239 -410.002953)
			(xy 157.49239 -410.057447) (xy 157.492389 -410.057453) (xy 158.930046 -410.057453) (xy 158.930046 -410.002947)
			(xy 158.937803 -409.948996) (xy 158.953158 -409.896698) (xy 158.9758 -409.847118) (xy 159.005268 -409.801264)
			(xy 159.040961 -409.760071) (xy 159.082153 -409.724376) (xy 159.128005 -409.694907) (xy 159.177585 -409.672263)
			(xy 159.229882 -409.656906) (xy 159.283833 -409.649147) (xy 159.311086 -409.64866) (xy 160.174686 -409.64866)
			(xy 160.201937 -409.649186) (xy 160.255885 -409.656941) (xy 160.30818 -409.672295) (xy 160.357758 -409.694934)
			(xy 160.403609 -409.724399) (xy 160.4448 -409.76009) (xy 160.480492 -409.80128) (xy 160.509959 -409.84713)
			(xy 160.532601 -409.896707) (xy 160.547956 -409.949001) (xy 160.555713 -410.002949) (xy 160.555713 -410.057451)
			(xy 160.555712 -410.057456) (xy 161.993223 -410.057456) (xy 161.993223 -410.002944) (xy 162.000981 -409.948986)
			(xy 162.01634 -409.896681) (xy 162.038986 -409.847095) (xy 162.068459 -409.801237) (xy 162.104159 -409.76004)
			(xy 162.145358 -409.724344) (xy 162.191218 -409.694874) (xy 162.240806 -409.672231) (xy 162.293111 -409.656876)
			(xy 162.34707 -409.649121) (xy 162.374326 -409.64866) (xy 163.237926 -409.64866) (xy 163.265174 -409.649212)
			(xy 163.319114 -409.656971) (xy 163.371401 -409.672327) (xy 163.420971 -409.694968) (xy 163.466814 -409.724432)
			(xy 163.507998 -409.760121) (xy 163.543684 -409.801307) (xy 163.573145 -409.847152) (xy 163.595782 -409.896723)
			(xy 163.611135 -409.949011) (xy 163.61889 -410.002952) (xy 163.61889 -410.057448) (xy 163.611135 -410.111389)
			(xy 163.595782 -410.163677) (xy 163.573145 -410.213248) (xy 163.543684 -410.259093) (xy 163.507998 -410.300279)
			(xy 163.466814 -410.335968) (xy 163.420971 -410.365432) (xy 163.371401 -410.388073) (xy 163.319114 -410.403429)
			(xy 163.265174 -410.411188) (xy 163.237926 -410.411676) (xy 162.374326 -410.411676) (xy 162.34707 -410.411279)
			(xy 162.293111 -410.403524) (xy 162.240806 -410.388169) (xy 162.191218 -410.365526) (xy 162.145358 -410.336056)
			(xy 162.104159 -410.30036) (xy 162.068459 -410.259163) (xy 162.038986 -410.213305) (xy 162.01634 -410.163719)
			(xy 162.000981 -410.111414) (xy 161.993223 -410.057456) (xy 160.555712 -410.057456) (xy 160.547956 -410.111399)
			(xy 160.532601 -410.163693) (xy 160.509959 -410.21327) (xy 160.480492 -410.25912) (xy 160.4448 -410.30031)
			(xy 160.403609 -410.336001) (xy 160.357758 -410.365466) (xy 160.30818 -410.388105) (xy 160.255885 -410.403459)
			(xy 160.201937 -410.411214) (xy 160.174686 -410.411676) (xy 159.311086 -410.411676) (xy 159.283833 -410.411253)
			(xy 159.229882 -410.403494) (xy 159.177585 -410.388137) (xy 159.128005 -410.365493) (xy 159.082153 -410.336024)
			(xy 159.040961 -410.300329) (xy 159.005268 -410.259136) (xy 158.9758 -410.213282) (xy 158.953158 -410.163702)
			(xy 158.937803 -410.111404) (xy 158.930046 -410.057453) (xy 157.492389 -410.057453) (xy 157.484635 -410.111386)
			(xy 157.469284 -410.163673) (xy 157.446648 -410.213243) (xy 157.417188 -410.259087) (xy 157.381505 -410.300272)
			(xy 157.340324 -410.335961) (xy 157.294483 -410.365426) (xy 157.244916 -410.388068) (xy 157.192631 -410.403425)
			(xy 157.138693 -410.411187) (xy 157.111446 -410.411676) (xy 156.247846 -410.411676) (xy 156.220589 -410.41128)
			(xy 156.166628 -410.403528) (xy 156.11432 -410.388175) (xy 156.06473 -410.365533) (xy 156.018867 -410.336063)
			(xy 155.977666 -410.300367) (xy 155.941964 -410.259169) (xy 155.912489 -410.21331) (xy 155.889842 -410.163723)
			(xy 155.874482 -410.111417) (xy 155.866723 -410.057457) (xy 154.429189 -410.057457) (xy 154.421434 -410.111391)
			(xy 154.406081 -410.163681) (xy 154.383442 -410.213254) (xy 154.353979 -410.2591) (xy 154.318291 -410.300287)
			(xy 154.277105 -410.335975) (xy 154.231259 -410.365439) (xy 154.181687 -410.388079) (xy 154.129397 -410.403433)
			(xy 154.075455 -410.411189) (xy 154.048206 -410.411676) (xy 153.184606 -410.411676) (xy 153.157351 -410.411277)
			(xy 153.103394 -410.403521) (xy 153.051091 -410.388164) (xy 153.001506 -410.36552) (xy 152.955649 -410.336049)
			(xy 152.914452 -410.300353) (xy 152.878754 -410.259156) (xy 152.849283 -410.213299) (xy 152.826638 -410.163714)
			(xy 152.811281 -410.111411) (xy 152.803523 -410.057455) (xy 151.366013 -410.057455) (xy 151.358255 -410.111402)
			(xy 151.342899 -410.163698) (xy 151.320256 -410.213276) (xy 151.290787 -410.259127) (xy 151.255093 -410.300317)
			(xy 151.2139 -410.336008) (xy 151.168046 -410.365472) (xy 151.118466 -410.388111) (xy 151.066168 -410.403463)
			(xy 151.012218 -410.411215) (xy 150.984966 -410.411676) (xy 150.121366 -410.411676) (xy 150.094114 -410.411252)
			(xy 150.040165 -410.403491) (xy 149.98787 -410.388131) (xy 149.938293 -410.365486) (xy 149.892443 -410.336017)
			(xy 149.851254 -410.300322) (xy 149.815563 -410.259129) (xy 149.786097 -410.213277) (xy 149.763457 -410.163698)
			(xy 149.748102 -410.111401) (xy 149.740346 -410.057452) (xy 148.302689 -410.057452) (xy 148.294935 -410.111389)
			(xy 148.279582 -410.163677) (xy 148.256945 -410.213248) (xy 148.227484 -410.259093) (xy 148.191798 -410.300279)
			(xy 148.150614 -410.335968) (xy 148.104771 -410.365432) (xy 148.055201 -410.388073) (xy 148.002914 -410.403429)
			(xy 147.948974 -410.411188) (xy 147.921726 -410.411676) (xy 147.058126 -410.411676) (xy 147.03087 -410.411279)
			(xy 146.976911 -410.403524) (xy 146.924606 -410.388169) (xy 146.875018 -410.365526) (xy 146.829158 -410.336056)
			(xy 146.787959 -410.30036) (xy 146.752259 -410.259163) (xy 146.722786 -410.213305) (xy 146.70014 -410.163719)
			(xy 146.684781 -410.111414) (xy 146.677023 -410.057456) (xy 145.239512 -410.057456) (xy 145.231756 -410.111399)
			(xy 145.216401 -410.163693) (xy 145.193759 -410.21327) (xy 145.164292 -410.25912) (xy 145.1286 -410.30031)
			(xy 145.087409 -410.336001) (xy 145.041558 -410.365466) (xy 144.99198 -410.388105) (xy 144.939685 -410.403459)
			(xy 144.885737 -410.411214) (xy 144.858486 -410.411676) (xy 143.994886 -410.411676) (xy 143.967633 -410.411253)
			(xy 143.913682 -410.403494) (xy 143.861385 -410.388137) (xy 143.811805 -410.365493) (xy 143.765953 -410.336024)
			(xy 143.724761 -410.300329) (xy 143.689068 -410.259136) (xy 143.6596 -410.213282) (xy 143.636958 -410.163702)
			(xy 143.621603 -410.111404) (xy 143.613846 -410.057453) (xy 142.176189 -410.057453) (xy 142.168435 -410.111386)
			(xy 142.153084 -410.163673) (xy 142.130448 -410.213243) (xy 142.100988 -410.259087) (xy 142.065305 -410.300272)
			(xy 142.024124 -410.335961) (xy 141.978283 -410.365426) (xy 141.928716 -410.388068) (xy 141.876431 -410.403425)
			(xy 141.822493 -410.411187) (xy 141.795246 -410.411676) (xy 140.931646 -410.411676) (xy 140.904389 -410.41128)
			(xy 140.850428 -410.403528) (xy 140.79812 -410.388175) (xy 140.74853 -410.365533) (xy 140.702667 -410.336063)
			(xy 140.661466 -410.300367) (xy 140.625764 -410.259169) (xy 140.596289 -410.21331) (xy 140.573642 -410.163723)
			(xy 140.558282 -410.111417) (xy 140.550523 -410.057457) (xy 139.112989 -410.057457) (xy 139.105234 -410.111391)
			(xy 139.089881 -410.163681) (xy 139.067242 -410.213254) (xy 139.037779 -410.2591) (xy 139.002091 -410.300287)
			(xy 138.960905 -410.335975) (xy 138.915059 -410.365439) (xy 138.865487 -410.388079) (xy 138.813197 -410.403433)
			(xy 138.759255 -410.411189) (xy 138.732006 -410.411676) (xy 137.868406 -410.411676) (xy 137.841151 -410.411277)
			(xy 137.787194 -410.403521) (xy 137.734891 -410.388164) (xy 137.685306 -410.36552) (xy 137.639449 -410.336049)
			(xy 137.598252 -410.300353) (xy 137.562554 -410.259156) (xy 137.533083 -410.213299) (xy 137.510438 -410.163714)
			(xy 137.495081 -410.111411) (xy 137.487323 -410.057455) (xy 136.049813 -410.057455) (xy 136.042055 -410.111402)
			(xy 136.026699 -410.163698) (xy 136.004056 -410.213276) (xy 135.974587 -410.259127) (xy 135.938893 -410.300317)
			(xy 135.8977 -410.336008) (xy 135.851846 -410.365472) (xy 135.802266 -410.388111) (xy 135.749968 -410.403463)
			(xy 135.696018 -410.411215) (xy 135.668766 -410.411676) (xy 134.805166 -410.411676) (xy 134.777914 -410.411252)
			(xy 134.723965 -410.403491) (xy 134.67167 -410.388131) (xy 134.622093 -410.365486) (xy 134.576243 -410.336017)
			(xy 134.535054 -410.300322) (xy 134.499363 -410.259129) (xy 134.469897 -410.213277) (xy 134.447257 -410.163698)
			(xy 134.431902 -410.111401) (xy 134.424146 -410.057452) (xy 132.986489 -410.057452) (xy 132.978735 -410.111389)
			(xy 132.963382 -410.163677) (xy 132.940745 -410.213248) (xy 132.911284 -410.259093) (xy 132.875598 -410.300279)
			(xy 132.834414 -410.335968) (xy 132.788571 -410.365432) (xy 132.739001 -410.388073) (xy 132.686714 -410.403429)
			(xy 132.632774 -410.411188) (xy 132.605526 -410.411676) (xy 131.741926 -410.411676) (xy 131.71467 -410.411279)
			(xy 131.660711 -410.403524) (xy 131.608406 -410.388169) (xy 131.558818 -410.365526) (xy 131.512958 -410.336056)
			(xy 131.471759 -410.30036) (xy 131.436059 -410.259163) (xy 131.406586 -410.213305) (xy 131.38394 -410.163719)
			(xy 131.368581 -410.111414) (xy 131.360823 -410.057456) (xy 129.923312 -410.057456) (xy 129.915556 -410.111399)
			(xy 129.900201 -410.163693) (xy 129.877559 -410.21327) (xy 129.848092 -410.25912) (xy 129.8124 -410.30031)
			(xy 129.771209 -410.336001) (xy 129.725358 -410.365466) (xy 129.67578 -410.388105) (xy 129.623485 -410.403459)
			(xy 129.569537 -410.411214) (xy 129.542286 -410.411676) (xy 128.678686 -410.411676) (xy 128.651433 -410.411253)
			(xy 128.597482 -410.403494) (xy 128.545185 -410.388137) (xy 128.495605 -410.365493) (xy 128.449753 -410.336024)
			(xy 128.408561 -410.300329) (xy 128.372868 -410.259136) (xy 128.3434 -410.213282) (xy 128.320758 -410.163702)
			(xy 128.305403 -410.111404) (xy 128.297646 -410.057453) (xy 126.859989 -410.057453) (xy 126.852235 -410.111386)
			(xy 126.836884 -410.163673) (xy 126.814248 -410.213243) (xy 126.784788 -410.259087) (xy 126.749105 -410.300272)
			(xy 126.707924 -410.335961) (xy 126.662083 -410.365426) (xy 126.612516 -410.388068) (xy 126.560231 -410.403425)
			(xy 126.506293 -410.411187) (xy 126.479046 -410.411676) (xy 125.615446 -410.411676) (xy 125.588189 -410.41128)
			(xy 125.534228 -410.403528) (xy 125.48192 -410.388175) (xy 125.43233 -410.365533) (xy 125.386467 -410.336063)
			(xy 125.345266 -410.300367) (xy 125.309564 -410.259169) (xy 125.280089 -410.21331) (xy 125.257442 -410.163723)
			(xy 125.242082 -410.111417) (xy 125.234323 -410.057457) (xy 123.796789 -410.057457) (xy 123.789034 -410.111391)
			(xy 123.773681 -410.163681) (xy 123.751042 -410.213254) (xy 123.721579 -410.2591) (xy 123.685891 -410.300287)
			(xy 123.644705 -410.335975) (xy 123.598859 -410.365439) (xy 123.549287 -410.388079) (xy 123.496997 -410.403433)
			(xy 123.443055 -410.411189) (xy 123.415806 -410.411676) (xy 122.552206 -410.411676) (xy 122.524951 -410.411277)
			(xy 122.470994 -410.403521) (xy 122.418691 -410.388164) (xy 122.369106 -410.36552) (xy 122.323249 -410.336049)
			(xy 122.282052 -410.300353) (xy 122.246354 -410.259156) (xy 122.216883 -410.213299) (xy 122.194238 -410.163714)
			(xy 122.178881 -410.111411) (xy 122.171123 -410.057455) (xy 120.733613 -410.057455) (xy 120.725855 -410.111402)
			(xy 120.710499 -410.163698) (xy 120.687856 -410.213276) (xy 120.658387 -410.259127) (xy 120.622693 -410.300317)
			(xy 120.5815 -410.336008) (xy 120.535646 -410.365472) (xy 120.486066 -410.388111) (xy 120.433768 -410.403463)
			(xy 120.379818 -410.411215) (xy 120.352566 -410.411676) (xy 119.488966 -410.411676) (xy 119.461714 -410.411252)
			(xy 119.407765 -410.403491) (xy 119.35547 -410.388131) (xy 119.305893 -410.365486) (xy 119.260043 -410.336017)
			(xy 119.218854 -410.300322) (xy 119.183163 -410.259129) (xy 119.153697 -410.213277) (xy 119.131057 -410.163698)
			(xy 119.115702 -410.111401) (xy 119.107946 -410.057452) (xy 117.670289 -410.057452) (xy 117.662535 -410.111389)
			(xy 117.647182 -410.163677) (xy 117.624545 -410.213248) (xy 117.595084 -410.259093) (xy 117.559398 -410.300279)
			(xy 117.518214 -410.335968) (xy 117.472371 -410.365432) (xy 117.422801 -410.388073) (xy 117.370514 -410.403429)
			(xy 117.316574 -410.411188) (xy 117.289326 -410.411676) (xy 116.425726 -410.411676) (xy 116.39847 -410.411279)
			(xy 116.344511 -410.403524) (xy 116.292206 -410.388169) (xy 116.242618 -410.365526) (xy 116.196758 -410.336056)
			(xy 116.155559 -410.30036) (xy 116.119859 -410.259163) (xy 116.090386 -410.213305) (xy 116.06774 -410.163719)
			(xy 116.052381 -410.111414) (xy 116.044623 -410.057456) (xy 111.28975 -410.057456) (xy 111.276373 -410.086747)
			(xy 111.246907 -410.132597) (xy 111.211216 -410.173788) (xy 111.170025 -410.209479) (xy 111.124175 -410.238945)
			(xy 111.074598 -410.261587) (xy 111.022303 -410.276942) (xy 110.968355 -410.284698) (xy 110.913853 -410.284698)
			(xy 110.859905 -410.276942) (xy 110.80761 -410.261587) (xy 110.758033 -410.238945) (xy 110.712183 -410.209479)
			(xy 110.670992 -410.173788) (xy 110.635301 -410.132597) (xy 110.605835 -410.086747) (xy 110.583193 -410.03717)
			(xy 110.567838 -409.984875) (xy 110.560082 -409.930927) (xy 110.559596 -409.903676) (xy 102.748244 -409.903676)
			(xy 102.708181 -409.921973) (xy 102.655851 -409.937338) (xy 102.601867 -409.9451) (xy 102.547329 -409.9451)
			(xy 102.493345 -409.937338) (xy 102.441015 -409.921973) (xy 102.391405 -409.899316) (xy 102.345524 -409.86983)
			(xy 102.304307 -409.834115) (xy 102.268592 -409.792898) (xy 102.239106 -409.747017) (xy 102.216449 -409.697407)
			(xy 102.201084 -409.645077) (xy 102.193322 -409.591093) (xy 102.192836 -409.563824) (xy 37.697664 -409.563824)
			(xy 38.191293 -410.057453) (xy 48.944746 -410.057453) (xy 48.944746 -410.002947) (xy 48.952503 -409.948996)
			(xy 48.967858 -409.896698) (xy 48.9905 -409.847118) (xy 49.019967 -409.801265) (xy 49.05566 -409.760071)
			(xy 49.096852 -409.724377) (xy 49.142704 -409.694908) (xy 49.192283 -409.672264) (xy 49.244581 -409.656906)
			(xy 49.298531 -409.649147) (xy 49.325784 -409.64866) (xy 50.189384 -409.64866) (xy 50.216635 -409.649186)
			(xy 50.270583 -409.656941) (xy 50.322879 -409.672294) (xy 50.372457 -409.694934) (xy 50.418308 -409.724399)
			(xy 50.459499 -409.760089) (xy 50.495192 -409.801279) (xy 50.524659 -409.847129) (xy 50.5473 -409.896706)
			(xy 50.562656 -409.949001) (xy 50.570413 -410.002949) (xy 50.570413 -410.057451) (xy 50.570412 -410.057456)
			(xy 52.007923 -410.057456) (xy 52.007923 -410.002944) (xy 52.015681 -409.948986) (xy 52.03104 -409.896682)
			(xy 52.053686 -409.847096) (xy 52.083159 -409.801238) (xy 52.118858 -409.760041) (xy 52.160057 -409.724344)
			(xy 52.205917 -409.694874) (xy 52.255504 -409.672231) (xy 52.30781 -409.656876) (xy 52.361768 -409.649121)
			(xy 52.389024 -409.64866) (xy 53.252624 -409.64866) (xy 53.279872 -409.649212) (xy 53.333812 -409.65697)
			(xy 53.3861 -409.672326) (xy 53.43567 -409.694967) (xy 53.481513 -409.724431) (xy 53.522697 -409.76012)
			(xy 53.558383 -409.801306) (xy 53.587845 -409.847151) (xy 53.610482 -409.896723) (xy 53.625835 -409.949011)
			(xy 53.63359 -410.002952) (xy 53.63359 -410.057448) (xy 53.633589 -410.057452) (xy 55.071246 -410.057452)
			(xy 55.071246 -410.002948) (xy 55.079002 -409.948999) (xy 55.094357 -409.896703) (xy 55.116997 -409.847124)
			(xy 55.146462 -409.801271) (xy 55.182153 -409.760079) (xy 55.223342 -409.724384) (xy 55.269192 -409.694914)
			(xy 55.318769 -409.672269) (xy 55.371064 -409.65691) (xy 55.425012 -409.649148) (xy 55.452264 -409.64866)
			(xy 56.315864 -409.64866) (xy 56.343116 -409.649185) (xy 56.397067 -409.656937) (xy 56.449364 -409.672289)
			(xy 56.498945 -409.694927) (xy 56.544799 -409.724392) (xy 56.585992 -409.760082) (xy 56.621687 -409.801273)
			(xy 56.651156 -409.847124) (xy 56.673799 -409.896702) (xy 56.689155 -409.948998) (xy 56.696913 -410.002948)
			(xy 56.696913 -410.057452) (xy 56.696913 -410.057455) (xy 58.134423 -410.057455) (xy 58.134423 -410.002945)
			(xy 58.142181 -409.948989) (xy 58.157538 -409.896686) (xy 58.180183 -409.847102) (xy 58.209654 -409.801244)
			(xy 58.245351 -409.760048) (xy 58.286548 -409.724351) (xy 58.332405 -409.694881) (xy 58.38199 -409.672237)
			(xy 58.434293 -409.65688) (xy 58.488249 -409.649123) (xy 58.515504 -409.64866) (xy 59.379104 -409.64866)
			(xy 59.406353 -409.64921) (xy 59.460295 -409.656967) (xy 59.512585 -409.672321) (xy 59.562158 -409.69496)
			(xy 59.608004 -409.724424) (xy 59.64919 -409.760113) (xy 59.684878 -409.801299) (xy 59.714342 -409.847146)
			(xy 59.73698 -409.896718) (xy 59.752334 -409.949008) (xy 59.76009 -410.002951) (xy 59.76009 -410.057449)
			(xy 59.760089 -410.057457) (xy 61.197623 -410.057457) (xy 61.197623 -410.002943) (xy 61.205382 -409.948983)
			(xy 61.220741 -409.896678) (xy 61.243389 -409.84709) (xy 61.272864 -409.801231) (xy 61.308565 -409.760034)
			(xy 61.349767 -409.724337) (xy 61.395629 -409.694868) (xy 61.445219 -409.672226) (xy 61.497527 -409.656872)
			(xy 61.551487 -409.64912) (xy 61.578744 -409.64866) (xy 62.442344 -409.64866) (xy 62.469591 -409.649213)
			(xy 62.523529 -409.656974) (xy 62.575814 -409.672332) (xy 62.625382 -409.694973) (xy 62.671223 -409.724438)
			(xy 62.712404 -409.760127) (xy 62.748088 -409.801313) (xy 62.777548 -409.847157) (xy 62.800184 -409.896727)
			(xy 62.815535 -409.949014) (xy 62.82329 -410.002953) (xy 62.82329 -410.057447) (xy 62.823289 -410.057453)
			(xy 64.260946 -410.057453) (xy 64.260946 -410.002947) (xy 64.268703 -409.948996) (xy 64.284058 -409.896698)
			(xy 64.3067 -409.847118) (xy 64.336167 -409.801265) (xy 64.37186 -409.760071) (xy 64.413052 -409.724377)
			(xy 64.458904 -409.694908) (xy 64.508483 -409.672264) (xy 64.560781 -409.656906) (xy 64.614731 -409.649147)
			(xy 64.641984 -409.64866) (xy 65.505584 -409.64866) (xy 65.532835 -409.649186) (xy 65.586783 -409.656941)
			(xy 65.639079 -409.672294) (xy 65.688657 -409.694934) (xy 65.734508 -409.724399) (xy 65.775699 -409.760089)
			(xy 65.811392 -409.801279) (xy 65.840859 -409.847129) (xy 65.8635 -409.896706) (xy 65.878856 -409.949001)
			(xy 65.886613 -410.002949) (xy 65.886613 -410.057451) (xy 65.886612 -410.057456) (xy 67.324123 -410.057456)
			(xy 67.324123 -410.002944) (xy 67.331881 -409.948986) (xy 67.34724 -409.896682) (xy 67.369886 -409.847096)
			(xy 67.399359 -409.801238) (xy 67.435058 -409.760041) (xy 67.476257 -409.724344) (xy 67.522117 -409.694874)
			(xy 67.571704 -409.672231) (xy 67.62401 -409.656876) (xy 67.677968 -409.649121) (xy 67.705224 -409.64866)
			(xy 68.568824 -409.64866) (xy 68.596072 -409.649212) (xy 68.650012 -409.65697) (xy 68.7023 -409.672326)
			(xy 68.75187 -409.694967) (xy 68.797713 -409.724431) (xy 68.838897 -409.76012) (xy 68.874583 -409.801306)
			(xy 68.904045 -409.847151) (xy 68.926682 -409.896723) (xy 68.942035 -409.949011) (xy 68.94979 -410.002952)
			(xy 68.94979 -410.057448) (xy 68.949789 -410.057452) (xy 70.387446 -410.057452) (xy 70.387446 -410.002948)
			(xy 70.395202 -409.948999) (xy 70.410557 -409.896703) (xy 70.433197 -409.847124) (xy 70.462662 -409.801271)
			(xy 70.498353 -409.760079) (xy 70.539542 -409.724384) (xy 70.585392 -409.694914) (xy 70.634969 -409.672269)
			(xy 70.687264 -409.65691) (xy 70.741212 -409.649148) (xy 70.768464 -409.64866) (xy 71.632064 -409.64866)
			(xy 71.659316 -409.649185) (xy 71.713267 -409.656937) (xy 71.765564 -409.672289) (xy 71.815145 -409.694927)
			(xy 71.860999 -409.724392) (xy 71.902192 -409.760082) (xy 71.937887 -409.801273) (xy 71.967356 -409.847124)
			(xy 71.989999 -409.896702) (xy 72.005355 -409.948998) (xy 72.013113 -410.002948) (xy 72.013113 -410.057452)
			(xy 72.013113 -410.057455) (xy 73.450623 -410.057455) (xy 73.450623 -410.002945) (xy 73.458381 -409.948989)
			(xy 73.473738 -409.896686) (xy 73.496383 -409.847102) (xy 73.525854 -409.801244) (xy 73.561551 -409.760048)
			(xy 73.602748 -409.724351) (xy 73.648605 -409.694881) (xy 73.69819 -409.672237) (xy 73.750493 -409.65688)
			(xy 73.804449 -409.649123) (xy 73.831704 -409.64866) (xy 74.695304 -409.64866) (xy 74.722553 -409.64921)
			(xy 74.776495 -409.656967) (xy 74.828785 -409.672321) (xy 74.878358 -409.69496) (xy 74.924204 -409.724424)
			(xy 74.96539 -409.760113) (xy 75.001078 -409.801299) (xy 75.030542 -409.847146) (xy 75.05318 -409.896718)
			(xy 75.068534 -409.949008) (xy 75.07629 -410.002951) (xy 75.07629 -410.057449) (xy 75.076289 -410.057457)
			(xy 76.513823 -410.057457) (xy 76.513823 -410.002943) (xy 76.521582 -409.948983) (xy 76.536941 -409.896678)
			(xy 76.559589 -409.84709) (xy 76.589064 -409.801231) (xy 76.624765 -409.760034) (xy 76.665967 -409.724337)
			(xy 76.711829 -409.694868) (xy 76.761419 -409.672226) (xy 76.813727 -409.656872) (xy 76.867687 -409.64912)
			(xy 76.894944 -409.64866) (xy 77.758544 -409.64866) (xy 77.785791 -409.649213) (xy 77.839729 -409.656974)
			(xy 77.892014 -409.672332) (xy 77.941582 -409.694973) (xy 77.987423 -409.724438) (xy 78.028604 -409.760127)
			(xy 78.064288 -409.801313) (xy 78.093748 -409.847157) (xy 78.116384 -409.896727) (xy 78.131735 -409.949014)
			(xy 78.13949 -410.002953) (xy 78.13949 -410.057447) (xy 78.139489 -410.057453) (xy 79.577146 -410.057453)
			(xy 79.577146 -410.002947) (xy 79.584903 -409.948996) (xy 79.600258 -409.896698) (xy 79.6229 -409.847118)
			(xy 79.652367 -409.801265) (xy 79.68806 -409.760071) (xy 79.729252 -409.724377) (xy 79.775104 -409.694908)
			(xy 79.824683 -409.672264) (xy 79.876981 -409.656906) (xy 79.930931 -409.649147) (xy 79.958184 -409.64866)
			(xy 80.821784 -409.64866) (xy 80.849035 -409.649186) (xy 80.902983 -409.656941) (xy 80.955279 -409.672294)
			(xy 81.004857 -409.694934) (xy 81.050708 -409.724399) (xy 81.091899 -409.760089) (xy 81.127592 -409.801279)
			(xy 81.157059 -409.847129) (xy 81.1797 -409.896706) (xy 81.195056 -409.949001) (xy 81.202813 -410.002949)
			(xy 81.202813 -410.057451) (xy 81.202812 -410.057456) (xy 82.640323 -410.057456) (xy 82.640323 -410.002944)
			(xy 82.648081 -409.948986) (xy 82.66344 -409.896682) (xy 82.686086 -409.847096) (xy 82.715559 -409.801238)
			(xy 82.751258 -409.760041) (xy 82.792457 -409.724344) (xy 82.838317 -409.694874) (xy 82.887904 -409.672231)
			(xy 82.94021 -409.656876) (xy 82.994168 -409.649121) (xy 83.021424 -409.64866) (xy 83.885024 -409.64866)
			(xy 83.912272 -409.649212) (xy 83.966212 -409.65697) (xy 84.0185 -409.672326) (xy 84.06807 -409.694967)
			(xy 84.113913 -409.724431) (xy 84.155097 -409.76012) (xy 84.190783 -409.801306) (xy 84.220245 -409.847151)
			(xy 84.242882 -409.896723) (xy 84.258235 -409.949011) (xy 84.26599 -410.002952) (xy 84.26599 -410.057448)
			(xy 84.265989 -410.057452) (xy 85.703646 -410.057452) (xy 85.703646 -410.002948) (xy 85.711402 -409.948999)
			(xy 85.726757 -409.896703) (xy 85.749397 -409.847124) (xy 85.778862 -409.801271) (xy 85.814553 -409.760079)
			(xy 85.855742 -409.724384) (xy 85.901592 -409.694914) (xy 85.951169 -409.672269) (xy 86.003464 -409.65691)
			(xy 86.057412 -409.649148) (xy 86.084664 -409.64866) (xy 86.948264 -409.64866) (xy 86.975516 -409.649185)
			(xy 87.029467 -409.656937) (xy 87.081764 -409.672289) (xy 87.131345 -409.694927) (xy 87.177199 -409.724392)
			(xy 87.218392 -409.760082) (xy 87.254087 -409.801273) (xy 87.283556 -409.847124) (xy 87.306199 -409.896702)
			(xy 87.321555 -409.948998) (xy 87.329313 -410.002948) (xy 87.329313 -410.057452) (xy 87.329313 -410.057455)
			(xy 88.766823 -410.057455) (xy 88.766823 -410.002945) (xy 88.774581 -409.948989) (xy 88.789938 -409.896686)
			(xy 88.812583 -409.847102) (xy 88.842054 -409.801244) (xy 88.877751 -409.760048) (xy 88.918948 -409.724351)
			(xy 88.964805 -409.694881) (xy 89.01439 -409.672237) (xy 89.066693 -409.65688) (xy 89.120649 -409.649123)
			(xy 89.147904 -409.64866) (xy 90.011504 -409.64866) (xy 90.038753 -409.64921) (xy 90.092695 -409.656967)
			(xy 90.144985 -409.672321) (xy 90.194558 -409.69496) (xy 90.240404 -409.724424) (xy 90.28159 -409.760113)
			(xy 90.317278 -409.801299) (xy 90.346742 -409.847146) (xy 90.36938 -409.896718) (xy 90.384734 -409.949008)
			(xy 90.39249 -410.002951) (xy 90.39249 -410.057449) (xy 90.392489 -410.057457) (xy 91.830023 -410.057457)
			(xy 91.830023 -410.002943) (xy 91.837782 -409.948983) (xy 91.853141 -409.896678) (xy 91.875789 -409.84709)
			(xy 91.905264 -409.801231) (xy 91.940965 -409.760034) (xy 91.982167 -409.724337) (xy 92.028029 -409.694868)
			(xy 92.077619 -409.672226) (xy 92.129927 -409.656872) (xy 92.183887 -409.64912) (xy 92.211144 -409.64866)
			(xy 93.074744 -409.64866) (xy 93.101991 -409.649213) (xy 93.155929 -409.656974) (xy 93.208214 -409.672332)
			(xy 93.257782 -409.694973) (xy 93.303623 -409.724438) (xy 93.344804 -409.760127) (xy 93.380488 -409.801313)
			(xy 93.409948 -409.847157) (xy 93.432584 -409.896727) (xy 93.447935 -409.949014) (xy 93.45569 -410.002953)
			(xy 93.45569 -410.057447) (xy 93.455689 -410.057453) (xy 94.893346 -410.057453) (xy 94.893346 -410.002947)
			(xy 94.901103 -409.948996) (xy 94.916458 -409.896698) (xy 94.9391 -409.847118) (xy 94.968567 -409.801265)
			(xy 95.00426 -409.760071) (xy 95.045452 -409.724377) (xy 95.091304 -409.694908) (xy 95.140883 -409.672264)
			(xy 95.193181 -409.656906) (xy 95.247131 -409.649147) (xy 95.274384 -409.64866) (xy 96.137984 -409.64866)
			(xy 96.165235 -409.649186) (xy 96.219183 -409.656941) (xy 96.271479 -409.672294) (xy 96.321057 -409.694934)
			(xy 96.366908 -409.724399) (xy 96.408099 -409.760089) (xy 96.443792 -409.801279) (xy 96.473259 -409.847129)
			(xy 96.4959 -409.896706) (xy 96.511256 -409.949001) (xy 96.519013 -410.002949) (xy 96.519013 -410.057451)
			(xy 96.511256 -410.111399) (xy 96.4959 -410.163694) (xy 96.473259 -410.213271) (xy 96.443792 -410.259121)
			(xy 96.408099 -410.300311) (xy 96.366908 -410.336001) (xy 96.321057 -410.365466) (xy 96.271479 -410.388106)
			(xy 96.219183 -410.403459) (xy 96.165235 -410.411214) (xy 96.137984 -410.411676) (xy 95.274384 -410.411676)
			(xy 95.247131 -410.411253) (xy 95.193181 -410.403494) (xy 95.140883 -410.388136) (xy 95.091304 -410.365492)
			(xy 95.045452 -410.336023) (xy 95.00426 -410.300329) (xy 94.968567 -410.259135) (xy 94.9391 -410.213282)
			(xy 94.916458 -410.163702) (xy 94.901103 -410.111404) (xy 94.893346 -410.057453) (xy 93.455689 -410.057453)
			(xy 93.447935 -410.111386) (xy 93.432584 -410.163673) (xy 93.409948 -410.213243) (xy 93.380488 -410.259087)
			(xy 93.344804 -410.300273) (xy 93.303623 -410.335962) (xy 93.257782 -410.365427) (xy 93.208214 -410.388068)
			(xy 93.155929 -410.403426) (xy 93.101991 -410.411187) (xy 93.074744 -410.411676) (xy 92.211144 -410.411676)
			(xy 92.183887 -410.41128) (xy 92.129927 -410.403528) (xy 92.077619 -410.388174) (xy 92.028029 -410.365532)
			(xy 91.982167 -410.336063) (xy 91.940965 -410.300366) (xy 91.905264 -410.259169) (xy 91.875789 -410.21331)
			(xy 91.853141 -410.163722) (xy 91.837782 -410.111417) (xy 91.830023 -410.057457) (xy 90.392489 -410.057457)
			(xy 90.384734 -410.111392) (xy 90.36938 -410.163682) (xy 90.346742 -410.213254) (xy 90.317278 -410.259101)
			(xy 90.28159 -410.300287) (xy 90.240404 -410.335976) (xy 90.194558 -410.36544) (xy 90.144985 -410.388079)
			(xy 90.092695 -410.403433) (xy 90.038753 -410.41119) (xy 90.011504 -410.411676) (xy 89.147904 -410.411676)
			(xy 89.120649 -410.411277) (xy 89.066693 -410.40352) (xy 89.01439 -410.388163) (xy 88.964805 -410.365519)
			(xy 88.918948 -410.336049) (xy 88.877751 -410.300352) (xy 88.842054 -410.259156) (xy 88.812583 -410.213298)
			(xy 88.789938 -410.163714) (xy 88.774581 -410.111411) (xy 88.766823 -410.057455) (xy 87.329313 -410.057455)
			(xy 87.321555 -410.111402) (xy 87.306199 -410.163698) (xy 87.283556 -410.213276) (xy 87.254087 -410.259127)
			(xy 87.218392 -410.300318) (xy 87.177199 -410.336008) (xy 87.131345 -410.365473) (xy 87.081764 -410.388111)
			(xy 87.029467 -410.403463) (xy 86.975516 -410.411215) (xy 86.948264 -410.411676) (xy 86.084664 -410.411676)
			(xy 86.057412 -410.411252) (xy 86.003464 -410.40349) (xy 85.951169 -410.388131) (xy 85.901592 -410.365486)
			(xy 85.855742 -410.336016) (xy 85.814553 -410.300321) (xy 85.778862 -410.259129) (xy 85.749397 -410.213276)
			(xy 85.726757 -410.163697) (xy 85.711402 -410.111401) (xy 85.703646 -410.057452) (xy 84.265989 -410.057452)
			(xy 84.258235 -410.111389) (xy 84.242882 -410.163677) (xy 84.220245 -410.213249) (xy 84.190783 -410.259094)
			(xy 84.155097 -410.30028) (xy 84.113913 -410.335969) (xy 84.06807 -410.365433) (xy 84.0185 -410.388074)
			(xy 83.966212 -410.40343) (xy 83.912272 -410.411188) (xy 83.885024 -410.411676) (xy 83.021424 -410.411676)
			(xy 82.994168 -410.411279) (xy 82.94021 -410.403524) (xy 82.887904 -410.388169) (xy 82.838317 -410.365526)
			(xy 82.792457 -410.336056) (xy 82.751258 -410.300359) (xy 82.715559 -410.259162) (xy 82.686086 -410.213304)
			(xy 82.66344 -410.163718) (xy 82.648081 -410.111414) (xy 82.640323 -410.057456) (xy 81.202812 -410.057456)
			(xy 81.195056 -410.111399) (xy 81.1797 -410.163694) (xy 81.157059 -410.213271) (xy 81.127592 -410.259121)
			(xy 81.091899 -410.300311) (xy 81.050708 -410.336001) (xy 81.004857 -410.365466) (xy 80.955279 -410.388106)
			(xy 80.902983 -410.403459) (xy 80.849035 -410.411214) (xy 80.821784 -410.411676) (xy 79.958184 -410.411676)
			(xy 79.930931 -410.411253) (xy 79.876981 -410.403494) (xy 79.824683 -410.388136) (xy 79.775104 -410.365492)
			(xy 79.729252 -410.336023) (xy 79.68806 -410.300329) (xy 79.652367 -410.259135) (xy 79.6229 -410.213282)
			(xy 79.600258 -410.163702) (xy 79.584903 -410.111404) (xy 79.577146 -410.057453) (xy 78.139489 -410.057453)
			(xy 78.131735 -410.111386) (xy 78.116384 -410.163673) (xy 78.093748 -410.213243) (xy 78.064288 -410.259087)
			(xy 78.028604 -410.300273) (xy 77.987423 -410.335962) (xy 77.941582 -410.365427) (xy 77.892014 -410.388068)
			(xy 77.839729 -410.403426) (xy 77.785791 -410.411187) (xy 77.758544 -410.411676) (xy 76.894944 -410.411676)
			(xy 76.867687 -410.41128) (xy 76.813727 -410.403528) (xy 76.761419 -410.388174) (xy 76.711829 -410.365532)
			(xy 76.665967 -410.336063) (xy 76.624765 -410.300366) (xy 76.589064 -410.259169) (xy 76.559589 -410.21331)
			(xy 76.536941 -410.163722) (xy 76.521582 -410.111417) (xy 76.513823 -410.057457) (xy 75.076289 -410.057457)
			(xy 75.068534 -410.111392) (xy 75.05318 -410.163682) (xy 75.030542 -410.213254) (xy 75.001078 -410.259101)
			(xy 74.96539 -410.300287) (xy 74.924204 -410.335976) (xy 74.878358 -410.36544) (xy 74.828785 -410.388079)
			(xy 74.776495 -410.403433) (xy 74.722553 -410.41119) (xy 74.695304 -410.411676) (xy 73.831704 -410.411676)
			(xy 73.804449 -410.411277) (xy 73.750493 -410.40352) (xy 73.69819 -410.388163) (xy 73.648605 -410.365519)
			(xy 73.602748 -410.336049) (xy 73.561551 -410.300352) (xy 73.525854 -410.259156) (xy 73.496383 -410.213298)
			(xy 73.473738 -410.163714) (xy 73.458381 -410.111411) (xy 73.450623 -410.057455) (xy 72.013113 -410.057455)
			(xy 72.005355 -410.111402) (xy 71.989999 -410.163698) (xy 71.967356 -410.213276) (xy 71.937887 -410.259127)
			(xy 71.902192 -410.300318) (xy 71.860999 -410.336008) (xy 71.815145 -410.365473) (xy 71.765564 -410.388111)
			(xy 71.713267 -410.403463) (xy 71.659316 -410.411215) (xy 71.632064 -410.411676) (xy 70.768464 -410.411676)
			(xy 70.741212 -410.411252) (xy 70.687264 -410.40349) (xy 70.634969 -410.388131) (xy 70.585392 -410.365486)
			(xy 70.539542 -410.336016) (xy 70.498353 -410.300321) (xy 70.462662 -410.259129) (xy 70.433197 -410.213276)
			(xy 70.410557 -410.163697) (xy 70.395202 -410.111401) (xy 70.387446 -410.057452) (xy 68.949789 -410.057452)
			(xy 68.942035 -410.111389) (xy 68.926682 -410.163677) (xy 68.904045 -410.213249) (xy 68.874583 -410.259094)
			(xy 68.838897 -410.30028) (xy 68.797713 -410.335969) (xy 68.75187 -410.365433) (xy 68.7023 -410.388074)
			(xy 68.650012 -410.40343) (xy 68.596072 -410.411188) (xy 68.568824 -410.411676) (xy 67.705224 -410.411676)
			(xy 67.677968 -410.411279) (xy 67.62401 -410.403524) (xy 67.571704 -410.388169) (xy 67.522117 -410.365526)
			(xy 67.476257 -410.336056) (xy 67.435058 -410.300359) (xy 67.399359 -410.259162) (xy 67.369886 -410.213304)
			(xy 67.34724 -410.163718) (xy 67.331881 -410.111414) (xy 67.324123 -410.057456) (xy 65.886612 -410.057456)
			(xy 65.878856 -410.111399) (xy 65.8635 -410.163694) (xy 65.840859 -410.213271) (xy 65.811392 -410.259121)
			(xy 65.775699 -410.300311) (xy 65.734508 -410.336001) (xy 65.688657 -410.365466) (xy 65.639079 -410.388106)
			(xy 65.586783 -410.403459) (xy 65.532835 -410.411214) (xy 65.505584 -410.411676) (xy 64.641984 -410.411676)
			(xy 64.614731 -410.411253) (xy 64.560781 -410.403494) (xy 64.508483 -410.388136) (xy 64.458904 -410.365492)
			(xy 64.413052 -410.336023) (xy 64.37186 -410.300329) (xy 64.336167 -410.259135) (xy 64.3067 -410.213282)
			(xy 64.284058 -410.163702) (xy 64.268703 -410.111404) (xy 64.260946 -410.057453) (xy 62.823289 -410.057453)
			(xy 62.815535 -410.111386) (xy 62.800184 -410.163673) (xy 62.777548 -410.213243) (xy 62.748088 -410.259087)
			(xy 62.712404 -410.300273) (xy 62.671223 -410.335962) (xy 62.625382 -410.365427) (xy 62.575814 -410.388068)
			(xy 62.523529 -410.403426) (xy 62.469591 -410.411187) (xy 62.442344 -410.411676) (xy 61.578744 -410.411676)
			(xy 61.551487 -410.41128) (xy 61.497527 -410.403528) (xy 61.445219 -410.388174) (xy 61.395629 -410.365532)
			(xy 61.349767 -410.336063) (xy 61.308565 -410.300366) (xy 61.272864 -410.259169) (xy 61.243389 -410.21331)
			(xy 61.220741 -410.163722) (xy 61.205382 -410.111417) (xy 61.197623 -410.057457) (xy 59.760089 -410.057457)
			(xy 59.752334 -410.111392) (xy 59.73698 -410.163682) (xy 59.714342 -410.213254) (xy 59.684878 -410.259101)
			(xy 59.64919 -410.300287) (xy 59.608004 -410.335976) (xy 59.562158 -410.36544) (xy 59.512585 -410.388079)
			(xy 59.460295 -410.403433) (xy 59.406353 -410.41119) (xy 59.379104 -410.411676) (xy 58.515504 -410.411676)
			(xy 58.488249 -410.411277) (xy 58.434293 -410.40352) (xy 58.38199 -410.388163) (xy 58.332405 -410.365519)
			(xy 58.286548 -410.336049) (xy 58.245351 -410.300352) (xy 58.209654 -410.259156) (xy 58.180183 -410.213298)
			(xy 58.157538 -410.163714) (xy 58.142181 -410.111411) (xy 58.134423 -410.057455) (xy 56.696913 -410.057455)
			(xy 56.689155 -410.111402) (xy 56.673799 -410.163698) (xy 56.651156 -410.213276) (xy 56.621687 -410.259127)
			(xy 56.585992 -410.300318) (xy 56.544799 -410.336008) (xy 56.498945 -410.365473) (xy 56.449364 -410.388111)
			(xy 56.397067 -410.403463) (xy 56.343116 -410.411215) (xy 56.315864 -410.411676) (xy 55.452264 -410.411676)
			(xy 55.425012 -410.411252) (xy 55.371064 -410.40349) (xy 55.318769 -410.388131) (xy 55.269192 -410.365486)
			(xy 55.223342 -410.336016) (xy 55.182153 -410.300321) (xy 55.146462 -410.259129) (xy 55.116997 -410.213276)
			(xy 55.094357 -410.163697) (xy 55.079002 -410.111401) (xy 55.071246 -410.057452) (xy 53.633589 -410.057452)
			(xy 53.625835 -410.111389) (xy 53.610482 -410.163677) (xy 53.587845 -410.213249) (xy 53.558383 -410.259094)
			(xy 53.522697 -410.30028) (xy 53.481513 -410.335969) (xy 53.43567 -410.365433) (xy 53.3861 -410.388074)
			(xy 53.333812 -410.40343) (xy 53.279872 -410.411188) (xy 53.252624 -410.411676) (xy 52.389024 -410.411676)
			(xy 52.361768 -410.411279) (xy 52.30781 -410.403524) (xy 52.255504 -410.388169) (xy 52.205917 -410.365526)
			(xy 52.160057 -410.336056) (xy 52.118858 -410.300359) (xy 52.083159 -410.259162) (xy 52.053686 -410.213304)
			(xy 52.03104 -410.163718) (xy 52.015681 -410.111414) (xy 52.007923 -410.057456) (xy 50.570412 -410.057456)
			(xy 50.562656 -410.111399) (xy 50.5473 -410.163694) (xy 50.524659 -410.213271) (xy 50.495192 -410.259121)
			(xy 50.459499 -410.300311) (xy 50.418308 -410.336001) (xy 50.372457 -410.365466) (xy 50.322879 -410.388106)
			(xy 50.270583 -410.403459) (xy 50.216635 -410.411214) (xy 50.189384 -410.411676) (xy 49.325784 -410.411676)
			(xy 49.298531 -410.411253) (xy 49.244581 -410.403494) (xy 49.192283 -410.388136) (xy 49.142704 -410.365492)
			(xy 49.096852 -410.336023) (xy 49.05566 -410.300329) (xy 49.019967 -410.259135) (xy 48.9905 -410.213282)
			(xy 48.967858 -410.163702) (xy 48.952503 -410.111404) (xy 48.944746 -410.057453) (xy 38.191293 -410.057453)
			(xy 40.731292 -412.597452) (xy 47.413146 -412.597452) (xy 47.413146 -412.542948) (xy 47.420902 -412.488999)
			(xy 47.436257 -412.436703) (xy 47.458897 -412.387124) (xy 47.488362 -412.341271) (xy 47.524053 -412.300079)
			(xy 47.565242 -412.264384) (xy 47.611092 -412.234914) (xy 47.660669 -412.212269) (xy 47.712964 -412.19691)
			(xy 47.766912 -412.189148) (xy 47.794164 -412.18866) (xy 48.657764 -412.18866) (xy 48.685016 -412.189185)
			(xy 48.738967 -412.196937) (xy 48.791264 -412.212289) (xy 48.840845 -412.234927) (xy 48.886699 -412.264392)
			(xy 48.927892 -412.300082) (xy 48.963587 -412.341273) (xy 48.993056 -412.387124) (xy 49.015699 -412.436702)
			(xy 49.031055 -412.488998) (xy 49.038813 -412.542948) (xy 49.038813 -412.597452) (xy 49.038813 -412.597455)
			(xy 50.476323 -412.597455) (xy 50.476323 -412.542945) (xy 50.484081 -412.488989) (xy 50.499438 -412.436686)
			(xy 50.522083 -412.387102) (xy 50.551554 -412.341244) (xy 50.587251 -412.300048) (xy 50.628448 -412.264351)
			(xy 50.674305 -412.234881) (xy 50.72389 -412.212237) (xy 50.776193 -412.19688) (xy 50.830149 -412.189123)
			(xy 50.857404 -412.18866) (xy 51.721004 -412.18866) (xy 51.748253 -412.18921) (xy 51.802195 -412.196967)
			(xy 51.854485 -412.212321) (xy 51.904058 -412.23496) (xy 51.949904 -412.264424) (xy 51.99109 -412.300113)
			(xy 52.026778 -412.341299) (xy 52.056242 -412.387146) (xy 52.07888 -412.436718) (xy 52.094234 -412.489008)
			(xy 52.10199 -412.542951) (xy 52.10199 -412.597449) (xy 52.101989 -412.597457) (xy 53.539523 -412.597457)
			(xy 53.539523 -412.542943) (xy 53.547282 -412.488983) (xy 53.562641 -412.436678) (xy 53.585289 -412.38709)
			(xy 53.614764 -412.341231) (xy 53.650465 -412.300034) (xy 53.691667 -412.264337) (xy 53.737529 -412.234868)
			(xy 53.787119 -412.212226) (xy 53.839427 -412.196872) (xy 53.893387 -412.18912) (xy 53.920644 -412.18866)
			(xy 54.784244 -412.18866) (xy 54.811491 -412.189213) (xy 54.865429 -412.196974) (xy 54.917714 -412.212332)
			(xy 54.967282 -412.234973) (xy 55.013123 -412.264438) (xy 55.054304 -412.300127) (xy 55.089988 -412.341313)
			(xy 55.119448 -412.387157) (xy 55.142084 -412.436727) (xy 55.157435 -412.489014) (xy 55.16519 -412.542953)
			(xy 55.16519 -412.597447) (xy 55.165189 -412.597453) (xy 56.602846 -412.597453) (xy 56.602846 -412.542947)
			(xy 56.610603 -412.488996) (xy 56.625958 -412.436698) (xy 56.6486 -412.387118) (xy 56.678067 -412.341265)
			(xy 56.71376 -412.300071) (xy 56.754952 -412.264377) (xy 56.800804 -412.234908) (xy 56.850383 -412.212264)
			(xy 56.902681 -412.196906) (xy 56.956631 -412.189147) (xy 56.983884 -412.18866) (xy 57.847484 -412.18866)
			(xy 57.874735 -412.189186) (xy 57.928683 -412.196941) (xy 57.980979 -412.212294) (xy 58.030557 -412.234934)
			(xy 58.076408 -412.264399) (xy 58.117599 -412.300089) (xy 58.153292 -412.341279) (xy 58.182759 -412.387129)
			(xy 58.2054 -412.436706) (xy 58.220756 -412.489001) (xy 58.228513 -412.542949) (xy 58.228513 -412.597451)
			(xy 58.228512 -412.597456) (xy 59.666023 -412.597456) (xy 59.666023 -412.542944) (xy 59.673781 -412.488986)
			(xy 59.68914 -412.436682) (xy 59.711786 -412.387096) (xy 59.741259 -412.341238) (xy 59.776958 -412.300041)
			(xy 59.818157 -412.264344) (xy 59.864017 -412.234874) (xy 59.913604 -412.212231) (xy 59.96591 -412.196876)
			(xy 60.019868 -412.189121) (xy 60.047124 -412.18866) (xy 60.910724 -412.18866) (xy 60.937972 -412.189212)
			(xy 60.991912 -412.19697) (xy 61.0442 -412.212326) (xy 61.09377 -412.234967) (xy 61.139613 -412.264431)
			(xy 61.180797 -412.30012) (xy 61.216483 -412.341306) (xy 61.245945 -412.387151) (xy 61.268582 -412.436723)
			(xy 61.283935 -412.489011) (xy 61.29169 -412.542952) (xy 61.29169 -412.597448) (xy 61.291689 -412.597452)
			(xy 62.729346 -412.597452) (xy 62.729346 -412.542948) (xy 62.737102 -412.488999) (xy 62.752457 -412.436703)
			(xy 62.775097 -412.387124) (xy 62.804562 -412.341271) (xy 62.840253 -412.300079) (xy 62.881442 -412.264384)
			(xy 62.927292 -412.234914) (xy 62.976869 -412.212269) (xy 63.029164 -412.19691) (xy 63.083112 -412.189148)
			(xy 63.110364 -412.18866) (xy 63.973964 -412.18866) (xy 64.001216 -412.189185) (xy 64.055167 -412.196937)
			(xy 64.107464 -412.212289) (xy 64.157045 -412.234927) (xy 64.202899 -412.264392) (xy 64.244092 -412.300082)
			(xy 64.279787 -412.341273) (xy 64.309256 -412.387124) (xy 64.331899 -412.436702) (xy 64.347255 -412.488998)
			(xy 64.355013 -412.542948) (xy 64.355013 -412.597452) (xy 64.355013 -412.597455) (xy 65.792523 -412.597455)
			(xy 65.792523 -412.542945) (xy 65.800281 -412.488989) (xy 65.815638 -412.436686) (xy 65.838283 -412.387102)
			(xy 65.867754 -412.341244) (xy 65.903451 -412.300048) (xy 65.944648 -412.264351) (xy 65.990505 -412.234881)
			(xy 66.04009 -412.212237) (xy 66.092393 -412.19688) (xy 66.146349 -412.189123) (xy 66.173604 -412.18866)
			(xy 67.037204 -412.18866) (xy 67.064453 -412.18921) (xy 67.118395 -412.196967) (xy 67.170685 -412.212321)
			(xy 67.220258 -412.23496) (xy 67.266104 -412.264424) (xy 67.30729 -412.300113) (xy 67.342978 -412.341299)
			(xy 67.372442 -412.387146) (xy 67.39508 -412.436718) (xy 67.410434 -412.489008) (xy 67.41819 -412.542951)
			(xy 67.41819 -412.597449) (xy 67.418189 -412.597457) (xy 68.855723 -412.597457) (xy 68.855723 -412.542943)
			(xy 68.863482 -412.488983) (xy 68.878841 -412.436678) (xy 68.901489 -412.38709) (xy 68.930964 -412.341231)
			(xy 68.966665 -412.300034) (xy 69.007867 -412.264337) (xy 69.053729 -412.234868) (xy 69.103319 -412.212226)
			(xy 69.155627 -412.196872) (xy 69.209587 -412.18912) (xy 69.236844 -412.18866) (xy 70.100444 -412.18866)
			(xy 70.127691 -412.189213) (xy 70.181629 -412.196974) (xy 70.233914 -412.212332) (xy 70.283482 -412.234973)
			(xy 70.329323 -412.264438) (xy 70.370504 -412.300127) (xy 70.406188 -412.341313) (xy 70.435648 -412.387157)
			(xy 70.458284 -412.436727) (xy 70.473635 -412.489014) (xy 70.48139 -412.542953) (xy 70.48139 -412.597447)
			(xy 70.481389 -412.597453) (xy 71.919046 -412.597453) (xy 71.919046 -412.542947) (xy 71.926803 -412.488996)
			(xy 71.942158 -412.436698) (xy 71.9648 -412.387118) (xy 71.994267 -412.341265) (xy 72.02996 -412.300071)
			(xy 72.071152 -412.264377) (xy 72.117004 -412.234908) (xy 72.166583 -412.212264) (xy 72.218881 -412.196906)
			(xy 72.272831 -412.189147) (xy 72.300084 -412.18866) (xy 73.163684 -412.18866) (xy 73.190935 -412.189186)
			(xy 73.244883 -412.196941) (xy 73.297179 -412.212294) (xy 73.346757 -412.234934) (xy 73.392608 -412.264399)
			(xy 73.433799 -412.300089) (xy 73.469492 -412.341279) (xy 73.498959 -412.387129) (xy 73.5216 -412.436706)
			(xy 73.536956 -412.489001) (xy 73.544713 -412.542949) (xy 73.544713 -412.597451) (xy 73.544712 -412.597456)
			(xy 74.982223 -412.597456) (xy 74.982223 -412.542944) (xy 74.989981 -412.488986) (xy 75.00534 -412.436682)
			(xy 75.027986 -412.387096) (xy 75.057459 -412.341238) (xy 75.093158 -412.300041) (xy 75.134357 -412.264344)
			(xy 75.180217 -412.234874) (xy 75.229804 -412.212231) (xy 75.28211 -412.196876) (xy 75.336068 -412.189121)
			(xy 75.363324 -412.18866) (xy 76.226924 -412.18866) (xy 76.254172 -412.189212) (xy 76.308112 -412.19697)
			(xy 76.3604 -412.212326) (xy 76.40997 -412.234967) (xy 76.455813 -412.264431) (xy 76.496997 -412.30012)
			(xy 76.532683 -412.341306) (xy 76.562145 -412.387151) (xy 76.584782 -412.436723) (xy 76.600135 -412.489011)
			(xy 76.60789 -412.542952) (xy 76.60789 -412.597448) (xy 76.607889 -412.597452) (xy 78.045546 -412.597452)
			(xy 78.045546 -412.542948) (xy 78.053302 -412.488999) (xy 78.068657 -412.436703) (xy 78.091297 -412.387124)
			(xy 78.120762 -412.341271) (xy 78.156453 -412.300079) (xy 78.197642 -412.264384) (xy 78.243492 -412.234914)
			(xy 78.293069 -412.212269) (xy 78.345364 -412.19691) (xy 78.399312 -412.189148) (xy 78.426564 -412.18866)
			(xy 79.290164 -412.18866) (xy 79.317416 -412.189185) (xy 79.371367 -412.196937) (xy 79.423664 -412.212289)
			(xy 79.473245 -412.234927) (xy 79.519099 -412.264392) (xy 79.560292 -412.300082) (xy 79.595987 -412.341273)
			(xy 79.625456 -412.387124) (xy 79.648099 -412.436702) (xy 79.663455 -412.488998) (xy 79.671213 -412.542948)
			(xy 79.671213 -412.597452) (xy 79.671213 -412.597455) (xy 81.108723 -412.597455) (xy 81.108723 -412.542945)
			(xy 81.116481 -412.488989) (xy 81.131838 -412.436686) (xy 81.154483 -412.387102) (xy 81.183954 -412.341244)
			(xy 81.219651 -412.300048) (xy 81.260848 -412.264351) (xy 81.306705 -412.234881) (xy 81.35629 -412.212237)
			(xy 81.408593 -412.19688) (xy 81.462549 -412.189123) (xy 81.489804 -412.18866) (xy 82.353404 -412.18866)
			(xy 82.380653 -412.18921) (xy 82.434595 -412.196967) (xy 82.486885 -412.212321) (xy 82.536458 -412.23496)
			(xy 82.582304 -412.264424) (xy 82.62349 -412.300113) (xy 82.659178 -412.341299) (xy 82.688642 -412.387146)
			(xy 82.71128 -412.436718) (xy 82.726634 -412.489008) (xy 82.73439 -412.542951) (xy 82.73439 -412.597449)
			(xy 82.734389 -412.597457) (xy 84.171923 -412.597457) (xy 84.171923 -412.542943) (xy 84.179682 -412.488983)
			(xy 84.195041 -412.436678) (xy 84.217689 -412.38709) (xy 84.247164 -412.341231) (xy 84.282865 -412.300034)
			(xy 84.324067 -412.264337) (xy 84.369929 -412.234868) (xy 84.419519 -412.212226) (xy 84.471827 -412.196872)
			(xy 84.525787 -412.18912) (xy 84.553044 -412.18866) (xy 85.416644 -412.18866) (xy 85.443891 -412.189213)
			(xy 85.497829 -412.196974) (xy 85.550114 -412.212332) (xy 85.599682 -412.234973) (xy 85.645523 -412.264438)
			(xy 85.686704 -412.300127) (xy 85.722388 -412.341313) (xy 85.751848 -412.387157) (xy 85.774484 -412.436727)
			(xy 85.789835 -412.489014) (xy 85.79759 -412.542953) (xy 85.79759 -412.597447) (xy 85.797589 -412.597453)
			(xy 87.235246 -412.597453) (xy 87.235246 -412.542947) (xy 87.243003 -412.488996) (xy 87.258358 -412.436698)
			(xy 87.281 -412.387118) (xy 87.310467 -412.341265) (xy 87.34616 -412.300071) (xy 87.387352 -412.264377)
			(xy 87.433204 -412.234908) (xy 87.482783 -412.212264) (xy 87.535081 -412.196906) (xy 87.589031 -412.189147)
			(xy 87.616284 -412.18866) (xy 88.479884 -412.18866) (xy 88.507135 -412.189186) (xy 88.561083 -412.196941)
			(xy 88.613379 -412.212294) (xy 88.662957 -412.234934) (xy 88.708808 -412.264399) (xy 88.749999 -412.300089)
			(xy 88.785692 -412.341279) (xy 88.815159 -412.387129) (xy 88.8378 -412.436706) (xy 88.853156 -412.489001)
			(xy 88.860913 -412.542949) (xy 88.860913 -412.597451) (xy 88.860912 -412.597456) (xy 90.298423 -412.597456)
			(xy 90.298423 -412.542944) (xy 90.306181 -412.488986) (xy 90.32154 -412.436682) (xy 90.344186 -412.387096)
			(xy 90.373659 -412.341238) (xy 90.409358 -412.300041) (xy 90.450557 -412.264344) (xy 90.496417 -412.234874)
			(xy 90.546004 -412.212231) (xy 90.59831 -412.196876) (xy 90.652268 -412.189121) (xy 90.679524 -412.18866)
			(xy 91.543124 -412.18866) (xy 91.570372 -412.189212) (xy 91.624312 -412.19697) (xy 91.6766 -412.212326)
			(xy 91.72617 -412.234967) (xy 91.772013 -412.264431) (xy 91.813197 -412.30012) (xy 91.848883 -412.341306)
			(xy 91.878345 -412.387151) (xy 91.900982 -412.436723) (xy 91.916335 -412.489011) (xy 91.92409 -412.542952)
			(xy 91.92409 -412.597448) (xy 91.924089 -412.597452) (xy 93.361746 -412.597452) (xy 93.361746 -412.542948)
			(xy 93.369502 -412.488999) (xy 93.384857 -412.436703) (xy 93.407497 -412.387124) (xy 93.436962 -412.341271)
			(xy 93.472653 -412.300079) (xy 93.513842 -412.264384) (xy 93.559692 -412.234914) (xy 93.609269 -412.212269)
			(xy 93.661564 -412.19691) (xy 93.715512 -412.189148) (xy 93.742764 -412.18866) (xy 94.606364 -412.18866)
			(xy 94.633616 -412.189185) (xy 94.687567 -412.196937) (xy 94.739864 -412.212289) (xy 94.789445 -412.234927)
			(xy 94.835299 -412.264392) (xy 94.876492 -412.300082) (xy 94.912187 -412.341273) (xy 94.941656 -412.387124)
			(xy 94.964299 -412.436702) (xy 94.979655 -412.488998) (xy 94.987413 -412.542948) (xy 94.987413 -412.597452)
			(xy 94.987413 -412.597455) (xy 114.513023 -412.597455) (xy 114.513023 -412.542945) (xy 114.520781 -412.488989)
			(xy 114.536138 -412.436686) (xy 114.558783 -412.387101) (xy 114.588254 -412.341244) (xy 114.623952 -412.300047)
			(xy 114.665149 -412.264351) (xy 114.711006 -412.23488) (xy 114.760591 -412.212236) (xy 114.812894 -412.196879)
			(xy 114.866851 -412.189123) (xy 114.894106 -412.18866) (xy 115.757706 -412.18866) (xy 115.784955 -412.189211)
			(xy 115.838897 -412.196967) (xy 115.891187 -412.212321) (xy 115.940759 -412.234961) (xy 115.986605 -412.264425)
			(xy 116.027791 -412.300113) (xy 116.063479 -412.3413) (xy 116.092942 -412.387146) (xy 116.115581 -412.436719)
			(xy 116.130934 -412.489009) (xy 116.13869 -412.542951) (xy 116.13869 -412.597449) (xy 116.138689 -412.597457)
			(xy 117.576223 -412.597457) (xy 117.576223 -412.542943) (xy 117.583982 -412.488983) (xy 117.599342 -412.436677)
			(xy 117.621989 -412.38709) (xy 117.651464 -412.341231) (xy 117.687166 -412.300033) (xy 117.728367 -412.264337)
			(xy 117.77423 -412.234867) (xy 117.82382 -412.212225) (xy 117.876128 -412.196872) (xy 117.930089 -412.18912)
			(xy 117.957346 -412.18866) (xy 118.820946 -412.18866) (xy 118.848193 -412.189213) (xy 118.902131 -412.196975)
			(xy 118.954416 -412.212332) (xy 119.003983 -412.234974) (xy 119.049824 -412.264439) (xy 119.091005 -412.300128)
			(xy 119.126688 -412.341313) (xy 119.156148 -412.387157) (xy 119.178784 -412.436727) (xy 119.194135 -412.489014)
			(xy 119.20189 -412.542953) (xy 119.20189 -412.597447) (xy 119.201889 -412.597453) (xy 120.639546 -412.597453)
			(xy 120.639546 -412.542947) (xy 120.647303 -412.488996) (xy 120.662658 -412.436698) (xy 120.6853 -412.387118)
			(xy 120.714768 -412.341264) (xy 120.750461 -412.300071) (xy 120.791653 -412.264376) (xy 120.837505 -412.234907)
			(xy 120.887085 -412.212263) (xy 120.939382 -412.196906) (xy 120.993333 -412.189147) (xy 121.020586 -412.18866)
			(xy 121.884186 -412.18866) (xy 121.911437 -412.189186) (xy 121.965385 -412.196941) (xy 122.01768 -412.212295)
			(xy 122.067258 -412.234934) (xy 122.113109 -412.264399) (xy 122.1543 -412.30009) (xy 122.189992 -412.34128)
			(xy 122.219459 -412.38713) (xy 122.242101 -412.436707) (xy 122.257456 -412.489001) (xy 122.265213 -412.542949)
			(xy 122.265213 -412.597451) (xy 122.265212 -412.597456) (xy 123.702723 -412.597456) (xy 123.702723 -412.542944)
			(xy 123.710481 -412.488986) (xy 123.72584 -412.436681) (xy 123.748486 -412.387095) (xy 123.777959 -412.341237)
			(xy 123.813659 -412.30004) (xy 123.854858 -412.264344) (xy 123.900718 -412.234874) (xy 123.950306 -412.212231)
			(xy 124.002611 -412.196876) (xy 124.05657 -412.189121) (xy 124.083826 -412.18866) (xy 124.947426 -412.18866)
			(xy 124.974674 -412.189212) (xy 125.028614 -412.196971) (xy 125.080901 -412.212327) (xy 125.130471 -412.234968)
			(xy 125.176314 -412.264432) (xy 125.217498 -412.300121) (xy 125.253184 -412.341307) (xy 125.282645 -412.387152)
			(xy 125.305282 -412.436723) (xy 125.320635 -412.489011) (xy 125.32839 -412.542952) (xy 125.32839 -412.597448)
			(xy 125.328389 -412.597452) (xy 126.766046 -412.597452) (xy 126.766046 -412.542948) (xy 126.773802 -412.488999)
			(xy 126.789157 -412.436702) (xy 126.811797 -412.387123) (xy 126.841263 -412.341271) (xy 126.876954 -412.300078)
			(xy 126.918143 -412.264383) (xy 126.963993 -412.234914) (xy 127.01357 -412.212269) (xy 127.065865 -412.196909)
			(xy 127.119814 -412.189148) (xy 127.147066 -412.18866) (xy 128.010666 -412.18866) (xy 128.037918 -412.189185)
			(xy 128.091868 -412.196937) (xy 128.144166 -412.212289) (xy 128.193746 -412.234928) (xy 128.2396 -412.264392)
			(xy 128.280793 -412.300083) (xy 128.316487 -412.341273) (xy 128.345956 -412.387124) (xy 128.368599 -412.436702)
			(xy 128.383955 -412.488999) (xy 128.391713 -412.542948) (xy 128.391713 -412.597452) (xy 128.391713 -412.597455)
			(xy 129.829223 -412.597455) (xy 129.829223 -412.542945) (xy 129.836981 -412.488989) (xy 129.852338 -412.436686)
			(xy 129.874983 -412.387101) (xy 129.904454 -412.341244) (xy 129.940152 -412.300047) (xy 129.981349 -412.264351)
			(xy 130.027206 -412.23488) (xy 130.076791 -412.212236) (xy 130.129094 -412.196879) (xy 130.183051 -412.189123)
			(xy 130.210306 -412.18866) (xy 131.073906 -412.18866) (xy 131.101155 -412.189211) (xy 131.155097 -412.196967)
			(xy 131.207387 -412.212321) (xy 131.256959 -412.234961) (xy 131.302805 -412.264425) (xy 131.343991 -412.300113)
			(xy 131.379679 -412.3413) (xy 131.409142 -412.387146) (xy 131.431781 -412.436719) (xy 131.447134 -412.489009)
			(xy 131.45489 -412.542951) (xy 131.45489 -412.597449) (xy 131.454889 -412.597457) (xy 132.892423 -412.597457)
			(xy 132.892423 -412.542943) (xy 132.900182 -412.488983) (xy 132.915542 -412.436677) (xy 132.938189 -412.38709)
			(xy 132.967664 -412.341231) (xy 133.003366 -412.300033) (xy 133.044567 -412.264337) (xy 133.09043 -412.234867)
			(xy 133.14002 -412.212225) (xy 133.192328 -412.196872) (xy 133.246289 -412.18912) (xy 133.273546 -412.18866)
			(xy 134.137146 -412.18866) (xy 134.164393 -412.189213) (xy 134.218331 -412.196975) (xy 134.270616 -412.212332)
			(xy 134.320183 -412.234974) (xy 134.366024 -412.264439) (xy 134.407205 -412.300128) (xy 134.442888 -412.341313)
			(xy 134.472348 -412.387157) (xy 134.494984 -412.436727) (xy 134.510335 -412.489014) (xy 134.51809 -412.542953)
			(xy 134.51809 -412.597447) (xy 134.518089 -412.597453) (xy 135.955746 -412.597453) (xy 135.955746 -412.542947)
			(xy 135.963503 -412.488996) (xy 135.978858 -412.436698) (xy 136.0015 -412.387118) (xy 136.030968 -412.341264)
			(xy 136.066661 -412.300071) (xy 136.107853 -412.264376) (xy 136.153705 -412.234907) (xy 136.203285 -412.212263)
			(xy 136.255582 -412.196906) (xy 136.309533 -412.189147) (xy 136.336786 -412.18866) (xy 137.200386 -412.18866)
			(xy 137.227637 -412.189186) (xy 137.281585 -412.196941) (xy 137.33388 -412.212295) (xy 137.383458 -412.234934)
			(xy 137.429309 -412.264399) (xy 137.4705 -412.30009) (xy 137.506192 -412.34128) (xy 137.535659 -412.38713)
			(xy 137.558301 -412.436707) (xy 137.573656 -412.489001) (xy 137.581413 -412.542949) (xy 137.581413 -412.597451)
			(xy 137.581412 -412.597456) (xy 139.018923 -412.597456) (xy 139.018923 -412.542944) (xy 139.026681 -412.488986)
			(xy 139.04204 -412.436681) (xy 139.064686 -412.387095) (xy 139.094159 -412.341237) (xy 139.129859 -412.30004)
			(xy 139.171058 -412.264344) (xy 139.216918 -412.234874) (xy 139.266506 -412.212231) (xy 139.318811 -412.196876)
			(xy 139.37277 -412.189121) (xy 139.400026 -412.18866) (xy 140.263626 -412.18866) (xy 140.290874 -412.189212)
			(xy 140.344814 -412.196971) (xy 140.397101 -412.212327) (xy 140.446671 -412.234968) (xy 140.492514 -412.264432)
			(xy 140.533698 -412.300121) (xy 140.569384 -412.341307) (xy 140.598845 -412.387152) (xy 140.621482 -412.436723)
			(xy 140.636835 -412.489011) (xy 140.64459 -412.542952) (xy 140.64459 -412.597448) (xy 140.644589 -412.597452)
			(xy 142.082246 -412.597452) (xy 142.082246 -412.542948) (xy 142.090002 -412.488999) (xy 142.105357 -412.436702)
			(xy 142.127997 -412.387123) (xy 142.157463 -412.341271) (xy 142.193154 -412.300078) (xy 142.234343 -412.264383)
			(xy 142.280193 -412.234914) (xy 142.32977 -412.212269) (xy 142.382065 -412.196909) (xy 142.436014 -412.189148)
			(xy 142.463266 -412.18866) (xy 143.326866 -412.18866) (xy 143.354118 -412.189185) (xy 143.408068 -412.196937)
			(xy 143.460366 -412.212289) (xy 143.509946 -412.234928) (xy 143.5558 -412.264392) (xy 143.596993 -412.300083)
			(xy 143.632687 -412.341273) (xy 143.662156 -412.387124) (xy 143.684799 -412.436702) (xy 143.700155 -412.488999)
			(xy 143.707913 -412.542948) (xy 143.707913 -412.597452) (xy 143.707913 -412.597455) (xy 145.145423 -412.597455)
			(xy 145.145423 -412.542945) (xy 145.153181 -412.488989) (xy 145.168538 -412.436686) (xy 145.191183 -412.387101)
			(xy 145.220654 -412.341244) (xy 145.256352 -412.300047) (xy 145.297549 -412.264351) (xy 145.343406 -412.23488)
			(xy 145.392991 -412.212236) (xy 145.445294 -412.196879) (xy 145.499251 -412.189123) (xy 145.526506 -412.18866)
			(xy 146.390106 -412.18866) (xy 146.417355 -412.189211) (xy 146.471297 -412.196967) (xy 146.523587 -412.212321)
			(xy 146.573159 -412.234961) (xy 146.619005 -412.264425) (xy 146.660191 -412.300113) (xy 146.695879 -412.3413)
			(xy 146.725342 -412.387146) (xy 146.747981 -412.436719) (xy 146.763334 -412.489009) (xy 146.77109 -412.542951)
			(xy 146.77109 -412.597449) (xy 146.771089 -412.597457) (xy 148.208623 -412.597457) (xy 148.208623 -412.542943)
			(xy 148.216382 -412.488983) (xy 148.231742 -412.436677) (xy 148.254389 -412.38709) (xy 148.283864 -412.341231)
			(xy 148.319566 -412.300033) (xy 148.360767 -412.264337) (xy 148.40663 -412.234867) (xy 148.45622 -412.212225)
			(xy 148.508528 -412.196872) (xy 148.562489 -412.18912) (xy 148.589746 -412.18866) (xy 149.453346 -412.18866)
			(xy 149.480593 -412.189213) (xy 149.534531 -412.196975) (xy 149.586816 -412.212332) (xy 149.636383 -412.234974)
			(xy 149.682224 -412.264439) (xy 149.723405 -412.300128) (xy 149.759088 -412.341313) (xy 149.788548 -412.387157)
			(xy 149.811184 -412.436727) (xy 149.826535 -412.489014) (xy 149.83429 -412.542953) (xy 149.83429 -412.597447)
			(xy 149.834289 -412.597453) (xy 151.271946 -412.597453) (xy 151.271946 -412.542947) (xy 151.279703 -412.488996)
			(xy 151.295058 -412.436698) (xy 151.3177 -412.387118) (xy 151.347168 -412.341264) (xy 151.382861 -412.300071)
			(xy 151.424053 -412.264376) (xy 151.469905 -412.234907) (xy 151.519485 -412.212263) (xy 151.571782 -412.196906)
			(xy 151.625733 -412.189147) (xy 151.652986 -412.18866) (xy 152.516586 -412.18866) (xy 152.543837 -412.189186)
			(xy 152.597785 -412.196941) (xy 152.65008 -412.212295) (xy 152.699658 -412.234934) (xy 152.745509 -412.264399)
			(xy 152.7867 -412.30009) (xy 152.822392 -412.34128) (xy 152.851859 -412.38713) (xy 152.874501 -412.436707)
			(xy 152.889856 -412.489001) (xy 152.897613 -412.542949) (xy 152.897613 -412.597451) (xy 152.897612 -412.597456)
			(xy 154.335123 -412.597456) (xy 154.335123 -412.542944) (xy 154.342881 -412.488986) (xy 154.35824 -412.436681)
			(xy 154.380886 -412.387095) (xy 154.410359 -412.341237) (xy 154.446059 -412.30004) (xy 154.487258 -412.264344)
			(xy 154.533118 -412.234874) (xy 154.582706 -412.212231) (xy 154.635011 -412.196876) (xy 154.68897 -412.189121)
			(xy 154.716226 -412.18866) (xy 155.579826 -412.18866) (xy 155.607074 -412.189212) (xy 155.661014 -412.196971)
			(xy 155.713301 -412.212327) (xy 155.762871 -412.234968) (xy 155.808714 -412.264432) (xy 155.849898 -412.300121)
			(xy 155.885584 -412.341307) (xy 155.915045 -412.387152) (xy 155.937682 -412.436723) (xy 155.953035 -412.489011)
			(xy 155.96079 -412.542952) (xy 155.96079 -412.597448) (xy 155.960789 -412.597452) (xy 157.398446 -412.597452)
			(xy 157.398446 -412.542948) (xy 157.406202 -412.488999) (xy 157.421557 -412.436702) (xy 157.444197 -412.387123)
			(xy 157.473663 -412.341271) (xy 157.509354 -412.300078) (xy 157.550543 -412.264383) (xy 157.596393 -412.234914)
			(xy 157.64597 -412.212269) (xy 157.698265 -412.196909) (xy 157.752214 -412.189148) (xy 157.779466 -412.18866)
			(xy 158.643066 -412.18866) (xy 158.670318 -412.189185) (xy 158.724268 -412.196937) (xy 158.776566 -412.212289)
			(xy 158.826146 -412.234928) (xy 158.872 -412.264392) (xy 158.913193 -412.300083) (xy 158.948887 -412.341273)
			(xy 158.978356 -412.387124) (xy 159.000999 -412.436702) (xy 159.016355 -412.488999) (xy 159.024113 -412.542948)
			(xy 159.024113 -412.597452) (xy 159.024113 -412.597455) (xy 160.461623 -412.597455) (xy 160.461623 -412.542945)
			(xy 160.469381 -412.488989) (xy 160.484738 -412.436686) (xy 160.507383 -412.387101) (xy 160.536854 -412.341244)
			(xy 160.572552 -412.300047) (xy 160.613749 -412.264351) (xy 160.659606 -412.23488) (xy 160.709191 -412.212236)
			(xy 160.761494 -412.196879) (xy 160.815451 -412.189123) (xy 160.842706 -412.18866) (xy 161.706306 -412.18866)
			(xy 161.733555 -412.189211) (xy 161.787497 -412.196967) (xy 161.839787 -412.212321) (xy 161.889359 -412.234961)
			(xy 161.935205 -412.264425) (xy 161.976391 -412.300113) (xy 162.012079 -412.3413) (xy 162.041542 -412.387146)
			(xy 162.064181 -412.436719) (xy 162.079534 -412.489009) (xy 162.08729 -412.542951) (xy 162.08729 -412.597449)
			(xy 162.079534 -412.651391) (xy 162.064181 -412.703681) (xy 162.041542 -412.753254) (xy 162.012079 -412.7991)
			(xy 161.976391 -412.840287) (xy 161.935205 -412.875975) (xy 161.889359 -412.905439) (xy 161.839787 -412.928079)
			(xy 161.787497 -412.943433) (xy 161.733555 -412.951189) (xy 161.706306 -412.951676) (xy 160.842706 -412.951676)
			(xy 160.815451 -412.951277) (xy 160.761494 -412.943521) (xy 160.709191 -412.928164) (xy 160.659606 -412.90552)
			(xy 160.613749 -412.876049) (xy 160.572552 -412.840353) (xy 160.536854 -412.799156) (xy 160.507383 -412.753299)
			(xy 160.484738 -412.703714) (xy 160.469381 -412.651411) (xy 160.461623 -412.597455) (xy 159.024113 -412.597455)
			(xy 159.016355 -412.651402) (xy 159.000999 -412.703698) (xy 158.978356 -412.753276) (xy 158.948887 -412.799127)
			(xy 158.913193 -412.840317) (xy 158.872 -412.876008) (xy 158.826146 -412.905472) (xy 158.776566 -412.928111)
			(xy 158.724268 -412.943463) (xy 158.670318 -412.951215) (xy 158.643066 -412.951676) (xy 157.779466 -412.951676)
			(xy 157.752214 -412.951252) (xy 157.698265 -412.943491) (xy 157.64597 -412.928131) (xy 157.596393 -412.905486)
			(xy 157.550543 -412.876017) (xy 157.509354 -412.840322) (xy 157.473663 -412.799129) (xy 157.444197 -412.753277)
			(xy 157.421557 -412.703698) (xy 157.406202 -412.651401) (xy 157.398446 -412.597452) (xy 155.960789 -412.597452)
			(xy 155.953035 -412.651389) (xy 155.937682 -412.703677) (xy 155.915045 -412.753248) (xy 155.885584 -412.799093)
			(xy 155.849898 -412.840279) (xy 155.808714 -412.875968) (xy 155.762871 -412.905432) (xy 155.713301 -412.928073)
			(xy 155.661014 -412.943429) (xy 155.607074 -412.951188) (xy 155.579826 -412.951676) (xy 154.716226 -412.951676)
			(xy 154.68897 -412.951279) (xy 154.635011 -412.943524) (xy 154.582706 -412.928169) (xy 154.533118 -412.905526)
			(xy 154.487258 -412.876056) (xy 154.446059 -412.84036) (xy 154.410359 -412.799163) (xy 154.380886 -412.753305)
			(xy 154.35824 -412.703719) (xy 154.342881 -412.651414) (xy 154.335123 -412.597456) (xy 152.897612 -412.597456)
			(xy 152.889856 -412.651399) (xy 152.874501 -412.703693) (xy 152.851859 -412.75327) (xy 152.822392 -412.79912)
			(xy 152.7867 -412.84031) (xy 152.745509 -412.876001) (xy 152.699658 -412.905466) (xy 152.65008 -412.928105)
			(xy 152.597785 -412.943459) (xy 152.543837 -412.951214) (xy 152.516586 -412.951676) (xy 151.652986 -412.951676)
			(xy 151.625733 -412.951253) (xy 151.571782 -412.943494) (xy 151.519485 -412.928137) (xy 151.469905 -412.905493)
			(xy 151.424053 -412.876024) (xy 151.382861 -412.840329) (xy 151.347168 -412.799136) (xy 151.3177 -412.753282)
			(xy 151.295058 -412.703702) (xy 151.279703 -412.651404) (xy 151.271946 -412.597453) (xy 149.834289 -412.597453)
			(xy 149.826535 -412.651386) (xy 149.811184 -412.703673) (xy 149.788548 -412.753243) (xy 149.759088 -412.799087)
			(xy 149.723405 -412.840272) (xy 149.682224 -412.875961) (xy 149.636383 -412.905426) (xy 149.586816 -412.928068)
			(xy 149.534531 -412.943425) (xy 149.480593 -412.951187) (xy 149.453346 -412.951676) (xy 148.589746 -412.951676)
			(xy 148.562489 -412.95128) (xy 148.508528 -412.943528) (xy 148.45622 -412.928175) (xy 148.40663 -412.905533)
			(xy 148.360767 -412.876063) (xy 148.319566 -412.840367) (xy 148.283864 -412.799169) (xy 148.254389 -412.75331)
			(xy 148.231742 -412.703723) (xy 148.216382 -412.651417) (xy 148.208623 -412.597457) (xy 146.771089 -412.597457)
			(xy 146.763334 -412.651391) (xy 146.747981 -412.703681) (xy 146.725342 -412.753254) (xy 146.695879 -412.7991)
			(xy 146.660191 -412.840287) (xy 146.619005 -412.875975) (xy 146.573159 -412.905439) (xy 146.523587 -412.928079)
			(xy 146.471297 -412.943433) (xy 146.417355 -412.951189) (xy 146.390106 -412.951676) (xy 145.526506 -412.951676)
			(xy 145.499251 -412.951277) (xy 145.445294 -412.943521) (xy 145.392991 -412.928164) (xy 145.343406 -412.90552)
			(xy 145.297549 -412.876049) (xy 145.256352 -412.840353) (xy 145.220654 -412.799156) (xy 145.191183 -412.753299)
			(xy 145.168538 -412.703714) (xy 145.153181 -412.651411) (xy 145.145423 -412.597455) (xy 143.707913 -412.597455)
			(xy 143.700155 -412.651402) (xy 143.684799 -412.703698) (xy 143.662156 -412.753276) (xy 143.632687 -412.799127)
			(xy 143.596993 -412.840317) (xy 143.5558 -412.876008) (xy 143.509946 -412.905472) (xy 143.460366 -412.928111)
			(xy 143.408068 -412.943463) (xy 143.354118 -412.951215) (xy 143.326866 -412.951676) (xy 142.463266 -412.951676)
			(xy 142.436014 -412.951252) (xy 142.382065 -412.943491) (xy 142.32977 -412.928131) (xy 142.280193 -412.905486)
			(xy 142.234343 -412.876017) (xy 142.193154 -412.840322) (xy 142.157463 -412.799129) (xy 142.127997 -412.753277)
			(xy 142.105357 -412.703698) (xy 142.090002 -412.651401) (xy 142.082246 -412.597452) (xy 140.644589 -412.597452)
			(xy 140.636835 -412.651389) (xy 140.621482 -412.703677) (xy 140.598845 -412.753248) (xy 140.569384 -412.799093)
			(xy 140.533698 -412.840279) (xy 140.492514 -412.875968) (xy 140.446671 -412.905432) (xy 140.397101 -412.928073)
			(xy 140.344814 -412.943429) (xy 140.290874 -412.951188) (xy 140.263626 -412.951676) (xy 139.400026 -412.951676)
			(xy 139.37277 -412.951279) (xy 139.318811 -412.943524) (xy 139.266506 -412.928169) (xy 139.216918 -412.905526)
			(xy 139.171058 -412.876056) (xy 139.129859 -412.84036) (xy 139.094159 -412.799163) (xy 139.064686 -412.753305)
			(xy 139.04204 -412.703719) (xy 139.026681 -412.651414) (xy 139.018923 -412.597456) (xy 137.581412 -412.597456)
			(xy 137.573656 -412.651399) (xy 137.558301 -412.703693) (xy 137.535659 -412.75327) (xy 137.506192 -412.79912)
			(xy 137.4705 -412.84031) (xy 137.429309 -412.876001) (xy 137.383458 -412.905466) (xy 137.33388 -412.928105)
			(xy 137.281585 -412.943459) (xy 137.227637 -412.951214) (xy 137.200386 -412.951676) (xy 136.336786 -412.951676)
			(xy 136.309533 -412.951253) (xy 136.255582 -412.943494) (xy 136.203285 -412.928137) (xy 136.153705 -412.905493)
			(xy 136.107853 -412.876024) (xy 136.066661 -412.840329) (xy 136.030968 -412.799136) (xy 136.0015 -412.753282)
			(xy 135.978858 -412.703702) (xy 135.963503 -412.651404) (xy 135.955746 -412.597453) (xy 134.518089 -412.597453)
			(xy 134.510335 -412.651386) (xy 134.494984 -412.703673) (xy 134.472348 -412.753243) (xy 134.442888 -412.799087)
			(xy 134.407205 -412.840272) (xy 134.366024 -412.875961) (xy 134.320183 -412.905426) (xy 134.270616 -412.928068)
			(xy 134.218331 -412.943425) (xy 134.164393 -412.951187) (xy 134.137146 -412.951676) (xy 133.273546 -412.951676)
			(xy 133.246289 -412.95128) (xy 133.192328 -412.943528) (xy 133.14002 -412.928175) (xy 133.09043 -412.905533)
			(xy 133.044567 -412.876063) (xy 133.003366 -412.840367) (xy 132.967664 -412.799169) (xy 132.938189 -412.75331)
			(xy 132.915542 -412.703723) (xy 132.900182 -412.651417) (xy 132.892423 -412.597457) (xy 131.454889 -412.597457)
			(xy 131.447134 -412.651391) (xy 131.431781 -412.703681) (xy 131.409142 -412.753254) (xy 131.379679 -412.7991)
			(xy 131.343991 -412.840287) (xy 131.302805 -412.875975) (xy 131.256959 -412.905439) (xy 131.207387 -412.928079)
			(xy 131.155097 -412.943433) (xy 131.101155 -412.951189) (xy 131.073906 -412.951676) (xy 130.210306 -412.951676)
			(xy 130.183051 -412.951277) (xy 130.129094 -412.943521) (xy 130.076791 -412.928164) (xy 130.027206 -412.90552)
			(xy 129.981349 -412.876049) (xy 129.940152 -412.840353) (xy 129.904454 -412.799156) (xy 129.874983 -412.753299)
			(xy 129.852338 -412.703714) (xy 129.836981 -412.651411) (xy 129.829223 -412.597455) (xy 128.391713 -412.597455)
			(xy 128.383955 -412.651402) (xy 128.368599 -412.703698) (xy 128.345956 -412.753276) (xy 128.316487 -412.799127)
			(xy 128.280793 -412.840317) (xy 128.2396 -412.876008) (xy 128.193746 -412.905472) (xy 128.144166 -412.928111)
			(xy 128.091868 -412.943463) (xy 128.037918 -412.951215) (xy 128.010666 -412.951676) (xy 127.147066 -412.951676)
			(xy 127.119814 -412.951252) (xy 127.065865 -412.943491) (xy 127.01357 -412.928131) (xy 126.963993 -412.905486)
			(xy 126.918143 -412.876017) (xy 126.876954 -412.840322) (xy 126.841263 -412.799129) (xy 126.811797 -412.753277)
			(xy 126.789157 -412.703698) (xy 126.773802 -412.651401) (xy 126.766046 -412.597452) (xy 125.328389 -412.597452)
			(xy 125.320635 -412.651389) (xy 125.305282 -412.703677) (xy 125.282645 -412.753248) (xy 125.253184 -412.799093)
			(xy 125.217498 -412.840279) (xy 125.176314 -412.875968) (xy 125.130471 -412.905432) (xy 125.080901 -412.928073)
			(xy 125.028614 -412.943429) (xy 124.974674 -412.951188) (xy 124.947426 -412.951676) (xy 124.083826 -412.951676)
			(xy 124.05657 -412.951279) (xy 124.002611 -412.943524) (xy 123.950306 -412.928169) (xy 123.900718 -412.905526)
			(xy 123.854858 -412.876056) (xy 123.813659 -412.84036) (xy 123.777959 -412.799163) (xy 123.748486 -412.753305)
			(xy 123.72584 -412.703719) (xy 123.710481 -412.651414) (xy 123.702723 -412.597456) (xy 122.265212 -412.597456)
			(xy 122.257456 -412.651399) (xy 122.242101 -412.703693) (xy 122.219459 -412.75327) (xy 122.189992 -412.79912)
			(xy 122.1543 -412.84031) (xy 122.113109 -412.876001) (xy 122.067258 -412.905466) (xy 122.01768 -412.928105)
			(xy 121.965385 -412.943459) (xy 121.911437 -412.951214) (xy 121.884186 -412.951676) (xy 121.020586 -412.951676)
			(xy 120.993333 -412.951253) (xy 120.939382 -412.943494) (xy 120.887085 -412.928137) (xy 120.837505 -412.905493)
			(xy 120.791653 -412.876024) (xy 120.750461 -412.840329) (xy 120.714768 -412.799136) (xy 120.6853 -412.753282)
			(xy 120.662658 -412.703702) (xy 120.647303 -412.651404) (xy 120.639546 -412.597453) (xy 119.201889 -412.597453)
			(xy 119.194135 -412.651386) (xy 119.178784 -412.703673) (xy 119.156148 -412.753243) (xy 119.126688 -412.799087)
			(xy 119.091005 -412.840272) (xy 119.049824 -412.875961) (xy 119.003983 -412.905426) (xy 118.954416 -412.928068)
			(xy 118.902131 -412.943425) (xy 118.848193 -412.951187) (xy 118.820946 -412.951676) (xy 117.957346 -412.951676)
			(xy 117.930089 -412.95128) (xy 117.876128 -412.943528) (xy 117.82382 -412.928175) (xy 117.77423 -412.905533)
			(xy 117.728367 -412.876063) (xy 117.687166 -412.840367) (xy 117.651464 -412.799169) (xy 117.621989 -412.75331)
			(xy 117.599342 -412.703723) (xy 117.583982 -412.651417) (xy 117.576223 -412.597457) (xy 116.138689 -412.597457)
			(xy 116.130934 -412.651391) (xy 116.115581 -412.703681) (xy 116.092942 -412.753254) (xy 116.063479 -412.7991)
			(xy 116.027791 -412.840287) (xy 115.986605 -412.875975) (xy 115.940759 -412.905439) (xy 115.891187 -412.928079)
			(xy 115.838897 -412.943433) (xy 115.784955 -412.951189) (xy 115.757706 -412.951676) (xy 114.894106 -412.951676)
			(xy 114.866851 -412.951277) (xy 114.812894 -412.943521) (xy 114.760591 -412.928164) (xy 114.711006 -412.90552)
			(xy 114.665149 -412.876049) (xy 114.623952 -412.840353) (xy 114.588254 -412.799156) (xy 114.558783 -412.753299)
			(xy 114.536138 -412.703714) (xy 114.520781 -412.651411) (xy 114.513023 -412.597455) (xy 94.987413 -412.597455)
			(xy 94.979655 -412.651402) (xy 94.964299 -412.703698) (xy 94.941656 -412.753276) (xy 94.912187 -412.799127)
			(xy 94.876492 -412.840318) (xy 94.835299 -412.876008) (xy 94.789445 -412.905473) (xy 94.739864 -412.928111)
			(xy 94.687567 -412.943463) (xy 94.633616 -412.951215) (xy 94.606364 -412.951676) (xy 93.742764 -412.951676)
			(xy 93.715512 -412.951252) (xy 93.661564 -412.94349) (xy 93.609269 -412.928131) (xy 93.559692 -412.905486)
			(xy 93.513842 -412.876016) (xy 93.472653 -412.840321) (xy 93.436962 -412.799129) (xy 93.407497 -412.753276)
			(xy 93.384857 -412.703697) (xy 93.369502 -412.651401) (xy 93.361746 -412.597452) (xy 91.924089 -412.597452)
			(xy 91.916335 -412.651389) (xy 91.900982 -412.703677) (xy 91.878345 -412.753249) (xy 91.848883 -412.799094)
			(xy 91.813197 -412.84028) (xy 91.772013 -412.875969) (xy 91.72617 -412.905433) (xy 91.6766 -412.928074)
			(xy 91.624312 -412.94343) (xy 91.570372 -412.951188) (xy 91.543124 -412.951676) (xy 90.679524 -412.951676)
			(xy 90.652268 -412.951279) (xy 90.59831 -412.943524) (xy 90.546004 -412.928169) (xy 90.496417 -412.905526)
			(xy 90.450557 -412.876056) (xy 90.409358 -412.840359) (xy 90.373659 -412.799162) (xy 90.344186 -412.753304)
			(xy 90.32154 -412.703718) (xy 90.306181 -412.651414) (xy 90.298423 -412.597456) (xy 88.860912 -412.597456)
			(xy 88.853156 -412.651399) (xy 88.8378 -412.703694) (xy 88.815159 -412.753271) (xy 88.785692 -412.799121)
			(xy 88.749999 -412.840311) (xy 88.708808 -412.876001) (xy 88.662957 -412.905466) (xy 88.613379 -412.928106)
			(xy 88.561083 -412.943459) (xy 88.507135 -412.951214) (xy 88.479884 -412.951676) (xy 87.616284 -412.951676)
			(xy 87.589031 -412.951253) (xy 87.535081 -412.943494) (xy 87.482783 -412.928136) (xy 87.433204 -412.905492)
			(xy 87.387352 -412.876023) (xy 87.34616 -412.840329) (xy 87.310467 -412.799135) (xy 87.281 -412.753282)
			(xy 87.258358 -412.703702) (xy 87.243003 -412.651404) (xy 87.235246 -412.597453) (xy 85.797589 -412.597453)
			(xy 85.789835 -412.651386) (xy 85.774484 -412.703673) (xy 85.751848 -412.753243) (xy 85.722388 -412.799087)
			(xy 85.686704 -412.840273) (xy 85.645523 -412.875962) (xy 85.599682 -412.905427) (xy 85.550114 -412.928068)
			(xy 85.497829 -412.943426) (xy 85.443891 -412.951187) (xy 85.416644 -412.951676) (xy 84.553044 -412.951676)
			(xy 84.525787 -412.95128) (xy 84.471827 -412.943528) (xy 84.419519 -412.928174) (xy 84.369929 -412.905532)
			(xy 84.324067 -412.876063) (xy 84.282865 -412.840366) (xy 84.247164 -412.799169) (xy 84.217689 -412.75331)
			(xy 84.195041 -412.703722) (xy 84.179682 -412.651417) (xy 84.171923 -412.597457) (xy 82.734389 -412.597457)
			(xy 82.726634 -412.651392) (xy 82.71128 -412.703682) (xy 82.688642 -412.753254) (xy 82.659178 -412.799101)
			(xy 82.62349 -412.840287) (xy 82.582304 -412.875976) (xy 82.536458 -412.90544) (xy 82.486885 -412.928079)
			(xy 82.434595 -412.943433) (xy 82.380653 -412.95119) (xy 82.353404 -412.951676) (xy 81.489804 -412.951676)
			(xy 81.462549 -412.951277) (xy 81.408593 -412.94352) (xy 81.35629 -412.928163) (xy 81.306705 -412.905519)
			(xy 81.260848 -412.876049) (xy 81.219651 -412.840352) (xy 81.183954 -412.799156) (xy 81.154483 -412.753298)
			(xy 81.131838 -412.703714) (xy 81.116481 -412.651411) (xy 81.108723 -412.597455) (xy 79.671213 -412.597455)
			(xy 79.663455 -412.651402) (xy 79.648099 -412.703698) (xy 79.625456 -412.753276) (xy 79.595987 -412.799127)
			(xy 79.560292 -412.840318) (xy 79.519099 -412.876008) (xy 79.473245 -412.905473) (xy 79.423664 -412.928111)
			(xy 79.371367 -412.943463) (xy 79.317416 -412.951215) (xy 79.290164 -412.951676) (xy 78.426564 -412.951676)
			(xy 78.399312 -412.951252) (xy 78.345364 -412.94349) (xy 78.293069 -412.928131) (xy 78.243492 -412.905486)
			(xy 78.197642 -412.876016) (xy 78.156453 -412.840321) (xy 78.120762 -412.799129) (xy 78.091297 -412.753276)
			(xy 78.068657 -412.703697) (xy 78.053302 -412.651401) (xy 78.045546 -412.597452) (xy 76.607889 -412.597452)
			(xy 76.600135 -412.651389) (xy 76.584782 -412.703677) (xy 76.562145 -412.753249) (xy 76.532683 -412.799094)
			(xy 76.496997 -412.84028) (xy 76.455813 -412.875969) (xy 76.40997 -412.905433) (xy 76.3604 -412.928074)
			(xy 76.308112 -412.94343) (xy 76.254172 -412.951188) (xy 76.226924 -412.951676) (xy 75.363324 -412.951676)
			(xy 75.336068 -412.951279) (xy 75.28211 -412.943524) (xy 75.229804 -412.928169) (xy 75.180217 -412.905526)
			(xy 75.134357 -412.876056) (xy 75.093158 -412.840359) (xy 75.057459 -412.799162) (xy 75.027986 -412.753304)
			(xy 75.00534 -412.703718) (xy 74.989981 -412.651414) (xy 74.982223 -412.597456) (xy 73.544712 -412.597456)
			(xy 73.536956 -412.651399) (xy 73.5216 -412.703694) (xy 73.498959 -412.753271) (xy 73.469492 -412.799121)
			(xy 73.433799 -412.840311) (xy 73.392608 -412.876001) (xy 73.346757 -412.905466) (xy 73.297179 -412.928106)
			(xy 73.244883 -412.943459) (xy 73.190935 -412.951214) (xy 73.163684 -412.951676) (xy 72.300084 -412.951676)
			(xy 72.272831 -412.951253) (xy 72.218881 -412.943494) (xy 72.166583 -412.928136) (xy 72.117004 -412.905492)
			(xy 72.071152 -412.876023) (xy 72.02996 -412.840329) (xy 71.994267 -412.799135) (xy 71.9648 -412.753282)
			(xy 71.942158 -412.703702) (xy 71.926803 -412.651404) (xy 71.919046 -412.597453) (xy 70.481389 -412.597453)
			(xy 70.473635 -412.651386) (xy 70.458284 -412.703673) (xy 70.435648 -412.753243) (xy 70.406188 -412.799087)
			(xy 70.370504 -412.840273) (xy 70.329323 -412.875962) (xy 70.283482 -412.905427) (xy 70.233914 -412.928068)
			(xy 70.181629 -412.943426) (xy 70.127691 -412.951187) (xy 70.100444 -412.951676) (xy 69.236844 -412.951676)
			(xy 69.209587 -412.95128) (xy 69.155627 -412.943528) (xy 69.103319 -412.928174) (xy 69.053729 -412.905532)
			(xy 69.007867 -412.876063) (xy 68.966665 -412.840366) (xy 68.930964 -412.799169) (xy 68.901489 -412.75331)
			(xy 68.878841 -412.703722) (xy 68.863482 -412.651417) (xy 68.855723 -412.597457) (xy 67.418189 -412.597457)
			(xy 67.410434 -412.651392) (xy 67.39508 -412.703682) (xy 67.372442 -412.753254) (xy 67.342978 -412.799101)
			(xy 67.30729 -412.840287) (xy 67.266104 -412.875976) (xy 67.220258 -412.90544) (xy 67.170685 -412.928079)
			(xy 67.118395 -412.943433) (xy 67.064453 -412.95119) (xy 67.037204 -412.951676) (xy 66.173604 -412.951676)
			(xy 66.146349 -412.951277) (xy 66.092393 -412.94352) (xy 66.04009 -412.928163) (xy 65.990505 -412.905519)
			(xy 65.944648 -412.876049) (xy 65.903451 -412.840352) (xy 65.867754 -412.799156) (xy 65.838283 -412.753298)
			(xy 65.815638 -412.703714) (xy 65.800281 -412.651411) (xy 65.792523 -412.597455) (xy 64.355013 -412.597455)
			(xy 64.347255 -412.651402) (xy 64.331899 -412.703698) (xy 64.309256 -412.753276) (xy 64.279787 -412.799127)
			(xy 64.244092 -412.840318) (xy 64.202899 -412.876008) (xy 64.157045 -412.905473) (xy 64.107464 -412.928111)
			(xy 64.055167 -412.943463) (xy 64.001216 -412.951215) (xy 63.973964 -412.951676) (xy 63.110364 -412.951676)
			(xy 63.083112 -412.951252) (xy 63.029164 -412.94349) (xy 62.976869 -412.928131) (xy 62.927292 -412.905486)
			(xy 62.881442 -412.876016) (xy 62.840253 -412.840321) (xy 62.804562 -412.799129) (xy 62.775097 -412.753276)
			(xy 62.752457 -412.703697) (xy 62.737102 -412.651401) (xy 62.729346 -412.597452) (xy 61.291689 -412.597452)
			(xy 61.283935 -412.651389) (xy 61.268582 -412.703677) (xy 61.245945 -412.753249) (xy 61.216483 -412.799094)
			(xy 61.180797 -412.84028) (xy 61.139613 -412.875969) (xy 61.09377 -412.905433) (xy 61.0442 -412.928074)
			(xy 60.991912 -412.94343) (xy 60.937972 -412.951188) (xy 60.910724 -412.951676) (xy 60.047124 -412.951676)
			(xy 60.019868 -412.951279) (xy 59.96591 -412.943524) (xy 59.913604 -412.928169) (xy 59.864017 -412.905526)
			(xy 59.818157 -412.876056) (xy 59.776958 -412.840359) (xy 59.741259 -412.799162) (xy 59.711786 -412.753304)
			(xy 59.68914 -412.703718) (xy 59.673781 -412.651414) (xy 59.666023 -412.597456) (xy 58.228512 -412.597456)
			(xy 58.220756 -412.651399) (xy 58.2054 -412.703694) (xy 58.182759 -412.753271) (xy 58.153292 -412.799121)
			(xy 58.117599 -412.840311) (xy 58.076408 -412.876001) (xy 58.030557 -412.905466) (xy 57.980979 -412.928106)
			(xy 57.928683 -412.943459) (xy 57.874735 -412.951214) (xy 57.847484 -412.951676) (xy 56.983884 -412.951676)
			(xy 56.956631 -412.951253) (xy 56.902681 -412.943494) (xy 56.850383 -412.928136) (xy 56.800804 -412.905492)
			(xy 56.754952 -412.876023) (xy 56.71376 -412.840329) (xy 56.678067 -412.799135) (xy 56.6486 -412.753282)
			(xy 56.625958 -412.703702) (xy 56.610603 -412.651404) (xy 56.602846 -412.597453) (xy 55.165189 -412.597453)
			(xy 55.157435 -412.651386) (xy 55.142084 -412.703673) (xy 55.119448 -412.753243) (xy 55.089988 -412.799087)
			(xy 55.054304 -412.840273) (xy 55.013123 -412.875962) (xy 54.967282 -412.905427) (xy 54.917714 -412.928068)
			(xy 54.865429 -412.943426) (xy 54.811491 -412.951187) (xy 54.784244 -412.951676) (xy 53.920644 -412.951676)
			(xy 53.893387 -412.95128) (xy 53.839427 -412.943528) (xy 53.787119 -412.928174) (xy 53.737529 -412.905532)
			(xy 53.691667 -412.876063) (xy 53.650465 -412.840366) (xy 53.614764 -412.799169) (xy 53.585289 -412.75331)
			(xy 53.562641 -412.703722) (xy 53.547282 -412.651417) (xy 53.539523 -412.597457) (xy 52.101989 -412.597457)
			(xy 52.094234 -412.651392) (xy 52.07888 -412.703682) (xy 52.056242 -412.753254) (xy 52.026778 -412.799101)
			(xy 51.99109 -412.840287) (xy 51.949904 -412.875976) (xy 51.904058 -412.90544) (xy 51.854485 -412.928079)
			(xy 51.802195 -412.943433) (xy 51.748253 -412.95119) (xy 51.721004 -412.951676) (xy 50.857404 -412.951676)
			(xy 50.830149 -412.951277) (xy 50.776193 -412.94352) (xy 50.72389 -412.928163) (xy 50.674305 -412.905519)
			(xy 50.628448 -412.876049) (xy 50.587251 -412.840352) (xy 50.551554 -412.799156) (xy 50.522083 -412.753298)
			(xy 50.499438 -412.703714) (xy 50.484081 -412.651411) (xy 50.476323 -412.597455) (xy 49.038813 -412.597455)
			(xy 49.031055 -412.651402) (xy 49.015699 -412.703698) (xy 48.993056 -412.753276) (xy 48.963587 -412.799127)
			(xy 48.927892 -412.840318) (xy 48.886699 -412.876008) (xy 48.840845 -412.905473) (xy 48.791264 -412.928111)
			(xy 48.738967 -412.943463) (xy 48.685016 -412.951215) (xy 48.657764 -412.951676) (xy 47.794164 -412.951676)
			(xy 47.766912 -412.951252) (xy 47.712964 -412.94349) (xy 47.660669 -412.928131) (xy 47.611092 -412.905486)
			(xy 47.565242 -412.876016) (xy 47.524053 -412.840321) (xy 47.488362 -412.799129) (xy 47.458897 -412.753276)
			(xy 47.436257 -412.703697) (xy 47.420902 -412.651401) (xy 47.413146 -412.597452) (xy 40.731292 -412.597452)
			(xy 41.64457 -413.51073) (xy 41.651969 -413.517573) (xy 41.670568 -413.525293) (xy 41.680638 -413.525716)
			(xy 102.58425 -413.525716)
		)
		(stroke
			(width 0)
			(type solid)
		)
		(fill yes)
		(layer "In8.Cu")
		(net "P0V9_CPU1_RT_2D")
	)
	(gr_poly
		(pts
			(xy 58.120534 -440.465972) (xy 58.129457 -440.465412) (xy 58.146089 -440.458882) (xy 58.159474 -440.447046)
			(xy 58.167991 -440.431338) (xy 58.169556 -440.422538) (xy 58.169556 -440.422284) (xy 58.174454 -440.3911)
			(xy 58.191282 -440.330259) (xy 58.21586 -440.272116) (xy 58.247774 -440.217652) (xy 58.286483 -440.167789)
			(xy 58.331334 -440.123369) (xy 58.381569 -440.085143) (xy 58.436338 -440.053757) (xy 58.494716 -440.029741)
			(xy 58.555716 -440.013501) (xy 58.618308 -440.005312) (xy 58.681432 -440.005312) (xy 58.744024 -440.013501)
			(xy 58.805024 -440.029741) (xy 58.863402 -440.053757) (xy 58.918171 -440.085143) (xy 58.968406 -440.123369)
			(xy 59.013257 -440.167789) (xy 59.051966 -440.217652) (xy 59.08388 -440.272116) (xy 59.108458 -440.330259)
			(xy 59.125286 -440.3911) (xy 59.130184 -440.422284) (xy 59.130184 -440.422538) (xy 59.131813 -440.431328)
			(xy 59.140299 -440.44705) (xy 59.153663 -440.458907) (xy 59.170283 -440.465461) (xy 59.179206 -440.465972)
			(xy 62.119256 -440.465972) (xy 62.120526 -440.465972) (xy 62.129439 -440.465398) (xy 62.146044 -440.458851)
			(xy 62.159403 -440.447013) (xy 62.167901 -440.431316) (xy 62.169548 -440.422538) (xy 62.169548 -440.422284)
			(xy 62.174446 -440.3911) (xy 62.191274 -440.330259) (xy 62.215852 -440.272116) (xy 62.247766 -440.217652)
			(xy 62.286475 -440.167789) (xy 62.331326 -440.123369) (xy 62.381561 -440.085143) (xy 62.43633 -440.053757)
			(xy 62.494708 -440.029741) (xy 62.555708 -440.013501) (xy 62.6183 -440.005312) (xy 62.681424 -440.005312)
			(xy 62.744016 -440.013501) (xy 62.805016 -440.029741) (xy 62.863394 -440.053757) (xy 62.918163 -440.085143)
			(xy 62.968398 -440.123369) (xy 63.013249 -440.167789) (xy 63.051958 -440.217652) (xy 63.083872 -440.272116)
			(xy 63.10845 -440.330259) (xy 63.125278 -440.3911) (xy 63.130176 -440.422284) (xy 63.130176 -440.422538)
			(xy 63.131808 -440.431321) (xy 63.140298 -440.447026) (xy 63.153665 -440.458862) (xy 63.170283 -440.465387)
			(xy 63.179198 -440.465972) (xy 66.119248 -440.465972) (xy 66.120518 -440.465972) (xy 66.129432 -440.465399)
			(xy 66.146039 -440.458854) (xy 66.159401 -440.447016) (xy 66.1679 -440.431318) (xy 66.16954 -440.422538)
			(xy 66.16954 -440.422284) (xy 66.174438 -440.3911) (xy 66.191266 -440.330259) (xy 66.215844 -440.272116)
			(xy 66.247758 -440.217652) (xy 66.286467 -440.167789) (xy 66.331318 -440.123369) (xy 66.381553 -440.085143)
			(xy 66.436322 -440.053757) (xy 66.4947 -440.029741) (xy 66.5557 -440.013501) (xy 66.618292 -440.005312)
			(xy 66.681416 -440.005312) (xy 66.744008 -440.013501) (xy 66.805008 -440.029741) (xy 66.863386 -440.053757)
			(xy 66.918155 -440.085143) (xy 66.96839 -440.123369) (xy 67.013241 -440.167789) (xy 67.05195 -440.217652)
			(xy 67.083864 -440.272116) (xy 67.108442 -440.330259) (xy 67.12527 -440.3911) (xy 67.130168 -440.422284)
			(xy 67.130168 -440.422538) (xy 67.131799 -440.431322) (xy 67.140289 -440.447028) (xy 67.153656 -440.458865)
			(xy 67.170274 -440.465393) (xy 67.17919 -440.465972) (xy 70.11924 -440.465972) (xy 70.12051 -440.465972)
			(xy 70.129425 -440.465401) (xy 70.146034 -440.458856) (xy 70.159398 -440.447019) (xy 70.167899 -440.43132)
			(xy 70.169532 -440.422538) (xy 70.169532 -440.422284) (xy 70.17443 -440.3911) (xy 70.191258 -440.330259)
			(xy 70.215836 -440.272116) (xy 70.24775 -440.217652) (xy 70.286459 -440.167789) (xy 70.33131 -440.123369)
			(xy 70.381545 -440.085143) (xy 70.436314 -440.053757) (xy 70.494692 -440.029741) (xy 70.555692 -440.013501)
			(xy 70.618284 -440.005312) (xy 70.681408 -440.005312) (xy 70.744 -440.013501) (xy 70.805 -440.029741)
			(xy 70.863378 -440.053757) (xy 70.918147 -440.085143) (xy 70.968382 -440.123369) (xy 71.013233 -440.167789)
			(xy 71.051942 -440.217652) (xy 71.083856 -440.272116) (xy 71.108434 -440.330259) (xy 71.125262 -440.3911)
			(xy 71.13016 -440.422284) (xy 71.13016 -440.422538) (xy 71.131791 -440.431322) (xy 71.140281 -440.44703)
			(xy 71.153647 -440.458869) (xy 71.170265 -440.4654) (xy 71.179182 -440.465972) (xy 75.119484 -440.465972)
			(xy 75.120754 -440.465972) (xy 75.129675 -440.465409) (xy 75.146301 -440.458875) (xy 75.159681 -440.447038)
			(xy 75.168193 -440.431333) (xy 75.169776 -440.422538) (xy 75.169776 -440.422284) (xy 75.174674 -440.3911)
			(xy 75.191502 -440.330259) (xy 75.21608 -440.272116) (xy 75.247994 -440.217652) (xy 75.286703 -440.167789)
			(xy 75.331554 -440.123369) (xy 75.381789 -440.085143) (xy 75.436558 -440.053757) (xy 75.494936 -440.029741)
			(xy 75.555936 -440.013501) (xy 75.618528 -440.005312) (xy 75.681652 -440.005312) (xy 75.744244 -440.013501)
			(xy 75.805244 -440.029741) (xy 75.863622 -440.053757) (xy 75.918391 -440.085143) (xy 75.968626 -440.123369)
			(xy 76.013477 -440.167789) (xy 76.052186 -440.217652) (xy 76.0841 -440.272116) (xy 76.108678 -440.330259)
			(xy 76.125506 -440.3911) (xy 76.130404 -440.422284) (xy 76.130404 -440.422538) (xy 76.132034 -440.431326)
			(xy 76.140521 -440.447045) (xy 76.153885 -440.458897) (xy 76.170505 -440.465445) (xy 76.179426 -440.465972)
			(xy 79.119476 -440.465972) (xy 79.120746 -440.465972) (xy 79.129668 -440.465411) (xy 79.146296 -440.458878)
			(xy 79.159678 -440.447041) (xy 79.168193 -440.431335) (xy 79.169768 -440.422538) (xy 79.169768 -440.422284)
			(xy 79.174666 -440.3911) (xy 79.191494 -440.330259) (xy 79.216072 -440.272116) (xy 79.247986 -440.217652)
			(xy 79.286695 -440.167789) (xy 79.331546 -440.123369) (xy 79.381781 -440.085143) (xy 79.43655 -440.053757)
			(xy 79.494928 -440.029741) (xy 79.555928 -440.013501) (xy 79.61852 -440.005312) (xy 79.681644 -440.005312)
			(xy 79.744236 -440.013501) (xy 79.805236 -440.029741) (xy 79.863614 -440.053757) (xy 79.918383 -440.085143)
			(xy 79.968618 -440.123369) (xy 80.013469 -440.167789) (xy 80.052178 -440.217652) (xy 80.084092 -440.272116)
			(xy 80.10867 -440.330259) (xy 80.125498 -440.3911) (xy 80.130396 -440.422284) (xy 80.130396 -440.422538)
			(xy 80.132025 -440.431327) (xy 80.140512 -440.447047) (xy 80.153876 -440.458901) (xy 80.170496 -440.465451)
			(xy 80.179418 -440.465972) (xy 83.119468 -440.465972) (xy 83.120738 -440.465972) (xy 83.129661 -440.465412)
			(xy 83.146291 -440.458881) (xy 83.159676 -440.447044) (xy 83.168192 -440.431337) (xy 83.16976 -440.422538)
			(xy 83.16976 -440.422284) (xy 83.174658 -440.3911) (xy 83.191486 -440.330259) (xy 83.216064 -440.272116)
			(xy 83.247978 -440.217652) (xy 83.286687 -440.167789) (xy 83.331538 -440.123369) (xy 83.381773 -440.085143)
			(xy 83.436542 -440.053757) (xy 83.49492 -440.029741) (xy 83.55592 -440.013501) (xy 83.618512 -440.005312)
			(xy 83.681636 -440.005312) (xy 83.744228 -440.013501) (xy 83.805228 -440.029741) (xy 83.863606 -440.053757)
			(xy 83.918375 -440.085143) (xy 83.96861 -440.123369) (xy 84.013461 -440.167789) (xy 84.05217 -440.217652)
			(xy 84.084084 -440.272116) (xy 84.108662 -440.330259) (xy 84.12549 -440.3911) (xy 84.130388 -440.422284)
			(xy 84.130388 -440.422538) (xy 84.132017 -440.431328) (xy 84.140503 -440.447049) (xy 84.153867 -440.458905)
			(xy 84.170488 -440.465458) (xy 84.17941 -440.465972) (xy 87.11946 -440.465972) (xy 87.12073 -440.465972)
			(xy 87.129654 -440.465413) (xy 87.146287 -440.458883) (xy 87.159673 -440.447047) (xy 87.168191 -440.431339)
			(xy 87.169752 -440.422538) (xy 87.169752 -440.422284) (xy 87.17465 -440.3911) (xy 87.191478 -440.330259)
			(xy 87.216056 -440.272116) (xy 87.24797 -440.217652) (xy 87.286679 -440.167789) (xy 87.33153 -440.123369)
			(xy 87.381765 -440.085143) (xy 87.436534 -440.053757) (xy 87.494912 -440.029741) (xy 87.555912 -440.013501)
			(xy 87.618504 -440.005312) (xy 87.681628 -440.005312) (xy 87.74422 -440.013501) (xy 87.80522 -440.029741)
			(xy 87.863598 -440.053757) (xy 87.918367 -440.085143) (xy 87.968602 -440.123369) (xy 88.013453 -440.167789)
			(xy 88.052162 -440.217652) (xy 88.084076 -440.272116) (xy 88.108654 -440.330259) (xy 88.125482 -440.3911)
			(xy 88.13038 -440.422284) (xy 88.13038 -440.422538) (xy 88.132012 -440.431321) (xy 88.140502 -440.447025)
			(xy 88.153869 -440.45886) (xy 88.170487 -440.465384) (xy 88.179402 -440.465972) (xy 98.017076 -440.465972)
			(xy 98.028369 -440.465371) (xy 98.048772 -440.455686) (xy 98.063042 -440.43818) (xy 98.066352 -440.427364)
			(xy 98.089974 -440.331352) (xy 98.092091 -440.320238) (xy 98.08758 -440.298097) (xy 98.074025 -440.280019)
			(xy 98.06432 -440.274202) (xy 98.064066 -440.274202) (xy 97.973298 -440.226317) (xy 97.795135 -440.124417)
			(xy 97.621073 -440.015658) (xy 97.451376 -439.900207) (xy 97.286302 -439.778237) (xy 97.126101 -439.649935)
			(xy 96.971015 -439.515494) (xy 96.82128 -439.375118) (xy 96.677123 -439.229021) (xy 96.538762 -439.077422)
			(xy 96.406406 -438.920553) (xy 96.280257 -438.758651) (xy 96.160505 -438.591961) (xy 96.047333 -438.420736)
			(xy 95.940911 -438.245236) (xy 95.841402 -438.065726) (xy 95.748955 -437.882479) (xy 95.663711 -437.695772)
			(xy 95.585799 -437.505889) (xy 95.515338 -437.313116) (xy 95.452433 -437.117748) (xy 95.397181 -436.920078)
			(xy 95.349665 -436.720408) (xy 95.309958 -436.51904) (xy 95.278118 -436.316278) (xy 95.254196 -436.112431)
			(xy 95.238226 -435.907807) (xy 95.230233 -435.702717) (xy 95.22968 -435.600094) (xy 95.230176 -435.497873)
			(xy 95.238103 -435.293583) (xy 95.253946 -435.089755) (xy 95.27768 -434.886695) (xy 95.30927 -434.684707)
			(xy 95.348669 -434.484096) (xy 95.395817 -434.285164) (xy 95.450643 -434.08821) (xy 95.513065 -433.893529)
			(xy 95.582988 -433.701416) (xy 95.660309 -433.512158) (xy 95.744909 -433.326041) (xy 95.836663 -433.143344)
			(xy 95.935432 -432.964342) (xy 96.041068 -432.789305) (xy 96.153411 -432.618495) (xy 96.272293 -432.45217)
			(xy 96.397535 -432.29058) (xy 96.528948 -432.133968) (xy 96.666335 -431.982569) (xy 96.80949 -431.836611)
			(xy 96.958196 -431.696314) (xy 97.112231 -431.561888) (xy 97.271362 -431.433536) (xy 97.435351 -431.311451)
			(xy 97.603949 -431.195817) (xy 97.776905 -431.086807) (xy 97.953958 -430.984586) (xy 98.134842 -430.889306)
			(xy 98.319283 -430.801113) (xy 98.507006 -430.720137) (xy 98.697728 -430.646501) (xy 98.891161 -430.580316)
			(xy 99.087015 -430.521681) (xy 99.284996 -430.470685) (xy 99.484805 -430.427403) (xy 99.686142 -430.391902)
			(xy 99.888704 -430.364235) (xy 100.092186 -430.344442) (xy 100.296283 -430.332555) (xy 100.500688 -430.328591)
			(xy 100.705093 -430.332555) (xy 100.90919 -430.344442) (xy 101.112672 -430.364235) (xy 101.315234 -430.391902)
			(xy 101.516571 -430.427403) (xy 101.71638 -430.470685) (xy 101.914361 -430.521681) (xy 102.110215 -430.580316)
			(xy 102.303648 -430.646501) (xy 102.49437 -430.720137) (xy 102.682093 -430.801113) (xy 102.866534 -430.889306)
			(xy 103.047418 -430.984586) (xy 103.224471 -431.086807) (xy 103.397427 -431.195817) (xy 103.566025 -431.311451)
			(xy 103.631334 -431.360072) (xy 108.13796 -431.360072) (xy 108.138464 -431.271581) (xy 108.146519 -431.094782)
			(xy 108.162613 -430.918533) (xy 108.186712 -430.743199) (xy 108.218766 -430.569144) (xy 108.25871 -430.396728)
			(xy 108.306459 -430.226308) (xy 108.361915 -430.058239) (xy 108.424964 -429.892868) (xy 108.495474 -429.730538)
			(xy 108.573299 -429.571585) (xy 108.658278 -429.416339) (xy 108.750235 -429.265122) (xy 108.84898 -429.118247)
			(xy 108.954307 -428.976019) (xy 109.065998 -428.838732) (xy 109.183822 -428.70667) (xy 109.307535 -428.580108)
			(xy 109.43688 -428.459309) (xy 109.571589 -428.344521) (xy 109.711383 -428.235984) (xy 109.855973 -428.133922)
			(xy 110.005057 -428.038546) (xy 110.158328 -427.950055) (xy 110.315468 -427.868632) (xy 110.476152 -427.794445)
			(xy 110.640045 -427.727648) (xy 110.806808 -427.66838) (xy 110.976096 -427.616764) (xy 111.147558 -427.572907)
			(xy 111.320839 -427.536899) (xy 111.495579 -427.508815) (xy 111.671416 -427.488713) (xy 111.847986 -427.476635)
			(xy 112.024922 -427.472607) (xy 112.201858 -427.476635) (xy 112.378428 -427.488713) (xy 112.554265 -427.508815)
			(xy 112.729005 -427.536899) (xy 112.902286 -427.572907) (xy 113.073748 -427.616764) (xy 113.243036 -427.66838)
			(xy 113.409799 -427.727648) (xy 113.573692 -427.794445) (xy 113.734376 -427.868632) (xy 113.891516 -427.950055)
			(xy 113.90967 -427.960536) (xy 125.241304 -427.960536) (xy 125.241304 -425.419012) (xy 125.241723 -425.406929)
			(xy 125.249189 -425.383944) (xy 125.263393 -425.364393) (xy 125.282944 -425.350189) (xy 125.305929 -425.342723)
			(xy 125.318012 -425.342304) (xy 126.257812 -425.342304) (xy 126.269888 -425.342754) (xy 126.292858 -425.350222)
			(xy 126.312396 -425.364421) (xy 126.326589 -425.383964) (xy 126.334049 -425.406935) (xy 126.33452 -425.419012)
			(xy 126.33452 -427.960536) (xy 126.334067 -427.972611) (xy 126.326596 -427.995578) (xy 126.312396 -428.015113)
			(xy 126.292856 -428.029307) (xy 126.269887 -428.036771) (xy 126.257812 -428.037244) (xy 125.318012 -428.037244)
			(xy 125.305942 -428.036726) (xy 125.282981 -428.029271) (xy 125.263447 -428.015087) (xy 125.249251 -427.995562)
			(xy 125.241781 -427.972606) (xy 125.241304 -427.960536) (xy 113.90967 -427.960536) (xy 114.044787 -428.038546)
			(xy 114.193871 -428.133922) (xy 114.338461 -428.235984) (xy 114.478255 -428.344521) (xy 114.612964 -428.459309)
			(xy 114.742309 -428.580108) (xy 114.866022 -428.70667) (xy 114.983846 -428.838732) (xy 115.095537 -428.976019)
			(xy 115.200864 -429.118247) (xy 115.299609 -429.265122) (xy 115.391566 -429.416339) (xy 115.476545 -429.571585)
			(xy 115.55437 -429.730538) (xy 115.62488 -429.892868) (xy 115.687929 -430.058239) (xy 115.743385 -430.226308)
			(xy 115.791134 -430.396728) (xy 115.831078 -430.569144) (xy 115.863132 -430.743199) (xy 115.887231 -430.918533)
			(xy 115.903325 -431.094782) (xy 115.91138 -431.271581) (xy 115.911884 -431.360072) (xy 115.911414 -431.447087)
			(xy 115.906335 -431.560478) (xy 125.241304 -431.560478) (xy 125.241304 -429.018954) (xy 125.241767 -429.006866)
			(xy 125.249232 -428.98387) (xy 125.263421 -428.964293) (xy 125.282953 -428.950043) (xy 125.305925 -428.942506)
			(xy 125.318012 -428.941992) (xy 126.257812 -428.941992) (xy 126.269921 -428.942406) (xy 126.292947 -428.949908)
			(xy 126.307529 -428.960534) (xy 127.2413 -428.960534) (xy 127.2413 -426.41901) (xy 127.241815 -426.406925)
			(xy 127.249264 -426.383931) (xy 127.26344 -426.364355) (xy 127.282961 -426.350103) (xy 127.305925 -426.342563)
			(xy 127.318008 -426.342048) (xy 128.257808 -426.342048) (xy 128.269912 -426.342509) (xy 128.292931 -426.350004)
			(xy 128.312499 -426.364256) (xy 128.326696 -426.383865) (xy 128.334125 -426.406905) (xy 128.334516 -426.41901)
			(xy 128.334516 -427.960536) (xy 129.241296 -427.960536) (xy 129.241296 -425.419012) (xy 129.241723 -425.40693)
			(xy 129.249188 -425.383947) (xy 129.26339 -425.364396) (xy 129.282939 -425.350191) (xy 129.305922 -425.342724)
			(xy 129.318004 -425.342304) (xy 130.257804 -425.342304) (xy 130.269888 -425.342709) (xy 130.292873 -425.350179)
			(xy 130.312424 -425.364387) (xy 130.326628 -425.383941) (xy 130.334093 -425.406928) (xy 130.334512 -425.419012)
			(xy 130.334512 -427.960536) (xy 130.334067 -427.972612) (xy 130.326595 -427.99558) (xy 130.312393 -428.015116)
			(xy 130.292851 -428.029309) (xy 130.26988 -428.036772) (xy 130.257804 -428.037244) (xy 129.318004 -428.037244)
			(xy 129.305933 -428.036733) (xy 129.282972 -428.029276) (xy 129.263438 -428.01509) (xy 129.249242 -427.995564)
			(xy 129.241773 -427.972607) (xy 129.241296 -427.960536) (xy 128.334516 -427.960536) (xy 128.334516 -428.960534)
			(xy 128.334121 -428.97263) (xy 128.326649 -428.995639) (xy 128.312446 -429.015222) (xy 128.292895 -429.02947)
			(xy 128.269903 -429.036993) (xy 128.257808 -429.037496) (xy 127.318008 -429.037496) (xy 127.305899 -429.037077)
			(xy 127.282871 -429.029579) (xy 127.263298 -429.015319) (xy 127.249103 -428.995697) (xy 127.241683 -428.972644)
			(xy 127.2413 -428.960534) (xy 126.307529 -428.960534) (xy 126.312519 -428.96417) (xy 126.326714 -428.983792)
			(xy 126.334136 -429.006844) (xy 126.33452 -429.018954) (xy 126.33452 -431.560478) (xy 126.334073 -431.57257)
			(xy 126.326618 -431.595577) (xy 126.312427 -431.615161) (xy 126.292887 -431.629411) (xy 126.269903 -431.636936)
			(xy 126.257812 -431.63744) (xy 125.318012 -431.63744) (xy 125.305908 -431.636974) (xy 125.282888 -431.629483)
			(xy 125.263318 -431.615232) (xy 125.249122 -431.595624) (xy 125.241693 -431.572583) (xy 125.241304 -431.560478)
			(xy 115.906335 -431.560478) (xy 115.903626 -431.620942) (xy 115.888064 -431.794275) (xy 115.86476 -431.966737)
			(xy 115.83376 -432.137984) (xy 115.795126 -432.307671) (xy 115.748935 -432.475459) (xy 115.695281 -432.641011)
			(xy 115.634271 -432.803996) (xy 115.566027 -432.964087) (xy 115.490686 -433.120963) (xy 115.408398 -433.27431)
			(xy 115.31933 -433.423819) (xy 115.223659 -433.569193) (xy 115.121577 -433.710138) (xy 115.013289 -433.846373)
			(xy 114.899011 -433.977625) (xy 114.778974 -434.10363) (xy 114.653417 -434.224137) (xy 114.522592 -434.338902)
			(xy 114.386761 -434.447698) (xy 114.246197 -434.550304) (xy 114.101181 -434.646516) (xy 113.952004 -434.736141)
			(xy 113.798966 -434.818999) (xy 113.72088 -434.857398) (xy 113.710212 -434.862478) (xy 113.695734 -434.881274)
			(xy 113.674906 -434.984398) (xy 113.681256 -435.007258) (xy 113.68913 -435.016148) (xy 113.733262 -435.066761)
			(xy 113.806634 -435.16042) (xy 125.241304 -435.16042) (xy 125.241304 -432.618896) (xy 125.241709 -432.606812)
			(xy 125.249179 -432.583827) (xy 125.263387 -432.564276) (xy 125.282941 -432.550072) (xy 125.305928 -432.542607)
			(xy 125.318012 -432.542188) (xy 126.257812 -432.542188) (xy 126.269887 -432.542654) (xy 126.292854 -432.550119)
			(xy 126.307106 -432.560476) (xy 127.2413 -432.560476) (xy 127.2413 -430.018952) (xy 127.241723 -430.006874)
			(xy 127.2492 -429.983904) (xy 127.263407 -429.964367) (xy 127.282954 -429.950174) (xy 127.30593 -429.942714)
			(xy 127.318008 -429.942244) (xy 128.257808 -429.942244) (xy 128.269878 -429.942757) (xy 128.292837 -429.950216)
			(xy 128.31237 -429.964401) (xy 128.326566 -429.983927) (xy 128.334037 -430.006882) (xy 128.334516 -430.018952)
			(xy 128.334516 -431.560478) (xy 129.241296 -431.560478) (xy 129.241296 -429.018954) (xy 129.241767 -429.006866)
			(xy 129.249231 -428.983872) (xy 129.263418 -428.964296) (xy 129.282948 -428.950046) (xy 129.305918 -428.942507)
			(xy 129.318004 -428.941992) (xy 130.257804 -428.941992) (xy 130.269912 -428.942413) (xy 130.292938 -428.949912)
			(xy 130.307517 -428.960534) (xy 131.241292 -428.960534) (xy 131.241292 -426.41901) (xy 131.241815 -426.406926)
			(xy 131.249263 -426.383934) (xy 131.263437 -426.364358) (xy 131.282956 -426.350105) (xy 131.305918 -426.342564)
			(xy 131.318 -426.342048) (xy 132.2578 -426.342048) (xy 132.269904 -426.342515) (xy 132.292922 -426.350009)
			(xy 132.312491 -426.364259) (xy 132.326687 -426.383866) (xy 132.334117 -426.406905) (xy 132.334508 -426.41901)
			(xy 132.334508 -427.960536) (xy 133.241288 -427.960536) (xy 133.241288 -425.419012) (xy 133.241723 -425.40693)
			(xy 133.249187 -425.383949) (xy 133.263387 -425.364399) (xy 133.282934 -425.350194) (xy 133.305914 -425.342726)
			(xy 133.317996 -425.342304) (xy 134.257796 -425.342304) (xy 134.26988 -425.342716) (xy 134.292864 -425.350184)
			(xy 134.312416 -425.36439) (xy 134.32662 -425.383943) (xy 134.334085 -425.406928) (xy 134.334504 -425.419012)
			(xy 134.334504 -427.960536) (xy 134.334067 -427.972613) (xy 134.326594 -427.995582) (xy 134.31239 -428.015119)
			(xy 134.292846 -428.029312) (xy 134.269873 -428.036773) (xy 134.257796 -428.037244) (xy 133.317996 -428.037244)
			(xy 133.305925 -428.03674) (xy 133.282964 -428.02928) (xy 133.26343 -428.015093) (xy 133.249234 -427.995565)
			(xy 133.241765 -427.972607) (xy 133.241288 -427.960536) (xy 132.334508 -427.960536) (xy 132.334508 -428.960534)
			(xy 132.334023 -428.972621) (xy 132.326562 -428.995614) (xy 132.312379 -429.01519) (xy 132.292853 -429.029441)
			(xy 132.269885 -429.03698) (xy 132.2578 -429.037496) (xy 131.318 -429.037496) (xy 131.305891 -429.037084)
			(xy 131.282863 -429.029584) (xy 131.263289 -429.015321) (xy 131.249095 -428.995699) (xy 131.241675 -428.972645)
			(xy 131.241292 -428.960534) (xy 130.307517 -428.960534) (xy 130.312511 -428.964173) (xy 130.326706 -428.983793)
			(xy 130.334128 -429.006844) (xy 130.334512 -429.018954) (xy 130.334512 -431.560478) (xy 130.334073 -431.572571)
			(xy 130.326616 -431.595579) (xy 130.312424 -431.615164) (xy 130.292882 -431.629413) (xy 130.269896 -431.636937)
			(xy 130.257804 -431.63744) (xy 129.318004 -431.63744) (xy 129.305899 -431.636981) (xy 129.282879 -431.629488)
			(xy 129.263309 -431.615236) (xy 129.249113 -431.595625) (xy 129.241685 -431.572584) (xy 129.241296 -431.560478)
			(xy 128.334516 -431.560478) (xy 128.334516 -432.560476) (xy 128.334067 -432.572557) (xy 128.326607 -432.595537)
			(xy 128.31241 -432.615087) (xy 128.292866 -432.629292) (xy 128.269888 -432.636762) (xy 128.257808 -432.637184)
			(xy 127.318008 -432.637184) (xy 127.305923 -432.63678) (xy 127.282937 -432.629312) (xy 127.263384 -432.615105)
			(xy 127.249181 -432.595549) (xy 127.241717 -432.572561) (xy 127.2413 -432.560476) (xy 126.307106 -432.560476)
			(xy 126.31239 -432.564316) (xy 126.326584 -432.583854) (xy 126.334047 -432.606821) (xy 126.33452 -432.618896)
			(xy 126.33452 -435.16042) (xy 126.334053 -435.172494) (xy 126.326586 -435.19546) (xy 126.31239 -435.214996)
			(xy 126.292853 -435.22919) (xy 126.269886 -435.236654) (xy 126.257812 -435.237128) (xy 125.318012 -435.237128)
			(xy 125.30594 -435.236626) (xy 125.282977 -435.229169) (xy 125.263441 -435.214982) (xy 125.249246 -435.195452)
			(xy 125.241779 -435.172492) (xy 125.241304 -435.16042) (xy 113.806634 -435.16042) (xy 113.816083 -435.172481)
			(xy 113.892372 -435.283007) (xy 113.96185 -435.397937) (xy 114.024263 -435.516852) (xy 114.079384 -435.639317)
			(xy 114.127013 -435.764886) (xy 114.166974 -435.893101) (xy 114.199124 -436.023494) (xy 114.223343 -436.155591)
			(xy 114.239544 -436.288908) (xy 114.247669 -436.422961) (xy 114.248184 -436.49011) (xy 114.247677 -436.557275)
			(xy 114.239566 -436.691359) (xy 114.223375 -436.824708) (xy 114.199161 -436.956837) (xy 114.167014 -437.087263)
			(xy 114.127051 -437.21551) (xy 114.079417 -437.34111) (xy 114.024287 -437.463604) (xy 113.961861 -437.582547)
			(xy 113.892367 -437.697503) (xy 113.81606 -437.808054) (xy 113.733216 -437.913796) (xy 113.64414 -438.014343)
			(xy 113.549155 -438.109328) (xy 113.448608 -438.198404) (xy 113.342866 -438.281248) (xy 113.232315 -438.357555)
			(xy 113.117359 -438.427049) (xy 112.998416 -438.489475) (xy 112.875922 -438.544605) (xy 112.750322 -438.592239)
			(xy 112.622075 -438.632202) (xy 112.491649 -438.664349) (xy 112.35952 -438.688563) (xy 112.226171 -438.704754)
			(xy 112.092087 -438.712865) (xy 111.957757 -438.712865) (xy 111.823673 -438.704754) (xy 111.690324 -438.688563)
			(xy 111.558195 -438.664349) (xy 111.427769 -438.632202) (xy 111.299522 -438.592239) (xy 111.173922 -438.544605)
			(xy 111.051428 -438.489475) (xy 110.932485 -438.427049) (xy 110.817529 -438.357555) (xy 110.706978 -438.281248)
			(xy 110.601236 -438.198404) (xy 110.500689 -438.109328) (xy 110.405704 -438.014343) (xy 110.316628 -437.913796)
			(xy 110.233784 -437.808054) (xy 110.157477 -437.697503) (xy 110.087983 -437.582547) (xy 110.025557 -437.463604)
			(xy 109.970427 -437.34111) (xy 109.922793 -437.21551) (xy 109.88283 -437.087263) (xy 109.850683 -436.956837)
			(xy 109.826469 -436.824708) (xy 109.810278 -436.691359) (xy 109.802167 -436.557275) (xy 109.80166 -436.49011)
			(xy 109.802144 -436.42296) (xy 109.810269 -436.288906) (xy 109.826471 -436.155587) (xy 109.850691 -436.023489)
			(xy 109.882841 -435.893094) (xy 109.922804 -435.764877) (xy 109.970434 -435.639307) (xy 110.025557 -435.516841)
			(xy 110.087972 -435.397926) (xy 110.157452 -435.282995) (xy 110.233742 -435.172468) (xy 110.316566 -435.066748)
			(xy 110.360714 -435.016148) (xy 110.368588 -435.007258) (xy 110.374938 -434.984398) (xy 110.35411 -434.881274)
			(xy 110.339632 -434.862478) (xy 110.328964 -434.857398) (xy 110.250887 -434.818983) (xy 110.097852 -434.736122)
			(xy 109.948678 -434.646495) (xy 109.803665 -434.550281) (xy 109.663104 -434.447673) (xy 109.527276 -434.338877)
			(xy 109.396454 -434.22411) (xy 109.270899 -434.103604) (xy 109.150864 -433.977598) (xy 109.036588 -433.846347)
			(xy 108.928302 -433.710112) (xy 108.826221 -433.569168) (xy 108.730551 -433.423796) (xy 108.641483 -433.274288)
			(xy 108.559196 -433.120943) (xy 108.483855 -432.964069) (xy 108.41561 -432.80398) (xy 108.354599 -432.640997)
			(xy 108.300943 -432.475446) (xy 108.254751 -432.30766) (xy 108.216115 -432.137975) (xy 108.185111 -431.966731)
			(xy 108.161804 -431.79427) (xy 108.146238 -431.62094) (xy 108.138446 -431.447086) (xy 108.13796 -431.360072)
			(xy 103.631334 -431.360072) (xy 103.730014 -431.433536) (xy 103.889145 -431.561888) (xy 104.04318 -431.696314)
			(xy 104.191886 -431.836611) (xy 104.335041 -431.982569) (xy 104.472428 -432.133968) (xy 104.603841 -432.29058)
			(xy 104.729083 -432.45217) (xy 104.847965 -432.618495) (xy 104.960308 -432.789305) (xy 105.065944 -432.964342)
			(xy 105.164713 -433.143344) (xy 105.256467 -433.326041) (xy 105.341067 -433.512158) (xy 105.418388 -433.701416)
			(xy 105.488311 -433.893529) (xy 105.550733 -434.08821) (xy 105.605559 -434.285164) (xy 105.652707 -434.484096)
			(xy 105.692106 -434.684707) (xy 105.723696 -434.886695) (xy 105.74743 -435.089755) (xy 105.763273 -435.293583)
			(xy 105.7712 -435.497873) (xy 105.771696 -435.600094) (xy 105.7712 -435.702718) (xy 105.763212 -435.907811)
			(xy 105.747246 -436.112437) (xy 105.723327 -436.316287) (xy 105.69149 -436.519051) (xy 105.651785 -436.720423)
			(xy 105.604271 -436.920096) (xy 105.54902 -437.117768) (xy 105.486116 -437.313139) (xy 105.415654 -437.505914)
			(xy 105.337742 -437.695799) (xy 105.252497 -437.882508) (xy 105.160048 -438.065757) (xy 105.060536 -438.245268)
			(xy 104.954112 -438.420769) (xy 104.840936 -438.591994) (xy 104.721181 -438.758684) (xy 104.719676 -438.760616)
			(xy 125.241304 -438.760616) (xy 125.241304 -436.219092) (xy 125.241706 -436.207008) (xy 125.249177 -436.184023)
			(xy 125.263386 -436.164471) (xy 125.282941 -436.150268) (xy 125.305928 -436.142803) (xy 125.318012 -436.142384)
			(xy 126.257812 -436.142384) (xy 126.269886 -436.142854) (xy 126.292853 -436.150319) (xy 126.306752 -436.160418)
			(xy 127.2413 -436.160418) (xy 127.2413 -433.618894) (xy 127.241802 -433.606808) (xy 127.249255 -433.583814)
			(xy 127.263434 -433.564238) (xy 127.282958 -433.549986) (xy 127.305924 -433.542447) (xy 127.318008 -433.541932)
			(xy 128.257808 -433.541932) (xy 128.269921 -433.54231) (xy 128.292954 -433.549815) (xy 128.312529 -433.564086)
			(xy 128.326723 -433.583717) (xy 128.334137 -433.60678) (xy 128.334516 -433.618894) (xy 128.334516 -435.16042)
			(xy 129.241296 -435.16042) (xy 129.241296 -432.618896) (xy 129.241761 -432.606821) (xy 129.249225 -432.583853)
			(xy 129.263421 -432.564316) (xy 129.28296 -432.550121) (xy 129.305929 -432.54266) (xy 129.318004 -432.542188)
			(xy 130.257804 -432.542188) (xy 130.269878 -432.542661) (xy 130.292845 -432.550124) (xy 130.307094 -432.560476)
			(xy 131.241292 -432.560476) (xy 131.241292 -430.018952) (xy 131.241723 -430.006875) (xy 131.249199 -429.983906)
			(xy 131.263404 -429.96437) (xy 131.282949 -429.950177) (xy 131.305923 -429.942716) (xy 131.318 -429.942244)
			(xy 132.2578 -429.942244) (xy 132.26987 -429.942764) (xy 132.292829 -429.95022) (xy 132.312362 -429.964404)
			(xy 132.326558 -429.983928) (xy 132.334029 -430.006883) (xy 132.334508 -430.018952) (xy 132.334508 -431.560478)
			(xy 133.241288 -431.560478) (xy 133.241288 -429.018954) (xy 133.241669 -429.006857) (xy 133.249144 -428.983847)
			(xy 133.263351 -428.964264) (xy 133.282905 -428.950016) (xy 133.3059 -428.942494) (xy 133.317996 -428.941992)
			(xy 134.257796 -428.941992) (xy 134.269904 -428.942419) (xy 134.29293 -428.949917) (xy 134.307503 -428.960534)
			(xy 135.241284 -428.960534) (xy 135.241284 -426.41901) (xy 135.241717 -426.406917) (xy 135.249176 -426.383909)
			(xy 135.26337 -426.364325) (xy 135.282914 -426.350076) (xy 135.3059 -426.342551) (xy 135.317992 -426.342048)
			(xy 136.257792 -426.342048) (xy 136.269895 -426.342522) (xy 136.292914 -426.350013) (xy 136.312482 -426.364262)
			(xy 136.326679 -426.383868) (xy 136.334109 -426.406906) (xy 136.3345 -426.41901) (xy 136.3345 -427.960536)
			(xy 137.24128 -427.960536) (xy 137.24128 -425.419012) (xy 137.241774 -425.406939) (xy 137.249232 -425.383974)
			(xy 137.263421 -425.364438) (xy 137.282953 -425.350243) (xy 137.305915 -425.342778) (xy 137.317988 -425.342304)
			(xy 138.257788 -425.342304) (xy 138.269871 -425.342723) (xy 138.292856 -425.350189) (xy 138.312407 -425.364393)
			(xy 138.326611 -425.383944) (xy 138.334077 -425.406929) (xy 138.334496 -425.419012) (xy 138.334496 -427.960536)
			(xy 138.334066 -427.972614) (xy 138.326593 -427.995584) (xy 138.312387 -428.015122) (xy 138.292841 -428.029315)
			(xy 138.269866 -428.036774) (xy 138.257788 -428.037244) (xy 137.317988 -428.037244) (xy 137.305916 -428.036746)
			(xy 137.282955 -428.029285) (xy 137.263421 -428.015096) (xy 137.249226 -427.995567) (xy 137.241757 -427.972607)
			(xy 137.24128 -427.960536) (xy 136.3345 -427.960536) (xy 136.3345 -428.960534) (xy 136.334022 -428.972621)
			(xy 136.326561 -428.995616) (xy 136.312376 -429.015192) (xy 136.292848 -429.029443) (xy 136.269878 -429.036981)
			(xy 136.257792 -429.037496) (xy 135.317992 -429.037496) (xy 135.305882 -429.037091) (xy 135.282854 -429.029588)
			(xy 135.263281 -429.015324) (xy 135.249086 -428.9957) (xy 135.241667 -428.972645) (xy 135.241284 -428.960534)
			(xy 134.307503 -428.960534) (xy 134.312502 -428.964176) (xy 134.326697 -428.983795) (xy 134.33412 -429.006845)
			(xy 134.334504 -429.018954) (xy 134.334504 -431.560478) (xy 134.333975 -431.572562) (xy 134.326529 -431.595555)
			(xy 134.312357 -431.615131) (xy 134.29284 -431.629384) (xy 134.269878 -431.636924) (xy 134.257796 -431.63744)
			(xy 133.317996 -431.63744) (xy 133.305891 -431.636988) (xy 133.28287 -431.629492) (xy 133.263301 -431.615238)
			(xy 133.249105 -431.595627) (xy 133.241677 -431.572584) (xy 133.241288 -431.560478) (xy 132.334508 -431.560478)
			(xy 132.334508 -432.560476) (xy 132.334067 -432.572557) (xy 132.326606 -432.595539) (xy 132.312407 -432.61509)
			(xy 132.292861 -432.629295) (xy 132.269881 -432.636763) (xy 132.2578 -432.637184) (xy 131.318 -432.637184)
			(xy 131.305915 -432.636787) (xy 131.282928 -432.629317) (xy 131.263376 -432.615107) (xy 131.249172 -432.59555)
			(xy 131.241709 -432.572561) (xy 131.241292 -432.560476) (xy 130.307094 -432.560476) (xy 130.312382 -432.564318)
			(xy 130.326576 -432.583855) (xy 130.334039 -432.606822) (xy 130.334512 -432.618896) (xy 130.334512 -435.16042)
			(xy 130.334053 -435.172495) (xy 130.326585 -435.195462) (xy 130.312387 -435.214999) (xy 130.292848 -435.229193)
			(xy 130.269879 -435.236655) (xy 130.257804 -435.237128) (xy 129.318004 -435.237128) (xy 129.305932 -435.236633)
			(xy 129.282968 -435.229174) (xy 129.263433 -435.214984) (xy 129.249237 -435.195454) (xy 129.241771 -435.172492)
			(xy 129.241296 -435.16042) (xy 128.334516 -435.16042) (xy 128.334516 -436.160418) (xy 128.334107 -436.172513)
			(xy 128.32664 -436.195522) (xy 128.31244 -436.215105) (xy 128.292892 -436.229353) (xy 128.269902 -436.236877)
			(xy 128.257808 -436.23738) (xy 127.318008 -436.23738) (xy 127.305898 -436.236977) (xy 127.282867 -436.229477)
			(xy 127.263292 -436.215213) (xy 127.249098 -436.195587) (xy 127.24168 -436.17253) (xy 127.2413 -436.160418)
			(xy 126.306752 -436.160418) (xy 126.312389 -436.164514) (xy 126.326583 -436.184051) (xy 126.334047 -436.207018)
			(xy 126.33452 -436.219092) (xy 126.33452 -438.760616) (xy 126.334049 -438.77269) (xy 126.326584 -438.795656)
			(xy 126.312389 -438.815191) (xy 126.292852 -438.829386) (xy 126.269886 -438.83685) (xy 126.257812 -438.837324)
			(xy 125.318012 -438.837324) (xy 125.30594 -438.836826) (xy 125.282976 -438.829369) (xy 125.26344 -438.81518)
			(xy 125.249244 -438.79565) (xy 125.241779 -438.772688) (xy 125.241304 -438.760616) (xy 104.719676 -438.760616)
			(xy 104.595027 -438.920586) (xy 104.462667 -439.077455) (xy 104.324301 -439.229052) (xy 104.180138 -439.375147)
			(xy 104.030397 -439.515521) (xy 103.875306 -439.649958) (xy 103.73713 -439.760614) (xy 127.2413 -439.760614)
			(xy 127.2413 -437.21909) (xy 127.241798 -437.207004) (xy 127.249253 -437.18401) (xy 127.263433 -437.164434)
			(xy 127.282957 -437.150182) (xy 127.305924 -437.142643) (xy 127.318008 -437.142128) (xy 128.257808 -437.142128)
			(xy 128.26992 -437.14251) (xy 128.292952 -437.150015) (xy 128.312528 -437.164284) (xy 128.326721 -437.183915)
			(xy 128.334137 -437.206976) (xy 128.334516 -437.21909) (xy 128.334516 -438.760616) (xy 129.241296 -438.760616)
			(xy 129.241296 -436.219092) (xy 129.241758 -436.207017) (xy 129.249223 -436.184049) (xy 129.26342 -436.164511)
			(xy 129.282959 -436.150317) (xy 129.305929 -436.142856) (xy 129.318004 -436.142384) (xy 130.257804 -436.142384)
			(xy 130.269878 -436.142861) (xy 130.292844 -436.150323) (xy 130.306738 -436.160418) (xy 131.241292 -436.160418)
			(xy 131.241292 -433.618894) (xy 131.241802 -433.606809) (xy 131.249254 -433.583816) (xy 131.263431 -433.564241)
			(xy 131.282953 -433.549989) (xy 131.305917 -433.542448) (xy 131.318 -433.541932) (xy 132.2578 -433.541932)
			(xy 132.269912 -433.542317) (xy 132.292945 -433.54982) (xy 132.312521 -433.564088) (xy 132.326714 -433.583719)
			(xy 132.334129 -433.60678) (xy 132.334508 -433.618894) (xy 132.334508 -435.16042) (xy 133.241288 -435.16042)
			(xy 133.241288 -432.618896) (xy 133.241761 -432.606822) (xy 133.249224 -432.583855) (xy 133.263418 -432.564318)
			(xy 133.282955 -432.550124) (xy 133.305922 -432.542661) (xy 133.317996 -432.542188) (xy 134.257796 -432.542188)
			(xy 134.26987 -432.542668) (xy 134.292836 -432.550129) (xy 134.30708 -432.560476) (xy 135.241284 -432.560476)
			(xy 135.241284 -430.018952) (xy 135.241723 -430.006876) (xy 135.249198 -429.983908) (xy 135.263401 -429.964373)
			(xy 135.282944 -429.95018) (xy 135.305915 -429.942717) (xy 135.317992 -429.942244) (xy 136.257792 -429.942244)
			(xy 136.269861 -429.94277) (xy 136.29282 -429.950225) (xy 136.312353 -429.964407) (xy 136.32655 -429.98393)
			(xy 136.334021 -430.006883) (xy 136.3345 -430.018952) (xy 136.3345 -431.560478) (xy 137.24128 -431.560478)
			(xy 137.24128 -429.018954) (xy 137.241669 -429.006858) (xy 137.249143 -428.983849) (xy 137.263348 -428.964267)
			(xy 137.2829 -428.950019) (xy 137.305893 -428.942495) (xy 137.317988 -428.941992) (xy 138.257788 -428.941992)
			(xy 138.269895 -428.942427) (xy 138.292921 -428.949922) (xy 138.307489 -428.960534) (xy 139.241276 -428.960534)
			(xy 139.241276 -426.41901) (xy 139.241717 -426.406917) (xy 139.249175 -426.383911) (xy 139.263367 -426.364328)
			(xy 139.282909 -426.350078) (xy 139.305893 -426.342553) (xy 139.317984 -426.342048) (xy 140.257784 -426.342048)
			(xy 140.269887 -426.342529) (xy 140.292905 -426.350018) (xy 140.312473 -426.364265) (xy 140.32667 -426.383869)
			(xy 140.334101 -426.406906) (xy 140.334492 -426.41901) (xy 140.334492 -427.960536) (xy 142.241016 -427.960536)
			(xy 142.241016 -425.419012) (xy 142.24147 -425.406961) (xy 142.248902 -425.384033) (xy 142.263043 -425.364516)
			(xy 142.282516 -425.350313) (xy 142.30542 -425.342809) (xy 142.31747 -425.342304) (xy 143.257778 -425.342304)
			(xy 143.269863 -425.342825) (xy 143.292857 -425.350272) (xy 143.312434 -425.364446) (xy 143.326686 -425.383966)
			(xy 143.334225 -425.406929) (xy 143.33474 -425.419012) (xy 143.33474 -427.960536) (xy 143.334272 -427.972584)
			(xy 143.326834 -427.995504) (xy 143.312694 -428.015016) (xy 143.293228 -428.029219) (xy 143.270333 -428.036732)
			(xy 143.258286 -428.037244) (xy 142.317978 -428.037244) (xy 142.305886 -428.036811) (xy 142.282882 -428.029347)
			(xy 142.263301 -428.015152) (xy 142.249051 -427.99561) (xy 142.241523 -427.972627) (xy 142.241016 -427.960536)
			(xy 140.334492 -427.960536) (xy 140.334492 -428.960534) (xy 140.334022 -428.972622) (xy 140.32656 -428.995619)
			(xy 140.312373 -429.015195) (xy 140.292843 -429.029446) (xy 140.269871 -429.036983) (xy 140.257784 -429.037496)
			(xy 139.317984 -429.037496) (xy 139.305874 -429.037097) (xy 139.282845 -429.029593) (xy 139.263272 -429.015327)
			(xy 139.249078 -428.995702) (xy 139.241659 -428.972646) (xy 139.241276 -428.960534) (xy 138.307489 -428.960534)
			(xy 138.312493 -428.964179) (xy 138.326689 -428.983796) (xy 138.334111 -429.006845) (xy 138.334496 -429.018954)
			(xy 138.334496 -431.560478) (xy 138.333975 -431.572563) (xy 138.326528 -431.595557) (xy 138.312354 -431.615134)
			(xy 138.292834 -431.629386) (xy 138.269871 -431.636925) (xy 138.257788 -431.63744) (xy 137.317988 -431.63744)
			(xy 137.305882 -431.636995) (xy 137.282862 -431.629497) (xy 137.263292 -431.615241) (xy 137.249096 -431.595628)
			(xy 137.241669 -431.572585) (xy 137.24128 -431.560478) (xy 136.3345 -431.560478) (xy 136.3345 -432.560476)
			(xy 136.334067 -432.572558) (xy 136.326605 -432.595542) (xy 136.312404 -432.615093) (xy 136.292856 -432.629297)
			(xy 136.269874 -432.636764) (xy 136.257792 -432.637184) (xy 135.317992 -432.637184) (xy 135.305906 -432.636794)
			(xy 135.282919 -432.629321) (xy 135.263367 -432.61511) (xy 135.249164 -432.595552) (xy 135.241701 -432.572562)
			(xy 135.241284 -432.560476) (xy 134.30708 -432.560476) (xy 134.312373 -432.564321) (xy 134.326568 -432.583857)
			(xy 134.334031 -432.606822) (xy 134.334504 -432.618896) (xy 134.334504 -435.16042) (xy 134.334053 -435.172496)
			(xy 134.326584 -435.195464) (xy 134.312384 -435.215001) (xy 134.292843 -435.229195) (xy 134.269872 -435.236656)
			(xy 134.257796 -435.237128) (xy 133.317996 -435.237128) (xy 133.305923 -435.236639) (xy 133.282959 -435.229178)
			(xy 133.263424 -435.214987) (xy 133.249229 -435.195455) (xy 133.241763 -435.172493) (xy 133.241288 -435.16042)
			(xy 132.334508 -435.16042) (xy 132.334508 -436.160418) (xy 132.334009 -436.172504) (xy 132.326553 -436.195497)
			(xy 132.312373 -436.215072) (xy 132.29285 -436.229324) (xy 132.269884 -436.236864) (xy 132.2578 -436.23738)
			(xy 131.318 -436.23738) (xy 131.305889 -436.236984) (xy 131.282858 -436.229482) (xy 131.263283 -436.215216)
			(xy 131.24909 -436.195589) (xy 131.241672 -436.17253) (xy 131.241292 -436.160418) (xy 130.306738 -436.160418)
			(xy 130.31238 -436.164517) (xy 130.326575 -436.184053) (xy 130.334039 -436.207018) (xy 130.334512 -436.219092)
			(xy 130.334512 -438.760616) (xy 130.334049 -438.772691) (xy 130.326583 -438.795658) (xy 130.312386 -438.815194)
			(xy 130.292847 -438.829388) (xy 130.269879 -438.836851) (xy 130.257804 -438.837324) (xy 129.318004 -438.837324)
			(xy 129.305931 -438.836833) (xy 129.282967 -438.829373) (xy 129.263431 -438.815183) (xy 129.249236 -438.795651)
			(xy 129.241771 -438.772689) (xy 129.241296 -438.760616) (xy 128.334516 -438.760616) (xy 128.334516 -439.760614)
			(xy 131.241292 -439.760614) (xy 131.241292 -437.21909) (xy 131.241798 -437.207005) (xy 131.249252 -437.184012)
			(xy 131.26343 -437.164436) (xy 131.282952 -437.150184) (xy 131.305917 -437.142644) (xy 131.318 -437.142128)
			(xy 132.2578 -437.142128) (xy 132.269912 -437.142516) (xy 132.292944 -437.150019) (xy 132.312519 -437.164287)
			(xy 132.326713 -437.183916) (xy 132.334129 -437.206977) (xy 132.334508 -437.21909) (xy 132.334508 -438.760616)
			(xy 133.241288 -438.760616) (xy 133.241288 -436.219092) (xy 133.241757 -436.207017) (xy 133.249222 -436.184051)
			(xy 133.263417 -436.164514) (xy 133.282954 -436.15032) (xy 133.305921 -436.142857) (xy 133.317996 -436.142384)
			(xy 134.257796 -436.142384) (xy 134.26987 -436.142868) (xy 134.292835 -436.150328) (xy 134.306725 -436.160418)
			(xy 135.241284 -436.160418) (xy 135.241284 -433.618894) (xy 135.241703 -433.6068) (xy 135.249167 -433.583792)
			(xy 135.263364 -433.564208) (xy 135.282911 -433.549959) (xy 135.305899 -433.542435) (xy 135.317992 -433.541932)
			(xy 136.257792 -433.541932) (xy 136.269904 -433.542323) (xy 136.292936 -433.549824) (xy 136.312512 -433.564091)
			(xy 136.326706 -433.58372) (xy 136.334121 -433.606781) (xy 136.3345 -433.618894) (xy 136.3345 -435.16042)
			(xy 137.24128 -435.16042) (xy 137.24128 -432.618896) (xy 137.241761 -432.606822) (xy 137.249223 -432.583857)
			(xy 137.263416 -432.564321) (xy 137.28295 -432.550126) (xy 137.305914 -432.542662) (xy 137.317988 -432.542188)
			(xy 138.257788 -432.542188) (xy 138.26987 -432.542623) (xy 138.292851 -432.550087) (xy 138.307154 -432.560476)
			(xy 139.241276 -432.560476) (xy 139.241276 -430.018952) (xy 139.241723 -430.006877) (xy 139.249197 -429.98391)
			(xy 139.263398 -429.964376) (xy 139.282939 -429.950182) (xy 139.305908 -429.942718) (xy 139.317984 -429.942244)
			(xy 140.257784 -429.942244) (xy 140.269853 -429.942777) (xy 140.292812 -429.950229) (xy 140.312345 -429.96441)
			(xy 140.326541 -429.983931) (xy 140.334013 -430.006883) (xy 140.334492 -430.018952) (xy 140.334492 -431.560478)
			(xy 142.241016 -431.560478) (xy 142.241016 -429.018954) (xy 142.241472 -429.006839) (xy 142.248969 -428.983798)
			(xy 142.263216 -428.964199) (xy 142.28282 -428.949958) (xy 142.305863 -428.942468) (xy 142.317978 -428.941992)
			(xy 143.257778 -428.941992) (xy 143.269887 -428.94253) (xy 143.292922 -428.950005) (xy 143.307426 -428.960534)
			(xy 144.241012 -428.960534) (xy 144.241012 -426.41901) (xy 144.24152 -426.406899) (xy 144.249001 -426.38386)
			(xy 144.263235 -426.36426) (xy 144.282828 -426.350018) (xy 144.305863 -426.342526) (xy 144.317974 -426.342048)
			(xy 145.257774 -426.342048) (xy 145.269896 -426.342482) (xy 145.292956 -426.349969) (xy 145.312572 -426.364216)
			(xy 145.326824 -426.38383) (xy 145.334315 -426.406888) (xy 145.334736 -426.41901) (xy 145.334736 -427.960536)
			(xy 146.241008 -427.960536) (xy 146.241008 -425.419012) (xy 146.24147 -425.406962) (xy 146.248901 -425.384035)
			(xy 146.263041 -425.364518) (xy 146.282511 -425.350315) (xy 146.305413 -425.34281) (xy 146.317462 -425.342304)
			(xy 147.25777 -425.342304) (xy 147.269854 -425.342832) (xy 147.292848 -425.350276) (xy 147.312425 -425.364448)
			(xy 147.326678 -425.383967) (xy 147.334217 -425.40693) (xy 147.334732 -425.419012) (xy 147.334732 -427.960536)
			(xy 147.334272 -427.972585) (xy 147.326833 -427.995506) (xy 147.312691 -428.015019) (xy 147.293223 -428.029222)
			(xy 147.270325 -428.036733) (xy 147.258278 -428.037244) (xy 146.31797 -428.037244) (xy 146.305877 -428.036818)
			(xy 146.282873 -428.029351) (xy 146.263292 -428.015154) (xy 146.249043 -427.995612) (xy 146.241515 -427.972627)
			(xy 146.241008 -427.960536) (xy 145.334736 -427.960536) (xy 145.334736 -428.960534) (xy 145.334317 -428.972653)
			(xy 145.326817 -428.995702) (xy 145.312562 -429.015305) (xy 145.292948 -429.029545) (xy 145.269893 -429.037026)
			(xy 145.257774 -429.037496) (xy 144.317974 -429.037496) (xy 144.305861 -429.037011) (xy 144.282823 -429.029521)
			(xy 144.263225 -429.015281) (xy 144.248983 -428.995684) (xy 144.24149 -428.972646) (xy 144.241012 -428.960534)
			(xy 143.307426 -428.960534) (xy 143.31252 -428.964232) (xy 143.326764 -428.983817) (xy 143.334259 -429.006846)
			(xy 143.33474 -429.018954) (xy 143.33474 -431.560478) (xy 143.334321 -431.572602) (xy 143.326832 -431.595664)
			(xy 143.312581 -431.615281) (xy 143.292964 -431.629532) (xy 143.269902 -431.637021) (xy 143.257778 -431.63744)
			(xy 142.317978 -431.63744) (xy 142.30586 -431.637007) (xy 142.282812 -431.629511) (xy 142.263209 -431.61526)
			(xy 142.248969 -431.595648) (xy 142.241486 -431.572596) (xy 142.241016 -431.560478) (xy 140.334492 -431.560478)
			(xy 140.334492 -432.560476) (xy 140.334067 -432.572559) (xy 140.326604 -432.595544) (xy 140.312401 -432.615096)
			(xy 140.292851 -432.6293) (xy 140.269867 -432.636765) (xy 140.257784 -432.637184) (xy 139.317984 -432.637184)
			(xy 139.305898 -432.636801) (xy 139.282911 -432.629326) (xy 139.263359 -432.615113) (xy 139.249156 -432.595553)
			(xy 139.241693 -432.572562) (xy 139.241276 -432.560476) (xy 138.307154 -432.560476) (xy 138.312401 -432.564287)
			(xy 138.326606 -432.583834) (xy 138.334074 -432.606814) (xy 138.334496 -432.618896) (xy 138.334496 -435.16042)
			(xy 138.334052 -435.172497) (xy 138.326583 -435.195467) (xy 138.312381 -435.215004) (xy 138.292838 -435.229198)
			(xy 138.269865 -435.236657) (xy 138.257788 -435.237128) (xy 137.317988 -435.237128) (xy 137.305915 -435.236646)
			(xy 137.282951 -435.229183) (xy 137.263416 -435.21499) (xy 137.249221 -435.195456) (xy 137.241755 -435.172493)
			(xy 137.24128 -435.16042) (xy 136.3345 -435.16042) (xy 136.3345 -436.160418) (xy 136.334009 -436.172505)
			(xy 136.326552 -436.195499) (xy 136.31237 -436.215075) (xy 136.292845 -436.229327) (xy 136.269877 -436.236865)
			(xy 136.257792 -436.23738) (xy 135.317992 -436.23738) (xy 135.305881 -436.23699) (xy 135.28285 -436.229486)
			(xy 135.263275 -436.215219) (xy 135.249081 -436.19559) (xy 135.241664 -436.172531) (xy 135.241284 -436.160418)
			(xy 134.306725 -436.160418) (xy 134.312372 -436.16452) (xy 134.326567 -436.184054) (xy 134.334031 -436.207019)
			(xy 134.334504 -436.219092) (xy 134.334504 -438.760616) (xy 134.334049 -438.772692) (xy 134.326582 -438.79566)
			(xy 134.312383 -438.815197) (xy 134.292842 -438.829391) (xy 134.269872 -438.836852) (xy 134.257796 -438.837324)
			(xy 133.317996 -438.837324) (xy 133.305923 -438.836839) (xy 133.282958 -438.829378) (xy 133.263423 -438.815186)
			(xy 133.249228 -438.795652) (xy 133.241763 -438.772689) (xy 133.241288 -438.760616) (xy 132.334508 -438.760616)
			(xy 132.334508 -439.760614) (xy 135.241284 -439.760614) (xy 135.241284 -437.21909) (xy 135.2417 -437.206996)
			(xy 135.249165 -437.183987) (xy 135.263363 -437.164404) (xy 135.28291 -437.150155) (xy 135.305899 -437.142631)
			(xy 135.317992 -437.142128) (xy 136.257792 -437.142128) (xy 136.269903 -437.142523) (xy 136.292935 -437.150024)
			(xy 136.312511 -437.16429) (xy 136.326705 -437.183918) (xy 136.334121 -437.206977) (xy 136.3345 -437.21909)
			(xy 136.3345 -438.760616) (xy 137.24128 -438.760616) (xy 137.24128 -436.219092) (xy 137.241757 -436.207018)
			(xy 137.249221 -436.184053) (xy 137.263414 -436.164517) (xy 137.282949 -436.150322) (xy 137.305914 -436.142858)
			(xy 137.317988 -436.142384) (xy 138.257788 -436.142384) (xy 138.269869 -436.142823) (xy 138.29285 -436.150286)
			(xy 138.306799 -436.160418) (xy 139.241276 -436.160418) (xy 139.241276 -433.618894) (xy 139.241703 -433.606801)
			(xy 139.249166 -433.583794) (xy 139.263361 -433.564211) (xy 139.282906 -433.549962) (xy 139.305892 -433.542436)
			(xy 139.317984 -433.541932) (xy 140.257784 -433.541932) (xy 140.269895 -433.542331) (xy 140.292927 -433.549829)
			(xy 140.312503 -433.564094) (xy 140.326697 -433.583722) (xy 140.334113 -433.606781) (xy 140.334492 -433.618894)
			(xy 140.334492 -435.16042) (xy 142.241016 -435.16042) (xy 142.241016 -432.618896) (xy 142.241457 -432.606844)
			(xy 142.248893 -432.583916) (xy 142.263038 -432.564399) (xy 142.282513 -432.550196) (xy 142.305419 -432.542693)
			(xy 142.31747 -432.542188) (xy 143.257778 -432.542188) (xy 143.269871 -432.542627) (xy 143.292879 -432.550084)
			(xy 143.30722 -432.560476) (xy 144.241012 -432.560476) (xy 144.241012 -430.018952) (xy 144.241419 -430.006898)
			(xy 144.248867 -429.983969) (xy 144.263021 -429.964453) (xy 144.282502 -429.950252) (xy 144.305413 -429.942749)
			(xy 144.317466 -429.942244) (xy 145.257774 -429.942244) (xy 145.269863 -429.94273) (xy 145.292863 -429.95018)
			(xy 145.312444 -429.964361) (xy 145.326695 -429.983891) (xy 145.334227 -430.006865) (xy 145.334736 -430.018952)
			(xy 145.334736 -431.560478) (xy 146.241008 -431.560478) (xy 146.241008 -429.018954) (xy 146.241472 -429.00684)
			(xy 146.248968 -428.9838) (xy 146.263213 -428.964202) (xy 146.282815 -428.949961) (xy 146.305856 -428.94247)
			(xy 146.31797 -428.941992) (xy 147.25777 -428.941992) (xy 147.269878 -428.942537) (xy 147.292913 -428.95001)
			(xy 147.307412 -428.960534) (xy 148.241004 -428.960534) (xy 148.241004 -426.41901) (xy 148.24152 -426.406899)
			(xy 148.249 -426.383862) (xy 148.263232 -426.364263) (xy 148.282823 -426.35002) (xy 148.305856 -426.342527)
			(xy 148.317966 -426.342048) (xy 149.257766 -426.342048) (xy 149.269888 -426.342489) (xy 149.292947 -426.349973)
			(xy 149.312564 -426.364219) (xy 149.326816 -426.383831) (xy 149.334307 -426.406888) (xy 149.334728 -426.41901)
			(xy 149.334728 -427.960536) (xy 150.241 -427.960536) (xy 150.241 -425.419012) (xy 150.24147 -425.406962)
			(xy 150.2489 -425.384037) (xy 150.263038 -425.364521) (xy 150.282506 -425.350318) (xy 150.305406 -425.342811)
			(xy 150.317454 -425.342304) (xy 151.257762 -425.342304) (xy 151.269846 -425.342839) (xy 151.292839 -425.350281)
			(xy 151.312417 -425.364451) (xy 151.32667 -425.383968) (xy 151.334209 -425.40693) (xy 151.334724 -425.419012)
			(xy 151.334724 -427.960536) (xy 151.334271 -427.972586) (xy 151.326832 -427.995508) (xy 151.312688 -428.015022)
			(xy 151.293218 -428.029225) (xy 151.270318 -428.036734) (xy 151.25827 -428.037244) (xy 150.317962 -428.037244)
			(xy 150.305869 -428.036825) (xy 150.282864 -428.029356) (xy 150.263284 -428.015157) (xy 150.249035 -427.995613)
			(xy 150.241507 -427.972628) (xy 150.241 -427.960536) (xy 149.334728 -427.960536) (xy 149.334728 -428.960534)
			(xy 149.334317 -428.972654) (xy 149.326816 -428.995704) (xy 149.31256 -429.015308) (xy 149.292943 -429.029547)
			(xy 149.269886 -429.037027) (xy 149.257766 -429.037496) (xy 148.317966 -429.037496) (xy 148.305853 -429.037018)
			(xy 148.282814 -429.029525) (xy 148.263216 -429.015284) (xy 148.248975 -428.995686) (xy 148.241482 -428.972647)
			(xy 148.241004 -428.960534) (xy 147.307412 -428.960534) (xy 147.312511 -428.964235) (xy 147.326755 -428.983819)
			(xy 147.334251 -429.006846) (xy 147.334732 -429.018954) (xy 147.334732 -431.560478) (xy 147.334321 -431.572603)
			(xy 147.326831 -431.595666) (xy 147.312578 -431.615284) (xy 147.292959 -431.629535) (xy 147.269895 -431.637022)
			(xy 147.25777 -431.63744) (xy 146.31797 -431.63744) (xy 146.305852 -431.637014) (xy 146.282804 -431.629515)
			(xy 146.263201 -431.615262) (xy 146.248961 -431.59565) (xy 146.241478 -431.572597) (xy 146.241008 -431.560478)
			(xy 145.334736 -431.560478) (xy 145.334736 -432.560476) (xy 145.33422 -432.572521) (xy 145.326799 -432.59544)
			(xy 145.312671 -432.614953) (xy 145.293214 -432.629159) (xy 145.270325 -432.636672) (xy 145.258282 -432.637184)
			(xy 144.317974 -432.637184) (xy 144.305885 -432.636715) (xy 144.282888 -432.629254) (xy 144.263311 -432.615067)
			(xy 144.24906 -432.595536) (xy 144.241524 -432.572563) (xy 144.241012 -432.560476) (xy 143.30722 -432.560476)
			(xy 143.312464 -432.564276) (xy 143.326713 -432.583818) (xy 143.334237 -432.606804) (xy 143.33474 -432.618896)
			(xy 143.33474 -435.16042) (xy 143.334258 -435.172467) (xy 143.326824 -435.195387) (xy 143.312688 -435.214899)
			(xy 143.293225 -435.229103) (xy 143.270332 -435.236615) (xy 143.258286 -435.237128) (xy 142.317978 -435.237128)
			(xy 142.305884 -435.236711) (xy 142.282877 -435.229244) (xy 142.263295 -435.215046) (xy 142.249046 -435.1955)
			(xy 142.24152 -435.172513) (xy 142.241016 -435.16042) (xy 140.334492 -435.16042) (xy 140.334492 -436.160418)
			(xy 140.334009 -436.172505) (xy 140.326551 -436.195501) (xy 140.312367 -436.215078) (xy 140.29284 -436.229329)
			(xy 140.26987 -436.236866) (xy 140.257784 -436.23738) (xy 139.317984 -436.23738) (xy 139.305872 -436.236997)
			(xy 139.282841 -436.229491) (xy 139.263266 -436.215221) (xy 139.249073 -436.195592) (xy 139.241656 -436.172531)
			(xy 139.241276 -436.160418) (xy 138.306799 -436.160418) (xy 138.3124 -436.164486) (xy 138.326605 -436.184032)
			(xy 138.334074 -436.207011) (xy 138.334496 -436.219092) (xy 138.334496 -438.760616) (xy 138.334049 -438.772693)
			(xy 138.326581 -438.795662) (xy 138.31238 -438.8152) (xy 138.292837 -438.829394) (xy 138.269865 -438.836853)
			(xy 138.257788 -438.837324) (xy 137.317988 -438.837324) (xy 137.305914 -438.836846) (xy 137.28295 -438.829382)
			(xy 137.263414 -438.815189) (xy 137.24922 -438.795654) (xy 137.241755 -438.77269) (xy 137.24128 -438.760616)
			(xy 136.3345 -438.760616) (xy 136.3345 -439.760614) (xy 139.241276 -439.760614) (xy 139.241276 -437.21909)
			(xy 139.2417 -437.206996) (xy 139.249164 -437.183989) (xy 139.26336 -437.164407) (xy 139.282905 -437.150158)
			(xy 139.305892 -437.142632) (xy 139.317984 -437.142128) (xy 140.257784 -437.142128) (xy 140.269895 -437.14253)
			(xy 140.292926 -437.150029) (xy 140.312502 -437.164293) (xy 140.326696 -437.18392) (xy 140.334112 -437.206978)
			(xy 140.334492 -437.21909) (xy 140.334492 -438.760616) (xy 142.241016 -438.760616) (xy 142.241016 -436.219092)
			(xy 142.241454 -436.20704) (xy 142.24889 -436.184111) (xy 142.263036 -436.164594) (xy 142.282512 -436.150392)
			(xy 142.305419 -436.142889) (xy 142.31747 -436.142384) (xy 143.257778 -436.142384) (xy 143.269871 -436.142827)
			(xy 143.292878 -436.150283) (xy 143.306865 -436.160418) (xy 144.241012 -436.160418) (xy 144.241012 -433.618894)
			(xy 144.241506 -433.606782) (xy 144.248992 -433.583743) (xy 144.263229 -433.564143) (xy 144.282825 -433.549901)
			(xy 144.305862 -433.54241) (xy 144.317974 -433.541932) (xy 145.257774 -433.541932) (xy 145.269895 -433.542382)
			(xy 145.292952 -433.549866) (xy 145.312567 -433.56411) (xy 145.326819 -433.58372) (xy 145.334313 -433.606773)
			(xy 145.334736 -433.618894) (xy 145.334736 -435.16042) (xy 146.241008 -435.16042) (xy 146.241008 -432.618896)
			(xy 146.241457 -432.606845) (xy 146.248892 -432.583918) (xy 146.263035 -432.564401) (xy 146.282508 -432.550199)
			(xy 146.305412 -432.542694) (xy 146.317462 -432.542188) (xy 147.25777 -432.542188) (xy 147.269863 -432.542634)
			(xy 147.29287 -432.550088) (xy 147.307207 -432.560476) (xy 148.241004 -432.560476) (xy 148.241004 -430.018952)
			(xy 148.241419 -430.006899) (xy 148.248865 -429.983971) (xy 148.263018 -429.964456) (xy 148.282497 -429.950254)
			(xy 148.305406 -429.94275) (xy 148.317458 -429.942244) (xy 149.257766 -429.942244) (xy 149.269854 -429.942736)
			(xy 149.292854 -429.950184) (xy 149.312435 -429.964364) (xy 149.326687 -429.983893) (xy 149.334219 -430.006866)
			(xy 149.334728 -430.018952) (xy 149.334728 -431.560478) (xy 150.241 -431.560478) (xy 150.241 -429.018954)
			(xy 150.241472 -429.006841) (xy 150.248967 -428.983803) (xy 150.263211 -428.964205) (xy 150.28281 -428.949964)
			(xy 150.305849 -428.942471) (xy 150.317962 -428.941992) (xy 151.257762 -428.941992) (xy 151.26987 -428.942543)
			(xy 151.292904 -428.950015) (xy 151.307399 -428.960534) (xy 152.240996 -428.960534) (xy 152.240996 -426.41901)
			(xy 152.24152 -426.4069) (xy 152.248999 -426.383864) (xy 152.263229 -426.364266) (xy 152.282818 -426.350023)
			(xy 152.305848 -426.342528) (xy 152.317958 -426.342048) (xy 153.257758 -426.342048) (xy 153.26988 -426.342496)
			(xy 153.292939 -426.349978) (xy 153.312555 -426.364222) (xy 153.326808 -426.383833) (xy 153.334299 -426.406889)
			(xy 153.33472 -426.41901) (xy 153.33472 -427.960536) (xy 154.240992 -427.960536) (xy 154.240992 -425.419012)
			(xy 154.24147 -425.406963) (xy 154.248898 -425.384039) (xy 154.263035 -425.364524) (xy 154.282501 -425.35032)
			(xy 154.305399 -425.342812) (xy 154.317446 -425.342304) (xy 155.257754 -425.342304) (xy 155.269838 -425.342846)
			(xy 155.292831 -425.350286) (xy 155.312408 -425.364454) (xy 155.326662 -425.38397) (xy 155.334201 -425.40693)
			(xy 155.334716 -425.419012) (xy 155.334716 -427.960536) (xy 155.334271 -427.972587) (xy 155.326831 -427.995511)
			(xy 155.312685 -428.015024) (xy 155.293213 -428.029227) (xy 155.270311 -428.036735) (xy 155.258262 -428.037244)
			(xy 154.317954 -428.037244) (xy 154.30586 -428.036832) (xy 154.282856 -428.02936) (xy 154.263275 -428.01516)
			(xy 154.249027 -427.995615) (xy 154.241499 -427.972628) (xy 154.240992 -427.960536) (xy 153.33472 -427.960536)
			(xy 153.33472 -428.960534) (xy 153.334369 -428.972663) (xy 153.326862 -428.99573) (xy 153.312594 -429.015348)
			(xy 153.292962 -429.029597) (xy 153.269887 -429.03708) (xy 153.257758 -429.037496) (xy 152.317958 -429.037496)
			(xy 152.305845 -429.037025) (xy 152.282806 -429.02953) (xy 152.263208 -429.015287) (xy 152.248966 -428.995687)
			(xy 152.241474 -428.972647) (xy 152.240996 -428.960534) (xy 151.307399 -428.960534) (xy 151.312503 -428.964238)
			(xy 151.326747 -428.98382) (xy 151.334243 -429.006847) (xy 151.334724 -429.018954) (xy 151.334724 -431.560478)
			(xy 151.334321 -431.572603) (xy 151.32683 -431.595668) (xy 151.312575 -431.615287) (xy 151.292954 -431.629537)
			(xy 151.269887 -431.637023) (xy 151.257762 -431.63744) (xy 150.317962 -431.63744) (xy 150.305843 -431.63702)
			(xy 150.282795 -431.62952) (xy 150.263192 -431.615265) (xy 150.248953 -431.595651) (xy 150.24147 -431.572597)
			(xy 150.241 -431.560478) (xy 149.334728 -431.560478) (xy 149.334728 -432.560476) (xy 149.33422 -432.572522)
			(xy 149.326797 -432.595442) (xy 149.312668 -432.614956) (xy 149.293209 -432.629161) (xy 149.270318 -432.636673)
			(xy 149.258274 -432.637184) (xy 148.317966 -432.637184) (xy 148.305877 -432.636722) (xy 148.282879 -432.629259)
			(xy 148.263302 -432.61507) (xy 148.249052 -432.595538) (xy 148.241516 -432.572563) (xy 148.241004 -432.560476)
			(xy 147.307207 -432.560476) (xy 147.312455 -432.564278) (xy 147.326705 -432.58382) (xy 147.334229 -432.606805)
			(xy 147.334732 -432.618896) (xy 147.334732 -435.16042) (xy 147.334258 -435.172468) (xy 147.326823 -435.195389)
			(xy 147.312685 -435.214901) (xy 147.29322 -435.229105) (xy 147.270324 -435.236616) (xy 147.258278 -435.237128)
			(xy 146.31797 -435.237128) (xy 146.305876 -435.236718) (xy 146.282869 -435.229249) (xy 146.263286 -435.215049)
			(xy 146.249038 -435.195502) (xy 146.241512 -435.172513) (xy 146.241008 -435.16042) (xy 145.334736 -435.16042)
			(xy 145.334736 -436.160418) (xy 145.334355 -436.172544) (xy 145.326854 -436.195608) (xy 145.312594 -436.215225)
			(xy 145.292969 -436.229474) (xy 145.2699 -436.236962) (xy 145.257774 -436.23738) (xy 144.317974 -436.23738)
			(xy 144.30586 -436.236911) (xy 144.282819 -436.229419) (xy 144.263219 -436.215175) (xy 144.248978 -436.195574)
			(xy 144.241488 -436.172532) (xy 144.241012 -436.160418) (xy 143.306865 -436.160418) (xy 143.312462 -436.164474)
			(xy 143.326712 -436.184016) (xy 143.334237 -436.207001) (xy 143.33474 -436.219092) (xy 143.33474 -438.760616)
			(xy 143.334254 -438.772663) (xy 143.326822 -438.795582) (xy 143.312686 -438.815094) (xy 143.293224 -438.829298)
			(xy 143.270331 -438.836811) (xy 143.258286 -438.837324) (xy 142.317978 -438.837324) (xy 142.305884 -438.836911)
			(xy 142.282876 -438.829444) (xy 142.263294 -438.815245) (xy 142.249045 -438.795698) (xy 142.24152 -438.772709)
			(xy 142.241016 -438.760616) (xy 140.334492 -438.760616) (xy 140.334492 -439.760614) (xy 144.241012 -439.760614)
			(xy 144.241012 -437.21909) (xy 144.241503 -437.206978) (xy 144.24899 -437.183938) (xy 144.263228 -437.164339)
			(xy 144.282824 -437.150097) (xy 144.305862 -437.142606) (xy 144.317974 -437.142128) (xy 145.257774 -437.142128)
			(xy 145.269894 -437.142582) (xy 145.292951 -437.150066) (xy 145.312565 -437.164309) (xy 145.326818 -437.183917)
			(xy 145.334312 -437.20697) (xy 145.334736 -437.21909) (xy 145.334736 -438.760616) (xy 146.241008 -438.760616)
			(xy 146.241008 -436.219092) (xy 146.241453 -436.207041) (xy 146.248889 -436.184113) (xy 146.263034 -436.164597)
			(xy 146.282507 -436.150394) (xy 146.305412 -436.14289) (xy 146.317462 -436.142384) (xy 147.25777 -436.142384)
			(xy 147.269862 -436.142834) (xy 147.292869 -436.150288) (xy 147.306851 -436.160418) (xy 148.241004 -436.160418)
			(xy 148.241004 -433.618894) (xy 148.241506 -433.606783) (xy 148.248991 -433.583745) (xy 148.263226 -433.564146)
			(xy 148.28282 -433.549904) (xy 148.305855 -433.542411) (xy 148.317966 -433.541932) (xy 149.257766 -433.541932)
			(xy 149.269886 -433.542389) (xy 149.292943 -433.549871) (xy 149.312558 -433.564113) (xy 149.326811 -433.583721)
			(xy 149.334305 -433.606774) (xy 149.334728 -433.618894) (xy 149.334728 -435.16042) (xy 150.241 -435.16042)
			(xy 150.241 -432.618896) (xy 150.241457 -432.606846) (xy 150.24889 -432.58392) (xy 150.263032 -432.564404)
			(xy 150.282503 -432.550201) (xy 150.305405 -432.542695) (xy 150.317454 -432.542188) (xy 151.257762 -432.542188)
			(xy 151.269854 -432.542641) (xy 151.292862 -432.550093) (xy 151.307195 -432.560476) (xy 152.240996 -432.560476)
			(xy 152.240996 -430.018952) (xy 152.241419 -430.0069) (xy 152.248864 -429.983973) (xy 152.263015 -429.964459)
			(xy 152.282492 -429.950257) (xy 152.305399 -429.942751) (xy 152.31745 -429.942244) (xy 153.257758 -429.942244)
			(xy 153.269846 -429.942743) (xy 153.292846 -429.950189) (xy 153.312427 -429.964367) (xy 153.326679 -429.983894)
			(xy 153.334211 -430.006866) (xy 153.33472 -430.018952) (xy 153.33472 -431.560478) (xy 154.240992 -431.560478)
			(xy 154.240992 -429.018954) (xy 154.241472 -429.006842) (xy 154.248966 -428.983805) (xy 154.263208 -428.964208)
			(xy 154.282805 -428.949966) (xy 154.305842 -428.942472) (xy 154.317954 -428.941992) (xy 155.257754 -428.941992)
			(xy 155.269862 -428.94255) (xy 155.292896 -428.950019) (xy 155.307387 -428.960534) (xy 156.240988 -428.960534)
			(xy 156.240988 -426.41901) (xy 156.24152 -426.406901) (xy 156.248998 -426.383867) (xy 156.263226 -426.364269)
			(xy 156.282813 -426.350025) (xy 156.305841 -426.342529) (xy 156.31795 -426.342048) (xy 157.25775 -426.342048)
			(xy 157.269868 -426.342469) (xy 157.292915 -426.349972) (xy 157.312516 -426.364226) (xy 157.326756 -426.383839)
			(xy 157.33424 -426.406891) (xy 157.334712 -426.41901) (xy 157.334712 -428.960534) (xy 157.334218 -428.972645)
			(xy 157.326728 -428.995681) (xy 157.31249 -429.015278) (xy 157.292896 -429.02952) (xy 157.269861 -429.037016)
			(xy 157.25775 -429.037496) (xy 156.31795 -429.037496) (xy 156.305836 -429.037031) (xy 156.282797 -429.029535)
			(xy 156.263199 -429.015289) (xy 156.248958 -428.995689) (xy 156.241466 -428.972648) (xy 156.240988 -428.960534)
			(xy 155.307387 -428.960534) (xy 155.312494 -428.96424) (xy 155.326739 -428.983822) (xy 155.334235 -429.006847)
			(xy 155.334716 -429.018954) (xy 155.334716 -431.560478) (xy 155.334321 -431.572604) (xy 155.326829 -431.59567)
			(xy 155.312572 -431.61529) (xy 155.292949 -431.62954) (xy 155.26988 -431.637024) (xy 155.257754 -431.63744)
			(xy 154.317954 -431.63744) (xy 154.305835 -431.637027) (xy 154.282786 -431.629525) (xy 154.263184 -431.615268)
			(xy 154.248944 -431.595653) (xy 154.241462 -431.572598) (xy 154.240992 -431.560478) (xy 153.33472 -431.560478)
			(xy 153.33472 -432.560476) (xy 153.33422 -432.572523) (xy 153.326796 -432.595444) (xy 153.312665 -432.614959)
			(xy 153.293204 -432.629164) (xy 153.270311 -432.636674) (xy 153.258266 -432.637184) (xy 152.317958 -432.637184)
			(xy 152.305869 -432.636729) (xy 152.282871 -432.629264) (xy 152.263293 -432.615073) (xy 152.249043 -432.595539)
			(xy 152.241508 -432.572564) (xy 152.240996 -432.560476) (xy 151.307195 -432.560476) (xy 151.312447 -432.564281)
			(xy 151.326697 -432.583821) (xy 151.334221 -432.606805) (xy 151.334724 -432.618896) (xy 151.334724 -435.16042)
			(xy 151.334257 -435.172469) (xy 151.326822 -435.195391) (xy 151.312682 -435.214904) (xy 151.293215 -435.229108)
			(xy 151.270317 -435.236618) (xy 151.25827 -435.237128) (xy 150.317962 -435.237128) (xy 150.305867 -435.236724)
			(xy 150.28286 -435.229253) (xy 150.263278 -435.215052) (xy 150.24903 -435.195503) (xy 150.241504 -435.172514)
			(xy 150.241 -435.16042) (xy 149.334728 -435.16042) (xy 149.334728 -436.160418) (xy 149.334355 -436.172545)
			(xy 149.326853 -436.19561) (xy 149.312591 -436.215228) (xy 149.292964 -436.229477) (xy 149.269893 -436.236963)
			(xy 149.257766 -436.23738) (xy 148.317966 -436.23738) (xy 148.305851 -436.236918) (xy 148.28281 -436.229423)
			(xy 148.26321 -436.215178) (xy 148.248969 -436.195576) (xy 148.24148 -436.172533) (xy 148.241004 -436.160418)
			(xy 147.306851 -436.160418) (xy 147.312454 -436.164477) (xy 147.326704 -436.184017) (xy 147.334229 -436.207001)
			(xy 147.334732 -436.219092) (xy 147.334732 -438.760616) (xy 147.334254 -438.772664) (xy 147.326821 -438.795584)
			(xy 147.312684 -438.815097) (xy 147.293219 -438.829301) (xy 147.270324 -438.836812) (xy 147.258278 -438.837324)
			(xy 146.31797 -438.837324) (xy 146.305875 -438.836918) (xy 146.282868 -438.829448) (xy 146.263285 -438.815247)
			(xy 146.249037 -438.795699) (xy 146.241512 -438.77271) (xy 146.241008 -438.760616) (xy 145.334736 -438.760616)
			(xy 145.334736 -439.760614) (xy 148.241004 -439.760614) (xy 148.241004 -437.21909) (xy 148.241503 -437.206978)
			(xy 148.248989 -437.183941) (xy 148.263225 -437.164342) (xy 148.282819 -437.1501) (xy 148.305854 -437.142607)
			(xy 148.317966 -437.142128) (xy 149.257766 -437.142128) (xy 149.269886 -437.142589) (xy 149.292942 -437.15007)
			(xy 149.312557 -437.164312) (xy 149.32681 -437.183918) (xy 149.334304 -437.20697) (xy 149.334728 -437.21909)
			(xy 149.334728 -438.760616) (xy 150.241 -438.760616) (xy 150.241 -436.219092) (xy 150.241453 -436.207041)
			(xy 150.248888 -436.184116) (xy 150.263031 -436.1646) (xy 150.282502 -436.150397) (xy 150.305405 -436.142891)
			(xy 150.317454 -436.142384) (xy 151.257762 -436.142384) (xy 151.269854 -436.142841) (xy 151.292861 -436.150292)
			(xy 151.306838 -436.160418) (xy 152.240996 -436.160418) (xy 152.240996 -433.618894) (xy 152.241506 -433.606783)
			(xy 152.24899 -433.583747) (xy 152.263224 -433.564149) (xy 152.282815 -433.549906) (xy 152.305848 -433.542412)
			(xy 152.317958 -433.541932) (xy 153.257758 -433.541932) (xy 153.269878 -433.542396) (xy 153.292934 -433.549876)
			(xy 153.31255 -433.564116) (xy 153.326803 -433.583722) (xy 153.334297 -433.606774) (xy 153.33472 -433.618894)
			(xy 153.33472 -435.16042) (xy 154.240992 -435.16042) (xy 154.240992 -432.618896) (xy 154.241456 -432.606846)
			(xy 154.248889 -432.583922) (xy 154.263029 -432.564407) (xy 154.282498 -432.550204) (xy 154.305398 -432.542696)
			(xy 154.317446 -432.542188) (xy 155.257754 -432.542188) (xy 155.269846 -432.542647) (xy 155.292853 -432.550097)
			(xy 155.307181 -432.560476) (xy 156.240988 -432.560476) (xy 156.240988 -430.018952) (xy 156.241419 -430.0069)
			(xy 156.248863 -429.983975) (xy 156.263012 -429.964461) (xy 156.282487 -429.950259) (xy 156.305392 -429.942752)
			(xy 156.317442 -429.942244) (xy 157.25775 -429.942244) (xy 157.269837 -429.94275) (xy 157.292837 -429.950193)
			(xy 157.312418 -429.96437) (xy 157.32667 -429.983896) (xy 157.334203 -430.006866) (xy 157.334712 -430.018952)
			(xy 157.334712 -432.560476) (xy 157.33422 -432.572524) (xy 157.326795 -432.595447) (xy 157.312662 -432.614962)
			(xy 157.293199 -432.629166) (xy 157.270304 -432.636675) (xy 157.258258 -432.637184) (xy 156.31795 -432.637184)
			(xy 156.305865 -432.636651) (xy 156.28287 -432.62921) (xy 156.263292 -432.61504) (xy 156.249039 -432.595522)
			(xy 156.241501 -432.572559) (xy 156.240988 -432.560476) (xy 155.307181 -432.560476) (xy 155.312438 -432.564284)
			(xy 155.326688 -432.583823) (xy 155.334213 -432.606806) (xy 155.334716 -432.618896) (xy 155.334716 -435.16042)
			(xy 155.334257 -435.17247) (xy 155.326821 -435.195393) (xy 155.312679 -435.214907) (xy 155.29321 -435.22911)
			(xy 155.27031 -435.236619) (xy 155.258262 -435.237128) (xy 154.317954 -435.237128) (xy 154.305859 -435.236731)
			(xy 154.282851 -435.229258) (xy 154.263269 -435.215054) (xy 154.249022 -435.195505) (xy 154.241496 -435.172514)
			(xy 154.240992 -435.16042) (xy 153.33472 -435.16042) (xy 153.33472 -436.160418) (xy 153.334354 -436.172546)
			(xy 153.326852 -436.195612) (xy 153.312588 -436.215231) (xy 153.292958 -436.22948) (xy 153.269886 -436.236964)
			(xy 153.257758 -436.23738) (xy 152.317958 -436.23738) (xy 152.305843 -436.236924) (xy 152.282801 -436.229428)
			(xy 152.263202 -436.215181) (xy 152.248961 -436.195577) (xy 152.241472 -436.172533) (xy 152.240996 -436.160418)
			(xy 151.306838 -436.160418) (xy 151.312445 -436.16448) (xy 151.326695 -436.184019) (xy 151.334221 -436.207002)
			(xy 151.334724 -436.219092) (xy 151.334724 -438.760616) (xy 151.334254 -438.772665) (xy 151.32682 -438.795587)
			(xy 151.312681 -438.8151) (xy 151.293214 -438.829304) (xy 151.270317 -438.836814) (xy 151.25827 -438.837324)
			(xy 150.317962 -438.837324) (xy 150.305867 -438.836924) (xy 150.282859 -438.829453) (xy 150.263277 -438.81525)
			(xy 150.249029 -438.795701) (xy 150.241504 -438.77271) (xy 150.241 -438.760616) (xy 149.334728 -438.760616)
			(xy 149.334728 -439.760614) (xy 152.240996 -439.760614) (xy 152.240996 -437.21909) (xy 152.241503 -437.206979)
			(xy 152.248988 -437.183943) (xy 152.263222 -437.164345) (xy 152.282814 -437.150102) (xy 152.305847 -437.142608)
			(xy 152.317958 -437.142128) (xy 153.257758 -437.142128) (xy 153.269878 -437.142595) (xy 153.292933 -437.150075)
			(xy 153.312548 -437.164315) (xy 153.326801 -437.18392) (xy 153.334296 -437.206971) (xy 153.33472 -437.21909)
			(xy 153.33472 -438.760616) (xy 154.240992 -438.760616) (xy 154.240992 -436.219092) (xy 154.241453 -436.207042)
			(xy 154.248887 -436.184118) (xy 154.263028 -436.164603) (xy 154.282497 -436.1504) (xy 154.305398 -436.142892)
			(xy 154.317446 -436.142384) (xy 155.257754 -436.142384) (xy 155.269846 -436.142847) (xy 155.292852 -436.150297)
			(xy 155.306825 -436.160418) (xy 156.240988 -436.160418) (xy 156.240988 -433.618894) (xy 156.241506 -433.606784)
			(xy 156.248989 -433.583749) (xy 156.263221 -433.564152) (xy 156.28281 -433.549909) (xy 156.30584 -433.542413)
			(xy 156.31795 -433.541932) (xy 157.25775 -433.541932) (xy 157.269867 -433.542369) (xy 157.29291 -433.549869)
			(xy 157.312511 -433.564121) (xy 157.326751 -433.583729) (xy 157.334238 -433.606777) (xy 157.334712 -433.618894)
			(xy 157.334712 -436.160418) (xy 157.334205 -436.172529) (xy 157.326718 -436.195564) (xy 157.312484 -436.215161)
			(xy 157.292893 -436.229404) (xy 157.26986 -436.2369) (xy 157.25775 -436.23738) (xy 156.31795 -436.23738)
			(xy 156.305835 -436.236931) (xy 156.282793 -436.229432) (xy 156.263193 -436.215184) (xy 156.248953 -436.195578)
			(xy 156.241464 -436.172534) (xy 156.240988 -436.160418) (xy 155.306825 -436.160418) (xy 155.312437 -436.164483)
			(xy 155.326687 -436.18402) (xy 155.334212 -436.207002) (xy 155.334716 -436.219092) (xy 155.334716 -438.760616)
			(xy 155.334254 -438.772665) (xy 155.326819 -438.795589) (xy 155.312678 -438.815103) (xy 155.293209 -438.829306)
			(xy 155.27031 -438.836815) (xy 155.258262 -438.837324) (xy 154.317954 -438.837324) (xy 154.305858 -438.836931)
			(xy 154.28285 -438.829457) (xy 154.263268 -438.815253) (xy 154.24902 -438.795702) (xy 154.241496 -438.77271)
			(xy 154.240992 -438.760616) (xy 153.33472 -438.760616) (xy 153.33472 -439.760614) (xy 156.240988 -439.760614)
			(xy 156.240988 -437.21909) (xy 156.241503 -437.20698) (xy 156.248987 -437.183945) (xy 156.263219 -437.164348)
			(xy 156.282809 -437.150105) (xy 156.30584 -437.142609) (xy 156.31795 -437.142128) (xy 157.25775 -437.142128)
			(xy 157.269866 -437.142569) (xy 157.292909 -437.150069) (xy 157.312509 -437.164319) (xy 157.32675 -437.183927)
			(xy 157.334237 -437.206974) (xy 157.334712 -437.21909) (xy 157.334712 -439.760614) (xy 157.334201 -439.772724)
			(xy 157.326716 -439.79576) (xy 157.312482 -439.815357) (xy 157.292892 -439.8296) (xy 157.26986 -439.837096)
			(xy 157.25775 -439.837576) (xy 156.31795 -439.837576) (xy 156.305834 -439.837131) (xy 156.282792 -439.829632)
			(xy 156.263192 -439.815382) (xy 156.248952 -439.795776) (xy 156.241463 -439.77273) (xy 156.240988 -439.760614)
			(xy 153.33472 -439.760614) (xy 153.334351 -439.772742) (xy 153.32685 -439.795808) (xy 153.312586 -439.815426)
			(xy 153.292958 -439.829675) (xy 153.269886 -439.83716) (xy 153.257758 -439.837576) (xy 152.317958 -439.837576)
			(xy 152.305843 -439.837124) (xy 152.2828 -439.829627) (xy 152.263201 -439.815379) (xy 152.24896 -439.795774)
			(xy 152.241471 -439.77273) (xy 152.240996 -439.760614) (xy 149.334728 -439.760614) (xy 149.334351 -439.772741)
			(xy 149.326851 -439.795806) (xy 149.312589 -439.815424) (xy 149.292963 -439.829673) (xy 149.269893 -439.837159)
			(xy 149.257766 -439.837576) (xy 148.317966 -439.837576) (xy 148.305851 -439.837118) (xy 148.282809 -439.829623)
			(xy 148.263209 -439.815377) (xy 148.248968 -439.795773) (xy 148.241479 -439.772729) (xy 148.241004 -439.760614)
			(xy 145.334736 -439.760614) (xy 145.334351 -439.77274) (xy 145.326852 -439.795804) (xy 145.312592 -439.815421)
			(xy 145.292968 -439.82967) (xy 145.2699 -439.837158) (xy 145.257774 -439.837576) (xy 144.317974 -439.837576)
			(xy 144.305859 -439.837111) (xy 144.282818 -439.829618) (xy 144.263218 -439.815374) (xy 144.248976 -439.795772)
			(xy 144.241487 -439.772729) (xy 144.241012 -439.760614) (xy 140.334492 -439.760614) (xy 140.334005 -439.772701)
			(xy 140.326549 -439.795697) (xy 140.312366 -439.815274) (xy 140.292839 -439.829525) (xy 140.269869 -439.837062)
			(xy 140.257784 -439.837576) (xy 139.317984 -439.837576) (xy 139.305872 -439.837197) (xy 139.28284 -439.82969)
			(xy 139.263265 -439.81542) (xy 139.249072 -439.795789) (xy 139.241656 -439.772728) (xy 139.241276 -439.760614)
			(xy 136.3345 -439.760614) (xy 136.334006 -439.7727) (xy 136.32655 -439.795695) (xy 136.312369 -439.815271)
			(xy 136.292844 -439.829523) (xy 136.269877 -439.837061) (xy 136.257792 -439.837576) (xy 135.317992 -439.837576)
			(xy 135.30588 -439.83719) (xy 135.282849 -439.829686) (xy 135.263274 -439.815417) (xy 135.24908 -439.795788)
			(xy 135.241664 -439.772727) (xy 135.241284 -439.760614) (xy 132.334508 -439.760614) (xy 132.334006 -439.7727)
			(xy 132.326551 -439.795693) (xy 132.312372 -439.815268) (xy 132.292849 -439.82952) (xy 132.269884 -439.83706)
			(xy 132.2578 -439.837576) (xy 131.318 -439.837576) (xy 131.305889 -439.837184) (xy 131.282857 -439.829681)
			(xy 131.263282 -439.815414) (xy 131.249088 -439.795786) (xy 131.241672 -439.772727) (xy 131.241292 -439.760614)
			(xy 128.334516 -439.760614) (xy 128.334104 -439.772709) (xy 128.326638 -439.795717) (xy 128.312439 -439.815301)
			(xy 128.292891 -439.829549) (xy 128.269901 -439.837073) (xy 128.257808 -439.837576) (xy 127.318008 -439.837576)
			(xy 127.305897 -439.837177) (xy 127.282866 -439.829677) (xy 127.263291 -439.815412) (xy 127.249096 -439.795785)
			(xy 127.24168 -439.772726) (xy 127.2413 -439.760614) (xy 103.73713 -439.760614) (xy 103.715099 -439.778257)
			(xy 103.550019 -439.900222) (xy 103.380316 -440.015668) (xy 103.206247 -440.124421) (xy 103.028078 -440.226315)
			(xy 102.93731 -440.274202) (xy 102.937056 -440.274202) (xy 102.927326 -440.279991) (xy 102.913754 -440.298074)
			(xy 102.909264 -440.320234) (xy 102.911402 -440.331352) (xy 102.935024 -440.427364) (xy 102.938326 -440.438177)
			(xy 102.952617 -440.455661) (xy 102.973011 -440.465356) (xy 102.9843 -440.465972) (xy 125.219206 -440.465972)
			(xy 125.220476 -440.465972) (xy 125.229394 -440.465406) (xy 125.246014 -440.458868) (xy 125.259388 -440.447031)
			(xy 125.267896 -440.431328) (xy 125.269498 -440.422538) (xy 125.269498 -440.422284) (xy 125.274396 -440.3911)
			(xy 125.291224 -440.330259) (xy 125.315802 -440.272116) (xy 125.347716 -440.217652) (xy 125.386425 -440.167789)
			(xy 125.431276 -440.123369) (xy 125.481511 -440.085143) (xy 125.53628 -440.053757) (xy 125.594658 -440.029741)
			(xy 125.655658 -440.013501) (xy 125.71825 -440.005312) (xy 125.781374 -440.005312) (xy 125.843966 -440.013501)
			(xy 125.904966 -440.029741) (xy 125.963344 -440.053757) (xy 126.018113 -440.085143) (xy 126.068348 -440.123369)
			(xy 126.113199 -440.167789) (xy 126.151908 -440.217652) (xy 126.183822 -440.272116) (xy 126.2084 -440.330259)
			(xy 126.225228 -440.3911) (xy 126.230126 -440.422284) (xy 126.230126 -440.422538) (xy 126.231756 -440.431325)
			(xy 126.240244 -440.447039) (xy 126.253609 -440.458886) (xy 126.270229 -440.465427) (xy 126.279148 -440.465972)
			(xy 129.219198 -440.465972) (xy 129.220468 -440.465972) (xy 129.229387 -440.465407) (xy 129.246009 -440.45887)
			(xy 129.259385 -440.447034) (xy 129.267895 -440.43133) (xy 129.26949 -440.422538) (xy 129.26949 -440.422284)
			(xy 129.274388 -440.3911) (xy 129.291216 -440.330259) (xy 129.315794 -440.272116) (xy 129.347708 -440.217652)
			(xy 129.386417 -440.167789) (xy 129.431268 -440.123369) (xy 129.481503 -440.085143) (xy 129.536272 -440.053757)
			(xy 129.59465 -440.029741) (xy 129.65565 -440.013501) (xy 129.718242 -440.005312) (xy 129.781366 -440.005312)
			(xy 129.843958 -440.013501) (xy 129.904958 -440.029741) (xy 129.963336 -440.053757) (xy 130.018105 -440.085143)
			(xy 130.06834 -440.123369) (xy 130.113191 -440.167789) (xy 130.1519 -440.217652) (xy 130.183814 -440.272116)
			(xy 130.208392 -440.330259) (xy 130.22522 -440.3911) (xy 130.230118 -440.422284) (xy 130.230118 -440.422538)
			(xy 130.231748 -440.431325) (xy 130.240236 -440.447041) (xy 130.253601 -440.45889) (xy 130.27022 -440.465433)
			(xy 130.27914 -440.465972) (xy 133.21919 -440.465972) (xy 133.22046 -440.465972) (xy 133.22938 -440.465408)
			(xy 133.246005 -440.458873) (xy 133.259383 -440.447036) (xy 133.267894 -440.431332) (xy 133.269482 -440.422538)
			(xy 133.269482 -440.422284) (xy 133.27438 -440.3911) (xy 133.291208 -440.330259) (xy 133.315786 -440.272116)
			(xy 133.3477 -440.217652) (xy 133.386409 -440.167789) (xy 133.43126 -440.123369) (xy 133.481495 -440.085143)
			(xy 133.536264 -440.053757) (xy 133.594642 -440.029741) (xy 133.655642 -440.013501) (xy 133.718234 -440.005312)
			(xy 133.781358 -440.005312) (xy 133.84395 -440.013501) (xy 133.90495 -440.029741) (xy 133.963328 -440.053757)
			(xy 134.018097 -440.085143) (xy 134.068332 -440.123369) (xy 134.113183 -440.167789) (xy 134.151892 -440.217652)
			(xy 134.183806 -440.272116) (xy 134.208384 -440.330259) (xy 134.225212 -440.3911) (xy 134.23011 -440.422284)
			(xy 134.23011 -440.422538) (xy 134.23174 -440.431326) (xy 134.240227 -440.447043) (xy 134.253592 -440.458894)
			(xy 134.270211 -440.46544) (xy 134.279132 -440.465972) (xy 137.219182 -440.465972) (xy 137.220452 -440.465972)
			(xy 137.229373 -440.46541) (xy 137.246 -440.458876) (xy 137.25938 -440.447039) (xy 137.267893 -440.431334)
			(xy 137.269474 -440.422538) (xy 137.269474 -440.422284) (xy 137.274372 -440.3911) (xy 137.2912 -440.330259)
			(xy 137.315778 -440.272116) (xy 137.347692 -440.217652) (xy 137.386401 -440.167789) (xy 137.431252 -440.123369)
			(xy 137.481487 -440.085143) (xy 137.536256 -440.053757) (xy 137.594634 -440.029741) (xy 137.655634 -440.013501)
			(xy 137.718226 -440.005312) (xy 137.78135 -440.005312) (xy 137.843942 -440.013501) (xy 137.904942 -440.029741)
			(xy 137.96332 -440.053757) (xy 138.018089 -440.085143) (xy 138.068324 -440.123369) (xy 138.113175 -440.167789)
			(xy 138.151884 -440.217652) (xy 138.183798 -440.272116) (xy 138.208376 -440.330259) (xy 138.225204 -440.3911)
			(xy 138.230102 -440.422284) (xy 138.230102 -440.422538) (xy 138.231732 -440.431326) (xy 138.240218 -440.447045)
			(xy 138.253583 -440.458898) (xy 138.270203 -440.465446) (xy 138.279124 -440.465972) (xy 142.219426 -440.465972)
			(xy 142.220696 -440.465972) (xy 142.229612 -440.465403) (xy 142.246226 -440.458861) (xy 142.259594 -440.447024)
			(xy 142.268098 -440.431323) (xy 142.269718 -440.422538) (xy 142.269718 -440.422284) (xy 142.274616 -440.3911)
			(xy 142.291444 -440.330259) (xy 142.316022 -440.272116) (xy 142.347936 -440.217652) (xy 142.386645 -440.167789)
			(xy 142.431496 -440.123369) (xy 142.481731 -440.085143) (xy 142.5365 -440.053757) (xy 142.594878 -440.029741)
			(xy 142.655878 -440.013501) (xy 142.71847 -440.005312) (xy 142.781594 -440.005312) (xy 142.844186 -440.013501)
			(xy 142.905186 -440.029741) (xy 142.963564 -440.053757) (xy 143.018333 -440.085143) (xy 143.068568 -440.123369)
			(xy 143.113419 -440.167789) (xy 143.152128 -440.217652) (xy 143.184042 -440.272116) (xy 143.20862 -440.330259)
			(xy 143.225448 -440.3911) (xy 143.230346 -440.422284) (xy 143.230346 -440.422538) (xy 143.231977 -440.431323)
			(xy 143.240465 -440.447034) (xy 143.253831 -440.458877) (xy 143.27045 -440.465411) (xy 143.279368 -440.465972)
			(xy 146.219418 -440.465972) (xy 146.220688 -440.465972) (xy 146.229605 -440.465404) (xy 146.246221 -440.458864)
			(xy 146.259591 -440.447026) (xy 146.268097 -440.431325) (xy 146.26971 -440.422538) (xy 146.26971 -440.422284)
			(xy 146.274608 -440.3911) (xy 146.291436 -440.330259) (xy 146.316014 -440.272116) (xy 146.347928 -440.217652)
			(xy 146.386637 -440.167789) (xy 146.431488 -440.123369) (xy 146.481723 -440.085143) (xy 146.536492 -440.053757)
			(xy 146.59487 -440.029741) (xy 146.65587 -440.013501) (xy 146.718462 -440.005312) (xy 146.781586 -440.005312)
			(xy 146.844178 -440.013501) (xy 146.905178 -440.029741) (xy 146.963556 -440.053757) (xy 147.018325 -440.085143)
			(xy 147.06856 -440.123369) (xy 147.113411 -440.167789) (xy 147.15212 -440.217652) (xy 147.184034 -440.272116)
			(xy 147.208612 -440.330259) (xy 147.22544 -440.3911) (xy 147.230338 -440.422284) (xy 147.230338 -440.422538)
			(xy 147.231968 -440.431324) (xy 147.240457 -440.447036) (xy 147.253823 -440.45888) (xy 147.270442 -440.465418)
			(xy 147.27936 -440.465972) (xy 150.21941 -440.465972) (xy 150.22068 -440.465972) (xy 150.229598 -440.465405)
			(xy 150.246217 -440.458866) (xy 150.259589 -440.447029) (xy 150.268096 -440.431327) (xy 150.269702 -440.422538)
			(xy 150.269702 -440.422284) (xy 150.2746 -440.3911) (xy 150.291428 -440.330259) (xy 150.316006 -440.272116)
			(xy 150.34792 -440.217652) (xy 150.386629 -440.167789) (xy 150.43148 -440.123369) (xy 150.481715 -440.085143)
			(xy 150.536484 -440.053757) (xy 150.594862 -440.029741) (xy 150.655862 -440.013501) (xy 150.718454 -440.005312)
			(xy 150.781578 -440.005312) (xy 150.84417 -440.013501) (xy 150.90517 -440.029741) (xy 150.963548 -440.053757)
			(xy 151.018317 -440.085143) (xy 151.068552 -440.123369) (xy 151.113403 -440.167789) (xy 151.152112 -440.217652)
			(xy 151.184026 -440.272116) (xy 151.208604 -440.330259) (xy 151.225432 -440.3911) (xy 151.23033 -440.422284)
			(xy 151.23033 -440.422538) (xy 151.23196 -440.431324) (xy 151.240448 -440.447038) (xy 151.253814 -440.458884)
			(xy 151.270433 -440.465424) (xy 151.279352 -440.465972) (xy 154.219402 -440.465972) (xy 154.220672 -440.465972)
			(xy 154.229591 -440.465407) (xy 154.246212 -440.458869) (xy 154.259586 -440.447032) (xy 154.268095 -440.431329)
			(xy 154.269694 -440.422538) (xy 154.269694 -440.422284) (xy 154.274592 -440.3911) (xy 154.29142 -440.330259)
			(xy 154.315998 -440.272116) (xy 154.347912 -440.217652) (xy 154.386621 -440.167789) (xy 154.431472 -440.123369)
			(xy 154.481707 -440.085143) (xy 154.536476 -440.053757) (xy 154.594854 -440.029741) (xy 154.655854 -440.013501)
			(xy 154.718446 -440.005312) (xy 154.78157 -440.005312) (xy 154.844162 -440.013501) (xy 154.905162 -440.029741)
			(xy 154.96354 -440.053757) (xy 155.018309 -440.085143) (xy 155.068544 -440.123369) (xy 155.113395 -440.167789)
			(xy 155.152104 -440.217652) (xy 155.184018 -440.272116) (xy 155.208596 -440.330259) (xy 155.225424 -440.3911)
			(xy 155.230322 -440.422284) (xy 155.230322 -440.422538) (xy 155.231952 -440.431325) (xy 155.24044 -440.44704)
			(xy 155.253805 -440.458888) (xy 155.270424 -440.46543) (xy 155.279344 -440.465972) (xy 177.2666 -440.465972)
			(xy 177.27789 -440.465366) (xy 177.298284 -440.455676) (xy 177.312546 -440.438172) (xy 177.315876 -440.427364)
			(xy 177.339498 -440.331352) (xy 177.341616 -440.320241) (xy 177.337101 -440.298105) (xy 177.323536 -440.280041)
			(xy 177.313844 -440.274202) (xy 177.31359 -440.274202) (xy 177.222822 -440.226317) (xy 177.044658 -440.124417)
			(xy 176.870595 -440.015659) (xy 176.700898 -439.900208) (xy 176.535823 -439.77824) (xy 176.375621 -439.649938)
			(xy 176.220535 -439.515497) (xy 176.070799 -439.375121) (xy 175.926641 -439.229024) (xy 175.788279 -439.077426)
			(xy 175.655923 -438.920556) (xy 175.529773 -438.758654) (xy 175.410021 -438.591964) (xy 175.296848 -438.420739)
			(xy 175.190426 -438.245239) (xy 175.090916 -438.065729) (xy 174.998469 -437.882482) (xy 174.913224 -437.695775)
			(xy 174.835312 -437.505891) (xy 174.76485 -437.313119) (xy 174.701946 -437.11775) (xy 174.646693 -436.92008)
			(xy 174.599177 -436.72041) (xy 174.559469 -436.519041) (xy 174.52763 -436.316279) (xy 174.503707 -436.112432)
			(xy 174.487737 -435.907808) (xy 174.479744 -435.702717) (xy 174.479204 -435.600094) (xy 174.4797 -435.497873)
			(xy 174.487627 -435.293583) (xy 174.50347 -435.089755) (xy 174.527204 -434.886695) (xy 174.558794 -434.684707)
			(xy 174.598193 -434.484096) (xy 174.645341 -434.285164) (xy 174.700167 -434.08821) (xy 174.762589 -433.893529)
			(xy 174.832512 -433.701416) (xy 174.909833 -433.512158) (xy 174.994433 -433.326041) (xy 175.086187 -433.143344)
			(xy 175.184956 -432.964342) (xy 175.290592 -432.789305) (xy 175.402935 -432.618495) (xy 175.521817 -432.45217)
			(xy 175.647059 -432.29058) (xy 175.778472 -432.133968) (xy 175.915859 -431.982569) (xy 176.059014 -431.836611)
			(xy 176.20772 -431.696314) (xy 176.361755 -431.561888) (xy 176.520886 -431.433536) (xy 176.684875 -431.311451)
			(xy 176.853473 -431.195817) (xy 177.026429 -431.086807) (xy 177.203482 -430.984586) (xy 177.384366 -430.889306)
			(xy 177.568807 -430.801113) (xy 177.75653 -430.720137) (xy 177.947252 -430.646501) (xy 178.140685 -430.580316)
			(xy 178.336539 -430.521681) (xy 178.53452 -430.470685) (xy 178.734329 -430.427403) (xy 178.935666 -430.391902)
			(xy 179.138228 -430.364235) (xy 179.34171 -430.344442) (xy 179.545807 -430.332555) (xy 179.750212 -430.328591)
			(xy 179.954617 -430.332555) (xy 180.158714 -430.344442) (xy 180.362196 -430.364235) (xy 180.564758 -430.391902)
			(xy 180.766095 -430.427403) (xy 180.965904 -430.470685) (xy 181.163885 -430.521681) (xy 181.359739 -430.580316)
			(xy 181.553172 -430.646501) (xy 181.743894 -430.720137) (xy 181.931617 -430.801113) (xy 182.116058 -430.889306)
			(xy 182.296942 -430.984586) (xy 182.473995 -431.086807) (xy 182.646951 -431.195817) (xy 182.815549 -431.311451)
			(xy 182.979538 -431.433536) (xy 183.138669 -431.561888) (xy 183.292704 -431.696314) (xy 183.44141 -431.836611)
			(xy 183.584565 -431.982569) (xy 183.721952 -432.133968) (xy 183.853365 -432.29058) (xy 183.978607 -432.45217)
			(xy 184.097489 -432.618495) (xy 184.209832 -432.789305) (xy 184.315468 -432.964342) (xy 184.409109 -433.134051)
			(xy 196.769222 -433.134051) (xy 196.769222 -432.950069) (xy 196.777247 -432.766261) (xy 196.793282 -432.582979)
			(xy 196.817296 -432.400571) (xy 196.849245 -432.219383) (xy 196.889066 -432.039762) (xy 196.936684 -431.862048)
			(xy 196.992008 -431.686581) (xy 197.054934 -431.513694) (xy 197.125341 -431.343717) (xy 197.203096 -431.176972)
			(xy 197.288049 -431.013777) (xy 197.38004 -430.854444) (xy 197.478894 -430.699275) (xy 197.584422 -430.548565)
			(xy 197.696424 -430.402602) (xy 197.814685 -430.261663) (xy 197.938982 -430.126017) (xy 198.069077 -429.995922)
			(xy 198.204723 -429.871625) (xy 198.345662 -429.753364) (xy 198.491625 -429.641362) (xy 198.642335 -429.535834)
			(xy 198.797504 -429.43698) (xy 198.956837 -429.344989) (xy 199.120032 -429.260036) (xy 199.286777 -429.182281)
			(xy 199.456754 -429.111874) (xy 199.629641 -429.048948) (xy 199.805108 -428.993624) (xy 199.982822 -428.946006)
			(xy 200.162443 -428.906185) (xy 200.343631 -428.874236) (xy 200.526039 -428.850222) (xy 200.709321 -428.834187)
			(xy 200.893129 -428.826162) (xy 201.077111 -428.826162) (xy 201.260919 -428.834187) (xy 201.444201 -428.850222)
			(xy 201.626609 -428.874236) (xy 201.807797 -428.906185) (xy 201.987418 -428.946006) (xy 202.165132 -428.993624)
			(xy 202.340599 -429.048948) (xy 202.513486 -429.111874) (xy 202.683463 -429.182281) (xy 202.850208 -429.260036)
			(xy 203.013403 -429.344989) (xy 203.172736 -429.43698) (xy 203.327905 -429.535834) (xy 203.478615 -429.641362)
			(xy 203.624578 -429.753364) (xy 203.765517 -429.871625) (xy 203.901163 -429.995922) (xy 204.031258 -430.126017)
			(xy 204.155555 -430.261663) (xy 204.273816 -430.402602) (xy 204.385818 -430.548565) (xy 204.491346 -430.699275)
			(xy 204.5902 -430.854444) (xy 204.682191 -431.013777) (xy 204.767144 -431.176972) (xy 204.844899 -431.343717)
			(xy 204.915306 -431.513694) (xy 204.978232 -431.686581) (xy 205.033556 -431.862048) (xy 205.081174 -432.039762)
			(xy 205.120995 -432.219383) (xy 205.152944 -432.400571) (xy 205.176958 -432.582979) (xy 205.192993 -432.766261)
			(xy 205.201018 -432.950069) (xy 205.20152 -433.04206) (xy 205.201018 -433.134051) (xy 205.192993 -433.317859)
			(xy 205.176958 -433.501141) (xy 205.152944 -433.683549) (xy 205.120995 -433.864737) (xy 205.081174 -434.044358)
			(xy 205.033556 -434.222072) (xy 204.978232 -434.397539) (xy 204.915306 -434.570426) (xy 204.844899 -434.740403)
			(xy 204.767144 -434.907148) (xy 204.682191 -435.070343) (xy 204.5902 -435.229676) (xy 204.491346 -435.384845)
			(xy 204.385818 -435.535555) (xy 204.273816 -435.681518) (xy 204.155555 -435.822457) (xy 204.031258 -435.958103)
			(xy 203.901163 -436.088198) (xy 203.765517 -436.212495) (xy 203.624578 -436.330756) (xy 203.478615 -436.442758)
			(xy 203.327905 -436.548286) (xy 203.172736 -436.64714) (xy 203.013403 -436.739131) (xy 202.850208 -436.824084)
			(xy 202.683463 -436.901839) (xy 202.513486 -436.972246) (xy 202.340599 -437.035172) (xy 202.165132 -437.090496)
			(xy 201.987418 -437.138114) (xy 201.807797 -437.177935) (xy 201.626609 -437.209884) (xy 201.444201 -437.233898)
			(xy 201.260919 -437.249933) (xy 201.077111 -437.257958) (xy 200.893129 -437.257958) (xy 200.709321 -437.249933)
			(xy 200.526039 -437.233898) (xy 200.343631 -437.209884) (xy 200.162443 -437.177935) (xy 199.982822 -437.138114)
			(xy 199.805108 -437.090496) (xy 199.629641 -437.035172) (xy 199.456754 -436.972246) (xy 199.286777 -436.901839)
			(xy 199.120032 -436.824084) (xy 198.956837 -436.739131) (xy 198.797504 -436.64714) (xy 198.642335 -436.548286)
			(xy 198.491625 -436.442758) (xy 198.345662 -436.330756) (xy 198.204723 -436.212495) (xy 198.069077 -436.088198)
			(xy 197.938982 -435.958103) (xy 197.814685 -435.822457) (xy 197.696424 -435.681518) (xy 197.584422 -435.535555)
			(xy 197.478894 -435.384845) (xy 197.38004 -435.229676) (xy 197.288049 -435.070343) (xy 197.203096 -434.907148)
			(xy 197.125341 -434.740403) (xy 197.054934 -434.570426) (xy 196.992008 -434.397539) (xy 196.936684 -434.222072)
			(xy 196.889066 -434.044358) (xy 196.849245 -433.864737) (xy 196.817296 -433.683549) (xy 196.793282 -433.501141)
			(xy 196.777247 -433.317859) (xy 196.769222 -433.134051) (xy 184.409109 -433.134051) (xy 184.414237 -433.143344)
			(xy 184.505991 -433.326041) (xy 184.590591 -433.512158) (xy 184.667912 -433.701416) (xy 184.737835 -433.893529)
			(xy 184.800257 -434.08821) (xy 184.855083 -434.285164) (xy 184.902231 -434.484096) (xy 184.94163 -434.684707)
			(xy 184.97322 -434.886695) (xy 184.996954 -435.089755) (xy 185.012797 -435.293583) (xy 185.020724 -435.497873)
			(xy 185.02122 -435.600094) (xy 185.020723 -435.702718) (xy 185.012734 -435.90781) (xy 184.996767 -436.112436)
			(xy 184.972846 -436.316285) (xy 184.941009 -436.519049) (xy 184.901302 -436.720419) (xy 184.853787 -436.920092)
			(xy 184.798535 -437.117763) (xy 184.73563 -437.313134) (xy 184.665168 -437.505908) (xy 184.587255 -437.695792)
			(xy 184.50201 -437.8825) (xy 184.409561 -438.065749) (xy 184.310049 -438.245259) (xy 184.203624 -438.42076)
			(xy 184.090448 -438.591985) (xy 183.970693 -438.758674) (xy 183.84454 -438.920576) (xy 183.71218 -439.077444)
			(xy 183.573814 -439.22904) (xy 183.429652 -439.375136) (xy 183.279912 -439.515509) (xy 183.124821 -439.649947)
			(xy 182.964614 -439.778245) (xy 182.799535 -439.90021) (xy 182.629832 -440.015657) (xy 182.455765 -440.124409)
			(xy 182.277596 -440.226304) (xy 182.186834 -440.274202) (xy 182.18658 -440.274202) (xy 182.176862 -440.279998)
			(xy 182.163311 -440.298082) (xy 182.158828 -440.320231) (xy 182.160926 -440.331352) (xy 182.184548 -440.427364)
			(xy 182.187851 -440.438175) (xy 182.202143 -440.455652) (xy 182.222537 -440.465338) (xy 182.233824 -440.465972)
			(xy 193.556636 -440.465972) (xy 193.564279 -440.465708) (xy 193.578878 -440.461176) (xy 193.585338 -440.457082)
			(xy 193.606674 -440.442604) (xy 193.612731 -440.438123) (xy 193.622153 -440.426374) (xy 193.625216 -440.41949)
			(xy 193.649199 -440.360754) (xy 193.703536 -440.246093) (xy 193.764949 -440.135061) (xy 193.833197 -440.028094)
			(xy 193.908011 -439.925612) (xy 193.989097 -439.828018) (xy 194.076138 -439.735696) (xy 194.168791 -439.649006)
			(xy 194.266693 -439.568291) (xy 194.369458 -439.493867) (xy 194.476684 -439.426027) (xy 194.587948 -439.365037)
			(xy 194.702815 -439.311136) (xy 194.820832 -439.264537) (xy 194.941537 -439.225422) (xy 195.064455 -439.193944)
			(xy 195.189103 -439.170229) (xy 195.314992 -439.154368) (xy 195.441628 -439.146424) (xy 195.50507 -439.145934)
			(xy 276.314916 -439.145934) (xy 276.378357 -439.146429) (xy 276.504991 -439.154378) (xy 276.630878 -439.170243)
			(xy 276.755524 -439.193962) (xy 276.878439 -439.225442) (xy 276.999141 -439.26456) (xy 277.117156 -439.311161)
			(xy 277.232021 -439.365063) (xy 277.343283 -439.426053) (xy 277.450507 -439.493894) (xy 277.553271 -439.568317)
			(xy 277.651171 -439.649031) (xy 277.743823 -439.735719) (xy 277.830863 -439.82804) (xy 277.91195 -439.925632)
			(xy 277.986765 -440.028111) (xy 278.055013 -440.135075) (xy 278.116428 -440.246104) (xy 278.170767 -440.360762)
			(xy 278.19477 -440.41949) (xy 278.197778 -440.426407) (xy 278.207212 -440.438168) (xy 278.213312 -440.442604)
			(xy 278.234648 -440.457082) (xy 278.241101 -440.46119) (xy 278.255705 -440.465719) (xy 278.26335 -440.465972)
			(xy 291.06622 -440.465972) (xy 291.077521 -440.465382) (xy 291.097944 -440.455707) (xy 291.112232 -440.438198)
			(xy 291.115496 -440.427364) (xy 291.139118 -440.331606) (xy 291.141295 -440.320453) (xy 291.136826 -440.298202)
			(xy 291.123214 -440.280044) (xy 291.113464 -440.274202) (xy 291.11321 -440.274202) (xy 291.022455 -440.226313)
			(xy 290.844317 -440.124405) (xy 290.67028 -440.015642) (xy 290.500608 -439.900186) (xy 290.335558 -439.778215)
			(xy 290.175381 -439.649912) (xy 290.020319 -439.515472) (xy 289.870607 -439.375099) (xy 289.726472 -439.229005)
			(xy 289.588132 -439.077411) (xy 289.455797 -438.920549) (xy 289.329668 -438.758654) (xy 289.209935 -438.591973)
			(xy 289.096781 -438.420759) (xy 288.990376 -438.245269) (xy 288.890882 -438.065772) (xy 288.79845 -437.882538)
			(xy 288.71322 -437.695845) (xy 288.63532 -437.505977) (xy 288.564869 -437.31322) (xy 288.501974 -437.117868)
			(xy 288.44673 -436.920215) (xy 288.399221 -436.720562) (xy 288.359519 -436.519212) (xy 288.327683 -436.316468)
			(xy 288.303763 -436.112639) (xy 288.287794 -435.908034) (xy 288.2798 -435.702962) (xy 288.279332 -435.600348)
			(xy 288.279828 -435.498127) (xy 288.287755 -435.293837) (xy 288.303598 -435.090009) (xy 288.327332 -434.886949)
			(xy 288.358922 -434.684961) (xy 288.398321 -434.48435) (xy 288.445469 -434.285418) (xy 288.500295 -434.088464)
			(xy 288.562717 -433.893783) (xy 288.63264 -433.70167) (xy 288.709961 -433.512412) (xy 288.794561 -433.326295)
			(xy 288.886315 -433.143598) (xy 288.985084 -432.964596) (xy 289.09072 -432.789559) (xy 289.203063 -432.618749)
			(xy 289.321945 -432.452424) (xy 289.447187 -432.290834) (xy 289.5786 -432.134222) (xy 289.715987 -431.982823)
			(xy 289.859142 -431.836865) (xy 290.007848 -431.696568) (xy 290.161883 -431.562142) (xy 290.321014 -431.43379)
			(xy 290.485003 -431.311705) (xy 290.653601 -431.196071) (xy 290.826557 -431.087061) (xy 291.00361 -430.98484)
			(xy 291.184494 -430.88956) (xy 291.368935 -430.801367) (xy 291.556658 -430.720391) (xy 291.74738 -430.646755)
			(xy 291.940813 -430.58057) (xy 292.136667 -430.521935) (xy 292.334648 -430.470939) (xy 292.534457 -430.427657)
			(xy 292.735794 -430.392156) (xy 292.938356 -430.364489) (xy 293.141838 -430.344696) (xy 293.345935 -430.332809)
			(xy 293.55034 -430.328845) (xy 293.754745 -430.332809) (xy 293.958842 -430.344696) (xy 294.162324 -430.364489)
			(xy 294.364886 -430.392156) (xy 294.566223 -430.427657) (xy 294.766032 -430.470939) (xy 294.964013 -430.521935)
			(xy 295.159867 -430.58057) (xy 295.3533 -430.646755) (xy 295.544022 -430.720391) (xy 295.731745 -430.801367)
			(xy 295.916186 -430.88956) (xy 296.09707 -430.98484) (xy 296.274123 -431.087061) (xy 296.447079 -431.196071)
			(xy 296.615677 -431.311705) (xy 296.779666 -431.43379) (xy 296.936734 -431.560478) (xy 314.141104 -431.560478)
			(xy 314.141104 -429.018954) (xy 314.141572 -429.00684) (xy 314.149068 -428.983801) (xy 314.163312 -428.964203)
			(xy 314.182912 -428.949962) (xy 314.205952 -428.94247) (xy 314.218066 -428.941992) (xy 315.157866 -428.941992)
			(xy 315.169974 -428.94254) (xy 315.193009 -428.950012) (xy 315.207506 -428.960534) (xy 316.1411 -428.960534)
			(xy 316.1411 -426.41901) (xy 316.14162 -426.4069) (xy 316.1491 -426.383863) (xy 316.163331 -426.364265)
			(xy 316.18292 -426.350022) (xy 316.205952 -426.342527) (xy 316.218062 -426.342048) (xy 317.157862 -426.342048)
			(xy 317.169984 -426.342492) (xy 317.193043 -426.349975) (xy 317.21266 -426.36422) (xy 317.226912 -426.383832)
			(xy 317.234403 -426.406888) (xy 317.234824 -426.41901) (xy 317.234824 -427.960536) (xy 318.141096 -427.960536)
			(xy 318.141096 -425.419012) (xy 318.14157 -425.406963) (xy 318.148999 -425.384038) (xy 318.163136 -425.364523)
			(xy 318.182604 -425.350319) (xy 318.205503 -425.342812) (xy 318.21755 -425.342304) (xy 319.157858 -425.342304)
			(xy 319.169942 -425.342842) (xy 319.192935 -425.350283) (xy 319.212513 -425.364453) (xy 319.226766 -425.383969)
			(xy 319.234305 -425.40693) (xy 319.23482 -425.419012) (xy 319.23482 -427.960536) (xy 319.234371 -427.972586)
			(xy 319.226931 -427.99551) (xy 319.212787 -428.015023) (xy 319.193316 -428.029226) (xy 319.170415 -428.036735)
			(xy 319.158366 -428.037244) (xy 318.218058 -428.037244) (xy 318.205965 -428.036828) (xy 318.18296 -428.029358)
			(xy 318.163379 -428.015159) (xy 318.149131 -427.995614) (xy 318.141603 -427.972628) (xy 318.141096 -427.960536)
			(xy 317.234824 -427.960536) (xy 317.234824 -428.960534) (xy 317.234469 -428.972662) (xy 317.226962 -428.995729)
			(xy 317.212695 -429.015347) (xy 317.193064 -429.029595) (xy 317.169991 -429.03708) (xy 317.157862 -429.037496)
			(xy 316.218062 -429.037496) (xy 316.205949 -429.037021) (xy 316.18291 -429.029528) (xy 316.163312 -429.015285)
			(xy 316.14907 -428.995686) (xy 316.141578 -428.972647) (xy 316.1411 -428.960534) (xy 315.207506 -428.960534)
			(xy 315.212607 -428.964236) (xy 315.226851 -428.98382) (xy 315.234347 -429.006846) (xy 315.234828 -429.018954)
			(xy 315.234828 -431.560478) (xy 315.234421 -431.572603) (xy 315.22693 -431.595667) (xy 315.212677 -431.615285)
			(xy 315.193056 -431.629536) (xy 315.169991 -431.637023) (xy 315.157866 -431.63744) (xy 314.218066 -431.63744)
			(xy 314.205947 -431.637017) (xy 314.182899 -431.629518) (xy 314.163296 -431.615264) (xy 314.149057 -431.59565)
			(xy 314.141574 -431.572597) (xy 314.141104 -431.560478) (xy 296.936734 -431.560478) (xy 296.938797 -431.562142)
			(xy 297.092832 -431.696568) (xy 297.241538 -431.836865) (xy 297.384693 -431.982823) (xy 297.52208 -432.134222)
			(xy 297.653493 -432.290834) (xy 297.778735 -432.452424) (xy 297.897617 -432.618749) (xy 298.00996 -432.789559)
			(xy 298.115596 -432.964596) (xy 298.214365 -433.143598) (xy 298.306119 -433.326295) (xy 298.390719 -433.512412)
			(xy 298.46804 -433.70167) (xy 298.537963 -433.893783) (xy 298.600385 -434.088464) (xy 298.655211 -434.285418)
			(xy 298.702359 -434.48435) (xy 298.741758 -434.684961) (xy 298.773348 -434.886949) (xy 298.797082 -435.090009)
			(xy 298.802555 -435.16042) (xy 314.141104 -435.16042) (xy 314.141104 -432.618896) (xy 314.141557 -432.606845)
			(xy 314.148991 -432.583919) (xy 314.163134 -432.564403) (xy 314.182606 -432.5502) (xy 314.205509 -432.542694)
			(xy 314.217558 -432.542188) (xy 315.157866 -432.542188) (xy 315.169959 -432.542637) (xy 315.192966 -432.55009)
			(xy 315.207301 -432.560476) (xy 316.1411 -432.560476) (xy 316.1411 -430.018952) (xy 316.141519 -430.006899)
			(xy 316.148965 -429.983972) (xy 316.163116 -429.964457) (xy 316.182595 -429.950255) (xy 316.205503 -429.94275)
			(xy 316.217554 -429.942244) (xy 317.157862 -429.942244) (xy 317.16995 -429.94274) (xy 317.19295 -429.950187)
			(xy 317.212531 -429.964366) (xy 317.226783 -429.983894) (xy 317.234315 -430.006866) (xy 317.234824 -430.018952)
			(xy 317.234824 -431.560478) (xy 318.141096 -431.560478) (xy 318.141096 -429.018954) (xy 318.141572 -429.006841)
			(xy 318.149067 -428.983804) (xy 318.163309 -428.964206) (xy 318.182907 -428.949965) (xy 318.205945 -428.942471)
			(xy 318.218058 -428.941992) (xy 319.157858 -428.941992) (xy 319.169966 -428.942547) (xy 319.193 -428.950017)
			(xy 319.207492 -428.960534) (xy 320.141092 -428.960534) (xy 320.141092 -426.41901) (xy 320.14162 -426.406901)
			(xy 320.149099 -426.383865) (xy 320.163328 -426.364268) (xy 320.182915 -426.350024) (xy 320.205945 -426.342528)
			(xy 320.218054 -426.342048) (xy 321.157854 -426.342048) (xy 321.169975 -426.342499) (xy 321.193034 -426.34998)
			(xy 321.212651 -426.364223) (xy 321.226904 -426.383833) (xy 321.234395 -426.406889) (xy 321.234816 -426.41901)
			(xy 321.234816 -427.960536) (xy 322.141088 -427.960536) (xy 322.141088 -425.419012) (xy 322.14157 -425.406964)
			(xy 322.148998 -425.38404) (xy 322.163133 -425.364526) (xy 322.182598 -425.350321) (xy 322.205495 -425.342813)
			(xy 322.217542 -425.342304) (xy 323.15785 -425.342304) (xy 323.169933 -425.342849) (xy 323.192926 -425.350288)
			(xy 323.212504 -425.364455) (xy 323.226758 -425.383971) (xy 323.234297 -425.406931) (xy 323.234812 -425.419012)
			(xy 323.234812 -427.960536) (xy 323.234371 -427.972587) (xy 323.22693 -427.995512) (xy 323.212784 -428.015026)
			(xy 323.193311 -428.029228) (xy 323.170407 -428.036736) (xy 323.158358 -428.037244) (xy 322.21805 -428.037244)
			(xy 322.205961 -428.03675) (xy 322.18296 -428.029305) (xy 322.163378 -428.015126) (xy 322.149126 -427.995597)
			(xy 322.141595 -427.972623) (xy 322.141088 -427.960536) (xy 321.234816 -427.960536) (xy 321.234816 -428.960534)
			(xy 321.234468 -428.972663) (xy 321.226961 -428.995731) (xy 321.212692 -429.015349) (xy 321.193059 -429.029598)
			(xy 321.169984 -429.037081) (xy 321.157854 -429.037496) (xy 320.218054 -429.037496) (xy 320.20594 -429.037028)
			(xy 320.182901 -429.029532) (xy 320.163303 -429.015288) (xy 320.149062 -428.995688) (xy 320.14157 -428.972648)
			(xy 320.141092 -428.960534) (xy 319.207492 -428.960534) (xy 319.212598 -428.964239) (xy 319.226843 -428.983821)
			(xy 319.234339 -429.006847) (xy 319.23482 -429.018954) (xy 319.23482 -431.560478) (xy 319.234421 -431.572604)
			(xy 319.226929 -431.595669) (xy 319.212674 -431.615288) (xy 319.193051 -431.629538) (xy 319.169984 -431.637024)
			(xy 319.157858 -431.63744) (xy 318.218058 -431.63744) (xy 318.205939 -431.637024) (xy 318.182891 -431.629522)
			(xy 318.163288 -431.615267) (xy 318.149048 -431.595652) (xy 318.141566 -431.572597) (xy 318.141096 -431.560478)
			(xy 317.234824 -431.560478) (xy 317.234824 -432.560476) (xy 317.23432 -432.572523) (xy 317.226897 -432.595443)
			(xy 317.212767 -432.614957) (xy 317.193307 -432.629162) (xy 317.170415 -432.636673) (xy 317.15837 -432.637184)
			(xy 316.218062 -432.637184) (xy 316.205973 -432.636726) (xy 316.182975 -432.629261) (xy 316.163398 -432.615072)
			(xy 316.149148 -432.595538) (xy 316.141612 -432.572564) (xy 316.1411 -432.560476) (xy 315.207301 -432.560476)
			(xy 315.212551 -432.56428) (xy 315.226801 -432.583821) (xy 315.234325 -432.606805) (xy 315.234828 -432.618896)
			(xy 315.234828 -435.16042) (xy 315.234357 -435.172468) (xy 315.226923 -435.19539) (xy 315.212784 -435.214903)
			(xy 315.193317 -435.229106) (xy 315.170421 -435.236617) (xy 315.158374 -435.237128) (xy 314.218066 -435.237128)
			(xy 314.205971 -435.236721) (xy 314.182964 -435.229251) (xy 314.163382 -435.21505) (xy 314.149134 -435.195502)
			(xy 314.141608 -435.172513) (xy 314.141104 -435.16042) (xy 298.802555 -435.16042) (xy 298.812925 -435.293837)
			(xy 298.820852 -435.498127) (xy 298.821348 -435.600348) (xy 298.820852 -435.702962) (xy 298.812866 -435.908036)
			(xy 298.796904 -436.112643) (xy 298.77299 -436.316473) (xy 298.74116 -436.519219) (xy 298.701463 -436.720571)
			(xy 298.653959 -436.920227) (xy 298.598719 -437.117881) (xy 298.535828 -437.313236) (xy 298.465381 -437.505995)
			(xy 298.387484 -437.695866) (xy 298.302256 -437.882561) (xy 298.209826 -438.065797) (xy 298.110333 -438.245297)
			(xy 298.00393 -438.420787) (xy 297.890776 -438.592004) (xy 297.771044 -438.758686) (xy 297.76954 -438.760616)
			(xy 314.141104 -438.760616) (xy 314.141104 -436.219092) (xy 314.141553 -436.207041) (xy 314.148989 -436.184115)
			(xy 314.163132 -436.164599) (xy 314.182605 -436.150396) (xy 314.205509 -436.14289) (xy 314.217558 -436.142384)
			(xy 315.157866 -436.142384) (xy 315.169958 -436.142837) (xy 315.192965 -436.15029) (xy 315.206945 -436.160418)
			(xy 316.1411 -436.160418) (xy 316.1411 -433.618894) (xy 316.141606 -433.606783) (xy 316.14909 -433.583746)
			(xy 316.163325 -433.564148) (xy 316.182917 -433.549905) (xy 316.205951 -433.542411) (xy 316.218062 -433.541932)
			(xy 317.157862 -433.541932) (xy 317.169982 -433.542392) (xy 317.193039 -433.549873) (xy 317.212654 -433.564115)
			(xy 317.226907 -433.583722) (xy 317.234401 -433.606774) (xy 317.234824 -433.618894) (xy 317.234824 -435.16042)
			(xy 318.141096 -435.16042) (xy 318.141096 -432.618896) (xy 318.141557 -432.606846) (xy 318.14899 -432.583921)
			(xy 318.163131 -432.564406) (xy 318.182601 -432.550202) (xy 318.205502 -432.542696) (xy 318.21755 -432.542188)
			(xy 319.157858 -432.542188) (xy 319.16995 -432.542644) (xy 319.192958 -432.550095) (xy 319.207287 -432.560476)
			(xy 320.141092 -432.560476) (xy 320.141092 -430.018952) (xy 320.141519 -430.0069) (xy 320.148964 -429.983974)
			(xy 320.163113 -429.96446) (xy 320.18259 -429.950258) (xy 320.205495 -429.942752) (xy 320.217546 -429.942244)
			(xy 321.157854 -429.942244) (xy 321.169942 -429.942747) (xy 321.192941 -429.950191) (xy 321.212522 -429.964368)
			(xy 321.226774 -429.983895) (xy 321.234307 -430.006866) (xy 321.234816 -430.018952) (xy 321.234816 -431.560478)
			(xy 322.141088 -431.560478) (xy 322.141088 -429.018954) (xy 322.141572 -429.006842) (xy 322.149066 -428.983806)
			(xy 322.163306 -428.964209) (xy 322.182902 -428.949967) (xy 322.205938 -428.942472) (xy 322.21805 -428.941992)
			(xy 323.15785 -428.941992) (xy 323.169963 -428.942468) (xy 323.193 -428.949964) (xy 323.207544 -428.960534)
			(xy 324.141084 -428.960534) (xy 324.141084 -426.41901) (xy 324.141469 -426.406883) (xy 324.148964 -426.383817)
			(xy 324.163223 -426.364198) (xy 324.182849 -426.349948) (xy 324.205919 -426.342464) (xy 324.218046 -426.342048)
			(xy 325.157846 -426.342048) (xy 325.169964 -426.342473) (xy 325.19301 -426.349974) (xy 325.212612 -426.364228)
			(xy 325.226852 -426.38384) (xy 325.234336 -426.406892) (xy 325.234808 -426.41901) (xy 325.234808 -427.960536)
			(xy 326.14108 -427.960536) (xy 326.14108 -425.419012) (xy 326.14157 -425.406964) (xy 326.148997 -425.384043)
			(xy 326.163131 -425.364528) (xy 326.182593 -425.350324) (xy 326.205488 -425.342814) (xy 326.217534 -425.342304)
			(xy 327.157842 -425.342304) (xy 327.16993 -425.342771) (xy 327.192926 -425.350235) (xy 327.212502 -425.364423)
			(xy 327.226753 -425.383953) (xy 327.23429 -425.406925) (xy 327.234804 -425.419012) (xy 327.234804 -427.960536)
			(xy 327.234371 -427.972588) (xy 327.226929 -427.995514) (xy 327.212781 -428.015029) (xy 327.193306 -428.029231)
			(xy 327.1704 -428.036737) (xy 327.15835 -428.037244) (xy 326.218042 -428.037244) (xy 326.205953 -428.036757)
			(xy 326.182951 -428.029309) (xy 326.163369 -428.015129) (xy 326.149118 -427.995598) (xy 326.141587 -427.972623)
			(xy 326.14108 -427.960536) (xy 325.234808 -427.960536) (xy 325.234808 -428.960534) (xy 325.234318 -428.972646)
			(xy 325.226827 -428.995682) (xy 325.212588 -429.01528) (xy 325.192993 -429.029522) (xy 325.169958 -429.037016)
			(xy 325.157846 -429.037496) (xy 324.218046 -429.037496) (xy 324.205929 -429.037002) (xy 324.182877 -429.029526)
			(xy 324.163264 -429.015292) (xy 324.149011 -428.995694) (xy 324.141511 -428.972651) (xy 324.141084 -428.960534)
			(xy 323.207544 -428.960534) (xy 323.212597 -428.964206) (xy 323.226838 -428.983804) (xy 323.234332 -429.006841)
			(xy 323.234812 -429.018954) (xy 323.234812 -431.560478) (xy 323.23427 -431.572586) (xy 323.226795 -431.59562)
			(xy 323.212569 -431.615218) (xy 323.192985 -431.629462) (xy 323.169958 -431.636959) (xy 323.15785 -431.63744)
			(xy 322.21805 -431.63744) (xy 322.205931 -431.63703) (xy 322.182882 -431.629527) (xy 322.163279 -431.615269)
			(xy 322.14904 -431.595653) (xy 322.141558 -431.572598) (xy 322.141088 -431.560478) (xy 321.234816 -431.560478)
			(xy 321.234816 -432.560476) (xy 321.23432 -432.572523) (xy 321.226896 -432.595445) (xy 321.212764 -432.61496)
			(xy 321.193302 -432.629165) (xy 321.170408 -432.636675) (xy 321.158362 -432.637184) (xy 320.218054 -432.637184)
			(xy 320.205964 -432.636732) (xy 320.182966 -432.629266) (xy 320.163389 -432.615074) (xy 320.149139 -432.59554)
			(xy 320.141604 -432.572564) (xy 320.141092 -432.560476) (xy 319.207287 -432.560476) (xy 319.212542 -432.564283)
			(xy 319.226793 -432.583822) (xy 319.234317 -432.606805) (xy 319.23482 -432.618896) (xy 319.23482 -435.16042)
			(xy 319.234357 -435.172469) (xy 319.226921 -435.195392) (xy 319.212781 -435.214906) (xy 319.193312 -435.229109)
			(xy 319.170414 -435.236618) (xy 319.158366 -435.237128) (xy 318.218058 -435.237128) (xy 318.205963 -435.236728)
			(xy 318.182956 -435.229256) (xy 318.163374 -435.215053) (xy 318.149126 -435.195504) (xy 318.1416 -435.172514)
			(xy 318.141096 -435.16042) (xy 317.234824 -435.16042) (xy 317.234824 -436.160418) (xy 317.234455 -436.172545)
			(xy 317.226953 -436.195611) (xy 317.212689 -436.215229) (xy 317.193061 -436.229478) (xy 317.16999 -436.236963)
			(xy 317.157862 -436.23738) (xy 316.218062 -436.23738) (xy 316.205947 -436.236921) (xy 316.182906 -436.229425)
			(xy 316.163306 -436.21518) (xy 316.149065 -436.195576) (xy 316.141576 -436.172533) (xy 316.1411 -436.160418)
			(xy 315.206945 -436.160418) (xy 315.212549 -436.164478) (xy 315.2268 -436.184018) (xy 315.234325 -436.207001)
			(xy 315.234828 -436.219092) (xy 315.234828 -438.760616) (xy 315.234354 -438.772664) (xy 315.22692 -438.795586)
			(xy 315.212782 -438.815099) (xy 315.193317 -438.829302) (xy 315.170421 -438.836813) (xy 315.158374 -438.837324)
			(xy 314.218066 -438.837324) (xy 314.205971 -438.836921) (xy 314.182963 -438.829451) (xy 314.163381 -438.815249)
			(xy 314.149133 -438.7957) (xy 314.141608 -438.77271) (xy 314.141104 -438.760616) (xy 297.76954 -438.760616)
			(xy 297.644914 -438.920582) (xy 297.512579 -439.077445) (xy 297.374238 -439.229039) (xy 297.230102 -439.375134)
			(xy 297.080389 -439.515507) (xy 296.925325 -439.649947) (xy 296.787162 -439.760614) (xy 316.1411 -439.760614)
			(xy 316.1411 -437.21909) (xy 316.141603 -437.206979) (xy 316.149088 -437.183942) (xy 316.163324 -437.164343)
			(xy 316.182917 -437.150101) (xy 316.205951 -437.142607) (xy 316.218062 -437.142128) (xy 317.157862 -437.142128)
			(xy 317.169982 -437.142592) (xy 317.193038 -437.150073) (xy 317.212653 -437.164313) (xy 317.226905 -437.183919)
			(xy 317.2344 -437.20697) (xy 317.234824 -437.21909) (xy 317.234824 -438.760616) (xy 318.141096 -438.760616)
			(xy 318.141096 -436.219092) (xy 318.141553 -436.207042) (xy 318.148988 -436.184117) (xy 318.163129 -436.164601)
			(xy 318.1826 -436.150398) (xy 318.205501 -436.142892) (xy 318.21755 -436.142384) (xy 319.157858 -436.142384)
			(xy 319.16995 -436.142844) (xy 319.192956 -436.150294) (xy 319.206932 -436.160418) (xy 320.141092 -436.160418)
			(xy 320.141092 -433.618894) (xy 320.141606 -433.606784) (xy 320.149089 -433.583748) (xy 320.163322 -433.564151)
			(xy 320.182912 -433.549908) (xy 320.205944 -433.542412) (xy 320.218054 -433.541932) (xy 321.157854 -433.541932)
			(xy 321.169974 -433.542399) (xy 321.19303 -433.549878) (xy 321.212646 -433.564117) (xy 321.226898 -433.583723)
			(xy 321.234393 -433.606775) (xy 321.234816 -433.618894) (xy 321.234816 -435.16042) (xy 322.141088 -435.16042)
			(xy 322.141088 -432.618896) (xy 322.141556 -432.606847) (xy 322.148989 -432.583923) (xy 322.163128 -432.564409)
			(xy 322.182596 -432.550205) (xy 322.205494 -432.542697) (xy 322.217542 -432.542188) (xy 323.15785 -432.542188)
			(xy 323.169942 -432.542651) (xy 323.192949 -432.5501) (xy 323.207275 -432.560476) (xy 324.141084 -432.560476)
			(xy 324.141084 -430.018952) (xy 324.141519 -430.006901) (xy 324.148963 -429.983976) (xy 324.163111 -429.964463)
			(xy 324.182585 -429.950261) (xy 324.205488 -429.942753) (xy 324.217538 -429.942244) (xy 325.157846 -429.942244)
			(xy 325.169938 -429.942668) (xy 325.192941 -429.950138) (xy 325.212521 -429.964336) (xy 325.22677 -429.983878)
			(xy 325.2343 -430.006861) (xy 325.234808 -430.018952) (xy 325.234808 -431.560478) (xy 326.14108 -431.560478)
			(xy 326.14108 -429.018954) (xy 326.141473 -429.006833) (xy 326.148978 -428.983781) (xy 326.163239 -428.964176)
			(xy 326.18286 -428.949938) (xy 326.20592 -428.942459) (xy 326.218042 -428.941992) (xy 327.157842 -428.941992)
			(xy 327.169954 -428.942475) (xy 327.192991 -428.949968) (xy 327.207531 -428.960534) (xy 328.141076 -428.960534)
			(xy 328.141076 -426.41901) (xy 328.141469 -426.406884) (xy 328.148963 -426.383819) (xy 328.16322 -426.364201)
			(xy 328.182844 -426.34995) (xy 328.205912 -426.342465) (xy 328.218038 -426.342048) (xy 329.157838 -426.342048)
			(xy 329.169956 -426.342479) (xy 329.193002 -426.349978) (xy 329.212604 -426.36423) (xy 329.226844 -426.383841)
			(xy 329.234328 -426.406892) (xy 329.2348 -426.41901) (xy 329.2348 -427.960536) (xy 331.141324 -427.960536)
			(xy 331.141324 -425.419012) (xy 331.141724 -425.406927) (xy 331.149192 -425.383939) (xy 331.1634 -425.364386)
			(xy 331.182957 -425.350183) (xy 331.205947 -425.34272) (xy 331.218032 -425.342304) (xy 332.157832 -425.342304)
			(xy 332.169909 -425.342737) (xy 332.19288 -425.35021) (xy 332.212417 -425.364414) (xy 332.22661 -425.38396)
			(xy 332.23407 -425.406934) (xy 332.23454 -425.419012) (xy 332.23454 -427.960536) (xy 332.234067 -427.972609)
			(xy 332.226599 -427.995572) (xy 332.212403 -428.015106) (xy 332.192869 -428.0293) (xy 332.169905 -428.036768)
			(xy 332.157832 -428.037244) (xy 331.218032 -428.037244) (xy 331.205963 -428.036709) (xy 331.183003 -428.02926)
			(xy 331.163468 -428.01508) (xy 331.149271 -427.995558) (xy 331.141801 -427.972605) (xy 331.141324 -427.960536)
			(xy 329.2348 -427.960536) (xy 329.2348 -428.960534) (xy 329.234318 -428.972647) (xy 329.226826 -428.995684)
			(xy 329.212585 -429.015282) (xy 329.192988 -429.029524) (xy 329.169951 -429.037017) (xy 329.157838 -429.037496)
			(xy 328.218038 -429.037496) (xy 328.205921 -429.037008) (xy 328.182869 -429.029531) (xy 328.163256 -429.015295)
			(xy 328.149002 -428.995696) (xy 328.141503 -428.972651) (xy 328.141076 -428.960534) (xy 327.207531 -428.960534)
			(xy 327.212588 -428.964209) (xy 327.22683 -428.983805) (xy 327.234324 -429.006842) (xy 327.234804 -429.018954)
			(xy 327.234804 -431.560478) (xy 327.23427 -431.572587) (xy 327.226794 -431.595623) (xy 327.212567 -431.615221)
			(xy 327.19298 -431.629465) (xy 327.169951 -431.63696) (xy 327.157842 -431.63744) (xy 326.218042 -431.63744)
			(xy 326.205919 -431.637004) (xy 326.182858 -431.629521) (xy 326.16324 -431.615274) (xy 326.148988 -431.59566)
			(xy 326.141499 -431.572601) (xy 326.14108 -431.560478) (xy 325.234808 -431.560478) (xy 325.234808 -432.560476)
			(xy 325.23432 -432.572524) (xy 325.226895 -432.595448) (xy 325.212761 -432.614963) (xy 325.193297 -432.629168)
			(xy 325.1704 -432.636676) (xy 325.158354 -432.637184) (xy 324.218046 -432.637184) (xy 324.205961 -432.636654)
			(xy 324.182966 -432.629213) (xy 324.163387 -432.615042) (xy 324.149134 -432.595522) (xy 324.141597 -432.572559)
			(xy 324.141084 -432.560476) (xy 323.207275 -432.560476) (xy 323.212534 -432.564285) (xy 323.226784 -432.583823)
			(xy 323.234309 -432.606806) (xy 323.234812 -432.618896) (xy 323.234812 -435.16042) (xy 323.234357 -435.17247)
			(xy 323.22692 -435.195394) (xy 323.212778 -435.214908) (xy 323.193307 -435.229111) (xy 323.170406 -435.236619)
			(xy 323.158358 -435.237128) (xy 322.21805 -435.237128) (xy 322.20596 -435.23665) (xy 322.182955 -435.229203)
			(xy 322.163372 -435.21502) (xy 322.149121 -435.195487) (xy 322.141593 -435.172508) (xy 322.141088 -435.16042)
			(xy 321.234816 -435.16042) (xy 321.234816 -436.160418) (xy 321.234454 -436.172546) (xy 321.226952 -436.195613)
			(xy 321.212686 -436.215232) (xy 321.193056 -436.229481) (xy 321.169983 -436.236965) (xy 321.157854 -436.23738)
			(xy 320.218054 -436.23738) (xy 320.205939 -436.236928) (xy 320.182897 -436.22943) (xy 320.163298 -436.215182)
			(xy 320.149057 -436.195578) (xy 320.141568 -436.172533) (xy 320.141092 -436.160418) (xy 319.206932 -436.160418)
			(xy 319.212541 -436.164481) (xy 319.226791 -436.184019) (xy 319.234316 -436.207002) (xy 319.23482 -436.219092)
			(xy 319.23482 -438.760616) (xy 319.234354 -438.772665) (xy 319.226919 -438.795588) (xy 319.212779 -438.815101)
			(xy 319.193312 -438.829305) (xy 319.170413 -438.836814) (xy 319.158366 -438.837324) (xy 318.218058 -438.837324)
			(xy 318.205963 -438.836928) (xy 318.182955 -438.829455) (xy 318.163372 -438.815252) (xy 318.149124 -438.795701)
			(xy 318.1416 -438.77271) (xy 318.141096 -438.760616) (xy 317.234824 -438.760616) (xy 317.234824 -439.760614)
			(xy 320.141092 -439.760614) (xy 320.141092 -437.21909) (xy 320.141603 -437.20698) (xy 320.149087 -437.183944)
			(xy 320.163321 -437.164346) (xy 320.182912 -437.150104) (xy 320.205944 -437.142608) (xy 320.218054 -437.142128)
			(xy 321.157854 -437.142128) (xy 321.169973 -437.142599) (xy 321.193029 -437.150077) (xy 321.212644 -437.164316)
			(xy 321.226897 -437.183921) (xy 321.234392 -437.206971) (xy 321.234816 -437.21909) (xy 321.234816 -438.760616)
			(xy 322.141088 -438.760616) (xy 322.141088 -436.219092) (xy 322.141553 -436.207043) (xy 322.148986 -436.184119)
			(xy 322.163126 -436.164604) (xy 322.182595 -436.150401) (xy 322.205494 -436.142893) (xy 322.217542 -436.142384)
			(xy 323.15785 -436.142384) (xy 323.169941 -436.142851) (xy 323.192948 -436.150299) (xy 323.206918 -436.160418)
			(xy 324.141084 -436.160418) (xy 324.141084 -433.618894) (xy 324.141456 -433.606766) (xy 324.148955 -433.5837)
			(xy 324.163218 -433.564081) (xy 324.182846 -433.549831) (xy 324.205918 -433.542348) (xy 324.218046 -433.541932)
			(xy 325.157846 -433.541932) (xy 325.169962 -433.542372) (xy 325.193006 -433.549872) (xy 325.212607 -433.564122)
			(xy 325.226847 -433.58373) (xy 325.234334 -433.606777) (xy 325.234808 -433.618894) (xy 325.234808 -435.16042)
			(xy 326.14108 -435.16042) (xy 326.14108 -432.618896) (xy 326.141556 -432.606848) (xy 326.148988 -432.583925)
			(xy 326.163125 -432.564411) (xy 326.182591 -432.550208) (xy 326.205487 -432.542698) (xy 326.217534 -432.542188)
			(xy 327.157842 -432.542188) (xy 327.169939 -432.542572) (xy 327.192949 -432.550047) (xy 327.207325 -432.560476)
			(xy 328.141076 -432.560476) (xy 328.141076 -430.018952) (xy 328.141518 -430.006902) (xy 328.148961 -429.983979)
			(xy 328.163108 -429.964466) (xy 328.18258 -429.950263) (xy 328.205481 -429.942754) (xy 328.21753 -429.942244)
			(xy 329.157838 -429.942244) (xy 329.16993 -429.942675) (xy 329.192933 -429.950143) (xy 329.212512 -429.964338)
			(xy 329.226761 -429.983879) (xy 329.234292 -430.006861) (xy 329.2348 -430.018952) (xy 329.2348 -431.560478)
			(xy 331.141324 -431.560478) (xy 331.141324 -429.018954) (xy 331.141768 -429.006864) (xy 331.149235 -428.983864)
			(xy 331.163428 -428.964286) (xy 331.182965 -428.950037) (xy 331.205943 -428.942503) (xy 331.218032 -428.941992)
			(xy 332.157832 -428.941992) (xy 332.169942 -428.942389) (xy 332.192969 -428.949896) (xy 332.207563 -428.960534)
			(xy 333.14132 -428.960534) (xy 333.14132 -426.41901) (xy 333.141816 -426.406923) (xy 333.149267 -426.383926)
			(xy 333.163447 -426.364348) (xy 333.182973 -426.350096) (xy 333.205943 -426.34256) (xy 333.218028 -426.342048)
			(xy 334.157828 -426.342048) (xy 334.169933 -426.342492) (xy 334.192952 -426.349993) (xy 334.212521 -426.364249)
			(xy 334.226716 -426.383861) (xy 334.234145 -426.406904) (xy 334.234536 -426.41901) (xy 334.234536 -427.960536)
			(xy 335.141316 -427.960536) (xy 335.141316 -425.419012) (xy 335.141723 -425.406928) (xy 335.149191 -425.383941)
			(xy 335.163397 -425.364389) (xy 335.182952 -425.350185) (xy 335.205939 -425.342722) (xy 335.218024 -425.342304)
			(xy 336.157824 -425.342304) (xy 336.169901 -425.342744) (xy 336.192871 -425.350215) (xy 336.212409 -425.364417)
			(xy 336.226602 -425.383961) (xy 336.234061 -425.406935) (xy 336.234532 -425.419012) (xy 336.234532 -427.960536)
			(xy 336.234067 -427.97261) (xy 336.226598 -427.995574) (xy 336.2124 -428.015109) (xy 336.192864 -428.029303)
			(xy 336.169898 -428.036769) (xy 336.157824 -428.037244) (xy 335.218024 -428.037244) (xy 335.205954 -428.036716)
			(xy 335.182994 -428.029264) (xy 335.16346 -428.015083) (xy 335.149263 -427.99556) (xy 335.141793 -427.972605)
			(xy 335.141316 -427.960536) (xy 334.234536 -427.960536) (xy 334.234536 -428.960534) (xy 334.234121 -428.972628)
			(xy 334.226652 -428.995634) (xy 334.212453 -429.015215) (xy 334.192907 -429.029464) (xy 334.16992 -429.03699)
			(xy 334.157828 -429.037496) (xy 333.218028 -429.037496) (xy 333.20592 -429.03706) (xy 333.182893 -429.029567)
			(xy 333.163319 -429.015311) (xy 333.149124 -428.995693) (xy 333.141703 -428.972643) (xy 333.14132 -428.960534)
			(xy 332.207563 -428.960534) (xy 332.212541 -428.964163) (xy 332.226734 -428.983788) (xy 332.234156 -429.006843)
			(xy 332.23454 -429.018954) (xy 332.23454 -431.560478) (xy 332.234073 -431.572568) (xy 332.22662 -431.595572)
			(xy 332.212434 -431.615154) (xy 332.192899 -431.629404) (xy 332.169921 -431.636933) (xy 332.157832 -431.63744)
			(xy 331.218032 -431.63744) (xy 331.205929 -431.636957) (xy 331.182909 -431.629471) (xy 331.163339 -431.615225)
			(xy 331.149142 -431.59562) (xy 331.141713 -431.572582) (xy 331.141324 -431.560478) (xy 329.2348 -431.560478)
			(xy 329.2348 -432.560476) (xy 329.23432 -432.572525) (xy 329.226894 -432.59545) (xy 329.212758 -432.614966)
			(xy 329.193292 -432.62917) (xy 329.170393 -432.636677) (xy 329.158346 -432.637184) (xy 328.218038 -432.637184)
			(xy 328.205953 -432.636661) (xy 328.182957 -432.629217) (xy 328.163379 -432.615044) (xy 328.149126 -432.595524)
			(xy 328.141589 -432.572559) (xy 328.141076 -432.560476) (xy 327.207325 -432.560476) (xy 327.212532 -432.564253)
			(xy 327.226779 -432.583806) (xy 327.234302 -432.606801) (xy 327.234804 -432.618896) (xy 327.234804 -435.16042)
			(xy 327.234357 -435.172471) (xy 327.226919 -435.195396) (xy 327.212775 -435.214911) (xy 327.193302 -435.229114)
			(xy 327.170399 -435.23662) (xy 327.15835 -435.237128) (xy 326.218042 -435.237128) (xy 326.205951 -435.236656)
			(xy 326.182947 -435.229207) (xy 326.163363 -435.215023) (xy 326.149113 -435.195488) (xy 326.141585 -435.172509)
			(xy 326.14108 -435.16042) (xy 325.234808 -435.16042) (xy 325.234808 -436.160418) (xy 325.234305 -436.172529)
			(xy 325.226818 -436.195565) (xy 325.212582 -436.215163) (xy 325.19299 -436.229405) (xy 325.169957 -436.2369)
			(xy 325.157846 -436.23738) (xy 324.218046 -436.23738) (xy 324.205927 -436.236901) (xy 324.182873 -436.229424)
			(xy 324.163259 -436.215187) (xy 324.149005 -436.195584) (xy 324.141509 -436.172536) (xy 324.141084 -436.160418)
			(xy 323.206918 -436.160418) (xy 323.212532 -436.164484) (xy 323.226783 -436.184021) (xy 323.234308 -436.207002)
			(xy 323.234812 -436.219092) (xy 323.234812 -438.760616) (xy 323.234354 -438.772666) (xy 323.226918 -438.79559)
			(xy 323.212776 -438.815104) (xy 323.193307 -438.829307) (xy 323.170406 -438.836815) (xy 323.158358 -438.837324)
			(xy 322.21805 -438.837324) (xy 322.205959 -438.836849) (xy 322.182954 -438.829402) (xy 322.16337 -438.815219)
			(xy 322.149119 -438.795684) (xy 322.141593 -438.772705) (xy 322.141088 -438.760616) (xy 321.234816 -438.760616)
			(xy 321.234816 -439.760614) (xy 324.141084 -439.760614) (xy 324.141084 -437.21909) (xy 324.141452 -437.206962)
			(xy 324.148953 -437.183895) (xy 324.163216 -437.164276) (xy 324.182845 -437.150027) (xy 324.205918 -437.142544)
			(xy 324.218046 -437.142128) (xy 325.157846 -437.142128) (xy 325.169962 -437.142572) (xy 325.193005 -437.150071)
			(xy 325.212605 -437.164321) (xy 325.226845 -437.183927) (xy 325.234333 -437.206974) (xy 325.234808 -437.21909)
			(xy 325.234808 -438.760616) (xy 326.14108 -438.760616) (xy 326.14108 -436.219092) (xy 326.141553 -436.207043)
			(xy 326.148985 -436.184121) (xy 326.163124 -436.164607) (xy 326.18259 -436.150403) (xy 326.205487 -436.142894)
			(xy 326.217534 -436.142384) (xy 327.157842 -436.142384) (xy 327.169938 -436.142772) (xy 327.192948 -436.150246)
			(xy 327.206971 -436.160418) (xy 328.141076 -436.160418) (xy 328.141076 -433.618894) (xy 328.141456 -433.606767)
			(xy 328.148954 -433.583702) (xy 328.163215 -433.564084) (xy 328.182841 -433.549834) (xy 328.205911 -433.542349)
			(xy 328.218038 -433.541932) (xy 329.157838 -433.541932) (xy 329.169954 -433.542379) (xy 329.192997 -433.549876)
			(xy 329.212598 -433.564125) (xy 329.226838 -433.583731) (xy 329.234326 -433.606778) (xy 329.2348 -433.618894)
			(xy 329.2348 -435.16042) (xy 331.141324 -435.16042) (xy 331.141324 -432.618896) (xy 331.14171 -432.60681)
			(xy 331.149182 -432.583822) (xy 331.163394 -432.564268) (xy 331.182954 -432.550066) (xy 331.205946 -432.542604)
			(xy 331.218032 -432.542188) (xy 332.157832 -432.542188) (xy 332.169908 -432.542637) (xy 332.192875 -432.550108)
			(xy 332.20714 -432.560476) (xy 333.14132 -432.560476) (xy 333.14132 -430.018952) (xy 333.141724 -430.006872)
			(xy 333.149203 -429.983899) (xy 333.163414 -429.96436) (xy 333.182967 -429.950168) (xy 333.205948 -429.942712)
			(xy 333.218028 -429.942244) (xy 334.157828 -429.942244) (xy 334.169899 -429.942739) (xy 334.192859 -429.950204)
			(xy 334.212392 -429.964394) (xy 334.226587 -429.983923) (xy 334.234058 -430.006881) (xy 334.234536 -430.018952)
			(xy 334.234536 -431.560478) (xy 335.141316 -431.560478) (xy 335.141316 -429.018954) (xy 335.141768 -429.006864)
			(xy 335.149234 -428.983866) (xy 335.163426 -428.964289) (xy 335.18296 -428.950039) (xy 335.205936 -428.942504)
			(xy 335.218024 -428.941992) (xy 336.157824 -428.941992) (xy 336.169933 -428.942396) (xy 336.19296 -428.949901)
			(xy 336.207549 -428.960534) (xy 337.141312 -428.960534) (xy 337.141312 -426.41901) (xy 337.141815 -426.406924)
			(xy 337.149266 -426.383928) (xy 337.163444 -426.364351) (xy 337.182968 -426.350099) (xy 337.205936 -426.342562)
			(xy 337.21802 -426.342048) (xy 338.15782 -426.342048) (xy 338.169925 -426.342499) (xy 338.192944 -426.349997)
			(xy 338.212512 -426.364252) (xy 338.226708 -426.383863) (xy 338.234137 -426.406904) (xy 338.234528 -426.41901)
			(xy 338.234528 -427.960536) (xy 339.141308 -427.960536) (xy 339.141308 -425.419012) (xy 339.141723 -425.406928)
			(xy 339.149189 -425.383943) (xy 339.163394 -425.364392) (xy 339.182947 -425.350188) (xy 339.205932 -425.342723)
			(xy 339.218016 -425.342304) (xy 340.157816 -425.342304) (xy 340.169893 -425.342751) (xy 340.192862 -425.350219)
			(xy 340.2124 -425.36442) (xy 340.226594 -425.383963) (xy 340.234053 -425.406935) (xy 340.234524 -425.419012)
			(xy 340.234524 -427.960536) (xy 340.234067 -427.972611) (xy 340.226596 -427.995577) (xy 340.212397 -428.015112)
			(xy 340.192859 -428.029306) (xy 340.169891 -428.03677) (xy 340.157816 -428.037244) (xy 339.218016 -428.037244)
			(xy 339.205946 -428.036723) (xy 339.182985 -428.029269) (xy 339.163451 -428.015086) (xy 339.149255 -427.995561)
			(xy 339.141785 -427.972606) (xy 339.141308 -427.960536) (xy 338.234528 -427.960536) (xy 338.234528 -428.960534)
			(xy 338.234121 -428.972629) (xy 338.226651 -428.995636) (xy 338.21245 -429.015218) (xy 338.192902 -429.029466)
			(xy 338.169913 -429.036992) (xy 338.15782 -429.037496) (xy 337.21802 -429.037496) (xy 337.205912 -429.037066)
			(xy 337.182885 -429.029572) (xy 337.163311 -429.015314) (xy 337.149116 -428.995695) (xy 337.141695 -428.972643)
			(xy 337.141312 -428.960534) (xy 336.207549 -428.960534) (xy 336.212532 -428.964166) (xy 336.226726 -428.983789)
			(xy 336.234148 -429.006843) (xy 336.234532 -429.018954) (xy 336.234532 -431.560478) (xy 336.234073 -431.572569)
			(xy 336.226619 -431.595574) (xy 336.212432 -431.615156) (xy 336.192894 -431.629407) (xy 336.169914 -431.636934)
			(xy 336.157824 -431.63744) (xy 335.218024 -431.63744) (xy 335.20592 -431.636964) (xy 335.182901 -431.629476)
			(xy 335.163331 -431.615228) (xy 335.149134 -431.595622) (xy 335.141705 -431.572583) (xy 335.141316 -431.560478)
			(xy 334.234536 -431.560478) (xy 334.234536 -432.560476) (xy 334.234016 -432.572547) (xy 334.226563 -432.595508)
			(xy 334.21238 -432.615043) (xy 334.192855 -432.62924) (xy 334.169898 -432.636708) (xy 334.157828 -432.637184)
			(xy 333.218028 -432.637184) (xy 333.205944 -432.636763) (xy 333.182959 -432.6293) (xy 333.163406 -432.615097)
			(xy 333.149202 -432.595545) (xy 333.141738 -432.57256) (xy 333.14132 -432.560476) (xy 332.20714 -432.560476)
			(xy 332.212412 -432.564308) (xy 332.226605 -432.58385) (xy 332.234068 -432.60682) (xy 332.23454 -432.618896)
			(xy 332.23454 -435.16042) (xy 332.234053 -435.172492) (xy 332.226589 -435.195455) (xy 332.212397 -435.214989)
			(xy 332.192865 -435.229184) (xy 332.169904 -435.236651) (xy 332.157832 -435.237128) (xy 331.218032 -435.237128)
			(xy 331.205953 -435.23666) (xy 331.182975 -435.229204) (xy 331.163426 -435.215011) (xy 331.14922 -435.195472)
			(xy 331.141748 -435.172499) (xy 331.141324 -435.16042) (xy 329.2348 -435.16042) (xy 329.2348 -436.160418)
			(xy 329.234304 -436.17253) (xy 329.226817 -436.195567) (xy 329.21258 -436.215165) (xy 329.192985 -436.229408)
			(xy 329.16995 -436.236901) (xy 329.157838 -436.23738) (xy 328.218038 -436.23738) (xy 328.205919 -436.236908)
			(xy 328.182864 -436.229428) (xy 328.16325 -436.21519) (xy 328.148997 -436.195586) (xy 328.141501 -436.172537)
			(xy 328.141076 -436.160418) (xy 327.206971 -436.160418) (xy 327.212531 -436.164451) (xy 327.226778 -436.184004)
			(xy 327.234301 -436.206997) (xy 327.234804 -436.219092) (xy 327.234804 -438.760616) (xy 327.234354 -438.772667)
			(xy 327.226917 -438.795592) (xy 327.212774 -438.815107) (xy 327.193302 -438.82931) (xy 327.170399 -438.836816)
			(xy 327.15835 -438.837324) (xy 326.218042 -438.837324) (xy 326.205951 -438.836856) (xy 326.182946 -438.829407)
			(xy 326.163362 -438.815222) (xy 326.149111 -438.795686) (xy 326.141585 -438.772705) (xy 326.14108 -438.760616)
			(xy 325.234808 -438.760616) (xy 325.234808 -439.760614) (xy 328.141076 -439.760614) (xy 328.141076 -437.21909)
			(xy 328.141452 -437.206963) (xy 328.148952 -437.183897) (xy 328.163213 -437.164279) (xy 328.18284 -437.15003)
			(xy 328.205911 -437.142545) (xy 328.218038 -437.142128) (xy 329.157838 -437.142128) (xy 329.169954 -437.142579)
			(xy 329.192996 -437.150076) (xy 329.212597 -437.164323) (xy 329.226837 -437.183929) (xy 329.234325 -437.206974)
			(xy 329.2348 -437.21909) (xy 329.2348 -438.760616) (xy 331.141324 -438.760616) (xy 331.141324 -436.219092)
			(xy 331.141706 -436.207006) (xy 331.14918 -436.184017) (xy 331.163393 -436.164464) (xy 331.182953 -436.150262)
			(xy 331.205945 -436.1428) (xy 331.218032 -436.142384) (xy 332.157832 -436.142384) (xy 332.169907 -436.142837)
			(xy 332.192874 -436.150307) (xy 332.206784 -436.160418) (xy 333.14132 -436.160418) (xy 333.14132 -433.618894)
			(xy 333.141802 -433.606806) (xy 333.149258 -433.583809) (xy 333.163441 -433.564231) (xy 333.18297 -433.54998)
			(xy 333.205942 -433.542444) (xy 333.218028 -433.541932) (xy 334.157828 -433.541932) (xy 334.169942 -433.542293)
			(xy 334.192975 -433.549804) (xy 334.212551 -433.564079) (xy 334.226743 -433.583714) (xy 334.234157 -433.606779)
			(xy 334.234536 -433.618894) (xy 334.234536 -435.16042) (xy 335.141316 -435.16042) (xy 335.141316 -432.618896)
			(xy 335.141709 -432.606811) (xy 335.149181 -432.583824) (xy 335.163391 -432.564271) (xy 335.182949 -432.550068)
			(xy 335.205938 -432.542605) (xy 335.218024 -432.542188) (xy 336.157824 -432.542188) (xy 336.169899 -432.542644)
			(xy 336.192867 -432.550113) (xy 336.207126 -432.560476) (xy 337.141312 -432.560476) (xy 337.141312 -430.018952)
			(xy 337.141724 -430.006873) (xy 337.149202 -429.983901) (xy 337.163411 -429.964363) (xy 337.182962 -429.950171)
			(xy 337.205941 -429.942713) (xy 337.21802 -429.942244) (xy 338.15782 -429.942244) (xy 338.169891 -429.942747)
			(xy 338.19285 -429.950209) (xy 338.212383 -429.964397) (xy 338.226578 -429.983924) (xy 338.234049 -430.006881)
			(xy 338.234528 -430.018952) (xy 338.234528 -431.560478) (xy 339.141308 -431.560478) (xy 339.141308 -429.018954)
			(xy 339.141768 -429.006865) (xy 339.149233 -428.983868) (xy 339.163423 -428.964292) (xy 339.182955 -428.950042)
			(xy 339.205929 -428.942505) (xy 339.218016 -428.941992) (xy 340.157816 -428.941992) (xy 340.169925 -428.942402)
			(xy 340.192951 -428.949905) (xy 340.207536 -428.960534) (xy 341.141304 -428.960534) (xy 341.141304 -426.41901)
			(xy 341.141815 -426.406925) (xy 341.149265 -426.38393) (xy 341.163441 -426.364353) (xy 341.182963 -426.350101)
			(xy 341.205928 -426.342563) (xy 341.218012 -426.342048) (xy 342.157812 -426.342048) (xy 342.169916 -426.342505)
			(xy 342.192935 -426.350002) (xy 342.212504 -426.364255) (xy 342.2267 -426.383864) (xy 342.234129 -426.406905)
			(xy 342.23452 -426.41901) (xy 342.23452 -427.960536) (xy 343.1413 -427.960536) (xy 343.1413 -425.419012)
			(xy 343.141723 -425.406929) (xy 343.149188 -425.383946) (xy 343.163392 -425.364394) (xy 343.182942 -425.35019)
			(xy 343.205925 -425.342724) (xy 343.218008 -425.342304) (xy 344.157808 -425.342304) (xy 344.169892 -425.342706)
			(xy 344.192877 -425.350177) (xy 344.212429 -425.364386) (xy 344.226632 -425.383941) (xy 344.234097 -425.406928)
			(xy 344.234516 -425.419012) (xy 344.234516 -427.960536) (xy 344.234067 -427.972612) (xy 344.226595 -427.995579)
			(xy 344.212395 -428.015115) (xy 344.192854 -428.029308) (xy 344.169884 -428.036771) (xy 344.157808 -428.037244)
			(xy 343.218008 -428.037244) (xy 343.205937 -428.03673) (xy 343.182977 -428.029274) (xy 343.163443 -428.015089)
			(xy 343.149247 -427.995563) (xy 343.141777 -427.972606) (xy 343.1413 -427.960536) (xy 342.23452 -427.960536)
			(xy 342.23452 -428.960534) (xy 342.234121 -428.972629) (xy 342.22665 -428.995638) (xy 342.212447 -429.015221)
			(xy 342.192897 -429.029469) (xy 342.169906 -429.036993) (xy 342.157812 -429.037496) (xy 341.218012 -429.037496)
			(xy 341.205903 -429.037073) (xy 341.182876 -429.029577) (xy 341.163302 -429.015317) (xy 341.149107 -428.995696)
			(xy 341.141687 -428.972644) (xy 341.141304 -428.960534) (xy 340.207536 -428.960534) (xy 340.212524 -428.964169)
			(xy 340.226718 -428.983791) (xy 340.23414 -429.006844) (xy 340.234524 -429.018954) (xy 340.234524 -431.560478)
			(xy 340.234073 -431.57257) (xy 340.226618 -431.595576) (xy 340.212429 -431.615159) (xy 340.192889 -431.629409)
			(xy 340.169906 -431.636935) (xy 340.157816 -431.63744) (xy 339.218016 -431.63744) (xy 339.205912 -431.63697)
			(xy 339.182892 -431.62948) (xy 339.163322 -431.615231) (xy 339.149126 -431.595623) (xy 339.141697 -431.572583)
			(xy 339.141308 -431.560478) (xy 338.234528 -431.560478) (xy 338.234528 -432.560476) (xy 338.234067 -432.572555)
			(xy 338.226609 -432.595534) (xy 338.212414 -432.615083) (xy 338.192873 -432.629288) (xy 338.169899 -432.63676)
			(xy 338.15782 -432.637184) (xy 337.21802 -432.637184) (xy 337.205936 -432.63677) (xy 337.18295 -432.629305)
			(xy 337.163397 -432.6151) (xy 337.149193 -432.595547) (xy 337.14173 -432.57256) (xy 337.141312 -432.560476)
			(xy 336.207126 -432.560476) (xy 336.212403 -432.564311) (xy 336.226597 -432.583851) (xy 336.234059 -432.606821)
			(xy 336.234532 -432.618896) (xy 336.234532 -435.16042) (xy 336.234053 -435.172493) (xy 336.226588 -435.195457)
			(xy 336.212394 -435.214991) (xy 336.19286 -435.229186) (xy 336.169897 -435.236652) (xy 336.157824 -435.237128)
			(xy 335.218024 -435.237128) (xy 335.205945 -435.236667) (xy 335.182966 -435.229209) (xy 335.163417 -435.215014)
			(xy 335.149212 -435.195473) (xy 335.14174 -435.172499) (xy 335.141316 -435.16042) (xy 334.234536 -435.16042)
			(xy 334.234536 -436.160418) (xy 334.234108 -436.172511) (xy 334.226643 -436.195516) (xy 334.212447 -436.215098)
			(xy 334.192904 -436.229347) (xy 334.16992 -436.236874) (xy 334.157828 -436.23738) (xy 333.218028 -436.23738)
			(xy 333.205919 -436.236959) (xy 333.182889 -436.229465) (xy 333.163314 -436.215206) (xy 333.149119 -436.195583)
			(xy 333.141701 -436.172529) (xy 333.14132 -436.160418) (xy 332.206784 -436.160418) (xy 332.21241 -436.164507)
			(xy 332.226604 -436.184047) (xy 332.234067 -436.207016) (xy 332.23454 -436.219092) (xy 332.23454 -438.760616)
			(xy 332.23405 -438.772688) (xy 332.226587 -438.79565) (xy 332.212396 -438.815184) (xy 332.192865 -438.829379)
			(xy 332.169904 -438.836847) (xy 332.157832 -438.837324) (xy 331.218032 -438.837324) (xy 331.205953 -438.83686)
			(xy 331.182974 -438.829403) (xy 331.163424 -438.81521) (xy 331.149218 -438.795669) (xy 331.141747 -438.772695)
			(xy 331.141324 -438.760616) (xy 329.2348 -438.760616) (xy 329.2348 -439.760614) (xy 333.14132 -439.760614)
			(xy 333.14132 -437.21909) (xy 333.141799 -437.207002) (xy 333.149256 -437.184004) (xy 333.16344 -437.164426)
			(xy 333.18297 -437.150176) (xy 333.205942 -437.14264) (xy 333.218028 -437.142128) (xy 334.157828 -437.142128)
			(xy 334.169941 -437.142493) (xy 334.192974 -437.150003) (xy 334.212549 -437.164277) (xy 334.226742 -437.183911)
			(xy 334.234157 -437.206975) (xy 334.234536 -437.21909) (xy 334.234536 -438.760616) (xy 335.141316 -438.760616)
			(xy 335.141316 -436.219092) (xy 335.141706 -436.207006) (xy 335.149179 -436.184019) (xy 335.16339 -436.164467)
			(xy 335.182948 -436.150264) (xy 335.205938 -436.142801) (xy 335.218024 -436.142384) (xy 336.157824 -436.142384)
			(xy 336.169899 -436.142844) (xy 336.192866 -436.150312) (xy 336.206771 -436.160418) (xy 337.141312 -436.160418)
			(xy 337.141312 -433.618894) (xy 337.141802 -433.606807) (xy 337.149257 -433.583811) (xy 337.163439 -433.564234)
			(xy 337.182965 -433.549982) (xy 337.205935 -433.542445) (xy 337.21802 -433.541932) (xy 338.15782 -433.541932)
			(xy 338.169933 -433.5423) (xy 338.192967 -433.549808) (xy 338.212542 -433.564081) (xy 338.226735 -433.583715)
			(xy 338.234149 -433.606779) (xy 338.234528 -433.618894) (xy 338.234528 -435.16042) (xy 339.141308 -435.16042)
			(xy 339.141308 -432.618896) (xy 339.141709 -432.606811) (xy 339.14918 -432.583826) (xy 339.163388 -432.564274)
			(xy 339.182944 -432.550071) (xy 339.205931 -432.542606) (xy 339.218016 -432.542188) (xy 340.157816 -432.542188)
			(xy 340.169891 -432.542651) (xy 340.192858 -432.550117) (xy 340.207113 -432.560476) (xy 341.141304 -432.560476)
			(xy 341.141304 -430.018952) (xy 341.141723 -430.006874) (xy 341.149201 -429.983903) (xy 341.163408 -429.964366)
			(xy 341.182957 -429.950173) (xy 341.205933 -429.942714) (xy 341.218012 -429.942244) (xy 342.157812 -429.942244)
			(xy 342.169882 -429.942753) (xy 342.192842 -429.950213) (xy 342.212374 -429.9644) (xy 342.22657 -429.983926)
			(xy 342.234041 -430.006882) (xy 342.23452 -430.018952) (xy 342.23452 -431.560478) (xy 343.1413 -431.560478)
			(xy 343.1413 -429.018954) (xy 343.141767 -429.006866) (xy 343.149232 -428.983871) (xy 343.16342 -428.964295)
			(xy 343.18295 -428.950044) (xy 343.205922 -428.942507) (xy 343.218008 -428.941992) (xy 344.157808 -428.941992)
			(xy 344.169917 -428.942409) (xy 344.192943 -428.94991) (xy 344.207523 -428.960534) (xy 345.141296 -428.960534)
			(xy 345.141296 -426.41901) (xy 345.141815 -426.406925) (xy 345.149264 -426.383932) (xy 345.163439 -426.364356)
			(xy 345.182958 -426.350104) (xy 345.205921 -426.342564) (xy 345.218004 -426.342048) (xy 346.157804 -426.342048)
			(xy 346.169908 -426.342512) (xy 346.192927 -426.350006) (xy 346.212495 -426.364257) (xy 346.226691 -426.383866)
			(xy 346.234121 -426.406905) (xy 346.234512 -426.41901) (xy 346.234512 -428.960534) (xy 346.234121 -428.97263)
			(xy 346.226649 -428.99564) (xy 346.212444 -429.015223) (xy 346.192892 -429.029471) (xy 346.169899 -429.036994)
			(xy 346.157804 -429.037496) (xy 345.218004 -429.037496) (xy 345.205895 -429.03708) (xy 345.182867 -429.029582)
			(xy 345.163293 -429.01532) (xy 345.149099 -428.995698) (xy 345.141679 -428.972644) (xy 345.141296 -428.960534)
			(xy 344.207523 -428.960534) (xy 344.212515 -428.964172) (xy 344.22671 -428.983792) (xy 344.234132 -429.006844)
			(xy 344.234516 -429.018954) (xy 344.234516 -431.560478) (xy 344.234073 -431.572571) (xy 344.226617 -431.595578)
			(xy 344.212426 -431.615162) (xy 344.192884 -431.629412) (xy 344.169899 -431.636937) (xy 344.157808 -431.63744)
			(xy 343.218008 -431.63744) (xy 343.205904 -431.636978) (xy 343.182883 -431.629485) (xy 343.163313 -431.615234)
			(xy 343.149117 -431.595625) (xy 343.141689 -431.572584) (xy 343.1413 -431.560478) (xy 342.23452 -431.560478)
			(xy 342.23452 -432.560476) (xy 342.234067 -432.572556) (xy 342.226607 -432.595536) (xy 342.212411 -432.615086)
			(xy 342.192868 -432.629291) (xy 342.169892 -432.636761) (xy 342.157812 -432.637184) (xy 341.218012 -432.637184)
			(xy 341.205928 -432.636777) (xy 341.182941 -432.629309) (xy 341.163389 -432.615103) (xy 341.149185 -432.595548)
			(xy 341.141722 -432.572561) (xy 341.141304 -432.560476) (xy 340.207113 -432.560476) (xy 340.212394 -432.564314)
			(xy 340.226588 -432.583853) (xy 340.234051 -432.606821) (xy 340.234524 -432.618896) (xy 340.234524 -435.16042)
			(xy 340.234053 -435.172494) (xy 340.226587 -435.195459) (xy 340.212391 -435.214994) (xy 340.192855 -435.229189)
			(xy 340.16989 -435.236654) (xy 340.157816 -435.237128) (xy 339.218016 -435.237128) (xy 339.205944 -435.236622)
			(xy 339.182981 -435.229167) (xy 339.163445 -435.21498) (xy 339.14925 -435.195451) (xy 339.141783 -435.172492)
			(xy 339.141308 -435.16042) (xy 338.234528 -435.16042) (xy 338.234528 -436.160418) (xy 338.234108 -436.172512)
			(xy 338.226642 -436.195518) (xy 338.212445 -436.215101) (xy 338.192899 -436.22935) (xy 338.169912 -436.236876)
			(xy 338.15782 -436.23738) (xy 337.21802 -436.23738) (xy 337.20591 -436.236966) (xy 337.18288 -436.22947)
			(xy 337.163305 -436.215208) (xy 337.149111 -436.195585) (xy 337.141693 -436.172529) (xy 337.141312 -436.160418)
			(xy 336.206771 -436.160418) (xy 336.212401 -436.16451) (xy 336.226595 -436.184049) (xy 336.234059 -436.207017)
			(xy 336.234532 -436.219092) (xy 336.234532 -438.760616) (xy 336.23405 -438.772689) (xy 336.226586 -438.795653)
			(xy 336.212393 -438.815187) (xy 336.19286 -438.829382) (xy 336.169897 -438.836848) (xy 336.157824 -438.837324)
			(xy 335.218024 -438.837324) (xy 335.205944 -438.836867) (xy 335.182965 -438.829408) (xy 335.163416 -438.815213)
			(xy 335.14921 -438.795671) (xy 335.141739 -438.772696) (xy 335.141316 -438.760616) (xy 334.234536 -438.760616)
			(xy 334.234536 -439.760614) (xy 337.141312 -439.760614) (xy 337.141312 -437.21909) (xy 337.141799 -437.207003)
			(xy 337.149255 -437.184007) (xy 337.163437 -437.164429) (xy 337.182965 -437.150178) (xy 337.205934 -437.142641)
			(xy 337.21802 -437.142128) (xy 338.15782 -437.142128) (xy 338.169933 -437.1425) (xy 338.192965 -437.150008)
			(xy 338.212541 -437.16428) (xy 338.226734 -437.183913) (xy 338.234149 -437.206976) (xy 338.234528 -437.21909)
			(xy 338.234528 -438.760616) (xy 339.141308 -438.760616) (xy 339.141308 -436.219092) (xy 339.141706 -436.207007)
			(xy 339.149178 -436.184021) (xy 339.163387 -436.16447) (xy 339.182943 -436.150267) (xy 339.205931 -436.142802)
			(xy 339.218016 -436.142384) (xy 340.157816 -436.142384) (xy 340.169891 -436.142851) (xy 340.192857 -436.150317)
			(xy 340.206758 -436.160418) (xy 341.141304 -436.160418) (xy 341.141304 -433.618894) (xy 341.141802 -433.606808)
			(xy 341.149256 -433.583813) (xy 341.163436 -433.564236) (xy 341.18296 -433.549985) (xy 341.205928 -433.542447)
			(xy 341.218012 -433.541932) (xy 342.157812 -433.541932) (xy 342.169925 -433.542306) (xy 342.192958 -433.549813)
			(xy 342.212534 -433.564084) (xy 342.226727 -433.583717) (xy 342.234141 -433.60678) (xy 342.23452 -433.618894)
			(xy 342.23452 -435.16042) (xy 343.1413 -435.16042) (xy 343.1413 -432.618896) (xy 343.141709 -432.606812)
			(xy 343.149179 -432.583828) (xy 343.163386 -432.564277) (xy 343.182939 -432.550073) (xy 343.205924 -432.542607)
			(xy 343.218008 -432.542188) (xy 344.157808 -432.542188) (xy 344.169883 -432.542657) (xy 344.192849 -432.550122)
			(xy 344.2071 -432.560476) (xy 345.141296 -432.560476) (xy 345.141296 -430.018952) (xy 345.141723 -430.006875)
			(xy 345.149199 -429.983905) (xy 345.163405 -429.964368) (xy 345.182952 -429.950176) (xy 345.205926 -429.942715)
			(xy 345.218004 -429.942244) (xy 346.157804 -429.942244) (xy 346.169874 -429.94276) (xy 346.192833 -429.950218)
			(xy 346.212366 -429.964403) (xy 346.226562 -429.983927) (xy 346.234033 -430.006882) (xy 346.234512 -430.018952)
			(xy 346.234512 -431.360072) (xy 355.888036 -431.360072) (xy 355.88854 -431.271581) (xy 355.896595 -431.094782)
			(xy 355.912689 -430.918533) (xy 355.936788 -430.743199) (xy 355.968842 -430.569144) (xy 356.008786 -430.396728)
			(xy 356.056535 -430.226308) (xy 356.111991 -430.058239) (xy 356.17504 -429.892868) (xy 356.24555 -429.730538)
			(xy 356.323375 -429.571585) (xy 356.408354 -429.416339) (xy 356.500311 -429.265122) (xy 356.599056 -429.118247)
			(xy 356.704383 -428.976019) (xy 356.816074 -428.838732) (xy 356.933898 -428.70667) (xy 357.057611 -428.580108)
			(xy 357.186956 -428.459309) (xy 357.321665 -428.344521) (xy 357.461459 -428.235984) (xy 357.606049 -428.133922)
			(xy 357.755133 -428.038546) (xy 357.908404 -427.950055) (xy 358.065544 -427.868632) (xy 358.226228 -427.794445)
			(xy 358.390121 -427.727648) (xy 358.556884 -427.66838) (xy 358.726172 -427.616764) (xy 358.897634 -427.572907)
			(xy 359.070915 -427.536899) (xy 359.245655 -427.508815) (xy 359.421492 -427.488713) (xy 359.598062 -427.476635)
			(xy 359.774998 -427.472607) (xy 359.951934 -427.476635) (xy 360.128504 -427.488713) (xy 360.304341 -427.508815)
			(xy 360.479081 -427.536899) (xy 360.652362 -427.572907) (xy 360.823824 -427.616764) (xy 360.993112 -427.66838)
			(xy 361.159875 -427.727648) (xy 361.323768 -427.794445) (xy 361.484452 -427.868632) (xy 361.641592 -427.950055)
			(xy 361.659746 -427.960536) (xy 381.2413 -427.960536) (xy 381.2413 -425.419012) (xy 381.241723 -425.406929)
			(xy 381.249188 -425.383946) (xy 381.263392 -425.364394) (xy 381.282942 -425.35019) (xy 381.305925 -425.342724)
			(xy 381.318008 -425.342304) (xy 382.257808 -425.342304) (xy 382.269892 -425.342706) (xy 382.292877 -425.350177)
			(xy 382.312429 -425.364386) (xy 382.326632 -425.383941) (xy 382.334097 -425.406928) (xy 382.334516 -425.419012)
			(xy 382.334516 -427.960536) (xy 382.334067 -427.972612) (xy 382.326595 -427.995579) (xy 382.312395 -428.015115)
			(xy 382.292854 -428.029308) (xy 382.269884 -428.036771) (xy 382.257808 -428.037244) (xy 381.318008 -428.037244)
			(xy 381.305937 -428.03673) (xy 381.282977 -428.029274) (xy 381.263443 -428.015089) (xy 381.249247 -427.995563)
			(xy 381.241777 -427.972606) (xy 381.2413 -427.960536) (xy 361.659746 -427.960536) (xy 361.794863 -428.038546)
			(xy 361.943947 -428.133922) (xy 362.088537 -428.235984) (xy 362.228331 -428.344521) (xy 362.36304 -428.459309)
			(xy 362.492385 -428.580108) (xy 362.616098 -428.70667) (xy 362.733922 -428.838732) (xy 362.845613 -428.976019)
			(xy 362.95094 -429.118247) (xy 363.049685 -429.265122) (xy 363.141642 -429.416339) (xy 363.226621 -429.571585)
			(xy 363.304446 -429.730538) (xy 363.374956 -429.892868) (xy 363.438005 -430.058239) (xy 363.493461 -430.226308)
			(xy 363.54121 -430.396728) (xy 363.581154 -430.569144) (xy 363.613208 -430.743199) (xy 363.637307 -430.918533)
			(xy 363.653401 -431.094782) (xy 363.661456 -431.271581) (xy 363.66196 -431.360072) (xy 363.661504 -431.447087)
			(xy 363.653716 -431.620943) (xy 363.638154 -431.794276) (xy 363.614849 -431.966739) (xy 363.583849 -432.137985)
			(xy 363.545214 -432.307673) (xy 363.499024 -432.475461) (xy 363.445369 -432.641014) (xy 363.384358 -432.803999)
			(xy 363.316114 -432.96409) (xy 363.240772 -433.120966) (xy 363.158484 -433.274313) (xy 363.069415 -433.423823)
			(xy 362.973744 -433.569196) (xy 362.871661 -433.710142) (xy 362.763372 -433.846377) (xy 362.649094 -433.977629)
			(xy 362.529056 -434.103634) (xy 362.403498 -434.22414) (xy 362.272672 -434.338905) (xy 362.136841 -434.4477)
			(xy 361.996276 -434.550306) (xy 361.851259 -434.646518) (xy 361.702082 -434.736142) (xy 361.549042 -434.819)
			(xy 361.470956 -434.857398) (xy 361.460288 -434.862478) (xy 361.44581 -434.881274) (xy 361.424982 -434.984398)
			(xy 361.431332 -435.007258) (xy 361.439206 -435.016148) (xy 361.483334 -435.066765) (xy 361.566156 -435.172484)
			(xy 361.642445 -435.28301) (xy 361.711923 -435.397939) (xy 361.774337 -435.516853) (xy 361.829459 -435.639318)
			(xy 361.877088 -435.764887) (xy 361.91705 -435.893102) (xy 361.949199 -436.023495) (xy 361.973419 -436.155591)
			(xy 361.98962 -436.288909) (xy 361.997745 -436.422961) (xy 361.99826 -436.49011) (xy 361.997753 -436.557275)
			(xy 361.989642 -436.691359) (xy 361.973451 -436.824708) (xy 361.949237 -436.956837) (xy 361.91709 -437.087263)
			(xy 361.877127 -437.21551) (xy 361.829493 -437.34111) (xy 361.774363 -437.463604) (xy 361.711937 -437.582547)
			(xy 361.642443 -437.697503) (xy 361.566136 -437.808054) (xy 361.483292 -437.913796) (xy 361.394216 -438.014343)
			(xy 361.299231 -438.109328) (xy 361.198684 -438.198404) (xy 361.092942 -438.281248) (xy 360.982391 -438.357555)
			(xy 360.867435 -438.427049) (xy 360.748492 -438.489475) (xy 360.625998 -438.544605) (xy 360.500398 -438.592239)
			(xy 360.372151 -438.632202) (xy 360.241725 -438.664349) (xy 360.109596 -438.688563) (xy 359.976247 -438.704754)
			(xy 359.842163 -438.712865) (xy 359.707833 -438.712865) (xy 359.573749 -438.704754) (xy 359.4404 -438.688563)
			(xy 359.308271 -438.664349) (xy 359.177845 -438.632202) (xy 359.049598 -438.592239) (xy 358.923998 -438.544605)
			(xy 358.801504 -438.489475) (xy 358.682561 -438.427049) (xy 358.567605 -438.357555) (xy 358.457054 -438.281248)
			(xy 358.351312 -438.198404) (xy 358.250765 -438.109328) (xy 358.15578 -438.014343) (xy 358.066704 -437.913796)
			(xy 357.98386 -437.808054) (xy 357.907553 -437.697503) (xy 357.838059 -437.582547) (xy 357.775633 -437.463604)
			(xy 357.720503 -437.34111) (xy 357.672869 -437.21551) (xy 357.632906 -437.087263) (xy 357.600759 -436.956837)
			(xy 357.576545 -436.824708) (xy 357.560354 -436.691359) (xy 357.552243 -436.557275) (xy 357.551736 -436.49011)
			(xy 357.552226 -436.42296) (xy 357.560351 -436.288906) (xy 357.576553 -436.155587) (xy 357.600772 -436.02349)
			(xy 357.632922 -435.893095) (xy 357.672885 -435.764878) (xy 357.720514 -435.639308) (xy 357.775636 -435.516842)
			(xy 357.838051 -435.397927) (xy 357.90753 -435.282996) (xy 357.98382 -435.172468) (xy 358.066642 -435.066748)
			(xy 358.11079 -435.016148) (xy 358.118664 -435.007258) (xy 358.125014 -434.984398) (xy 358.104186 -434.881274)
			(xy 358.089708 -434.862478) (xy 358.07904 -434.857398) (xy 358.000981 -434.818946) (xy 357.847945 -434.736088)
			(xy 357.698771 -434.646463) (xy 357.553757 -434.550252) (xy 357.413195 -434.447647) (xy 357.277366 -434.338853)
			(xy 357.146543 -434.224088) (xy 357.020987 -434.103584) (xy 356.90095 -433.977581) (xy 356.786674 -433.846331)
			(xy 356.678386 -433.710098) (xy 356.576305 -433.569155) (xy 356.480633 -433.423784) (xy 356.391565 -433.274278)
			(xy 356.309277 -433.120934) (xy 356.233934 -432.964061) (xy 356.165689 -432.803973) (xy 356.104677 -432.640991)
			(xy 356.051021 -432.475441) (xy 356.004828 -432.307656) (xy 355.966191 -432.137972) (xy 355.935188 -431.966728)
			(xy 355.91188 -431.794269) (xy 355.896314 -431.620939) (xy 355.888522 -431.447086) (xy 355.888036 -431.360072)
			(xy 346.234512 -431.360072) (xy 346.234512 -432.560476) (xy 346.234067 -432.572557) (xy 346.226606 -432.595538)
			(xy 346.212409 -432.615089) (xy 346.192863 -432.629294) (xy 346.169885 -432.636762) (xy 346.157804 -432.637184)
			(xy 345.218004 -432.637184) (xy 345.205919 -432.636784) (xy 345.182932 -432.629314) (xy 345.16338 -432.615106)
			(xy 345.149176 -432.59555) (xy 345.141713 -432.572561) (xy 345.141296 -432.560476) (xy 344.2071 -432.560476)
			(xy 344.212386 -432.564317) (xy 344.22658 -432.583854) (xy 344.234043 -432.606821) (xy 344.234516 -432.618896)
			(xy 344.234516 -435.16042) (xy 344.234053 -435.172495) (xy 344.226586 -435.195461) (xy 344.212389 -435.214997)
			(xy 344.19285 -435.229191) (xy 344.169883 -435.236655) (xy 344.157808 -435.237128) (xy 343.218008 -435.237128)
			(xy 343.205936 -435.236629) (xy 343.182972 -435.229171) (xy 343.163437 -435.214983) (xy 343.149241 -435.195453)
			(xy 343.141775 -435.172492) (xy 343.1413 -435.16042) (xy 342.23452 -435.16042) (xy 342.23452 -436.160418)
			(xy 342.234107 -436.172513) (xy 342.226641 -436.195521) (xy 342.212442 -436.215104) (xy 342.192894 -436.229352)
			(xy 342.169905 -436.236877) (xy 342.157812 -436.23738) (xy 341.218012 -436.23738) (xy 341.205902 -436.236973)
			(xy 341.182872 -436.229474) (xy 341.163297 -436.215211) (xy 341.149102 -436.195586) (xy 341.141685 -436.17253)
			(xy 341.141304 -436.160418) (xy 340.206758 -436.160418) (xy 340.212393 -436.164513) (xy 340.226587 -436.18405)
			(xy 340.234051 -436.207017) (xy 340.234524 -436.219092) (xy 340.234524 -438.760616) (xy 340.23405 -438.77269)
			(xy 340.226585 -438.795655) (xy 340.21239 -438.81519) (xy 340.192855 -438.829385) (xy 340.16989 -438.83685)
			(xy 340.157816 -438.837324) (xy 339.218016 -438.837324) (xy 339.205944 -438.836822) (xy 339.18298 -438.829366)
			(xy 339.163444 -438.815179) (xy 339.149248 -438.795649) (xy 339.141783 -438.772688) (xy 339.141308 -438.760616)
			(xy 338.234528 -438.760616) (xy 338.234528 -439.760614) (xy 341.141304 -439.760614) (xy 341.141304 -437.21909)
			(xy 341.141798 -437.207004) (xy 341.149253 -437.184009) (xy 341.163434 -437.164432) (xy 341.18296 -437.150181)
			(xy 341.205927 -437.142643) (xy 341.218012 -437.142128) (xy 342.157812 -437.142128) (xy 342.169924 -437.142506)
			(xy 342.192957 -437.150012) (xy 342.212532 -437.164283) (xy 342.226725 -437.183914) (xy 342.234141 -437.206976)
			(xy 342.23452 -437.21909) (xy 342.23452 -438.760616) (xy 343.1413 -438.760616) (xy 343.1413 -436.219092)
			(xy 343.141758 -436.207016) (xy 343.149223 -436.184047) (xy 343.163421 -436.16451) (xy 343.182962 -436.150316)
			(xy 343.205932 -436.142855) (xy 343.218008 -436.142384) (xy 344.157808 -436.142384) (xy 344.169882 -436.142857)
			(xy 344.192848 -436.150321) (xy 344.206744 -436.160418) (xy 345.141296 -436.160418) (xy 345.141296 -433.618894)
			(xy 345.141802 -433.606809) (xy 345.149255 -433.583815) (xy 345.163433 -433.564239) (xy 345.182955 -433.549987)
			(xy 345.20592 -433.542448) (xy 345.218004 -433.541932) (xy 346.157804 -433.541932) (xy 346.169916 -433.542313)
			(xy 346.192949 -433.549818) (xy 346.212525 -433.564087) (xy 346.226718 -433.583718) (xy 346.234133 -433.60678)
			(xy 346.234512 -433.618894) (xy 346.234512 -436.160418) (xy 346.234107 -436.172513) (xy 346.22664 -436.195523)
			(xy 346.212439 -436.215106) (xy 346.192889 -436.229355) (xy 346.169898 -436.236878) (xy 346.157804 -436.23738)
			(xy 345.218004 -436.23738) (xy 345.205893 -436.23698) (xy 345.182863 -436.229479) (xy 345.163288 -436.215214)
			(xy 345.149094 -436.195588) (xy 345.141676 -436.17253) (xy 345.141296 -436.160418) (xy 344.206744 -436.160418)
			(xy 344.212384 -436.164516) (xy 344.226579 -436.184052) (xy 344.234043 -436.207018) (xy 344.234516 -436.219092)
			(xy 344.234516 -438.760616) (xy 344.234049 -438.772691) (xy 344.226583 -438.795657) (xy 344.212387 -438.815193)
			(xy 344.19285 -438.829387) (xy 344.169883 -438.836851) (xy 344.157808 -438.837324) (xy 343.218008 -438.837324)
			(xy 343.205935 -438.836829) (xy 343.182971 -438.829371) (xy 343.163435 -438.815182) (xy 343.14924 -438.79565)
			(xy 343.141775 -438.772688) (xy 343.1413 -438.760616) (xy 342.23452 -438.760616) (xy 342.23452 -439.760614)
			(xy 345.141296 -439.760614) (xy 345.141296 -437.21909) (xy 345.141798 -437.207004) (xy 345.149252 -437.184011)
			(xy 345.163431 -437.164435) (xy 345.182955 -437.150183) (xy 345.20592 -437.142644) (xy 345.218004 -437.142128)
			(xy 346.157804 -437.142128) (xy 346.169916 -437.142513) (xy 346.192948 -437.150017) (xy 346.212524 -437.164286)
			(xy 346.226717 -437.183916) (xy 346.234133 -437.206977) (xy 346.234512 -437.21909) (xy 346.234512 -439.760614)
			(xy 346.234104 -439.772709) (xy 346.226638 -439.795718) (xy 346.212437 -439.815302) (xy 346.192889 -439.829551)
			(xy 346.169898 -439.837074) (xy 346.157804 -439.837576) (xy 345.218004 -439.837576) (xy 345.205893 -439.83718)
			(xy 345.182862 -439.829679) (xy 345.163286 -439.815413) (xy 345.149092 -439.795785) (xy 345.141676 -439.772727)
			(xy 345.141296 -439.760614) (xy 342.23452 -439.760614) (xy 342.234104 -439.772708) (xy 342.226639 -439.795716)
			(xy 342.21244 -439.815299) (xy 342.192894 -439.829548) (xy 342.169905 -439.837073) (xy 342.157812 -439.837576)
			(xy 341.218012 -439.837576) (xy 341.205901 -439.837173) (xy 341.18287 -439.829674) (xy 341.163295 -439.81541)
			(xy 341.149101 -439.795784) (xy 341.141684 -439.772726) (xy 341.141304 -439.760614) (xy 338.234528 -439.760614)
			(xy 338.234104 -439.772708) (xy 338.22664 -439.795714) (xy 338.212443 -439.815297) (xy 338.192899 -439.829546)
			(xy 338.169912 -439.837072) (xy 338.15782 -439.837576) (xy 337.21802 -439.837576) (xy 337.20591 -439.837166)
			(xy 337.182879 -439.829669) (xy 337.163304 -439.815407) (xy 337.149109 -439.795782) (xy 337.141692 -439.772726)
			(xy 337.141312 -439.760614) (xy 334.234536 -439.760614) (xy 334.234104 -439.772707) (xy 334.226641 -439.795712)
			(xy 334.212446 -439.815294) (xy 334.192904 -439.829543) (xy 334.169919 -439.83707) (xy 334.157828 -439.837576)
			(xy 333.218028 -439.837576) (xy 333.205918 -439.837159) (xy 333.182888 -439.829665) (xy 333.163312 -439.815404)
			(xy 333.149117 -439.795781) (xy 333.1417 -439.772725) (xy 333.14132 -439.760614) (xy 329.2348 -439.760614)
			(xy 329.234301 -439.772726) (xy 329.226815 -439.795763) (xy 329.212578 -439.815361) (xy 329.192984 -439.829604)
			(xy 329.169949 -439.837097) (xy 329.157838 -439.837576) (xy 328.218038 -439.837576) (xy 328.205919 -439.837108)
			(xy 328.182863 -439.829628) (xy 328.163249 -439.815388) (xy 328.148996 -439.795783) (xy 328.1415 -439.772733)
			(xy 328.141076 -439.760614) (xy 325.234808 -439.760614) (xy 325.234301 -439.772725) (xy 325.226816 -439.795761)
			(xy 325.212581 -439.815358) (xy 325.192989 -439.829601) (xy 325.169957 -439.837096) (xy 325.157846 -439.837576)
			(xy 324.218046 -439.837576) (xy 324.205927 -439.837101) (xy 324.182872 -439.829623) (xy 324.163257 -439.815385)
			(xy 324.149004 -439.795782) (xy 324.141508 -439.772733) (xy 324.141084 -439.760614) (xy 321.234816 -439.760614)
			(xy 321.234451 -439.772742) (xy 321.226949 -439.795809) (xy 321.212685 -439.815428) (xy 321.193055 -439.829677)
			(xy 321.169982 -439.83716) (xy 321.157854 -439.837576) (xy 320.218054 -439.837576) (xy 320.205938 -439.837128)
			(xy 320.182896 -439.82963) (xy 320.163296 -439.815381) (xy 320.149056 -439.795775) (xy 320.141567 -439.77273)
			(xy 320.141092 -439.760614) (xy 317.234824 -439.760614) (xy 317.234451 -439.772741) (xy 317.22695 -439.795807)
			(xy 317.212688 -439.815425) (xy 317.19306 -439.829674) (xy 317.16999 -439.837159) (xy 317.157862 -439.837576)
			(xy 316.218062 -439.837576) (xy 316.205947 -439.837121) (xy 316.182905 -439.829625) (xy 316.163305 -439.815378)
			(xy 316.149064 -439.795774) (xy 316.141575 -439.772729) (xy 316.1411 -439.760614) (xy 296.787162 -439.760614)
			(xy 296.765145 -439.778249) (xy 296.600094 -439.900219) (xy 296.43042 -440.015672) (xy 296.25638 -440.124434)
			(xy 296.078239 -440.226339) (xy 295.98747 -440.274202) (xy 295.987216 -440.274202) (xy 295.977461 -440.280027)
			(xy 295.963872 -440.298199) (xy 295.959411 -440.320448) (xy 295.961562 -440.331606) (xy 295.985184 -440.427364)
			(xy 295.988489 -440.438171) (xy 296.002783 -440.455638) (xy 296.023175 -440.46531) (xy 296.03446 -440.465972)
			(xy 314.119006 -440.465972) (xy 314.120276 -440.465972) (xy 314.129194 -440.465406) (xy 314.145814 -440.458868)
			(xy 314.159188 -440.447031) (xy 314.167696 -440.431328) (xy 314.169298 -440.422538) (xy 314.169298 -440.422284)
			(xy 314.174196 -440.3911) (xy 314.191024 -440.330259) (xy 314.215602 -440.272116) (xy 314.247516 -440.217652)
			(xy 314.286225 -440.167789) (xy 314.331076 -440.123369) (xy 314.381311 -440.085143) (xy 314.43608 -440.053757)
			(xy 314.494458 -440.029741) (xy 314.555458 -440.013501) (xy 314.61805 -440.005312) (xy 314.681174 -440.005312)
			(xy 314.743766 -440.013501) (xy 314.804766 -440.029741) (xy 314.863144 -440.053757) (xy 314.917913 -440.085143)
			(xy 314.968148 -440.123369) (xy 315.012999 -440.167789) (xy 315.051708 -440.217652) (xy 315.083622 -440.272116)
			(xy 315.1082 -440.330259) (xy 315.125028 -440.3911) (xy 315.129926 -440.422284) (xy 315.129926 -440.422538)
			(xy 315.131556 -440.431325) (xy 315.140044 -440.447039) (xy 315.153409 -440.458886) (xy 315.170029 -440.465427)
			(xy 315.178948 -440.465972) (xy 318.118998 -440.465972) (xy 318.120268 -440.465972) (xy 318.129187 -440.465407)
			(xy 318.145809 -440.45887) (xy 318.159185 -440.447034) (xy 318.167695 -440.43133) (xy 318.16929 -440.422538)
			(xy 318.16929 -440.422284) (xy 318.174188 -440.3911) (xy 318.191016 -440.330259) (xy 318.215594 -440.272116)
			(xy 318.247508 -440.217652) (xy 318.286217 -440.167789) (xy 318.331068 -440.123369) (xy 318.381303 -440.085143)
			(xy 318.436072 -440.053757) (xy 318.49445 -440.029741) (xy 318.55545 -440.013501) (xy 318.618042 -440.005312)
			(xy 318.681166 -440.005312) (xy 318.743758 -440.013501) (xy 318.804758 -440.029741) (xy 318.863136 -440.053757)
			(xy 318.917905 -440.085143) (xy 318.96814 -440.123369) (xy 319.012991 -440.167789) (xy 319.0517 -440.217652)
			(xy 319.083614 -440.272116) (xy 319.108192 -440.330259) (xy 319.12502 -440.3911) (xy 319.129918 -440.422284)
			(xy 319.129918 -440.422538) (xy 319.131548 -440.431325) (xy 319.140036 -440.447041) (xy 319.153401 -440.45889)
			(xy 319.17002 -440.465433) (xy 319.17894 -440.465972) (xy 322.11899 -440.465972) (xy 322.12026 -440.465972)
			(xy 322.12918 -440.465408) (xy 322.145805 -440.458873) (xy 322.159183 -440.447036) (xy 322.167694 -440.431332)
			(xy 322.169282 -440.422538) (xy 322.169282 -440.422284) (xy 322.17418 -440.3911) (xy 322.191008 -440.330259)
			(xy 322.215586 -440.272116) (xy 322.2475 -440.217652) (xy 322.286209 -440.167789) (xy 322.33106 -440.123369)
			(xy 322.381295 -440.085143) (xy 322.436064 -440.053757) (xy 322.494442 -440.029741) (xy 322.555442 -440.013501)
			(xy 322.618034 -440.005312) (xy 322.681158 -440.005312) (xy 322.74375 -440.013501) (xy 322.80475 -440.029741)
			(xy 322.863128 -440.053757) (xy 322.917897 -440.085143) (xy 322.968132 -440.123369) (xy 323.012983 -440.167789)
			(xy 323.051692 -440.217652) (xy 323.083606 -440.272116) (xy 323.108184 -440.330259) (xy 323.125012 -440.3911)
			(xy 323.12991 -440.422284) (xy 323.12991 -440.422538) (xy 323.13154 -440.431326) (xy 323.140027 -440.447043)
			(xy 323.153392 -440.458894) (xy 323.170011 -440.46544) (xy 323.178932 -440.465972) (xy 326.118982 -440.465972)
			(xy 326.120252 -440.465972) (xy 326.129173 -440.46541) (xy 326.1458 -440.458876) (xy 326.15918 -440.447039)
			(xy 326.167693 -440.431334) (xy 326.169274 -440.422538) (xy 326.169274 -440.422284) (xy 326.174172 -440.3911)
			(xy 326.191 -440.330259) (xy 326.215578 -440.272116) (xy 326.247492 -440.217652) (xy 326.286201 -440.167789)
			(xy 326.331052 -440.123369) (xy 326.381287 -440.085143) (xy 326.436056 -440.053757) (xy 326.494434 -440.029741)
			(xy 326.555434 -440.013501) (xy 326.618026 -440.005312) (xy 326.68115 -440.005312) (xy 326.743742 -440.013501)
			(xy 326.804742 -440.029741) (xy 326.86312 -440.053757) (xy 326.917889 -440.085143) (xy 326.968124 -440.123369)
			(xy 327.012975 -440.167789) (xy 327.051684 -440.217652) (xy 327.083598 -440.272116) (xy 327.108176 -440.330259)
			(xy 327.125004 -440.3911) (xy 327.129902 -440.422284) (xy 327.129902 -440.422538) (xy 327.131532 -440.431326)
			(xy 327.140018 -440.447045) (xy 327.153383 -440.458898) (xy 327.170003 -440.465446) (xy 327.178924 -440.465972)
			(xy 331.119226 -440.465972) (xy 331.120496 -440.465972) (xy 331.129412 -440.465403) (xy 331.146026 -440.458861)
			(xy 331.159394 -440.447024) (xy 331.167898 -440.431323) (xy 331.169518 -440.422538) (xy 331.169518 -440.422284)
			(xy 331.174416 -440.3911) (xy 331.191244 -440.330259) (xy 331.215822 -440.272116) (xy 331.247736 -440.217652)
			(xy 331.286445 -440.167789) (xy 331.331296 -440.123369) (xy 331.381531 -440.085143) (xy 331.4363 -440.053757)
			(xy 331.494678 -440.029741) (xy 331.555678 -440.013501) (xy 331.61827 -440.005312) (xy 331.681394 -440.005312)
			(xy 331.743986 -440.013501) (xy 331.804986 -440.029741) (xy 331.863364 -440.053757) (xy 331.918133 -440.085143)
			(xy 331.968368 -440.123369) (xy 332.013219 -440.167789) (xy 332.051928 -440.217652) (xy 332.083842 -440.272116)
			(xy 332.10842 -440.330259) (xy 332.125248 -440.3911) (xy 332.130146 -440.422284) (xy 332.130146 -440.422538)
			(xy 332.131777 -440.431323) (xy 332.140265 -440.447034) (xy 332.153631 -440.458877) (xy 332.17025 -440.465411)
			(xy 332.179168 -440.465972) (xy 335.119218 -440.465972) (xy 335.120488 -440.465972) (xy 335.129405 -440.465404)
			(xy 335.146021 -440.458864) (xy 335.159391 -440.447026) (xy 335.167897 -440.431325) (xy 335.16951 -440.422538)
			(xy 335.16951 -440.422284) (xy 335.174408 -440.3911) (xy 335.191236 -440.330259) (xy 335.215814 -440.272116)
			(xy 335.247728 -440.217652) (xy 335.286437 -440.167789) (xy 335.331288 -440.123369) (xy 335.381523 -440.085143)
			(xy 335.436292 -440.053757) (xy 335.49467 -440.029741) (xy 335.55567 -440.013501) (xy 335.618262 -440.005312)
			(xy 335.681386 -440.005312) (xy 335.743978 -440.013501) (xy 335.804978 -440.029741) (xy 335.863356 -440.053757)
			(xy 335.918125 -440.085143) (xy 335.96836 -440.123369) (xy 336.013211 -440.167789) (xy 336.05192 -440.217652)
			(xy 336.083834 -440.272116) (xy 336.108412 -440.330259) (xy 336.12524 -440.3911) (xy 336.130138 -440.422284)
			(xy 336.130138 -440.422538) (xy 336.131768 -440.431324) (xy 336.140257 -440.447036) (xy 336.153623 -440.45888)
			(xy 336.170242 -440.465418) (xy 336.17916 -440.465972) (xy 339.11921 -440.465972) (xy 339.12048 -440.465972)
			(xy 339.129398 -440.465405) (xy 339.146017 -440.458866) (xy 339.159389 -440.447029) (xy 339.167896 -440.431327)
			(xy 339.169502 -440.422538) (xy 339.169502 -440.422284) (xy 339.1744 -440.3911) (xy 339.191228 -440.330259)
			(xy 339.215806 -440.272116) (xy 339.24772 -440.217652) (xy 339.286429 -440.167789) (xy 339.33128 -440.123369)
			(xy 339.381515 -440.085143) (xy 339.436284 -440.053757) (xy 339.494662 -440.029741) (xy 339.555662 -440.013501)
			(xy 339.618254 -440.005312) (xy 339.681378 -440.005312) (xy 339.74397 -440.013501) (xy 339.80497 -440.029741)
			(xy 339.863348 -440.053757) (xy 339.918117 -440.085143) (xy 339.968352 -440.123369) (xy 340.013203 -440.167789)
			(xy 340.051912 -440.217652) (xy 340.083826 -440.272116) (xy 340.108404 -440.330259) (xy 340.125232 -440.3911)
			(xy 340.13013 -440.422284) (xy 340.13013 -440.422538) (xy 340.13176 -440.431324) (xy 340.140248 -440.447038)
			(xy 340.153614 -440.458884) (xy 340.170233 -440.465424) (xy 340.179152 -440.465972) (xy 343.119202 -440.465972)
			(xy 343.120472 -440.465972) (xy 343.129391 -440.465407) (xy 343.146012 -440.458869) (xy 343.159386 -440.447032)
			(xy 343.167895 -440.431329) (xy 343.169494 -440.422538) (xy 343.169494 -440.422284) (xy 343.174392 -440.3911)
			(xy 343.19122 -440.330259) (xy 343.215798 -440.272116) (xy 343.247712 -440.217652) (xy 343.286421 -440.167789)
			(xy 343.331272 -440.123369) (xy 343.381507 -440.085143) (xy 343.436276 -440.053757) (xy 343.494654 -440.029741)
			(xy 343.555654 -440.013501) (xy 343.618246 -440.005312) (xy 343.68137 -440.005312) (xy 343.743962 -440.013501)
			(xy 343.804962 -440.029741) (xy 343.86334 -440.053757) (xy 343.918109 -440.085143) (xy 343.968344 -440.123369)
			(xy 344.013195 -440.167789) (xy 344.051904 -440.217652) (xy 344.083818 -440.272116) (xy 344.108396 -440.330259)
			(xy 344.125224 -440.3911) (xy 344.130122 -440.422284) (xy 344.130122 -440.422538) (xy 344.131752 -440.431325)
			(xy 344.14024 -440.44704) (xy 344.153605 -440.458888) (xy 344.170224 -440.46543) (xy 344.179144 -440.465972)
			(xy 368.814858 -440.465972) (xy 368.826153 -440.465375) (xy 368.846563 -440.455693) (xy 368.860839 -440.438185)
			(xy 368.864134 -440.427364) (xy 368.887756 -440.331606) (xy 368.889934 -440.320455) (xy 368.885463 -440.298209)
			(xy 368.871841 -440.280062) (xy 368.862102 -440.274202) (xy 368.861848 -440.274202) (xy 368.771086 -440.226319)
			(xy 368.592935 -440.124422) (xy 368.418885 -440.015668) (xy 368.2492 -439.900222) (xy 368.084138 -439.778258)
			(xy 367.923948 -439.649962) (xy 367.768873 -439.515527) (xy 367.619149 -439.375158) (xy 367.475002 -439.229068)
			(xy 367.336651 -439.077477) (xy 367.204305 -438.920616) (xy 367.078166 -438.758722) (xy 366.958423 -438.592041)
			(xy 366.84526 -438.420826) (xy 366.738846 -438.245335) (xy 366.639345 -438.065835) (xy 366.546905 -437.882598)
			(xy 366.461669 -437.695902) (xy 366.383764 -437.506029) (xy 366.313308 -437.313268) (xy 366.25041 -437.117911)
			(xy 366.195163 -436.920253) (xy 366.147652 -436.720595) (xy 366.107948 -436.519238) (xy 366.076113 -436.316489)
			(xy 366.052193 -436.112654) (xy 366.036226 -435.908043) (xy 366.028236 -435.702965) (xy 366.027716 -435.600348)
			(xy 366.028212 -435.498122) (xy 366.036139 -435.293823) (xy 366.051983 -435.089985) (xy 366.075719 -434.886914)
			(xy 366.10731 -434.684917) (xy 366.146711 -434.484297) (xy 366.193861 -434.285355) (xy 366.24869 -434.088391)
			(xy 366.311114 -433.893701) (xy 366.381041 -433.701578) (xy 366.458365 -433.512312) (xy 366.54297 -433.326185)
			(xy 366.634728 -433.14348) (xy 366.733502 -432.964469) (xy 366.839143 -432.789424) (xy 366.951491 -432.618606)
			(xy 367.070379 -432.452273) (xy 367.195627 -432.290675) (xy 367.327047 -432.134055) (xy 367.464441 -431.982648)
			(xy 367.607602 -431.836684) (xy 367.756316 -431.69638) (xy 367.910358 -431.561947) (xy 368.069496 -431.43359)
			(xy 368.233493 -431.311499) (xy 368.4021 -431.195859) (xy 368.575064 -431.086844) (xy 368.752126 -430.984617)
			(xy 368.933018 -430.889333) (xy 369.117468 -430.801135) (xy 369.3052 -430.720156) (xy 369.495931 -430.646516)
			(xy 369.689373 -430.580328) (xy 369.885237 -430.52169) (xy 370.083227 -430.470691) (xy 370.283046 -430.427408)
			(xy 370.484392 -430.391905) (xy 370.686964 -430.364236) (xy 370.890457 -430.344443) (xy 371.094564 -430.332555)
			(xy 371.298978 -430.328591) (xy 371.503392 -430.332555) (xy 371.707499 -430.344443) (xy 371.910992 -430.364236)
			(xy 372.113564 -430.391905) (xy 372.31491 -430.427408) (xy 372.514729 -430.470691) (xy 372.712719 -430.52169)
			(xy 372.908583 -430.580328) (xy 373.102025 -430.646516) (xy 373.292756 -430.720156) (xy 373.480488 -430.801135)
			(xy 373.664938 -430.889333) (xy 373.84583 -430.984617) (xy 374.022892 -431.086844) (xy 374.195856 -431.195859)
			(xy 374.364463 -431.311499) (xy 374.52846 -431.43359) (xy 374.685777 -431.560478) (xy 381.2413 -431.560478)
			(xy 381.2413 -429.018954) (xy 381.241767 -429.006866) (xy 381.249232 -428.983871) (xy 381.26342 -428.964295)
			(xy 381.28295 -428.950044) (xy 381.305922 -428.942507) (xy 381.318008 -428.941992) (xy 382.257808 -428.941992)
			(xy 382.269917 -428.942409) (xy 382.292943 -428.94991) (xy 382.307523 -428.960534) (xy 383.241296 -428.960534)
			(xy 383.241296 -426.41901) (xy 383.241815 -426.406925) (xy 383.249264 -426.383932) (xy 383.263439 -426.364356)
			(xy 383.282958 -426.350104) (xy 383.305921 -426.342564) (xy 383.318004 -426.342048) (xy 384.257804 -426.342048)
			(xy 384.269908 -426.342512) (xy 384.292927 -426.350006) (xy 384.312495 -426.364257) (xy 384.326691 -426.383866)
			(xy 384.334121 -426.406905) (xy 384.334512 -426.41901) (xy 384.334512 -427.960536) (xy 385.241292 -427.960536)
			(xy 385.241292 -425.419012) (xy 385.241723 -425.40693) (xy 385.249187 -425.383948) (xy 385.263389 -425.364397)
			(xy 385.282937 -425.350193) (xy 385.305918 -425.342725) (xy 385.318 -425.342304) (xy 386.2578 -425.342304)
			(xy 386.269884 -425.342713) (xy 386.292869 -425.350182) (xy 386.31242 -425.364388) (xy 386.326624 -425.383942)
			(xy 386.334089 -425.406928) (xy 386.334508 -425.419012) (xy 386.334508 -427.960536) (xy 386.334067 -427.972612)
			(xy 386.326594 -427.995581) (xy 386.312392 -428.015117) (xy 386.292849 -428.029311) (xy 386.269877 -428.036772)
			(xy 386.2578 -428.037244) (xy 385.318 -428.037244) (xy 385.305929 -428.036736) (xy 385.282968 -428.029278)
			(xy 385.263434 -428.015092) (xy 385.249238 -427.995564) (xy 385.241769 -427.972607) (xy 385.241292 -427.960536)
			(xy 384.334512 -427.960536) (xy 384.334512 -428.960534) (xy 384.334121 -428.97263) (xy 384.326649 -428.99564)
			(xy 384.312444 -429.015223) (xy 384.292892 -429.029471) (xy 384.269899 -429.036994) (xy 384.257804 -429.037496)
			(xy 383.318004 -429.037496) (xy 383.305895 -429.03708) (xy 383.282867 -429.029582) (xy 383.263293 -429.01532)
			(xy 383.249099 -428.995698) (xy 383.241679 -428.972644) (xy 383.241296 -428.960534) (xy 382.307523 -428.960534)
			(xy 382.312515 -428.964172) (xy 382.32671 -428.983792) (xy 382.334132 -429.006844) (xy 382.334516 -429.018954)
			(xy 382.334516 -431.560478) (xy 382.334073 -431.572571) (xy 382.326617 -431.595578) (xy 382.312426 -431.615162)
			(xy 382.292884 -431.629412) (xy 382.269899 -431.636937) (xy 382.257808 -431.63744) (xy 381.318008 -431.63744)
			(xy 381.305904 -431.636978) (xy 381.282883 -431.629485) (xy 381.263313 -431.615234) (xy 381.249117 -431.595625)
			(xy 381.241689 -431.572584) (xy 381.2413 -431.560478) (xy 374.685777 -431.560478) (xy 374.687598 -431.561947)
			(xy 374.84164 -431.69638) (xy 374.990354 -431.836684) (xy 375.133515 -431.982648) (xy 375.270909 -432.134055)
			(xy 375.402329 -432.290675) (xy 375.527577 -432.452273) (xy 375.646465 -432.618606) (xy 375.758813 -432.789424)
			(xy 375.864454 -432.964469) (xy 375.963228 -433.14348) (xy 376.054986 -433.326185) (xy 376.139591 -433.512312)
			(xy 376.216915 -433.701578) (xy 376.286842 -433.893701) (xy 376.349266 -434.088391) (xy 376.404095 -434.285355)
			(xy 376.451245 -434.484297) (xy 376.490646 -434.684917) (xy 376.522237 -434.886914) (xy 376.545973 -435.089985)
			(xy 376.551448 -435.16042) (xy 381.2413 -435.16042) (xy 381.2413 -432.618896) (xy 381.241709 -432.606812)
			(xy 381.249179 -432.583828) (xy 381.263386 -432.564277) (xy 381.282939 -432.550073) (xy 381.305924 -432.542607)
			(xy 381.318008 -432.542188) (xy 382.257808 -432.542188) (xy 382.269883 -432.542657) (xy 382.292849 -432.550122)
			(xy 382.3071 -432.560476) (xy 383.241296 -432.560476) (xy 383.241296 -430.018952) (xy 383.241723 -430.006875)
			(xy 383.249199 -429.983905) (xy 383.263405 -429.964368) (xy 383.282952 -429.950176) (xy 383.305926 -429.942715)
			(xy 383.318004 -429.942244) (xy 384.257804 -429.942244) (xy 384.269874 -429.94276) (xy 384.292833 -429.950218)
			(xy 384.312366 -429.964403) (xy 384.326562 -429.983927) (xy 384.334033 -430.006882) (xy 384.334512 -430.018952)
			(xy 384.334512 -431.560478) (xy 385.241292 -431.560478) (xy 385.241292 -429.018954) (xy 385.241767 -429.006867)
			(xy 385.249231 -428.983873) (xy 385.263417 -428.964298) (xy 385.282945 -428.950047) (xy 385.305914 -428.942508)
			(xy 385.318 -428.941992) (xy 386.2578 -428.941992) (xy 386.269908 -428.942416) (xy 386.292934 -428.949914)
			(xy 386.307511 -428.960534) (xy 387.241288 -428.960534) (xy 387.241288 -426.41901) (xy 387.241717 -426.406916)
			(xy 387.249177 -426.383908) (xy 387.263371 -426.364324) (xy 387.282916 -426.350075) (xy 387.305904 -426.342551)
			(xy 387.317996 -426.342048) (xy 388.257796 -426.342048) (xy 388.269899 -426.342519) (xy 388.292918 -426.350011)
			(xy 388.312487 -426.36426) (xy 388.326683 -426.383867) (xy 388.334113 -426.406905) (xy 388.334504 -426.41901)
			(xy 388.334504 -427.960536) (xy 389.241284 -427.960536) (xy 389.241284 -425.419012) (xy 389.241723 -425.406931)
			(xy 389.249186 -425.38395) (xy 389.263386 -425.3644) (xy 389.282932 -425.350195) (xy 389.305911 -425.342726)
			(xy 389.317992 -425.342304) (xy 390.257792 -425.342304) (xy 390.269876 -425.342719) (xy 390.29286 -425.350186)
			(xy 390.312412 -425.364391) (xy 390.326616 -425.383943) (xy 390.334081 -425.406928) (xy 390.3345 -425.419012)
			(xy 390.3345 -427.960536) (xy 390.334067 -427.972613) (xy 390.326593 -427.995583) (xy 390.312389 -428.01512)
			(xy 390.292844 -428.029313) (xy 390.26987 -428.036773) (xy 390.257792 -428.037244) (xy 389.317992 -428.037244)
			(xy 389.305921 -428.036743) (xy 389.282959 -428.029283) (xy 389.263426 -428.015094) (xy 389.24923 -427.995566)
			(xy 389.241761 -427.972607) (xy 389.241284 -427.960536) (xy 388.334504 -427.960536) (xy 388.334504 -428.960534)
			(xy 388.334023 -428.972621) (xy 388.326562 -428.995615) (xy 388.312377 -429.015191) (xy 388.29285 -429.029442)
			(xy 388.269881 -429.036981) (xy 388.257796 -429.037496) (xy 387.317996 -429.037496) (xy 387.305887 -429.037087)
			(xy 387.282858 -429.029586) (xy 387.263285 -429.015323) (xy 387.249091 -428.995699) (xy 387.241671 -428.972645)
			(xy 387.241288 -428.960534) (xy 386.307511 -428.960534) (xy 386.312507 -428.964174) (xy 386.326701 -428.983794)
			(xy 386.334124 -429.006845) (xy 386.334508 -429.018954) (xy 386.334508 -431.560478) (xy 386.333975 -431.572562)
			(xy 386.32653 -431.595553) (xy 386.312359 -431.61513) (xy 386.292842 -431.629383) (xy 386.269882 -431.636924)
			(xy 386.2578 -431.63744) (xy 385.318 -431.63744) (xy 385.305895 -431.636984) (xy 385.282875 -431.62949)
			(xy 385.263305 -431.615237) (xy 385.249109 -431.595626) (xy 385.241681 -431.572584) (xy 385.241292 -431.560478)
			(xy 384.334512 -431.560478) (xy 384.334512 -432.560476) (xy 384.334067 -432.572557) (xy 384.326606 -432.595538)
			(xy 384.312409 -432.615089) (xy 384.292863 -432.629294) (xy 384.269885 -432.636762) (xy 384.257804 -432.637184)
			(xy 383.318004 -432.637184) (xy 383.305919 -432.636784) (xy 383.282932 -432.629314) (xy 383.26338 -432.615106)
			(xy 383.249176 -432.59555) (xy 383.241713 -432.572561) (xy 383.241296 -432.560476) (xy 382.3071 -432.560476)
			(xy 382.312386 -432.564317) (xy 382.32658 -432.583854) (xy 382.334043 -432.606821) (xy 382.334516 -432.618896)
			(xy 382.334516 -435.16042) (xy 382.334053 -435.172495) (xy 382.326586 -435.195461) (xy 382.312389 -435.214997)
			(xy 382.29285 -435.229191) (xy 382.269883 -435.236655) (xy 382.257808 -435.237128) (xy 381.318008 -435.237128)
			(xy 381.305936 -435.236629) (xy 381.282972 -435.229171) (xy 381.263437 -435.214983) (xy 381.249241 -435.195453)
			(xy 381.241775 -435.172492) (xy 381.2413 -435.16042) (xy 376.551448 -435.16042) (xy 376.561817 -435.293823)
			(xy 376.569744 -435.498122) (xy 376.57024 -435.600348) (xy 376.569744 -435.702966) (xy 376.561757 -435.908045)
			(xy 376.545793 -436.112659) (xy 376.521877 -436.316496) (xy 376.490044 -436.519247) (xy 376.450343 -436.720606)
			(xy 376.402833 -436.920267) (xy 376.347588 -437.117927) (xy 376.284691 -437.313286) (xy 376.214236 -437.50605)
			(xy 376.136332 -437.695924) (xy 376.051096 -437.882622) (xy 375.958656 -438.065861) (xy 375.859154 -438.245363)
			(xy 375.75274 -438.420855) (xy 375.639576 -438.592073) (xy 375.519833 -438.758755) (xy 375.518383 -438.760616)
			(xy 381.2413 -438.760616) (xy 381.2413 -436.219092) (xy 381.241758 -436.207016) (xy 381.249223 -436.184047)
			(xy 381.263421 -436.16451) (xy 381.282962 -436.150316) (xy 381.305932 -436.142855) (xy 381.318008 -436.142384)
			(xy 382.257808 -436.142384) (xy 382.269882 -436.142857) (xy 382.292848 -436.150321) (xy 382.306744 -436.160418)
			(xy 383.241296 -436.160418) (xy 383.241296 -433.618894) (xy 383.241802 -433.606809) (xy 383.249255 -433.583815)
			(xy 383.263433 -433.564239) (xy 383.282955 -433.549987) (xy 383.30592 -433.542448) (xy 383.318004 -433.541932)
			(xy 384.257804 -433.541932) (xy 384.269916 -433.542313) (xy 384.292949 -433.549818) (xy 384.312525 -433.564087)
			(xy 384.326718 -433.583718) (xy 384.334133 -433.60678) (xy 384.334512 -433.618894) (xy 384.334512 -435.16042)
			(xy 385.241292 -435.16042) (xy 385.241292 -432.618896) (xy 385.241761 -432.606821) (xy 385.249224 -432.583854)
			(xy 385.26342 -432.564317) (xy 385.282958 -432.550123) (xy 385.305925 -432.54266) (xy 385.318 -432.542188)
			(xy 386.2578 -432.542188) (xy 386.269874 -432.542664) (xy 386.292841 -432.550126) (xy 386.307086 -432.560476)
			(xy 387.241288 -432.560476) (xy 387.241288 -430.018952) (xy 387.241723 -430.006875) (xy 387.249198 -429.983907)
			(xy 387.263403 -429.964371) (xy 387.282947 -429.950178) (xy 387.305919 -429.942716) (xy 387.317996 -429.942244)
			(xy 388.257796 -429.942244) (xy 388.269866 -429.942767) (xy 388.292824 -429.950222) (xy 388.312357 -429.964406)
			(xy 388.326554 -429.983929) (xy 388.334025 -430.006883) (xy 388.334504 -430.018952) (xy 388.334504 -431.560478)
			(xy 389.241284 -431.560478) (xy 389.241284 -429.018954) (xy 389.241669 -429.006858) (xy 389.249144 -428.983848)
			(xy 389.26335 -428.964265) (xy 389.282903 -428.950018) (xy 389.305897 -428.942495) (xy 389.317992 -428.941992)
			(xy 390.257792 -428.941992) (xy 390.2699 -428.942423) (xy 390.292925 -428.949919) (xy 390.307497 -428.960534)
			(xy 391.24128 -428.960534) (xy 391.24128 -426.41901) (xy 391.241717 -426.406917) (xy 391.249176 -426.38391)
			(xy 391.263369 -426.364326) (xy 391.282911 -426.350077) (xy 391.305896 -426.342552) (xy 391.317988 -426.342048)
			(xy 392.257788 -426.342048) (xy 392.269891 -426.342526) (xy 392.292909 -426.350016) (xy 392.312478 -426.364263)
			(xy 392.326675 -426.383869) (xy 392.334105 -426.406906) (xy 392.334496 -426.41901) (xy 392.334496 -427.960536)
			(xy 393.241276 -427.960536) (xy 393.241276 -425.419012) (xy 393.241774 -425.40694) (xy 393.249231 -425.383976)
			(xy 393.26342 -425.36444) (xy 393.28295 -425.350244) (xy 393.305912 -425.342779) (xy 393.317984 -425.342304)
			(xy 394.257784 -425.342304) (xy 394.269867 -425.342727) (xy 394.292851 -425.350191) (xy 394.312403 -425.364394)
			(xy 394.326607 -425.383945) (xy 394.334073 -425.406929) (xy 394.334492 -425.419012) (xy 394.334492 -427.960536)
			(xy 394.334066 -427.972614) (xy 394.326592 -427.995585) (xy 394.312386 -428.015123) (xy 394.292839 -428.029316)
			(xy 394.269862 -428.036775) (xy 394.257784 -428.037244) (xy 393.317984 -428.037244) (xy 393.305912 -428.03675)
			(xy 393.282951 -428.029287) (xy 393.263417 -428.015097) (xy 393.249222 -427.995567) (xy 393.241753 -427.972608)
			(xy 393.241276 -427.960536) (xy 392.334496 -427.960536) (xy 392.334496 -428.960534) (xy 392.334022 -428.972622)
			(xy 392.326561 -428.995617) (xy 392.312374 -429.015194) (xy 392.292845 -429.029444) (xy 392.269874 -429.036982)
			(xy 392.257788 -429.037496) (xy 391.317988 -429.037496) (xy 391.305878 -429.037094) (xy 391.28285 -429.029591)
			(xy 391.263276 -429.015326) (xy 391.249082 -428.995701) (xy 391.241663 -428.972645) (xy 391.24128 -428.960534)
			(xy 390.307497 -428.960534) (xy 390.312498 -428.964177) (xy 390.326693 -428.983795) (xy 390.334116 -429.006845)
			(xy 390.3345 -429.018954) (xy 390.3345 -431.560478) (xy 390.333975 -431.572562) (xy 390.326529 -431.595556)
			(xy 390.312356 -431.615132) (xy 390.292837 -431.629385) (xy 390.269874 -431.636925) (xy 390.257792 -431.63744)
			(xy 389.317992 -431.63744) (xy 389.305887 -431.636991) (xy 389.282866 -431.629494) (xy 389.263296 -431.61524)
			(xy 389.249101 -431.595628) (xy 389.241673 -431.572585) (xy 389.241284 -431.560478) (xy 388.334504 -431.560478)
			(xy 388.334504 -432.560476) (xy 388.334067 -432.572558) (xy 388.326605 -432.59554) (xy 388.312406 -432.615091)
			(xy 388.292858 -432.629296) (xy 388.269878 -432.636764) (xy 388.257796 -432.637184) (xy 387.317996 -432.637184)
			(xy 387.305911 -432.636791) (xy 387.282924 -432.629319) (xy 387.263371 -432.615109) (xy 387.249168 -432.595551)
			(xy 387.241705 -432.572562) (xy 387.241288 -432.560476) (xy 386.307086 -432.560476) (xy 386.312377 -432.56432)
			(xy 386.326572 -432.583856) (xy 386.334035 -432.606822) (xy 386.334508 -432.618896) (xy 386.334508 -435.16042)
			(xy 386.334053 -435.172496) (xy 386.326585 -435.195463) (xy 386.312386 -435.215) (xy 386.292845 -435.229194)
			(xy 386.269876 -435.236656) (xy 386.2578 -435.237128) (xy 385.318 -435.237128) (xy 385.305927 -435.236636)
			(xy 385.282964 -435.229176) (xy 385.263428 -435.214986) (xy 385.249233 -435.195454) (xy 385.241767 -435.172492)
			(xy 385.241292 -435.16042) (xy 384.334512 -435.16042) (xy 384.334512 -436.160418) (xy 384.334107 -436.172513)
			(xy 384.32664 -436.195523) (xy 384.312439 -436.215106) (xy 384.292889 -436.229355) (xy 384.269898 -436.236878)
			(xy 384.257804 -436.23738) (xy 383.318004 -436.23738) (xy 383.305893 -436.23698) (xy 383.282863 -436.229479)
			(xy 383.263288 -436.215214) (xy 383.249094 -436.195588) (xy 383.241676 -436.17253) (xy 383.241296 -436.160418)
			(xy 382.306744 -436.160418) (xy 382.312384 -436.164516) (xy 382.326579 -436.184052) (xy 382.334043 -436.207018)
			(xy 382.334516 -436.219092) (xy 382.334516 -438.760616) (xy 382.334049 -438.772691) (xy 382.326583 -438.795657)
			(xy 382.312387 -438.815193) (xy 382.29285 -438.829387) (xy 382.269883 -438.836851) (xy 382.257808 -438.837324)
			(xy 381.318008 -438.837324) (xy 381.305935 -438.836829) (xy 381.282971 -438.829371) (xy 381.263435 -438.815182)
			(xy 381.24924 -438.79565) (xy 381.241775 -438.772688) (xy 381.2413 -438.760616) (xy 375.518383 -438.760616)
			(xy 375.393692 -438.92065) (xy 375.261344 -439.077512) (xy 375.122991 -439.229103) (xy 374.978842 -439.375194)
			(xy 374.829116 -439.515563) (xy 374.674039 -439.649997) (xy 374.53592 -439.760614) (xy 383.241296 -439.760614)
			(xy 383.241296 -437.21909) (xy 383.241798 -437.207004) (xy 383.249252 -437.184011) (xy 383.263431 -437.164435)
			(xy 383.282955 -437.150183) (xy 383.30592 -437.142644) (xy 383.318004 -437.142128) (xy 384.257804 -437.142128)
			(xy 384.269916 -437.142513) (xy 384.292948 -437.150017) (xy 384.312524 -437.164286) (xy 384.326717 -437.183916)
			(xy 384.334133 -437.206977) (xy 384.334512 -437.21909) (xy 384.334512 -438.760616) (xy 385.241292 -438.760616)
			(xy 385.241292 -436.219092) (xy 385.241758 -436.207017) (xy 385.249222 -436.18405) (xy 385.263418 -436.164513)
			(xy 385.282957 -436.150319) (xy 385.305925 -436.142856) (xy 385.318 -436.142384) (xy 386.2578 -436.142384)
			(xy 386.269874 -436.142864) (xy 386.29284 -436.150326) (xy 386.306732 -436.160418) (xy 387.241288 -436.160418)
			(xy 387.241288 -433.618894) (xy 387.241703 -433.606799) (xy 387.249168 -433.583791) (xy 387.263366 -433.564207)
			(xy 387.282913 -433.549958) (xy 387.305903 -433.542435) (xy 387.317996 -433.541932) (xy 388.257796 -433.541932)
			(xy 388.269908 -433.54232) (xy 388.292941 -433.549822) (xy 388.312517 -433.56409) (xy 388.32671 -433.58372)
			(xy 388.334125 -433.606781) (xy 388.334504 -433.618894) (xy 388.334504 -435.16042) (xy 389.241284 -435.16042)
			(xy 389.241284 -432.618896) (xy 389.241761 -432.606822) (xy 389.249223 -432.583856) (xy 389.263417 -432.56432)
			(xy 389.282953 -432.550125) (xy 389.305918 -432.542661) (xy 389.317992 -432.542188) (xy 390.257792 -432.542188)
			(xy 390.269874 -432.542619) (xy 390.292856 -432.550084) (xy 390.307161 -432.560476) (xy 391.24128 -432.560476)
			(xy 391.24128 -430.018952) (xy 391.241723 -430.006876) (xy 391.249197 -429.983909) (xy 391.2634 -429.964374)
			(xy 391.282942 -429.950181) (xy 391.305912 -429.942717) (xy 391.317988 -429.942244) (xy 392.257788 -429.942244)
			(xy 392.269857 -429.942774) (xy 392.292816 -429.950227) (xy 392.312349 -429.964408) (xy 392.326546 -429.98393)
			(xy 392.334017 -430.006883) (xy 392.334496 -430.018952) (xy 392.334496 -431.560478) (xy 393.241276 -431.560478)
			(xy 393.241276 -429.018954) (xy 393.241669 -429.006858) (xy 393.249143 -428.98385) (xy 393.263347 -428.964268)
			(xy 393.282898 -428.95002) (xy 393.30589 -428.942496) (xy 393.317984 -428.941992) (xy 394.257784 -428.941992)
			(xy 394.269891 -428.94243) (xy 394.292917 -428.949924) (xy 394.307483 -428.960534) (xy 395.241272 -428.960534)
			(xy 395.241272 -426.41901) (xy 395.241717 -426.406918) (xy 395.249174 -426.383912) (xy 395.263366 -426.364329)
			(xy 395.282906 -426.35008) (xy 395.305889 -426.342553) (xy 395.31798 -426.342048) (xy 396.25778 -426.342048)
			(xy 396.269883 -426.342533) (xy 396.2929 -426.35002) (xy 396.312469 -426.364266) (xy 396.326666 -426.38387)
			(xy 396.334097 -426.406906) (xy 396.334488 -426.41901) (xy 396.334488 -427.960536) (xy 398.241012 -427.960536)
			(xy 398.241012 -425.419012) (xy 398.24147 -425.406961) (xy 398.248901 -425.384034) (xy 398.263042 -425.364517)
			(xy 398.282514 -425.350314) (xy 398.305417 -425.342809) (xy 398.317466 -425.342304) (xy 399.257774 -425.342304)
			(xy 399.269859 -425.342829) (xy 399.292852 -425.350274) (xy 399.31243 -425.364447) (xy 399.326682 -425.383966)
			(xy 399.334221 -425.406929) (xy 399.334736 -425.419012) (xy 399.334736 -427.960536) (xy 399.334272 -427.972585)
			(xy 399.326833 -427.995505) (xy 399.312692 -428.015017) (xy 399.293226 -428.029221) (xy 399.270329 -428.036732)
			(xy 399.258282 -428.037244) (xy 398.317974 -428.037244) (xy 398.305881 -428.036815) (xy 398.282877 -428.029349)
			(xy 398.263296 -428.015153) (xy 398.249047 -427.995611) (xy 398.241519 -427.972627) (xy 398.241012 -427.960536)
			(xy 396.334488 -427.960536) (xy 396.334488 -428.960534) (xy 396.334022 -428.972623) (xy 396.32656 -428.99562)
			(xy 396.312372 -429.015197) (xy 396.29284 -429.029447) (xy 396.269867 -429.036983) (xy 396.25778 -429.037496)
			(xy 395.31798 -429.037496) (xy 395.30587 -429.037101) (xy 395.282841 -429.029595) (xy 395.263268 -429.015328)
			(xy 395.249074 -428.995702) (xy 395.241655 -428.972646) (xy 395.241272 -428.960534) (xy 394.307483 -428.960534)
			(xy 394.312489 -428.96418) (xy 394.326685 -428.983797) (xy 394.334107 -429.006846) (xy 394.334492 -429.018954)
			(xy 394.334492 -431.560478) (xy 394.333974 -431.572563) (xy 394.326528 -431.595558) (xy 394.312353 -431.615135)
			(xy 394.292832 -431.629388) (xy 394.269867 -431.636926) (xy 394.257784 -431.63744) (xy 393.317984 -431.63744)
			(xy 393.305878 -431.636998) (xy 393.282857 -431.629499) (xy 393.263288 -431.615243) (xy 393.249092 -431.595629)
			(xy 393.241665 -431.572585) (xy 393.241276 -431.560478) (xy 392.334496 -431.560478) (xy 392.334496 -432.560476)
			(xy 392.334067 -432.572559) (xy 392.326604 -432.595543) (xy 392.312403 -432.615094) (xy 392.292853 -432.629299)
			(xy 392.269871 -432.636765) (xy 392.257788 -432.637184) (xy 391.317988 -432.637184) (xy 391.305902 -432.636797)
			(xy 391.282915 -432.629324) (xy 391.263363 -432.615112) (xy 391.24916 -432.595553) (xy 391.241697 -432.572562)
			(xy 391.24128 -432.560476) (xy 390.307161 -432.560476) (xy 390.312406 -432.564286) (xy 390.326611 -432.583833)
			(xy 390.334079 -432.606814) (xy 390.3345 -432.618896) (xy 390.3345 -435.16042) (xy 390.334053 -435.172496)
			(xy 390.326584 -435.195465) (xy 390.312383 -435.215003) (xy 390.29284 -435.229196) (xy 390.269869 -435.236657)
			(xy 390.257792 -435.237128) (xy 389.317992 -435.237128) (xy 389.305919 -435.236643) (xy 389.282955 -435.229181)
			(xy 389.26342 -435.214989) (xy 389.249225 -435.195456) (xy 389.241759 -435.172493) (xy 389.241284 -435.16042)
			(xy 388.334504 -435.16042) (xy 388.334504 -436.160418) (xy 388.334009 -436.172504) (xy 388.326553 -436.195498)
			(xy 388.312372 -436.215074) (xy 388.292847 -436.229325) (xy 388.26988 -436.236865) (xy 388.257796 -436.23738)
			(xy 387.317996 -436.23738) (xy 387.305885 -436.236987) (xy 387.282854 -436.229484) (xy 387.263279 -436.215217)
			(xy 387.249085 -436.195589) (xy 387.241668 -436.172531) (xy 387.241288 -436.160418) (xy 386.306732 -436.160418)
			(xy 386.312376 -436.164518) (xy 386.326571 -436.184053) (xy 386.334035 -436.207018) (xy 386.334508 -436.219092)
			(xy 386.334508 -438.760616) (xy 386.334049 -438.772691) (xy 386.326582 -438.795659) (xy 386.312384 -438.815196)
			(xy 386.292845 -438.82939) (xy 386.269875 -438.836852) (xy 386.2578 -438.837324) (xy 385.318 -438.837324)
			(xy 385.305927 -438.836836) (xy 385.282963 -438.829375) (xy 385.263427 -438.815184) (xy 385.249232 -438.795652)
			(xy 385.241767 -438.772689) (xy 385.241292 -438.760616) (xy 384.334512 -438.760616) (xy 384.334512 -439.760614)
			(xy 387.241288 -439.760614) (xy 387.241288 -437.21909) (xy 387.2417 -437.206995) (xy 387.249165 -437.183986)
			(xy 387.263364 -437.164402) (xy 387.282912 -437.150154) (xy 387.305902 -437.142631) (xy 387.317996 -437.142128)
			(xy 388.257796 -437.142128) (xy 388.269907 -437.14252) (xy 388.292939 -437.150022) (xy 388.312515 -437.164288)
			(xy 388.326709 -437.183917) (xy 388.334125 -437.206977) (xy 388.334504 -437.21909) (xy 388.334504 -438.760616)
			(xy 389.241284 -438.760616) (xy 389.241284 -436.219092) (xy 389.241757 -436.207018) (xy 389.249221 -436.184052)
			(xy 389.263416 -436.164516) (xy 389.282952 -436.150321) (xy 389.305918 -436.142857) (xy 389.317992 -436.142384)
			(xy 390.257792 -436.142384) (xy 390.269865 -436.142871) (xy 390.292831 -436.15033) (xy 390.306719 -436.160418)
			(xy 391.24128 -436.160418) (xy 391.24128 -433.618894) (xy 391.241703 -433.6068) (xy 391.249166 -433.583793)
			(xy 391.263363 -433.564209) (xy 391.282908 -433.549961) (xy 391.305896 -433.542436) (xy 391.317988 -433.541932)
			(xy 392.257788 -433.541932) (xy 392.269899 -433.542327) (xy 392.292932 -433.549827) (xy 392.312508 -433.564093)
			(xy 392.326702 -433.583721) (xy 392.334117 -433.606781) (xy 392.334496 -433.618894) (xy 392.334496 -435.16042)
			(xy 393.241276 -435.16042) (xy 393.241276 -432.618896) (xy 393.241761 -432.606823) (xy 393.249222 -432.583858)
			(xy 393.263414 -432.564323) (xy 393.282948 -432.550128) (xy 393.305911 -432.542663) (xy 393.317984 -432.542188)
			(xy 394.257784 -432.542188) (xy 394.269865 -432.542626) (xy 394.292847 -432.550089) (xy 394.307147 -432.560476)
			(xy 395.241272 -432.560476) (xy 395.241272 -430.018952) (xy 395.241723 -430.006877) (xy 395.249196 -429.983912)
			(xy 395.263397 -429.964377) (xy 395.282937 -429.950183) (xy 395.305905 -429.942718) (xy 395.31798 -429.942244)
			(xy 396.25778 -429.942244) (xy 396.269849 -429.94278) (xy 396.292807 -429.950232) (xy 396.31234 -429.964411)
			(xy 396.326537 -429.983932) (xy 396.334009 -430.006884) (xy 396.334488 -430.018952) (xy 396.334488 -431.560478)
			(xy 398.241012 -431.560478) (xy 398.241012 -429.018954) (xy 398.241472 -429.00684) (xy 398.248969 -428.983799)
			(xy 398.263215 -428.964201) (xy 398.282817 -428.94996) (xy 398.30586 -428.942469) (xy 398.317974 -428.941992)
			(xy 399.257774 -428.941992) (xy 399.269883 -428.942533) (xy 399.292917 -428.950008) (xy 399.307419 -428.960534)
			(xy 400.241008 -428.960534) (xy 400.241008 -426.41901) (xy 400.24152 -426.406899) (xy 400.249001 -426.383861)
			(xy 400.263233 -426.364262) (xy 400.282825 -426.350019) (xy 400.305859 -426.342526) (xy 400.31797 -426.342048)
			(xy 401.25777 -426.342048) (xy 401.269892 -426.342486) (xy 401.292952 -426.349971) (xy 401.312568 -426.364218)
			(xy 401.32682 -426.38383) (xy 401.334311 -426.406888) (xy 401.334732 -426.41901) (xy 401.334732 -427.960536)
			(xy 402.241004 -427.960536) (xy 402.241004 -425.419012) (xy 402.24147 -425.406962) (xy 402.2489 -425.384036)
			(xy 402.263039 -425.36452) (xy 402.282509 -425.350316) (xy 402.30541 -425.342811) (xy 402.317458 -425.342304)
			(xy 403.257766 -425.342304) (xy 403.26985 -425.342836) (xy 403.292844 -425.350279) (xy 403.312421 -425.36445)
			(xy 403.326674 -425.383968) (xy 403.334213 -425.40693) (xy 403.334728 -425.419012) (xy 403.334728 -427.960536)
			(xy 403.334271 -427.972585) (xy 403.326832 -427.995507) (xy 403.31269 -428.01502) (xy 403.293221 -428.029223)
			(xy 403.270322 -428.036734) (xy 403.258274 -428.037244) (xy 402.317966 -428.037244) (xy 402.305873 -428.036821)
			(xy 402.282869 -428.029353) (xy 402.263288 -428.015156) (xy 402.249039 -427.995612) (xy 402.241511 -427.972628)
			(xy 402.241004 -427.960536) (xy 401.334732 -427.960536) (xy 401.334732 -428.960534) (xy 401.334317 -428.972653)
			(xy 401.326817 -428.995703) (xy 401.312561 -429.015307) (xy 401.292945 -429.029546) (xy 401.26989 -429.037027)
			(xy 401.25777 -429.037496) (xy 400.31797 -429.037496) (xy 400.305857 -429.037014) (xy 400.282819 -429.029523)
			(xy 400.26322 -429.015282) (xy 400.248979 -428.995685) (xy 400.241486 -428.972647) (xy 400.241008 -428.960534)
			(xy 399.307419 -428.960534) (xy 399.312515 -428.964233) (xy 399.326759 -428.983818) (xy 399.334255 -429.006846)
			(xy 399.334736 -429.018954) (xy 399.334736 -431.560478) (xy 399.334321 -431.572602) (xy 399.326832 -431.595665)
			(xy 399.31258 -431.615282) (xy 399.292961 -431.629533) (xy 399.269898 -431.637022) (xy 399.257774 -431.63744)
			(xy 398.317974 -431.63744) (xy 398.305856 -431.63701) (xy 398.282808 -431.629513) (xy 398.263205 -431.615261)
			(xy 398.248965 -431.595649) (xy 398.241482 -431.572596) (xy 398.241012 -431.560478) (xy 396.334488 -431.560478)
			(xy 396.334488 -432.560476) (xy 396.334066 -432.572559) (xy 396.326603 -432.595545) (xy 396.3124 -432.615097)
			(xy 396.292848 -432.629301) (xy 396.269863 -432.636766) (xy 396.25778 -432.637184) (xy 395.31798 -432.637184)
			(xy 395.305894 -432.636804) (xy 395.282906 -432.629328) (xy 395.263354 -432.615114) (xy 395.249152 -432.595554)
			(xy 395.241689 -432.572562) (xy 395.241272 -432.560476) (xy 394.307147 -432.560476) (xy 394.312397 -432.564289)
			(xy 394.326602 -432.583835) (xy 394.33407 -432.606815) (xy 394.334492 -432.618896) (xy 394.334492 -435.16042)
			(xy 394.334052 -435.172497) (xy 394.326582 -435.195468) (xy 394.31238 -435.215006) (xy 394.292835 -435.229199)
			(xy 394.269861 -435.236658) (xy 394.257784 -435.237128) (xy 393.317984 -435.237128) (xy 393.305911 -435.23665)
			(xy 393.282946 -435.229185) (xy 393.263411 -435.214991) (xy 393.249217 -435.195457) (xy 393.241751 -435.172493)
			(xy 393.241276 -435.16042) (xy 392.334496 -435.16042) (xy 392.334496 -436.160418) (xy 392.334009 -436.172505)
			(xy 392.326552 -436.1955) (xy 392.312369 -436.215077) (xy 392.292842 -436.229328) (xy 392.269873 -436.236866)
			(xy 392.257788 -436.23738) (xy 391.317988 -436.23738) (xy 391.305876 -436.236994) (xy 391.282845 -436.229489)
			(xy 391.263271 -436.21522) (xy 391.249077 -436.195591) (xy 391.24166 -436.172531) (xy 391.24128 -436.160418)
			(xy 390.306719 -436.160418) (xy 390.312367 -436.164521) (xy 390.326562 -436.184055) (xy 390.334027 -436.207019)
			(xy 390.3345 -436.219092) (xy 390.3345 -438.760616) (xy 390.334049 -438.772692) (xy 390.326581 -438.795661)
			(xy 390.312382 -438.815199) (xy 390.29284 -438.829392) (xy 390.269868 -438.836853) (xy 390.257792 -438.837324)
			(xy 389.317992 -438.837324) (xy 389.305919 -438.836843) (xy 389.282954 -438.82938) (xy 389.263418 -438.815187)
			(xy 389.249224 -438.795653) (xy 389.241759 -438.772689) (xy 389.241284 -438.760616) (xy 388.334504 -438.760616)
			(xy 388.334504 -439.760614) (xy 391.24128 -439.760614) (xy 391.24128 -437.21909) (xy 391.2417 -437.206996)
			(xy 391.249164 -437.183988) (xy 391.263361 -437.164405) (xy 391.282907 -437.150156) (xy 391.305895 -437.142632)
			(xy 391.317988 -437.142128) (xy 392.257788 -437.142128) (xy 392.269899 -437.142527) (xy 392.292931 -437.150027)
			(xy 392.312506 -437.164292) (xy 392.3267 -437.183919) (xy 392.334116 -437.206978) (xy 392.334496 -437.21909)
			(xy 392.334496 -438.760616) (xy 393.241276 -438.760616) (xy 393.241276 -436.219092) (xy 393.241757 -436.207019)
			(xy 393.24922 -436.184054) (xy 393.263413 -436.164518) (xy 393.282947 -436.150324) (xy 393.305911 -436.142859)
			(xy 393.317984 -436.142384) (xy 394.257784 -436.142384) (xy 394.269865 -436.142826) (xy 394.292846 -436.150288)
			(xy 394.306794 -436.160418) (xy 395.241272 -436.160418) (xy 395.241272 -433.618894) (xy 395.241703 -433.606801)
			(xy 395.249165 -433.583795) (xy 395.26336 -433.564212) (xy 395.282903 -433.549963) (xy 395.305888 -433.542437)
			(xy 395.31798 -433.541932) (xy 396.25778 -433.541932) (xy 396.269891 -433.542334) (xy 396.292923 -433.549832)
			(xy 396.312499 -433.564096) (xy 396.326693 -433.583723) (xy 396.334109 -433.606782) (xy 396.334488 -433.618894)
			(xy 396.334488 -435.16042) (xy 398.241012 -435.16042) (xy 398.241012 -432.618896) (xy 398.241457 -432.606844)
			(xy 398.248892 -432.583917) (xy 398.263036 -432.5644) (xy 398.282511 -432.550197) (xy 398.305416 -432.542693)
			(xy 398.317466 -432.542188) (xy 399.257774 -432.542188) (xy 399.269867 -432.54263) (xy 399.292875 -432.550086)
			(xy 399.307214 -432.560476) (xy 400.241008 -432.560476) (xy 400.241008 -430.018952) (xy 400.241419 -430.006898)
			(xy 400.248866 -429.98397) (xy 400.263019 -429.964454) (xy 400.2825 -429.950253) (xy 400.30541 -429.942749)
			(xy 400.317462 -429.942244) (xy 401.25777 -429.942244) (xy 401.269858 -429.942733) (xy 401.292859 -429.950182)
			(xy 401.312439 -429.964363) (xy 401.326691 -429.983892) (xy 401.334223 -430.006865) (xy 401.334732 -430.018952)
			(xy 401.334732 -431.560478) (xy 402.241004 -431.560478) (xy 402.241004 -429.018954) (xy 402.241472 -429.00684)
			(xy 402.248968 -428.983801) (xy 402.263212 -428.964203) (xy 402.282812 -428.949962) (xy 402.305852 -428.94247)
			(xy 402.317966 -428.941992) (xy 403.257766 -428.941992) (xy 403.269874 -428.94254) (xy 403.292909 -428.950012)
			(xy 403.307406 -428.960534) (xy 404.241 -428.960534) (xy 404.241 -426.41901) (xy 404.24152 -426.4069)
			(xy 404.249 -426.383863) (xy 404.263231 -426.364265) (xy 404.28282 -426.350022) (xy 404.305852 -426.342527)
			(xy 404.317962 -426.342048) (xy 405.257762 -426.342048) (xy 405.269884 -426.342492) (xy 405.292943 -426.349975)
			(xy 405.31256 -426.36422) (xy 405.326812 -426.383832) (xy 405.334303 -426.406888) (xy 405.334724 -426.41901)
			(xy 405.334724 -427.960536) (xy 406.240996 -427.960536) (xy 406.240996 -425.419012) (xy 406.24147 -425.406963)
			(xy 406.248899 -425.384038) (xy 406.263036 -425.364523) (xy 406.282504 -425.350319) (xy 406.305403 -425.342812)
			(xy 406.31745 -425.342304) (xy 407.257758 -425.342304) (xy 407.269842 -425.342842) (xy 407.292835 -425.350283)
			(xy 407.312413 -425.364453) (xy 407.326666 -425.383969) (xy 407.334205 -425.40693) (xy 407.33472 -425.419012)
			(xy 407.33472 -427.960536) (xy 407.334271 -427.972586) (xy 407.326831 -427.99551) (xy 407.312687 -428.015023)
			(xy 407.293216 -428.029226) (xy 407.270315 -428.036735) (xy 407.258266 -428.037244) (xy 406.317958 -428.037244)
			(xy 406.305865 -428.036828) (xy 406.28286 -428.029358) (xy 406.263279 -428.015159) (xy 406.249031 -427.995614)
			(xy 406.241503 -427.972628) (xy 406.240996 -427.960536) (xy 405.334724 -427.960536) (xy 405.334724 -428.960534)
			(xy 405.334369 -428.972662) (xy 405.326862 -428.995729) (xy 405.312595 -429.015347) (xy 405.292964 -429.029595)
			(xy 405.269891 -429.03708) (xy 405.257762 -429.037496) (xy 404.317962 -429.037496) (xy 404.305849 -429.037021)
			(xy 404.28281 -429.029528) (xy 404.263212 -429.015285) (xy 404.24897 -428.995686) (xy 404.241478 -428.972647)
			(xy 404.241 -428.960534) (xy 403.307406 -428.960534) (xy 403.312507 -428.964236) (xy 403.326751 -428.98382)
			(xy 403.334247 -429.006846) (xy 403.334728 -429.018954) (xy 403.334728 -431.560478) (xy 403.334321 -431.572603)
			(xy 403.32683 -431.595667) (xy 403.312577 -431.615285) (xy 403.292956 -431.629536) (xy 403.269891 -431.637023)
			(xy 403.257766 -431.63744) (xy 402.317966 -431.63744) (xy 402.305847 -431.637017) (xy 402.282799 -431.629518)
			(xy 402.263196 -431.615264) (xy 402.248957 -431.59565) (xy 402.241474 -431.572597) (xy 402.241004 -431.560478)
			(xy 401.334732 -431.560478) (xy 401.334732 -432.560476) (xy 401.33422 -432.572522) (xy 401.326798 -432.595441)
			(xy 401.312669 -432.614955) (xy 401.293212 -432.62916) (xy 401.270322 -432.636672) (xy 401.258278 -432.637184)
			(xy 400.31797 -432.637184) (xy 400.305881 -432.636719) (xy 400.282884 -432.629257) (xy 400.263306 -432.615069)
			(xy 400.249056 -432.595537) (xy 400.24152 -432.572563) (xy 400.241008 -432.560476) (xy 399.307214 -432.560476)
			(xy 399.312459 -432.564277) (xy 399.326709 -432.583819) (xy 399.334233 -432.606804) (xy 399.334736 -432.618896)
			(xy 399.334736 -435.16042) (xy 399.334258 -435.172468) (xy 399.326824 -435.195388) (xy 399.312686 -435.2149)
			(xy 399.293223 -435.229104) (xy 399.270328 -435.236616) (xy 399.258282 -435.237128) (xy 398.317974 -435.237128)
			(xy 398.30588 -435.236714) (xy 398.282873 -435.229247) (xy 398.263291 -435.215047) (xy 398.249042 -435.195501)
			(xy 398.241516 -435.172513) (xy 398.241012 -435.16042) (xy 396.334488 -435.16042) (xy 396.334488 -436.160418)
			(xy 396.334009 -436.172506) (xy 396.32655 -436.195502) (xy 396.312366 -436.21508) (xy 396.292837 -436.229331)
			(xy 396.269866 -436.236867) (xy 396.25778 -436.23738) (xy 395.31798 -436.23738) (xy 395.305868 -436.237001)
			(xy 395.282837 -436.229493) (xy 395.263262 -436.215223) (xy 395.249069 -436.195592) (xy 395.241652 -436.172532)
			(xy 395.241272 -436.160418) (xy 394.306794 -436.160418) (xy 394.312396 -436.164487) (xy 394.326601 -436.184033)
			(xy 394.33407 -436.207011) (xy 394.334492 -436.219092) (xy 394.334492 -438.760616) (xy 394.334049 -438.772693)
			(xy 394.32658 -438.795663) (xy 394.312379 -438.815201) (xy 394.292835 -438.829395) (xy 394.269861 -438.836854)
			(xy 394.257784 -438.837324) (xy 393.317984 -438.837324) (xy 393.30591 -438.83685) (xy 393.282945 -438.829385)
			(xy 393.26341 -438.81519) (xy 393.249215 -438.795655) (xy 393.24175 -438.77269) (xy 393.241276 -438.760616)
			(xy 392.334496 -438.760616) (xy 392.334496 -439.760614) (xy 395.241272 -439.760614) (xy 395.241272 -437.21909)
			(xy 395.2417 -437.206997) (xy 395.249163 -437.183991) (xy 395.263359 -437.164408) (xy 395.282902 -437.150159)
			(xy 395.305888 -437.142633) (xy 395.31798 -437.142128) (xy 396.25778 -437.142128) (xy 396.269891 -437.142534)
			(xy 396.292922 -437.150031) (xy 396.312498 -437.164294) (xy 396.326692 -437.18392) (xy 396.334108 -437.206978)
			(xy 396.334488 -437.21909) (xy 396.334488 -438.760616) (xy 398.241012 -438.760616) (xy 398.241012 -436.219092)
			(xy 398.241453 -436.20704) (xy 398.24889 -436.184112) (xy 398.263035 -436.164596) (xy 398.28251 -436.150393)
			(xy 398.305416 -436.142889) (xy 398.317466 -436.142384) (xy 399.257774 -436.142384) (xy 399.269867 -436.14283)
			(xy 399.292874 -436.150285) (xy 399.306858 -436.160418) (xy 400.241008 -436.160418) (xy 400.241008 -433.618894)
			(xy 400.241506 -433.606782) (xy 400.248992 -433.583744) (xy 400.263228 -433.564145) (xy 400.282822 -433.549903)
			(xy 400.305858 -433.54241) (xy 400.31797 -433.541932) (xy 401.25777 -433.541932) (xy 401.269891 -433.542385)
			(xy 401.292947 -433.549869) (xy 401.312563 -433.564112) (xy 401.326815 -433.58372) (xy 401.334309 -433.606774)
			(xy 401.334732 -433.618894) (xy 401.334732 -435.16042) (xy 402.241004 -435.16042) (xy 402.241004 -432.618896)
			(xy 402.241457 -432.606845) (xy 402.248891 -432.583919) (xy 402.263034 -432.564403) (xy 402.282506 -432.5502)
			(xy 402.305409 -432.542694) (xy 402.317458 -432.542188) (xy 403.257766 -432.542188) (xy 403.269859 -432.542637)
			(xy 403.292866 -432.55009) (xy 403.307201 -432.560476) (xy 404.241 -432.560476) (xy 404.241 -430.018952)
			(xy 404.241419 -430.006899) (xy 404.248865 -429.983972) (xy 404.263016 -429.964457) (xy 404.282495 -429.950255)
			(xy 404.305403 -429.94275) (xy 404.317454 -429.942244) (xy 405.257762 -429.942244) (xy 405.26985 -429.94274)
			(xy 405.29285 -429.950187) (xy 405.312431 -429.964366) (xy 405.326683 -429.983894) (xy 405.334215 -430.006866)
			(xy 405.334724 -430.018952) (xy 405.334724 -431.560478) (xy 406.240996 -431.560478) (xy 406.240996 -429.018954)
			(xy 406.241472 -429.006841) (xy 406.248967 -428.983804) (xy 406.263209 -428.964206) (xy 406.282807 -428.949965)
			(xy 406.305845 -428.942471) (xy 406.317958 -428.941992) (xy 407.257758 -428.941992) (xy 407.269866 -428.942547)
			(xy 407.2929 -428.950017) (xy 407.307392 -428.960534) (xy 408.240992 -428.960534) (xy 408.240992 -426.41901)
			(xy 408.24152 -426.406901) (xy 408.248999 -426.383865) (xy 408.263228 -426.364268) (xy 408.282815 -426.350024)
			(xy 408.305845 -426.342528) (xy 408.317954 -426.342048) (xy 409.257754 -426.342048) (xy 409.269875 -426.342499)
			(xy 409.292934 -426.34998) (xy 409.312551 -426.364223) (xy 409.326804 -426.383833) (xy 409.334295 -426.406889)
			(xy 409.334716 -426.41901) (xy 409.334716 -427.960536) (xy 410.240988 -427.960536) (xy 410.240988 -425.419012)
			(xy 410.24147 -425.406964) (xy 410.248898 -425.38404) (xy 410.263033 -425.364526) (xy 410.282498 -425.350321)
			(xy 410.305395 -425.342813) (xy 410.317442 -425.342304) (xy 411.25775 -425.342304) (xy 411.269833 -425.342849)
			(xy 411.292826 -425.350288) (xy 411.312404 -425.364455) (xy 411.326658 -425.383971) (xy 411.334197 -425.406931)
			(xy 411.334712 -425.419012) (xy 411.334712 -427.960536) (xy 411.334271 -427.972587) (xy 411.32683 -427.995512)
			(xy 411.312684 -428.015026) (xy 411.293211 -428.029228) (xy 411.270307 -428.036736) (xy 411.258258 -428.037244)
			(xy 410.31795 -428.037244) (xy 410.305861 -428.03675) (xy 410.28286 -428.029305) (xy 410.263278 -428.015126)
			(xy 410.249026 -427.995597) (xy 410.241495 -427.972623) (xy 410.240988 -427.960536) (xy 409.334716 -427.960536)
			(xy 409.334716 -428.960534) (xy 409.334368 -428.972663) (xy 409.326861 -428.995731) (xy 409.312592 -429.015349)
			(xy 409.292959 -429.029598) (xy 409.269884 -429.037081) (xy 409.257754 -429.037496) (xy 408.317954 -429.037496)
			(xy 408.30584 -429.037028) (xy 408.282801 -429.029532) (xy 408.263203 -429.015288) (xy 408.248962 -428.995688)
			(xy 408.24147 -428.972648) (xy 408.240992 -428.960534) (xy 407.307392 -428.960534) (xy 407.312498 -428.964239)
			(xy 407.326743 -428.983821) (xy 407.334239 -429.006847) (xy 407.33472 -429.018954) (xy 407.33472 -431.560478)
			(xy 407.334321 -431.572604) (xy 407.326829 -431.595669) (xy 407.312574 -431.615288) (xy 407.292951 -431.629538)
			(xy 407.269884 -431.637024) (xy 407.257758 -431.63744) (xy 406.317958 -431.63744) (xy 406.305839 -431.637024)
			(xy 406.282791 -431.629522) (xy 406.263188 -431.615267) (xy 406.248948 -431.595652) (xy 406.241466 -431.572597)
			(xy 406.240996 -431.560478) (xy 405.334724 -431.560478) (xy 405.334724 -432.560476) (xy 405.33422 -432.572523)
			(xy 405.326797 -432.595443) (xy 405.312667 -432.614957) (xy 405.293207 -432.629162) (xy 405.270315 -432.636673)
			(xy 405.25827 -432.637184) (xy 404.317962 -432.637184) (xy 404.305873 -432.636726) (xy 404.282875 -432.629261)
			(xy 404.263298 -432.615072) (xy 404.249048 -432.595538) (xy 404.241512 -432.572564) (xy 404.241 -432.560476)
			(xy 403.307201 -432.560476) (xy 403.312451 -432.56428) (xy 403.326701 -432.583821) (xy 403.334225 -432.606805)
			(xy 403.334728 -432.618896) (xy 403.334728 -435.16042) (xy 403.334257 -435.172468) (xy 403.326823 -435.19539)
			(xy 403.312684 -435.214903) (xy 403.293217 -435.229106) (xy 403.270321 -435.236617) (xy 403.258274 -435.237128)
			(xy 402.317966 -435.237128) (xy 402.305871 -435.236721) (xy 402.282864 -435.229251) (xy 402.263282 -435.21505)
			(xy 402.249034 -435.195502) (xy 402.241508 -435.172513) (xy 402.241004 -435.16042) (xy 401.334732 -435.16042)
			(xy 401.334732 -436.160418) (xy 401.334355 -436.172545) (xy 401.326854 -436.195609) (xy 401.312592 -436.215226)
			(xy 401.292966 -436.229476) (xy 401.269897 -436.236962) (xy 401.25777 -436.23738) (xy 400.31797 -436.23738)
			(xy 400.305856 -436.236914) (xy 400.282814 -436.229421) (xy 400.263215 -436.215177) (xy 400.248974 -436.195575)
			(xy 400.241484 -436.172532) (xy 400.241008 -436.160418) (xy 399.306858 -436.160418) (xy 399.312458 -436.164476)
			(xy 399.326708 -436.184017) (xy 399.334233 -436.207001) (xy 399.334736 -436.219092) (xy 399.334736 -438.760616)
			(xy 399.334254 -438.772663) (xy 399.326821 -438.795583) (xy 399.312685 -438.815096) (xy 399.293222 -438.8293)
			(xy 399.270328 -438.836812) (xy 399.258282 -438.837324) (xy 398.317974 -438.837324) (xy 398.305879 -438.836914)
			(xy 398.282872 -438.829446) (xy 398.263289 -438.815246) (xy 398.249041 -438.795698) (xy 398.241516 -438.772709)
			(xy 398.241012 -438.760616) (xy 396.334488 -438.760616) (xy 396.334488 -439.760614) (xy 400.241008 -439.760614)
			(xy 400.241008 -437.21909) (xy 400.241503 -437.206978) (xy 400.248989 -437.18394) (xy 400.263226 -437.164341)
			(xy 400.282822 -437.150098) (xy 400.305858 -437.142606) (xy 400.31797 -437.142128) (xy 401.25777 -437.142128)
			(xy 401.26989 -437.142585) (xy 401.292946 -437.150068) (xy 401.312561 -437.16431) (xy 401.326814 -437.183918)
			(xy 401.334308 -437.20697) (xy 401.334732 -437.21909) (xy 401.334732 -438.760616) (xy 402.241004 -438.760616)
			(xy 402.241004 -436.219092) (xy 402.241453 -436.207041) (xy 402.248889 -436.184115) (xy 402.263032 -436.164599)
			(xy 402.282505 -436.150396) (xy 402.305409 -436.14289) (xy 402.317458 -436.142384) (xy 403.257766 -436.142384)
			(xy 403.269858 -436.142837) (xy 403.292865 -436.15029) (xy 403.306845 -436.160418) (xy 404.241 -436.160418)
			(xy 404.241 -433.618894) (xy 404.241506 -433.606783) (xy 404.24899 -433.583746) (xy 404.263225 -433.564148)
			(xy 404.282817 -433.549905) (xy 404.305851 -433.542411) (xy 404.317962 -433.541932) (xy 405.257762 -433.541932)
			(xy 405.269882 -433.542392) (xy 405.292939 -433.549873) (xy 405.312554 -433.564115) (xy 405.326807 -433.583722)
			(xy 405.334301 -433.606774) (xy 405.334724 -433.618894) (xy 405.334724 -435.16042) (xy 406.240996 -435.16042)
			(xy 406.240996 -432.618896) (xy 406.241457 -432.606846) (xy 406.24889 -432.583921) (xy 406.263031 -432.564406)
			(xy 406.282501 -432.550202) (xy 406.305402 -432.542696) (xy 406.31745 -432.542188) (xy 407.257758 -432.542188)
			(xy 407.26985 -432.542644) (xy 407.292858 -432.550095) (xy 407.307187 -432.560476) (xy 408.240992 -432.560476)
			(xy 408.240992 -430.018952) (xy 408.241419 -430.0069) (xy 408.248864 -429.983974) (xy 408.263013 -429.96446)
			(xy 408.28249 -429.950258) (xy 408.305395 -429.942752) (xy 408.317446 -429.942244) (xy 409.257754 -429.942244)
			(xy 409.269842 -429.942747) (xy 409.292841 -429.950191) (xy 409.312422 -429.964368) (xy 409.326674 -429.983895)
			(xy 409.334207 -430.006866) (xy 409.334716 -430.018952) (xy 409.334716 -431.560478) (xy 410.240988 -431.560478)
			(xy 410.240988 -429.018954) (xy 410.241472 -429.006842) (xy 410.248966 -428.983806) (xy 410.263206 -428.964209)
			(xy 410.282802 -428.949967) (xy 410.305838 -428.942472) (xy 410.31795 -428.941992) (xy 411.25775 -428.941992)
			(xy 411.269863 -428.942468) (xy 411.2929 -428.949964) (xy 411.307444 -428.960534) (xy 412.240984 -428.960534)
			(xy 412.240984 -426.41901) (xy 412.241369 -426.406883) (xy 412.248864 -426.383817) (xy 412.263123 -426.364198)
			(xy 412.282749 -426.349948) (xy 412.305819 -426.342464) (xy 412.317946 -426.342048) (xy 413.257746 -426.342048)
			(xy 413.269864 -426.342473) (xy 413.29291 -426.349974) (xy 413.312512 -426.364228) (xy 413.326752 -426.38384)
			(xy 413.334236 -426.406892) (xy 413.334708 -426.41901) (xy 413.334708 -428.960534) (xy 413.334218 -428.972646)
			(xy 413.326727 -428.995682) (xy 413.312488 -429.01528) (xy 413.292893 -429.029522) (xy 413.269858 -429.037016)
			(xy 413.257746 -429.037496) (xy 412.317946 -429.037496) (xy 412.305829 -429.037002) (xy 412.282777 -429.029526)
			(xy 412.263164 -429.015292) (xy 412.248911 -428.995694) (xy 412.241411 -428.972651) (xy 412.240984 -428.960534)
			(xy 411.307444 -428.960534) (xy 411.312497 -428.964206) (xy 411.326738 -428.983804) (xy 411.334232 -429.006841)
			(xy 411.334712 -429.018954) (xy 411.334712 -431.560478) (xy 411.33417 -431.572586) (xy 411.326695 -431.59562)
			(xy 411.312469 -431.615218) (xy 411.292885 -431.629462) (xy 411.269858 -431.636959) (xy 411.25775 -431.63744)
			(xy 410.31795 -431.63744) (xy 410.305831 -431.63703) (xy 410.282782 -431.629527) (xy 410.263179 -431.615269)
			(xy 410.24894 -431.595653) (xy 410.241458 -431.572598) (xy 410.240988 -431.560478) (xy 409.334716 -431.560478)
			(xy 409.334716 -432.560476) (xy 409.33422 -432.572523) (xy 409.326796 -432.595445) (xy 409.312664 -432.61496)
			(xy 409.293202 -432.629165) (xy 409.270308 -432.636675) (xy 409.258262 -432.637184) (xy 408.317954 -432.637184)
			(xy 408.305864 -432.636732) (xy 408.282866 -432.629266) (xy 408.263289 -432.615074) (xy 408.249039 -432.59554)
			(xy 408.241504 -432.572564) (xy 408.240992 -432.560476) (xy 407.307187 -432.560476) (xy 407.312442 -432.564283)
			(xy 407.326693 -432.583822) (xy 407.334217 -432.606805) (xy 407.33472 -432.618896) (xy 407.33472 -435.16042)
			(xy 407.334257 -435.172469) (xy 407.326821 -435.195392) (xy 407.312681 -435.214906) (xy 407.293212 -435.229109)
			(xy 407.270314 -435.236618) (xy 407.258266 -435.237128) (xy 406.317958 -435.237128) (xy 406.305863 -435.236728)
			(xy 406.282856 -435.229256) (xy 406.263274 -435.215053) (xy 406.249026 -435.195504) (xy 406.2415 -435.172514)
			(xy 406.240996 -435.16042) (xy 405.334724 -435.16042) (xy 405.334724 -436.160418) (xy 405.334355 -436.172545)
			(xy 405.326853 -436.195611) (xy 405.312589 -436.215229) (xy 405.292961 -436.229478) (xy 405.26989 -436.236963)
			(xy 405.257762 -436.23738) (xy 404.317962 -436.23738) (xy 404.305847 -436.236921) (xy 404.282806 -436.229425)
			(xy 404.263206 -436.21518) (xy 404.248965 -436.195576) (xy 404.241476 -436.172533) (xy 404.241 -436.160418)
			(xy 403.306845 -436.160418) (xy 403.312449 -436.164478) (xy 403.3267 -436.184018) (xy 403.334225 -436.207001)
			(xy 403.334728 -436.219092) (xy 403.334728 -438.760616) (xy 403.334254 -438.772664) (xy 403.32682 -438.795586)
			(xy 403.312682 -438.815099) (xy 403.293217 -438.829302) (xy 403.270321 -438.836813) (xy 403.258274 -438.837324)
			(xy 402.317966 -438.837324) (xy 402.305871 -438.836921) (xy 402.282863 -438.829451) (xy 402.263281 -438.815249)
			(xy 402.249033 -438.7957) (xy 402.241508 -438.77271) (xy 402.241004 -438.760616) (xy 401.334732 -438.760616)
			(xy 401.334732 -439.760614) (xy 404.241 -439.760614) (xy 404.241 -437.21909) (xy 404.241503 -437.206979)
			(xy 404.248988 -437.183942) (xy 404.263224 -437.164343) (xy 404.282817 -437.150101) (xy 404.305851 -437.142607)
			(xy 404.317962 -437.142128) (xy 405.257762 -437.142128) (xy 405.269882 -437.142592) (xy 405.292938 -437.150073)
			(xy 405.312553 -437.164313) (xy 405.326805 -437.183919) (xy 405.3343 -437.20697) (xy 405.334724 -437.21909)
			(xy 405.334724 -438.760616) (xy 406.240996 -438.760616) (xy 406.240996 -436.219092) (xy 406.241453 -436.207042)
			(xy 406.248888 -436.184117) (xy 406.263029 -436.164601) (xy 406.2825 -436.150398) (xy 406.305401 -436.142892)
			(xy 406.31745 -436.142384) (xy 407.257758 -436.142384) (xy 407.26985 -436.142844) (xy 407.292856 -436.150294)
			(xy 407.306832 -436.160418) (xy 408.240992 -436.160418) (xy 408.240992 -433.618894) (xy 408.241506 -433.606784)
			(xy 408.248989 -433.583748) (xy 408.263222 -433.564151) (xy 408.282812 -433.549908) (xy 408.305844 -433.542412)
			(xy 408.317954 -433.541932) (xy 409.257754 -433.541932) (xy 409.269874 -433.542399) (xy 409.29293 -433.549878)
			(xy 409.312546 -433.564117) (xy 409.326798 -433.583723) (xy 409.334293 -433.606775) (xy 409.334716 -433.618894)
			(xy 409.334716 -435.16042) (xy 410.240988 -435.16042) (xy 410.240988 -432.618896) (xy 410.241456 -432.606847)
			(xy 410.248889 -432.583923) (xy 410.263028 -432.564409) (xy 410.282496 -432.550205) (xy 410.305394 -432.542697)
			(xy 410.317442 -432.542188) (xy 411.25775 -432.542188) (xy 411.269842 -432.542651) (xy 411.292849 -432.5501)
			(xy 411.307175 -432.560476) (xy 412.240984 -432.560476) (xy 412.240984 -430.018952) (xy 412.241419 -430.006901)
			(xy 412.248863 -429.983976) (xy 412.263011 -429.964463) (xy 412.282485 -429.950261) (xy 412.305388 -429.942753)
			(xy 412.317438 -429.942244) (xy 413.257746 -429.942244) (xy 413.269838 -429.942668) (xy 413.292841 -429.950138)
			(xy 413.312421 -429.964336) (xy 413.32667 -429.983878) (xy 413.3342 -430.006861) (xy 413.334708 -430.018952)
			(xy 413.334708 -432.560476) (xy 413.33422 -432.572524) (xy 413.326795 -432.595448) (xy 413.312661 -432.614963)
			(xy 413.293197 -432.629168) (xy 413.2703 -432.636676) (xy 413.258254 -432.637184) (xy 412.317946 -432.637184)
			(xy 412.305861 -432.636654) (xy 412.282866 -432.629213) (xy 412.263287 -432.615042) (xy 412.249034 -432.595522)
			(xy 412.241497 -432.572559) (xy 412.240984 -432.560476) (xy 411.307175 -432.560476) (xy 411.312434 -432.564285)
			(xy 411.326684 -432.583823) (xy 411.334209 -432.606806) (xy 411.334712 -432.618896) (xy 411.334712 -435.16042)
			(xy 411.334257 -435.17247) (xy 411.32682 -435.195394) (xy 411.312678 -435.214908) (xy 411.293207 -435.229111)
			(xy 411.270306 -435.236619) (xy 411.258258 -435.237128) (xy 410.31795 -435.237128) (xy 410.30586 -435.23665)
			(xy 410.282855 -435.229203) (xy 410.263272 -435.21502) (xy 410.249021 -435.195487) (xy 410.241493 -435.172508)
			(xy 410.240988 -435.16042) (xy 409.334716 -435.16042) (xy 409.334716 -436.160418) (xy 409.334354 -436.172546)
			(xy 409.326852 -436.195613) (xy 409.312586 -436.215232) (xy 409.292956 -436.229481) (xy 409.269883 -436.236965)
			(xy 409.257754 -436.23738) (xy 408.317954 -436.23738) (xy 408.305839 -436.236928) (xy 408.282797 -436.22943)
			(xy 408.263198 -436.215182) (xy 408.248957 -436.195578) (xy 408.241468 -436.172533) (xy 408.240992 -436.160418)
			(xy 407.306832 -436.160418) (xy 407.312441 -436.164481) (xy 407.326691 -436.184019) (xy 407.334216 -436.207002)
			(xy 407.33472 -436.219092) (xy 407.33472 -438.760616) (xy 407.334254 -438.772665) (xy 407.326819 -438.795588)
			(xy 407.312679 -438.815101) (xy 407.293212 -438.829305) (xy 407.270313 -438.836814) (xy 407.258266 -438.837324)
			(xy 406.317958 -438.837324) (xy 406.305863 -438.836928) (xy 406.282855 -438.829455) (xy 406.263272 -438.815252)
			(xy 406.249024 -438.795701) (xy 406.2415 -438.77271) (xy 406.240996 -438.760616) (xy 405.334724 -438.760616)
			(xy 405.334724 -439.760614) (xy 408.240992 -439.760614) (xy 408.240992 -437.21909) (xy 408.241503 -437.20698)
			(xy 408.248987 -437.183944) (xy 408.263221 -437.164346) (xy 408.282812 -437.150104) (xy 408.305844 -437.142608)
			(xy 408.317954 -437.142128) (xy 409.257754 -437.142128) (xy 409.269873 -437.142599) (xy 409.292929 -437.150077)
			(xy 409.312544 -437.164316) (xy 409.326797 -437.183921) (xy 409.334292 -437.206971) (xy 409.334716 -437.21909)
			(xy 409.334716 -438.760616) (xy 410.240988 -438.760616) (xy 410.240988 -436.219092) (xy 410.241453 -436.207043)
			(xy 410.248886 -436.184119) (xy 410.263026 -436.164604) (xy 410.282495 -436.150401) (xy 410.305394 -436.142893)
			(xy 410.317442 -436.142384) (xy 411.25775 -436.142384) (xy 411.269841 -436.142851) (xy 411.292848 -436.150299)
			(xy 411.306818 -436.160418) (xy 412.240984 -436.160418) (xy 412.240984 -433.618894) (xy 412.241356 -433.606766)
			(xy 412.248855 -433.5837) (xy 412.263118 -433.564081) (xy 412.282746 -433.549831) (xy 412.305818 -433.542348)
			(xy 412.317946 -433.541932) (xy 413.257746 -433.541932) (xy 413.269862 -433.542372) (xy 413.292906 -433.549872)
			(xy 413.312507 -433.564122) (xy 413.326747 -433.58373) (xy 413.334234 -433.606777) (xy 413.334708 -433.618894)
			(xy 413.334708 -435.679338) (xy 445.662808 -435.679338) (xy 445.662808 -435.520342) (xy 445.670861 -435.361549)
			(xy 445.686946 -435.203369) (xy 445.711023 -435.046206) (xy 445.743028 -434.890464) (xy 445.782881 -434.736543)
			(xy 445.830479 -434.584838) (xy 445.885699 -434.435739) (xy 445.9484 -434.289628) (xy 446.018422 -434.14688)
			(xy 446.095583 -434.007862) (xy 446.179686 -433.87293) (xy 446.270516 -433.742432) (xy 446.367839 -433.616701)
			(xy 446.471405 -433.496061) (xy 446.580948 -433.380822) (xy 446.696187 -433.271279) (xy 446.816827 -433.167713)
			(xy 446.942558 -433.07039) (xy 447.073056 -432.97956) (xy 447.207988 -432.895457) (xy 447.347006 -432.818296)
			(xy 447.489754 -432.748274) (xy 447.635865 -432.685573) (xy 447.784964 -432.630353) (xy 447.936669 -432.582755)
			(xy 448.09059 -432.542902) (xy 448.246332 -432.510897) (xy 448.403495 -432.48682) (xy 448.561675 -432.470735)
			(xy 448.720468 -432.462682) (xy 448.879464 -432.462682) (xy 449.038257 -432.470735) (xy 449.196437 -432.48682)
			(xy 449.3536 -432.510897) (xy 449.509342 -432.542902) (xy 449.663263 -432.582755) (xy 449.814968 -432.630353)
			(xy 449.964067 -432.685573) (xy 450.110178 -432.748274) (xy 450.252926 -432.818296) (xy 450.391944 -432.895457)
			(xy 450.526876 -432.97956) (xy 450.657374 -433.07039) (xy 450.783105 -433.167713) (xy 450.903745 -433.271279)
			(xy 451.018984 -433.380822) (xy 451.128527 -433.496061) (xy 451.232093 -433.616701) (xy 451.329416 -433.742432)
			(xy 451.420246 -433.87293) (xy 451.504349 -434.007862) (xy 451.58151 -434.14688) (xy 451.651532 -434.289628)
			(xy 451.714233 -434.435739) (xy 451.769453 -434.584838) (xy 451.817051 -434.736543) (xy 451.856904 -434.890464)
			(xy 451.888909 -435.046206) (xy 451.912986 -435.203369) (xy 451.929071 -435.361549) (xy 451.937124 -435.520342)
			(xy 451.937628 -435.59984) (xy 451.937124 -435.679338) (xy 451.929071 -435.838131) (xy 451.912986 -435.996311)
			(xy 451.888909 -436.153474) (xy 451.856904 -436.309216) (xy 451.817051 -436.463137) (xy 451.769453 -436.614842)
			(xy 451.714233 -436.763941) (xy 451.651532 -436.910052) (xy 451.58151 -437.0528) (xy 451.504349 -437.191818)
			(xy 451.420246 -437.32675) (xy 451.329416 -437.457248) (xy 451.232093 -437.582979) (xy 451.128527 -437.703619)
			(xy 451.018984 -437.818858) (xy 450.903745 -437.928401) (xy 450.783105 -438.031967) (xy 450.657374 -438.12929)
			(xy 450.526876 -438.22012) (xy 450.391944 -438.304223) (xy 450.252926 -438.381384) (xy 450.110178 -438.451406)
			(xy 449.964067 -438.514107) (xy 449.814968 -438.569327) (xy 449.663263 -438.616925) (xy 449.509342 -438.656778)
			(xy 449.3536 -438.688783) (xy 449.196437 -438.71286) (xy 449.038257 -438.728945) (xy 448.879464 -438.736998)
			(xy 448.720468 -438.736998) (xy 448.561675 -438.728945) (xy 448.403495 -438.71286) (xy 448.246332 -438.688783)
			(xy 448.09059 -438.656778) (xy 447.936669 -438.616925) (xy 447.784964 -438.569327) (xy 447.635865 -438.514107)
			(xy 447.489754 -438.451406) (xy 447.347006 -438.381384) (xy 447.207988 -438.304223) (xy 447.073056 -438.22012)
			(xy 446.942558 -438.12929) (xy 446.816827 -438.031967) (xy 446.696187 -437.928401) (xy 446.580948 -437.818858)
			(xy 446.471405 -437.703619) (xy 446.367839 -437.582979) (xy 446.270516 -437.457248) (xy 446.179686 -437.32675)
			(xy 446.095583 -437.191818) (xy 446.018422 -437.0528) (xy 445.9484 -436.910052) (xy 445.885699 -436.763941)
			(xy 445.830479 -436.614842) (xy 445.782881 -436.463137) (xy 445.743028 -436.309216) (xy 445.711023 -436.153474)
			(xy 445.686946 -435.996311) (xy 445.670861 -435.838131) (xy 445.662808 -435.679338) (xy 413.334708 -435.679338)
			(xy 413.334708 -436.160418) (xy 413.334205 -436.172529) (xy 413.326718 -436.195565) (xy 413.312482 -436.215163)
			(xy 413.29289 -436.229405) (xy 413.269857 -436.2369) (xy 413.257746 -436.23738) (xy 412.317946 -436.23738)
			(xy 412.305827 -436.236901) (xy 412.282773 -436.229424) (xy 412.263159 -436.215187) (xy 412.248905 -436.195584)
			(xy 412.241409 -436.172536) (xy 412.240984 -436.160418) (xy 411.306818 -436.160418) (xy 411.312432 -436.164484)
			(xy 411.326683 -436.184021) (xy 411.334208 -436.207002) (xy 411.334712 -436.219092) (xy 411.334712 -438.760616)
			(xy 411.334254 -438.772666) (xy 411.326818 -438.79559) (xy 411.312676 -438.815104) (xy 411.293207 -438.829307)
			(xy 411.270306 -438.836815) (xy 411.258258 -438.837324) (xy 410.31795 -438.837324) (xy 410.305859 -438.836849)
			(xy 410.282854 -438.829402) (xy 410.26327 -438.815219) (xy 410.249019 -438.795684) (xy 410.241493 -438.772705)
			(xy 410.240988 -438.760616) (xy 409.334716 -438.760616) (xy 409.334716 -439.760614) (xy 412.240984 -439.760614)
			(xy 412.240984 -437.21909) (xy 412.241352 -437.206962) (xy 412.248853 -437.183895) (xy 412.263116 -437.164276)
			(xy 412.282745 -437.150027) (xy 412.305818 -437.142544) (xy 412.317946 -437.142128) (xy 413.257746 -437.142128)
			(xy 413.269862 -437.142572) (xy 413.292905 -437.150071) (xy 413.312505 -437.164321) (xy 413.326745 -437.183927)
			(xy 413.334233 -437.206974) (xy 413.334708 -437.21909) (xy 413.334708 -439.760614) (xy 413.334201 -439.772725)
			(xy 413.326716 -439.795761) (xy 413.312481 -439.815358) (xy 413.292889 -439.829601) (xy 413.269857 -439.837096)
			(xy 413.257746 -439.837576) (xy 412.317946 -439.837576) (xy 412.305827 -439.837101) (xy 412.282772 -439.829623)
			(xy 412.263157 -439.815385) (xy 412.248904 -439.795782) (xy 412.241408 -439.772733) (xy 412.240984 -439.760614)
			(xy 409.334716 -439.760614) (xy 409.334351 -439.772742) (xy 409.326849 -439.795809) (xy 409.312585 -439.815428)
			(xy 409.292955 -439.829677) (xy 409.269882 -439.83716) (xy 409.257754 -439.837576) (xy 408.317954 -439.837576)
			(xy 408.305838 -439.837128) (xy 408.282796 -439.82963) (xy 408.263196 -439.815381) (xy 408.248956 -439.795775)
			(xy 408.241467 -439.77273) (xy 408.240992 -439.760614) (xy 405.334724 -439.760614) (xy 405.334351 -439.772741)
			(xy 405.32685 -439.795807) (xy 405.312588 -439.815425) (xy 405.29296 -439.829674) (xy 405.26989 -439.837159)
			(xy 405.257762 -439.837576) (xy 404.317962 -439.837576) (xy 404.305847 -439.837121) (xy 404.282805 -439.829625)
			(xy 404.263205 -439.815378) (xy 404.248964 -439.795774) (xy 404.241475 -439.772729) (xy 404.241 -439.760614)
			(xy 401.334732 -439.760614) (xy 401.334351 -439.77274) (xy 401.326852 -439.795805) (xy 401.312591 -439.815422)
			(xy 401.292965 -439.829672) (xy 401.269897 -439.837158) (xy 401.25777 -439.837576) (xy 400.31797 -439.837576)
			(xy 400.305855 -439.837114) (xy 400.282813 -439.82962) (xy 400.263213 -439.815375) (xy 400.248972 -439.795772)
			(xy 400.241483 -439.772729) (xy 400.241008 -439.760614) (xy 396.334488 -439.760614) (xy 396.334005 -439.772702)
			(xy 396.326548 -439.795698) (xy 396.312365 -439.815275) (xy 396.292836 -439.829526) (xy 396.269866 -439.837063)
			(xy 396.25778 -439.837576) (xy 395.31798 -439.837576) (xy 395.305868 -439.8372) (xy 395.282836 -439.829693)
			(xy 395.263261 -439.815421) (xy 395.249068 -439.79579) (xy 395.241652 -439.772728) (xy 395.241272 -439.760614)
			(xy 392.334496 -439.760614) (xy 392.334005 -439.772701) (xy 392.326549 -439.795696) (xy 392.312367 -439.815272)
			(xy 392.292841 -439.829524) (xy 392.269873 -439.837062) (xy 392.257788 -439.837576) (xy 391.317988 -439.837576)
			(xy 391.305876 -439.837194) (xy 391.282844 -439.829688) (xy 391.263269 -439.815419) (xy 391.249076 -439.795788)
			(xy 391.24166 -439.772727) (xy 391.24128 -439.760614) (xy 388.334504 -439.760614) (xy 388.334006 -439.7727)
			(xy 388.32655 -439.795694) (xy 388.31237 -439.81527) (xy 388.292846 -439.829521) (xy 388.26988 -439.837061)
			(xy 388.257796 -439.837576) (xy 387.317996 -439.837576) (xy 387.305885 -439.837187) (xy 387.282853 -439.829683)
			(xy 387.263278 -439.815416) (xy 387.249084 -439.795787) (xy 387.241668 -439.772727) (xy 387.241288 -439.760614)
			(xy 384.334512 -439.760614) (xy 384.334104 -439.772709) (xy 384.326638 -439.795718) (xy 384.312437 -439.815302)
			(xy 384.292889 -439.829551) (xy 384.269898 -439.837074) (xy 384.257804 -439.837576) (xy 383.318004 -439.837576)
			(xy 383.305893 -439.83718) (xy 383.282862 -439.829679) (xy 383.263286 -439.815413) (xy 383.249092 -439.795785)
			(xy 383.241676 -439.772727) (xy 383.241296 -439.760614) (xy 374.53592 -439.760614) (xy 374.513846 -439.778293)
			(xy 374.348781 -439.900257) (xy 374.179093 -440.015702) (xy 374.005041 -440.124454) (xy 373.826886 -440.226349)
			(xy 373.736108 -440.274202) (xy 373.735854 -440.274202) (xy 373.726093 -440.280024) (xy 373.712493 -440.298196)
			(xy 373.708029 -440.32045) (xy 373.7102 -440.331606) (xy 373.733822 -440.427364) (xy 373.737124 -440.438178)
			(xy 373.751415 -440.455662) (xy 373.771809 -440.465357) (xy 373.783098 -440.465972) (xy 381.219202 -440.465972)
			(xy 381.220472 -440.465972) (xy 381.229391 -440.465407) (xy 381.246012 -440.458869) (xy 381.259386 -440.447032)
			(xy 381.267895 -440.431329) (xy 381.269494 -440.422538) (xy 381.269494 -440.422284) (xy 381.274392 -440.3911)
			(xy 381.29122 -440.330259) (xy 381.315798 -440.272116) (xy 381.347712 -440.217652) (xy 381.386421 -440.167789)
			(xy 381.431272 -440.123369) (xy 381.481507 -440.085143) (xy 381.536276 -440.053757) (xy 381.594654 -440.029741)
			(xy 381.655654 -440.013501) (xy 381.718246 -440.005312) (xy 381.78137 -440.005312) (xy 381.843962 -440.013501)
			(xy 381.904962 -440.029741) (xy 381.96334 -440.053757) (xy 382.018109 -440.085143) (xy 382.068344 -440.123369)
			(xy 382.113195 -440.167789) (xy 382.151904 -440.217652) (xy 382.183818 -440.272116) (xy 382.208396 -440.330259)
			(xy 382.225224 -440.3911) (xy 382.230122 -440.422284) (xy 382.230122 -440.422538) (xy 382.231752 -440.431325)
			(xy 382.24024 -440.44704) (xy 382.253605 -440.458888) (xy 382.270224 -440.46543) (xy 382.279144 -440.465972)
			(xy 385.219194 -440.465972) (xy 385.220464 -440.465972) (xy 385.229384 -440.465408) (xy 385.246007 -440.458872)
			(xy 385.259384 -440.447035) (xy 385.267894 -440.431331) (xy 385.269486 -440.422538) (xy 385.269486 -440.422284)
			(xy 385.274384 -440.3911) (xy 385.291212 -440.330259) (xy 385.31579 -440.272116) (xy 385.347704 -440.217652)
			(xy 385.386413 -440.167789) (xy 385.431264 -440.123369) (xy 385.481499 -440.085143) (xy 385.536268 -440.053757)
			(xy 385.594646 -440.029741) (xy 385.655646 -440.013501) (xy 385.718238 -440.005312) (xy 385.781362 -440.005312)
			(xy 385.843954 -440.013501) (xy 385.904954 -440.029741) (xy 385.963332 -440.053757) (xy 386.018101 -440.085143)
			(xy 386.068336 -440.123369) (xy 386.113187 -440.167789) (xy 386.151896 -440.217652) (xy 386.18381 -440.272116)
			(xy 386.208388 -440.330259) (xy 386.225216 -440.3911) (xy 386.230114 -440.422284) (xy 386.230114 -440.422538)
			(xy 386.231744 -440.431326) (xy 386.240231 -440.447042) (xy 386.253596 -440.458892) (xy 386.270216 -440.465437)
			(xy 386.279136 -440.465972) (xy 389.219186 -440.465972) (xy 389.220456 -440.465972) (xy 389.229377 -440.465409)
			(xy 389.246002 -440.458874) (xy 389.259381 -440.447038) (xy 389.267894 -440.431333) (xy 389.269478 -440.422538)
			(xy 389.269478 -440.422284) (xy 389.274376 -440.3911) (xy 389.291204 -440.330259) (xy 389.315782 -440.272116)
			(xy 389.347696 -440.217652) (xy 389.386405 -440.167789) (xy 389.431256 -440.123369) (xy 389.481491 -440.085143)
			(xy 389.53626 -440.053757) (xy 389.594638 -440.029741) (xy 389.655638 -440.013501) (xy 389.71823 -440.005312)
			(xy 389.781354 -440.005312) (xy 389.843946 -440.013501) (xy 389.904946 -440.029741) (xy 389.963324 -440.053757)
			(xy 390.018093 -440.085143) (xy 390.068328 -440.123369) (xy 390.113179 -440.167789) (xy 390.151888 -440.217652)
			(xy 390.183802 -440.272116) (xy 390.20838 -440.330259) (xy 390.225208 -440.3911) (xy 390.230106 -440.422284)
			(xy 390.230106 -440.422538) (xy 390.231736 -440.431326) (xy 390.240223 -440.447044) (xy 390.253587 -440.458896)
			(xy 390.270207 -440.465443) (xy 390.279128 -440.465972) (xy 393.219178 -440.465972) (xy 393.220448 -440.465972)
			(xy 393.22937 -440.46541) (xy 393.245997 -440.458877) (xy 393.259379 -440.447041) (xy 393.267893 -440.431335)
			(xy 393.26947 -440.422538) (xy 393.26947 -440.422284) (xy 393.274368 -440.3911) (xy 393.291196 -440.330259)
			(xy 393.315774 -440.272116) (xy 393.347688 -440.217652) (xy 393.386397 -440.167789) (xy 393.431248 -440.123369)
			(xy 393.481483 -440.085143) (xy 393.536252 -440.053757) (xy 393.59463 -440.029741) (xy 393.65563 -440.013501)
			(xy 393.718222 -440.005312) (xy 393.781346 -440.005312) (xy 393.843938 -440.013501) (xy 393.904938 -440.029741)
			(xy 393.963316 -440.053757) (xy 394.018085 -440.085143) (xy 394.06832 -440.123369) (xy 394.113171 -440.167789)
			(xy 394.15188 -440.217652) (xy 394.183794 -440.272116) (xy 394.208372 -440.330259) (xy 394.2252 -440.3911)
			(xy 394.230098 -440.422284) (xy 394.230098 -440.422538) (xy 394.231727 -440.431327) (xy 394.240214 -440.447046)
			(xy 394.253578 -440.4589) (xy 394.270198 -440.46545) (xy 394.27912 -440.465972) (xy 398.219422 -440.465972)
			(xy 398.220692 -440.465972) (xy 398.229609 -440.465403) (xy 398.246224 -440.458862) (xy 398.259593 -440.447025)
			(xy 398.268097 -440.431324) (xy 398.269714 -440.422538) (xy 398.269714 -440.422284) (xy 398.274612 -440.3911)
			(xy 398.29144 -440.330259) (xy 398.316018 -440.272116) (xy 398.347932 -440.217652) (xy 398.386641 -440.167789)
			(xy 398.431492 -440.123369) (xy 398.481727 -440.085143) (xy 398.536496 -440.053757) (xy 398.594874 -440.029741)
			(xy 398.655874 -440.013501) (xy 398.718466 -440.005312) (xy 398.78159 -440.005312) (xy 398.844182 -440.013501)
			(xy 398.905182 -440.029741) (xy 398.96356 -440.053757) (xy 399.018329 -440.085143) (xy 399.068564 -440.123369)
			(xy 399.113415 -440.167789) (xy 399.152124 -440.217652) (xy 399.184038 -440.272116) (xy 399.208616 -440.330259)
			(xy 399.225444 -440.3911) (xy 399.230342 -440.422284) (xy 399.230342 -440.422538) (xy 399.231973 -440.431324)
			(xy 399.240461 -440.447035) (xy 399.253827 -440.458878) (xy 399.270446 -440.465415) (xy 399.279364 -440.465972)
			(xy 402.219414 -440.465972) (xy 402.220684 -440.465972) (xy 402.229602 -440.465405) (xy 402.246219 -440.458865)
			(xy 402.25959 -440.447028) (xy 402.268097 -440.431326) (xy 402.269706 -440.422538) (xy 402.269706 -440.422284)
			(xy 402.274604 -440.3911) (xy 402.291432 -440.330259) (xy 402.31601 -440.272116) (xy 402.347924 -440.217652)
			(xy 402.386633 -440.167789) (xy 402.431484 -440.123369) (xy 402.481719 -440.085143) (xy 402.536488 -440.053757)
			(xy 402.594866 -440.029741) (xy 402.655866 -440.013501) (xy 402.718458 -440.005312) (xy 402.781582 -440.005312)
			(xy 402.844174 -440.013501) (xy 402.905174 -440.029741) (xy 402.963552 -440.053757) (xy 403.018321 -440.085143)
			(xy 403.068556 -440.123369) (xy 403.113407 -440.167789) (xy 403.152116 -440.217652) (xy 403.18403 -440.272116)
			(xy 403.208608 -440.330259) (xy 403.225436 -440.3911) (xy 403.230334 -440.422284) (xy 403.230334 -440.422538)
			(xy 403.231964 -440.431324) (xy 403.240453 -440.447037) (xy 403.253818 -440.458882) (xy 403.270437 -440.465421)
			(xy 403.279356 -440.465972) (xy 406.219406 -440.465972) (xy 406.220676 -440.465972) (xy 406.229594 -440.465406)
			(xy 406.246214 -440.458868) (xy 406.259588 -440.447031) (xy 406.268096 -440.431328) (xy 406.269698 -440.422538)
			(xy 406.269698 -440.422284) (xy 406.274596 -440.3911) (xy 406.291424 -440.330259) (xy 406.316002 -440.272116)
			(xy 406.347916 -440.217652) (xy 406.386625 -440.167789) (xy 406.431476 -440.123369) (xy 406.481711 -440.085143)
			(xy 406.53648 -440.053757) (xy 406.594858 -440.029741) (xy 406.655858 -440.013501) (xy 406.71845 -440.005312)
			(xy 406.781574 -440.005312) (xy 406.844166 -440.013501) (xy 406.905166 -440.029741) (xy 406.963544 -440.053757)
			(xy 407.018313 -440.085143) (xy 407.068548 -440.123369) (xy 407.113399 -440.167789) (xy 407.152108 -440.217652)
			(xy 407.184022 -440.272116) (xy 407.2086 -440.330259) (xy 407.225428 -440.3911) (xy 407.230326 -440.422284)
			(xy 407.230326 -440.422538) (xy 407.231956 -440.431325) (xy 407.240444 -440.447039) (xy 407.253809 -440.458886)
			(xy 407.270429 -440.465427) (xy 407.279348 -440.465972) (xy 410.219398 -440.465972) (xy 410.220668 -440.465972)
			(xy 410.229587 -440.465407) (xy 410.246209 -440.45887) (xy 410.259585 -440.447034) (xy 410.268095 -440.43133)
			(xy 410.26969 -440.422538) (xy 410.26969 -440.422284) (xy 410.274588 -440.3911) (xy 410.291416 -440.330259)
			(xy 410.315994 -440.272116) (xy 410.347908 -440.217652) (xy 410.386617 -440.167789) (xy 410.431468 -440.123369)
			(xy 410.481703 -440.085143) (xy 410.536472 -440.053757) (xy 410.59485 -440.029741) (xy 410.65585 -440.013501)
			(xy 410.718442 -440.005312) (xy 410.781566 -440.005312) (xy 410.844158 -440.013501) (xy 410.905158 -440.029741)
			(xy 410.963536 -440.053757) (xy 411.018305 -440.085143) (xy 411.06854 -440.123369) (xy 411.113391 -440.167789)
			(xy 411.1521 -440.217652) (xy 411.184014 -440.272116) (xy 411.208592 -440.330259) (xy 411.22542 -440.3911)
			(xy 411.230318 -440.422284) (xy 411.230318 -440.422538) (xy 411.231948 -440.431325) (xy 411.240436 -440.447041)
			(xy 411.253801 -440.45889) (xy 411.27042 -440.465433) (xy 411.27934 -440.465972) (xy 456.315318 -440.465972)
			(xy 456.326619 -440.465382) (xy 456.347043 -440.455708) (xy 456.361332 -440.438199) (xy 456.364594 -440.427364)
			(xy 456.388216 -440.331352) (xy 456.390334 -440.32024) (xy 456.38582 -440.298104) (xy 456.372257 -440.280036)
			(xy 456.362562 -440.274202) (xy 456.362308 -440.274202) (xy 456.271044 -440.22604) (xy 456.091927 -440.123518)
			(xy 455.916959 -440.014064) (xy 455.74641 -439.897845) (xy 455.580541 -439.77504) (xy 455.419605 -439.645837)
			(xy 455.26385 -439.510433) (xy 455.113514 -439.369037) (xy 454.968828 -439.221865) (xy 454.830013 -439.069143)
			(xy 454.697281 -438.911104) (xy 454.570838 -438.747992) (xy 454.450875 -438.580055) (xy 454.337578 -438.407551)
			(xy 454.23112 -438.230745) (xy 454.131663 -438.049908) (xy 454.03936 -437.865316) (xy 453.954354 -437.677253)
			(xy 453.876773 -437.486007) (xy 453.806738 -437.291871) (xy 453.744355 -437.095143) (xy 453.689719 -436.896123)
			(xy 453.642916 -436.695118) (xy 453.604015 -436.492435) (xy 453.573078 -436.288384) (xy 453.550151 -436.083279)
			(xy 453.53527 -435.877434) (xy 453.528457 -435.671164) (xy 453.529722 -435.464785) (xy 453.539065 -435.258614)
			(xy 453.55647 -435.052967) (xy 453.581911 -434.848158) (xy 453.615349 -434.644502) (xy 453.656732 -434.442311)
			(xy 453.705998 -434.241895) (xy 453.76307 -434.043561) (xy 453.827862 -433.847612) (xy 453.900273 -433.65435)
			(xy 453.980194 -433.46407) (xy 454.067501 -433.277064) (xy 454.16206 -433.093618) (xy 454.263728 -432.914014)
			(xy 454.372347 -432.738528) (xy 454.487751 -432.567427) (xy 454.609765 -432.400974) (xy 454.7382 -432.239424)
			(xy 454.872859 -432.083026) (xy 455.013537 -431.932017) (xy 455.160018 -431.786631) (xy 455.312077 -431.64709)
			(xy 455.469481 -431.513607) (xy 455.631989 -431.386387) (xy 455.799353 -431.265626) (xy 455.971314 -431.151508)
			(xy 456.147611 -431.044208) (xy 456.327972 -430.94389) (xy 456.512122 -430.850709) (xy 456.699777 -430.764807)
			(xy 456.890651 -430.686316) (xy 457.084451 -430.615356) (xy 457.28088 -430.552036) (xy 457.479637 -430.496453)
			(xy 457.680417 -430.448692) (xy 457.882913 -430.408826) (xy 458.086814 -430.376917) (xy 458.291807 -430.353012)
			(xy 458.497579 -430.33715) (xy 458.703815 -430.329354) (xy 458.910197 -430.329636) (xy 459.11641 -430.337996)
			(xy 459.322138 -430.354421) (xy 459.527066 -430.378886) (xy 459.730878 -430.411353) (xy 459.933264 -430.451772)
			(xy 460.133913 -430.500082) (xy 460.332517 -430.556208) (xy 460.528772 -430.620065) (xy 460.722377 -430.691555)
			(xy 460.913036 -430.770568) (xy 461.100456 -430.856982) (xy 461.28435 -430.950666) (xy 461.464437 -431.051477)
			(xy 461.640439 -431.159258) (xy 461.812088 -431.273846) (xy 461.979121 -431.395065) (xy 462.14128 -431.522728)
			(xy 462.298319 -431.656641) (xy 462.449996 -431.796598) (xy 462.596079 -431.942384) (xy 462.736343 -432.093776)
			(xy 462.870575 -432.250542) (xy 462.998567 -432.412442) (xy 463.120125 -432.579228) (xy 463.235061 -432.750644)
			(xy 463.3432 -432.926427) (xy 463.444376 -433.106308) (xy 463.538434 -433.290012) (xy 463.582258 -433.383436)
			(xy 463.582258 -433.38369) (xy 463.58763 -433.393931) (xy 463.605536 -433.408528) (xy 463.628015 -433.413861)
			(xy 463.639408 -433.411884) (xy 463.736182 -433.390548) (xy 463.73669 -433.390548) (xy 463.747001 -433.387535)
			(xy 463.764071 -433.374537) (xy 463.774395 -433.355729) (xy 463.775806 -433.345082) (xy 463.77606 -433.341018)
			(xy 463.77606 -409.528264) (xy 463.776591 -409.442432) (xy 463.784964 -409.270971) (xy 463.801675 -409.100122)
			(xy 463.826683 -408.930289) (xy 463.859929 -408.761874) (xy 463.901335 -408.595278) (xy 463.950802 -408.430895)
			(xy 464.008213 -408.269115) (xy 464.073432 -408.110322) (xy 464.146304 -407.954892) (xy 464.226656 -407.803194)
			(xy 464.314298 -407.655588) (xy 464.409022 -407.512423) (xy 464.510603 -407.37404) (xy 464.618801 -407.240766)
			(xy 464.733358 -407.112917) (xy 464.79333 -407.05151) (xy 464.808062 -407.036778) (xy 464.808062 -407.036524)
			(xy 466.636608 -405.207978) (xy 466.658299 -405.185621) (xy 466.696247 -405.13622) (xy 466.72742 -405.082289)
			(xy 466.751285 -405.024748) (xy 466.767434 -404.964585) (xy 466.77559 -404.902828) (xy 466.776054 -404.871682)
			(xy 466.776054 -82.82813) (xy 466.776586 -82.742298) (xy 466.784961 -82.570838) (xy 466.801673 -82.39999)
			(xy 466.826682 -82.230157) (xy 466.85993 -82.061744) (xy 466.901337 -81.895148) (xy 466.950805 -81.730766)
			(xy 467.008217 -81.568988) (xy 467.073437 -81.410196) (xy 467.14631 -81.254767) (xy 467.226663 -81.10307)
			(xy 467.314306 -80.955465) (xy 467.40903 -80.812301) (xy 467.510612 -80.673919) (xy 467.61881 -80.540646)
			(xy 467.733368 -80.412798) (xy 467.793324 -80.351376) (xy 467.808056 -80.336644) (xy 467.808056 -80.33639)
			(xy 470.136474 -78.007972) (xy 470.158166 -77.985616) (xy 470.196116 -77.936216) (xy 470.22729 -77.882284)
			(xy 470.251157 -77.824744) (xy 470.267306 -77.76458) (xy 470.275462 -77.702823) (xy 470.27592 -77.671676)
			(xy 470.27592 -13.780008) (xy 470.275411 -13.748842) (xy 470.267276 -13.687043) (xy 470.251145 -13.626835)
			(xy 470.227293 -13.569247) (xy 470.196128 -13.515265) (xy 470.158185 -13.465813) (xy 470.114111 -13.421736)
			(xy 470.064661 -13.383789) (xy 470.010681 -13.352621) (xy 469.953095 -13.328766) (xy 469.892888 -13.31263)
			(xy 469.83109 -13.304491) (xy 469.799924 -13.304012) (xy 458.20203 -13.304012) (xy 458.118154 -13.303522)
			(xy 457.950593 -13.295541) (xy 457.783601 -13.279597) (xy 457.617557 -13.255724) (xy 457.452837 -13.223979)
			(xy 457.289814 -13.184431) (xy 457.128858 -13.137171) (xy 456.970332 -13.082306) (xy 456.814597 -13.019961)
			(xy 456.662004 -12.950276) (xy 456.5129 -12.873409) (xy 456.367623 -12.789534) (xy 456.226501 -12.698842)
			(xy 456.089854 -12.601537) (xy 455.957992 -12.497841) (xy 455.831213 -12.387988) (xy 455.709805 -12.272228)
			(xy 455.594043 -12.150821) (xy 455.484188 -12.024044) (xy 455.38049 -11.892183) (xy 455.283184 -11.755537)
			(xy 455.19249 -11.614417) (xy 455.108614 -11.46914) (xy 455.031745 -11.320037) (xy 454.962057 -11.167446)
			(xy 454.89971 -11.011711) (xy 454.844843 -10.853186) (xy 454.797581 -10.69223) (xy 454.758031 -10.529208)
			(xy 454.726283 -10.364488) (xy 454.702409 -10.198445) (xy 454.686462 -10.031453) (xy 454.67848 -9.863892)
			(xy 454.678034 -9.780016) (xy 454.678034 -7.29234) (xy 454.677691 -7.283605) (xy 454.671823 -7.267153)
			(xy 454.66073 -7.253659) (xy 454.653396 -7.248906) (xy 454.578974 -7.203694) (xy 454.5711 -7.199884)
			(xy 454.560642 -7.196362) (xy 454.538638 -7.197667) (xy 454.528682 -7.202424) (xy 454.486547 -7.224219)
			(xy 454.399396 -7.261709) (xy 454.309493 -7.292011) (xy 454.21743 -7.314927) (xy 454.123812 -7.330305)
			(xy 454.029256 -7.338045) (xy 453.98182 -7.338568) (xy 453.933503 -7.338083) (xy 453.837199 -7.330105)
			(xy 453.741883 -7.314201) (xy 453.648206 -7.29048) (xy 453.556808 -7.259104) (xy 453.468312 -7.220288)
			(xy 453.383325 -7.174296) (xy 453.302426 -7.121443) (xy 453.226168 -7.062091) (xy 453.155071 -6.996643)
			(xy 453.089622 -6.925548) (xy 453.030268 -6.84929) (xy 452.977414 -6.768392) (xy 452.931421 -6.683406)
			(xy 452.892603 -6.594911) (xy 452.861226 -6.503513) (xy 452.837503 -6.409836) (xy 452.821598 -6.314521)
			(xy 452.813618 -6.218217) (xy 452.813618 -6.121583) (xy 452.821598 -6.025279) (xy 452.837503 -5.929964)
			(xy 452.861226 -5.836287) (xy 452.892603 -5.744889) (xy 452.931421 -5.656394) (xy 452.977414 -5.571408)
			(xy 453.030268 -5.49051) (xy 453.089622 -5.414252) (xy 453.155071 -5.343157) (xy 453.226168 -5.277709)
			(xy 453.302426 -5.218357) (xy 453.383325 -5.165504) (xy 453.468312 -5.119512) (xy 453.556808 -5.080696)
			(xy 453.648206 -5.04932) (xy 453.741883 -5.025599) (xy 453.837199 -5.009695) (xy 453.933503 -5.001717)
			(xy 453.98182 -5.00126) (xy 454.029257 -5.001754) (xy 454.123817 -5.009483) (xy 454.217439 -5.024857)
			(xy 454.309505 -5.047774) (xy 454.399409 -5.078083) (xy 454.486558 -5.115585) (xy 454.528682 -5.137404)
			(xy 454.538657 -5.142095) (xy 454.560639 -5.143416) (xy 454.5711 -5.139944) (xy 454.578974 -5.136134)
			(xy 454.653396 -5.090922) (xy 454.660683 -5.086113) (xy 454.671749 -5.072622) (xy 454.677671 -5.05621)
			(xy 454.678034 -5.047488) (xy 454.678034 -1.5748) (xy 454.677547 -1.56479) (xy 454.669888 -1.546292)
			(xy 454.655736 -1.532131) (xy 454.637244 -1.52446) (xy 454.627234 -1.524) (xy 389.176768 -1.524)
			(xy 389.166765 -1.524494) (xy 389.148284 -1.532159) (xy 389.134141 -1.546311) (xy 389.126487 -1.564796)
			(xy 389.125968 -1.5748) (xy 389.125968 -4.044442) (xy 389.126324 -4.053169) (xy 389.13221 -4.069601)
			(xy 389.143309 -4.083072) (xy 389.150606 -4.087876) (xy 389.224774 -4.133088) (xy 389.237982 -4.138676)
			(xy 389.247276 -4.140771) (xy 389.266199 -4.138684) (xy 389.274812 -4.134612) (xy 389.316649 -4.113242)
			(xy 389.403115 -4.076491) (xy 389.492252 -4.046798) (xy 389.583485 -4.024353) (xy 389.676224 -4.009303)
			(xy 389.769872 -4.001743) (xy 389.816848 -4.001262) (xy 389.865161 -4.001763) (xy 389.961458 -4.009746)
			(xy 390.056766 -4.025654) (xy 390.150435 -4.049378) (xy 390.241825 -4.080755) (xy 390.330312 -4.119572)
			(xy 390.415291 -4.165564) (xy 390.496182 -4.218416) (xy 390.572433 -4.277767) (xy 390.643522 -4.343212)
			(xy 390.708964 -4.414304) (xy 390.768312 -4.490557) (xy 390.821161 -4.57145) (xy 390.867149 -4.656431)
			(xy 390.905962 -4.74492) (xy 390.937336 -4.836311) (xy 390.961056 -4.929981) (xy 390.97696 -5.02529)
			(xy 390.984939 -5.121587) (xy 390.984939 -5.218213) (xy 390.97696 -5.31451) (xy 390.961056 -5.409819)
			(xy 390.937336 -5.503489) (xy 390.905962 -5.59488) (xy 390.867149 -5.683369) (xy 390.821161 -5.76835)
			(xy 390.768312 -5.849243) (xy 390.708964 -5.925496) (xy 390.643522 -5.996588) (xy 390.572433 -6.062033)
			(xy 390.496182 -6.121384) (xy 390.415291 -6.174236) (xy 390.330312 -6.220228) (xy 390.241825 -6.259045)
			(xy 390.150435 -6.290422) (xy 390.056766 -6.314146) (xy 389.961458 -6.330054) (xy 389.865161 -6.338037)
			(xy 389.816848 -6.33857) (xy 389.769871 -6.338101) (xy 389.67622 -6.330556) (xy 389.583478 -6.315512)
			(xy 389.492245 -6.293064) (xy 389.40311 -6.263359) (xy 389.316651 -6.226589) (xy 389.274812 -6.20522)
			(xy 389.266201 -6.201137) (xy 389.247274 -6.199041) (xy 389.237982 -6.201156) (xy 389.234516 -6.202127)
			(xy 389.227887 -6.204935) (xy 389.224774 -6.206744) (xy 389.150606 -6.251956) (xy 389.143316 -6.256764)
			(xy 389.132244 -6.270253) (xy 389.126315 -6.286666) (xy 389.125968 -6.29539) (xy 389.125968 -6.598158)
			(xy 392.428222 -6.598158) (xy 392.428685 -6.570888) (xy 392.436452 -6.516905) (xy 392.451822 -6.464576)
			(xy 392.474482 -6.414966) (xy 392.503971 -6.369087) (xy 392.539688 -6.32787) (xy 392.580907 -6.292155)
			(xy 392.626789 -6.26267) (xy 392.6764 -6.240013) (xy 392.72873 -6.224647) (xy 392.782714 -6.216883)
			(xy 392.809984 -6.216396) (xy 392.810238 -6.216396) (xy 392.829796 -6.216904) (xy 392.840718 -6.217412)
			(xy 392.860784 -6.210046) (xy 392.929618 -6.140958) (xy 392.937238 -6.121146) (xy 392.93673 -6.110224)
			(xy 392.936222 -6.091174) (xy 392.9367 -6.063905) (xy 392.944465 -6.009922) (xy 392.959833 -5.957593)
			(xy 392.982491 -5.907984) (xy 393.011978 -5.862104) (xy 393.047694 -5.820887) (xy 393.088912 -5.785172)
			(xy 393.134793 -5.755686) (xy 393.184402 -5.733029) (xy 393.236731 -5.717663) (xy 393.290715 -5.7099)
			(xy 393.317984 -5.709412) (xy 393.3468 -5.709883) (xy 393.403776 -5.718565) (xy 393.458802 -5.735704)
			(xy 393.51063 -5.760911) (xy 393.558086 -5.793615) (xy 393.600092 -5.833075) (xy 393.635697 -5.878394)
			(xy 393.664093 -5.928547) (xy 393.674854 -5.955284) (xy 393.679841 -5.966338) (xy 393.69787 -5.982508)
			(xy 393.709398 -5.986272) (xy 393.746493 -5.9965) (xy 393.818584 -6.023419) (xy 393.887599 -6.057458)
			(xy 393.920472 -6.077458) (xy 393.928728 -6.082172) (xy 393.947396 -6.085699) (xy 393.966064 -6.082172)
			(xy 393.97432 -6.077458) (xy 394.007202 -6.057473) (xy 394.076218 -6.023441) (xy 394.148303 -5.996511)
			(xy 394.185394 -5.986272) (xy 394.196957 -5.982569) (xy 394.215001 -5.966377) (xy 394.219938 -5.955284)
			(xy 394.230707 -5.92855) (xy 394.259091 -5.878393) (xy 394.29469 -5.833071) (xy 394.336696 -5.793612)
			(xy 394.384153 -5.760914) (xy 394.435985 -5.735717) (xy 394.491015 -5.718595) (xy 394.547992 -5.709937)
			(xy 394.576808 -5.709412) (xy 394.587564 -5.709519) (xy 394.60904 -5.710789) (xy 394.619734 -5.711952)
			(xy 394.630656 -5.713222) (xy 394.651484 -5.706364) (xy 394.716254 -5.646674) (xy 394.723884 -5.639)
			(xy 394.732428 -5.619137) (xy 394.732764 -5.60832) (xy 394.732764 -5.608066) (xy 394.73251 -5.597652)
			(xy 394.73251 -5.597398) (xy 394.732898 -5.572667) (xy 394.73927 -5.523618) (xy 394.74521 -5.499608)
			(xy 394.74785 -5.487606) (xy 394.742524 -5.463643) (xy 394.73505 -5.453888) (xy 394.718213 -5.433581)
			(xy 394.68707 -5.390997) (xy 394.67282 -5.368798) (xy 394.667808 -5.361478) (xy 394.653834 -5.350566)
			(xy 394.636988 -5.345039) (xy 394.628116 -5.344922) (xy 394.614654 -5.345176) (xy 394.587388 -5.344658)
			(xy 394.533411 -5.336892) (xy 394.481089 -5.321523) (xy 394.431486 -5.298865) (xy 394.385613 -5.269379)
			(xy 394.344402 -5.233665) (xy 394.308693 -5.19245) (xy 394.279213 -5.146573) (xy 394.256561 -5.096968)
			(xy 394.241198 -5.044644) (xy 394.233438 -4.990666) (xy 394.233438 -4.936134) (xy 394.241198 -4.882156)
			(xy 394.256561 -4.829832) (xy 394.279213 -4.780227) (xy 394.308693 -4.73435) (xy 394.344402 -4.693135)
			(xy 394.385613 -4.657421) (xy 394.431486 -4.627935) (xy 394.481089 -4.605277) (xy 394.533411 -4.589908)
			(xy 394.587388 -4.582142) (xy 394.614654 -4.581652) (xy 394.628116 -4.581906) (xy 394.637001 -4.581876)
			(xy 394.653878 -4.576356) (xy 394.667846 -4.565393) (xy 394.67282 -4.55803) (xy 394.687084 -4.53584)
			(xy 394.718225 -4.493256) (xy 394.73505 -4.47294) (xy 394.742339 -4.463099) (xy 394.747638 -4.439224)
			(xy 394.74521 -4.42722) (xy 394.73929 -4.4034) (xy 394.73292 -4.354733) (xy 394.73251 -4.330192)
			(xy 394.73251 -4.32943) (xy 394.733029 -4.302161) (xy 394.740787 -4.248178) (xy 394.756148 -4.195848)
			(xy 394.7788 -4.146236) (xy 394.808282 -4.100354) (xy 394.843993 -4.059134) (xy 394.885208 -4.023416)
			(xy 394.931086 -3.993928) (xy 394.980693 -3.971268) (xy 395.033021 -3.955899) (xy 395.087003 -3.948133)
			(xy 395.114272 -3.947668) (xy 395.14295 -3.948235) (xy 395.199659 -3.956818) (xy 395.254449 -3.973782)
			(xy 395.306088 -3.998744) (xy 395.353415 -4.031145) (xy 395.395368 -4.070255) (xy 395.431003 -4.115197)
			(xy 395.459521 -4.164961) (xy 395.47038 -4.191508) (xy 395.475438 -4.20265) (xy 395.493758 -4.218823)
			(xy 395.505432 -4.222496) (xy 395.544079 -4.232699) (xy 395.619167 -4.26011) (xy 395.690985 -4.295208)
			(xy 395.725142 -4.315968) (xy 395.733403 -4.320664) (xy 395.752066 -4.324172) (xy 395.770729 -4.320664)
			(xy 395.77899 -4.315968) (xy 395.811487 -4.296173) (xy 395.879674 -4.262388) (xy 395.950883 -4.235555)
			(xy 395.987524 -4.22529) (xy 395.999071 -4.221547) (xy 396.017123 -4.205384) (xy 396.022068 -4.194302)
			(xy 396.032844 -4.16752) (xy 396.06118 -4.11723) (xy 396.096761 -4.071776) (xy 396.138777 -4.032194)
			(xy 396.186271 -3.999386) (xy 396.238161 -3.974098) (xy 396.293266 -3.956907) (xy 396.35033 -3.948205)
			(xy 396.379192 -3.947668) (xy 396.406464 -3.948109) (xy 396.460453 -3.955871) (xy 396.512788 -3.971238)
			(xy 396.562403 -3.993896) (xy 396.608289 -4.023386) (xy 396.64951 -4.059106) (xy 396.685227 -4.100329)
			(xy 396.714714 -4.146216) (xy 396.73737 -4.195832) (xy 396.752734 -4.248168) (xy 396.760493 -4.302158)
			(xy 396.760954 -4.32943) (xy 396.760954 -4.329684) (xy 396.760599 -4.352127) (xy 396.755245 -4.396693)
			(xy 396.750286 -4.418584) (xy 396.748149 -4.430576) (xy 396.753977 -4.454187) (xy 396.761462 -4.463796)
			(xy 396.78049 -4.486154) (xy 396.815456 -4.533322) (xy 396.831312 -4.55803) (xy 396.836324 -4.565351)
			(xy 396.850295 -4.576269) (xy 396.867143 -4.581793) (xy 396.876016 -4.581906) (xy 396.889478 -4.581652)
			(xy 396.916751 -4.582086) (xy 396.970742 -4.589846) (xy 397.023079 -4.605211) (xy 397.072697 -4.627868)
			(xy 397.118585 -4.657356) (xy 397.15981 -4.693075) (xy 397.195531 -4.734297) (xy 397.225021 -4.780183)
			(xy 397.247681 -4.8298) (xy 397.263049 -4.882136) (xy 397.270812 -4.936127) (xy 397.270812 -4.990673)
			(xy 397.263049 -5.044664) (xy 397.247681 -5.097) (xy 397.225021 -5.146617) (xy 397.195531 -5.192503)
			(xy 397.15981 -5.233725) (xy 397.118585 -5.269444) (xy 397.072697 -5.298932) (xy 397.023079 -5.321589)
			(xy 396.970742 -5.336954) (xy 396.916751 -5.344714) (xy 396.889478 -5.345176) (xy 396.876016 -5.344922)
			(xy 396.867132 -5.344961) (xy 396.850253 -5.350474) (xy 396.836285 -5.361436) (xy 396.831312 -5.368798)
			(xy 396.815464 -5.393512) (xy 396.780498 -5.44068) (xy 396.761462 -5.463032) (xy 396.754023 -5.472666)
			(xy 396.748179 -5.496257) (xy 396.750286 -5.508244) (xy 396.75524 -5.5302) (xy 396.760593 -5.574893)
			(xy 396.760954 -5.597398) (xy 396.760954 -5.597652) (xy 396.7607 -5.60832) (xy 396.760977 -5.619209)
			(xy 396.769518 -5.639218) (xy 396.77721 -5.646928) (xy 396.833852 -5.698998) (xy 396.842244 -5.705905)
			(xy 396.862885 -5.712634) (xy 396.87373 -5.711952) (xy 396.874238 -5.711952) (xy 396.885121 -5.710769)
			(xy 396.906979 -5.709497) (xy 396.917926 -5.709412) (xy 396.946741 -5.709933) (xy 397.003714 -5.718607)
			(xy 397.058739 -5.735737) (xy 397.110567 -5.760937) (xy 397.158023 -5.793635) (xy 397.20003 -5.833088)
			(xy 397.235636 -5.878402) (xy 397.264034 -5.928549) (xy 397.274796 -5.955284) (xy 397.279763 -5.96635)
			(xy 397.297806 -5.982515) (xy 397.30934 -5.986272) (xy 397.346438 -5.99649) (xy 397.418528 -6.023413)
			(xy 397.487541 -6.057456) (xy 397.520414 -6.077458) (xy 397.52867 -6.082172) (xy 397.547338 -6.085699)
			(xy 397.566006 -6.082172) (xy 397.574262 -6.077458) (xy 397.607139 -6.057465) (xy 397.676157 -6.023436)
			(xy 397.748244 -5.996509) (xy 397.785336 -5.986272) (xy 397.796889 -5.982543) (xy 397.814938 -5.966371)
			(xy 397.81988 -5.955284) (xy 397.830614 -5.928535) (xy 397.859003 -5.878377) (xy 397.894606 -5.833054)
			(xy 397.936616 -5.793596) (xy 397.984079 -5.760898) (xy 398.035916 -5.735705) (xy 398.090951 -5.718587)
			(xy 398.147932 -5.709933) (xy 398.17675 -5.709412) (xy 398.18757 -5.709513) (xy 398.209173 -5.710782)
			(xy 398.21993 -5.711952) (xy 398.230852 -5.713222) (xy 398.25168 -5.706364) (xy 398.31645 -5.646674)
			(xy 398.32408 -5.639) (xy 398.332624 -5.619137) (xy 398.33296 -5.60832) (xy 398.33296 -5.608066)
			(xy 398.332706 -5.597398) (xy 398.332706 -5.59689) (xy 398.33305 -5.572356) (xy 398.339297 -5.523689)
			(xy 398.345152 -5.499862) (xy 398.347579 -5.487921) (xy 398.342264 -5.464175) (xy 398.334992 -5.454396)
			(xy 398.318153 -5.433958) (xy 398.287008 -5.391121) (xy 398.272762 -5.368798) (xy 398.267724 -5.361498)
			(xy 398.253762 -5.350582) (xy 398.236926 -5.345046) (xy 398.228058 -5.344922) (xy 398.214596 -5.345176)
			(xy 398.187328 -5.344661) (xy 398.133347 -5.336899) (xy 398.081019 -5.321534) (xy 398.031412 -5.298879)
			(xy 397.985533 -5.269394) (xy 397.944317 -5.23368) (xy 397.908604 -5.192464) (xy 397.879119 -5.146585)
			(xy 397.856464 -5.096977) (xy 397.8411 -5.044649) (xy 397.833338 -4.990668) (xy 397.833338 -4.936132)
			(xy 397.8411 -4.882151) (xy 397.856464 -4.829823) (xy 397.879119 -4.780215) (xy 397.908604 -4.734336)
			(xy 397.944317 -4.69312) (xy 397.985533 -4.657406) (xy 398.031412 -4.627921) (xy 398.081019 -4.605266)
			(xy 398.133347 -4.589901) (xy 398.187328 -4.582139) (xy 398.214596 -4.581652) (xy 398.228058 -4.581906)
			(xy 398.236944 -4.581907) (xy 398.253824 -4.576373) (xy 398.26779 -4.565398) (xy 398.272762 -4.55803)
			(xy 398.287003 -4.535703) (xy 398.318145 -4.492864) (xy 398.334992 -4.472432) (xy 398.342268 -4.462654)
			(xy 398.347582 -4.438908) (xy 398.345152 -4.426966) (xy 398.339328 -4.403133) (xy 398.333086 -4.354469)
			(xy 398.332706 -4.329938) (xy 398.332706 -4.32943) (xy 398.333252 -4.302163) (xy 398.341009 -4.248183)
			(xy 398.356369 -4.195857) (xy 398.379019 -4.146249) (xy 398.408499 -4.100369) (xy 398.444208 -4.059152)
			(xy 398.485419 -4.023436) (xy 398.531294 -3.993949) (xy 398.580898 -3.971291) (xy 398.633222 -3.955922)
			(xy 398.687201 -3.948157) (xy 398.714468 -3.947668) (xy 398.743146 -3.948238) (xy 398.799855 -3.956821)
			(xy 398.854645 -3.973784) (xy 398.906283 -3.998746) (xy 398.953611 -4.031146) (xy 398.995563 -4.070256)
			(xy 399.031199 -4.115198) (xy 399.059717 -4.164961) (xy 399.070576 -4.191508) (xy 399.075636 -4.202649)
			(xy 399.093954 -4.218823) (xy 399.105628 -4.222496) (xy 399.144223 -4.232676) (xy 399.21922 -4.260007)
			(xy 399.29096 -4.295008) (xy 399.325084 -4.315714) (xy 399.33334 -4.320428) (xy 399.352008 -4.323955)
			(xy 399.370676 -4.320428) (xy 399.378932 -4.315714) (xy 399.411502 -4.295886) (xy 399.479858 -4.262087)
			(xy 399.551242 -4.235267) (xy 399.587974 -4.225036) (xy 399.599454 -4.221266) (xy 399.617356 -4.205089)
			(xy 399.622264 -4.194048) (xy 399.633001 -4.167262) (xy 399.661371 -4.117012) (xy 399.696977 -4.071601)
			(xy 399.739007 -4.032061) (xy 399.786505 -3.999292) (xy 399.838392 -3.974039) (xy 399.893486 -3.956877)
			(xy 399.950535 -3.948196) (xy 399.979388 -3.947668) (xy 400.00666 -3.948113) (xy 400.060649 -3.955874)
			(xy 400.112984 -3.97124) (xy 400.162599 -3.993899) (xy 400.208484 -4.023388) (xy 400.249705 -4.059107)
			(xy 400.285423 -4.10033) (xy 400.31491 -4.146217) (xy 400.337566 -4.195833) (xy 400.35293 -4.248168)
			(xy 400.360689 -4.302158) (xy 400.36115 -4.32943) (xy 400.36115 -4.330192) (xy 400.360773 -4.352571)
			(xy 400.355427 -4.397009) (xy 400.350482 -4.418838) (xy 400.34831 -4.430826) (xy 400.354162 -4.454443)
			(xy 400.361658 -4.46405) (xy 400.380613 -4.486353) (xy 400.41545 -4.533394) (xy 400.431254 -4.55803)
			(xy 400.436302 -4.565323) (xy 400.450256 -4.576246) (xy 400.46709 -4.581784) (xy 400.475958 -4.581906)
			(xy 400.48942 -4.581652) (xy 400.516689 -4.582112) (xy 400.570673 -4.589876) (xy 400.623002 -4.605244)
			(xy 400.672611 -4.627902) (xy 400.718491 -4.657389) (xy 400.759708 -4.693106) (xy 400.795423 -4.734325)
			(xy 400.824908 -4.780206) (xy 400.847563 -4.829817) (xy 400.862928 -4.882147) (xy 400.87069 -4.936131)
			(xy 400.87069 -4.990669) (xy 400.862928 -5.044653) (xy 400.847563 -5.096983) (xy 400.824908 -5.146594)
			(xy 400.795423 -5.192475) (xy 400.759708 -5.233694) (xy 400.718491 -5.269411) (xy 400.672611 -5.298898)
			(xy 400.623002 -5.321556) (xy 400.570673 -5.336924) (xy 400.516689 -5.344688) (xy 400.48942 -5.345176)
			(xy 400.475958 -5.344922) (xy 400.467071 -5.34492) (xy 400.450191 -5.350452) (xy 400.436224 -5.361429)
			(xy 400.431254 -5.368798) (xy 400.415459 -5.39344) (xy 400.380621 -5.440482) (xy 400.361658 -5.462778)
			(xy 400.354192 -5.472395) (xy 400.348364 -5.496) (xy 400.350482 -5.50799) (xy 400.355421 -5.52982)
			(xy 400.360769 -5.574258) (xy 400.36115 -5.596636) (xy 400.36115 -5.597398) (xy 400.360896 -5.608066)
			(xy 400.360896 -5.60832) (xy 400.361155 -5.61915) (xy 400.369731 -5.639025) (xy 400.377406 -5.646674)
			(xy 400.434048 -5.698998) (xy 400.442441 -5.705903) (xy 400.463081 -5.712633) (xy 400.473926 -5.711952)
			(xy 400.474434 -5.711952) (xy 400.48519 -5.710777) (xy 400.506794 -5.709508) (xy 400.517614 -5.709412)
			(xy 400.517868 -5.709412) (xy 400.546684 -5.709897) (xy 400.603659 -5.718576) (xy 400.658684 -5.735713)
			(xy 400.710513 -5.760918) (xy 400.757968 -5.79362) (xy 400.799975 -5.833078) (xy 400.835581 -5.878396)
			(xy 400.863977 -5.928547) (xy 400.874738 -5.955284) (xy 400.879733 -5.966334) (xy 400.897756 -5.982506)
			(xy 400.909282 -5.986272) (xy 400.946376 -5.996503) (xy 401.018467 -6.023421) (xy 401.087482 -6.057459)
			(xy 401.120356 -6.077458) (xy 401.128612 -6.082172) (xy 401.14728 -6.085699) (xy 401.165948 -6.082172)
			(xy 401.174204 -6.077458) (xy 401.207088 -6.057476) (xy 401.276103 -6.023443) (xy 401.348187 -5.996512)
			(xy 401.385278 -5.986272) (xy 401.396838 -5.982562) (xy 401.414883 -5.966375) (xy 401.419822 -5.955284)
			(xy 401.430521 -5.92852) (xy 401.458914 -5.87836) (xy 401.494522 -5.833036) (xy 401.536537 -5.793579)
			(xy 401.584005 -5.760883) (xy 401.635847 -5.735692) (xy 401.690887 -5.718579) (xy 401.747873 -5.70993)
			(xy 401.776692 -5.709412) (xy 401.787512 -5.70951) (xy 401.809115 -5.710781) (xy 401.819872 -5.711952)
			(xy 401.830794 -5.713222) (xy 401.851622 -5.706364) (xy 401.916392 -5.646674) (xy 401.924014 -5.638992)
			(xy 401.932565 -5.619135) (xy 401.932902 -5.60832) (xy 401.932902 -5.608066) (xy 401.932648 -5.597398)
			(xy 401.932648 -5.59689) (xy 401.932994 -5.572356) (xy 401.939239 -5.523689) (xy 401.945094 -5.499862)
			(xy 401.947512 -5.48792) (xy 401.942201 -5.464177) (xy 401.934934 -5.454396) (xy 401.918092 -5.43396)
			(xy 401.886949 -5.391122) (xy 401.872704 -5.368798) (xy 401.867701 -5.361471) (xy 401.853724 -5.350559)
			(xy 401.836873 -5.345037) (xy 401.828 -5.344922) (xy 401.814538 -5.345176) (xy 401.787266 -5.344687)
			(xy 401.733277 -5.33693) (xy 401.680942 -5.321567) (xy 401.631326 -5.298913) (xy 401.585439 -5.269427)
			(xy 401.544216 -5.233711) (xy 401.508496 -5.192491) (xy 401.479006 -5.146608) (xy 401.456346 -5.096994)
			(xy 401.440978 -5.04466) (xy 401.433216 -4.990672) (xy 401.433216 -4.936128) (xy 401.440978 -4.88214)
			(xy 401.456346 -4.829806) (xy 401.479006 -4.780192) (xy 401.508496 -4.734309) (xy 401.544216 -4.693089)
			(xy 401.585439 -4.657373) (xy 401.631326 -4.627887) (xy 401.680942 -4.605233) (xy 401.733277 -4.58987)
			(xy 401.787266 -4.582113) (xy 401.814538 -4.581652) (xy 401.828 -4.581906) (xy 401.836884 -4.581865)
			(xy 401.853761 -4.57635) (xy 401.86773 -4.565391) (xy 401.872704 -4.55803) (xy 401.886948 -4.535705)
			(xy 401.918088 -4.492865) (xy 401.934934 -4.472432) (xy 401.942213 -4.462656) (xy 401.947523 -4.438909)
			(xy 401.945094 -4.426966) (xy 401.939271 -4.403133) (xy 401.933028 -4.354469) (xy 401.932648 -4.329938)
			(xy 401.932648 -4.32943) (xy 401.933129 -4.302159) (xy 401.940888 -4.248173) (xy 401.956251 -4.19584)
			(xy 401.978906 -4.146226) (xy 402.008391 -4.100342) (xy 402.044107 -4.059121) (xy 402.085326 -4.023403)
			(xy 402.131208 -3.993915) (xy 402.180821 -3.971258) (xy 402.233153 -3.955892) (xy 402.287139 -3.948131)
			(xy 402.31441 -3.947668) (xy 402.343089 -3.948202) (xy 402.3998 -3.956791) (xy 402.45459 -3.97376)
			(xy 402.506229 -3.998727) (xy 402.553556 -4.031132) (xy 402.595508 -4.070247) (xy 402.631143 -4.115192)
			(xy 402.65966 -4.164959) (xy 402.670518 -4.191508) (xy 402.675606 -4.202633) (xy 402.693905 -4.218813)
			(xy 402.70557 -4.222496) (xy 402.744161 -4.23269) (xy 402.81916 -4.260015) (xy 402.890901 -4.295011)
			(xy 402.925026 -4.315714) (xy 402.933282 -4.320428) (xy 402.95195 -4.323955) (xy 402.970618 -4.320428)
			(xy 402.978874 -4.315714) (xy 403.011439 -4.295878) (xy 403.079797 -4.262081) (xy 403.151183 -4.235265)
			(xy 403.187916 -4.225036) (xy 403.199403 -4.221284) (xy 403.217301 -4.205094) (xy 403.222206 -4.194048)
			(xy 403.232908 -4.167247) (xy 403.261283 -4.116996) (xy 403.296892 -4.071584) (xy 403.338927 -4.032044)
			(xy 403.386431 -3.999276) (xy 403.438323 -3.974026) (xy 403.493422 -3.956869) (xy 403.550475 -3.948193)
			(xy 403.57933 -3.947668) (xy 403.606601 -3.948097) (xy 403.660589 -3.955863) (xy 403.712921 -3.971234)
			(xy 403.762533 -3.993896) (xy 403.808416 -4.023387) (xy 403.849634 -4.059109) (xy 403.885349 -4.100332)
			(xy 403.914833 -4.146219) (xy 403.937487 -4.195835) (xy 403.95285 -4.24817) (xy 403.960608 -4.302158)
			(xy 403.961092 -4.32943) (xy 403.961092 -4.330192) (xy 403.960716 -4.352571) (xy 403.955369 -4.397009)
			(xy 403.950424 -4.418838) (xy 403.948242 -4.430826) (xy 403.954099 -4.454445) (xy 403.9616 -4.46405)
			(xy 403.980557 -4.486351) (xy 404.015393 -4.533393) (xy 404.031196 -4.55803) (xy 404.036218 -4.565343)
			(xy 404.050184 -4.576263) (xy 404.067029 -4.58179) (xy 404.0759 -4.581906) (xy 404.089362 -4.581652)
			(xy 404.116636 -4.582085) (xy 404.170629 -4.589843) (xy 404.222968 -4.605206) (xy 404.272588 -4.627863)
			(xy 404.318478 -4.65735) (xy 404.359704 -4.693069) (xy 404.395427 -4.734292) (xy 404.424919 -4.780179)
			(xy 404.44758 -4.829796) (xy 404.462949 -4.882134) (xy 404.470712 -4.936126) (xy 404.470712 -4.990674)
			(xy 404.462949 -5.044666) (xy 404.44758 -5.097004) (xy 404.424919 -5.146621) (xy 404.395427 -5.192508)
			(xy 404.359704 -5.233731) (xy 404.318478 -5.26945) (xy 404.272588 -5.298937) (xy 404.222968 -5.321594)
			(xy 404.170629 -5.336957) (xy 404.116636 -5.344715) (xy 404.089362 -5.345176) (xy 404.0759 -5.344922)
			(xy 404.067015 -5.34495) (xy 404.050136 -5.350468) (xy 404.036168 -5.361434) (xy 404.031196 -5.368798)
			(xy 404.015399 -5.393439) (xy 403.980562 -5.440481) (xy 403.9616 -5.462778) (xy 403.954137 -5.472397)
			(xy 403.948306 -5.496) (xy 403.950424 -5.50799) (xy 403.955385 -5.529945) (xy 403.960734 -5.574638)
			(xy 403.961092 -5.597144) (xy 403.961092 -5.597652) (xy 403.960838 -5.60832) (xy 403.961104 -5.61921)
			(xy 403.969651 -5.639221) (xy 403.977348 -5.646928) (xy 404.03399 -5.698998) (xy 404.042368 -5.705925)
			(xy 404.06302 -5.712641) (xy 404.073868 -5.711952) (xy 404.074376 -5.711952) (xy 404.085259 -5.710766)
			(xy 404.107117 -5.709496) (xy 404.118064 -5.709412) (xy 404.14688 -5.7099) (xy 404.203855 -5.718579)
			(xy 404.25888 -5.735715) (xy 404.310708 -5.76092) (xy 404.358164 -5.793622) (xy 404.400171 -5.833079)
			(xy 404.435776 -5.878397) (xy 404.464173 -5.928548) (xy 404.474934 -5.955284) (xy 404.479931 -5.966333)
			(xy 404.497953 -5.982505) (xy 404.509478 -5.986272) (xy 404.546572 -5.996504) (xy 404.618663 -6.023421)
			(xy 404.687678 -6.057459) (xy 404.720552 -6.077458) (xy 404.728808 -6.082172) (xy 404.747476 -6.085699)
			(xy 404.766144 -6.082172) (xy 404.7744 -6.077458) (xy 404.807284 -6.057477) (xy 404.876299 -6.023444)
			(xy 404.948383 -5.996512) (xy 404.985474 -5.986272) (xy 404.997034 -5.98256) (xy 405.015079 -5.966375)
			(xy 405.020018 -5.955284) (xy 405.03072 -5.928522) (xy 405.059113 -5.878362) (xy 405.094721 -5.833038)
			(xy 405.136735 -5.79358) (xy 405.184203 -5.760885) (xy 405.236044 -5.735694) (xy 405.291083 -5.718579)
			(xy 405.348069 -5.709931) (xy 405.376888 -5.709412) (xy 405.377142 -5.709412) (xy 405.388025 -5.709509)
			(xy 405.409756 -5.710777) (xy 405.420576 -5.711952) (xy 405.42083 -5.711952) (xy 405.431681 -5.712648)
			(xy 405.452342 -5.705943) (xy 405.460708 -5.698998) (xy 405.51735 -5.646674) (xy 405.52498 -5.639)
			(xy 405.533524 -5.619137) (xy 405.53386 -5.60832) (xy 405.53386 -5.608066) (xy 405.533606 -5.597398)
			(xy 405.533606 -5.59689) (xy 405.534015 -5.572549) (xy 405.540253 -5.524268) (xy 405.546052 -5.500624)
			(xy 405.548352 -5.488651) (xy 405.542937 -5.46492) (xy 405.535638 -5.455158) (xy 405.518639 -5.434553)
			(xy 405.487241 -5.391333) (xy 405.4729 -5.368798) (xy 405.4679 -5.361469) (xy 405.453921 -5.350558)
			(xy 405.43707 -5.345036) (xy 405.428196 -5.344922) (xy 405.414734 -5.345176) (xy 405.387462 -5.344687)
			(xy 405.333474 -5.336929) (xy 405.281139 -5.321566) (xy 405.231523 -5.298911) (xy 405.185637 -5.269426)
			(xy 405.144414 -5.23371) (xy 405.108695 -5.19249) (xy 405.079205 -5.146607) (xy 405.056546 -5.096993)
			(xy 405.041178 -5.044659) (xy 405.033416 -4.990672) (xy 405.033416 -4.936128) (xy 405.041178 -4.882141)
			(xy 405.056546 -4.829807) (xy 405.079205 -4.780193) (xy 405.108695 -4.73431) (xy 405.144414 -4.69309)
			(xy 405.185637 -4.657374) (xy 405.231523 -4.627889) (xy 405.281139 -4.605234) (xy 405.333474 -4.589871)
			(xy 405.387462 -4.582113) (xy 405.414734 -4.581652) (xy 405.428196 -4.581906) (xy 405.43708 -4.581862)
			(xy 405.453956 -4.576349) (xy 405.467925 -4.56539) (xy 405.4729 -4.55803) (xy 405.48725 -4.535501)
			(xy 405.51865 -4.492283) (xy 405.535638 -4.47167) (xy 405.542984 -4.461926) (xy 405.548421 -4.438175)
			(xy 405.546052 -4.426204) (xy 405.540273 -4.402556) (xy 405.534025 -4.354278) (xy 405.533606 -4.329938)
			(xy 405.533606 -4.32943) (xy 405.534152 -4.302163) (xy 405.541909 -4.248183) (xy 405.557269 -4.195857)
			(xy 405.579919 -4.146249) (xy 405.609399 -4.100369) (xy 405.645108 -4.059152) (xy 405.686319 -4.023436)
			(xy 405.732194 -3.993949) (xy 405.781798 -3.971291) (xy 405.834122 -3.955922) (xy 405.888101 -3.948157)
			(xy 405.915368 -3.947668) (xy 405.944046 -3.948238) (xy 406.000755 -3.956821) (xy 406.055545 -3.973784)
			(xy 406.107183 -3.998746) (xy 406.154511 -4.031146) (xy 406.196463 -4.070256) (xy 406.232099 -4.115198)
			(xy 406.260617 -4.164961) (xy 406.271476 -4.191508) (xy 406.276381 -4.202761) (xy 406.294761 -4.218996)
			(xy 406.306528 -4.222496) (xy 406.344988 -4.232722) (xy 406.419725 -4.260074) (xy 406.491216 -4.295044)
			(xy 406.525222 -4.315714) (xy 406.533443 -4.320485) (xy 406.5521 -4.324063) (xy 406.570785 -4.32063)
			(xy 406.57907 -4.315968) (xy 406.611712 -4.296075) (xy 406.680232 -4.262176) (xy 406.751794 -4.235289)
			(xy 406.78862 -4.225036) (xy 406.800178 -4.221317) (xy 406.818226 -4.205138) (xy 406.823164 -4.194048)
			(xy 406.833901 -4.167262) (xy 406.862271 -4.117012) (xy 406.897877 -4.071601) (xy 406.939907 -4.032061)
			(xy 406.987405 -3.999292) (xy 407.039292 -3.974039) (xy 407.094386 -3.956877) (xy 407.151435 -3.948196)
			(xy 407.180288 -3.947668) (xy 407.20756 -3.948113) (xy 407.261549 -3.955874) (xy 407.313884 -3.97124)
			(xy 407.363499 -3.993899) (xy 407.409384 -4.023388) (xy 407.450605 -4.059107) (xy 407.486323 -4.10033)
			(xy 407.51581 -4.146217) (xy 407.538466 -4.195833) (xy 407.55383 -4.248168) (xy 407.561589 -4.302158)
			(xy 407.56205 -4.32943) (xy 407.56205 -4.329684) (xy 407.561736 -4.352318) (xy 407.556386 -4.397269)
			(xy 407.551382 -4.419346) (xy 407.549139 -4.431308) (xy 407.554858 -4.454929) (xy 407.562304 -4.464558)
			(xy 407.58112 -4.486745) (xy 407.615701 -4.533533) (xy 407.631392 -4.55803) (xy 407.636417 -4.565341)
			(xy 407.650382 -4.576261) (xy 407.667225 -4.58179) (xy 407.676096 -4.581906) (xy 407.689558 -4.581652)
			(xy 407.716832 -4.582085) (xy 407.770825 -4.589842) (xy 407.823165 -4.605205) (xy 407.872785 -4.627861)
			(xy 407.918676 -4.657349) (xy 407.959903 -4.693068) (xy 407.995626 -4.73429) (xy 408.025118 -4.780178)
			(xy 408.04778 -4.829796) (xy 408.063149 -4.882134) (xy 408.070912 -4.936126) (xy 408.070912 -4.990674)
			(xy 408.063149 -5.044666) (xy 408.04778 -5.097004) (xy 408.025118 -5.146622) (xy 407.995626 -5.19251)
			(xy 407.959903 -5.233732) (xy 407.918676 -5.269451) (xy 407.872785 -5.298939) (xy 407.823165 -5.321595)
			(xy 407.770825 -5.336958) (xy 407.716832 -5.344715) (xy 407.689558 -5.345176) (xy 407.676096 -5.344922)
			(xy 407.667211 -5.344947) (xy 407.650332 -5.350467) (xy 407.636364 -5.361433) (xy 407.631392 -5.368798)
			(xy 407.6157 -5.393294) (xy 407.581118 -5.440081) (xy 407.562304 -5.46227) (xy 407.554878 -5.471902)
			(xy 407.549192 -5.495517) (xy 407.551382 -5.507482) (xy 407.556365 -5.529562) (xy 407.561714 -5.574511)
			(xy 407.56205 -5.597144) (xy 407.56205 -5.597398) (xy 407.561597 -5.62467) (xy 407.553834 -5.678657)
			(xy 407.538468 -5.730991) (xy 407.51581 -5.780605) (xy 407.486321 -5.826489) (xy 407.450603 -5.86771)
			(xy 407.409381 -5.903427) (xy 407.363496 -5.932914) (xy 407.313882 -5.955571) (xy 407.261548 -5.970937)
			(xy 407.20756 -5.978697) (xy 407.180288 -5.97916) (xy 407.151436 -5.978613) (xy 407.094389 -5.969933)
			(xy 407.039296 -5.952772) (xy 406.987411 -5.927522) (xy 406.939912 -5.894755) (xy 406.897882 -5.855218)
			(xy 406.862276 -5.80981) (xy 406.833904 -5.759564) (xy 406.823164 -5.73278) (xy 406.818145 -5.721743)
			(xy 406.80014 -5.705563) (xy 406.78862 -5.701792) (xy 406.751795 -5.691538) (xy 406.68023 -5.664657)
			(xy 406.611711 -5.630755) (xy 406.57907 -5.61086) (xy 406.570773 -5.606223) (xy 406.5521 -5.60277)
			(xy 406.533455 -5.606369) (xy 406.525222 -5.611114) (xy 406.491219 -5.631792) (xy 406.419732 -5.666773)
			(xy 406.344993 -5.694122) (xy 406.306528 -5.704332) (xy 406.294865 -5.708023) (xy 406.27656 -5.724194)
			(xy 406.271476 -5.73532) (xy 406.260603 -5.761865) (xy 406.232105 -5.811647) (xy 406.196481 -5.856607)
			(xy 406.154534 -5.895732) (xy 406.107206 -5.928143) (xy 406.055563 -5.95311) (xy 406.000766 -5.970072)
			(xy 405.944049 -5.978647) (xy 405.915368 -5.97916) (xy 405.915114 -5.97916) (xy 405.90423 -5.979067)
			(xy 405.8825 -5.977796) (xy 405.87168 -5.97662) (xy 405.871426 -5.97662) (xy 405.860574 -5.97588)
			(xy 405.839909 -5.982613) (xy 405.831548 -5.989574) (xy 405.774906 -6.041898) (xy 405.767297 -6.04959)
			(xy 405.758738 -6.069439) (xy 405.758396 -6.080252) (xy 405.758396 -6.080506) (xy 405.75865 -6.09092)
			(xy 405.75865 -6.091428) (xy 405.758142 -6.110224) (xy 405.757634 -6.121146) (xy 405.765254 -6.140958)
			(xy 405.834088 -6.210046) (xy 405.854154 -6.217412) (xy 405.865076 -6.216904) (xy 405.884634 -6.216396)
			(xy 405.884888 -6.216396) (xy 405.912155 -6.216935) (xy 405.966135 -6.224694) (xy 406.018461 -6.240056)
			(xy 406.068068 -6.262708) (xy 406.113947 -6.292189) (xy 406.155164 -6.327898) (xy 406.190879 -6.36911)
			(xy 406.220366 -6.414985) (xy 406.243025 -6.464589) (xy 406.258394 -6.516912) (xy 406.266161 -6.570891)
			(xy 406.26665 -6.598158) (xy 412.338266 -6.598158) (xy 412.338685 -6.570886) (xy 412.346454 -6.516899)
			(xy 412.361826 -6.464566) (xy 412.384489 -6.414954) (xy 412.413982 -6.369072) (xy 412.449704 -6.327854)
			(xy 412.490928 -6.29214) (xy 412.536816 -6.262655) (xy 412.586432 -6.240001) (xy 412.638767 -6.224639)
			(xy 412.692756 -6.21688) (xy 412.720028 -6.216396) (xy 412.720282 -6.216396) (xy 412.73984 -6.216904)
			(xy 412.750762 -6.217412) (xy 412.770828 -6.210046) (xy 412.839662 -6.140958) (xy 412.847282 -6.121146)
			(xy 412.846774 -6.110224) (xy 412.846266 -6.091174) (xy 412.846677 -6.063901) (xy 412.854444 -6.009911)
			(xy 412.869815 -5.957576) (xy 412.892477 -5.90796) (xy 412.92197 -5.862076) (xy 412.957693 -5.820855)
			(xy 412.998919 -5.785138) (xy 413.044808 -5.755652) (xy 413.094426 -5.732996) (xy 413.146764 -5.717632)
			(xy 413.200755 -5.709874) (xy 413.228028 -5.709412) (xy 413.256843 -5.709932) (xy 413.313816 -5.718605)
			(xy 413.368841 -5.735736) (xy 413.420669 -5.760936) (xy 413.468125 -5.793634) (xy 413.510132 -5.833087)
			(xy 413.545738 -5.878402) (xy 413.574136 -5.928549) (xy 413.584898 -5.955284) (xy 413.589864 -5.96635)
			(xy 413.607907 -5.982515) (xy 413.619442 -5.986272) (xy 413.65654 -5.99649) (xy 413.72863 -6.023413)
			(xy 413.797643 -6.057456) (xy 413.830516 -6.077458) (xy 413.838772 -6.082172) (xy 413.85744 -6.085699)
			(xy 413.876108 -6.082172) (xy 413.884364 -6.077458) (xy 413.91724 -6.057464) (xy 413.986259 -6.023436)
			(xy 414.058346 -5.996509) (xy 414.095438 -5.986272) (xy 414.106991 -5.982544) (xy 414.125041 -5.966371)
			(xy 414.129982 -5.955284) (xy 414.140714 -5.928535) (xy 414.169103 -5.878376) (xy 414.204707 -5.833053)
			(xy 414.246717 -5.793595) (xy 414.29418 -5.760898) (xy 414.346018 -5.735704) (xy 414.401052 -5.718587)
			(xy 414.458034 -5.709933) (xy 414.486852 -5.709412) (xy 414.497608 -5.709515) (xy 414.519084 -5.710788)
			(xy 414.529778 -5.711952) (xy 414.5407 -5.713222) (xy 414.561528 -5.706364) (xy 414.626298 -5.646674)
			(xy 414.63392 -5.638993) (xy 414.642471 -5.619136) (xy 414.642808 -5.60832) (xy 414.642808 -5.608066)
			(xy 414.642554 -5.597652) (xy 414.642554 -5.597398) (xy 414.642944 -5.572667) (xy 414.649315 -5.523618)
			(xy 414.655254 -5.499608) (xy 414.657884 -5.487605) (xy 414.652563 -5.463644) (xy 414.645094 -5.453888)
			(xy 414.628255 -5.433583) (xy 414.597113 -5.390998) (xy 414.582864 -5.368798) (xy 414.577825 -5.361499)
			(xy 414.563864 -5.350583) (xy 414.547028 -5.345046) (xy 414.53816 -5.344922) (xy 414.524698 -5.345176)
			(xy 414.49743 -5.344661) (xy 414.443448 -5.3369) (xy 414.391121 -5.321535) (xy 414.341513 -5.298879)
			(xy 414.295634 -5.269395) (xy 414.254418 -5.233681) (xy 414.218704 -5.192465) (xy 414.18922 -5.146585)
			(xy 414.166564 -5.096977) (xy 414.1512 -5.04465) (xy 414.143438 -4.990668) (xy 414.143438 -4.936132)
			(xy 414.1512 -4.88215) (xy 414.166564 -4.829823) (xy 414.18922 -4.780215) (xy 414.218704 -4.734335)
			(xy 414.254418 -4.693119) (xy 414.295634 -4.657405) (xy 414.341513 -4.627921) (xy 414.391121 -4.605265)
			(xy 414.443448 -4.5899) (xy 414.49743 -4.582139) (xy 414.524698 -4.581652) (xy 414.53816 -4.581906)
			(xy 414.547042 -4.581836) (xy 414.563917 -4.576334) (xy 414.577888 -4.565386) (xy 414.582864 -4.55803)
			(xy 414.597126 -4.535839) (xy 414.628268 -4.493256) (xy 414.645094 -4.47294) (xy 414.652379 -4.463096)
			(xy 414.657683 -4.439224) (xy 414.655254 -4.42722) (xy 414.649333 -4.403401) (xy 414.642964 -4.354733)
			(xy 414.642554 -4.330192) (xy 414.642554 -4.32943) (xy 414.643029 -4.302159) (xy 414.650788 -4.248172)
			(xy 414.666151 -4.195838) (xy 414.688806 -4.146224) (xy 414.718292 -4.10034) (xy 414.754009 -4.059119)
			(xy 414.795228 -4.023401) (xy 414.841112 -3.993913) (xy 414.890725 -3.971256) (xy 414.943058 -3.955891)
			(xy 414.997045 -3.94813) (xy 415.024316 -3.947668) (xy 415.052995 -3.948196) (xy 415.109706 -3.956787)
			(xy 415.164497 -3.973756) (xy 415.216136 -3.998724) (xy 415.263463 -4.03113) (xy 415.305415 -4.070245)
			(xy 415.341049 -4.115191) (xy 415.369566 -4.164959) (xy 415.380424 -4.191508) (xy 415.385509 -4.202634)
			(xy 415.40381 -4.218814) (xy 415.415476 -4.222496) (xy 415.454119 -4.232712) (xy 415.529209 -4.260117)
			(xy 415.601028 -4.295211) (xy 415.635186 -4.315968) (xy 415.643447 -4.320664) (xy 415.66211 -4.324172)
			(xy 415.680773 -4.320664) (xy 415.689034 -4.315968) (xy 415.721526 -4.296164) (xy 415.789715 -4.262382)
			(xy 415.860926 -4.235553) (xy 415.897568 -4.22529) (xy 415.909123 -4.221567) (xy 415.92717 -4.205389)
			(xy 415.932112 -4.194302) (xy 415.942851 -4.167505) (xy 415.971191 -4.117212) (xy 416.006777 -4.071758)
			(xy 416.048799 -4.032177) (xy 416.096298 -3.99937) (xy 416.148194 -3.974085) (xy 416.203304 -3.956899)
			(xy 416.260372 -3.948201) (xy 416.289236 -3.947668) (xy 416.316508 -3.948091) (xy 416.370495 -3.955858)
			(xy 416.422828 -3.97123) (xy 416.47244 -3.993892) (xy 416.518322 -4.023385) (xy 416.55954 -4.059107)
			(xy 416.595255 -4.100331) (xy 416.624739 -4.146218) (xy 416.647393 -4.195834) (xy 416.662756 -4.24817)
			(xy 416.670514 -4.302158) (xy 416.670998 -4.32943) (xy 416.670998 -4.329684) (xy 416.670642 -4.352127)
			(xy 416.665289 -4.396693) (xy 416.66033 -4.418584) (xy 416.658182 -4.430575) (xy 416.664016 -4.454189)
			(xy 416.671506 -4.463796) (xy 416.690536 -4.486152) (xy 416.7255 -4.533321) (xy 416.741356 -4.55803)
			(xy 416.746403 -4.565324) (xy 416.760358 -4.576247) (xy 416.777192 -4.581784) (xy 416.78606 -4.581906)
			(xy 416.799522 -4.581652) (xy 416.826791 -4.582112) (xy 416.880775 -4.589876) (xy 416.933103 -4.605244)
			(xy 416.982713 -4.627903) (xy 417.028592 -4.65739) (xy 417.069809 -4.693107) (xy 417.105523 -4.734325)
			(xy 417.135008 -4.780207) (xy 417.157663 -4.829817) (xy 417.173028 -4.882147) (xy 417.18079 -4.936131)
			(xy 417.18079 -4.990669) (xy 417.173028 -5.044653) (xy 417.157663 -5.096983) (xy 417.135008 -5.146593)
			(xy 417.105523 -5.192475) (xy 417.069809 -5.233693) (xy 417.028592 -5.26941) (xy 416.982713 -5.298897)
			(xy 416.933103 -5.321556) (xy 416.880775 -5.336924) (xy 416.826791 -5.344688) (xy 416.799522 -5.345176)
			(xy 416.78606 -5.344922) (xy 416.777173 -5.344922) (xy 416.760293 -5.350453) (xy 416.746326 -5.361429)
			(xy 416.741356 -5.368798) (xy 416.725506 -5.393511) (xy 416.690541 -5.44068) (xy 416.671506 -5.463032)
			(xy 416.66407 -5.472669) (xy 416.658222 -5.496258) (xy 416.66033 -5.508244) (xy 416.665284 -5.530201)
			(xy 416.670637 -5.574893) (xy 416.670998 -5.597398) (xy 416.670998 -5.597652) (xy 416.670744 -5.60832)
			(xy 416.671008 -5.61921) (xy 416.679556 -5.639221) (xy 416.687254 -5.646928) (xy 416.743896 -5.698998)
			(xy 416.752272 -5.705928) (xy 416.772926 -5.712643) (xy 416.783774 -5.711952) (xy 416.784282 -5.711952)
			(xy 416.795165 -5.710765) (xy 416.817023 -5.709496) (xy 416.82797 -5.709412) (xy 416.856786 -5.709895)
			(xy 416.913761 -5.718575) (xy 416.968787 -5.735712) (xy 417.020615 -5.760917) (xy 417.068071 -5.79362)
			(xy 417.110077 -5.833078) (xy 417.145683 -5.878396) (xy 417.174079 -5.928547) (xy 417.18484 -5.955284)
			(xy 417.189834 -5.966334) (xy 417.207858 -5.982506) (xy 417.219384 -5.986272) (xy 417.256478 -5.996503)
			(xy 417.328569 -6.02342) (xy 417.397585 -6.057458) (xy 417.430458 -6.077458) (xy 417.438714 -6.082172)
			(xy 417.457382 -6.085699) (xy 417.47605 -6.082172) (xy 417.484306 -6.077458) (xy 417.517189 -6.057476)
			(xy 417.586205 -6.023443) (xy 417.658289 -5.996511) (xy 417.69538 -5.986272) (xy 417.706941 -5.982563)
			(xy 417.724986 -5.966375) (xy 417.729924 -5.955284) (xy 417.740621 -5.92852) (xy 417.769014 -5.878359)
			(xy 417.804623 -5.833036) (xy 417.846638 -5.793578) (xy 417.894106 -5.760882) (xy 417.945949 -5.735692)
			(xy 418.000988 -5.718578) (xy 418.057975 -5.70993) (xy 418.086794 -5.709412) (xy 418.097614 -5.70951)
			(xy 418.119217 -5.710781) (xy 418.129974 -5.711952) (xy 418.140896 -5.713222) (xy 418.161724 -5.706364)
			(xy 418.226494 -5.646674) (xy 418.234116 -5.638993) (xy 418.242667 -5.619135) (xy 418.243004 -5.60832)
			(xy 418.243004 -5.608066) (xy 418.24275 -5.597398) (xy 418.24275 -5.59689) (xy 418.243096 -5.572356)
			(xy 418.249341 -5.523689) (xy 418.255196 -5.499862) (xy 418.257614 -5.48792) (xy 418.252303 -5.464177)
			(xy 418.245036 -5.454396) (xy 418.228194 -5.43396) (xy 418.197051 -5.391122) (xy 418.182806 -5.368798)
			(xy 418.177802 -5.361472) (xy 418.163825 -5.35056) (xy 418.146975 -5.345037) (xy 418.138102 -5.344922)
			(xy 418.12464 -5.345176) (xy 418.097368 -5.344687) (xy 418.043379 -5.33693) (xy 417.991043 -5.321568)
			(xy 417.941427 -5.298913) (xy 417.89554 -5.269428) (xy 417.854317 -5.233712) (xy 417.818596 -5.192492)
			(xy 417.789106 -5.146608) (xy 417.766446 -5.096994) (xy 417.751078 -5.04466) (xy 417.743316 -4.990672)
			(xy 417.743316 -4.936128) (xy 417.751078 -4.88214) (xy 417.766446 -4.829806) (xy 417.789106 -4.780192)
			(xy 417.818596 -4.734308) (xy 417.854317 -4.693088) (xy 417.89554 -4.657372) (xy 417.941427 -4.627887)
			(xy 417.991043 -4.605232) (xy 418.043379 -4.58987) (xy 418.097368 -4.582113) (xy 418.12464 -4.581652)
			(xy 418.138102 -4.581906) (xy 418.146986 -4.581866) (xy 418.163863 -4.576351) (xy 418.177832 -4.565391)
			(xy 418.182806 -4.55803) (xy 418.19705 -4.535705) (xy 418.22819 -4.492865) (xy 418.245036 -4.472432)
			(xy 418.252315 -4.462657) (xy 418.257625 -4.438909) (xy 418.255196 -4.426966) (xy 418.249373 -4.403133)
			(xy 418.24313 -4.354469) (xy 418.24275 -4.329938) (xy 418.24275 -4.32943) (xy 418.243229 -4.302159)
			(xy 418.250988 -4.248172) (xy 418.266351 -4.195839) (xy 418.289006 -4.146225) (xy 418.318491 -4.100341)
			(xy 418.354207 -4.05912) (xy 418.395426 -4.023402) (xy 418.441309 -3.993914) (xy 418.490922 -3.971257)
			(xy 418.543255 -3.955892) (xy 418.597241 -3.948131) (xy 418.624512 -3.947668) (xy 418.653191 -3.9482)
			(xy 418.709902 -3.956789) (xy 418.764693 -3.973759) (xy 418.816331 -3.998726) (xy 418.863659 -4.031131)
			(xy 418.905611 -4.070246) (xy 418.941245 -4.115192) (xy 418.969762 -4.164959) (xy 418.98062 -4.191508)
			(xy 418.985707 -4.202633) (xy 419.004007 -4.218813) (xy 419.015672 -4.222496) (xy 419.054263 -4.232689)
			(xy 419.129262 -4.260015) (xy 419.201003 -4.295011) (xy 419.235128 -4.315714) (xy 419.243384 -4.320428)
			(xy 419.262052 -4.323955) (xy 419.28072 -4.320428) (xy 419.288976 -4.315714) (xy 419.321553 -4.295897)
			(xy 419.389905 -4.262094) (xy 419.461287 -4.23527) (xy 419.498018 -4.225036) (xy 419.509488 -4.221241)
			(xy 419.527395 -4.205083) (xy 419.532308 -4.194048) (xy 419.543009 -4.167247) (xy 419.571383 -4.116995)
			(xy 419.606993 -4.071583) (xy 419.649028 -4.032043) (xy 419.696532 -3.999276) (xy 419.748425 -3.974026)
			(xy 419.803524 -3.956868) (xy 419.860577 -3.948193) (xy 419.889432 -3.947668) (xy 419.916704 -3.948095)
			(xy 419.970691 -3.955862) (xy 420.023023 -3.971232) (xy 420.072636 -3.993895) (xy 420.118518 -4.023387)
			(xy 420.159736 -4.059108) (xy 420.195451 -4.100332) (xy 420.224935 -4.146219) (xy 420.247589 -4.195835)
			(xy 420.262952 -4.24817) (xy 420.27071 -4.302158) (xy 420.271194 -4.32943) (xy 420.271194 -4.330192)
			(xy 420.270818 -4.352571) (xy 420.265471 -4.397009) (xy 420.260526 -4.418838) (xy 420.258343 -4.430826)
			(xy 420.264201 -4.454445) (xy 420.271702 -4.46405) (xy 420.290659 -4.486351) (xy 420.325495 -4.533393)
			(xy 420.341298 -4.55803) (xy 420.346319 -4.565344) (xy 420.360286 -4.576263) (xy 420.377131 -4.581791)
			(xy 420.386002 -4.581906) (xy 420.399464 -4.581652) (xy 420.426738 -4.582085) (xy 420.48073 -4.589843)
			(xy 420.533069 -4.605207) (xy 420.582689 -4.627863) (xy 420.628579 -4.657351) (xy 420.669805 -4.69307)
			(xy 420.705527 -4.734292) (xy 420.735019 -4.78018) (xy 420.75768 -4.829797) (xy 420.773049 -4.882134)
			(xy 420.780812 -4.936126) (xy 420.780812 -4.990674) (xy 420.773049 -5.044666) (xy 420.75768 -5.097003)
			(xy 420.735019 -5.14662) (xy 420.705527 -5.192508) (xy 420.669805 -5.23373) (xy 420.628579 -5.269449)
			(xy 420.582689 -5.298937) (xy 420.533069 -5.321593) (xy 420.48073 -5.336957) (xy 420.426738 -5.344715)
			(xy 420.399464 -5.345176) (xy 420.386002 -5.344922) (xy 420.377117 -5.344951) (xy 420.360238 -5.350469)
			(xy 420.34627 -5.361434) (xy 420.341298 -5.368798) (xy 420.325501 -5.393439) (xy 420.290664 -5.440481)
			(xy 420.271702 -5.462778) (xy 420.264239 -5.472398) (xy 420.258408 -5.496) (xy 420.260526 -5.50799)
			(xy 420.265464 -5.52982) (xy 420.270813 -5.574258) (xy 420.271194 -5.596636) (xy 420.271194 -5.597398)
			(xy 420.270674 -5.624666) (xy 420.262913 -5.678647) (xy 420.24755 -5.730974) (xy 420.224896 -5.780582)
			(xy 420.195413 -5.826461) (xy 420.159702 -5.867678) (xy 420.118488 -5.903393) (xy 420.072611 -5.93288)
			(xy 420.023005 -5.955538) (xy 419.97068 -5.970906) (xy 419.9167 -5.978671) (xy 419.889432 -5.97916)
			(xy 419.860581 -5.978575) (xy 419.803536 -5.969901) (xy 419.748444 -5.952747) (xy 419.696559 -5.927502)
			(xy 419.64906 -5.894741) (xy 419.607029 -5.855209) (xy 419.571422 -5.809805) (xy 419.543048 -5.759562)
			(xy 419.532308 -5.73278) (xy 419.527382 -5.721752) (xy 419.509486 -5.705582) (xy 419.498018 -5.701792)
			(xy 419.461287 -5.691555) (xy 419.389904 -5.664736) (xy 419.321546 -5.630941) (xy 419.288976 -5.611114)
			(xy 419.28072 -5.6064) (xy 419.262052 -5.602873) (xy 419.243384 -5.6064) (xy 419.235128 -5.611114)
			(xy 419.201005 -5.631822) (xy 419.129267 -5.666826) (xy 419.054267 -5.694152) (xy 419.015672 -5.704332)
			(xy 419.003985 -5.707983) (xy 418.985667 -5.724166) (xy 418.98062 -5.73532) (xy 418.96971 -5.761849)
			(xy 418.941216 -5.81163) (xy 418.905598 -5.856589) (xy 418.863656 -5.895714) (xy 418.816333 -5.928127)
			(xy 418.764696 -5.953097) (xy 418.709904 -5.970064) (xy 418.653191 -5.978644) (xy 418.624512 -5.97916)
			(xy 418.613692 -5.979062) (xy 418.592089 -5.977791) (xy 418.581332 -5.97662) (xy 418.57041 -5.97535)
			(xy 418.549582 -5.982208) (xy 418.484812 -6.041898) (xy 418.477204 -6.049591) (xy 418.468644 -6.069439)
			(xy 418.468302 -6.080252) (xy 418.468302 -6.080506) (xy 418.468556 -6.09092) (xy 418.468556 -6.091428)
			(xy 418.468048 -6.110224) (xy 418.46754 -6.121146) (xy 418.47516 -6.140958) (xy 418.543994 -6.210046)
			(xy 418.56406 -6.217412) (xy 418.574982 -6.216904) (xy 418.59454 -6.216396) (xy 418.594794 -6.216396)
			(xy 418.622061 -6.21693) (xy 418.676041 -6.22469) (xy 418.728367 -6.240052) (xy 418.777974 -6.262705)
			(xy 418.823853 -6.292186) (xy 418.86507 -6.327896) (xy 418.900785 -6.369108) (xy 418.930272 -6.414983)
			(xy 418.952931 -6.464588) (xy 418.9683 -6.516912) (xy 418.976067 -6.570891) (xy 418.976556 -6.598158)
			(xy 423.548302 -6.598158) (xy 423.548785 -6.570889) (xy 423.556552 -6.516907) (xy 423.571921 -6.46458)
			(xy 423.594579 -6.414972) (xy 423.624066 -6.369093) (xy 423.659781 -6.327877) (xy 423.700998 -6.292162)
			(xy 423.746877 -6.262676) (xy 423.796486 -6.240018) (xy 423.848813 -6.22465) (xy 423.902795 -6.216885)
			(xy 423.930064 -6.216396) (xy 423.930318 -6.216396) (xy 423.949876 -6.216904) (xy 423.960798 -6.217412)
			(xy 423.980864 -6.210046) (xy 424.049698 -6.140958) (xy 424.057318 -6.121146) (xy 424.05681 -6.110224)
			(xy 424.056302 -6.091174) (xy 424.0568 -6.063906) (xy 424.064564 -6.009924) (xy 424.079931 -5.957597)
			(xy 424.102588 -5.907989) (xy 424.132073 -5.86211) (xy 424.167787 -5.820894) (xy 424.209002 -5.785179)
			(xy 424.254881 -5.755693) (xy 424.304488 -5.733035) (xy 424.356815 -5.717667) (xy 424.410796 -5.709901)
			(xy 424.438064 -5.709412) (xy 424.46688 -5.7099) (xy 424.523855 -5.718579) (xy 424.57888 -5.735715)
			(xy 424.630708 -5.76092) (xy 424.678164 -5.793622) (xy 424.720171 -5.833079) (xy 424.755776 -5.878397)
			(xy 424.784173 -5.928548) (xy 424.794934 -5.955284) (xy 424.799931 -5.966333) (xy 424.817953 -5.982505)
			(xy 424.829478 -5.986272) (xy 424.866572 -5.996504) (xy 424.938663 -6.023421) (xy 425.007678 -6.057459)
			(xy 425.040552 -6.077458) (xy 425.048808 -6.082172) (xy 425.067476 -6.085699) (xy 425.086144 -6.082172)
			(xy 425.0944 -6.077458) (xy 425.127284 -6.057477) (xy 425.196299 -6.023444) (xy 425.268383 -5.996512)
			(xy 425.305474 -5.986272) (xy 425.317034 -5.98256) (xy 425.335079 -5.966375) (xy 425.340018 -5.955284)
			(xy 425.35072 -5.928522) (xy 425.379113 -5.878362) (xy 425.414721 -5.833038) (xy 425.456735 -5.79358)
			(xy 425.504203 -5.760885) (xy 425.556044 -5.735694) (xy 425.611083 -5.718579) (xy 425.668069 -5.709931)
			(xy 425.696888 -5.709412) (xy 425.707644 -5.709521) (xy 425.72912 -5.71079) (xy 425.739814 -5.711952)
			(xy 425.750736 -5.713222) (xy 425.771564 -5.706364) (xy 425.836334 -5.646674) (xy 425.843962 -5.638998)
			(xy 425.852508 -5.619137) (xy 425.852844 -5.60832) (xy 425.852844 -5.608066) (xy 425.85259 -5.597652)
			(xy 425.85259 -5.597398) (xy 425.852979 -5.572667) (xy 425.859351 -5.523618) (xy 425.86529 -5.499608)
			(xy 425.867934 -5.487606) (xy 425.862606 -5.463642) (xy 425.85513 -5.453888) (xy 425.838292 -5.433581)
			(xy 425.80715 -5.390997) (xy 425.7929 -5.368798) (xy 425.7879 -5.361469) (xy 425.773921 -5.350558)
			(xy 425.75707 -5.345036) (xy 425.748196 -5.344922) (xy 425.734734 -5.345176) (xy 425.707462 -5.344687)
			(xy 425.653474 -5.336929) (xy 425.601139 -5.321566) (xy 425.551523 -5.298911) (xy 425.505637 -5.269426)
			(xy 425.464414 -5.23371) (xy 425.428695 -5.19249) (xy 425.399205 -5.146607) (xy 425.376546 -5.096993)
			(xy 425.361178 -5.044659) (xy 425.353416 -4.990672) (xy 425.353416 -4.936128) (xy 425.361178 -4.882141)
			(xy 425.376546 -4.829807) (xy 425.399205 -4.780193) (xy 425.428695 -4.73431) (xy 425.464414 -4.69309)
			(xy 425.505637 -4.657374) (xy 425.551523 -4.627889) (xy 425.601139 -4.605234) (xy 425.653474 -4.589871)
			(xy 425.707462 -4.582113) (xy 425.734734 -4.581652) (xy 425.748196 -4.581906) (xy 425.75708 -4.581862)
			(xy 425.773956 -4.576349) (xy 425.787925 -4.56539) (xy 425.7929 -4.55803) (xy 425.80716 -4.535838)
			(xy 425.838303 -4.493255) (xy 425.85513 -4.47294) (xy 425.862418 -4.463098) (xy 425.867718 -4.439224)
			(xy 425.86529 -4.42722) (xy 425.85937 -4.4034) (xy 425.853 -4.354733) (xy 425.85259 -4.330192) (xy 425.85259 -4.32943)
			(xy 425.853152 -4.302164) (xy 425.860909 -4.248185) (xy 425.876268 -4.19586) (xy 425.898917 -4.146253)
			(xy 425.928395 -4.100374) (xy 425.964102 -4.059158) (xy 426.005312 -4.023442) (xy 426.051185 -3.993954)
			(xy 426.100787 -3.971295) (xy 426.153109 -3.955925) (xy 426.207086 -3.948158) (xy 426.234352 -3.947668)
			(xy 426.263029 -3.948252) (xy 426.319738 -3.956833) (xy 426.374527 -3.973793) (xy 426.426166 -3.998753)
			(xy 426.473493 -4.031151) (xy 426.515446 -4.07026) (xy 426.551082 -4.1152) (xy 426.579601 -4.164961)
			(xy 426.59046 -4.191508) (xy 426.595528 -4.202644) (xy 426.613841 -4.21882) (xy 426.625512 -4.222496)
			(xy 426.664157 -4.232703) (xy 426.739246 -4.260113) (xy 426.811064 -4.295209) (xy 426.845222 -4.315968)
			(xy 426.853483 -4.320664) (xy 426.872146 -4.324172) (xy 426.890809 -4.320664) (xy 426.89907 -4.315968)
			(xy 426.93157 -4.296177) (xy 426.999755 -4.26239) (xy 427.070963 -4.235556) (xy 427.107604 -4.22529)
			(xy 427.119165 -4.221583) (xy 427.137209 -4.205393) (xy 427.142148 -4.194302) (xy 427.152857 -4.167492)
			(xy 427.181201 -4.117198) (xy 427.216791 -4.071743) (xy 427.258816 -4.032162) (xy 427.30632 -3.999357)
			(xy 427.358221 -3.974075) (xy 427.413334 -3.956892) (xy 427.470407 -3.948199) (xy 427.499272 -3.947668)
			(xy 427.526544 -3.948128) (xy 427.580532 -3.955887) (xy 427.632867 -3.971251) (xy 427.682482 -3.993907)
			(xy 427.728367 -4.023395) (xy 427.769588 -4.059113) (xy 427.805306 -4.100334) (xy 427.834794 -4.14622)
			(xy 427.85745 -4.195835) (xy 427.872814 -4.24817) (xy 427.880573 -4.302158) (xy 427.881034 -4.32943)
			(xy 427.881034 -4.329684) (xy 427.880677 -4.352127) (xy 427.875325 -4.396693) (xy 427.870366 -4.418584)
			(xy 427.868233 -4.430576) (xy 427.874059 -4.454187) (xy 427.881542 -4.463796) (xy 427.900569 -4.486155)
			(xy 427.935535 -4.533322) (xy 427.951392 -4.55803) (xy 427.956417 -4.565341) (xy 427.970382 -4.576261)
			(xy 427.987225 -4.58179) (xy 427.996096 -4.581906) (xy 428.009558 -4.581652) (xy 428.036832 -4.582085)
			(xy 428.090825 -4.589842) (xy 428.143165 -4.605205) (xy 428.192785 -4.627861) (xy 428.238676 -4.657349)
			(xy 428.279903 -4.693068) (xy 428.315626 -4.73429) (xy 428.345118 -4.780178) (xy 428.36778 -4.829796)
			(xy 428.383149 -4.882134) (xy 428.390912 -4.936126) (xy 428.390912 -4.990674) (xy 428.383149 -5.044666)
			(xy 428.36778 -5.097004) (xy 428.345118 -5.146622) (xy 428.315626 -5.19251) (xy 428.279903 -5.233732)
			(xy 428.238676 -5.269451) (xy 428.192785 -5.298939) (xy 428.143165 -5.321595) (xy 428.090825 -5.336958)
			(xy 428.036832 -5.344715) (xy 428.009558 -5.345176) (xy 427.996096 -5.344922) (xy 427.987211 -5.344947)
			(xy 427.970332 -5.350467) (xy 427.956364 -5.361433) (xy 427.951392 -5.368798) (xy 427.93554 -5.393509)
			(xy 427.900576 -5.440679) (xy 427.881542 -5.463032) (xy 427.874109 -5.472671) (xy 427.868258 -5.496258)
			(xy 427.870366 -5.508244) (xy 427.87532 -5.5302) (xy 427.880673 -5.574893) (xy 427.881034 -5.597398)
			(xy 427.881034 -5.597652) (xy 427.88078 -5.60832) (xy 427.881033 -5.619212) (xy 427.889588 -5.639223)
			(xy 427.89729 -5.646928) (xy 427.953932 -5.698998) (xy 427.962295 -5.705946) (xy 427.982959 -5.71265)
			(xy 427.99381 -5.711952) (xy 427.994318 -5.711952) (xy 428.005202 -5.710771) (xy 428.027059 -5.709498)
			(xy 428.038006 -5.709412) (xy 428.06682 -5.70995) (xy 428.123793 -5.718621) (xy 428.178817 -5.735749)
			(xy 428.230645 -5.760946) (xy 428.278101 -5.793641) (xy 428.320109 -5.833092) (xy 428.355715 -5.878404)
			(xy 428.384113 -5.92855) (xy 428.394876 -5.955284) (xy 428.399852 -5.966344) (xy 428.417889 -5.982512)
			(xy 428.42942 -5.986272) (xy 428.466517 -5.996495) (xy 428.538607 -6.023416) (xy 428.607621 -6.057457)
			(xy 428.640494 -6.077458) (xy 428.64875 -6.082172) (xy 428.667418 -6.085699) (xy 428.686086 -6.082172)
			(xy 428.694342 -6.077458) (xy 428.727221 -6.057469) (xy 428.796239 -6.023438) (xy 428.868324 -5.99651)
			(xy 428.905416 -5.986272) (xy 428.916983 -5.982579) (xy 428.935024 -5.966379) (xy 428.93996 -5.955284)
			(xy 428.95071 -5.928543) (xy 428.979097 -5.878385) (xy 429.014699 -5.833062) (xy 429.056707 -5.793604)
			(xy 429.104167 -5.760906) (xy 429.156001 -5.735711) (xy 429.211033 -5.718591) (xy 429.268013 -5.709935)
			(xy 429.29683 -5.709412) (xy 429.30765 -5.709507) (xy 429.329253 -5.71078) (xy 429.34001 -5.711952)
			(xy 429.350932 -5.713222) (xy 429.37176 -5.706364) (xy 429.43653 -5.646674) (xy 429.444157 -5.638997)
			(xy 429.452704 -5.619136) (xy 429.45304 -5.60832) (xy 429.45304 -5.608066) (xy 429.452786 -5.597398)
			(xy 429.452786 -5.59689) (xy 429.453131 -5.572356) (xy 429.459377 -5.523689) (xy 429.465232 -5.499862)
			(xy 429.467664 -5.487921) (xy 429.462346 -5.464174) (xy 429.455072 -5.454396) (xy 429.438232 -5.433959)
			(xy 429.407088 -5.391121) (xy 429.392842 -5.368798) (xy 429.387816 -5.361489) (xy 429.373849 -5.350574)
			(xy 429.357008 -5.345043) (xy 429.348138 -5.344922) (xy 429.334676 -5.345176) (xy 429.307409 -5.34466)
			(xy 429.25343 -5.336896) (xy 429.201105 -5.321529) (xy 429.1515 -5.298872) (xy 429.105623 -5.269387)
			(xy 429.06441 -5.233673) (xy 429.028699 -5.192457) (xy 428.999216 -5.146579) (xy 428.976563 -5.096972)
			(xy 428.961199 -5.044647) (xy 428.953438 -4.990667) (xy 428.953438 -4.936133) (xy 428.961199 -4.882153)
			(xy 428.976563 -4.829828) (xy 428.999216 -4.780221) (xy 429.028699 -4.734343) (xy 429.06441 -4.693127)
			(xy 429.105623 -4.657413) (xy 429.1515 -4.627928) (xy 429.201105 -4.605271) (xy 429.25343 -4.589904)
			(xy 429.307409 -4.58214) (xy 429.334676 -4.581652) (xy 429.348138 -4.581906) (xy 429.357023 -4.581893)
			(xy 429.373902 -4.576365) (xy 429.38787 -4.565395) (xy 429.392842 -4.55803) (xy 429.407084 -4.535703)
			(xy 429.438225 -4.492865) (xy 429.455072 -4.472432) (xy 429.462347 -4.462653) (xy 429.467662 -4.438908)
			(xy 429.465232 -4.426966) (xy 429.459408 -4.403133) (xy 429.453166 -4.354469) (xy 429.452786 -4.329938)
			(xy 429.452786 -4.32943) (xy 429.45323 -4.302158) (xy 429.460989 -4.248167) (xy 429.476354 -4.195831)
			(xy 429.499011 -4.146215) (xy 429.5285 -4.100329) (xy 429.56422 -4.059107) (xy 429.605444 -4.023389)
			(xy 429.651331 -3.993903) (xy 429.700948 -3.971247) (xy 429.753285 -3.955885) (xy 429.807276 -3.948128)
			(xy 429.834548 -3.947668) (xy 429.863225 -3.948255) (xy 429.919934 -3.956835) (xy 429.974723 -3.973796)
			(xy 430.026361 -3.998755) (xy 430.073689 -4.031153) (xy 430.115642 -4.070261) (xy 430.151278 -4.1152)
			(xy 430.179797 -4.164962) (xy 430.190656 -4.191508) (xy 430.195726 -4.202643) (xy 430.214037 -4.218819)
			(xy 430.225708 -4.222496) (xy 430.264301 -4.232681) (xy 430.339299 -4.26001) (xy 430.411039 -4.295009)
			(xy 430.445164 -4.315714) (xy 430.45342 -4.320428) (xy 430.472088 -4.323955) (xy 430.490756 -4.320428)
			(xy 430.499012 -4.315714) (xy 430.531584 -4.29589) (xy 430.599939 -4.262089) (xy 430.671322 -4.235268)
			(xy 430.708054 -4.225036) (xy 430.71953 -4.221257) (xy 430.737434 -4.205087) (xy 430.742344 -4.194048)
			(xy 430.753098 -4.167269) (xy 430.781466 -4.11702) (xy 430.817069 -4.071609) (xy 430.859097 -4.032069)
			(xy 430.906593 -3.999299) (xy 430.958477 -3.974045) (xy 431.013569 -3.956881) (xy 431.070616 -3.948198)
			(xy 431.099468 -3.947668) (xy 431.12674 -3.948131) (xy 431.180728 -3.95589) (xy 431.233063 -3.971254)
			(xy 431.282678 -3.99391) (xy 431.328563 -4.023397) (xy 431.369784 -4.059114) (xy 431.405502 -4.100336)
			(xy 431.434989 -4.146221) (xy 431.457646 -4.195836) (xy 431.47301 -4.24817) (xy 431.480769 -4.302158)
			(xy 431.48123 -4.32943) (xy 431.48123 -4.330192) (xy 431.480854 -4.352571) (xy 431.475507 -4.397009)
			(xy 431.470562 -4.418838) (xy 431.468394 -4.430827) (xy 431.474244 -4.454442) (xy 431.481738 -4.46405)
			(xy 431.500698 -4.486349) (xy 431.535535 -4.53339) (xy 431.551334 -4.55803) (xy 431.556394 -4.565314)
			(xy 431.570343 -4.576239) (xy 431.587172 -4.58178) (xy 431.596038 -4.581906) (xy 431.6095 -4.581652)
			(xy 431.63677 -4.58211) (xy 431.690756 -4.589872) (xy 431.743087 -4.605238) (xy 431.792699 -4.627895)
			(xy 431.838582 -4.657382) (xy 431.879801 -4.693099) (xy 431.915518 -4.734318) (xy 431.945005 -4.780201)
			(xy 431.967662 -4.829813) (xy 431.983028 -4.882144) (xy 431.99079 -4.93613) (xy 431.99079 -4.99067)
			(xy 431.983028 -5.044656) (xy 431.967662 -5.096987) (xy 431.945005 -5.146599) (xy 431.915518 -5.192482)
			(xy 431.879801 -5.233701) (xy 431.838582 -5.269418) (xy 431.792699 -5.298905) (xy 431.743087 -5.321562)
			(xy 431.690756 -5.336928) (xy 431.63677 -5.34469) (xy 431.6095 -5.345176) (xy 431.596038 -5.344922)
			(xy 431.587155 -5.344978) (xy 431.570277 -5.350483) (xy 431.556308 -5.361438) (xy 431.551334 -5.368798)
			(xy 431.53554 -5.393441) (xy 431.500701 -5.440482) (xy 431.481738 -5.462778) (xy 431.474278 -5.4724)
			(xy 431.468443 -5.496001) (xy 431.470562 -5.50799) (xy 431.475501 -5.52982) (xy 431.480849 -5.574258)
			(xy 431.48123 -5.596636) (xy 431.48123 -5.597398) (xy 431.480797 -5.62467) (xy 431.473034 -5.67866)
			(xy 431.457666 -5.730995) (xy 431.435007 -5.780611) (xy 431.405516 -5.826496) (xy 431.369795 -5.867717)
			(xy 431.328572 -5.903434) (xy 431.282684 -5.932921) (xy 431.233067 -5.955577) (xy 431.180731 -5.97094)
			(xy 431.12674 -5.978699) (xy 431.099468 -5.97916) (xy 431.070616 -5.97863) (xy 431.013568 -5.969947)
			(xy 430.958474 -5.952784) (xy 430.906589 -5.927531) (xy 430.859091 -5.894762) (xy 430.817061 -5.855223)
			(xy 430.781455 -5.809813) (xy 430.753083 -5.759564) (xy 430.742344 -5.73278) (xy 430.737449 -5.721735)
			(xy 430.719531 -5.705571) (xy 430.708054 -5.701792) (xy 430.671326 -5.691547) (xy 430.599941 -5.664732)
			(xy 430.531583 -5.63094) (xy 430.499012 -5.611114) (xy 430.490756 -5.6064) (xy 430.472088 -5.602873)
			(xy 430.45342 -5.6064) (xy 430.445164 -5.611114) (xy 430.411037 -5.631815) (xy 430.3393 -5.666821)
			(xy 430.264302 -5.694151) (xy 430.225708 -5.704332) (xy 430.21401 -5.707954) (xy 430.195698 -5.724159)
			(xy 430.190656 -5.73532) (xy 430.179799 -5.761873) (xy 430.151299 -5.811655) (xy 430.115673 -5.856615)
			(xy 430.073724 -5.89574) (xy 430.026393 -5.92815) (xy 429.974748 -5.953116) (xy 429.919949 -5.970076)
			(xy 429.86323 -5.978649) (xy 429.834548 -5.97916) (xy 429.823728 -5.979059) (xy 429.802125 -5.97779)
			(xy 429.791368 -5.97662) (xy 429.780446 -5.97535) (xy 429.759618 -5.982208) (xy 429.694848 -6.041898)
			(xy 429.687231 -6.049582) (xy 429.678679 -6.069438) (xy 429.678338 -6.080252) (xy 429.678338 -6.080506)
			(xy 429.678592 -6.09092) (xy 429.678592 -6.091428) (xy 429.678084 -6.110224) (xy 429.677576 -6.121146)
			(xy 429.685196 -6.140958) (xy 429.75403 -6.210046) (xy 429.774096 -6.217412) (xy 429.785018 -6.216904)
			(xy 429.804576 -6.216396) (xy 429.80483 -6.216396) (xy 429.832098 -6.216896) (xy 429.886079 -6.224661)
			(xy 429.938406 -6.240028) (xy 429.988013 -6.262685) (xy 430.033892 -6.29217) (xy 430.075108 -6.327883)
			(xy 430.110823 -6.369098) (xy 430.14031 -6.414976) (xy 430.162968 -6.464583) (xy 430.178336 -6.516909)
			(xy 430.186103 -6.57089) (xy 430.186592 -6.598158) (xy 430.186103 -6.624997) (xy 430.17857 -6.678145)
			(xy 430.163673 -6.729715) (xy 430.141707 -6.778693) (xy 430.113103 -6.824116) (xy 430.078425 -6.865089)
			(xy 430.038354 -6.900806) (xy 429.993679 -6.930565) (xy 429.969676 -6.942582) (xy 429.96104 -6.946646)
			(xy 429.947832 -6.96087) (xy 429.915828 -7.043928) (xy 429.916082 -7.063232) (xy 429.919638 -7.072122)
			(xy 429.928377 -7.094807) (xy 429.940676 -7.141841) (xy 429.94691 -7.190055) (xy 429.947324 -7.214362)
			(xy 429.947324 -7.215124) (xy 430.983898 -7.215124) (xy 430.984421 -7.185969) (xy 430.993298 -7.12834)
			(xy 431.010833 -7.07273) (xy 431.03662 -7.020433) (xy 431.070058 -6.972664) (xy 431.089816 -6.951218)
			(xy 431.098063 -6.941611) (xy 431.104711 -6.917208) (xy 431.102516 -6.904736) (xy 431.093268 -6.86222)
			(xy 431.083334 -6.775776) (xy 431.082704 -6.73227) (xy 431.083217 -6.69227) (xy 431.091582 -6.612707)
			(xy 431.108218 -6.534455) (xy 431.132941 -6.45837) (xy 431.165482 -6.385287) (xy 431.205484 -6.316005)
			(xy 431.252508 -6.251283) (xy 431.30604 -6.191831) (xy 431.365492 -6.138301) (xy 431.430215 -6.091277)
			(xy 431.499497 -6.051277) (xy 431.572582 -6.018737) (xy 431.648667 -5.994015) (xy 431.726919 -5.97738)
			(xy 431.806482 -5.969016) (xy 431.846482 -5.968492) (xy 431.889171 -5.969113) (xy 431.974013 -5.978673)
			(xy 432.057261 -5.997631) (xy 432.137876 -6.025751) (xy 432.214854 -6.062683) (xy 432.251358 -6.084824)
			(xy 432.259619 -6.08952) (xy 432.278282 -6.093028) (xy 432.296945 -6.08952) (xy 432.305206 -6.084824)
			(xy 432.341711 -6.062682) (xy 432.418683 -6.025734) (xy 432.499297 -5.997606) (xy 432.582547 -5.978647)
			(xy 432.667392 -5.969096) (xy 432.710082 -5.968492) (xy 432.750081 -5.969062) (xy 432.829641 -5.977423)
			(xy 432.907892 -5.994053) (xy 432.983975 -6.018772) (xy 433.057058 -6.051308) (xy 433.12634 -6.091305)
			(xy 433.191061 -6.138325) (xy 433.250513 -6.191853) (xy 433.304045 -6.251301) (xy 433.351069 -6.31602)
			(xy 433.39107 -6.385299) (xy 433.423611 -6.45838) (xy 433.448334 -6.534462) (xy 433.46497 -6.612711)
			(xy 433.473335 -6.692271) (xy 433.47386 -6.73227) (xy 433.473516 -6.764888) (xy 433.467959 -6.829886)
			(xy 433.456889 -6.894175) (xy 433.448968 -6.925818) (xy 433.446529 -6.937735) (xy 433.451692 -6.961468)
			(xy 433.458874 -6.971284) (xy 433.475474 -6.991915) (xy 433.503432 -7.036885) (xy 433.524892 -7.085295)
			(xy 433.539441 -7.136209) (xy 433.546799 -7.188648) (xy 433.547266 -7.215124) (xy 444.97879 -7.215124)
			(xy 444.979306 -7.186968) (xy 444.987629 -7.131275) (xy 445.004041 -7.077407) (xy 445.028184 -7.026533)
			(xy 445.059535 -6.979755) (xy 445.078104 -6.958584) (xy 445.0861 -6.948778) (xy 445.092231 -6.924262)
			(xy 445.089788 -6.911848) (xy 445.078982 -6.866062) (xy 445.067386 -6.772704) (xy 445.066674 -6.725666)
			(xy 445.066674 -6.725158) (xy 445.067206 -6.685158) (xy 445.075572 -6.605598) (xy 445.092207 -6.527347)
			(xy 445.116931 -6.451264) (xy 445.149471 -6.378182) (xy 445.189472 -6.308901) (xy 445.236495 -6.24418)
			(xy 445.290025 -6.184729) (xy 445.349476 -6.131199) (xy 445.414196 -6.084175) (xy 445.483476 -6.044174)
			(xy 445.556558 -6.011633) (xy 445.632641 -5.986909) (xy 445.710892 -5.970272) (xy 445.790452 -5.961906)
			(xy 445.830452 -5.96138) (xy 445.873141 -5.962017) (xy 445.957982 -5.971573) (xy 446.04123 -5.990528)
			(xy 446.121845 -6.018645) (xy 446.198824 -6.055573) (xy 446.235328 -6.077712) (xy 446.243589 -6.082408)
			(xy 446.262252 -6.085916) (xy 446.280915 -6.082408) (xy 446.289176 -6.077712) (xy 446.325687 -6.055581)
			(xy 446.402658 -6.018632) (xy 446.48327 -5.990501) (xy 446.566518 -5.97154) (xy 446.651362 -5.961986)
			(xy 446.694052 -5.96138) (xy 446.734051 -5.961973) (xy 446.813612 -5.97033) (xy 446.891863 -5.986958)
			(xy 446.967947 -6.011674) (xy 447.041031 -6.044208) (xy 447.110314 -6.084203) (xy 447.175037 -6.131221)
			(xy 447.23449 -6.184746) (xy 447.288023 -6.244193) (xy 447.335048 -6.308911) (xy 447.375051 -6.378189)
			(xy 447.407594 -6.451269) (xy 447.432319 -6.52735) (xy 447.448956 -6.605599) (xy 447.457322 -6.685159)
			(xy 447.45783 -6.725158) (xy 447.457078 -6.772981) (xy 447.445102 -6.867876) (xy 447.433954 -6.914388)
			(xy 447.431466 -6.926715) (xy 447.437463 -6.951103) (xy 447.445384 -6.96087) (xy 447.463545 -6.981976)
			(xy 447.494216 -7.028442) (xy 447.517808 -7.078874) (xy 447.533819 -7.132199) (xy 447.541908 -7.187285)
			(xy 447.542412 -7.215124) (xy 447.541898 -7.242392) (xy 447.534134 -7.296372) (xy 447.518769 -7.348698)
			(xy 447.496113 -7.398305) (xy 447.466629 -7.444183) (xy 447.430917 -7.485399) (xy 447.389704 -7.521114)
			(xy 447.343827 -7.550601) (xy 447.294222 -7.573259) (xy 447.241897 -7.588629) (xy 447.187918 -7.596396)
			(xy 447.16065 -7.596886) (xy 447.130937 -7.596292) (xy 447.072229 -7.587088) (xy 447.015652 -7.56891)
			(xy 446.96257 -7.542196) (xy 446.914261 -7.507589) (xy 446.89268 -7.487158) (xy 446.883343 -7.4788)
			(xy 446.85936 -7.471623) (xy 446.84696 -7.473442) (xy 446.809148 -7.480681) (xy 446.732548 -7.488443)
			(xy 446.694052 -7.488936) (xy 446.651363 -7.48831) (xy 446.566521 -7.478753) (xy 446.483273 -7.459796)
			(xy 446.402657 -7.431677) (xy 446.32568 -7.394745) (xy 446.289176 -7.372604) (xy 446.280915 -7.367908)
			(xy 446.262252 -7.3644) (xy 446.243589 -7.367908) (xy 446.235328 -7.372604) (xy 446.198817 -7.394735)
			(xy 446.121846 -7.431684) (xy 446.041234 -7.459815) (xy 445.957986 -7.478776) (xy 445.873142 -7.48833)
			(xy 445.830452 -7.488936) (xy 445.829944 -7.488936) (xy 445.790991 -7.488395) (xy 445.713496 -7.480383)
			(xy 445.675258 -7.472934) (xy 445.662798 -7.471038) (xy 445.638678 -7.478246) (xy 445.629284 -7.48665)
			(xy 445.607683 -7.507165) (xy 445.559313 -7.541934) (xy 445.506135 -7.56878) (xy 445.449437 -7.587052)
			(xy 445.390591 -7.596308) (xy 445.360806 -7.596886) (xy 445.360552 -7.596886) (xy 445.333283 -7.59642)
			(xy 445.279299 -7.588653) (xy 445.226971 -7.573282) (xy 445.177362 -7.550622) (xy 445.131483 -7.521134)
			(xy 445.090266 -7.485417) (xy 445.054552 -7.444198) (xy 445.025066 -7.398317) (xy 445.002409 -7.348706)
			(xy 444.987042 -7.296377) (xy 444.979278 -7.242393) (xy 444.97879 -7.215124) (xy 433.547266 -7.215124)
			(xy 433.546798 -7.242394) (xy 433.539033 -7.296378) (xy 433.523665 -7.348707) (xy 433.501006 -7.398317)
			(xy 433.471518 -7.444198) (xy 433.435801 -7.485415) (xy 433.394582 -7.52113) (xy 433.3487 -7.550616)
			(xy 433.299089 -7.573272) (xy 433.246758 -7.588637) (xy 433.192774 -7.596399) (xy 433.165504 -7.596886)
			(xy 433.1368 -7.596378) (xy 433.08004 -7.587777) (xy 433.025209 -7.570768) (xy 432.973546 -7.545736)
			(xy 432.926217 -7.513245) (xy 432.9049 -7.494016) (xy 432.895558 -7.486253) (xy 432.872225 -7.479626)
			(xy 432.860196 -7.481316) (xy 432.823182 -7.488229) (xy 432.748242 -7.495608) (xy 432.71059 -7.496048)
			(xy 432.710082 -7.496048) (xy 432.667392 -7.495453) (xy 432.582549 -7.485889) (xy 432.499301 -7.466925)
			(xy 432.418686 -7.438798) (xy 432.341709 -7.40186) (xy 432.305206 -7.379716) (xy 432.296945 -7.37502)
			(xy 432.278282 -7.371512) (xy 432.259619 -7.37502) (xy 432.251358 -7.379716) (xy 432.214865 -7.401877)
			(xy 432.137889 -7.438821) (xy 432.057272 -7.466945) (xy 431.97402 -7.485899) (xy 431.889173 -7.495446)
			(xy 431.846482 -7.496048) (xy 431.803761 -7.495445) (xy 431.718853 -7.485896) (xy 431.677064 -7.476998)
			(xy 431.664567 -7.474811) (xy 431.640162 -7.481631) (xy 431.630582 -7.489952) (xy 431.609121 -7.509904)
			(xy 431.561218 -7.54365) (xy 431.508722 -7.569681) (xy 431.452864 -7.587386) (xy 431.394958 -7.596348)
			(xy 431.36566 -7.596886) (xy 431.338391 -7.596413) (xy 431.284408 -7.588646) (xy 431.23208 -7.573277)
			(xy 431.182471 -7.550618) (xy 431.136591 -7.52113) (xy 431.095375 -7.485414) (xy 431.05966 -7.444196)
			(xy 431.030174 -7.398315) (xy 431.007517 -7.348705) (xy 430.99215 -7.296376) (xy 430.984386 -7.242393)
			(xy 430.983898 -7.215124) (xy 429.947324 -7.215124) (xy 429.946921 -7.242397) (xy 429.939154 -7.296388)
			(xy 429.923783 -7.348724) (xy 429.90112 -7.39834) (xy 429.871626 -7.444226) (xy 429.835902 -7.485446)
			(xy 429.794676 -7.521163) (xy 429.748786 -7.55065) (xy 429.699166 -7.573305) (xy 429.646828 -7.588668)
			(xy 429.592835 -7.596425) (xy 429.565562 -7.596886) (xy 429.535871 -7.596306) (xy 429.477208 -7.587102)
			(xy 429.420678 -7.56892) (xy 429.367647 -7.542201) (xy 429.319396 -7.50759) (xy 429.297846 -7.487158)
			(xy 429.288482 -7.478838) (xy 429.264521 -7.471639) (xy 429.252126 -7.473442) (xy 429.214315 -7.480686)
			(xy 429.137714 -7.488444) (xy 429.099218 -7.488936) (xy 429.056528 -7.488326) (xy 428.971686 -7.478765)
			(xy 428.888438 -7.459805) (xy 428.807822 -7.431682) (xy 428.730845 -7.394747) (xy 428.694342 -7.372604)
			(xy 428.686081 -7.367908) (xy 428.667418 -7.3644) (xy 428.648755 -7.367908) (xy 428.640494 -7.372604)
			(xy 428.603991 -7.394749) (xy 428.527018 -7.431696) (xy 428.446403 -7.459823) (xy 428.363154 -7.478781)
			(xy 428.278308 -7.488332) (xy 428.235618 -7.488936) (xy 428.23511 -7.488936) (xy 428.196157 -7.4884)
			(xy 428.118662 -7.480384) (xy 428.080424 -7.472934) (xy 428.067962 -7.471082) (xy 428.043847 -7.47826)
			(xy 428.03445 -7.48665) (xy 428.012864 -7.507181) (xy 427.96449 -7.541948) (xy 427.911308 -7.568791)
			(xy 427.854607 -7.587059) (xy 427.795758 -7.596311) (xy 427.765972 -7.596886) (xy 427.765718 -7.596886)
			(xy 427.73845 -7.596359) (xy 427.684469 -7.5886) (xy 427.632142 -7.573238) (xy 427.582533 -7.550586)
			(xy 427.536654 -7.521104) (xy 427.495436 -7.485393) (xy 427.459721 -7.44418) (xy 427.430234 -7.398303)
			(xy 427.407576 -7.348697) (xy 427.392209 -7.296372) (xy 427.384444 -7.242392) (xy 427.383956 -7.215124)
			(xy 427.384345 -7.190503) (xy 427.390666 -7.141668) (xy 427.403219 -7.094053) (xy 427.41215 -7.071106)
			(xy 427.415706 -7.062216) (xy 427.41596 -7.042912) (xy 427.387766 -6.968744) (xy 427.384009 -6.959993)
			(xy 427.371218 -6.945902) (xy 427.362874 -6.941312) (xy 427.36262 -6.941312) (xy 427.338881 -6.929167)
			(xy 427.294679 -6.899343) (xy 427.255057 -6.863659) (xy 427.220785 -6.822809) (xy 427.192529 -6.777589)
			(xy 427.17084 -6.728877) (xy 427.15614 -6.677621) (xy 427.148713 -6.624819) (xy 427.148244 -6.598158)
			(xy 427.148685 -6.570887) (xy 427.156453 -6.516902) (xy 427.171824 -6.464571) (xy 427.194485 -6.41496)
			(xy 427.223976 -6.369079) (xy 427.259696 -6.327862) (xy 427.300918 -6.292147) (xy 427.346803 -6.262662)
			(xy 427.396416 -6.240007) (xy 427.448749 -6.224643) (xy 427.502735 -6.216882) (xy 427.530006 -6.216396)
			(xy 427.53026 -6.216396) (xy 427.549818 -6.216904) (xy 427.56074 -6.217412) (xy 427.580806 -6.210046)
			(xy 427.64964 -6.140958) (xy 427.65726 -6.121146) (xy 427.656752 -6.110224) (xy 427.656244 -6.091174)
			(xy 427.656244 -6.09092) (xy 427.656498 -6.080252) (xy 427.656237 -6.069362) (xy 427.647685 -6.049352)
			(xy 427.639988 -6.041644) (xy 427.583346 -5.989574) (xy 427.574958 -5.982662) (xy 427.554314 -5.975938)
			(xy 427.543468 -5.97662) (xy 427.54296 -5.97662) (xy 427.532077 -5.977803) (xy 427.510219 -5.979074)
			(xy 427.499272 -5.97916) (xy 427.470405 -5.97862) (xy 427.413326 -5.969949) (xy 427.358204 -5.95278)
			(xy 427.306297 -5.927504) (xy 427.25879 -5.894698) (xy 427.216766 -5.855111) (xy 427.181185 -5.809645)
			(xy 427.152857 -5.759338) (xy 427.142148 -5.732526) (xy 427.137156 -5.721475) (xy 427.119131 -5.705303)
			(xy 427.107604 -5.701538) (xy 427.07096 -5.691283) (xy 426.999752 -5.664445) (xy 426.931565 -5.630659)
			(xy 426.89907 -5.61086) (xy 426.890809 -5.606164) (xy 426.872146 -5.602656) (xy 426.853483 -5.606164)
			(xy 426.845222 -5.61086) (xy 426.811077 -5.631642) (xy 426.739258 -5.666742) (xy 426.664163 -5.694142)
			(xy 426.625512 -5.704332) (xy 426.613815 -5.707956) (xy 426.595502 -5.724159) (xy 426.59046 -5.73532)
			(xy 426.5796 -5.761871) (xy 426.5511 -5.811654) (xy 426.515475 -5.856613) (xy 426.473526 -5.895738)
			(xy 426.426196 -5.928149) (xy 426.374551 -5.953115) (xy 426.319752 -5.970075) (xy 426.263034 -5.978649)
			(xy 426.234352 -5.97916) (xy 426.223596 -5.979056) (xy 426.20212 -5.977784) (xy 426.191426 -5.97662)
			(xy 426.180504 -5.97535) (xy 426.159676 -5.982208) (xy 426.094906 -6.041898) (xy 426.087297 -6.04959)
			(xy 426.078738 -6.069439) (xy 426.078396 -6.080252) (xy 426.078396 -6.080506) (xy 426.07865 -6.090666)
			(xy 426.07865 -6.091174) (xy 426.078142 -6.110224) (xy 426.077634 -6.121146) (xy 426.085254 -6.140958)
			(xy 426.154088 -6.210046) (xy 426.174154 -6.217412) (xy 426.185076 -6.216904) (xy 426.204634 -6.216396)
			(xy 426.204888 -6.216396) (xy 426.232155 -6.216935) (xy 426.286135 -6.224694) (xy 426.338461 -6.240056)
			(xy 426.388068 -6.262708) (xy 426.433947 -6.292189) (xy 426.475164 -6.327898) (xy 426.510879 -6.36911)
			(xy 426.540366 -6.414985) (xy 426.563025 -6.464589) (xy 426.578394 -6.516912) (xy 426.586161 -6.570891)
			(xy 426.58665 -6.598158) (xy 426.586185 -6.624998) (xy 426.57865 -6.678148) (xy 426.563752 -6.72972)
			(xy 426.541783 -6.778699) (xy 426.513176 -6.824122) (xy 426.478493 -6.865095) (xy 426.438418 -6.900811)
			(xy 426.393739 -6.930567) (xy 426.369734 -6.942582) (xy 426.361098 -6.946646) (xy 426.34789 -6.96087)
			(xy 426.315886 -7.043928) (xy 426.31614 -7.063232) (xy 426.319696 -7.072122) (xy 426.328438 -7.094806)
			(xy 426.340735 -7.141841) (xy 426.346968 -7.190055) (xy 426.347382 -7.214362) (xy 426.347382 -7.215124)
			(xy 426.346898 -7.242393) (xy 426.339134 -7.296376) (xy 426.323766 -7.348704) (xy 426.301109 -7.398313)
			(xy 426.271622 -7.444193) (xy 426.235907 -7.48541) (xy 426.19469 -7.521125) (xy 426.148809 -7.550611)
			(xy 426.0992 -7.573268) (xy 426.046872 -7.588634) (xy 425.992889 -7.596398) (xy 425.96562 -7.596886)
			(xy 425.935928 -7.596332) (xy 425.877263 -7.587121) (xy 425.820734 -7.568934) (xy 425.767703 -7.542209)
			(xy 425.719453 -7.507592) (xy 425.697904 -7.487158) (xy 425.688557 -7.478814) (xy 425.664582 -7.471629)
			(xy 425.652184 -7.473442) (xy 425.614371 -7.480677) (xy 425.537772 -7.488441) (xy 425.499276 -7.488936)
			(xy 425.456586 -7.488346) (xy 425.371742 -7.47878) (xy 425.288494 -7.459816) (xy 425.207879 -7.431688)
			(xy 425.130903 -7.394749) (xy 425.0944 -7.372604) (xy 425.086139 -7.367908) (xy 425.067476 -7.3644)
			(xy 425.048813 -7.367908) (xy 425.040552 -7.372604) (xy 425.004059 -7.394766) (xy 424.927083 -7.43171)
			(xy 424.846466 -7.459834) (xy 424.763214 -7.478788) (xy 424.678367 -7.488334) (xy 424.635676 -7.488936)
			(xy 424.596468 -7.488447) (xy 424.518463 -7.480426) (xy 424.479974 -7.472934) (xy 424.467483 -7.470968)
			(xy 424.443236 -7.478038) (xy 424.433746 -7.486396) (xy 424.412201 -7.506954) (xy 424.363902 -7.541786)
			(xy 424.310777 -7.568688) (xy 424.254116 -7.587007) (xy 424.195296 -7.596296) (xy 424.165522 -7.596886)
			(xy 424.138254 -7.596355) (xy 424.084273 -7.588597) (xy 424.031946 -7.573236) (xy 423.982338 -7.550584)
			(xy 423.936458 -7.521103) (xy 423.895241 -7.485392) (xy 423.859525 -7.444179) (xy 423.830038 -7.398303)
			(xy 423.80738 -7.348697) (xy 423.792013 -7.296372) (xy 423.784248 -7.242392) (xy 423.78376 -7.215124)
			(xy 423.784181 -7.190454) (xy 423.790586 -7.141529) (xy 423.803229 -7.093834) (xy 423.812208 -7.070852)
			(xy 423.812208 -7.070598) (xy 423.815298 -7.061658) (xy 423.815413 -7.042757) (xy 423.812462 -7.033768)
			(xy 423.784268 -6.959346) (xy 423.771568 -6.945376) (xy 423.762678 -6.941058) (xy 423.738902 -6.929006)
			(xy 423.694698 -6.899215) (xy 423.655072 -6.86356) (xy 423.620798 -6.822734) (xy 423.592542 -6.777533)
			(xy 423.570855 -6.728838) (xy 423.55616 -6.677598) (xy 423.548743 -6.624811) (xy 423.548302 -6.598158)
			(xy 418.976556 -6.598158) (xy 418.976087 -6.624998) (xy 418.968553 -6.678147) (xy 418.953655 -6.729719)
			(xy 418.931687 -6.778699) (xy 418.90308 -6.824122) (xy 418.868398 -6.865094) (xy 418.828323 -6.90081)
			(xy 418.783645 -6.930567) (xy 418.75964 -6.942582) (xy 418.751004 -6.946646) (xy 418.737796 -6.96087)
			(xy 418.705792 -7.043928) (xy 418.706046 -7.063232) (xy 418.709602 -7.072122) (xy 418.718344 -7.094806)
			(xy 418.730641 -7.141841) (xy 418.736874 -7.190055) (xy 418.737288 -7.214362) (xy 418.737288 -7.215124)
			(xy 418.736798 -7.242393) (xy 418.729034 -7.296375) (xy 418.713667 -7.348703) (xy 418.69101 -7.398311)
			(xy 418.661524 -7.444191) (xy 418.625809 -7.485407) (xy 418.584592 -7.521122) (xy 418.538713 -7.550609)
			(xy 418.489105 -7.573266) (xy 418.436777 -7.588633) (xy 418.382795 -7.596398) (xy 418.355526 -7.596886)
			(xy 418.325834 -7.596329) (xy 418.26717 -7.587118) (xy 418.21064 -7.568932) (xy 418.15761 -7.542208)
			(xy 418.109359 -7.507592) (xy 418.08781 -7.487158) (xy 418.078461 -7.478818) (xy 418.054488 -7.47163)
			(xy 418.04209 -7.473442) (xy 418.004277 -7.480676) (xy 417.927678 -7.488441) (xy 417.889182 -7.488936)
			(xy 417.846492 -7.488343) (xy 417.761648 -7.478778) (xy 417.6784 -7.459814) (xy 417.597785 -7.431687)
			(xy 417.520809 -7.394748) (xy 417.484306 -7.372604) (xy 417.476045 -7.367908) (xy 417.457382 -7.3644)
			(xy 417.438719 -7.367908) (xy 417.430458 -7.372604) (xy 417.393964 -7.394764) (xy 417.316988 -7.431708)
			(xy 417.236371 -7.459833) (xy 417.15312 -7.478787) (xy 417.068273 -7.488334) (xy 417.025582 -7.488936)
			(xy 417.025074 -7.488936) (xy 416.98612 -7.488405) (xy 416.908626 -7.480386) (xy 416.870388 -7.472934)
			(xy 416.857927 -7.471058) (xy 416.833809 -7.478252) (xy 416.824414 -7.48665) (xy 416.8028 -7.507151)
			(xy 416.754433 -7.541922) (xy 416.701259 -7.56877) (xy 416.644564 -7.587046) (xy 416.58572 -7.596306)
			(xy 416.555936 -7.596886) (xy 416.555682 -7.596886) (xy 416.528413 -7.596392) (xy 416.474431 -7.588629)
			(xy 416.422103 -7.573262) (xy 416.372495 -7.550606) (xy 416.326615 -7.52112) (xy 416.285398 -7.485406)
			(xy 416.249683 -7.44419) (xy 416.220197 -7.398311) (xy 416.19754 -7.348702) (xy 416.182172 -7.296375)
			(xy 416.174408 -7.242393) (xy 416.17392 -7.215124) (xy 416.174311 -7.190503) (xy 416.180631 -7.141668)
			(xy 416.193183 -7.094053) (xy 416.202114 -7.071106) (xy 416.20567 -7.062216) (xy 416.205924 -7.042912)
			(xy 416.17773 -6.968744) (xy 416.173986 -6.959987) (xy 416.161186 -6.945898) (xy 416.152838 -6.941312)
			(xy 416.152584 -6.941312) (xy 416.128836 -6.929183) (xy 416.084636 -6.899355) (xy 416.045015 -6.863668)
			(xy 416.010745 -6.822816) (xy 415.982491 -6.777593) (xy 415.960803 -6.72888) (xy 415.946103 -6.677623)
			(xy 415.938676 -6.62482) (xy 415.938208 -6.598158) (xy 415.938685 -6.570889) (xy 415.946452 -6.516907)
			(xy 415.961821 -6.464579) (xy 415.98448 -6.41497) (xy 416.013967 -6.369091) (xy 416.049683 -6.327875)
			(xy 416.090901 -6.29216) (xy 416.136781 -6.262674) (xy 416.18639 -6.240017) (xy 416.238718 -6.224649)
			(xy 416.292701 -6.216884) (xy 416.31997 -6.216396) (xy 416.320224 -6.216396) (xy 416.339782 -6.216904)
			(xy 416.350704 -6.217412) (xy 416.37077 -6.210046) (xy 416.439604 -6.140958) (xy 416.447224 -6.121146)
			(xy 416.446716 -6.110224) (xy 416.446208 -6.091174) (xy 416.446208 -6.09092) (xy 416.446462 -6.080252)
			(xy 416.446212 -6.06936) (xy 416.437654 -6.04935) (xy 416.429952 -6.041644) (xy 416.37331 -5.989574)
			(xy 416.364934 -5.982644) (xy 416.34428 -5.97593) (xy 416.333432 -5.97662) (xy 416.332924 -5.97662)
			(xy 416.322041 -5.977806) (xy 416.300183 -5.979075) (xy 416.289236 -5.97916) (xy 416.260368 -5.978651)
			(xy 416.203287 -5.969975) (xy 416.148165 -5.952801) (xy 416.096258 -5.92752) (xy 416.048751 -5.89471)
			(xy 416.006728 -5.855118) (xy 415.971147 -5.809649) (xy 415.942821 -5.75934) (xy 415.932112 -5.732526)
			(xy 415.927138 -5.721464) (xy 415.9091 -5.705297) (xy 415.897568 -5.701538) (xy 415.860928 -5.69127)
			(xy 415.789719 -5.664437) (xy 415.72153 -5.630657) (xy 415.689034 -5.61086) (xy 415.680773 -5.606164)
			(xy 415.66211 -5.602656) (xy 415.643447 -5.606164) (xy 415.635186 -5.61086) (xy 415.601046 -5.63165)
			(xy 415.529224 -5.666746) (xy 415.454128 -5.694143) (xy 415.415476 -5.704332) (xy 415.40379 -5.707985)
			(xy 415.385471 -5.724167) (xy 415.380424 -5.73532) (xy 415.369594 -5.761884) (xy 415.341091 -5.811668)
			(xy 415.305461 -5.856628) (xy 415.263508 -5.895753) (xy 415.216173 -5.928162) (xy 415.164524 -5.953126)
			(xy 415.109722 -5.970083) (xy 415.052999 -5.978651) (xy 415.024316 -5.97916) (xy 415.01356 -5.979051)
			(xy 414.992084 -5.977782) (xy 414.98139 -5.97662) (xy 414.970468 -5.97535) (xy 414.94964 -5.982208)
			(xy 414.88487 -6.041898) (xy 414.877256 -6.049585) (xy 414.868701 -6.069438) (xy 414.86836 -6.080252)
			(xy 414.86836 -6.080506) (xy 414.868614 -6.090666) (xy 414.868614 -6.091174) (xy 414.868106 -6.110224)
			(xy 414.867598 -6.121146) (xy 414.875218 -6.140958) (xy 414.944052 -6.210046) (xy 414.964118 -6.217412)
			(xy 414.97504 -6.216904) (xy 414.994598 -6.216396) (xy 414.994852 -6.216396) (xy 415.02212 -6.216946)
			(xy 415.076102 -6.2247) (xy 415.12843 -6.240059) (xy 415.17804 -6.262707) (xy 415.223922 -6.292186)
			(xy 415.265142 -6.327895) (xy 415.30086 -6.369106) (xy 415.330349 -6.414981) (xy 415.35301 -6.464586)
			(xy 415.36838 -6.51691) (xy 415.376148 -6.57089) (xy 415.376614 -6.598158) (xy 415.376169 -6.624999)
			(xy 415.368634 -6.67815) (xy 415.353734 -6.729724) (xy 415.331763 -6.778705) (xy 415.303153 -6.824128)
			(xy 415.268467 -6.8651) (xy 415.228388 -6.900815) (xy 415.183705 -6.930568) (xy 415.159698 -6.942582)
			(xy 415.151062 -6.946646) (xy 415.137854 -6.96087) (xy 415.10585 -7.043928) (xy 415.106104 -7.063232)
			(xy 415.10966 -7.072122) (xy 415.1184 -7.094807) (xy 415.130699 -7.141841) (xy 415.136932 -7.190055)
			(xy 415.137346 -7.214362) (xy 415.137346 -7.215124) (xy 415.136898 -7.242395) (xy 415.129132 -7.29638)
			(xy 415.113763 -7.348712) (xy 415.091103 -7.398323) (xy 415.061613 -7.444205) (xy 415.025894 -7.485422)
			(xy 414.984673 -7.521137) (xy 414.938788 -7.550622) (xy 414.889174 -7.573277) (xy 414.836841 -7.588641)
			(xy 414.782855 -7.596401) (xy 414.755584 -7.596886) (xy 414.725894 -7.596293) (xy 414.667231 -7.587091)
			(xy 414.610701 -7.568913) (xy 414.557671 -7.542197) (xy 414.509419 -7.507588) (xy 414.487868 -7.487158)
			(xy 414.478494 -7.478851) (xy 414.454541 -7.471644) (xy 414.442148 -7.473442) (xy 414.404336 -7.480683)
			(xy 414.327736 -7.488443) (xy 414.28924 -7.488936) (xy 414.246551 -7.488316) (xy 414.161708 -7.478757)
			(xy 414.07846 -7.459799) (xy 413.997845 -7.431679) (xy 413.920867 -7.394746) (xy 413.884364 -7.372604)
			(xy 413.876103 -7.367908) (xy 413.85744 -7.3644) (xy 413.838777 -7.367908) (xy 413.830516 -7.372604)
			(xy 413.794008 -7.39474) (xy 413.717036 -7.431688) (xy 413.636423 -7.459818) (xy 413.553174 -7.478778)
			(xy 413.46833 -7.488331) (xy 413.42564 -7.488936) (xy 413.386432 -7.488437) (xy 413.308427 -7.480423)
			(xy 413.269938 -7.472934) (xy 413.257449 -7.470944) (xy 413.233198 -7.478031) (xy 413.22371 -7.486396)
			(xy 413.20218 -7.506971) (xy 413.153877 -7.541801) (xy 413.100748 -7.5687) (xy 413.044084 -7.587014)
			(xy 412.985261 -7.596299) (xy 412.955486 -7.596886) (xy 412.928217 -7.596389) (xy 412.874235 -7.588626)
			(xy 412.821908 -7.57326) (xy 412.772299 -7.550604) (xy 412.726419 -7.521119) (xy 412.685202 -7.485405)
			(xy 412.649487 -7.444189) (xy 412.620001 -7.39831) (xy 412.597344 -7.348702) (xy 412.581976 -7.296374)
			(xy 412.574212 -7.242393) (xy 412.573724 -7.215124) (xy 412.574147 -7.190454) (xy 412.580552 -7.141529)
			(xy 412.593194 -7.093834) (xy 412.602172 -7.070852) (xy 412.602172 -7.070598) (xy 412.60526 -7.061657)
			(xy 412.605374 -7.042757) (xy 412.602426 -7.033768) (xy 412.574232 -6.959346) (xy 412.561532 -6.945376)
			(xy 412.552642 -6.941058) (xy 412.528881 -6.928977) (xy 412.484674 -6.899193) (xy 412.445046 -6.863544)
			(xy 412.410768 -6.822722) (xy 412.38251 -6.777525) (xy 412.360821 -6.728833) (xy 412.346125 -6.677595)
			(xy 412.338707 -6.62481) (xy 412.338266 -6.598158) (xy 406.26665 -6.598158) (xy 406.266185 -6.624998)
			(xy 406.25865 -6.678148) (xy 406.243752 -6.72972) (xy 406.221783 -6.778699) (xy 406.193176 -6.824122)
			(xy 406.158493 -6.865095) (xy 406.118418 -6.900811) (xy 406.073739 -6.930567) (xy 406.049734 -6.942582)
			(xy 406.041098 -6.946646) (xy 406.02789 -6.96087) (xy 405.995886 -7.043928) (xy 405.99614 -7.063232)
			(xy 405.999696 -7.072122) (xy 406.008438 -7.094806) (xy 406.020735 -7.141841) (xy 406.026968 -7.190055)
			(xy 406.027382 -7.214362) (xy 406.027382 -7.215124) (xy 406.026898 -7.242393) (xy 406.019134 -7.296376)
			(xy 406.003766 -7.348704) (xy 405.981109 -7.398313) (xy 405.951622 -7.444193) (xy 405.915907 -7.48541)
			(xy 405.87469 -7.521125) (xy 405.828809 -7.550611) (xy 405.7792 -7.573268) (xy 405.726872 -7.588634)
			(xy 405.672889 -7.596398) (xy 405.64562 -7.596886) (xy 405.615928 -7.596332) (xy 405.557263 -7.587121)
			(xy 405.500734 -7.568934) (xy 405.447703 -7.542209) (xy 405.399453 -7.507592) (xy 405.377904 -7.487158)
			(xy 405.368557 -7.478814) (xy 405.344582 -7.471629) (xy 405.332184 -7.473442) (xy 405.294371 -7.480677)
			(xy 405.217772 -7.488441) (xy 405.179276 -7.488936) (xy 405.136586 -7.488346) (xy 405.051742 -7.47878)
			(xy 404.968494 -7.459816) (xy 404.887879 -7.431688) (xy 404.810903 -7.394749) (xy 404.7744 -7.372604)
			(xy 404.766139 -7.367908) (xy 404.747476 -7.3644) (xy 404.728813 -7.367908) (xy 404.720552 -7.372604)
			(xy 404.684059 -7.394766) (xy 404.607083 -7.43171) (xy 404.526466 -7.459834) (xy 404.443214 -7.478788)
			(xy 404.358367 -7.488334) (xy 404.315676 -7.488936) (xy 404.276468 -7.488447) (xy 404.198463 -7.480426)
			(xy 404.159974 -7.472934) (xy 404.147483 -7.470968) (xy 404.123236 -7.478038) (xy 404.113746 -7.486396)
			(xy 404.092201 -7.506954) (xy 404.043902 -7.541786) (xy 403.990777 -7.568688) (xy 403.934116 -7.587007)
			(xy 403.875296 -7.596296) (xy 403.845522 -7.596886) (xy 403.818254 -7.596355) (xy 403.764273 -7.588597)
			(xy 403.711946 -7.573236) (xy 403.662338 -7.550584) (xy 403.616458 -7.521103) (xy 403.575241 -7.485392)
			(xy 403.539525 -7.444179) (xy 403.510038 -7.398303) (xy 403.48738 -7.348697) (xy 403.472013 -7.296372)
			(xy 403.464248 -7.242392) (xy 403.46376 -7.215124) (xy 403.464181 -7.190454) (xy 403.470586 -7.141529)
			(xy 403.483229 -7.093834) (xy 403.492208 -7.070852) (xy 403.492208 -7.070598) (xy 403.495298 -7.061658)
			(xy 403.495413 -7.042757) (xy 403.492462 -7.033768) (xy 403.464268 -6.959346) (xy 403.451568 -6.945376)
			(xy 403.442678 -6.941058) (xy 403.418902 -6.929006) (xy 403.374698 -6.899215) (xy 403.335072 -6.86356)
			(xy 403.300798 -6.822734) (xy 403.272542 -6.777533) (xy 403.250855 -6.728838) (xy 403.23616 -6.677598)
			(xy 403.228743 -6.624811) (xy 403.228302 -6.598158) (xy 403.228785 -6.570889) (xy 403.236552 -6.516907)
			(xy 403.251921 -6.46458) (xy 403.274579 -6.414972) (xy 403.304066 -6.369093) (xy 403.339781 -6.327877)
			(xy 403.380998 -6.292162) (xy 403.426877 -6.262676) (xy 403.476486 -6.240018) (xy 403.528813 -6.22465)
			(xy 403.582795 -6.216885) (xy 403.610064 -6.216396) (xy 403.610318 -6.216396) (xy 403.629876 -6.216904)
			(xy 403.640798 -6.217412) (xy 403.660864 -6.210046) (xy 403.729698 -6.140958) (xy 403.737318 -6.121146)
			(xy 403.73681 -6.110224) (xy 403.736302 -6.091174) (xy 403.736302 -6.09092) (xy 403.736556 -6.080252)
			(xy 403.736308 -6.06936) (xy 403.727748 -6.049349) (xy 403.720046 -6.041644) (xy 403.663404 -5.989574)
			(xy 403.65503 -5.982641) (xy 403.634375 -5.975929) (xy 403.623526 -5.97662) (xy 403.623018 -5.97662)
			(xy 403.612135 -5.977806) (xy 403.590277 -5.979075) (xy 403.57933 -5.97916) (xy 403.550479 -5.978576)
			(xy 403.493434 -5.969903) (xy 403.438342 -5.952748) (xy 403.386456 -5.927503) (xy 403.338958 -5.894742)
			(xy 403.296927 -5.855209) (xy 403.26132 -5.809805) (xy 403.232946 -5.759562) (xy 403.222206 -5.73278)
			(xy 403.217281 -5.721752) (xy 403.199384 -5.705581) (xy 403.187916 -5.701792) (xy 403.151185 -5.691556)
			(xy 403.079802 -5.664737) (xy 403.011444 -5.630942) (xy 402.978874 -5.611114) (xy 402.970618 -5.6064)
			(xy 402.95195 -5.602873) (xy 402.933282 -5.6064) (xy 402.925026 -5.611114) (xy 402.890904 -5.631823)
			(xy 402.819165 -5.666826) (xy 402.744165 -5.694153) (xy 402.70557 -5.704332) (xy 402.693883 -5.707982)
			(xy 402.675565 -5.724166) (xy 402.670518 -5.73532) (xy 402.65961 -5.76185) (xy 402.631116 -5.811631)
			(xy 402.595497 -5.856589) (xy 402.553555 -5.895715) (xy 402.506232 -5.928128) (xy 402.454594 -5.953098)
			(xy 402.399802 -5.970064) (xy 402.343089 -5.978644) (xy 402.31441 -5.97916) (xy 402.30359 -5.979062)
			(xy 402.281987 -5.977791) (xy 402.27123 -5.97662) (xy 402.260308 -5.97535) (xy 402.23948 -5.982208)
			(xy 402.17471 -6.041898) (xy 402.167101 -6.049591) (xy 402.158542 -6.069439) (xy 402.1582 -6.080252)
			(xy 402.1582 -6.080506) (xy 402.158454 -6.09092) (xy 402.158454 -6.091428) (xy 402.157946 -6.110224)
			(xy 402.157438 -6.121146) (xy 402.165058 -6.140958) (xy 402.233892 -6.210046) (xy 402.253958 -6.217412)
			(xy 402.26488 -6.216904) (xy 402.284438 -6.216396) (xy 402.284692 -6.216396) (xy 402.311959 -6.216932)
			(xy 402.365939 -6.224691) (xy 402.418265 -6.240053) (xy 402.467872 -6.262706) (xy 402.513751 -6.292187)
			(xy 402.554968 -6.327897) (xy 402.590683 -6.369109) (xy 402.62017 -6.414984) (xy 402.642829 -6.464588)
			(xy 402.658198 -6.516912) (xy 402.665965 -6.570891) (xy 402.666454 -6.598158) (xy 402.665955 -6.624974)
			(xy 402.658442 -6.678076) (xy 402.643571 -6.729605) (xy 402.621636 -6.778546) (xy 402.593068 -6.823935)
			(xy 402.558429 -6.86488) (xy 402.518401 -6.900575) (xy 402.473772 -6.930317) (xy 402.449792 -6.942328)
			(xy 402.441156 -6.946392) (xy 402.427948 -6.960616) (xy 402.39569 -7.043928) (xy 402.395944 -7.062724)
			(xy 402.3995 -7.071614) (xy 402.3995 -7.072122) (xy 402.408304 -7.094883) (xy 402.42073 -7.142076)
			(xy 402.427022 -7.19047) (xy 402.42744 -7.21487) (xy 402.42744 -7.215124) (xy 402.426998 -7.242395)
			(xy 402.419232 -7.296381) (xy 402.403863 -7.348713) (xy 402.381202 -7.398325) (xy 402.351712 -7.444207)
			(xy 402.315992 -7.485424) (xy 402.27477 -7.521139) (xy 402.228884 -7.550624) (xy 402.17927 -7.573279)
			(xy 402.126936 -7.588642) (xy 402.072949 -7.596401) (xy 402.045678 -7.596886) (xy 402.015964 -7.596337)
			(xy 401.957253 -7.587122) (xy 401.900676 -7.568934) (xy 401.847594 -7.542209) (xy 401.799288 -7.507593)
			(xy 401.777708 -7.487158) (xy 401.768359 -7.478816) (xy 401.744386 -7.47163) (xy 401.731988 -7.473442)
			(xy 401.694175 -7.480677) (xy 401.617576 -7.488441) (xy 401.57908 -7.488936) (xy 401.53639 -7.488344)
			(xy 401.451546 -7.478779) (xy 401.368298 -7.459815) (xy 401.287683 -7.431688) (xy 401.210707 -7.394749)
			(xy 401.174204 -7.372604) (xy 401.165943 -7.367908) (xy 401.14728 -7.3644) (xy 401.128617 -7.367908)
			(xy 401.120356 -7.372604) (xy 401.083862 -7.394765) (xy 401.006887 -7.431709) (xy 400.92627 -7.459833)
			(xy 400.843018 -7.478787) (xy 400.758171 -7.488334) (xy 400.71548 -7.488936) (xy 400.714972 -7.488936)
			(xy 400.676018 -7.488406) (xy 400.598524 -7.480386) (xy 400.560286 -7.472934) (xy 400.547825 -7.471057)
			(xy 400.523707 -7.478252) (xy 400.514312 -7.48665) (xy 400.492699 -7.507152) (xy 400.444332 -7.541923)
			(xy 400.391157 -7.568771) (xy 400.334462 -7.587046) (xy 400.275618 -7.596306) (xy 400.245834 -7.596886)
			(xy 400.24558 -7.596886) (xy 400.218311 -7.596394) (xy 400.164329 -7.58863) (xy 400.112001 -7.573264)
			(xy 400.062392 -7.550607) (xy 400.016513 -7.521121) (xy 399.975296 -7.485407) (xy 399.939581 -7.44419)
			(xy 399.910095 -7.398311) (xy 399.887438 -7.348703) (xy 399.87207 -7.296375) (xy 399.864306 -7.242393)
			(xy 399.863818 -7.215124) (xy 399.864209 -7.190503) (xy 399.870529 -7.141668) (xy 399.883081 -7.094053)
			(xy 399.892012 -7.071106) (xy 399.895568 -7.062216) (xy 399.895822 -7.042912) (xy 399.867628 -6.968744)
			(xy 399.863885 -6.959986) (xy 399.851084 -6.945898) (xy 399.842736 -6.941312) (xy 399.842482 -6.941312)
			(xy 399.818734 -6.929184) (xy 399.774533 -6.899356) (xy 399.734913 -6.863669) (xy 399.700642 -6.822816)
			(xy 399.672388 -6.777594) (xy 399.650701 -6.72888) (xy 399.636001 -6.677623) (xy 399.628574 -6.62482)
			(xy 399.628106 -6.598158) (xy 399.628585 -6.570889) (xy 399.636352 -6.516907) (xy 399.651721 -6.464579)
			(xy 399.67438 -6.414971) (xy 399.703867 -6.369092) (xy 399.739583 -6.327876) (xy 399.7808 -6.292161)
			(xy 399.82668 -6.262675) (xy 399.876289 -6.240017) (xy 399.928617 -6.22465) (xy 399.982599 -6.216885)
			(xy 400.009868 -6.216396) (xy 400.010122 -6.216396) (xy 400.02968 -6.216904) (xy 400.040602 -6.217412)
			(xy 400.060668 -6.210046) (xy 400.129502 -6.140958) (xy 400.137122 -6.121146) (xy 400.136614 -6.110224)
			(xy 400.136106 -6.091428) (xy 400.136106 -6.09092) (xy 400.13636 -6.080506) (xy 400.13636 -6.080252)
			(xy 400.136044 -6.069428) (xy 400.127505 -6.049554) (xy 400.11985 -6.041898) (xy 400.063208 -5.989574)
			(xy 400.054833 -5.982643) (xy 400.034179 -5.97593) (xy 400.02333 -5.97662) (xy 400.022822 -5.97662)
			(xy 400.012065 -5.977791) (xy 399.990462 -5.979063) (xy 399.979642 -5.97916) (xy 399.979388 -5.97916)
			(xy 399.950536 -5.978613) (xy 399.893489 -5.969933) (xy 399.838396 -5.952772) (xy 399.786511 -5.927522)
			(xy 399.739012 -5.894755) (xy 399.696982 -5.855218) (xy 399.661376 -5.80981) (xy 399.633004 -5.759564)
			(xy 399.622264 -5.73278) (xy 399.617359 -5.72174) (xy 399.599448 -5.705575) (xy 399.587974 -5.701792)
			(xy 399.55124 -5.691565) (xy 399.479858 -5.664742) (xy 399.411501 -5.630943) (xy 399.378932 -5.611114)
			(xy 399.370676 -5.6064) (xy 399.352008 -5.602873) (xy 399.33334 -5.6064) (xy 399.325084 -5.611114)
			(xy 399.290967 -5.631832) (xy 399.219226 -5.666832) (xy 399.144224 -5.694155) (xy 399.105628 -5.704332)
			(xy 399.093934 -5.707964) (xy 399.07562 -5.724161) (xy 399.070576 -5.73532) (xy 399.059703 -5.761865)
			(xy 399.031205 -5.811647) (xy 398.995581 -5.856607) (xy 398.953634 -5.895732) (xy 398.906306 -5.928143)
			(xy 398.854663 -5.95311) (xy 398.799866 -5.970072) (xy 398.743149 -5.978647) (xy 398.714468 -5.97916)
			(xy 398.703648 -5.979066) (xy 398.682045 -5.977793) (xy 398.671288 -5.97662) (xy 398.660366 -5.97535)
			(xy 398.639538 -5.982208) (xy 398.574768 -6.041898) (xy 398.567153 -6.049585) (xy 398.558599 -6.069438)
			(xy 398.558258 -6.080252) (xy 398.558258 -6.080506) (xy 398.558512 -6.09092) (xy 398.558512 -6.091428)
			(xy 398.558004 -6.110224) (xy 398.557496 -6.121146) (xy 398.565116 -6.140958) (xy 398.63395 -6.210046)
			(xy 398.654016 -6.217412) (xy 398.664938 -6.216904) (xy 398.684496 -6.216396) (xy 398.68475 -6.216396)
			(xy 398.712019 -6.216878) (xy 398.766 -6.224645) (xy 398.818327 -6.240015) (xy 398.867935 -6.262674)
			(xy 398.913813 -6.292161) (xy 398.955029 -6.327876) (xy 398.990744 -6.369093) (xy 399.02023 -6.414972)
			(xy 399.042888 -6.46458) (xy 399.058256 -6.516908) (xy 399.066023 -6.570889) (xy 399.066512 -6.598158)
			(xy 399.066012 -6.624997) (xy 399.058479 -6.678143) (xy 399.043583 -6.729713) (xy 399.021618 -6.77869)
			(xy 398.993016 -6.824113) (xy 398.95834 -6.865086) (xy 398.918271 -6.900804) (xy 398.873598 -6.930564)
			(xy 398.849596 -6.942582) (xy 398.84096 -6.946646) (xy 398.827752 -6.96087) (xy 398.795748 -7.043928)
			(xy 398.796002 -7.063232) (xy 398.799558 -7.072122) (xy 398.808298 -7.094807) (xy 398.820596 -7.141841)
			(xy 398.82683 -7.190055) (xy 398.827244 -7.214362) (xy 398.827244 -7.215124) (xy 398.826798 -7.242395)
			(xy 398.819032 -7.296381) (xy 398.803663 -7.348712) (xy 398.781003 -7.398324) (xy 398.751513 -7.444205)
			(xy 398.715793 -7.485423) (xy 398.674572 -7.521138) (xy 398.628687 -7.550623) (xy 398.579073 -7.573278)
			(xy 398.52674 -7.588641) (xy 398.472753 -7.596401) (xy 398.445482 -7.596886) (xy 398.415792 -7.596294)
			(xy 398.357129 -7.587092) (xy 398.300599 -7.568914) (xy 398.247568 -7.542197) (xy 398.199316 -7.507588)
			(xy 398.177766 -7.487158) (xy 398.168393 -7.47885) (xy 398.144439 -7.471643) (xy 398.132046 -7.473442)
			(xy 398.094234 -7.480683) (xy 398.017634 -7.488443) (xy 397.979138 -7.488936) (xy 397.936449 -7.488317)
			(xy 397.851606 -7.478758) (xy 397.768358 -7.4598) (xy 397.687743 -7.431679) (xy 397.610765 -7.394746)
			(xy 397.574262 -7.372604) (xy 397.566001 -7.367908) (xy 397.547338 -7.3644) (xy 397.528675 -7.367908)
			(xy 397.520414 -7.372604) (xy 397.483906 -7.39474) (xy 397.406935 -7.431689) (xy 397.326321 -7.459818)
			(xy 397.243072 -7.478778) (xy 397.158228 -7.488331) (xy 397.115538 -7.488936) (xy 397.11503 -7.488936)
			(xy 397.076077 -7.488397) (xy 396.998582 -7.480383) (xy 396.960344 -7.472934) (xy 396.947881 -7.471096)
			(xy 396.923768 -7.478264) (xy 396.91437 -7.48665) (xy 396.892775 -7.507172) (xy 396.844403 -7.54194)
			(xy 396.791224 -7.568784) (xy 396.734525 -7.587055) (xy 396.675677 -7.59631) (xy 396.645892 -7.596886)
			(xy 396.645638 -7.596886) (xy 396.618369 -7.596363) (xy 396.564386 -7.588607) (xy 396.512055 -7.573247)
			(xy 396.462444 -7.550595) (xy 396.416561 -7.521114) (xy 396.375341 -7.485403) (xy 396.339623 -7.444188)
			(xy 396.310134 -7.398311) (xy 396.287475 -7.348703) (xy 396.272106 -7.296375) (xy 396.264341 -7.242393)
			(xy 396.263876 -7.215124) (xy 396.264263 -7.190503) (xy 396.270585 -7.141668) (xy 396.283139 -7.094053)
			(xy 396.29207 -7.071106) (xy 396.295626 -7.062216) (xy 396.29588 -7.042912) (xy 396.267686 -6.968744)
			(xy 396.263957 -6.959979) (xy 396.251147 -6.945894) (xy 396.242794 -6.941312) (xy 396.24254 -6.941312)
			(xy 396.218782 -6.929203) (xy 396.174583 -6.89937) (xy 396.134965 -6.863679) (xy 396.100696 -6.822824)
			(xy 396.072444 -6.777599) (xy 396.050757 -6.728883) (xy 396.036058 -6.677625) (xy 396.028632 -6.62482)
			(xy 396.028164 -6.598158) (xy 396.028585 -6.570886) (xy 396.036354 -6.516899) (xy 396.051726 -6.464567)
			(xy 396.074388 -6.414955) (xy 396.103881 -6.369073) (xy 396.139603 -6.327855) (xy 396.180827 -6.29214)
			(xy 396.226715 -6.262656) (xy 396.276331 -6.240002) (xy 396.328666 -6.224639) (xy 396.382654 -6.216881)
			(xy 396.409926 -6.216396) (xy 396.41018 -6.216396) (xy 396.429738 -6.216904) (xy 396.44066 -6.217412)
			(xy 396.460726 -6.210046) (xy 396.52956 -6.140958) (xy 396.53718 -6.121146) (xy 396.536672 -6.110224)
			(xy 396.536164 -6.091174) (xy 396.536164 -6.09092) (xy 396.536418 -6.080252) (xy 396.536181 -6.069359)
			(xy 396.527615 -6.049347) (xy 396.519908 -6.041644) (xy 396.463266 -5.989574) (xy 396.454906 -5.982622)
			(xy 396.43424 -5.975921) (xy 396.423388 -5.97662) (xy 396.42288 -5.97662) (xy 396.411996 -5.977801)
			(xy 396.390139 -5.979074) (xy 396.379192 -5.97916) (xy 396.350325 -5.978602) (xy 396.293247 -5.969935)
			(xy 396.238126 -5.952769) (xy 396.186219 -5.927495) (xy 396.138712 -5.894692) (xy 396.096687 -5.855106)
			(xy 396.061105 -5.809642) (xy 396.032778 -5.759337) (xy 396.022068 -5.732526) (xy 396.017066 -5.72148)
			(xy 395.999048 -5.705306) (xy 395.987524 -5.701538) (xy 395.950881 -5.691279) (xy 395.879673 -5.664442)
			(xy 395.811486 -5.630658) (xy 395.77899 -5.61086) (xy 395.770729 -5.606164) (xy 395.752066 -5.602656)
			(xy 395.733403 -5.606164) (xy 395.725142 -5.61086) (xy 395.690986 -5.631622) (xy 395.61917 -5.666722)
			(xy 395.544078 -5.694124) (xy 395.505432 -5.704332) (xy 395.493738 -5.707965) (xy 395.475424 -5.724162)
			(xy 395.47038 -5.73532) (xy 395.459503 -5.761864) (xy 395.431006 -5.811646) (xy 395.395383 -5.856605)
			(xy 395.353436 -5.89573) (xy 395.306108 -5.928142) (xy 395.254466 -5.953109) (xy 395.19967 -5.970072)
			(xy 395.142953 -5.978647) (xy 395.114272 -5.97916) (xy 395.103516 -5.979054) (xy 395.08204 -5.977783)
			(xy 395.071346 -5.97662) (xy 395.060424 -5.97535) (xy 395.039596 -5.982208) (xy 394.974826 -6.041898)
			(xy 394.967205 -6.049579) (xy 394.958656 -6.069437) (xy 394.958316 -6.080252) (xy 394.958316 -6.080506)
			(xy 394.95857 -6.090666) (xy 394.95857 -6.091174) (xy 394.958062 -6.110224) (xy 394.957554 -6.121146)
			(xy 394.965174 -6.140958) (xy 395.034008 -6.210046) (xy 395.054074 -6.217412) (xy 395.064996 -6.216904)
			(xy 395.084554 -6.216396) (xy 395.084808 -6.216396) (xy 395.112076 -6.216917) (xy 395.166056 -6.224679)
			(xy 395.218382 -6.240043) (xy 395.26799 -6.262697) (xy 395.313868 -6.29218) (xy 395.355085 -6.327891)
			(xy 395.3908 -6.369104) (xy 395.420287 -6.414981) (xy 395.442945 -6.464586) (xy 395.458314 -6.516911)
			(xy 395.466081 -6.57089) (xy 395.46657 -6.598158) (xy 395.466094 -6.624998) (xy 395.45856 -6.678146)
			(xy 395.443662 -6.729717) (xy 395.421695 -6.778696) (xy 395.393089 -6.824119) (xy 395.358408 -6.865092)
			(xy 395.318335 -6.900809) (xy 395.273658 -6.930566) (xy 395.249654 -6.942582) (xy 395.241018 -6.946646)
			(xy 395.22781 -6.96087) (xy 395.195806 -7.043928) (xy 395.19606 -7.063232) (xy 395.199616 -7.072122)
			(xy 395.208359 -7.094806) (xy 395.220655 -7.141841) (xy 395.226888 -7.190055) (xy 395.227302 -7.214362)
			(xy 395.227302 -7.215124) (xy 395.226798 -7.242392) (xy 395.219034 -7.296373) (xy 395.203668 -7.3487)
			(xy 395.181012 -7.398307) (xy 395.151527 -7.444186) (xy 395.115814 -7.485403) (xy 395.074599 -7.521117)
			(xy 395.028721 -7.550604) (xy 394.979115 -7.573262) (xy 394.926789 -7.588631) (xy 394.872808 -7.596397)
			(xy 394.84554 -7.596886) (xy 394.815849 -7.59632) (xy 394.757185 -7.587112) (xy 394.700655 -7.568927)
			(xy 394.647624 -7.542205) (xy 394.599374 -7.507591) (xy 394.577824 -7.487158) (xy 394.568469 -7.478826)
			(xy 394.544501 -7.471633) (xy 394.532104 -7.473442) (xy 394.494291 -7.480674) (xy 394.417692 -7.48844)
			(xy 394.379196 -7.488936) (xy 394.336506 -7.488337) (xy 394.251663 -7.478773) (xy 394.168415 -7.459811)
			(xy 394.0878 -7.431685) (xy 394.010823 -7.394748) (xy 393.97432 -7.372604) (xy 393.966059 -7.367908)
			(xy 393.947396 -7.3644) (xy 393.928733 -7.367908) (xy 393.920472 -7.372604) (xy 393.883975 -7.394758)
			(xy 393.807 -7.431703) (xy 393.726384 -7.459829) (xy 393.643133 -7.478785) (xy 393.558287 -7.488333)
			(xy 393.515596 -7.488936) (xy 393.515088 -7.488936) (xy 393.476135 -7.488403) (xy 393.39864 -7.480385)
			(xy 393.360402 -7.472934) (xy 393.34794 -7.471067) (xy 393.323824 -7.478255) (xy 393.314428 -7.48665)
			(xy 393.292808 -7.507144) (xy 393.244443 -7.541916) (xy 393.19127 -7.568766) (xy 393.134576 -7.587043)
			(xy 393.075733 -7.596305) (xy 393.04595 -7.596886) (xy 393.045696 -7.596886) (xy 393.018428 -7.596379)
			(xy 392.964446 -7.588618) (xy 392.912118 -7.573253) (xy 392.86251 -7.550598) (xy 392.81663 -7.521114)
			(xy 392.775413 -7.485401) (xy 392.739698 -7.444186) (xy 392.710211 -7.398308) (xy 392.687554 -7.3487)
			(xy 392.672186 -7.296374) (xy 392.664422 -7.242392) (xy 392.663934 -7.215124) (xy 392.664324 -7.190503)
			(xy 392.670645 -7.141668) (xy 392.683197 -7.094053) (xy 392.692128 -7.071106) (xy 392.695684 -7.062216)
			(xy 392.695938 -7.042912) (xy 392.667744 -6.968744) (xy 392.663995 -6.959989) (xy 392.651199 -6.9459)
			(xy 392.642852 -6.941312) (xy 392.642598 -6.941312) (xy 392.618853 -6.929177) (xy 392.574653 -6.89935)
			(xy 392.535031 -6.863665) (xy 392.50076 -6.822813) (xy 392.472506 -6.777592) (xy 392.450817 -6.728879)
			(xy 392.436117 -6.677622) (xy 392.42869 -6.624819) (xy 392.428222 -6.598158) (xy 389.125968 -6.598158)
			(xy 389.125968 -9.780016) (xy 389.125476 -9.863891) (xy 389.117494 -10.03145) (xy 389.101547 -10.198439)
			(xy 389.077674 -10.364481) (xy 389.045926 -10.529198) (xy 389.006377 -10.692219) (xy 388.959116 -10.853173)
			(xy 388.904249 -11.011695) (xy 388.841902 -11.167428) (xy 388.772216 -11.320018) (xy 388.695348 -11.469118)
			(xy 388.611473 -11.614393) (xy 388.52078 -11.755512) (xy 388.423475 -11.892156) (xy 388.319779 -12.024015)
			(xy 388.209926 -12.150791) (xy 388.094165 -12.272196) (xy 387.986471 -12.37488) (xy 430.986438 -12.37488)
			(xy 430.986906 -12.34761) (xy 430.99467 -12.293626) (xy 431.010038 -12.241296) (xy 431.032697 -12.191686)
			(xy 431.062185 -12.145805) (xy 431.097902 -12.104588) (xy 431.139121 -12.068873) (xy 431.185003 -12.039387)
			(xy 431.234615 -12.016731) (xy 431.286945 -12.001366) (xy 431.34093 -11.993604) (xy 431.3682 -11.993118)
			(xy 431.397892 -11.993658) (xy 431.456558 -12.002872) (xy 431.513088 -12.021063) (xy 431.566118 -12.047791)
			(xy 431.614367 -12.082411) (xy 431.635916 -12.102846) (xy 431.645254 -12.111202) (xy 431.669236 -12.11838)
			(xy 431.681636 -12.116562) (xy 431.719448 -12.109324) (xy 431.796048 -12.101562) (xy 431.834544 -12.101068)
			(xy 431.877233 -12.10171) (xy 431.962074 -12.111266) (xy 432.045321 -12.130219) (xy 432.125937 -12.158335)
			(xy 432.202915 -12.195262) (xy 432.23942 -12.2174) (xy 432.247681 -12.222096) (xy 432.266344 -12.225604)
			(xy 432.285007 -12.222096) (xy 432.293268 -12.2174) (xy 432.32978 -12.195272) (xy 432.406751 -12.158322)
			(xy 432.487363 -12.13019) (xy 432.570611 -12.111229) (xy 432.655454 -12.101674) (xy 432.698144 -12.101068)
			(xy 432.698652 -12.101068) (xy 432.737606 -12.101595) (xy 432.8151 -12.109616) (xy 432.853338 -12.11707)
			(xy 432.865797 -12.11899) (xy 432.889923 -12.11177) (xy 432.899312 -12.103354) (xy 432.920915 -12.082842)
			(xy 432.969285 -12.048072) (xy 433.022462 -12.021226) (xy 433.07916 -12.002953) (xy 433.138005 -11.993696)
			(xy 433.16779 -11.993118) (xy 433.168044 -11.993118) (xy 433.195314 -11.993583) (xy 433.249297 -12.001351)
			(xy 433.301626 -12.016721) (xy 433.351235 -12.03938) (xy 433.397114 -12.068869) (xy 433.438331 -12.104586)
			(xy 433.474045 -12.145805) (xy 433.503531 -12.191687) (xy 433.526188 -12.241297) (xy 433.541554 -12.293627)
			(xy 433.549318 -12.34761) (xy 433.549806 -12.37488) (xy 433.549335 -12.400788) (xy 436.813452 -12.400788)
			(xy 436.813941 -12.359678) (xy 436.821529 -12.27781) (xy 436.83664 -12.196991) (xy 436.859145 -12.117912)
			(xy 436.888851 -12.041247) (xy 436.925505 -11.96765) (xy 436.968795 -11.89775) (xy 437.01835 -11.832142)
			(xy 437.073748 -11.771388) (xy 437.134516 -11.716006) (xy 437.200136 -11.666467) (xy 437.270047 -11.623195)
			(xy 437.343653 -11.58656) (xy 437.420326 -11.556873) (xy 437.499411 -11.534389) (xy 437.580234 -11.519298)
			(xy 437.662104 -11.511731) (xy 437.703214 -11.51128) (xy 437.747029 -11.511772) (xy 437.83424 -11.520318)
			(xy 437.920187 -11.537406) (xy 438.004035 -11.562868) (xy 438.084971 -11.596458) (xy 438.123838 -11.61669)
			(xy 438.135191 -11.622017) (xy 438.160237 -11.622017) (xy 438.17159 -11.61669) (xy 438.210465 -11.596477)
			(xy 438.291405 -11.562905) (xy 438.375252 -11.537448) (xy 438.461195 -11.520353) (xy 438.548401 -11.511784)
			(xy 438.592214 -11.51128) (xy 438.636029 -11.511772) (xy 438.72324 -11.520318) (xy 438.809187 -11.537406)
			(xy 438.893035 -11.562868) (xy 438.973971 -11.596458) (xy 439.012838 -11.61669) (xy 439.024191 -11.622017)
			(xy 439.049237 -11.622017) (xy 439.06059 -11.61669) (xy 439.099465 -11.596477) (xy 439.180405 -11.562905)
			(xy 439.264252 -11.537448) (xy 439.350195 -11.520353) (xy 439.437401 -11.511784) (xy 439.481214 -11.51128)
			(xy 439.521951 -11.511719) (xy 439.603086 -11.519152) (xy 439.683202 -11.533973) (xy 439.761626 -11.556057)
			(xy 439.837703 -11.585219) (xy 439.910794 -11.621216) (xy 439.94578 -11.64209) (xy 439.954798 -11.647053)
			(xy 439.975154 -11.650004) (xy 439.995036 -11.644737) (xy 440.003438 -11.638788) (xy 440.091322 -11.570462)
			(xy 440.10072 -11.54049) (xy 440.095894 -11.52525) (xy 440.083229 -11.482506) (xy 440.065483 -11.395136)
			(xy 440.056563 -11.306429) (xy 440.056016 -11.261852) (xy 440.056016 -11.26109) (xy 440.056438 -11.22287)
			(xy 440.062998 -11.146712) (xy 440.076079 -11.071399) (xy 440.095582 -10.997489) (xy 440.108086 -10.96137)
			(xy 440.110695 -10.953059) (xy 440.110679 -10.935651) (xy 440.108086 -10.927334) (xy 440.095582 -10.891215)
			(xy 440.076095 -10.817302) (xy 440.063015 -10.74199) (xy 440.056437 -10.665834) (xy 440.056016 -10.627614)
			(xy 440.056016 -10.626852) (xy 440.05652 -10.584504) (xy 440.064571 -10.50019) (xy 440.0806 -10.417024)
			(xy 440.104461 -10.335757) (xy 440.13594 -10.257127) (xy 440.174751 -10.181846) (xy 440.220541 -10.110594)
			(xy 440.272897 -10.044018) (xy 440.331345 -9.98272) (xy 440.395355 -9.927255) (xy 440.464347 -9.878126)
			(xy 440.537697 -9.835777) (xy 440.61474 -9.800593) (xy 440.694779 -9.772891) (xy 440.777088 -9.752923)
			(xy 440.860923 -9.74087) (xy 440.945524 -9.73684) (xy 441.030125 -9.74087) (xy 441.11396 -9.752923)
			(xy 441.196269 -9.772891) (xy 441.276308 -9.800593) (xy 441.353351 -9.835777) (xy 441.426701 -9.878126)
			(xy 441.495693 -9.927255) (xy 441.559703 -9.98272) (xy 441.618151 -10.044018) (xy 441.670507 -10.110594)
			(xy 441.716297 -10.181846) (xy 441.755108 -10.257127) (xy 441.786587 -10.335757) (xy 441.810448 -10.417024)
			(xy 441.826477 -10.50019) (xy 441.834528 -10.584504) (xy 441.835032 -10.626852) (xy 441.835032 -10.627614)
			(xy 441.834614 -10.665834) (xy 441.828053 -10.741992) (xy 441.814972 -10.817305) (xy 441.795467 -10.891215)
			(xy 441.782962 -10.927334) (xy 441.780399 -10.935656) (xy 441.780383 -10.953054) (xy 441.782962 -10.96137)
			(xy 441.795465 -10.997489) (xy 441.814952 -11.071403) (xy 441.828033 -11.146715) (xy 441.834611 -11.22287)
			(xy 441.835032 -11.26109) (xy 441.835032 -11.261852) (xy 441.834502 -11.302954) (xy 441.826922 -11.384807)
			(xy 441.811821 -11.465611) (xy 441.789329 -11.544677) (xy 441.759637 -11.621331) (xy 441.722999 -11.694918)
			(xy 441.679728 -11.764811) (xy 441.630192 -11.830413) (xy 441.574815 -11.891164) (xy 441.514068 -11.946546)
			(xy 441.44847 -11.996087) (xy 441.378581 -12.039364) (xy 441.304997 -12.076008) (xy 441.228346 -12.105706)
			(xy 441.149281 -12.128204) (xy 441.068478 -12.143312) (xy 440.986626 -12.150899) (xy 440.945524 -12.15136)
			(xy 440.945016 -12.15136) (xy 440.904322 -12.150875) (xy 440.823276 -12.143416) (xy 440.74325 -12.128584)
			(xy 440.664913 -12.106505) (xy 440.58892 -12.077363) (xy 440.515907 -12.041401) (xy 440.480958 -12.02055)
			(xy 440.471926 -12.015614) (xy 440.451579 -12.012649) (xy 440.431701 -12.017907) (xy 440.4233 -12.023852)
			(xy 440.335416 -12.092178) (xy 440.326018 -12.12215) (xy 440.330844 -12.13739) (xy 440.343568 -12.180123)
			(xy 440.361398 -12.267491) (xy 440.370394 -12.356204) (xy 440.370638 -12.37488) (xy 444.98133 -12.37488)
			(xy 444.981806 -12.347611) (xy 444.98957 -12.293627) (xy 445.004937 -12.241298) (xy 445.027595 -12.191688)
			(xy 445.057083 -12.145808) (xy 445.092799 -12.10459) (xy 445.134017 -12.068875) (xy 445.179899 -12.03939)
			(xy 445.229509 -12.016733) (xy 445.281839 -12.001367) (xy 445.335822 -11.993605) (xy 445.363092 -11.993118)
			(xy 445.392806 -11.993684) (xy 445.451515 -12.002895) (xy 445.508093 -12.021079) (xy 445.561174 -12.0478)
			(xy 445.609482 -12.082412) (xy 445.631062 -12.102846) (xy 445.640423 -12.111171) (xy 445.664386 -12.118367)
			(xy 445.676782 -12.116562) (xy 445.714593 -12.109317) (xy 445.791194 -12.101559) (xy 445.82969 -12.101068)
			(xy 445.872379 -12.101688) (xy 445.957221 -12.111249) (xy 446.040469 -12.130208) (xy 446.121084 -12.158328)
			(xy 446.198062 -12.195259) (xy 446.234566 -12.2174) (xy 446.242827 -12.222096) (xy 446.26149 -12.225604)
			(xy 446.280153 -12.222096) (xy 446.288414 -12.2174) (xy 446.324915 -12.195252) (xy 446.401889 -12.158306)
			(xy 446.482504 -12.130179) (xy 446.565754 -12.111222) (xy 446.6506 -12.101672) (xy 446.69329 -12.101068)
			(xy 446.693798 -12.101068) (xy 446.732751 -12.101603) (xy 446.810246 -12.109619) (xy 446.848484 -12.11707)
			(xy 446.860946 -12.118954) (xy 446.885066 -12.111758) (xy 446.894458 -12.103354) (xy 446.916042 -12.08282)
			(xy 446.964416 -12.048053) (xy 447.017598 -12.021211) (xy 447.074301 -12.002943) (xy 447.13315 -11.993692)
			(xy 447.162936 -11.993118) (xy 447.16319 -11.993118) (xy 447.190458 -11.993634) (xy 447.24444 -12.001393)
			(xy 447.296768 -12.016757) (xy 447.346376 -12.03941) (xy 447.392256 -12.068893) (xy 447.433474 -12.104605)
			(xy 447.469189 -12.14582) (xy 447.498676 -12.191697) (xy 447.521333 -12.241304) (xy 447.5367 -12.293631)
			(xy 447.544464 -12.347612) (xy 447.544952 -12.37488) (xy 447.544428 -12.403035) (xy 447.536105 -12.458728)
			(xy 447.519695 -12.512595) (xy 447.495554 -12.563469) (xy 447.464205 -12.610248) (xy 447.445638 -12.63142)
			(xy 447.437635 -12.641221) (xy 447.431511 -12.66574) (xy 447.433954 -12.678156) (xy 447.444761 -12.723941)
			(xy 447.456357 -12.8173) (xy 447.457068 -12.864338) (xy 447.457068 -12.864846) (xy 447.456598 -12.904848)
			(xy 447.448231 -12.984412) (xy 447.431593 -13.062666) (xy 447.406867 -13.138753) (xy 447.374323 -13.211838)
			(xy 447.334318 -13.281121) (xy 447.287291 -13.345843) (xy 447.233756 -13.405295) (xy 447.1743 -13.458826)
			(xy 447.109574 -13.505849) (xy 447.040288 -13.545849) (xy 446.967201 -13.578387) (xy 446.891112 -13.603108)
			(xy 446.812857 -13.61974) (xy 446.733292 -13.628101) (xy 446.69329 -13.628624) (xy 446.650601 -13.628014)
			(xy 446.565758 -13.618451) (xy 446.482511 -13.59949) (xy 446.401895 -13.571368) (xy 446.324918 -13.534434)
			(xy 446.288414 -13.512292) (xy 446.280153 -13.507596) (xy 446.26149 -13.504088) (xy 446.242827 -13.507596)
			(xy 446.234566 -13.512292) (xy 446.198069 -13.534447) (xy 446.121095 -13.571392) (xy 446.040478 -13.599518)
			(xy 445.957227 -13.618473) (xy 445.872381 -13.628021) (xy 445.82969 -13.628624) (xy 445.789691 -13.628064)
			(xy 445.710131 -13.619701) (xy 445.631881 -13.603069) (xy 445.555798 -13.578348) (xy 445.482716 -13.54581)
			(xy 445.413435 -13.505812) (xy 445.348714 -13.458791) (xy 445.289263 -13.405263) (xy 445.235732 -13.345814)
			(xy 445.188708 -13.281096) (xy 445.148706 -13.211816) (xy 445.116165 -13.138736) (xy 445.091441 -13.062654)
			(xy 445.074804 -12.984405) (xy 445.066438 -12.904845) (xy 445.065912 -12.864846) (xy 445.066666 -12.817023)
			(xy 445.078641 -12.722128) (xy 445.089788 -12.675616) (xy 445.092263 -12.663288) (xy 445.086273 -12.638902)
			(xy 445.078358 -12.629134) (xy 445.06019 -12.608035) (xy 445.029521 -12.561565) (xy 445.005932 -12.511132)
			(xy 444.989923 -12.457806) (xy 444.981834 -12.402719) (xy 444.98133 -12.37488) (xy 440.370638 -12.37488)
			(xy 440.370976 -12.400788) (xy 440.370415 -12.444238) (xy 440.361895 -12.530719) (xy 440.344992 -12.615959)
			(xy 440.319868 -12.699148) (xy 440.286761 -12.779495) (xy 440.266836 -12.81811) (xy 440.262961 -12.82623)
			(xy 440.260628 -12.84406) (xy 440.262264 -12.852908) (xy 440.272023 -12.900055) (xy 440.282457 -12.995773)
			(xy 440.283092 -13.043916) (xy 440.282667 -13.085188) (xy 440.275027 -13.167377) (xy 440.259804 -13.248505)
			(xy 440.23713 -13.327874) (xy 440.2072 -13.4048) (xy 440.170271 -13.478622) (xy 440.126661 -13.548705)
			(xy 440.076745 -13.614446) (xy 440.020952 -13.675279) (xy 439.959763 -13.730681) (xy 439.893704 -13.780175)
			(xy 439.823344 -13.823336) (xy 439.786522 -13.841984) (xy 439.778885 -13.846179) (xy 439.766763 -13.858679)
			(xy 439.759479 -13.874495) (xy 439.758328 -13.883132) (xy 439.755251 -13.911241) (xy 439.741951 -13.966197)
			(xy 439.720685 -14.018587) (xy 439.69192 -14.067266) (xy 439.656285 -14.111165) (xy 439.643167 -14.123162)
			(xy 440.58586 -14.123162) (xy 440.586283 -14.084873) (xy 440.592885 -14.008579) (xy 440.60603 -13.933136)
			(xy 440.625619 -13.859105) (xy 440.638184 -13.822934) (xy 440.640853 -13.814502) (xy 440.64084 -13.796827)
			(xy 440.638184 -13.78839) (xy 440.625655 -13.752208) (xy 440.606078 -13.678176) (xy 440.592927 -13.602738)
			(xy 440.586298 -13.52645) (xy 440.58586 -13.488162) (xy 440.586364 -13.445801) (xy 440.594417 -13.361464)
			(xy 440.610451 -13.278274) (xy 440.634319 -13.196984) (xy 440.665807 -13.118332) (xy 440.704629 -13.043029)
			(xy 440.750432 -12.971757) (xy 440.802803 -12.905161) (xy 440.861268 -12.843846) (xy 440.925296 -12.788365)
			(xy 440.994308 -12.739222) (xy 441.067678 -12.696862) (xy 441.144743 -12.661667) (xy 441.224805 -12.633958)
			(xy 441.307138 -12.613984) (xy 441.390997 -12.601927) (xy 441.475622 -12.597896) (xy 441.560247 -12.601927)
			(xy 441.644106 -12.613984) (xy 441.726439 -12.633958) (xy 441.806501 -12.661667) (xy 441.883566 -12.696862)
			(xy 441.956936 -12.739222) (xy 442.025948 -12.788365) (xy 442.089976 -12.843846) (xy 442.148441 -12.905161)
			(xy 442.200812 -12.971757) (xy 442.246615 -13.043029) (xy 442.285437 -13.118332) (xy 442.316925 -13.196984)
			(xy 442.340793 -13.278274) (xy 442.356827 -13.361464) (xy 442.36488 -13.445801) (xy 442.365384 -13.488162)
			(xy 442.364966 -13.526452) (xy 442.358362 -13.602745) (xy 442.345216 -13.678188) (xy 442.325626 -13.752219)
			(xy 442.31306 -13.78839) (xy 442.310428 -13.796831) (xy 442.310415 -13.814498) (xy 442.31306 -13.822934)
			(xy 442.325598 -13.859113) (xy 442.345172 -13.933146) (xy 442.358321 -14.008585) (xy 442.364947 -14.084874)
			(xy 442.365384 -14.123162) (xy 442.36488 -14.165523) (xy 442.356827 -14.24986) (xy 442.340793 -14.33305)
			(xy 442.316925 -14.41434) (xy 442.285437 -14.492992) (xy 442.268155 -14.526514) (xy 449.780152 -14.526514)
			(xy 449.780656 -14.484153) (xy 449.788709 -14.399816) (xy 449.804743 -14.316626) (xy 449.828611 -14.235336)
			(xy 449.860099 -14.156684) (xy 449.898921 -14.081381) (xy 449.944724 -14.010109) (xy 449.997095 -13.943513)
			(xy 450.05556 -13.882198) (xy 450.119588 -13.826717) (xy 450.1886 -13.777574) (xy 450.26197 -13.735214)
			(xy 450.339035 -13.700019) (xy 450.419097 -13.67231) (xy 450.50143 -13.652336) (xy 450.585289 -13.640279)
			(xy 450.669914 -13.636248) (xy 450.754539 -13.640279) (xy 450.838398 -13.652336) (xy 450.920731 -13.67231)
			(xy 451.000793 -13.700019) (xy 451.077858 -13.735214) (xy 451.151228 -13.777574) (xy 451.22024 -13.826717)
			(xy 451.284268 -13.882198) (xy 451.342733 -13.943513) (xy 451.395104 -14.010109) (xy 451.440907 -14.081381)
			(xy 451.479729 -14.156684) (xy 451.511217 -14.235336) (xy 451.535085 -14.316626) (xy 451.551119 -14.399816)
			(xy 451.559172 -14.484153) (xy 451.559676 -14.526514) (xy 451.559114 -14.571839) (xy 451.549887 -14.662018)
			(xy 451.531531 -14.750791) (xy 451.504235 -14.837234) (xy 451.486778 -14.879066) (xy 451.483143 -14.888844)
			(xy 451.483128 -14.909681) (xy 451.486778 -14.919452) (xy 451.504363 -14.961485) (xy 451.531877 -15.048351)
			(xy 451.550364 -15.137575) (xy 451.559632 -15.228222) (xy 451.560184 -15.273782) (xy 451.559623 -15.318552)
			(xy 451.550621 -15.407639) (xy 451.532717 -15.495371) (xy 451.506092 -15.580861) (xy 451.489064 -15.62227)
			(xy 451.485509 -15.631864) (xy 451.485503 -15.652304) (xy 451.489064 -15.661894) (xy 451.50607 -15.703278)
			(xy 451.532693 -15.788702) (xy 451.550602 -15.876368) (xy 451.559616 -15.96539) (xy 451.560184 -16.010128)
			(xy 451.560184 -16.010382) (xy 451.55968 -16.05273) (xy 451.551629 -16.137044) (xy 451.5356 -16.22021)
			(xy 451.511739 -16.301477) (xy 451.48026 -16.380107) (xy 451.441449 -16.455388) (xy 451.395659 -16.52664)
			(xy 451.343303 -16.593216) (xy 451.284855 -16.654514) (xy 451.220845 -16.709979) (xy 451.151853 -16.759108)
			(xy 451.078503 -16.801457) (xy 451.00146 -16.836641) (xy 450.921421 -16.864343) (xy 450.839112 -16.884311)
			(xy 450.755277 -16.896364) (xy 450.670676 -16.900395) (xy 450.586075 -16.896364) (xy 450.50224 -16.884311)
			(xy 450.419931 -16.864343) (xy 450.339892 -16.836641) (xy 450.262849 -16.801457) (xy 450.189499 -16.759108)
			(xy 450.120507 -16.709979) (xy 450.056497 -16.654514) (xy 449.998049 -16.593216) (xy 449.945693 -16.52664)
			(xy 449.899903 -16.455388) (xy 449.861092 -16.380107) (xy 449.829613 -16.301477) (xy 449.805752 -16.22021)
			(xy 449.789723 -16.137044) (xy 449.781672 -16.05273) (xy 449.781168 -16.010382) (xy 449.781168 -16.010128)
			(xy 449.781731 -15.96539) (xy 449.790749 -15.876368) (xy 449.808655 -15.788701) (xy 449.83527 -15.703273)
			(xy 449.852288 -15.661894) (xy 449.855865 -15.652307) (xy 449.855859 -15.63186) (xy 449.852288 -15.62227)
			(xy 449.835263 -15.580859) (xy 449.808628 -15.495372) (xy 449.790721 -15.40764) (xy 449.781723 -15.318552)
			(xy 449.781168 -15.273782) (xy 449.781749 -15.228458) (xy 449.79099 -15.138283) (xy 449.809345 -15.049513)
			(xy 449.836623 -14.963067) (xy 449.854066 -14.92123) (xy 449.857691 -14.911438) (xy 449.857571 -14.890584)
			(xy 449.853812 -14.880844) (xy 449.836183 -14.838823) (xy 449.808624 -14.751958) (xy 449.790079 -14.662732)
			(xy 449.780742 -14.57208) (xy 449.780152 -14.526514) (xy 442.268155 -14.526514) (xy 442.246615 -14.568295)
			(xy 442.200812 -14.639567) (xy 442.148441 -14.706163) (xy 442.089976 -14.767478) (xy 442.025948 -14.822959)
			(xy 441.956936 -14.872102) (xy 441.883566 -14.914462) (xy 441.806501 -14.949657) (xy 441.726439 -14.977366)
			(xy 441.644106 -14.99734) (xy 441.560247 -15.009397) (xy 441.475622 -15.013429) (xy 441.390997 -15.009397)
			(xy 441.307138 -14.99734) (xy 441.224805 -14.977366) (xy 441.144743 -14.949657) (xy 441.067678 -14.914462)
			(xy 440.994308 -14.872102) (xy 440.925296 -14.822959) (xy 440.861268 -14.767478) (xy 440.802803 -14.706163)
			(xy 440.750432 -14.639567) (xy 440.704629 -14.568295) (xy 440.665807 -14.492992) (xy 440.634319 -14.41434)
			(xy 440.610451 -14.33305) (xy 440.594417 -14.24986) (xy 440.586364 -14.165523) (xy 440.58586 -14.123162)
			(xy 439.643167 -14.123162) (xy 439.614561 -14.149324) (xy 439.567661 -14.180907) (xy 439.516614 -14.205222)
			(xy 439.462537 -14.221736) (xy 439.406615 -14.230088) (xy 439.378344 -14.230604) (xy 439.350975 -14.230111)
			(xy 439.296797 -14.2223) (xy 439.244294 -14.206817) (xy 439.194547 -14.183981) (xy 439.148579 -14.154262)
			(xy 439.127646 -14.136624) (xy 439.127392 -14.13637) (xy 439.120314 -14.130771) (xy 439.103391 -14.124533)
			(xy 439.094372 -14.124178) (xy 439.027316 -14.124178) (xy 439.018301 -14.124547) (xy 439.001384 -14.130787)
			(xy 438.994296 -14.13637) (xy 438.994296 -14.136624) (xy 438.994042 -14.136624) (xy 438.973108 -14.154261)
			(xy 438.927135 -14.183972) (xy 438.877388 -14.206808) (xy 438.824888 -14.2223) (xy 438.770713 -14.230129)
			(xy 438.743344 -14.230604) (xy 438.713998 -14.230028) (xy 438.656001 -14.221024) (xy 438.600065 -14.203253)
			(xy 438.547506 -14.177132) (xy 438.499563 -14.143277) (xy 438.457364 -14.102486) (xy 438.421903 -14.055718)
			(xy 438.394015 -14.004075) (xy 438.38368 -13.976604) (xy 438.380221 -13.968026) (xy 438.368225 -13.953963)
			(xy 438.360312 -13.949172) (xy 438.333388 -13.93444) (xy 438.324705 -13.93016) (xy 438.305508 -13.927807)
			(xy 438.29605 -13.929868) (xy 438.259095 -13.939128) (xy 438.184005 -13.952036) (xy 438.108086 -13.958466)
			(xy 438.06999 -13.958824) (xy 438.028658 -13.958363) (xy 437.94635 -13.95071) (xy 437.865107 -13.935453)
			(xy 437.78563 -13.912724) (xy 437.708605 -13.882718) (xy 437.634696 -13.845694) (xy 437.564542 -13.801972)
			(xy 437.498747 -13.751929) (xy 437.43788 -13.695998) (xy 437.382465 -13.634659) (xy 437.332981 -13.568444)
			(xy 437.289854 -13.497922) (xy 437.253456 -13.423703) (xy 437.224103 -13.346427) (xy 437.202046 -13.266761)
			(xy 437.187477 -13.185391) (xy 437.18353 -13.144246) (xy 437.182106 -13.133691) (xy 437.171856 -13.11505)
			(xy 437.163718 -13.108178) (xy 437.131484 -13.082996) (xy 437.071245 -13.027653) (xy 437.016344 -12.967011)
			(xy 436.967245 -12.901582) (xy 436.924364 -12.831919) (xy 436.888063 -12.758612) (xy 436.858649 -12.682281)
			(xy 436.83637 -12.603571) (xy 436.821416 -12.523147) (xy 436.813913 -12.441689) (xy 436.813452 -12.400788)
			(xy 433.549335 -12.400788) (xy 433.549294 -12.403036) (xy 433.540969 -12.45873) (xy 433.524557 -12.512597)
			(xy 433.500414 -12.563471) (xy 433.469061 -12.610249) (xy 433.450492 -12.63142) (xy 433.442494 -12.641224)
			(xy 433.436365 -12.665741) (xy 433.438808 -12.678156) (xy 433.449615 -12.723941) (xy 433.461211 -12.8173)
			(xy 433.461922 -12.864338) (xy 433.461922 -12.864846) (xy 433.461398 -12.904846) (xy 433.453032 -12.984407)
			(xy 433.436395 -13.062658) (xy 433.411671 -13.138741) (xy 433.37913 -13.211824) (xy 433.339129 -13.281105)
			(xy 433.292106 -13.345825) (xy 433.238575 -13.405276) (xy 433.179124 -13.458807) (xy 433.114403 -13.50583)
			(xy 433.045122 -13.545831) (xy 432.972039 -13.578372) (xy 432.895956 -13.603096) (xy 432.817705 -13.619732)
			(xy 432.738144 -13.628098) (xy 432.698144 -13.628624) (xy 432.655455 -13.627989) (xy 432.570614 -13.618432)
			(xy 432.487366 -13.599476) (xy 432.406751 -13.571359) (xy 432.329772 -13.534431) (xy 432.293268 -13.512292)
			(xy 432.285007 -13.507596) (xy 432.266344 -13.504088) (xy 432.247681 -13.507596) (xy 432.23942 -13.512292)
			(xy 432.20291 -13.534425) (xy 432.125939 -13.571374) (xy 432.045326 -13.599504) (xy 431.962078 -13.618465)
			(xy 431.877234 -13.628018) (xy 431.834544 -13.628624) (xy 431.794546 -13.628013) (xy 431.714987 -13.619656)
			(xy 431.636738 -13.603028) (xy 431.560656 -13.578312) (xy 431.487574 -13.545779) (xy 431.418293 -13.505785)
			(xy 431.353572 -13.458768) (xy 431.29412 -13.405244) (xy 431.240588 -13.345798) (xy 431.193564 -13.281083)
			(xy 431.153562 -13.211806) (xy 431.12102 -13.138728) (xy 431.096295 -13.062649) (xy 431.079658 -12.984402)
			(xy 431.071292 -12.904844) (xy 431.070766 -12.864846) (xy 431.070766 -12.864338) (xy 431.071539 -12.816579)
			(xy 431.083509 -12.721812) (xy 431.094642 -12.675362) (xy 431.097165 -12.663039) (xy 431.091145 -12.638645)
			(xy 431.083212 -12.62888) (xy 431.065086 -12.607791) (xy 431.034497 -12.561353) (xy 431.010971 -12.510968)
			(xy 430.995005 -12.457702) (xy 430.986939 -12.402684) (xy 430.986438 -12.37488) (xy 387.986471 -12.37488)
			(xy 387.972758 -12.387955) (xy 387.845981 -12.497807) (xy 387.714121 -12.601501) (xy 387.577476 -12.698805)
			(xy 387.436355 -12.789496) (xy 387.29108 -12.873369) (xy 387.141978 -12.950235) (xy 386.989387 -13.01992)
			(xy 386.833654 -13.082265) (xy 386.675131 -13.137129) (xy 386.514176 -13.184388) (xy 386.351155 -13.223935)
			(xy 386.186437 -13.255681) (xy 386.020395 -13.279553) (xy 385.853406 -13.295497) (xy 385.685847 -13.303478)
			(xy 385.601972 -13.304012) (xy 260.800088 -13.304012) (xy 260.768924 -13.304522) (xy 260.707128 -13.31266)
			(xy 260.646924 -13.328793) (xy 260.58934 -13.352646) (xy 260.535363 -13.383812) (xy 260.485915 -13.421756)
			(xy 260.441843 -13.46583) (xy 260.403901 -13.51528) (xy 260.372737 -13.569258) (xy 260.348886 -13.626843)
			(xy 260.332756 -13.687048) (xy 260.324621 -13.748844) (xy 260.324092 -13.780008) (xy 260.324092 -17.137634)
			(xy 310.13197 -17.137634) (xy 310.136013 -17.041183) (xy 310.148112 -16.945408) (xy 310.168183 -16.850982)
			(xy 310.196085 -16.758566) (xy 310.231622 -16.668809) (xy 310.274545 -16.582341) (xy 310.324553 -16.499767)
			(xy 310.381296 -16.421668) (xy 310.444374 -16.348591) (xy 310.513347 -16.281048) (xy 310.587729 -16.219514)
			(xy 310.666999 -16.164419) (xy 310.750602 -16.116151) (xy 310.83795 -16.075048) (xy 310.928432 -16.041399)
			(xy 311.021411 -16.015438) (xy 311.116237 -15.997349) (xy 311.212245 -15.987258) (xy 311.308759 -15.985237)
			(xy 311.405105 -15.991298) (xy 311.500605 -16.005401) (xy 311.59459 -16.027445) (xy 311.686402 -16.057276)
			(xy 311.775395 -16.094685) (xy 311.860945 -16.13941) (xy 311.942453 -16.191136) (xy 312.019347 -16.249502)
			(xy 312.091087 -16.314097) (xy 312.15717 -16.384469) (xy 312.217133 -16.460123) (xy 312.270556 -16.54053)
			(xy 312.317062 -16.625125) (xy 312.356327 -16.713315) (xy 312.388074 -16.804481) (xy 312.412082 -16.897985)
			(xy 312.428181 -16.993169) (xy 312.436259 -17.089366) (xy 312.436764 -17.137634) (xy 312.436259 -17.185902)
			(xy 312.428181 -17.282099) (xy 312.412082 -17.377283) (xy 312.388074 -17.470787) (xy 312.356327 -17.561953)
			(xy 312.321724 -17.639671) (xy 388.966684 -17.639671) (xy 388.966684 -17.585129) (xy 388.974446 -17.531143)
			(xy 388.989811 -17.478811) (xy 389.012467 -17.429198) (xy 389.041953 -17.383314) (xy 389.077668 -17.342093)
			(xy 389.118885 -17.306374) (xy 389.164767 -17.276884) (xy 389.214377 -17.254224) (xy 389.266708 -17.238854)
			(xy 389.320693 -17.231087) (xy 389.347964 -17.230598) (xy 389.37184 -17.23136) (xy 389.389578 -17.201218)
			(xy 389.429774 -17.143978) (xy 389.452104 -17.11706) (xy 389.459422 -17.107371) (xy 389.465005 -17.083781)
			(xy 389.462772 -17.071848) (xy 389.457447 -17.04917) (xy 389.451718 -17.002938) (xy 389.451342 -16.979646)
			(xy 389.451342 -16.979138) (xy 389.451837 -16.951868) (xy 389.459594 -16.897882) (xy 389.474956 -16.845549)
			(xy 389.497609 -16.795936) (xy 389.527093 -16.750052) (xy 389.562807 -16.708831) (xy 389.604025 -16.673113)
			(xy 389.649906 -16.643625) (xy 389.699518 -16.620967) (xy 389.751849 -16.605601) (xy 389.805834 -16.597839)
			(xy 389.833104 -16.597376) (xy 389.861805 -16.597968) (xy 389.918558 -16.606576) (xy 389.973383 -16.623581)
			(xy 390.025046 -16.648601) (xy 390.072381 -16.681071) (xy 390.114323 -16.720262) (xy 390.149927 -16.765288)
			(xy 390.17839 -16.815137) (xy 390.189212 -16.841724) (xy 390.19422 -16.852833) (xy 390.212399 -16.869011)
			(xy 390.22401 -16.872712) (xy 390.261734 -16.88292) (xy 390.335057 -16.909977) (xy 390.405232 -16.944382)
			(xy 390.43864 -16.96466) (xy 390.446896 -16.969374) (xy 390.465564 -16.972901) (xy 390.484232 -16.969374)
			(xy 390.492488 -16.96466) (xy 390.525896 -16.94438) (xy 390.59607 -16.909973) (xy 390.66939 -16.882908)
			(xy 390.707118 -16.872712) (xy 390.718728 -16.86901) (xy 390.736902 -16.85283) (xy 390.741916 -16.841724)
			(xy 390.75273 -16.815127) (xy 390.781173 -16.765256) (xy 390.816766 -16.720208) (xy 390.858705 -16.681)
			(xy 390.906045 -16.648517) (xy 390.957716 -16.623492) (xy 391.012553 -16.606489) (xy 391.069318 -16.597892)
			(xy 391.098024 -16.597376) (xy 391.125297 -16.597779) (xy 391.179288 -16.605546) (xy 391.231624 -16.620917)
			(xy 391.28124 -16.64358) (xy 391.327126 -16.673074) (xy 391.368346 -16.708798) (xy 391.404063 -16.750024)
			(xy 391.43355 -16.795914) (xy 391.456205 -16.845534) (xy 391.471568 -16.897872) (xy 391.479325 -16.951865)
			(xy 391.479786 -16.979138) (xy 391.479786 -16.979646) (xy 391.479408 -17.002938) (xy 391.473673 -17.049168)
			(xy 391.468356 -17.071848) (xy 391.46608 -17.083783) (xy 391.471658 -17.107396) (xy 391.479024 -17.11706)
			(xy 391.501353 -17.143979) (xy 391.54155 -17.201218) (xy 391.559288 -17.23136) (xy 391.583164 -17.230598)
			(xy 391.610434 -17.231139) (xy 391.664419 -17.238896) (xy 391.71675 -17.254258) (xy 391.766363 -17.276911)
			(xy 391.812246 -17.306394) (xy 391.853466 -17.342108) (xy 391.889184 -17.383325) (xy 391.918672 -17.429205)
			(xy 391.94133 -17.478816) (xy 391.956696 -17.531146) (xy 391.964459 -17.58513) (xy 391.964458 -17.63967)
			(xy 391.964458 -17.639671) (xy 394.554684 -17.639671) (xy 394.554684 -17.585129) (xy 394.562446 -17.531143)
			(xy 394.577811 -17.478811) (xy 394.600467 -17.429198) (xy 394.629953 -17.383314) (xy 394.665668 -17.342093)
			(xy 394.706885 -17.306374) (xy 394.752767 -17.276884) (xy 394.802377 -17.254224) (xy 394.854708 -17.238854)
			(xy 394.908693 -17.231087) (xy 394.935964 -17.230598) (xy 394.95984 -17.23136) (xy 394.977578 -17.201218)
			(xy 395.017774 -17.143978) (xy 395.040104 -17.11706) (xy 395.047422 -17.107371) (xy 395.053005 -17.083781)
			(xy 395.050772 -17.071848) (xy 395.045447 -17.04917) (xy 395.039718 -17.002938) (xy 395.039342 -16.979646)
			(xy 395.039342 -16.979138) (xy 395.039837 -16.951868) (xy 395.047594 -16.897882) (xy 395.062956 -16.845549)
			(xy 395.085609 -16.795936) (xy 395.115093 -16.750052) (xy 395.150807 -16.708831) (xy 395.192025 -16.673113)
			(xy 395.237906 -16.643625) (xy 395.287518 -16.620967) (xy 395.339849 -16.605601) (xy 395.393834 -16.597839)
			(xy 395.421104 -16.597376) (xy 395.449805 -16.597968) (xy 395.506558 -16.606576) (xy 395.561383 -16.623581)
			(xy 395.613046 -16.648601) (xy 395.660381 -16.681071) (xy 395.702323 -16.720262) (xy 395.737927 -16.765288)
			(xy 395.76639 -16.815137) (xy 395.777212 -16.841724) (xy 395.78222 -16.852833) (xy 395.800399 -16.869011)
			(xy 395.81201 -16.872712) (xy 395.849734 -16.88292) (xy 395.923057 -16.909977) (xy 395.993232 -16.944382)
			(xy 396.02664 -16.96466) (xy 396.034896 -16.969374) (xy 396.053564 -16.972901) (xy 396.072232 -16.969374)
			(xy 396.080488 -16.96466) (xy 396.113896 -16.94438) (xy 396.18407 -16.909973) (xy 396.25739 -16.882908)
			(xy 396.295118 -16.872712) (xy 396.306728 -16.86901) (xy 396.324902 -16.85283) (xy 396.329916 -16.841724)
			(xy 396.34073 -16.815127) (xy 396.369173 -16.765256) (xy 396.404766 -16.720208) (xy 396.446705 -16.681)
			(xy 396.494045 -16.648517) (xy 396.545716 -16.623492) (xy 396.600553 -16.606489) (xy 396.657318 -16.597892)
			(xy 396.686024 -16.597376) (xy 396.713297 -16.597779) (xy 396.767288 -16.605546) (xy 396.819624 -16.620917)
			(xy 396.86924 -16.64358) (xy 396.915126 -16.673074) (xy 396.956346 -16.708798) (xy 396.992063 -16.750024)
			(xy 397.02155 -16.795914) (xy 397.044205 -16.845534) (xy 397.059568 -16.897872) (xy 397.067325 -16.951865)
			(xy 397.067786 -16.979138) (xy 397.067786 -16.979646) (xy 397.067408 -17.002938) (xy 397.061673 -17.049168)
			(xy 397.056356 -17.071848) (xy 397.05408 -17.083783) (xy 397.059658 -17.107396) (xy 397.067024 -17.11706)
			(xy 397.089353 -17.143979) (xy 397.12955 -17.201218) (xy 397.147288 -17.23136) (xy 397.171164 -17.230598)
			(xy 397.198434 -17.231139) (xy 397.252419 -17.238896) (xy 397.30475 -17.254258) (xy 397.354363 -17.276911)
			(xy 397.400246 -17.306394) (xy 397.441466 -17.342108) (xy 397.477184 -17.383325) (xy 397.506672 -17.429205)
			(xy 397.52933 -17.478816) (xy 397.544696 -17.531146) (xy 397.552459 -17.58513) (xy 397.552458 -17.63967)
			(xy 397.552458 -17.639671) (xy 400.142684 -17.639671) (xy 400.142684 -17.585129) (xy 400.150446 -17.531143)
			(xy 400.165811 -17.478811) (xy 400.188467 -17.429198) (xy 400.217953 -17.383314) (xy 400.253668 -17.342093)
			(xy 400.294885 -17.306374) (xy 400.340767 -17.276884) (xy 400.390377 -17.254224) (xy 400.442708 -17.238854)
			(xy 400.496693 -17.231087) (xy 400.523964 -17.230598) (xy 400.54784 -17.23136) (xy 400.565578 -17.201218)
			(xy 400.605774 -17.143978) (xy 400.628104 -17.11706) (xy 400.635422 -17.107371) (xy 400.641005 -17.083781)
			(xy 400.638772 -17.071848) (xy 400.633447 -17.04917) (xy 400.627718 -17.002938) (xy 400.627342 -16.979646)
			(xy 400.627342 -16.979138) (xy 400.627837 -16.951868) (xy 400.635594 -16.897882) (xy 400.650956 -16.845549)
			(xy 400.673609 -16.795936) (xy 400.703093 -16.750052) (xy 400.738807 -16.708831) (xy 400.780025 -16.673113)
			(xy 400.825906 -16.643625) (xy 400.875518 -16.620967) (xy 400.927849 -16.605601) (xy 400.981834 -16.597839)
			(xy 401.009104 -16.597376) (xy 401.037805 -16.597968) (xy 401.094558 -16.606576) (xy 401.149383 -16.623581)
			(xy 401.201046 -16.648601) (xy 401.248381 -16.681071) (xy 401.290323 -16.720262) (xy 401.325927 -16.765288)
			(xy 401.35439 -16.815137) (xy 401.365212 -16.841724) (xy 401.37022 -16.852833) (xy 401.388399 -16.869011)
			(xy 401.40001 -16.872712) (xy 401.437734 -16.88292) (xy 401.511057 -16.909977) (xy 401.581232 -16.944382)
			(xy 401.61464 -16.96466) (xy 401.622896 -16.969374) (xy 401.641564 -16.972901) (xy 401.660232 -16.969374)
			(xy 401.668488 -16.96466) (xy 401.701896 -16.94438) (xy 401.77207 -16.909973) (xy 401.84539 -16.882908)
			(xy 401.883118 -16.872712) (xy 401.894728 -16.86901) (xy 401.912902 -16.85283) (xy 401.917916 -16.841724)
			(xy 401.92873 -16.815127) (xy 401.957173 -16.765256) (xy 401.992766 -16.720208) (xy 402.034705 -16.681)
			(xy 402.082045 -16.648517) (xy 402.133716 -16.623492) (xy 402.188553 -16.606489) (xy 402.245318 -16.597892)
			(xy 402.274024 -16.597376) (xy 402.301297 -16.597779) (xy 402.355288 -16.605546) (xy 402.407624 -16.620917)
			(xy 402.45724 -16.64358) (xy 402.503126 -16.673074) (xy 402.544346 -16.708798) (xy 402.580063 -16.750024)
			(xy 402.60955 -16.795914) (xy 402.632205 -16.845534) (xy 402.647568 -16.897872) (xy 402.655325 -16.951865)
			(xy 402.655786 -16.979138) (xy 402.655786 -16.979646) (xy 402.655408 -17.002938) (xy 402.649673 -17.049168)
			(xy 402.644356 -17.071848) (xy 402.64208 -17.083783) (xy 402.647658 -17.107396) (xy 402.655024 -17.11706)
			(xy 402.677353 -17.143979) (xy 402.71755 -17.201218) (xy 402.735288 -17.23136) (xy 402.759164 -17.230598)
			(xy 402.786434 -17.231139) (xy 402.840419 -17.238896) (xy 402.89275 -17.254258) (xy 402.942363 -17.276911)
			(xy 402.988246 -17.306394) (xy 403.029466 -17.342108) (xy 403.065184 -17.383325) (xy 403.094672 -17.429205)
			(xy 403.11733 -17.478816) (xy 403.132696 -17.531146) (xy 403.140459 -17.58513) (xy 403.140458 -17.63967)
			(xy 403.140358 -17.640366) (xy 405.730746 -17.640366) (xy 405.730746 -17.585834) (xy 405.738507 -17.531857)
			(xy 405.753869 -17.479533) (xy 405.776521 -17.429928) (xy 405.806002 -17.384051) (xy 405.841712 -17.342837)
			(xy 405.882923 -17.307124) (xy 405.928796 -17.277639) (xy 405.978399 -17.254982) (xy 406.030721 -17.239614)
			(xy 406.084698 -17.231849) (xy 406.111964 -17.23136) (xy 406.134824 -17.232122) (xy 406.152721 -17.201764)
			(xy 406.193299 -17.14414) (xy 406.21585 -17.11706) (xy 406.223163 -17.107368) (xy 406.228751 -17.08378)
			(xy 406.226518 -17.071848) (xy 406.221292 -17.04935) (xy 406.215691 -17.003502) (xy 406.215342 -16.980408)
			(xy 406.215342 -16.9799) (xy 406.215801 -16.952629) (xy 406.223564 -16.898642) (xy 406.23893 -16.846309)
			(xy 406.261588 -16.796695) (xy 406.291076 -16.750811) (xy 406.326794 -16.709591) (xy 406.368015 -16.673874)
			(xy 406.413899 -16.644386) (xy 406.463512 -16.621729) (xy 406.515846 -16.606363) (xy 406.569833 -16.598601)
			(xy 406.597104 -16.598138) (xy 406.625832 -16.598652) (xy 406.682636 -16.607283) (xy 406.737508 -16.62432)
			(xy 406.789212 -16.649379) (xy 406.836581 -16.681896) (xy 406.87855 -16.721137) (xy 406.914171 -16.766218)
			(xy 406.942643 -16.816123) (xy 406.953466 -16.84274) (xy 406.958491 -16.85384) (xy 406.976658 -16.87002)
			(xy 406.988264 -16.873728) (xy 407.02577 -16.883926) (xy 407.098656 -16.910938) (xy 407.168414 -16.945227)
			(xy 407.201624 -16.965422) (xy 407.20988 -16.970136) (xy 407.228548 -16.973663) (xy 407.247216 -16.970136)
			(xy 407.255472 -16.965422) (xy 407.289022 -16.945008) (xy 407.359518 -16.910385) (xy 407.4332 -16.883193)
			(xy 407.471118 -16.872966) (xy 407.482685 -16.869299) (xy 407.500848 -16.853258) (xy 407.505916 -16.842232)
			(xy 407.516699 -16.815636) (xy 407.545184 -16.765813) (xy 407.580805 -16.720814) (xy 407.622758 -16.681652)
			(xy 407.670099 -16.64921) (xy 407.721762 -16.624217) (xy 407.776583 -16.607237) (xy 407.833329 -16.598652)
			(xy 407.862024 -16.598138) (xy 407.889294 -16.598602) (xy 407.943278 -16.606367) (xy 407.995608 -16.621735)
			(xy 408.045219 -16.644394) (xy 408.091099 -16.673883) (xy 408.132317 -16.7096) (xy 408.168032 -16.75082)
			(xy 408.197517 -16.796703) (xy 408.220173 -16.846314) (xy 408.235538 -16.898645) (xy 408.2433 -16.95263)
			(xy 408.243786 -16.9799) (xy 408.243425 -17.003518) (xy 408.237561 -17.05039) (xy 408.232102 -17.073372)
			(xy 408.229792 -17.085344) (xy 408.235211 -17.109077) (xy 408.242516 -17.118838) (xy 408.264678 -17.145528)
			(xy 408.304615 -17.20226) (xy 408.322272 -17.232122) (xy 408.347164 -17.23136) (xy 408.374438 -17.231777)
			(xy 408.428432 -17.239536) (xy 408.480772 -17.2549) (xy 408.530393 -17.277556) (xy 408.576284 -17.307045)
			(xy 408.61751 -17.342764) (xy 408.653234 -17.383988) (xy 408.682726 -17.429876) (xy 408.705388 -17.479494)
			(xy 408.720757 -17.531833) (xy 408.72852 -17.585826) (xy 408.72852 -17.640372) (xy 411.317624 -17.640372)
			(xy 411.317624 -17.585828) (xy 411.325387 -17.53184) (xy 411.340754 -17.479507) (xy 411.363414 -17.429893)
			(xy 411.392904 -17.38401) (xy 411.428625 -17.342791) (xy 411.469849 -17.307076) (xy 411.515736 -17.277591)
			(xy 411.565352 -17.254938) (xy 411.617687 -17.239576) (xy 411.671676 -17.23182) (xy 411.698948 -17.23136)
			(xy 411.722824 -17.232122) (xy 411.740721 -17.201764) (xy 411.781299 -17.14414) (xy 411.80385 -17.11706)
			(xy 411.811163 -17.107368) (xy 411.816751 -17.08378) (xy 411.814518 -17.071848) (xy 411.809292 -17.04935)
			(xy 411.803691 -17.003502) (xy 411.803342 -16.980408) (xy 411.803342 -16.9799) (xy 411.803801 -16.952629)
			(xy 411.811564 -16.898642) (xy 411.82693 -16.846309) (xy 411.849588 -16.796695) (xy 411.879076 -16.750811)
			(xy 411.914794 -16.709591) (xy 411.956015 -16.673874) (xy 412.001899 -16.644386) (xy 412.051512 -16.621729)
			(xy 412.103846 -16.606363) (xy 412.157833 -16.598601) (xy 412.185104 -16.598138) (xy 412.213832 -16.598652)
			(xy 412.270636 -16.607283) (xy 412.325508 -16.62432) (xy 412.377212 -16.649379) (xy 412.424581 -16.681896)
			(xy 412.46655 -16.721137) (xy 412.502171 -16.766218) (xy 412.530643 -16.816123) (xy 412.541466 -16.84274)
			(xy 412.546491 -16.85384) (xy 412.564658 -16.87002) (xy 412.576264 -16.873728) (xy 412.61377 -16.883926)
			(xy 412.686656 -16.910938) (xy 412.756414 -16.945227) (xy 412.789624 -16.965422) (xy 412.79788 -16.970136)
			(xy 412.816548 -16.973663) (xy 412.835216 -16.970136) (xy 412.843472 -16.965422) (xy 412.877022 -16.945008)
			(xy 412.947518 -16.910385) (xy 413.0212 -16.883193) (xy 413.059118 -16.872966) (xy 413.070685 -16.869299)
			(xy 413.088848 -16.853258) (xy 413.093916 -16.842232) (xy 413.104699 -16.815636) (xy 413.133184 -16.765813)
			(xy 413.168805 -16.720814) (xy 413.210758 -16.681652) (xy 413.258099 -16.64921) (xy 413.309762 -16.624217)
			(xy 413.364583 -16.607237) (xy 413.421329 -16.598652) (xy 413.450024 -16.598138) (xy 413.477294 -16.598602)
			(xy 413.531278 -16.606367) (xy 413.583608 -16.621735) (xy 413.633219 -16.644394) (xy 413.679099 -16.673883)
			(xy 413.720317 -16.7096) (xy 413.756032 -16.75082) (xy 413.785517 -16.796703) (xy 413.808173 -16.846314)
			(xy 413.823538 -16.898645) (xy 413.8313 -16.95263) (xy 413.831786 -16.9799) (xy 413.831425 -17.003518)
			(xy 413.825561 -17.05039) (xy 413.820102 -17.073372) (xy 413.817792 -17.085344) (xy 413.823211 -17.109077)
			(xy 413.830516 -17.118838) (xy 413.852678 -17.145528) (xy 413.892615 -17.20226) (xy 413.910272 -17.232122)
			(xy 413.934148 -17.23136) (xy 413.961417 -17.231806) (xy 414.015398 -17.239573) (xy 414.067725 -17.254944)
			(xy 414.117332 -17.277604) (xy 414.16321 -17.307093) (xy 414.204424 -17.34281) (xy 414.240136 -17.384029)
			(xy 414.269619 -17.42991) (xy 414.292273 -17.47952) (xy 414.307637 -17.531849) (xy 414.315398 -17.585831)
			(xy 414.315398 -17.639671) (xy 417.212484 -17.639671) (xy 417.212484 -17.585129) (xy 417.220246 -17.531141)
			(xy 417.235612 -17.478808) (xy 417.258269 -17.429194) (xy 417.287757 -17.383309) (xy 417.323473 -17.342088)
			(xy 417.364693 -17.306369) (xy 417.410576 -17.276879) (xy 417.460189 -17.254219) (xy 417.512522 -17.238851)
			(xy 417.566509 -17.231086) (xy 417.59378 -17.230598) (xy 417.617656 -17.23136) (xy 417.635393 -17.201217)
			(xy 417.67559 -17.143978) (xy 417.69792 -17.11706) (xy 417.705239 -17.107372) (xy 417.71082 -17.083781)
			(xy 417.708588 -17.071848) (xy 417.703263 -17.04917) (xy 417.697534 -17.002938) (xy 417.697158 -16.979646)
			(xy 417.697158 -16.979138) (xy 417.697637 -16.951867) (xy 417.705394 -16.89788) (xy 417.720757 -16.845546)
			(xy 417.743411 -16.795932) (xy 417.772897 -16.750047) (xy 417.808613 -16.708826) (xy 417.849832 -16.673108)
			(xy 417.895716 -16.64362) (xy 417.945329 -16.620963) (xy 417.997662 -16.605598) (xy 418.051649 -16.597838)
			(xy 418.07892 -16.597376) (xy 418.107621 -16.597954) (xy 418.164375 -16.606564) (xy 418.219201 -16.623572)
			(xy 418.270863 -16.648594) (xy 418.318199 -16.681066) (xy 418.36014 -16.720258) (xy 418.395743 -16.765286)
			(xy 418.424206 -16.815136) (xy 418.435028 -16.841724) (xy 418.440078 -16.852809) (xy 418.458227 -16.868996)
			(xy 418.469826 -16.872712) (xy 418.507551 -16.882916) (xy 418.580874 -16.909975) (xy 418.651048 -16.944381)
			(xy 418.684456 -16.96466) (xy 418.692712 -16.969374) (xy 418.71138 -16.972901) (xy 418.730048 -16.969374)
			(xy 418.738304 -16.96466) (xy 418.77171 -16.944377) (xy 418.841885 -16.909971) (xy 418.915206 -16.882907)
			(xy 418.952934 -16.872712) (xy 418.964547 -16.869017) (xy 418.982719 -16.852832) (xy 418.987732 -16.841724)
			(xy 418.998533 -16.815122) (xy 419.026977 -16.76525) (xy 419.062572 -16.720202) (xy 419.104513 -16.680994)
			(xy 419.151855 -16.648511) (xy 419.203528 -16.623487) (xy 419.258367 -16.606486) (xy 419.315133 -16.597891)
			(xy 419.34384 -16.597376) (xy 419.371112 -16.597787) (xy 419.4251 -16.605555) (xy 419.477434 -16.620928)
			(xy 419.527046 -16.643591) (xy 419.572929 -16.673085) (xy 419.614147 -16.708808) (xy 419.649862 -16.750034)
			(xy 419.679346 -16.795922) (xy 419.701999 -16.84554) (xy 419.717361 -16.897876) (xy 419.725118 -16.951866)
			(xy 419.725602 -16.979138) (xy 419.725602 -16.979646) (xy 419.725223 -17.002938) (xy 419.719489 -17.049168)
			(xy 419.714172 -17.071848) (xy 419.711892 -17.083783) (xy 419.717472 -17.107396) (xy 419.72484 -17.11706)
			(xy 419.74717 -17.143978) (xy 419.787367 -17.201217) (xy 419.805104 -17.23136) (xy 419.82898 -17.230598)
			(xy 419.856249 -17.23114) (xy 419.910232 -17.238899) (xy 419.962562 -17.254262) (xy 420.012173 -17.276916)
			(xy 420.058054 -17.3064) (xy 420.099272 -17.342114) (xy 420.134988 -17.38333) (xy 420.164474 -17.42921)
			(xy 420.187131 -17.478819) (xy 420.202497 -17.531148) (xy 420.210259 -17.585131) (xy 420.210259 -17.639669)
			(xy 420.210259 -17.639671) (xy 422.800484 -17.639671) (xy 422.800484 -17.585129) (xy 422.808246 -17.531141)
			(xy 422.823612 -17.478808) (xy 422.846269 -17.429194) (xy 422.875757 -17.383309) (xy 422.911473 -17.342088)
			(xy 422.952693 -17.306369) (xy 422.998576 -17.276879) (xy 423.048189 -17.254219) (xy 423.100522 -17.238851)
			(xy 423.154509 -17.231086) (xy 423.18178 -17.230598) (xy 423.205656 -17.23136) (xy 423.223393 -17.201217)
			(xy 423.26359 -17.143978) (xy 423.28592 -17.11706) (xy 423.293239 -17.107372) (xy 423.29882 -17.083781)
			(xy 423.296588 -17.071848) (xy 423.291263 -17.04917) (xy 423.285534 -17.002938) (xy 423.285158 -16.979646)
			(xy 423.285158 -16.979138) (xy 423.285637 -16.951867) (xy 423.293394 -16.89788) (xy 423.308757 -16.845546)
			(xy 423.331411 -16.795932) (xy 423.360897 -16.750047) (xy 423.396613 -16.708826) (xy 423.437832 -16.673108)
			(xy 423.483716 -16.64362) (xy 423.533329 -16.620963) (xy 423.585662 -16.605598) (xy 423.639649 -16.597838)
			(xy 423.66692 -16.597376) (xy 423.695621 -16.597954) (xy 423.752375 -16.606564) (xy 423.807201 -16.623572)
			(xy 423.858863 -16.648594) (xy 423.906199 -16.681066) (xy 423.94814 -16.720258) (xy 423.983743 -16.765286)
			(xy 424.012206 -16.815136) (xy 424.023028 -16.841724) (xy 424.028078 -16.852809) (xy 424.046227 -16.868996)
			(xy 424.057826 -16.872712) (xy 424.095551 -16.882916) (xy 424.168874 -16.909975) (xy 424.239048 -16.944381)
			(xy 424.272456 -16.96466) (xy 424.280712 -16.969374) (xy 424.29938 -16.972901) (xy 424.318048 -16.969374)
			(xy 424.326304 -16.96466) (xy 424.35971 -16.944377) (xy 424.429885 -16.909971) (xy 424.503206 -16.882907)
			(xy 424.540934 -16.872712) (xy 424.552547 -16.869017) (xy 424.570719 -16.852832) (xy 424.575732 -16.841724)
			(xy 424.586533 -16.815122) (xy 424.614977 -16.76525) (xy 424.650572 -16.720202) (xy 424.692513 -16.680994)
			(xy 424.739855 -16.648511) (xy 424.791528 -16.623487) (xy 424.846367 -16.606486) (xy 424.903133 -16.597891)
			(xy 424.93184 -16.597376) (xy 424.959112 -16.597787) (xy 425.0131 -16.605555) (xy 425.065434 -16.620928)
			(xy 425.115046 -16.643591) (xy 425.160929 -16.673085) (xy 425.202147 -16.708808) (xy 425.237862 -16.750034)
			(xy 425.267346 -16.795922) (xy 425.289999 -16.84554) (xy 425.305361 -16.897876) (xy 425.313118 -16.951866)
			(xy 425.313602 -16.979138) (xy 425.313602 -16.979646) (xy 425.313223 -17.002938) (xy 425.307489 -17.049168)
			(xy 425.302172 -17.071848) (xy 425.299892 -17.083783) (xy 425.305472 -17.107396) (xy 425.31284 -17.11706)
			(xy 425.33517 -17.143978) (xy 425.375367 -17.201217) (xy 425.393104 -17.23136) (xy 425.41698 -17.230598)
			(xy 425.444249 -17.23114) (xy 425.498232 -17.238899) (xy 425.550562 -17.254262) (xy 425.600173 -17.276916)
			(xy 425.646054 -17.3064) (xy 425.687272 -17.342114) (xy 425.722988 -17.38333) (xy 425.752474 -17.42921)
			(xy 425.775131 -17.478819) (xy 425.790497 -17.531148) (xy 425.798259 -17.585131) (xy 425.798259 -17.639669)
			(xy 425.798158 -17.640368) (xy 428.421546 -17.640368) (xy 428.421546 -17.585832) (xy 428.429308 -17.531852)
			(xy 428.444672 -17.479525) (xy 428.467327 -17.429918) (xy 428.496811 -17.38404) (xy 428.532524 -17.342824)
			(xy 428.57374 -17.307111) (xy 428.619618 -17.277627) (xy 428.669225 -17.254972) (xy 428.721552 -17.239608)
			(xy 428.775532 -17.231846) (xy 428.8028 -17.23136) (xy 428.826676 -17.232122) (xy 428.844559 -17.201755)
			(xy 428.88514 -17.144132) (xy 428.907702 -17.11706) (xy 428.91502 -17.107371) (xy 428.920603 -17.083781)
			(xy 428.91837 -17.071848) (xy 428.913145 -17.04935) (xy 428.907543 -17.003502) (xy 428.907194 -16.980408)
			(xy 428.907194 -16.9799) (xy 428.907724 -16.952633) (xy 428.915485 -16.898653) (xy 428.930848 -16.846327)
			(xy 428.953501 -16.79672) (xy 428.982983 -16.750841) (xy 429.018693 -16.709624) (xy 429.059906 -16.673909)
			(xy 429.105781 -16.644422) (xy 429.155386 -16.621763) (xy 429.20771 -16.606394) (xy 429.261689 -16.598627)
			(xy 429.288956 -16.598138) (xy 429.317682 -16.598693) (xy 429.374485 -16.607317) (xy 429.429356 -16.624348)
			(xy 429.481059 -16.649401) (xy 429.528429 -16.681911) (xy 429.570399 -16.721147) (xy 429.606021 -16.766224)
			(xy 429.634495 -16.816125) (xy 429.645318 -16.84274) (xy 429.650317 -16.853854) (xy 429.668503 -16.870029)
			(xy 429.680116 -16.873728) (xy 429.717626 -16.883914) (xy 429.79051 -16.910931) (xy 429.860267 -16.945225)
			(xy 429.893476 -16.965422) (xy 429.901732 -16.970136) (xy 429.9204 -16.973663) (xy 429.939068 -16.970136)
			(xy 429.947324 -16.965422) (xy 429.98088 -16.945017) (xy 430.051374 -16.910391) (xy 430.125053 -16.883195)
			(xy 430.16297 -16.872966) (xy 430.174529 -16.869277) (xy 430.192696 -16.853252) (xy 430.197768 -16.842232)
			(xy 430.208591 -16.815653) (xy 430.237072 -16.765832) (xy 430.272686 -16.720834) (xy 430.314634 -16.681672)
			(xy 430.361969 -16.649227) (xy 430.413626 -16.624231) (xy 430.468442 -16.607247) (xy 430.525183 -16.598656)
			(xy 430.553876 -16.598138) (xy 430.581146 -16.598624) (xy 430.635132 -16.606383) (xy 430.687465 -16.621746)
			(xy 430.737078 -16.644401) (xy 430.782962 -16.673886) (xy 430.824182 -16.709601) (xy 430.8599 -16.750819)
			(xy 430.889388 -16.796701) (xy 430.912046 -16.846313) (xy 430.927412 -16.898644) (xy 430.935174 -16.95263)
			(xy 430.935638 -16.9799) (xy 430.935278 -17.003518) (xy 430.929413 -17.05039) (xy 430.923954 -17.073372)
			(xy 430.921655 -17.085345) (xy 430.927069 -17.109076) (xy 430.934368 -17.118838) (xy 430.956527 -17.14553)
			(xy 430.996466 -17.202261) (xy 431.014124 -17.232122) (xy 431.038 -17.23136) (xy 431.065271 -17.231802)
			(xy 431.119258 -17.239565) (xy 431.17159 -17.254931) (xy 431.221203 -17.277588) (xy 431.267087 -17.307076)
			(xy 431.308307 -17.342793) (xy 431.344024 -17.384013) (xy 431.373512 -17.429897) (xy 431.396169 -17.47951)
			(xy 431.411535 -17.531842) (xy 431.419298 -17.585829) (xy 431.419298 -17.640371) (xy 431.411535 -17.694358)
			(xy 431.396169 -17.74669) (xy 431.373512 -17.796303) (xy 431.344024 -17.842187) (xy 431.308307 -17.883407)
			(xy 431.267087 -17.919124) (xy 431.221203 -17.948612) (xy 431.17159 -17.971269) (xy 431.119258 -17.986635)
			(xy 431.065271 -17.994398) (xy 431.038 -17.994884) (xy 431.014124 -17.994122) (xy 430.996418 -18.024119)
			(xy 430.956352 -18.081104) (xy 430.934114 -18.107914) (xy 430.926781 -18.117667) (xy 430.921333 -18.141411)
			(xy 430.9237 -18.15338) (xy 430.929273 -18.176604) (xy 430.935255 -18.223988) (xy 430.935638 -18.247868)
			(xy 430.935169 -18.275139) (xy 430.92741 -18.329127) (xy 430.912047 -18.381461) (xy 430.889391 -18.431076)
			(xy 430.859905 -18.476961) (xy 430.824188 -18.518182) (xy 430.782967 -18.5539) (xy 430.737083 -18.583387)
			(xy 430.687469 -18.606044) (xy 430.635135 -18.621409) (xy 430.581147 -18.629168) (xy 430.553876 -18.62963)
			(xy 430.525085 -18.629127) (xy 430.468158 -18.620463) (xy 430.413177 -18.60335) (xy 430.361389 -18.578175)
			(xy 430.313967 -18.54551) (xy 430.271988 -18.506095) (xy 430.236403 -18.460824) (xy 430.208019 -18.410723)
			(xy 430.19726 -18.384012) (xy 430.19225 -18.37279) (xy 430.173928 -18.356469) (xy 430.162208 -18.35277)
			(xy 430.124427 -18.342555) (xy 430.051011 -18.315421) (xy 429.980761 -18.280909) (xy 429.947324 -18.260568)
			(xy 429.939063 -18.255872) (xy 429.9204 -18.252364) (xy 429.901737 -18.255872) (xy 429.893476 -18.260568)
			(xy 429.86034 -18.280732) (xy 429.790747 -18.314996) (xy 429.71804 -18.342034) (xy 429.680624 -18.352262)
			(xy 429.669056 -18.356076) (xy 429.651007 -18.372368) (xy 429.64608 -18.383504) (xy 429.635294 -18.410257)
			(xy 429.606905 -18.460468) (xy 429.571291 -18.505841) (xy 429.529261 -18.545344) (xy 429.48177 -18.578079)
			(xy 429.429897 -18.603303) (xy 429.374822 -18.620442) (xy 429.317796 -18.629107) (xy 429.288956 -18.62963)
			(xy 429.261684 -18.629216) (xy 429.207696 -18.621448) (xy 429.155363 -18.606075) (xy 429.105751 -18.583412)
			(xy 429.059869 -18.553918) (xy 429.018651 -18.518195) (xy 428.982936 -18.47697) (xy 428.953452 -18.431082)
			(xy 428.930798 -18.381465) (xy 428.915436 -18.329129) (xy 428.907678 -18.27514) (xy 428.907194 -18.247868)
			(xy 428.907194 -18.24736) (xy 428.907548 -18.223941) (xy 428.913281 -18.177454) (xy 428.918624 -18.15465)
			(xy 428.920895 -18.14265) (xy 428.915341 -18.118909) (xy 428.907956 -18.109184) (xy 428.885351 -18.082101)
			(xy 428.844643 -18.024481) (xy 428.826676 -17.994122) (xy 428.8028 -17.994884) (xy 428.775532 -17.994354)
			(xy 428.721552 -17.986592) (xy 428.669225 -17.971228) (xy 428.619618 -17.948573) (xy 428.57374 -17.919089)
			(xy 428.532524 -17.883376) (xy 428.496811 -17.84216) (xy 428.467327 -17.796282) (xy 428.444672 -17.746675)
			(xy 428.429308 -17.694348) (xy 428.421546 -17.640368) (xy 425.798158 -17.640368) (xy 425.790497 -17.693652)
			(xy 425.775131 -17.745981) (xy 425.752474 -17.79559) (xy 425.722988 -17.84147) (xy 425.687272 -17.882686)
			(xy 425.646054 -17.9184) (xy 425.600173 -17.947884) (xy 425.550562 -17.970538) (xy 425.498232 -17.985901)
			(xy 425.444249 -17.99366) (xy 425.41698 -17.994122) (xy 425.393104 -17.99336) (xy 425.375243 -18.023515)
			(xy 425.334794 -18.080757) (xy 425.312332 -18.10766) (xy 425.304973 -18.117397) (xy 425.29954 -18.141154)
			(xy 425.301918 -18.153126) (xy 425.307366 -18.17611) (xy 425.31323 -18.22298) (xy 425.313602 -18.246598)
			(xy 425.313602 -18.247106) (xy 425.313081 -18.274374) (xy 425.30532 -18.328354) (xy 425.289956 -18.38068)
			(xy 425.267302 -18.430288) (xy 425.237819 -18.476167) (xy 425.202107 -18.517383) (xy 425.160894 -18.553099)
			(xy 425.115018 -18.582585) (xy 425.065412 -18.605244) (xy 425.013087 -18.620613) (xy 424.959108 -18.628379)
			(xy 424.93184 -18.628868) (xy 424.903027 -18.628325) (xy 424.846057 -18.619649) (xy 424.791035 -18.602518)
			(xy 424.73921 -18.577319) (xy 424.691755 -18.544626) (xy 424.649747 -18.505177) (xy 424.614138 -18.459869)
			(xy 424.585735 -18.409728) (xy 424.57497 -18.382996) (xy 424.569987 -18.37182) (xy 424.551822 -18.355489)
			(xy 424.540172 -18.351754) (xy 424.502575 -18.341525) (xy 424.429512 -18.314446) (xy 424.35959 -18.280059)
			(xy 424.326304 -18.259806) (xy 424.318043 -18.25511) (xy 424.29938 -18.251602) (xy 424.280717 -18.25511)
			(xy 424.272456 -18.259806) (xy 424.239163 -18.280046) (xy 424.16924 -18.314429) (xy 424.096183 -18.341523)
			(xy 424.058588 -18.351754) (xy 424.046946 -18.355502) (xy 424.028781 -18.371829) (xy 424.02379 -18.382996)
			(xy 424.013071 -18.409751) (xy 423.984681 -18.459911) (xy 423.949076 -18.505236) (xy 423.907064 -18.544694)
			(xy 423.859599 -18.577391) (xy 423.80776 -18.602583) (xy 423.752723 -18.619699) (xy 423.695739 -18.628349)
			(xy 423.66692 -18.628868) (xy 423.63965 -18.62838) (xy 423.585664 -18.620621) (xy 423.533332 -18.605257)
			(xy 423.48372 -18.582602) (xy 423.437836 -18.553117) (xy 423.396616 -18.517403) (xy 423.360898 -18.476185)
			(xy 423.33141 -18.430303) (xy 423.308752 -18.380692) (xy 423.293385 -18.328361) (xy 423.285622 -18.274376)
			(xy 423.285158 -18.247106) (xy 423.285158 -18.246598) (xy 423.285517 -18.22298) (xy 423.291383 -18.176108)
			(xy 423.296842 -18.153126) (xy 423.299143 -18.141153) (xy 423.293728 -18.117422) (xy 423.286428 -18.10766)
			(xy 423.263971 -18.080752) (xy 423.223519 -18.023513) (xy 423.205656 -17.99336) (xy 423.18178 -17.994122)
			(xy 423.154509 -17.993714) (xy 423.100522 -17.985949) (xy 423.048189 -17.970581) (xy 422.998576 -17.947921)
			(xy 422.952693 -17.918431) (xy 422.911473 -17.882712) (xy 422.875757 -17.841491) (xy 422.846269 -17.795606)
			(xy 422.823612 -17.745992) (xy 422.808246 -17.693659) (xy 422.800484 -17.639671) (xy 420.210259 -17.639671)
			(xy 420.202497 -17.693652) (xy 420.187131 -17.745981) (xy 420.164474 -17.79559) (xy 420.134988 -17.84147)
			(xy 420.099272 -17.882686) (xy 420.058054 -17.9184) (xy 420.012173 -17.947884) (xy 419.962562 -17.970538)
			(xy 419.910232 -17.985901) (xy 419.856249 -17.99366) (xy 419.82898 -17.994122) (xy 419.805104 -17.99336)
			(xy 419.787243 -18.023515) (xy 419.746794 -18.080757) (xy 419.724332 -18.10766) (xy 419.716973 -18.117397)
			(xy 419.71154 -18.141154) (xy 419.713918 -18.153126) (xy 419.719366 -18.17611) (xy 419.72523 -18.22298)
			(xy 419.725602 -18.246598) (xy 419.725602 -18.247106) (xy 419.725081 -18.274374) (xy 419.71732 -18.328354)
			(xy 419.701956 -18.38068) (xy 419.679302 -18.430288) (xy 419.649819 -18.476167) (xy 419.614107 -18.517383)
			(xy 419.572894 -18.553099) (xy 419.527018 -18.582585) (xy 419.477412 -18.605244) (xy 419.425087 -18.620613)
			(xy 419.371108 -18.628379) (xy 419.34384 -18.628868) (xy 419.315027 -18.628325) (xy 419.258057 -18.619649)
			(xy 419.203035 -18.602518) (xy 419.15121 -18.577319) (xy 419.103755 -18.544626) (xy 419.061747 -18.505177)
			(xy 419.026138 -18.459869) (xy 418.997735 -18.409728) (xy 418.98697 -18.382996) (xy 418.981987 -18.37182)
			(xy 418.963822 -18.355489) (xy 418.952172 -18.351754) (xy 418.914575 -18.341525) (xy 418.841512 -18.314446)
			(xy 418.77159 -18.280059) (xy 418.738304 -18.259806) (xy 418.730043 -18.25511) (xy 418.71138 -18.251602)
			(xy 418.692717 -18.25511) (xy 418.684456 -18.259806) (xy 418.651163 -18.280046) (xy 418.58124 -18.314429)
			(xy 418.508183 -18.341523) (xy 418.470588 -18.351754) (xy 418.458946 -18.355502) (xy 418.440781 -18.371829)
			(xy 418.43579 -18.382996) (xy 418.425071 -18.409751) (xy 418.396681 -18.459911) (xy 418.361076 -18.505236)
			(xy 418.319064 -18.544694) (xy 418.271599 -18.577391) (xy 418.21976 -18.602583) (xy 418.164723 -18.619699)
			(xy 418.107739 -18.628349) (xy 418.07892 -18.628868) (xy 418.05165 -18.62838) (xy 417.997664 -18.620621)
			(xy 417.945332 -18.605257) (xy 417.89572 -18.582602) (xy 417.849836 -18.553117) (xy 417.808616 -18.517403)
			(xy 417.772898 -18.476185) (xy 417.74341 -18.430303) (xy 417.720752 -18.380692) (xy 417.705385 -18.328361)
			(xy 417.697622 -18.274376) (xy 417.697158 -18.247106) (xy 417.697158 -18.246598) (xy 417.697517 -18.22298)
			(xy 417.703383 -18.176108) (xy 417.708842 -18.153126) (xy 417.711143 -18.141153) (xy 417.705728 -18.117422)
			(xy 417.698428 -18.10766) (xy 417.675971 -18.080752) (xy 417.635519 -18.023513) (xy 417.617656 -17.99336)
			(xy 417.59378 -17.994122) (xy 417.566509 -17.993714) (xy 417.512522 -17.985949) (xy 417.460189 -17.970581)
			(xy 417.410576 -17.947921) (xy 417.364693 -17.918431) (xy 417.323473 -17.882712) (xy 417.287757 -17.841491)
			(xy 417.258269 -17.795606) (xy 417.235612 -17.745992) (xy 417.220246 -17.693659) (xy 417.212484 -17.639671)
			(xy 414.315398 -17.639671) (xy 414.315398 -17.640369) (xy 414.307637 -17.694351) (xy 414.292273 -17.74668)
			(xy 414.269619 -17.79629) (xy 414.240136 -17.842171) (xy 414.204424 -17.88339) (xy 414.16321 -17.919107)
			(xy 414.117332 -17.948596) (xy 414.067725 -17.971256) (xy 414.015398 -17.986627) (xy 413.961417 -17.994394)
			(xy 413.934148 -17.994884) (xy 413.910272 -17.994122) (xy 413.892569 -18.024121) (xy 413.852501 -18.081105)
			(xy 413.830262 -18.107914) (xy 413.822926 -18.117664) (xy 413.817483 -18.14141) (xy 413.819848 -18.15338)
			(xy 413.82542 -18.176604) (xy 413.831403 -18.223988) (xy 413.831786 -18.247868) (xy 413.831269 -18.275137)
			(xy 413.823512 -18.329121) (xy 413.808151 -18.381451) (xy 413.785499 -18.431062) (xy 413.756017 -18.476945)
			(xy 413.720305 -18.518165) (xy 413.67909 -18.553883) (xy 413.633212 -18.583372) (xy 413.583604 -18.606031)
			(xy 413.531276 -18.6214) (xy 413.477293 -18.629165) (xy 413.450024 -18.62963) (xy 413.421234 -18.629086)
			(xy 413.364309 -18.620429) (xy 413.309329 -18.603322) (xy 413.257541 -18.578153) (xy 413.210119 -18.545494)
			(xy 413.16814 -18.506084) (xy 413.132553 -18.460818) (xy 413.104168 -18.410721) (xy 413.093408 -18.384012)
			(xy 413.088375 -18.372804) (xy 413.070069 -18.356477) (xy 413.058356 -18.35277) (xy 413.020578 -18.342544)
			(xy 412.947161 -18.315415) (xy 412.87691 -18.280907) (xy 412.843472 -18.260568) (xy 412.835211 -18.255872)
			(xy 412.816548 -18.252364) (xy 412.797885 -18.255872) (xy 412.789624 -18.260568) (xy 412.756483 -18.280722)
			(xy 412.686892 -18.31499) (xy 412.614187 -18.342032) (xy 412.576772 -18.352262) (xy 412.565195 -18.356053)
			(xy 412.547151 -18.372362) (xy 412.542228 -18.383504) (xy 412.531485 -18.410276) (xy 412.503092 -18.460489)
			(xy 412.467472 -18.505862) (xy 412.425435 -18.545364) (xy 412.377938 -18.578098) (xy 412.326059 -18.603318)
			(xy 412.270977 -18.620452) (xy 412.213946 -18.629111) (xy 412.185104 -18.62963) (xy 412.157832 -18.629195)
			(xy 412.103842 -18.621432) (xy 412.051507 -18.606065) (xy 412.001892 -18.583405) (xy 411.956006 -18.553915)
			(xy 411.914785 -18.518195) (xy 411.879068 -18.476971) (xy 411.849581 -18.431084) (xy 411.826925 -18.381467)
			(xy 411.811562 -18.329131) (xy 411.803803 -18.27514) (xy 411.803342 -18.247868) (xy 411.803342 -18.24736)
			(xy 411.803697 -18.223941) (xy 411.80943 -18.177454) (xy 411.814772 -18.15465) (xy 411.817032 -18.142649)
			(xy 411.811483 -18.118911) (xy 411.804104 -18.109184) (xy 411.781496 -18.082103) (xy 411.74079 -18.024482)
			(xy 411.722824 -17.994122) (xy 411.698948 -17.994884) (xy 411.671676 -17.99438) (xy 411.617687 -17.986624)
			(xy 411.565352 -17.971262) (xy 411.515736 -17.948609) (xy 411.469849 -17.919124) (xy 411.428625 -17.883409)
			(xy 411.392904 -17.84219) (xy 411.363414 -17.796307) (xy 411.340754 -17.746693) (xy 411.325387 -17.69436)
			(xy 411.317624 -17.640372) (xy 408.72852 -17.640372) (xy 408.72852 -17.640374) (xy 408.720757 -17.694367)
			(xy 408.705388 -17.746706) (xy 408.682726 -17.796324) (xy 408.653234 -17.842212) (xy 408.61751 -17.883436)
			(xy 408.576284 -17.919155) (xy 408.530393 -17.948644) (xy 408.480772 -17.9713) (xy 408.428432 -17.986664)
			(xy 408.374438 -17.994423) (xy 408.347164 -17.994884) (xy 408.322272 -17.994122) (xy 408.304569 -18.024121)
			(xy 408.264501 -18.081105) (xy 408.242262 -18.107914) (xy 408.234926 -18.117664) (xy 408.229483 -18.14141)
			(xy 408.231848 -18.15338) (xy 408.23742 -18.176604) (xy 408.243403 -18.223988) (xy 408.243786 -18.247868)
			(xy 408.243269 -18.275137) (xy 408.235512 -18.329121) (xy 408.220151 -18.381451) (xy 408.197499 -18.431062)
			(xy 408.168017 -18.476945) (xy 408.132305 -18.518165) (xy 408.09109 -18.553883) (xy 408.045212 -18.583372)
			(xy 407.995604 -18.606031) (xy 407.943276 -18.6214) (xy 407.889293 -18.629165) (xy 407.862024 -18.62963)
			(xy 407.833234 -18.629086) (xy 407.776309 -18.620429) (xy 407.721329 -18.603322) (xy 407.669541 -18.578153)
			(xy 407.622119 -18.545494) (xy 407.58014 -18.506084) (xy 407.544553 -18.460818) (xy 407.516168 -18.410721)
			(xy 407.505408 -18.384012) (xy 407.500375 -18.372804) (xy 407.482069 -18.356477) (xy 407.470356 -18.35277)
			(xy 407.432578 -18.342544) (xy 407.359161 -18.315415) (xy 407.28891 -18.280907) (xy 407.255472 -18.260568)
			(xy 407.247211 -18.255872) (xy 407.228548 -18.252364) (xy 407.209885 -18.255872) (xy 407.201624 -18.260568)
			(xy 407.168483 -18.280722) (xy 407.098892 -18.31499) (xy 407.026187 -18.342032) (xy 406.988772 -18.352262)
			(xy 406.977195 -18.356053) (xy 406.959151 -18.372362) (xy 406.954228 -18.383504) (xy 406.943485 -18.410276)
			(xy 406.915092 -18.460489) (xy 406.879472 -18.505862) (xy 406.837435 -18.545364) (xy 406.789938 -18.578098)
			(xy 406.738059 -18.603318) (xy 406.682977 -18.620452) (xy 406.625946 -18.629111) (xy 406.597104 -18.62963)
			(xy 406.569832 -18.629195) (xy 406.515842 -18.621432) (xy 406.463507 -18.606065) (xy 406.413892 -18.583405)
			(xy 406.368006 -18.553915) (xy 406.326785 -18.518195) (xy 406.291068 -18.476971) (xy 406.261581 -18.431084)
			(xy 406.238925 -18.381467) (xy 406.223562 -18.329131) (xy 406.215803 -18.27514) (xy 406.215342 -18.247868)
			(xy 406.215342 -18.24736) (xy 406.215697 -18.223941) (xy 406.22143 -18.177454) (xy 406.226772 -18.15465)
			(xy 406.229032 -18.142649) (xy 406.223483 -18.118911) (xy 406.216104 -18.109184) (xy 406.193496 -18.082103)
			(xy 406.15279 -18.024482) (xy 406.134824 -17.994122) (xy 406.111964 -17.994884) (xy 406.084698 -17.994351)
			(xy 406.030721 -17.986586) (xy 405.978399 -17.971218) (xy 405.928796 -17.948561) (xy 405.882923 -17.919076)
			(xy 405.841712 -17.883363) (xy 405.806002 -17.842149) (xy 405.776521 -17.796272) (xy 405.753869 -17.746667)
			(xy 405.738507 -17.694343) (xy 405.730746 -17.640366) (xy 403.140358 -17.640366) (xy 403.132696 -17.693654)
			(xy 403.11733 -17.745984) (xy 403.094672 -17.795595) (xy 403.065184 -17.841475) (xy 403.029466 -17.882692)
			(xy 402.988246 -17.918406) (xy 402.942363 -17.947889) (xy 402.89275 -17.970542) (xy 402.840419 -17.985904)
			(xy 402.786434 -17.993661) (xy 402.759164 -17.994122) (xy 402.735288 -17.99336) (xy 402.717429 -18.023516)
			(xy 402.676979 -18.080757) (xy 402.654516 -18.10766) (xy 402.647156 -18.117396) (xy 402.641724 -18.141154)
			(xy 402.644102 -18.153126) (xy 402.64955 -18.17611) (xy 402.655414 -18.22298) (xy 402.655786 -18.246598)
			(xy 402.655786 -18.247106) (xy 402.655281 -18.274374) (xy 402.647519 -18.328356) (xy 402.632154 -18.380684)
			(xy 402.609499 -18.430292) (xy 402.580015 -18.476172) (xy 402.544302 -18.517389) (xy 402.503087 -18.553104)
			(xy 402.457208 -18.582591) (xy 402.407601 -18.605248) (xy 402.355274 -18.620616) (xy 402.301292 -18.62838)
			(xy 402.274024 -18.628868) (xy 402.24521 -18.628339) (xy 402.18824 -18.619661) (xy 402.133218 -18.602527)
			(xy 402.081392 -18.577327) (xy 402.033938 -18.544631) (xy 401.99193 -18.505181) (xy 401.956321 -18.459871)
			(xy 401.927919 -18.409728) (xy 401.917154 -18.382996) (xy 401.912179 -18.371815) (xy 401.894009 -18.355486)
			(xy 401.882356 -18.351754) (xy 401.844758 -18.341528) (xy 401.771695 -18.314448) (xy 401.701773 -18.28006)
			(xy 401.668488 -18.259806) (xy 401.660227 -18.25511) (xy 401.641564 -18.251602) (xy 401.622901 -18.25511)
			(xy 401.61464 -18.259806) (xy 401.581349 -18.280049) (xy 401.511425 -18.314431) (xy 401.438368 -18.341524)
			(xy 401.400772 -18.351754) (xy 401.389128 -18.355495) (xy 401.370964 -18.371827) (xy 401.365974 -18.382996)
			(xy 401.355268 -18.409757) (xy 401.326877 -18.459918) (xy 401.29127 -18.505242) (xy 401.249256 -18.544701)
			(xy 401.201789 -18.577397) (xy 401.149948 -18.602588) (xy 401.094909 -18.619702) (xy 401.037923 -18.62835)
			(xy 401.009104 -18.628868) (xy 400.981835 -18.628372) (xy 400.927852 -18.620611) (xy 400.875523 -18.605246)
			(xy 400.825913 -18.582591) (xy 400.780033 -18.553106) (xy 400.738815 -18.517392) (xy 400.7031 -18.476175)
			(xy 400.673614 -18.430295) (xy 400.650957 -18.380686) (xy 400.635591 -18.328358) (xy 400.627829 -18.274375)
			(xy 400.627342 -18.247106) (xy 400.627342 -18.246598) (xy 400.627702 -18.22298) (xy 400.633567 -18.176108)
			(xy 400.639026 -18.153126) (xy 400.641331 -18.141153) (xy 400.635914 -18.117422) (xy 400.628612 -18.10766)
			(xy 400.606154 -18.080753) (xy 400.565703 -18.023514) (xy 400.54784 -17.99336) (xy 400.523964 -17.994122)
			(xy 400.496693 -17.993713) (xy 400.442708 -17.985946) (xy 400.390377 -17.970576) (xy 400.340767 -17.947916)
			(xy 400.294885 -17.918426) (xy 400.253668 -17.882707) (xy 400.217953 -17.841486) (xy 400.188467 -17.795602)
			(xy 400.165811 -17.745989) (xy 400.150446 -17.693657) (xy 400.142684 -17.639671) (xy 397.552458 -17.639671)
			(xy 397.544696 -17.693654) (xy 397.52933 -17.745984) (xy 397.506672 -17.795595) (xy 397.477184 -17.841475)
			(xy 397.441466 -17.882692) (xy 397.400246 -17.918406) (xy 397.354363 -17.947889) (xy 397.30475 -17.970542)
			(xy 397.252419 -17.985904) (xy 397.198434 -17.993661) (xy 397.171164 -17.994122) (xy 397.147288 -17.99336)
			(xy 397.129429 -18.023516) (xy 397.088979 -18.080757) (xy 397.066516 -18.10766) (xy 397.059156 -18.117396)
			(xy 397.053724 -18.141154) (xy 397.056102 -18.153126) (xy 397.06155 -18.17611) (xy 397.067414 -18.22298)
			(xy 397.067786 -18.246598) (xy 397.067786 -18.247106) (xy 397.067281 -18.274374) (xy 397.059519 -18.328356)
			(xy 397.044154 -18.380684) (xy 397.021499 -18.430292) (xy 396.992015 -18.476172) (xy 396.956302 -18.517389)
			(xy 396.915087 -18.553104) (xy 396.869208 -18.582591) (xy 396.819601 -18.605248) (xy 396.767274 -18.620616)
			(xy 396.713292 -18.62838) (xy 396.686024 -18.628868) (xy 396.65721 -18.628339) (xy 396.60024 -18.619661)
			(xy 396.545218 -18.602527) (xy 396.493392 -18.577327) (xy 396.445938 -18.544631) (xy 396.40393 -18.505181)
			(xy 396.368321 -18.459871) (xy 396.339919 -18.409728) (xy 396.329154 -18.382996) (xy 396.324179 -18.371815)
			(xy 396.306009 -18.355486) (xy 396.294356 -18.351754) (xy 396.256758 -18.341528) (xy 396.183695 -18.314448)
			(xy 396.113773 -18.28006) (xy 396.080488 -18.259806) (xy 396.072227 -18.25511) (xy 396.053564 -18.251602)
			(xy 396.034901 -18.25511) (xy 396.02664 -18.259806) (xy 395.993349 -18.280049) (xy 395.923425 -18.314431)
			(xy 395.850368 -18.341524) (xy 395.812772 -18.351754) (xy 395.801128 -18.355495) (xy 395.782964 -18.371827)
			(xy 395.777974 -18.382996) (xy 395.767268 -18.409757) (xy 395.738877 -18.459918) (xy 395.70327 -18.505242)
			(xy 395.661256 -18.544701) (xy 395.613789 -18.577397) (xy 395.561948 -18.602588) (xy 395.506909 -18.619702)
			(xy 395.449923 -18.62835) (xy 395.421104 -18.628868) (xy 395.393835 -18.628372) (xy 395.339852 -18.620611)
			(xy 395.287523 -18.605246) (xy 395.237913 -18.582591) (xy 395.192033 -18.553106) (xy 395.150815 -18.517392)
			(xy 395.1151 -18.476175) (xy 395.085614 -18.430295) (xy 395.062957 -18.380686) (xy 395.047591 -18.328358)
			(xy 395.039829 -18.274375) (xy 395.039342 -18.247106) (xy 395.039342 -18.246598) (xy 395.039702 -18.22298)
			(xy 395.045567 -18.176108) (xy 395.051026 -18.153126) (xy 395.053331 -18.141153) (xy 395.047914 -18.117422)
			(xy 395.040612 -18.10766) (xy 395.018154 -18.080753) (xy 394.977703 -18.023514) (xy 394.95984 -17.99336)
			(xy 394.935964 -17.994122) (xy 394.908693 -17.993713) (xy 394.854708 -17.985946) (xy 394.802377 -17.970576)
			(xy 394.752767 -17.947916) (xy 394.706885 -17.918426) (xy 394.665668 -17.882707) (xy 394.629953 -17.841486)
			(xy 394.600467 -17.795602) (xy 394.577811 -17.745989) (xy 394.562446 -17.693657) (xy 394.554684 -17.639671)
			(xy 391.964458 -17.639671) (xy 391.956696 -17.693654) (xy 391.94133 -17.745984) (xy 391.918672 -17.795595)
			(xy 391.889184 -17.841475) (xy 391.853466 -17.882692) (xy 391.812246 -17.918406) (xy 391.766363 -17.947889)
			(xy 391.71675 -17.970542) (xy 391.664419 -17.985904) (xy 391.610434 -17.993661) (xy 391.583164 -17.994122)
			(xy 391.559288 -17.99336) (xy 391.541429 -18.023516) (xy 391.500979 -18.080757) (xy 391.478516 -18.10766)
			(xy 391.471156 -18.117396) (xy 391.465724 -18.141154) (xy 391.468102 -18.153126) (xy 391.47355 -18.17611)
			(xy 391.479414 -18.22298) (xy 391.479786 -18.246598) (xy 391.479786 -18.247106) (xy 391.479281 -18.274374)
			(xy 391.471519 -18.328356) (xy 391.456154 -18.380684) (xy 391.433499 -18.430292) (xy 391.404015 -18.476172)
			(xy 391.368302 -18.517389) (xy 391.327087 -18.553104) (xy 391.281208 -18.582591) (xy 391.231601 -18.605248)
			(xy 391.179274 -18.620616) (xy 391.125292 -18.62838) (xy 391.098024 -18.628868) (xy 391.06921 -18.628339)
			(xy 391.01224 -18.619661) (xy 390.957218 -18.602527) (xy 390.905392 -18.577327) (xy 390.857938 -18.544631)
			(xy 390.81593 -18.505181) (xy 390.780321 -18.459871) (xy 390.751919 -18.409728) (xy 390.741154 -18.382996)
			(xy 390.736179 -18.371815) (xy 390.718009 -18.355486) (xy 390.706356 -18.351754) (xy 390.668758 -18.341528)
			(xy 390.595695 -18.314448) (xy 390.525773 -18.28006) (xy 390.492488 -18.259806) (xy 390.484227 -18.25511)
			(xy 390.465564 -18.251602) (xy 390.446901 -18.25511) (xy 390.43864 -18.259806) (xy 390.405349 -18.280049)
			(xy 390.335425 -18.314431) (xy 390.262368 -18.341524) (xy 390.224772 -18.351754) (xy 390.213128 -18.355495)
			(xy 390.194964 -18.371827) (xy 390.189974 -18.382996) (xy 390.179268 -18.409757) (xy 390.150877 -18.459918)
			(xy 390.11527 -18.505242) (xy 390.073256 -18.544701) (xy 390.025789 -18.577397) (xy 389.973948 -18.602588)
			(xy 389.918909 -18.619702) (xy 389.861923 -18.62835) (xy 389.833104 -18.628868) (xy 389.805835 -18.628372)
			(xy 389.751852 -18.620611) (xy 389.699523 -18.605246) (xy 389.649913 -18.582591) (xy 389.604033 -18.553106)
			(xy 389.562815 -18.517392) (xy 389.5271 -18.476175) (xy 389.497614 -18.430295) (xy 389.474957 -18.380686)
			(xy 389.459591 -18.328358) (xy 389.451829 -18.274375) (xy 389.451342 -18.247106) (xy 389.451342 -18.246598)
			(xy 389.451702 -18.22298) (xy 389.457567 -18.176108) (xy 389.463026 -18.153126) (xy 389.465331 -18.141153)
			(xy 389.459914 -18.117422) (xy 389.452612 -18.10766) (xy 389.430154 -18.080753) (xy 389.389703 -18.023514)
			(xy 389.37184 -17.99336) (xy 389.347964 -17.994122) (xy 389.320693 -17.993713) (xy 389.266708 -17.985946)
			(xy 389.214377 -17.970576) (xy 389.164767 -17.947916) (xy 389.118885 -17.918426) (xy 389.077668 -17.882707)
			(xy 389.041953 -17.841486) (xy 389.012467 -17.795602) (xy 388.989811 -17.745989) (xy 388.974446 -17.693657)
			(xy 388.966684 -17.639671) (xy 312.321724 -17.639671) (xy 312.317062 -17.650143) (xy 312.270556 -17.734738)
			(xy 312.217133 -17.815145) (xy 312.15717 -17.890799) (xy 312.091087 -17.961171) (xy 312.019347 -18.025766)
			(xy 311.942453 -18.084132) (xy 311.860945 -18.135858) (xy 311.775395 -18.180583) (xy 311.686402 -18.217992)
			(xy 311.59459 -18.247823) (xy 311.500605 -18.269867) (xy 311.405105 -18.28397) (xy 311.308759 -18.290031)
			(xy 311.212245 -18.28801) (xy 311.116237 -18.277919) (xy 311.021411 -18.25983) (xy 310.928432 -18.233869)
			(xy 310.83795 -18.20022) (xy 310.750602 -18.159117) (xy 310.666999 -18.110849) (xy 310.587729 -18.055754)
			(xy 310.513347 -17.99422) (xy 310.444374 -17.926677) (xy 310.381296 -17.8536) (xy 310.324553 -17.775501)
			(xy 310.274545 -17.692927) (xy 310.231622 -17.606459) (xy 310.196085 -17.516702) (xy 310.168183 -17.424286)
			(xy 310.148112 -17.32986) (xy 310.136013 -17.234085) (xy 310.13197 -17.137634) (xy 260.324092 -17.137634)
			(xy 260.324092 -19.164372) (xy 391.759624 -19.164372) (xy 391.759624 -19.109828) (xy 391.767387 -19.05584)
			(xy 391.782754 -19.003507) (xy 391.805414 -18.953893) (xy 391.834904 -18.90801) (xy 391.870625 -18.866791)
			(xy 391.911849 -18.831076) (xy 391.957736 -18.801591) (xy 392.007352 -18.778938) (xy 392.059687 -18.763576)
			(xy 392.113676 -18.75582) (xy 392.140948 -18.75536) (xy 392.164824 -18.756122) (xy 392.182721 -18.725764)
			(xy 392.223299 -18.66814) (xy 392.24585 -18.64106) (xy 392.253163 -18.631368) (xy 392.258751 -18.60778)
			(xy 392.256518 -18.595848) (xy 392.251292 -18.57335) (xy 392.245691 -18.527502) (xy 392.245342 -18.504408)
			(xy 392.245342 -18.5039) (xy 392.245801 -18.476629) (xy 392.253564 -18.422642) (xy 392.26893 -18.370309)
			(xy 392.291588 -18.320695) (xy 392.321076 -18.274811) (xy 392.356794 -18.233591) (xy 392.398015 -18.197874)
			(xy 392.443899 -18.168386) (xy 392.493512 -18.145729) (xy 392.545846 -18.130363) (xy 392.599833 -18.122601)
			(xy 392.627104 -18.122138) (xy 392.655832 -18.122652) (xy 392.712636 -18.131283) (xy 392.767508 -18.14832)
			(xy 392.819212 -18.173379) (xy 392.866581 -18.205896) (xy 392.90855 -18.245137) (xy 392.944171 -18.290218)
			(xy 392.972643 -18.340123) (xy 392.983466 -18.36674) (xy 392.988491 -18.37784) (xy 393.006658 -18.39402)
			(xy 393.018264 -18.397728) (xy 393.05577 -18.407926) (xy 393.128656 -18.434938) (xy 393.198414 -18.469227)
			(xy 393.231624 -18.489422) (xy 393.23988 -18.494136) (xy 393.258548 -18.497663) (xy 393.277216 -18.494136)
			(xy 393.285472 -18.489422) (xy 393.319022 -18.469008) (xy 393.389518 -18.434385) (xy 393.4632 -18.407193)
			(xy 393.501118 -18.396966) (xy 393.512685 -18.393299) (xy 393.530848 -18.377258) (xy 393.535916 -18.366232)
			(xy 393.546699 -18.339636) (xy 393.575184 -18.289813) (xy 393.610805 -18.244814) (xy 393.652758 -18.205652)
			(xy 393.700099 -18.17321) (xy 393.751762 -18.148217) (xy 393.806583 -18.131237) (xy 393.863329 -18.122652)
			(xy 393.892024 -18.122138) (xy 393.919294 -18.122602) (xy 393.973278 -18.130367) (xy 394.025608 -18.145735)
			(xy 394.075219 -18.168394) (xy 394.121099 -18.197883) (xy 394.162317 -18.2336) (xy 394.198032 -18.27482)
			(xy 394.227517 -18.320703) (xy 394.250173 -18.370314) (xy 394.265538 -18.422645) (xy 394.2733 -18.47663)
			(xy 394.273786 -18.5039) (xy 394.273425 -18.527518) (xy 394.267561 -18.57439) (xy 394.262102 -18.597372)
			(xy 394.259792 -18.609344) (xy 394.265211 -18.633077) (xy 394.272516 -18.642838) (xy 394.294678 -18.669528)
			(xy 394.334615 -18.72626) (xy 394.352272 -18.756122) (xy 394.376148 -18.75536) (xy 394.403417 -18.755806)
			(xy 394.457398 -18.763573) (xy 394.509725 -18.778944) (xy 394.559332 -18.801604) (xy 394.60521 -18.831093)
			(xy 394.646424 -18.86681) (xy 394.682136 -18.908029) (xy 394.711619 -18.95391) (xy 394.734273 -19.00352)
			(xy 394.749637 -19.055849) (xy 394.757398 -19.109831) (xy 394.757398 -19.163671) (xy 397.348684 -19.163671)
			(xy 397.348684 -19.109129) (xy 397.356446 -19.055143) (xy 397.371811 -19.002811) (xy 397.394467 -18.953198)
			(xy 397.423953 -18.907314) (xy 397.459668 -18.866093) (xy 397.500885 -18.830374) (xy 397.546767 -18.800884)
			(xy 397.596377 -18.778224) (xy 397.648708 -18.762854) (xy 397.702693 -18.755087) (xy 397.729964 -18.754598)
			(xy 397.75384 -18.75536) (xy 397.771578 -18.725218) (xy 397.811774 -18.667978) (xy 397.834104 -18.64106)
			(xy 397.841422 -18.631371) (xy 397.847005 -18.607781) (xy 397.844772 -18.595848) (xy 397.839447 -18.57317)
			(xy 397.833718 -18.526938) (xy 397.833342 -18.503646) (xy 397.833342 -18.503138) (xy 397.833837 -18.475868)
			(xy 397.841594 -18.421882) (xy 397.856956 -18.369549) (xy 397.879609 -18.319936) (xy 397.909093 -18.274052)
			(xy 397.944807 -18.232831) (xy 397.986025 -18.197113) (xy 398.031906 -18.167625) (xy 398.081518 -18.144967)
			(xy 398.133849 -18.129601) (xy 398.187834 -18.121839) (xy 398.215104 -18.121376) (xy 398.243805 -18.121968)
			(xy 398.300558 -18.130576) (xy 398.355383 -18.147581) (xy 398.407046 -18.172601) (xy 398.454381 -18.205071)
			(xy 398.496323 -18.244262) (xy 398.531927 -18.289288) (xy 398.56039 -18.339137) (xy 398.571212 -18.365724)
			(xy 398.57622 -18.376833) (xy 398.594399 -18.393011) (xy 398.60601 -18.396712) (xy 398.643734 -18.40692)
			(xy 398.717057 -18.433977) (xy 398.787232 -18.468382) (xy 398.82064 -18.48866) (xy 398.828896 -18.493374)
			(xy 398.847564 -18.496901) (xy 398.866232 -18.493374) (xy 398.874488 -18.48866) (xy 398.907896 -18.46838)
			(xy 398.97807 -18.433973) (xy 399.05139 -18.406908) (xy 399.089118 -18.396712) (xy 399.100728 -18.39301)
			(xy 399.118902 -18.37683) (xy 399.123916 -18.365724) (xy 399.13473 -18.339127) (xy 399.163173 -18.289256)
			(xy 399.198766 -18.244208) (xy 399.240705 -18.205) (xy 399.288045 -18.172517) (xy 399.339716 -18.147492)
			(xy 399.394553 -18.130489) (xy 399.451318 -18.121892) (xy 399.480024 -18.121376) (xy 399.507297 -18.121779)
			(xy 399.561288 -18.129546) (xy 399.613624 -18.144917) (xy 399.66324 -18.16758) (xy 399.709126 -18.197074)
			(xy 399.750346 -18.232798) (xy 399.786063 -18.274024) (xy 399.81555 -18.319914) (xy 399.838205 -18.369534)
			(xy 399.853568 -18.421872) (xy 399.861325 -18.475865) (xy 399.861786 -18.503138) (xy 399.861786 -18.503646)
			(xy 399.861408 -18.526938) (xy 399.855673 -18.573168) (xy 399.850356 -18.595848) (xy 399.84808 -18.607783)
			(xy 399.853658 -18.631396) (xy 399.861024 -18.64106) (xy 399.883353 -18.667979) (xy 399.92355 -18.725218)
			(xy 399.941288 -18.75536) (xy 399.965164 -18.754598) (xy 399.992434 -18.755139) (xy 400.046419 -18.762896)
			(xy 400.09875 -18.778258) (xy 400.148363 -18.800911) (xy 400.194246 -18.830394) (xy 400.235466 -18.866108)
			(xy 400.271184 -18.907325) (xy 400.300672 -18.953205) (xy 400.32333 -19.002816) (xy 400.338696 -19.055146)
			(xy 400.346459 -19.10913) (xy 400.346458 -19.16367) (xy 400.346458 -19.163671) (xy 402.936684 -19.163671)
			(xy 402.936684 -19.109129) (xy 402.944446 -19.055143) (xy 402.959811 -19.002811) (xy 402.982467 -18.953198)
			(xy 403.011953 -18.907314) (xy 403.047668 -18.866093) (xy 403.088885 -18.830374) (xy 403.134767 -18.800884)
			(xy 403.184377 -18.778224) (xy 403.236708 -18.762854) (xy 403.290693 -18.755087) (xy 403.317964 -18.754598)
			(xy 403.34184 -18.75536) (xy 403.359578 -18.725218) (xy 403.399774 -18.667978) (xy 403.422104 -18.64106)
			(xy 403.429422 -18.631371) (xy 403.435005 -18.607781) (xy 403.432772 -18.595848) (xy 403.427447 -18.57317)
			(xy 403.421718 -18.526938) (xy 403.421342 -18.503646) (xy 403.421342 -18.503138) (xy 403.421837 -18.475868)
			(xy 403.429594 -18.421882) (xy 403.444956 -18.369549) (xy 403.467609 -18.319936) (xy 403.497093 -18.274052)
			(xy 403.532807 -18.232831) (xy 403.574025 -18.197113) (xy 403.619906 -18.167625) (xy 403.669518 -18.144967)
			(xy 403.721849 -18.129601) (xy 403.775834 -18.121839) (xy 403.803104 -18.121376) (xy 403.831805 -18.121968)
			(xy 403.888558 -18.130576) (xy 403.943383 -18.147581) (xy 403.995046 -18.172601) (xy 404.042381 -18.205071)
			(xy 404.084323 -18.244262) (xy 404.119927 -18.289288) (xy 404.14839 -18.339137) (xy 404.159212 -18.365724)
			(xy 404.16422 -18.376833) (xy 404.182399 -18.393011) (xy 404.19401 -18.396712) (xy 404.231734 -18.40692)
			(xy 404.305057 -18.433977) (xy 404.375232 -18.468382) (xy 404.40864 -18.48866) (xy 404.416896 -18.493374)
			(xy 404.435564 -18.496901) (xy 404.454232 -18.493374) (xy 404.462488 -18.48866) (xy 404.495896 -18.46838)
			(xy 404.56607 -18.433973) (xy 404.63939 -18.406908) (xy 404.677118 -18.396712) (xy 404.688728 -18.39301)
			(xy 404.706902 -18.37683) (xy 404.711916 -18.365724) (xy 404.72273 -18.339127) (xy 404.751173 -18.289256)
			(xy 404.786766 -18.244208) (xy 404.828705 -18.205) (xy 404.876045 -18.172517) (xy 404.927716 -18.147492)
			(xy 404.982553 -18.130489) (xy 405.039318 -18.121892) (xy 405.068024 -18.121376) (xy 405.095297 -18.121779)
			(xy 405.149288 -18.129546) (xy 405.201624 -18.144917) (xy 405.25124 -18.16758) (xy 405.297126 -18.197074)
			(xy 405.338346 -18.232798) (xy 405.374063 -18.274024) (xy 405.40355 -18.319914) (xy 405.426205 -18.369534)
			(xy 405.441568 -18.421872) (xy 405.449325 -18.475865) (xy 405.449786 -18.503138) (xy 405.449786 -18.503646)
			(xy 405.449408 -18.526938) (xy 405.443673 -18.573168) (xy 405.438356 -18.595848) (xy 405.43608 -18.607783)
			(xy 405.441658 -18.631396) (xy 405.449024 -18.64106) (xy 405.471353 -18.667979) (xy 405.51155 -18.725218)
			(xy 405.529288 -18.75536) (xy 405.553164 -18.754598) (xy 405.580434 -18.755139) (xy 405.634419 -18.762896)
			(xy 405.68675 -18.778258) (xy 405.736363 -18.800911) (xy 405.782246 -18.830394) (xy 405.823466 -18.866108)
			(xy 405.859184 -18.907325) (xy 405.888672 -18.953205) (xy 405.91133 -19.002816) (xy 405.926696 -19.055146)
			(xy 405.934459 -19.10913) (xy 405.934458 -19.16367) (xy 405.934458 -19.163671) (xy 408.524684 -19.163671)
			(xy 408.524684 -19.109129) (xy 408.532446 -19.055143) (xy 408.547811 -19.002811) (xy 408.570467 -18.953198)
			(xy 408.599953 -18.907314) (xy 408.635668 -18.866093) (xy 408.676885 -18.830374) (xy 408.722767 -18.800884)
			(xy 408.772377 -18.778224) (xy 408.824708 -18.762854) (xy 408.878693 -18.755087) (xy 408.905964 -18.754598)
			(xy 408.92984 -18.75536) (xy 408.947578 -18.725218) (xy 408.987774 -18.667978) (xy 409.010104 -18.64106)
			(xy 409.017422 -18.631371) (xy 409.023005 -18.607781) (xy 409.020772 -18.595848) (xy 409.015447 -18.57317)
			(xy 409.009718 -18.526938) (xy 409.009342 -18.503646) (xy 409.009342 -18.503138) (xy 409.009837 -18.475868)
			(xy 409.017594 -18.421882) (xy 409.032956 -18.369549) (xy 409.055609 -18.319936) (xy 409.085093 -18.274052)
			(xy 409.120807 -18.232831) (xy 409.162025 -18.197113) (xy 409.207906 -18.167625) (xy 409.257518 -18.144967)
			(xy 409.309849 -18.129601) (xy 409.363834 -18.121839) (xy 409.391104 -18.121376) (xy 409.419805 -18.121968)
			(xy 409.476558 -18.130576) (xy 409.531383 -18.147581) (xy 409.583046 -18.172601) (xy 409.630381 -18.205071)
			(xy 409.672323 -18.244262) (xy 409.707927 -18.289288) (xy 409.73639 -18.339137) (xy 409.747212 -18.365724)
			(xy 409.75222 -18.376833) (xy 409.770399 -18.393011) (xy 409.78201 -18.396712) (xy 409.819734 -18.40692)
			(xy 409.893057 -18.433977) (xy 409.963232 -18.468382) (xy 409.99664 -18.48866) (xy 410.004896 -18.493374)
			(xy 410.023564 -18.496901) (xy 410.042232 -18.493374) (xy 410.050488 -18.48866) (xy 410.083896 -18.46838)
			(xy 410.15407 -18.433973) (xy 410.22739 -18.406908) (xy 410.265118 -18.396712) (xy 410.276728 -18.39301)
			(xy 410.294902 -18.37683) (xy 410.299916 -18.365724) (xy 410.31073 -18.339127) (xy 410.339173 -18.289256)
			(xy 410.374766 -18.244208) (xy 410.416705 -18.205) (xy 410.464045 -18.172517) (xy 410.515716 -18.147492)
			(xy 410.570553 -18.130489) (xy 410.627318 -18.121892) (xy 410.656024 -18.121376) (xy 410.683297 -18.121779)
			(xy 410.737288 -18.129546) (xy 410.789624 -18.144917) (xy 410.83924 -18.16758) (xy 410.885126 -18.197074)
			(xy 410.926346 -18.232798) (xy 410.962063 -18.274024) (xy 410.99155 -18.319914) (xy 411.014205 -18.369534)
			(xy 411.029568 -18.421872) (xy 411.037325 -18.475865) (xy 411.037786 -18.503138) (xy 411.037786 -18.503646)
			(xy 411.037408 -18.526938) (xy 411.031673 -18.573168) (xy 411.026356 -18.595848) (xy 411.02408 -18.607783)
			(xy 411.029658 -18.631396) (xy 411.037024 -18.64106) (xy 411.059353 -18.667979) (xy 411.09955 -18.725218)
			(xy 411.117288 -18.75536) (xy 411.141164 -18.754598) (xy 411.168434 -18.755139) (xy 411.222419 -18.762896)
			(xy 411.27475 -18.778258) (xy 411.324363 -18.800911) (xy 411.370246 -18.830394) (xy 411.411466 -18.866108)
			(xy 411.447184 -18.907325) (xy 411.476672 -18.953205) (xy 411.49933 -19.002816) (xy 411.514696 -19.055146)
			(xy 411.522459 -19.10913) (xy 411.522458 -19.16367) (xy 411.522458 -19.163671) (xy 414.418484 -19.163671)
			(xy 414.418484 -19.109129) (xy 414.426246 -19.055141) (xy 414.441612 -19.002808) (xy 414.464269 -18.953194)
			(xy 414.493757 -18.907309) (xy 414.529473 -18.866088) (xy 414.570693 -18.830369) (xy 414.616576 -18.800879)
			(xy 414.666189 -18.778219) (xy 414.718522 -18.762851) (xy 414.772509 -18.755086) (xy 414.79978 -18.754598)
			(xy 414.823656 -18.75536) (xy 414.841393 -18.725217) (xy 414.88159 -18.667978) (xy 414.90392 -18.64106)
			(xy 414.911239 -18.631372) (xy 414.91682 -18.607781) (xy 414.914588 -18.595848) (xy 414.909263 -18.57317)
			(xy 414.903534 -18.526938) (xy 414.903158 -18.503646) (xy 414.903158 -18.503138) (xy 414.903637 -18.475867)
			(xy 414.911394 -18.42188) (xy 414.926757 -18.369546) (xy 414.949411 -18.319932) (xy 414.978897 -18.274047)
			(xy 415.014613 -18.232826) (xy 415.055832 -18.197108) (xy 415.101716 -18.16762) (xy 415.151329 -18.144963)
			(xy 415.203662 -18.129598) (xy 415.257649 -18.121838) (xy 415.28492 -18.121376) (xy 415.313621 -18.121954)
			(xy 415.370375 -18.130564) (xy 415.425201 -18.147572) (xy 415.476863 -18.172594) (xy 415.524199 -18.205066)
			(xy 415.56614 -18.244258) (xy 415.601743 -18.289286) (xy 415.630206 -18.339136) (xy 415.641028 -18.365724)
			(xy 415.646078 -18.376809) (xy 415.664227 -18.392996) (xy 415.675826 -18.396712) (xy 415.713551 -18.406916)
			(xy 415.786874 -18.433975) (xy 415.857048 -18.468381) (xy 415.890456 -18.48866) (xy 415.898712 -18.493374)
			(xy 415.91738 -18.496901) (xy 415.936048 -18.493374) (xy 415.944304 -18.48866) (xy 415.97771 -18.468377)
			(xy 416.047885 -18.433971) (xy 416.121206 -18.406907) (xy 416.158934 -18.396712) (xy 416.170547 -18.393017)
			(xy 416.188719 -18.376832) (xy 416.193732 -18.365724) (xy 416.204533 -18.339122) (xy 416.232977 -18.28925)
			(xy 416.268572 -18.244202) (xy 416.310513 -18.204994) (xy 416.357855 -18.172511) (xy 416.409528 -18.147487)
			(xy 416.464367 -18.130486) (xy 416.521133 -18.121891) (xy 416.54984 -18.121376) (xy 416.577112 -18.121787)
			(xy 416.6311 -18.129555) (xy 416.683434 -18.144928) (xy 416.733046 -18.167591) (xy 416.778929 -18.197085)
			(xy 416.820147 -18.232808) (xy 416.855862 -18.274034) (xy 416.885346 -18.319922) (xy 416.907999 -18.36954)
			(xy 416.923361 -18.421876) (xy 416.931118 -18.475866) (xy 416.931602 -18.503138) (xy 416.931602 -18.503646)
			(xy 416.931223 -18.526938) (xy 416.925489 -18.573168) (xy 416.920172 -18.595848) (xy 416.917892 -18.607783)
			(xy 416.923472 -18.631396) (xy 416.93084 -18.64106) (xy 416.95317 -18.667978) (xy 416.993367 -18.725217)
			(xy 417.011104 -18.75536) (xy 417.03498 -18.754598) (xy 417.062249 -18.75514) (xy 417.116232 -18.762899)
			(xy 417.168562 -18.778262) (xy 417.218173 -18.800916) (xy 417.264054 -18.8304) (xy 417.305272 -18.866114)
			(xy 417.340988 -18.90733) (xy 417.370474 -18.95321) (xy 417.393131 -19.002819) (xy 417.408497 -19.055148)
			(xy 417.416259 -19.109131) (xy 417.416259 -19.163669) (xy 417.416159 -19.164366) (xy 420.005546 -19.164366)
			(xy 420.005546 -19.109834) (xy 420.013307 -19.055857) (xy 420.028669 -19.003533) (xy 420.051321 -18.953928)
			(xy 420.080802 -18.908051) (xy 420.116512 -18.866837) (xy 420.157723 -18.831124) (xy 420.203596 -18.801639)
			(xy 420.253199 -18.778982) (xy 420.305521 -18.763614) (xy 420.359498 -18.755849) (xy 420.386764 -18.75536)
			(xy 420.41064 -18.756122) (xy 420.428525 -18.725757) (xy 420.469105 -18.668133) (xy 420.491666 -18.64106)
			(xy 420.49898 -18.631369) (xy 420.504567 -18.60778) (xy 420.502334 -18.595848) (xy 420.497108 -18.57335)
			(xy 420.491507 -18.527502) (xy 420.491158 -18.504408) (xy 420.491158 -18.5039) (xy 420.491602 -18.476628)
			(xy 420.499364 -18.422639) (xy 420.514731 -18.370305) (xy 420.537391 -18.320691) (xy 420.56688 -18.274806)
			(xy 420.6026 -18.233585) (xy 420.643822 -18.197868) (xy 420.689708 -18.168381) (xy 420.739324 -18.145724)
			(xy 420.791659 -18.13036) (xy 420.845648 -18.1226) (xy 420.87292 -18.122138) (xy 420.901648 -18.122638)
			(xy 420.958453 -18.131272) (xy 421.013326 -18.148311) (xy 421.065029 -18.173372) (xy 421.112399 -18.20589)
			(xy 421.154367 -18.245133) (xy 421.189988 -18.290216) (xy 421.21846 -18.340123) (xy 421.229282 -18.36674)
			(xy 421.234299 -18.377844) (xy 421.252472 -18.394023) (xy 421.26408 -18.397728) (xy 421.301588 -18.407922)
			(xy 421.374473 -18.434935) (xy 421.44423 -18.469227) (xy 421.47744 -18.489422) (xy 421.485693 -18.494126)
			(xy 421.50433 -18.497727) (xy 421.523003 -18.494322) (xy 421.531288 -18.489676) (xy 421.568924 -18.466839)
			(xy 421.648421 -18.429011) (xy 421.731736 -18.400565) (xy 421.77462 -18.390616) (xy 421.786648 -18.387408)
			(xy 421.805694 -18.371424) (xy 421.810942 -18.360136) (xy 421.822064 -18.334135) (xy 421.850855 -18.285463)
			(xy 421.88651 -18.24157) (xy 421.928251 -18.203417) (xy 421.975163 -18.171839) (xy 422.02622 -18.147526)
			(xy 422.080306 -18.131012) (xy 422.136235 -18.122657) (xy 422.16451 -18.122138) (xy 422.19178 -18.122615)
			(xy 422.245764 -18.130378) (xy 422.298093 -18.145745) (xy 422.347703 -18.168402) (xy 422.393584 -18.197889)
			(xy 422.434802 -18.233605) (xy 422.470517 -18.274824) (xy 422.500003 -18.320705) (xy 422.522659 -18.370316)
			(xy 422.538024 -18.422646) (xy 422.545786 -18.47663) (xy 422.546272 -18.5039) (xy 422.546272 -18.504154)
			(xy 422.545694 -18.533325) (xy 422.536759 -18.590981) (xy 422.528492 -18.618962) (xy 422.525374 -18.630973)
			(xy 422.529915 -18.655345) (xy 422.537128 -18.665444) (xy 422.553774 -18.687137) (xy 422.584285 -18.732519)
			(xy 422.598088 -18.756122) (xy 422.621964 -18.75536) (xy 422.649238 -18.755777) (xy 422.703232 -18.763536)
			(xy 422.755572 -18.7789) (xy 422.805193 -18.801556) (xy 422.851084 -18.831045) (xy 422.89231 -18.866764)
			(xy 422.928034 -18.907988) (xy 422.957526 -18.953876) (xy 422.980188 -19.003494) (xy 422.995557 -19.055833)
			(xy 423.00332 -19.109826) (xy 423.00332 -19.163675) (xy 425.628462 -19.163675) (xy 425.628462 -19.109125)
			(xy 425.636225 -19.055131) (xy 425.651594 -19.002792) (xy 425.674255 -18.953173) (xy 425.703747 -18.907283)
			(xy 425.73947 -18.866059) (xy 425.780696 -18.830337) (xy 425.826587 -18.800847) (xy 425.876207 -18.778188)
			(xy 425.928547 -18.762822) (xy 425.982541 -18.75506) (xy 426.009816 -18.754598) (xy 426.033692 -18.75536)
			(xy 426.051426 -18.725215) (xy 426.091625 -18.667977) (xy 426.113956 -18.64106) (xy 426.12127 -18.631368)
			(xy 426.126857 -18.60778) (xy 426.124624 -18.595848) (xy 426.119298 -18.57317) (xy 426.11357 -18.526938)
			(xy 426.113194 -18.503646) (xy 426.113194 -18.503138) (xy 426.11376 -18.475872) (xy 426.121515 -18.421893)
			(xy 426.136873 -18.369568) (xy 426.159522 -18.319961) (xy 426.189 -18.274082) (xy 426.224707 -18.232865)
			(xy 426.265916 -18.197149) (xy 426.311789 -18.167661) (xy 426.361391 -18.145002) (xy 426.413713 -18.129632)
			(xy 426.46769 -18.121865) (xy 426.494956 -18.121376) (xy 426.523658 -18.121924) (xy 426.580413 -18.130539)
			(xy 426.63524 -18.147551) (xy 426.686903 -18.172578) (xy 426.734238 -18.205054) (xy 426.776179 -18.24425)
			(xy 426.811781 -18.289282) (xy 426.840242 -18.339135) (xy 426.851064 -18.365724) (xy 426.856096 -18.37682)
			(xy 426.874258 -18.393003) (xy 426.885862 -18.396712) (xy 426.92359 -18.406908) (xy 426.996911 -18.43397)
			(xy 427.067085 -18.468379) (xy 427.100492 -18.48866) (xy 427.108748 -18.493374) (xy 427.127416 -18.496901)
			(xy 427.146084 -18.493374) (xy 427.15434 -18.48866) (xy 427.187753 -18.46839) (xy 427.257925 -18.433979)
			(xy 427.331243 -18.40691) (xy 427.36897 -18.396712) (xy 427.38059 -18.393034) (xy 427.398758 -18.376836)
			(xy 427.403768 -18.365724) (xy 427.414539 -18.339109) (xy 427.442987 -18.289235) (xy 427.478586 -18.244187)
			(xy 427.520531 -18.204979) (xy 427.567877 -18.172498) (xy 427.619555 -18.147476) (xy 427.674397 -18.130479)
			(xy 427.731168 -18.121889) (xy 427.759876 -18.121376) (xy 427.787148 -18.121824) (xy 427.841138 -18.129584)
			(xy 427.893473 -18.144949) (xy 427.943088 -18.167606) (xy 427.988974 -18.197095) (xy 428.030195 -18.232814)
			(xy 428.065913 -18.274037) (xy 428.0954 -18.319924) (xy 428.118056 -18.36954) (xy 428.133419 -18.421876)
			(xy 428.141177 -18.475866) (xy 428.141638 -18.503138) (xy 428.141638 -18.503646) (xy 428.141258 -18.526938)
			(xy 428.135525 -18.573168) (xy 428.130208 -18.595848) (xy 428.12792 -18.607782) (xy 428.133504 -18.631398)
			(xy 428.140876 -18.64106) (xy 428.163208 -18.667976) (xy 428.203403 -18.725217) (xy 428.22114 -18.75536)
			(xy 428.245016 -18.754598) (xy 428.272282 -18.755165) (xy 428.326258 -18.762928) (xy 428.37858 -18.778293)
			(xy 428.428183 -18.800948) (xy 428.474057 -18.830431) (xy 428.515269 -18.866143) (xy 428.550978 -18.907356)
			(xy 428.58046 -18.953231) (xy 428.603112 -19.002835) (xy 428.618475 -19.055158) (xy 428.626236 -19.109134)
			(xy 428.626236 -19.163666) (xy 428.626235 -19.163675) (xy 431.216462 -19.163675) (xy 431.216462 -19.109125)
			(xy 431.224225 -19.055131) (xy 431.239594 -19.002792) (xy 431.262255 -18.953173) (xy 431.291747 -18.907283)
			(xy 431.32747 -18.866059) (xy 431.368696 -18.830337) (xy 431.414587 -18.800847) (xy 431.464207 -18.778188)
			(xy 431.516547 -18.762822) (xy 431.570541 -18.75506) (xy 431.597816 -18.754598) (xy 431.621692 -18.75536)
			(xy 431.639426 -18.725215) (xy 431.679625 -18.667977) (xy 431.701956 -18.64106) (xy 431.70927 -18.631368)
			(xy 431.714857 -18.60778) (xy 431.712624 -18.595848) (xy 431.707298 -18.57317) (xy 431.70157 -18.526938)
			(xy 431.701194 -18.503646) (xy 431.701194 -18.503138) (xy 431.70176 -18.475872) (xy 431.709515 -18.421893)
			(xy 431.724873 -18.369568) (xy 431.747522 -18.319961) (xy 431.777 -18.274082) (xy 431.812707 -18.232865)
			(xy 431.853916 -18.197149) (xy 431.899789 -18.167661) (xy 431.949391 -18.145002) (xy 432.001713 -18.129632)
			(xy 432.05569 -18.121865) (xy 432.082956 -18.121376) (xy 432.111658 -18.121924) (xy 432.168413 -18.130539)
			(xy 432.22324 -18.147551) (xy 432.274903 -18.172578) (xy 432.322238 -18.205054) (xy 432.364179 -18.24425)
			(xy 432.399781 -18.289282) (xy 432.428242 -18.339135) (xy 432.439064 -18.365724) (xy 432.444096 -18.37682)
			(xy 432.462258 -18.393003) (xy 432.473862 -18.396712) (xy 432.51159 -18.406908) (xy 432.584911 -18.43397)
			(xy 432.655085 -18.468379) (xy 432.688492 -18.48866) (xy 432.696748 -18.493374) (xy 432.715416 -18.496901)
			(xy 432.734084 -18.493374) (xy 432.74234 -18.48866) (xy 432.775753 -18.46839) (xy 432.845925 -18.433979)
			(xy 432.919243 -18.40691) (xy 432.95697 -18.396712) (xy 432.96859 -18.393034) (xy 432.986758 -18.376836)
			(xy 432.991768 -18.365724) (xy 433.002539 -18.339109) (xy 433.030987 -18.289235) (xy 433.066586 -18.244187)
			(xy 433.108531 -18.204979) (xy 433.155877 -18.172498) (xy 433.207555 -18.147476) (xy 433.262397 -18.130479)
			(xy 433.319168 -18.121889) (xy 433.347876 -18.121376) (xy 433.375148 -18.121824) (xy 433.429138 -18.129584)
			(xy 433.481473 -18.144949) (xy 433.531088 -18.167606) (xy 433.576974 -18.197095) (xy 433.618195 -18.232814)
			(xy 433.653913 -18.274037) (xy 433.6834 -18.319924) (xy 433.706056 -18.36954) (xy 433.721419 -18.421876)
			(xy 433.729177 -18.475866) (xy 433.729638 -18.503138) (xy 433.729638 -18.503646) (xy 433.729258 -18.526938)
			(xy 433.723525 -18.573168) (xy 433.718208 -18.595848) (xy 433.71592 -18.607782) (xy 433.721504 -18.631398)
			(xy 433.728876 -18.64106) (xy 433.751208 -18.667976) (xy 433.791403 -18.725217) (xy 433.80914 -18.75536)
			(xy 433.833016 -18.754598) (xy 433.860282 -18.755165) (xy 433.914258 -18.762928) (xy 433.96658 -18.778293)
			(xy 434.016183 -18.800948) (xy 434.062057 -18.830431) (xy 434.103269 -18.866143) (xy 434.138978 -18.907356)
			(xy 434.16846 -18.953231) (xy 434.191112 -19.002835) (xy 434.206475 -19.055158) (xy 434.214236 -19.109134)
			(xy 434.214236 -19.163666) (xy 434.206475 -19.217642) (xy 434.191112 -19.269965) (xy 434.16846 -19.319569)
			(xy 434.138978 -19.365444) (xy 434.103269 -19.406657) (xy 434.062057 -19.442369) (xy 434.016183 -19.471852)
			(xy 433.96658 -19.494507) (xy 433.914258 -19.509872) (xy 433.860282 -19.517635) (xy 433.833016 -19.518122)
			(xy 433.80914 -19.51736) (xy 433.791284 -19.547518) (xy 433.750832 -19.604758) (xy 433.728368 -19.63166)
			(xy 433.721005 -19.641393) (xy 433.715577 -19.665153) (xy 433.717954 -19.677126) (xy 433.723401 -19.70011)
			(xy 433.729266 -19.74698) (xy 433.729638 -19.770598) (xy 433.729638 -19.771106) (xy 433.729204 -19.798378)
			(xy 433.72144 -19.852367) (xy 433.706072 -19.904702) (xy 433.683412 -19.954317) (xy 433.653922 -20.000202)
			(xy 433.618201 -20.041422) (xy 433.576978 -20.07714) (xy 433.531091 -20.106627) (xy 433.481474 -20.129283)
			(xy 433.429138 -20.144647) (xy 433.375148 -20.152406) (xy 433.347876 -20.152868) (xy 433.319064 -20.152294)
			(xy 433.262095 -20.143623) (xy 433.207075 -20.126497) (xy 433.155249 -20.101303) (xy 433.107794 -20.068614)
			(xy 433.065785 -20.029169) (xy 433.030176 -19.983865) (xy 433.001772 -19.933726) (xy 432.991006 -19.906996)
			(xy 432.986056 -19.895802) (xy 432.967868 -19.879478) (xy 432.956208 -19.875754) (xy 432.918607 -19.865539)
			(xy 432.845545 -19.838454) (xy 432.775624 -19.804062) (xy 432.74234 -19.783806) (xy 432.734079 -19.77911)
			(xy 432.715416 -19.775602) (xy 432.696753 -19.77911) (xy 432.688492 -19.783806) (xy 432.655206 -19.804059)
			(xy 432.58528 -19.838437) (xy 432.512221 -19.865526) (xy 432.474624 -19.875754) (xy 432.462989 -19.879518)
			(xy 432.44482 -19.895833) (xy 432.439826 -19.906996) (xy 432.429077 -19.933738) (xy 432.400691 -19.983897)
			(xy 432.36509 -20.029221) (xy 432.323082 -20.06868) (xy 432.275622 -20.101378) (xy 432.223786 -20.126573)
			(xy 432.168753 -20.143692) (xy 432.111773 -20.152346) (xy 432.082956 -20.152868) (xy 432.055686 -20.152416)
			(xy 432.001701 -20.144649) (xy 431.949371 -20.129278) (xy 431.899762 -20.106617) (xy 431.853881 -20.077128)
			(xy 431.812664 -20.041409) (xy 431.77695 -20.000188) (xy 431.747464 -19.954305) (xy 431.724808 -19.904693)
			(xy 431.709443 -19.852362) (xy 431.701681 -19.798376) (xy 431.701194 -19.771106) (xy 431.701194 -19.770598)
			(xy 431.701555 -19.74698) (xy 431.707419 -19.700108) (xy 431.712878 -19.677126) (xy 431.715193 -19.665154)
			(xy 431.709771 -19.64142) (xy 431.702464 -19.63166) (xy 431.680004 -19.604755) (xy 431.639554 -19.547514)
			(xy 431.621692 -19.51736) (xy 431.597816 -19.518122) (xy 431.570541 -19.51774) (xy 431.516547 -19.509978)
			(xy 431.464207 -19.494612) (xy 431.414587 -19.471953) (xy 431.368696 -19.442463) (xy 431.32747 -19.406741)
			(xy 431.291747 -19.365517) (xy 431.262255 -19.319627) (xy 431.239594 -19.270008) (xy 431.224225 -19.217669)
			(xy 431.216462 -19.163675) (xy 428.626235 -19.163675) (xy 428.618475 -19.217642) (xy 428.603112 -19.269965)
			(xy 428.58046 -19.319569) (xy 428.550978 -19.365444) (xy 428.515269 -19.406657) (xy 428.474057 -19.442369)
			(xy 428.428183 -19.471852) (xy 428.37858 -19.494507) (xy 428.326258 -19.509872) (xy 428.272282 -19.517635)
			(xy 428.245016 -19.518122) (xy 428.22114 -19.51736) (xy 428.203284 -19.547518) (xy 428.162832 -19.604758)
			(xy 428.140368 -19.63166) (xy 428.133005 -19.641393) (xy 428.127577 -19.665153) (xy 428.129954 -19.677126)
			(xy 428.135401 -19.70011) (xy 428.141266 -19.74698) (xy 428.141638 -19.770598) (xy 428.141638 -19.771106)
			(xy 428.141204 -19.798378) (xy 428.13344 -19.852367) (xy 428.118072 -19.904702) (xy 428.095412 -19.954317)
			(xy 428.065922 -20.000202) (xy 428.030201 -20.041422) (xy 427.988978 -20.07714) (xy 427.943091 -20.106627)
			(xy 427.893474 -20.129283) (xy 427.841138 -20.144647) (xy 427.787148 -20.152406) (xy 427.759876 -20.152868)
			(xy 427.731064 -20.152294) (xy 427.674095 -20.143623) (xy 427.619075 -20.126497) (xy 427.567249 -20.101303)
			(xy 427.519794 -20.068614) (xy 427.477785 -20.029169) (xy 427.442176 -19.983865) (xy 427.413772 -19.933726)
			(xy 427.403006 -19.906996) (xy 427.398056 -19.895802) (xy 427.379868 -19.879478) (xy 427.368208 -19.875754)
			(xy 427.330607 -19.865539) (xy 427.257545 -19.838454) (xy 427.187624 -19.804062) (xy 427.15434 -19.783806)
			(xy 427.146079 -19.77911) (xy 427.127416 -19.775602) (xy 427.108753 -19.77911) (xy 427.100492 -19.783806)
			(xy 427.067206 -19.804059) (xy 426.99728 -19.838437) (xy 426.924221 -19.865526) (xy 426.886624 -19.875754)
			(xy 426.874989 -19.879518) (xy 426.85682 -19.895833) (xy 426.851826 -19.906996) (xy 426.841077 -19.933738)
			(xy 426.812691 -19.983897) (xy 426.77709 -20.029221) (xy 426.735082 -20.06868) (xy 426.687622 -20.101378)
			(xy 426.635786 -20.126573) (xy 426.580753 -20.143692) (xy 426.523773 -20.152346) (xy 426.494956 -20.152868)
			(xy 426.467686 -20.152416) (xy 426.413701 -20.144649) (xy 426.361371 -20.129278) (xy 426.311762 -20.106617)
			(xy 426.265881 -20.077128) (xy 426.224664 -20.041409) (xy 426.18895 -20.000188) (xy 426.159464 -19.954305)
			(xy 426.136808 -19.904693) (xy 426.121443 -19.852362) (xy 426.113681 -19.798376) (xy 426.113194 -19.771106)
			(xy 426.113194 -19.770598) (xy 426.113555 -19.74698) (xy 426.119419 -19.700108) (xy 426.124878 -19.677126)
			(xy 426.127193 -19.665154) (xy 426.121771 -19.64142) (xy 426.114464 -19.63166) (xy 426.092004 -19.604755)
			(xy 426.051554 -19.547514) (xy 426.033692 -19.51736) (xy 426.009816 -19.518122) (xy 425.982541 -19.51774)
			(xy 425.928547 -19.509978) (xy 425.876207 -19.494612) (xy 425.826587 -19.471953) (xy 425.780696 -19.442463)
			(xy 425.73947 -19.406741) (xy 425.703747 -19.365517) (xy 425.674255 -19.319627) (xy 425.651594 -19.270008)
			(xy 425.636225 -19.217669) (xy 425.628462 -19.163675) (xy 423.00332 -19.163675) (xy 423.00332 -19.164374)
			(xy 422.995557 -19.218367) (xy 422.980188 -19.270706) (xy 422.957526 -19.320324) (xy 422.928034 -19.366212)
			(xy 422.89231 -19.407436) (xy 422.851084 -19.443155) (xy 422.805193 -19.472644) (xy 422.755572 -19.4953)
			(xy 422.703232 -19.510664) (xy 422.649238 -19.518423) (xy 422.621964 -19.518884) (xy 422.598088 -19.518122)
			(xy 422.584167 -19.5418) (xy 422.553405 -19.587312) (xy 422.53662 -19.609054) (xy 422.52942 -19.619302)
			(xy 422.525034 -19.643935) (xy 422.528238 -19.656044) (xy 422.536682 -19.684251) (xy 422.545733 -19.742429)
			(xy 422.546272 -19.771868) (xy 422.545769 -19.799138) (xy 422.538011 -19.853123) (xy 422.52265 -19.905454)
			(xy 422.499996 -19.955066) (xy 422.470513 -20.00095) (xy 422.4348 -20.04217) (xy 422.393583 -20.077888)
			(xy 422.347703 -20.107376) (xy 422.298093 -20.130035) (xy 422.245764 -20.145402) (xy 422.19178 -20.153166)
			(xy 422.16451 -20.15363) (xy 422.136121 -20.15315) (xy 422.079966 -20.144755) (xy 422.025675 -20.128133)
			(xy 421.974446 -20.103651) (xy 421.927409 -20.071851) (xy 421.885602 -20.033432) (xy 421.849948 -19.989244)
			(xy 421.821234 -19.940262) (xy 421.81018 -19.914108) (xy 421.804901 -19.902842) (xy 421.785871 -19.886862)
			(xy 421.773858 -19.883628) (xy 421.731111 -19.873685) (xy 421.648062 -19.845299) (xy 421.568814 -19.807579)
			(xy 421.531288 -19.784822) (xy 421.523064 -19.780057) (xy 421.504408 -19.776472) (xy 421.485724 -19.779905)
			(xy 421.47744 -19.784568) (xy 421.444309 -19.804739) (xy 421.374713 -19.839001) (xy 421.302005 -19.866036)
			(xy 421.264588 -19.876262) (xy 421.253014 -19.88006) (xy 421.234968 -19.896364) (xy 421.230044 -19.907504)
			(xy 421.219288 -19.93427) (xy 421.190896 -19.984482) (xy 421.155278 -20.029855) (xy 421.113243 -20.069358)
			(xy 421.065748 -20.102092) (xy 421.013871 -20.127314) (xy 420.958791 -20.144449) (xy 420.901762 -20.153109)
			(xy 420.87292 -20.15363) (xy 420.845648 -20.15318) (xy 420.791659 -20.14542) (xy 420.739324 -20.130054)
			(xy 420.689709 -20.107397) (xy 420.643824 -20.077908) (xy 420.602602 -20.042189) (xy 420.566885 -20.000967)
			(xy 420.537398 -19.955081) (xy 420.514742 -19.905465) (xy 420.499378 -19.853129) (xy 420.491619 -19.79914)
			(xy 420.491158 -19.771868) (xy 420.491158 -19.77136) (xy 420.491513 -19.747941) (xy 420.497245 -19.701454)
			(xy 420.502588 -19.67865) (xy 420.504845 -19.666649) (xy 420.499298 -19.642911) (xy 420.49192 -19.633184)
			(xy 420.469313 -19.606102) (xy 420.428606 -19.548482) (xy 420.41064 -19.518122) (xy 420.386764 -19.518884)
			(xy 420.359498 -19.518351) (xy 420.305521 -19.510586) (xy 420.253199 -19.495218) (xy 420.203596 -19.472561)
			(xy 420.157723 -19.443076) (xy 420.116512 -19.407363) (xy 420.080802 -19.366149) (xy 420.051321 -19.320272)
			(xy 420.028669 -19.270667) (xy 420.013307 -19.218343) (xy 420.005546 -19.164366) (xy 417.416159 -19.164366)
			(xy 417.408497 -19.217652) (xy 417.393131 -19.269981) (xy 417.370474 -19.31959) (xy 417.340988 -19.36547)
			(xy 417.305272 -19.406686) (xy 417.264054 -19.4424) (xy 417.218173 -19.471884) (xy 417.168562 -19.494538)
			(xy 417.116232 -19.509901) (xy 417.062249 -19.51766) (xy 417.03498 -19.518122) (xy 417.011104 -19.51736)
			(xy 416.993243 -19.547515) (xy 416.952794 -19.604757) (xy 416.930332 -19.63166) (xy 416.922973 -19.641397)
			(xy 416.91754 -19.665154) (xy 416.919918 -19.677126) (xy 416.925366 -19.70011) (xy 416.93123 -19.74698)
			(xy 416.931602 -19.770598) (xy 416.931602 -19.771106) (xy 416.931081 -19.798374) (xy 416.92332 -19.852354)
			(xy 416.907956 -19.90468) (xy 416.885302 -19.954288) (xy 416.855819 -20.000167) (xy 416.820107 -20.041383)
			(xy 416.778894 -20.077099) (xy 416.733018 -20.106585) (xy 416.683412 -20.129244) (xy 416.631087 -20.144613)
			(xy 416.577108 -20.152379) (xy 416.54984 -20.152868) (xy 416.521027 -20.152325) (xy 416.464057 -20.143649)
			(xy 416.409035 -20.126518) (xy 416.35721 -20.101319) (xy 416.309755 -20.068626) (xy 416.267747 -20.029177)
			(xy 416.232138 -19.983869) (xy 416.203735 -19.933728) (xy 416.19297 -19.906996) (xy 416.187987 -19.89582)
			(xy 416.169822 -19.879489) (xy 416.158172 -19.875754) (xy 416.120575 -19.865525) (xy 416.047512 -19.838446)
			(xy 415.97759 -19.804059) (xy 415.944304 -19.783806) (xy 415.936043 -19.77911) (xy 415.91738 -19.775602)
			(xy 415.898717 -19.77911) (xy 415.890456 -19.783806) (xy 415.857163 -19.804046) (xy 415.78724 -19.838429)
			(xy 415.714183 -19.865523) (xy 415.676588 -19.875754) (xy 415.664946 -19.879502) (xy 415.646781 -19.895829)
			(xy 415.64179 -19.906996) (xy 415.631071 -19.933751) (xy 415.602681 -19.983911) (xy 415.567076 -20.029236)
			(xy 415.525064 -20.068694) (xy 415.477599 -20.101391) (xy 415.42576 -20.126583) (xy 415.370723 -20.143699)
			(xy 415.313739 -20.152349) (xy 415.28492 -20.152868) (xy 415.25765 -20.15238) (xy 415.203664 -20.144621)
			(xy 415.151332 -20.129257) (xy 415.10172 -20.106602) (xy 415.055836 -20.077117) (xy 415.014616 -20.041403)
			(xy 414.978898 -20.000185) (xy 414.94941 -19.954303) (xy 414.926752 -19.904692) (xy 414.911385 -19.852361)
			(xy 414.903622 -19.798376) (xy 414.903158 -19.771106) (xy 414.903158 -19.770598) (xy 414.903517 -19.74698)
			(xy 414.909383 -19.700108) (xy 414.914842 -19.677126) (xy 414.917143 -19.665153) (xy 414.911728 -19.641422)
			(xy 414.904428 -19.63166) (xy 414.881971 -19.604752) (xy 414.841519 -19.547513) (xy 414.823656 -19.51736)
			(xy 414.79978 -19.518122) (xy 414.772509 -19.517714) (xy 414.718522 -19.509949) (xy 414.666189 -19.494581)
			(xy 414.616576 -19.471921) (xy 414.570693 -19.442431) (xy 414.529473 -19.406712) (xy 414.493757 -19.365491)
			(xy 414.464269 -19.319606) (xy 414.441612 -19.269992) (xy 414.426246 -19.217659) (xy 414.418484 -19.163671)
			(xy 411.522458 -19.163671) (xy 411.514696 -19.217654) (xy 411.49933 -19.269984) (xy 411.476672 -19.319595)
			(xy 411.447184 -19.365475) (xy 411.411466 -19.406692) (xy 411.370246 -19.442406) (xy 411.324363 -19.471889)
			(xy 411.27475 -19.494542) (xy 411.222419 -19.509904) (xy 411.168434 -19.517661) (xy 411.141164 -19.518122)
			(xy 411.117288 -19.51736) (xy 411.099429 -19.547516) (xy 411.058979 -19.604757) (xy 411.036516 -19.63166)
			(xy 411.029156 -19.641396) (xy 411.023724 -19.665154) (xy 411.026102 -19.677126) (xy 411.03155 -19.70011)
			(xy 411.037414 -19.74698) (xy 411.037786 -19.770598) (xy 411.037786 -19.771106) (xy 411.037281 -19.798374)
			(xy 411.029519 -19.852356) (xy 411.014154 -19.904684) (xy 410.991499 -19.954292) (xy 410.962015 -20.000172)
			(xy 410.926302 -20.041389) (xy 410.885087 -20.077104) (xy 410.839208 -20.106591) (xy 410.789601 -20.129248)
			(xy 410.737274 -20.144616) (xy 410.683292 -20.15238) (xy 410.656024 -20.152868) (xy 410.62721 -20.152339)
			(xy 410.57024 -20.143661) (xy 410.515218 -20.126527) (xy 410.463392 -20.101327) (xy 410.415938 -20.068631)
			(xy 410.37393 -20.029181) (xy 410.338321 -19.983871) (xy 410.309919 -19.933728) (xy 410.299154 -19.906996)
			(xy 410.294179 -19.895815) (xy 410.276009 -19.879486) (xy 410.264356 -19.875754) (xy 410.226758 -19.865528)
			(xy 410.153695 -19.838448) (xy 410.083773 -19.80406) (xy 410.050488 -19.783806) (xy 410.042227 -19.77911)
			(xy 410.023564 -19.775602) (xy 410.004901 -19.77911) (xy 409.99664 -19.783806) (xy 409.963349 -19.804049)
			(xy 409.893425 -19.838431) (xy 409.820368 -19.865524) (xy 409.782772 -19.875754) (xy 409.771128 -19.879495)
			(xy 409.752964 -19.895827) (xy 409.747974 -19.906996) (xy 409.737268 -19.933757) (xy 409.708877 -19.983918)
			(xy 409.67327 -20.029242) (xy 409.631256 -20.068701) (xy 409.583789 -20.101397) (xy 409.531948 -20.126588)
			(xy 409.476909 -20.143702) (xy 409.419923 -20.15235) (xy 409.391104 -20.152868) (xy 409.363835 -20.152372)
			(xy 409.309852 -20.144611) (xy 409.257523 -20.129246) (xy 409.207913 -20.106591) (xy 409.162033 -20.077106)
			(xy 409.120815 -20.041392) (xy 409.0851 -20.000175) (xy 409.055614 -19.954295) (xy 409.032957 -19.904686)
			(xy 409.017591 -19.852358) (xy 409.009829 -19.798375) (xy 409.009342 -19.771106) (xy 409.009342 -19.770598)
			(xy 409.009702 -19.74698) (xy 409.015567 -19.700108) (xy 409.021026 -19.677126) (xy 409.023331 -19.665153)
			(xy 409.017914 -19.641422) (xy 409.010612 -19.63166) (xy 408.988154 -19.604753) (xy 408.947703 -19.547514)
			(xy 408.92984 -19.51736) (xy 408.905964 -19.518122) (xy 408.878693 -19.517713) (xy 408.824708 -19.509946)
			(xy 408.772377 -19.494576) (xy 408.722767 -19.471916) (xy 408.676885 -19.442426) (xy 408.635668 -19.406707)
			(xy 408.599953 -19.365486) (xy 408.570467 -19.319602) (xy 408.547811 -19.269989) (xy 408.532446 -19.217657)
			(xy 408.524684 -19.163671) (xy 405.934458 -19.163671) (xy 405.926696 -19.217654) (xy 405.91133 -19.269984)
			(xy 405.888672 -19.319595) (xy 405.859184 -19.365475) (xy 405.823466 -19.406692) (xy 405.782246 -19.442406)
			(xy 405.736363 -19.471889) (xy 405.68675 -19.494542) (xy 405.634419 -19.509904) (xy 405.580434 -19.517661)
			(xy 405.553164 -19.518122) (xy 405.529288 -19.51736) (xy 405.511429 -19.547516) (xy 405.470979 -19.604757)
			(xy 405.448516 -19.63166) (xy 405.441156 -19.641396) (xy 405.435724 -19.665154) (xy 405.438102 -19.677126)
			(xy 405.44355 -19.70011) (xy 405.449414 -19.74698) (xy 405.449786 -19.770598) (xy 405.449786 -19.771106)
			(xy 405.449281 -19.798374) (xy 405.441519 -19.852356) (xy 405.426154 -19.904684) (xy 405.403499 -19.954292)
			(xy 405.374015 -20.000172) (xy 405.338302 -20.041389) (xy 405.297087 -20.077104) (xy 405.251208 -20.106591)
			(xy 405.201601 -20.129248) (xy 405.149274 -20.144616) (xy 405.095292 -20.15238) (xy 405.068024 -20.152868)
			(xy 405.03921 -20.152339) (xy 404.98224 -20.143661) (xy 404.927218 -20.126527) (xy 404.875392 -20.101327)
			(xy 404.827938 -20.068631) (xy 404.78593 -20.029181) (xy 404.750321 -19.983871) (xy 404.721919 -19.933728)
			(xy 404.711154 -19.906996) (xy 404.706179 -19.895815) (xy 404.688009 -19.879486) (xy 404.676356 -19.875754)
			(xy 404.638758 -19.865528) (xy 404.565695 -19.838448) (xy 404.495773 -19.80406) (xy 404.462488 -19.783806)
			(xy 404.454227 -19.77911) (xy 404.435564 -19.775602) (xy 404.416901 -19.77911) (xy 404.40864 -19.783806)
			(xy 404.375349 -19.804049) (xy 404.305425 -19.838431) (xy 404.232368 -19.865524) (xy 404.194772 -19.875754)
			(xy 404.183128 -19.879495) (xy 404.164964 -19.895827) (xy 404.159974 -19.906996) (xy 404.149268 -19.933757)
			(xy 404.120877 -19.983918) (xy 404.08527 -20.029242) (xy 404.043256 -20.068701) (xy 403.995789 -20.101397)
			(xy 403.943948 -20.126588) (xy 403.888909 -20.143702) (xy 403.831923 -20.15235) (xy 403.803104 -20.152868)
			(xy 403.775835 -20.152372) (xy 403.721852 -20.144611) (xy 403.669523 -20.129246) (xy 403.619913 -20.106591)
			(xy 403.574033 -20.077106) (xy 403.532815 -20.041392) (xy 403.4971 -20.000175) (xy 403.467614 -19.954295)
			(xy 403.444957 -19.904686) (xy 403.429591 -19.852358) (xy 403.421829 -19.798375) (xy 403.421342 -19.771106)
			(xy 403.421342 -19.770598) (xy 403.421702 -19.74698) (xy 403.427567 -19.700108) (xy 403.433026 -19.677126)
			(xy 403.435331 -19.665153) (xy 403.429914 -19.641422) (xy 403.422612 -19.63166) (xy 403.400154 -19.604753)
			(xy 403.359703 -19.547514) (xy 403.34184 -19.51736) (xy 403.317964 -19.518122) (xy 403.290693 -19.517713)
			(xy 403.236708 -19.509946) (xy 403.184377 -19.494576) (xy 403.134767 -19.471916) (xy 403.088885 -19.442426)
			(xy 403.047668 -19.406707) (xy 403.011953 -19.365486) (xy 402.982467 -19.319602) (xy 402.959811 -19.269989)
			(xy 402.944446 -19.217657) (xy 402.936684 -19.163671) (xy 400.346458 -19.163671) (xy 400.338696 -19.217654)
			(xy 400.32333 -19.269984) (xy 400.300672 -19.319595) (xy 400.271184 -19.365475) (xy 400.235466 -19.406692)
			(xy 400.194246 -19.442406) (xy 400.148363 -19.471889) (xy 400.09875 -19.494542) (xy 400.046419 -19.509904)
			(xy 399.992434 -19.517661) (xy 399.965164 -19.518122) (xy 399.941288 -19.51736) (xy 399.923429 -19.547516)
			(xy 399.882979 -19.604757) (xy 399.860516 -19.63166) (xy 399.853156 -19.641396) (xy 399.847724 -19.665154)
			(xy 399.850102 -19.677126) (xy 399.85555 -19.70011) (xy 399.861414 -19.74698) (xy 399.861786 -19.770598)
			(xy 399.861786 -19.771106) (xy 399.861281 -19.798374) (xy 399.853519 -19.852356) (xy 399.838154 -19.904684)
			(xy 399.815499 -19.954292) (xy 399.786015 -20.000172) (xy 399.750302 -20.041389) (xy 399.709087 -20.077104)
			(xy 399.663208 -20.106591) (xy 399.613601 -20.129248) (xy 399.561274 -20.144616) (xy 399.507292 -20.15238)
			(xy 399.480024 -20.152868) (xy 399.45121 -20.152339) (xy 399.39424 -20.143661) (xy 399.339218 -20.126527)
			(xy 399.287392 -20.101327) (xy 399.239938 -20.068631) (xy 399.19793 -20.029181) (xy 399.162321 -19.983871)
			(xy 399.133919 -19.933728) (xy 399.123154 -19.906996) (xy 399.118179 -19.895815) (xy 399.100009 -19.879486)
			(xy 399.088356 -19.875754) (xy 399.050758 -19.865528) (xy 398.977695 -19.838448) (xy 398.907773 -19.80406)
			(xy 398.874488 -19.783806) (xy 398.866227 -19.77911) (xy 398.847564 -19.775602) (xy 398.828901 -19.77911)
			(xy 398.82064 -19.783806) (xy 398.787349 -19.804049) (xy 398.717425 -19.838431) (xy 398.644368 -19.865524)
			(xy 398.606772 -19.875754) (xy 398.595128 -19.879495) (xy 398.576964 -19.895827) (xy 398.571974 -19.906996)
			(xy 398.561268 -19.933757) (xy 398.532877 -19.983918) (xy 398.49727 -20.029242) (xy 398.455256 -20.068701)
			(xy 398.407789 -20.101397) (xy 398.355948 -20.126588) (xy 398.300909 -20.143702) (xy 398.243923 -20.15235)
			(xy 398.215104 -20.152868) (xy 398.187835 -20.152372) (xy 398.133852 -20.144611) (xy 398.081523 -20.129246)
			(xy 398.031913 -20.106591) (xy 397.986033 -20.077106) (xy 397.944815 -20.041392) (xy 397.9091 -20.000175)
			(xy 397.879614 -19.954295) (xy 397.856957 -19.904686) (xy 397.841591 -19.852358) (xy 397.833829 -19.798375)
			(xy 397.833342 -19.771106) (xy 397.833342 -19.770598) (xy 397.833702 -19.74698) (xy 397.839567 -19.700108)
			(xy 397.845026 -19.677126) (xy 397.847331 -19.665153) (xy 397.841914 -19.641422) (xy 397.834612 -19.63166)
			(xy 397.812154 -19.604753) (xy 397.771703 -19.547514) (xy 397.75384 -19.51736) (xy 397.729964 -19.518122)
			(xy 397.702693 -19.517713) (xy 397.648708 -19.509946) (xy 397.596377 -19.494576) (xy 397.546767 -19.471916)
			(xy 397.500885 -19.442426) (xy 397.459668 -19.406707) (xy 397.423953 -19.365486) (xy 397.394467 -19.319602)
			(xy 397.371811 -19.269989) (xy 397.356446 -19.217657) (xy 397.348684 -19.163671) (xy 394.757398 -19.163671)
			(xy 394.757398 -19.164369) (xy 394.749637 -19.218351) (xy 394.734273 -19.27068) (xy 394.711619 -19.32029)
			(xy 394.682136 -19.366171) (xy 394.646424 -19.40739) (xy 394.60521 -19.443107) (xy 394.559332 -19.472596)
			(xy 394.509725 -19.495256) (xy 394.457398 -19.510627) (xy 394.403417 -19.518394) (xy 394.376148 -19.518884)
			(xy 394.352272 -19.518122) (xy 394.334569 -19.548121) (xy 394.294501 -19.605105) (xy 394.272262 -19.631914)
			(xy 394.264926 -19.641664) (xy 394.259483 -19.66541) (xy 394.261848 -19.67738) (xy 394.26742 -19.700604)
			(xy 394.273403 -19.747988) (xy 394.273786 -19.771868) (xy 394.273269 -19.799137) (xy 394.265512 -19.853121)
			(xy 394.250151 -19.905451) (xy 394.227499 -19.955062) (xy 394.198017 -20.000945) (xy 394.162305 -20.042165)
			(xy 394.12109 -20.077883) (xy 394.075212 -20.107372) (xy 394.025604 -20.130031) (xy 393.973276 -20.1454)
			(xy 393.919293 -20.153165) (xy 393.892024 -20.15363) (xy 393.863234 -20.153086) (xy 393.806309 -20.144429)
			(xy 393.751329 -20.127322) (xy 393.699541 -20.102153) (xy 393.652119 -20.069494) (xy 393.61014 -20.030084)
			(xy 393.574553 -19.984818) (xy 393.546168 -19.934721) (xy 393.535408 -19.908012) (xy 393.530375 -19.896804)
			(xy 393.512069 -19.880477) (xy 393.500356 -19.87677) (xy 393.462578 -19.866544) (xy 393.389161 -19.839415)
			(xy 393.31891 -19.804907) (xy 393.285472 -19.784568) (xy 393.277211 -19.779872) (xy 393.258548 -19.776364)
			(xy 393.239885 -19.779872) (xy 393.231624 -19.784568) (xy 393.198483 -19.804722) (xy 393.128892 -19.83899)
			(xy 393.056187 -19.866032) (xy 393.018772 -19.876262) (xy 393.007195 -19.880053) (xy 392.989151 -19.896362)
			(xy 392.984228 -19.907504) (xy 392.973485 -19.934276) (xy 392.945092 -19.984489) (xy 392.909472 -20.029862)
			(xy 392.867435 -20.069364) (xy 392.819938 -20.102098) (xy 392.768059 -20.127318) (xy 392.712977 -20.144452)
			(xy 392.655946 -20.153111) (xy 392.627104 -20.15363) (xy 392.599832 -20.153195) (xy 392.545842 -20.145432)
			(xy 392.493507 -20.130065) (xy 392.443892 -20.107405) (xy 392.398006 -20.077915) (xy 392.356785 -20.042195)
			(xy 392.321068 -20.000971) (xy 392.291581 -19.955084) (xy 392.268925 -19.905467) (xy 392.253562 -19.853131)
			(xy 392.245803 -19.79914) (xy 392.245342 -19.771868) (xy 392.245342 -19.77136) (xy 392.245697 -19.747941)
			(xy 392.25143 -19.701454) (xy 392.256772 -19.67865) (xy 392.259032 -19.666649) (xy 392.253483 -19.642911)
			(xy 392.246104 -19.633184) (xy 392.223496 -19.606103) (xy 392.18279 -19.548482) (xy 392.164824 -19.518122)
			(xy 392.140948 -19.518884) (xy 392.113676 -19.51838) (xy 392.059687 -19.510624) (xy 392.007352 -19.495262)
			(xy 391.957736 -19.472609) (xy 391.911849 -19.443124) (xy 391.870625 -19.407409) (xy 391.834904 -19.36619)
			(xy 391.805414 -19.320307) (xy 391.782754 -19.270693) (xy 391.767387 -19.21836) (xy 391.759624 -19.164372)
			(xy 260.324092 -19.164372) (xy 260.324092 -20.40763) (xy 368.365788 -20.40763) (xy 368.369831 -20.311179)
			(xy 368.38193 -20.215404) (xy 368.402001 -20.120978) (xy 368.429903 -20.028562) (xy 368.46544 -19.938805)
			(xy 368.508363 -19.852337) (xy 368.558371 -19.769763) (xy 368.615114 -19.691664) (xy 368.678192 -19.618587)
			(xy 368.747165 -19.551044) (xy 368.821547 -19.48951) (xy 368.900817 -19.434415) (xy 368.98442 -19.386147)
			(xy 369.071768 -19.345044) (xy 369.16225 -19.311395) (xy 369.255229 -19.285434) (xy 369.350055 -19.267345)
			(xy 369.446063 -19.257254) (xy 369.542577 -19.255233) (xy 369.638923 -19.261294) (xy 369.734423 -19.275397)
			(xy 369.828408 -19.297441) (xy 369.92022 -19.327272) (xy 370.009213 -19.364681) (xy 370.094763 -19.409406)
			(xy 370.176271 -19.461132) (xy 370.253165 -19.519498) (xy 370.324905 -19.584093) (xy 370.390988 -19.654465)
			(xy 370.450951 -19.730119) (xy 370.504374 -19.810526) (xy 370.55088 -19.895121) (xy 370.590145 -19.983311)
			(xy 370.621892 -20.074477) (xy 370.6459 -20.167981) (xy 370.661999 -20.263165) (xy 370.670077 -20.359362)
			(xy 370.670582 -20.40763) (xy 370.670077 -20.455898) (xy 370.661999 -20.552095) (xy 370.6459 -20.647279)
			(xy 370.622976 -20.73656) (xy 440.464956 -20.73656) (xy 440.465378 -20.698271) (xy 440.471981 -20.621977)
			(xy 440.485126 -20.546534) (xy 440.504715 -20.472503) (xy 440.51728 -20.436332) (xy 440.51995 -20.4279)
			(xy 440.519937 -20.410225) (xy 440.51728 -20.401788) (xy 440.50475 -20.365606) (xy 440.485173 -20.291575)
			(xy 440.472022 -20.216136) (xy 440.465394 -20.139848) (xy 440.464956 -20.10156) (xy 440.46549 -20.057765)
			(xy 440.474106 -19.9706) (xy 440.49125 -19.884704) (xy 440.516756 -19.80091) (xy 440.550377 -19.72003)
			(xy 440.57062 -19.68119) (xy 440.576064 -19.669733) (xy 440.576046 -19.644397) (xy 440.57062 -19.63293)
			(xy 440.550398 -19.594081) (xy 440.51679 -19.513198) (xy 440.491286 -19.429406) (xy 440.474133 -19.343514)
			(xy 440.465497 -19.256354) (xy 440.464956 -19.21256) (xy 440.465378 -19.174271) (xy 440.471981 -19.097977)
			(xy 440.485126 -19.022534) (xy 440.504715 -18.948503) (xy 440.51728 -18.912332) (xy 440.51995 -18.9039)
			(xy 440.519937 -18.886225) (xy 440.51728 -18.877788) (xy 440.50475 -18.841606) (xy 440.485173 -18.767575)
			(xy 440.472022 -18.692136) (xy 440.465394 -18.615848) (xy 440.464956 -18.57756) (xy 440.465414 -18.53645)
			(xy 440.473005 -18.45458) (xy 440.488119 -18.373761) (xy 440.510626 -18.294681) (xy 440.540334 -18.218015)
			(xy 440.576991 -18.144418) (xy 440.620282 -18.074518) (xy 440.66984 -18.008911) (xy 440.72524 -17.948157)
			(xy 440.78601 -17.892775) (xy 440.851631 -17.843237) (xy 440.921544 -17.799965) (xy 440.995152 -17.76333)
			(xy 441.071826 -17.733644) (xy 441.150912 -17.71116) (xy 441.231736 -17.69607) (xy 441.313608 -17.688502)
			(xy 441.354718 -17.688052) (xy 441.395668 -17.688478) (xy 441.477223 -17.695989) (xy 441.557742 -17.710965)
			(xy 441.636544 -17.733279) (xy 441.712961 -17.762742) (xy 441.786347 -17.799105) (xy 441.856079 -17.842059)
			(xy 441.921567 -17.891241) (xy 441.982258 -17.946234) (xy 442.010292 -17.976088) (xy 442.017449 -17.983101)
			(xy 442.035585 -17.991562) (xy 442.055576 -17.99248) (xy 442.065156 -17.98955) (xy 442.102033 -17.976445)
			(xy 442.177582 -17.955997) (xy 442.254637 -17.94227) (xy 442.3326 -17.935373) (xy 442.371734 -17.93494)
			(xy 442.412849 -17.93538) (xy 442.494727 -17.942971) (xy 442.575557 -17.958083) (xy 442.654646 -17.980589)
			(xy 442.731323 -18.010296) (xy 442.804931 -18.046951) (xy 442.874843 -18.090241) (xy 442.940462 -18.139797)
			(xy 443.001229 -18.195196) (xy 443.056626 -18.255966) (xy 443.106179 -18.321587) (xy 443.149467 -18.391501)
			(xy 443.186119 -18.46511) (xy 443.213248 -18.535142) (xy 451.165468 -18.535142) (xy 451.165468 -18.534888)
			(xy 451.166052 -18.49015) (xy 451.175063 -18.401129) (xy 451.192964 -18.313462) (xy 451.219572 -18.228034)
			(xy 451.236588 -18.186654) (xy 451.240131 -18.177057) (xy 451.240147 -18.15662) (xy 451.236588 -18.14703)
			(xy 451.219555 -18.105656) (xy 451.192939 -18.020228) (xy 451.175038 -17.932559) (xy 451.166032 -17.843535)
			(xy 451.165468 -17.798796) (xy 451.165468 -17.798542) (xy 451.165972 -17.756194) (xy 451.174023 -17.67188)
			(xy 451.190052 -17.588714) (xy 451.213913 -17.507447) (xy 451.245392 -17.428817) (xy 451.284203 -17.353536)
			(xy 451.329993 -17.282284) (xy 451.382349 -17.215708) (xy 451.440797 -17.15441) (xy 451.504807 -17.098945)
			(xy 451.573799 -17.049816) (xy 451.647149 -17.007467) (xy 451.724192 -16.972283) (xy 451.804231 -16.944581)
			(xy 451.88654 -16.924613) (xy 451.970375 -16.91256) (xy 452.054976 -16.90853) (xy 452.139577 -16.91256)
			(xy 452.223412 -16.924613) (xy 452.305721 -16.944581) (xy 452.38576 -16.972283) (xy 452.462803 -17.007467)
			(xy 452.536153 -17.049816) (xy 452.605145 -17.098945) (xy 452.669155 -17.15441) (xy 452.727603 -17.215708)
			(xy 452.779959 -17.282284) (xy 452.825749 -17.353536) (xy 452.86456 -17.428817) (xy 452.896039 -17.507447)
			(xy 452.9199 -17.588714) (xy 452.935929 -17.67188) (xy 452.94398 -17.756194) (xy 452.944484 -17.798542)
			(xy 452.944484 -17.798796) (xy 452.943898 -17.843534) (xy 452.934888 -17.932555) (xy 452.916988 -18.020222)
			(xy 452.890379 -18.10565) (xy 452.873364 -18.14703) (xy 452.869775 -18.156614) (xy 452.869791 -18.177063)
			(xy 452.873364 -18.186654) (xy 452.890389 -18.228031) (xy 452.917007 -18.313458) (xy 452.934911 -18.401126)
			(xy 452.943919 -18.490149) (xy 452.944484 -18.534888) (xy 452.944484 -18.535142) (xy 452.94398 -18.57749)
			(xy 452.935929 -18.661804) (xy 452.9199 -18.74497) (xy 452.896039 -18.826237) (xy 452.86456 -18.904867)
			(xy 452.825749 -18.980148) (xy 452.779959 -19.0514) (xy 452.727603 -19.117976) (xy 452.669155 -19.179274)
			(xy 452.605145 -19.234739) (xy 452.536153 -19.283868) (xy 452.462803 -19.326217) (xy 452.38576 -19.361401)
			(xy 452.305721 -19.389103) (xy 452.223412 -19.409071) (xy 452.139577 -19.421124) (xy 452.054976 -19.425155)
			(xy 451.970375 -19.421124) (xy 451.88654 -19.409071) (xy 451.804231 -19.389103) (xy 451.724192 -19.361401)
			(xy 451.647149 -19.326217) (xy 451.573799 -19.283868) (xy 451.504807 -19.234739) (xy 451.440797 -19.179274)
			(xy 451.382349 -19.117976) (xy 451.329993 -19.0514) (xy 451.284203 -18.980148) (xy 451.245392 -18.904867)
			(xy 451.213913 -18.826237) (xy 451.190052 -18.74497) (xy 451.174023 -18.661804) (xy 451.165972 -18.57749)
			(xy 451.165468 -18.535142) (xy 443.213248 -18.535142) (xy 443.215823 -18.541788) (xy 443.238325 -18.620878)
			(xy 443.253434 -18.701708) (xy 443.261021 -18.783587) (xy 443.261496 -18.824702) (xy 443.261095 -18.862992)
			(xy 443.254486 -18.939286) (xy 443.241336 -19.014729) (xy 443.221741 -19.088759) (xy 443.209172 -19.12493)
			(xy 443.206519 -19.133366) (xy 443.20652 -19.151037) (xy 443.209172 -19.159474) (xy 443.221718 -19.195651)
			(xy 443.24129 -19.269684) (xy 443.254437 -19.345124) (xy 443.261061 -19.421414) (xy 443.261496 -19.459702)
			(xy 443.260982 -19.503497) (xy 443.252361 -19.590663) (xy 443.235212 -19.676559) (xy 443.209701 -19.760353)
			(xy 443.176076 -19.841233) (xy 443.155832 -19.880072) (xy 443.15041 -19.891537) (xy 443.150411 -19.916866)
			(xy 443.155832 -19.928332) (xy 443.176073 -19.967172) (xy 443.209679 -20.048057) (xy 443.235179 -20.131851)
			(xy 443.252328 -20.217745) (xy 443.260958 -20.304908) (xy 443.261496 -20.348702) (xy 443.261095 -20.386992)
			(xy 443.254486 -20.463286) (xy 443.241336 -20.538729) (xy 443.221741 -20.612759) (xy 443.209172 -20.64893)
			(xy 443.206519 -20.657366) (xy 443.20652 -20.675037) (xy 443.209172 -20.683474) (xy 443.221718 -20.719651)
			(xy 443.24129 -20.793684) (xy 443.254437 -20.869124) (xy 443.261061 -20.945414) (xy 443.261496 -20.983702)
			(xy 443.260989 -21.024815) (xy 443.253402 -21.106691) (xy 443.238293 -21.187518) (xy 443.215791 -21.266605)
			(xy 443.186088 -21.343279) (xy 443.149437 -21.416886) (xy 443.106152 -21.486797) (xy 443.0566 -21.552416)
			(xy 443.001205 -21.613183) (xy 442.94044 -21.66858) (xy 442.874823 -21.718133) (xy 442.804914 -21.761422)
			(xy 442.731309 -21.798075) (xy 442.654636 -21.827781) (xy 442.575549 -21.850286) (xy 442.494723 -21.865398)
			(xy 442.412847 -21.872988) (xy 442.371734 -21.873464) (xy 442.330778 -21.872996) (xy 442.249213 -21.865468)
			(xy 442.168686 -21.850472) (xy 442.089879 -21.828136) (xy 442.013459 -21.798648) (xy 441.940074 -21.762259)
			(xy 441.870346 -21.719277) (xy 441.804865 -21.670066) (xy 441.744186 -21.615042) (xy 441.71616 -21.585174)
			(xy 441.709037 -21.578124) (xy 441.690882 -21.569676) (xy 441.670879 -21.568774) (xy 441.661296 -21.571712)
			(xy 441.624502 -21.584749) (xy 441.549137 -21.605106) (xy 441.472276 -21.618771) (xy 441.394513 -21.625637)
			(xy 441.35548 -21.626068) (xy 441.354718 -21.626068) (xy 441.313612 -21.62557) (xy 441.23175 -21.617988)
			(xy 441.150936 -21.602885) (xy 441.07186 -21.580392) (xy 440.995197 -21.5507) (xy 440.9216 -21.514062)
			(xy 440.851696 -21.470791) (xy 440.786082 -21.421255) (xy 440.725318 -21.365878) (xy 440.669922 -21.305132)
			(xy 440.620366 -21.239533) (xy 440.577073 -21.169643) (xy 440.540412 -21.096058) (xy 440.510696 -21.019403)
			(xy 440.488178 -20.940335) (xy 440.473051 -20.859526) (xy 440.465443 -20.777666) (xy 440.464956 -20.73656)
			(xy 370.622976 -20.73656) (xy 370.621892 -20.740783) (xy 370.590145 -20.831949) (xy 370.55088 -20.920139)
			(xy 370.504374 -21.004734) (xy 370.450951 -21.085141) (xy 370.390988 -21.160795) (xy 370.324905 -21.231167)
			(xy 370.253165 -21.295762) (xy 370.176271 -21.354128) (xy 370.094763 -21.405854) (xy 370.009213 -21.450579)
			(xy 369.92022 -21.487988) (xy 369.828408 -21.517819) (xy 369.734423 -21.539863) (xy 369.638923 -21.553966)
			(xy 369.542577 -21.560027) (xy 369.446063 -21.558006) (xy 369.350055 -21.547915) (xy 369.255229 -21.529826)
			(xy 369.16225 -21.503865) (xy 369.071768 -21.470216) (xy 368.98442 -21.429113) (xy 368.900817 -21.380845)
			(xy 368.821547 -21.32575) (xy 368.747165 -21.264216) (xy 368.678192 -21.196673) (xy 368.615114 -21.123596)
			(xy 368.558371 -21.045497) (xy 368.508363 -20.962923) (xy 368.46544 -20.876455) (xy 368.429903 -20.786698)
			(xy 368.402001 -20.694282) (xy 368.38193 -20.599856) (xy 368.369831 -20.504081) (xy 368.365788 -20.40763)
			(xy 260.324092 -20.40763) (xy 260.324092 -25.982422) (xy 440.239912 -25.982422) (xy 440.240419 -25.939461)
			(xy 440.248702 -25.85394) (xy 440.265193 -25.769616) (xy 440.289738 -25.687275) (xy 440.322109 -25.607684)
			(xy 440.362003 -25.531586) (xy 440.40905 -25.459689) (xy 440.46281 -25.392664) (xy 440.522782 -25.331135)
			(xy 440.588408 -25.275676) (xy 440.659076 -25.226803) (xy 440.69635 -25.205436) (xy 440.704332 -25.200469)
			(xy 440.716316 -25.186006) (xy 440.719718 -25.177242) (xy 440.733823 -25.137039) (xy 440.768699 -25.059297)
			(xy 440.810847 -24.985247) (xy 440.859883 -24.915565) (xy 440.915357 -24.850891) (xy 440.97676 -24.791817)
			(xy 441.043529 -24.738885) (xy 441.115054 -24.692579) (xy 441.190679 -24.653323) (xy 441.26971 -24.621478)
			(xy 441.351424 -24.597336) (xy 441.435072 -24.581116) (xy 441.519887 -24.572969) (xy 441.56249 -24.572468)
			(xy 441.562998 -24.572468) (xy 441.606762 -24.572982) (xy 441.693869 -24.581557) (xy 441.77971 -24.598653)
			(xy 441.863455 -24.624106) (xy 441.944293 -24.657667) (xy 441.983114 -24.677878) (xy 441.994467 -24.683205)
			(xy 442.019513 -24.683205) (xy 442.030866 -24.677878) (xy 442.069745 -24.657673) (xy 442.150684 -24.6241)
			(xy 442.23453 -24.598641) (xy 442.320472 -24.581544) (xy 442.407677 -24.572973) (xy 442.45149 -24.572468)
			(xy 442.495305 -24.572971) (xy 442.582516 -24.581515) (xy 442.668462 -24.5986) (xy 442.752311 -24.62406)
			(xy 442.833246 -24.657648) (xy 442.872114 -24.677878) (xy 442.883467 -24.683205) (xy 442.908513 -24.683205)
			(xy 442.919866 -24.677878) (xy 442.959061 -24.657499) (xy 443.040701 -24.623735) (xy 443.125286 -24.598229)
			(xy 443.211982 -24.581233) (xy 443.255908 -24.576532) (xy 443.266358 -24.575008) (xy 443.284755 -24.564681)
			(xy 443.297434 -24.547819) (xy 443.300358 -24.53767) (xy 443.310609 -24.496358) (xy 443.337964 -24.415751)
			(xy 443.372893 -24.338124) (xy 443.415077 -24.264189) (xy 443.464129 -24.19462) (xy 443.519603 -24.130055)
			(xy 443.580989 -24.071084) (xy 443.647727 -24.018245) (xy 443.719207 -23.972023) (xy 443.794775 -23.932839)
			(xy 443.87374 -23.901052) (xy 443.955381 -23.876952) (xy 444.038949 -23.86076) (xy 444.123683 -23.852625)
			(xy 444.166244 -23.852124) (xy 444.207348 -23.852525) (xy 444.289205 -23.860114) (xy 444.370013 -23.875224)
			(xy 444.449082 -23.897725) (xy 444.525738 -23.927425) (xy 444.599326 -23.964072) (xy 444.669219 -24.007352)
			(xy 444.734821 -24.056897) (xy 444.795571 -24.112283) (xy 444.850952 -24.173038) (xy 444.900491 -24.238644)
			(xy 444.943765 -24.30854) (xy 444.980405 -24.382132) (xy 445.0101 -24.45879) (xy 445.032594 -24.537861)
			(xy 445.047697 -24.61867) (xy 445.055279 -24.700528) (xy 445.055752 -24.741632) (xy 445.055238 -24.782654)
			(xy 445.04768 -24.864348) (xy 445.032631 -24.944999) (xy 445.01022 -25.023921) (xy 444.980635 -25.100445)
			(xy 444.94413 -25.173919) (xy 444.901014 -25.243719) (xy 444.851653 -25.309252) (xy 444.796467 -25.369961)
			(xy 444.735925 -25.425331) (xy 444.670542 -25.47489) (xy 444.600873 -25.518217) (xy 444.52751 -25.554945)
			(xy 444.451076 -25.584761) (xy 444.372222 -25.607412) (xy 444.291617 -25.622705) (xy 444.250826 -25.627076)
			(xy 444.240379 -25.628618) (xy 444.221981 -25.638935) (xy 444.2093 -25.655791) (xy 444.206376 -25.665938)
			(xy 444.196473 -25.705794) (xy 444.170375 -25.783666) (xy 444.137208 -25.8588) (xy 444.097254 -25.930555)
			(xy 444.050854 -25.998321) (xy 443.998403 -26.061519) (xy 443.940348 -26.119612) (xy 443.877184 -26.172104)
			(xy 443.809448 -26.218548) (xy 443.773814 -26.238962) (xy 443.765845 -26.243946) (xy 443.753852 -26.258396)
			(xy 443.750446 -26.267156) (xy 443.736369 -26.307378) (xy 443.701515 -26.385148) (xy 443.659384 -26.459228)
			(xy 443.61036 -26.528939) (xy 443.554893 -26.593641) (xy 443.493492 -26.652741) (xy 443.42672 -26.705698)
			(xy 443.355189 -26.752025) (xy 443.279554 -26.791298) (xy 443.200511 -26.823158) (xy 443.118782 -26.847311)
			(xy 443.035118 -26.863536) (xy 442.950285 -26.871685) (xy 442.907674 -26.872184) (xy 442.863879 -26.871639)
			(xy 442.776715 -26.863025) (xy 442.690819 -26.845883) (xy 442.607025 -26.82038) (xy 442.526144 -26.786761)
			(xy 442.487304 -26.76652) (xy 442.475838 -26.761102) (xy 442.45051 -26.761102) (xy 442.439044 -26.76652)
			(xy 442.400209 -26.786769) (xy 442.319322 -26.820374) (xy 442.235526 -26.845873) (xy 442.149632 -26.863019)
			(xy 442.062468 -26.871647) (xy 442.018674 -26.872184) (xy 441.974879 -26.871639) (xy 441.887715 -26.863025)
			(xy 441.801819 -26.845883) (xy 441.718025 -26.82038) (xy 441.637144 -26.786761) (xy 441.598304 -26.76652)
			(xy 441.586838 -26.761102) (xy 441.56151 -26.761102) (xy 441.550044 -26.76652) (xy 441.511209 -26.786769)
			(xy 441.430322 -26.820374) (xy 441.346526 -26.845873) (xy 441.260632 -26.863019) (xy 441.173468 -26.871647)
			(xy 441.129674 -26.872184) (xy 441.08856 -26.871712) (xy 441.006683 -26.864123) (xy 440.925855 -26.849012)
			(xy 440.846767 -26.826507) (xy 440.770092 -26.796802) (xy 440.696485 -26.760149) (xy 440.626574 -26.71686)
			(xy 440.560955 -26.667306) (xy 440.500188 -26.61191) (xy 440.444791 -26.551142) (xy 440.395237 -26.485523)
			(xy 440.351949 -26.415612) (xy 440.315297 -26.342004) (xy 440.285592 -26.265329) (xy 440.263088 -26.186241)
			(xy 440.247977 -26.105413) (xy 440.240388 -26.023536) (xy 440.239912 -25.982422) (xy 260.324092 -25.982422)
			(xy 260.324092 -32.117846) (xy 455.218281 -32.117846) (xy 455.218281 -31.988706) (xy 455.226231 -31.859811)
			(xy 455.242101 -31.731651) (xy 455.26583 -31.60471) (xy 455.297329 -31.479471) (xy 455.336478 -31.356408)
			(xy 455.383129 -31.235989) (xy 455.437104 -31.11867) (xy 455.498199 -31.004896) (xy 455.566182 -30.895099)
			(xy 455.640796 -30.789696) (xy 455.721757 -30.689086) (xy 455.808757 -30.593651) (xy 455.901468 -30.503752)
			(xy 455.999538 -30.419731) (xy 456.102593 -30.341907) (xy 456.210244 -30.270575) (xy 456.322083 -30.206005)
			(xy 456.437684 -30.148443) (xy 456.556609 -30.098106) (xy 456.678408 -30.055186) (xy 456.802618 -30.019845)
			(xy 456.928767 -29.992218) (xy 457.056379 -29.972409) (xy 457.184968 -29.960493) (xy 457.314046 -29.956517)
			(xy 457.443124 -29.960493) (xy 457.571713 -29.972409) (xy 457.699325 -29.992218) (xy 457.825474 -30.019845)
			(xy 457.949684 -30.055186) (xy 458.071483 -30.098106) (xy 458.190408 -30.148443) (xy 458.306009 -30.206005)
			(xy 458.417848 -30.270575) (xy 458.525499 -30.341907) (xy 458.628554 -30.419731) (xy 458.726624 -30.503752)
			(xy 458.819335 -30.593651) (xy 458.906335 -30.689086) (xy 458.987296 -30.789696) (xy 459.06191 -30.895099)
			(xy 459.129893 -31.004896) (xy 459.190988 -31.11867) (xy 459.244963 -31.235989) (xy 459.291614 -31.356408)
			(xy 459.330763 -31.479471) (xy 459.362262 -31.60471) (xy 459.385991 -31.731651) (xy 459.401861 -31.859811)
			(xy 459.409811 -31.988706) (xy 459.410308 -32.053276) (xy 459.409811 -32.117846) (xy 459.401861 -32.246741)
			(xy 459.385991 -32.374901) (xy 459.362262 -32.501842) (xy 459.330763 -32.627081) (xy 459.291614 -32.750144)
			(xy 459.244963 -32.870563) (xy 459.190988 -32.987882) (xy 459.129893 -33.101656) (xy 459.06191 -33.211453)
			(xy 458.987296 -33.316856) (xy 458.906335 -33.417466) (xy 458.819335 -33.512901) (xy 458.726624 -33.6028)
			(xy 458.628554 -33.686821) (xy 458.525499 -33.764645) (xy 458.417848 -33.835977) (xy 458.307206 -33.899856)
			(xy 461.798924 -33.899856) (xy 461.798924 -32.299656) (xy 461.799422 -32.222373) (xy 461.807378 -32.068013)
			(xy 461.823271 -31.914267) (xy 461.847057 -31.761543) (xy 461.878674 -31.610247) (xy 461.918037 -31.460778)
			(xy 461.965042 -31.313534) (xy 462.019566 -31.168904) (xy 462.081462 -31.027274) (xy 462.150567 -30.889017)
			(xy 462.226698 -30.754502) (xy 462.309652 -30.624083) (xy 462.399211 -30.498108) (xy 462.495135 -30.376911)
			(xy 462.597172 -30.260812) (xy 462.705049 -30.15012) (xy 462.818482 -30.045128) (xy 462.93717 -29.946115)
			(xy 463.060797 -29.853342) (xy 463.189036 -29.767057) (xy 463.321547 -29.687488) (xy 463.457979 -29.614846)
			(xy 463.597969 -29.549324) (xy 463.741146 -29.491095) (xy 463.887131 -29.440314) (xy 464.035537 -29.397115)
			(xy 464.185969 -29.361613) (xy 464.33803 -29.333903) (xy 464.491316 -29.314057) (xy 464.64542 -29.302128)
			(xy 464.799934 -29.298149) (xy 464.954448 -29.302128) (xy 465.108552 -29.314057) (xy 465.261838 -29.333903)
			(xy 465.413899 -29.361613) (xy 465.564331 -29.397115) (xy 465.712737 -29.440314) (xy 465.858722 -29.491095)
			(xy 466.001899 -29.549324) (xy 466.141889 -29.614846) (xy 466.278321 -29.687488) (xy 466.410832 -29.767057)
			(xy 466.539071 -29.853342) (xy 466.662698 -29.946115) (xy 466.781386 -30.045128) (xy 466.894819 -30.15012)
			(xy 467.002696 -30.260812) (xy 467.104733 -30.376911) (xy 467.200657 -30.498108) (xy 467.290216 -30.624083)
			(xy 467.37317 -30.754502) (xy 467.449301 -30.889017) (xy 467.518406 -31.027274) (xy 467.580302 -31.168904)
			(xy 467.634826 -31.313534) (xy 467.681831 -31.460778) (xy 467.721194 -31.610247) (xy 467.752811 -31.761543)
			(xy 467.776597 -31.914267) (xy 467.79249 -32.068013) (xy 467.800446 -32.222373) (xy 467.800944 -32.299656)
			(xy 467.800944 -33.899856) (xy 467.800446 -33.977139) (xy 467.79249 -34.131499) (xy 467.776597 -34.285245)
			(xy 467.752811 -34.437969) (xy 467.721194 -34.589265) (xy 467.681831 -34.738734) (xy 467.634826 -34.885978)
			(xy 467.580302 -35.030608) (xy 467.518406 -35.172238) (xy 467.449301 -35.310495) (xy 467.37317 -35.44501)
			(xy 467.290216 -35.575429) (xy 467.200657 -35.701404) (xy 467.104733 -35.822601) (xy 467.002696 -35.9387)
			(xy 466.894819 -36.049392) (xy 466.781386 -36.154384) (xy 466.662698 -36.253397) (xy 466.539071 -36.34617)
			(xy 466.410832 -36.432455) (xy 466.278321 -36.512024) (xy 466.141889 -36.584666) (xy 466.001899 -36.650188)
			(xy 465.858722 -36.708417) (xy 465.712737 -36.759198) (xy 465.564331 -36.802397) (xy 465.413899 -36.837899)
			(xy 465.261838 -36.865609) (xy 465.108552 -36.885455) (xy 464.954448 -36.897384) (xy 464.799934 -36.901364)
			(xy 464.64542 -36.897384) (xy 464.491316 -36.885455) (xy 464.33803 -36.865609) (xy 464.185969 -36.837899)
			(xy 464.035537 -36.802397) (xy 463.887131 -36.759198) (xy 463.741146 -36.708417) (xy 463.597969 -36.650188)
			(xy 463.457979 -36.584666) (xy 463.321547 -36.512024) (xy 463.189036 -36.432455) (xy 463.060797 -36.34617)
			(xy 462.93717 -36.253397) (xy 462.818482 -36.154384) (xy 462.705049 -36.049392) (xy 462.597172 -35.9387)
			(xy 462.495135 -35.822601) (xy 462.399211 -35.701404) (xy 462.309652 -35.575429) (xy 462.226698 -35.44501)
			(xy 462.150567 -35.310495) (xy 462.081462 -35.172238) (xy 462.019566 -35.030608) (xy 461.965042 -34.885978)
			(xy 461.918037 -34.738734) (xy 461.878674 -34.589265) (xy 461.847057 -34.437969) (xy 461.823271 -34.285245)
			(xy 461.807378 -34.131499) (xy 461.799422 -33.977139) (xy 461.798924 -33.899856) (xy 458.307206 -33.899856)
			(xy 458.306009 -33.900547) (xy 458.190408 -33.958109) (xy 458.071483 -34.008446) (xy 457.949684 -34.051366)
			(xy 457.825474 -34.086707) (xy 457.699325 -34.114334) (xy 457.571713 -34.134143) (xy 457.443124 -34.146059)
			(xy 457.314046 -34.150036) (xy 457.184968 -34.146059) (xy 457.056379 -34.134143) (xy 456.928767 -34.114334)
			(xy 456.802618 -34.086707) (xy 456.678408 -34.051366) (xy 456.556609 -34.008446) (xy 456.437684 -33.958109)
			(xy 456.322083 -33.900547) (xy 456.210244 -33.835977) (xy 456.102593 -33.764645) (xy 455.999538 -33.686821)
			(xy 455.901468 -33.6028) (xy 455.808757 -33.512901) (xy 455.721757 -33.417466) (xy 455.640796 -33.316856)
			(xy 455.566182 -33.211453) (xy 455.498199 -33.101656) (xy 455.437104 -32.987882) (xy 455.383129 -32.870563)
			(xy 455.336478 -32.750144) (xy 455.297329 -32.627081) (xy 455.26583 -32.501842) (xy 455.242101 -32.374901)
			(xy 455.226231 -32.246741) (xy 455.218281 -32.117846) (xy 260.324092 -32.117846) (xy 260.324092 -34.120074)
			(xy 260.323601 -34.203949) (xy 260.315621 -34.37151) (xy 260.299676 -34.538502) (xy 260.275804 -34.704545)
			(xy 260.244058 -34.869265) (xy 260.20451 -35.032287) (xy 260.15725 -35.193243) (xy 260.102385 -35.351768)
			(xy 260.040039 -35.507503) (xy 259.970354 -35.660095) (xy 259.893487 -35.809198) (xy 259.809612 -35.954475)
			(xy 259.71892 -36.095596) (xy 259.621615 -36.232243) (xy 259.517919 -36.364104) (xy 259.408066 -36.490882)
			(xy 259.292305 -36.612289) (xy 259.170898 -36.728051) (xy 259.044121 -36.837905) (xy 258.91226 -36.941602)
			(xy 258.775615 -37.038907) (xy 258.634494 -37.1296) (xy 258.489217 -37.213476) (xy 258.340115 -37.290344)
			(xy 258.187523 -37.360031) (xy 258.031789 -37.422377) (xy 257.873264 -37.477243) (xy 257.712308 -37.524504)
			(xy 257.549286 -37.564053) (xy 257.384567 -37.5958) (xy 257.218524 -37.619674) (xy 257.051532 -37.635619)
			(xy 256.883971 -37.643601) (xy 256.800096 -37.64407) (xy 225.300032 -37.64407) (xy 225.216157 -37.64358)
			(xy 225.048596 -37.635599) (xy 224.881605 -37.619655) (xy 224.715561 -37.595783) (xy 224.550842 -37.564037)
			(xy 224.38782 -37.524489) (xy 224.226864 -37.477229) (xy 224.068339 -37.422364) (xy 223.912605 -37.360019)
			(xy 223.760013 -37.290333) (xy 223.61091 -37.213466) (xy 223.465633 -37.129591) (xy 223.324512 -37.038899)
			(xy 223.187866 -36.941594) (xy 223.056005 -36.837898) (xy 222.929228 -36.728045) (xy 222.807821 -36.612284)
			(xy 222.692059 -36.490877) (xy 222.582206 -36.364099) (xy 222.478509 -36.232239) (xy 222.381205 -36.095593)
			(xy 222.290512 -35.954472) (xy 222.206637 -35.809195) (xy 222.12977 -35.660093) (xy 222.060084 -35.507501)
			(xy 221.997738 -35.351766) (xy 221.942873 -35.193242) (xy 221.895612 -35.032286) (xy 221.856064 -34.869264)
			(xy 221.824318 -34.704544) (xy 221.800446 -34.538501) (xy 221.784501 -34.37151) (xy 221.776521 -34.203949)
			(xy 221.776036 -34.120074) (xy 221.776036 -13.780008) (xy 221.775527 -13.748842) (xy 221.767392 -13.687042)
			(xy 221.751261 -13.626833) (xy 221.727409 -13.569244) (xy 221.696245 -13.515262) (xy 221.658302 -13.465808)
			(xy 221.614228 -13.42173) (xy 221.564778 -13.383782) (xy 221.510799 -13.352612) (xy 221.453212 -13.328754)
			(xy 221.393005 -13.312617) (xy 221.331206 -13.304476) (xy 221.30004 -13.304012) (xy 196.701918 -13.304012)
			(xy 196.615946 -13.303495) (xy 196.444208 -13.295111) (xy 196.273082 -13.278362) (xy 196.102977 -13.253287)
			(xy 195.934297 -13.219948) (xy 195.767443 -13.178422) (xy 195.602813 -13.128808) (xy 195.440798 -13.071226)
			(xy 195.281785 -13.005811) (xy 195.12615 -12.932719) (xy 194.974265 -12.852125) (xy 194.826491 -12.76422)
			(xy 194.683179 -12.669213) (xy 194.544671 -12.56733) (xy 194.411297 -12.458814) (xy 194.283372 -12.343924)
			(xy 194.161203 -12.222931) (xy 194.04508 -12.096125) (xy 193.935278 -11.963807) (xy 193.83206 -11.826291)
			(xy 193.783458 -11.755374) (xy 193.776849 -11.746538) (xy 193.758022 -11.735076) (xy 193.747136 -11.733276)
			(xy 193.73342 -11.73353) (xy 193.642742 -11.747754) (xy 193.635754 -11.749136) (xy 193.622868 -11.755196)
			(xy 193.617342 -11.759692) (xy 193.612008 -11.764264) (xy 193.604388 -11.776202) (xy 193.602102 -11.783314)
			(xy 193.587006 -11.83201) (xy 193.549479 -11.92681) (xy 193.503839 -12.017983) (xy 193.450433 -12.104834)
			(xy 193.389666 -12.186705) (xy 193.322001 -12.262973) (xy 193.285364 -12.298426) (xy 193.277744 -12.305792)
			(xy 193.27368 -12.31519) (xy 193.271729 -12.320171) (xy 193.269687 -12.330669) (xy 193.269616 -12.336018)
			(xy 193.270378 -12.41044) (xy 193.270378 -12.41298) (xy 193.271476 -12.422807) (xy 193.280102 -12.44058)
			(xy 193.287142 -12.447524) (xy 193.317409 -12.475579) (xy 193.373175 -12.536421) (xy 193.423068 -12.602166)
			(xy 193.466658 -12.672249) (xy 193.50357 -12.746067) (xy 193.533488 -12.822986) (xy 193.556154 -12.902346)
			(xy 193.571374 -12.983463) (xy 193.579016 -13.065642) (xy 193.579496 -13.106908) (xy 193.579035 -13.148011)
			(xy 193.57145 -13.229865) (xy 193.556344 -13.310671) (xy 193.533846 -13.389738) (xy 193.50415 -13.466392)
			(xy 193.467507 -13.539979) (xy 193.42423 -13.609871) (xy 193.37469 -13.675472) (xy 193.319308 -13.736222)
			(xy 193.258557 -13.791603) (xy 193.192955 -13.841142) (xy 193.123062 -13.884416) (xy 193.049474 -13.921058)
			(xy 192.972819 -13.950753) (xy 192.893752 -13.973248) (xy 192.812946 -13.988353) (xy 192.731091 -13.995936)
			(xy 192.689988 -13.996416) (xy 192.68948 -13.996416) (xy 192.643115 -13.995821) (xy 192.550889 -13.986178)
			(xy 192.460167 -13.966989) (xy 192.371936 -13.938461) (xy 192.329308 -13.920216) (xy 192.319366 -13.91641)
			(xy 192.298102 -13.91641) (xy 192.28816 -13.920216) (xy 192.245554 -13.938428) (xy 192.157385 -13.966933)
			(xy 192.06673 -13.986122) (xy 191.974573 -13.995786) (xy 191.928242 -13.996416) (xy 191.927734 -13.996416)
			(xy 191.886627 -13.995943) (xy 191.804763 -13.988361) (xy 191.723948 -13.973259) (xy 191.644871 -13.950766)
			(xy 191.568206 -13.921074) (xy 191.494608 -13.884435) (xy 191.424704 -13.841162) (xy 191.35909 -13.791625)
			(xy 191.298326 -13.736246) (xy 191.24293 -13.675497) (xy 191.193375 -13.609896) (xy 191.150083 -13.540004)
			(xy 191.113424 -13.466415) (xy 191.083711 -13.389758) (xy 191.061196 -13.310687) (xy 191.046072 -13.229876)
			(xy 191.038468 -13.148015) (xy 191.037972 -13.106908) (xy 191.0385 -13.063026) (xy 191.047142 -12.975689)
			(xy 191.064341 -12.889627) (xy 191.089932 -12.805677) (xy 191.123665 -12.724654) (xy 191.165212 -12.647348)
			(xy 191.21417 -12.574508) (xy 191.270063 -12.506843) (xy 191.332347 -12.445011) (xy 191.400417 -12.389613)
			(xy 191.473611 -12.341187) (xy 191.51219 -12.32027) (xy 191.51694 -12.317586) (xy 191.525266 -12.31054)
			(xy 191.5287 -12.3063) (xy 191.5414 -12.28979) (xy 191.544688 -12.285338) (xy 191.549425 -12.275339)
			(xy 191.550798 -12.269978) (xy 191.565276 -12.2047) (xy 191.566368 -12.199299) (xy 191.566494 -12.188282)
			(xy 191.56553 -12.182856) (xy 191.56299 -12.17168) (xy 191.556132 -12.16279) (xy 191.52726 -12.12452)
			(xy 191.47517 -12.044031) (xy 191.429852 -11.959544) (xy 191.391611 -11.871626) (xy 191.360705 -11.78087)
			(xy 191.337341 -11.687886) (xy 191.321677 -11.593301) (xy 191.313818 -11.497749) (xy 191.313308 -11.449812)
			(xy 191.313807 -11.401496) (xy 191.321785 -11.305194) (xy 191.337689 -11.209879) (xy 191.36141 -11.116203)
			(xy 191.392785 -11.024806) (xy 191.4316 -10.936313) (xy 191.477591 -10.851326) (xy 191.530442 -10.770428)
			(xy 191.589793 -10.69417) (xy 191.655239 -10.623074) (xy 191.726332 -10.557626) (xy 191.802587 -10.498271)
			(xy 191.883483 -10.445416) (xy 191.968468 -10.399422) (xy 192.05696 -10.360603) (xy 192.148355 -10.329224)
			(xy 192.24203 -10.3055) (xy 192.337344 -10.289592) (xy 192.433646 -10.281609) (xy 192.481962 -10.281158)
			(xy 192.53335 -10.281753) (xy 192.635723 -10.29085) (xy 192.736902 -10.308898) (xy 192.836107 -10.335758)
			(xy 192.932571 -10.371223) (xy 193.025549 -10.415018) (xy 193.070226 -10.440416) (xy 193.070734 -10.440416)
			(xy 193.070734 -10.44067) (xy 193.07919 -10.445027) (xy 193.098002 -10.447749) (xy 193.116511 -10.44342)
			(xy 193.124582 -10.438384) (xy 193.200782 -10.386568) (xy 193.206632 -10.382287) (xy 193.215794 -10.37106)
			(xy 193.218816 -10.36447) (xy 193.224404 -10.351516) (xy 193.22288 -10.341864) (xy 193.208562 -10.249169)
			(xy 193.18859 -10.06265) (xy 193.178567 -9.875332) (xy 193.177922 -9.78154) (xy 193.177922 -6.854698)
			(xy 193.177434 -6.844689) (xy 193.169775 -6.826194) (xy 193.155623 -6.812036) (xy 193.137131 -6.80437)
			(xy 193.127122 -6.803898) (xy 127.67691 -6.803898) (xy 127.666887 -6.804316) (xy 127.648367 -6.811984)
			(xy 127.634191 -6.826156) (xy 127.626518 -6.844675) (xy 127.62611 -6.854698) (xy 127.62611 -9.32434)
			(xy 127.626465 -9.33304) (xy 127.632285 -9.349438) (xy 127.643244 -9.362953) (xy 127.650494 -9.367774)
			(xy 127.72517 -9.412986) (xy 127.731774 -9.416288) (xy 127.742331 -9.420131) (xy 127.76475 -9.41921)
			(xy 127.774954 -9.41451) (xy 127.816791 -9.393142) (xy 127.903258 -9.356394) (xy 127.992395 -9.326704)
			(xy 128.083628 -9.304263) (xy 128.176367 -9.289215) (xy 128.270014 -9.281659) (xy 128.31699 -9.28116)
			(xy 128.365305 -9.281645) (xy 128.461606 -9.289624) (xy 128.55692 -9.305528) (xy 128.650594 -9.329249)
			(xy 128.741989 -9.360625) (xy 128.830482 -9.39944) (xy 128.915466 -9.445431) (xy 128.996363 -9.498283)
			(xy 129.072618 -9.557634) (xy 129.143712 -9.62308) (xy 129.209159 -9.694174) (xy 129.268511 -9.770429)
			(xy 129.321364 -9.851325) (xy 129.367355 -9.936309) (xy 129.406172 -10.024801) (xy 129.437548 -10.116197)
			(xy 129.461269 -10.209871) (xy 129.477174 -10.305184) (xy 129.485154 -10.401485) (xy 129.485154 -10.498115)
			(xy 129.477174 -10.594416) (xy 129.461269 -10.689729) (xy 129.437548 -10.783403) (xy 129.406172 -10.874799)
			(xy 129.367355 -10.963291) (xy 129.321364 -11.048275) (xy 129.268511 -11.129171) (xy 129.209159 -11.205426)
			(xy 129.143712 -11.27652) (xy 129.072618 -11.341966) (xy 128.996363 -11.401317) (xy 128.915466 -11.454169)
			(xy 128.830482 -11.50016) (xy 128.741989 -11.538975) (xy 128.650594 -11.570351) (xy 128.55692 -11.594072)
			(xy 128.461606 -11.609976) (xy 128.365305 -11.617955) (xy 128.31699 -11.618468) (xy 128.268974 -11.617965)
			(xy 128.173269 -11.610054) (xy 128.078536 -11.594319) (xy 127.985413 -11.570865) (xy 127.894527 -11.539851)
			(xy 127.806492 -11.501487) (xy 127.721901 -11.456029) (xy 127.641324 -11.403786) (xy 127.565304 -11.345109)
			(xy 127.494353 -11.280394) (xy 127.461264 -11.245596) (xy 127.46101 -11.245342) (xy 127.452008 -11.236723)
			(xy 127.428436 -11.228718) (xy 127.416052 -11.230102) (xy 127.332994 -11.243056) (xy 127.326807 -11.244259)
			(xy 127.315251 -11.24928) (xy 127.310134 -11.252962) (xy 127.305308 -11.256518) (xy 127.297434 -11.26617)
			(xy 127.294894 -11.271758) (xy 127.259208 -11.346958) (xy 127.181684 -11.494278) (xy 127.09729 -11.637774)
			(xy 127.006215 -11.777125) (xy 126.960963 -11.8397) (xy 129.452596 -11.8397) (xy 129.456508 -11.762557)
			(xy 129.468205 -11.686205) (xy 129.487567 -11.611429) (xy 129.514394 -11.538994) (xy 129.548412 -11.469646)
			(xy 129.589272 -11.404096) (xy 129.636553 -11.343015) (xy 129.689772 -11.287031) (xy 129.748381 -11.236719)
			(xy 129.81178 -11.192594) (xy 129.879318 -11.15511) (xy 129.950302 -11.124652) (xy 130.024002 -11.101531)
			(xy 130.099664 -11.085985) (xy 130.176511 -11.078173) (xy 130.215132 -11.077702) (xy 130.215386 -11.077702)
			(xy 130.258051 -11.078335) (xy 130.342845 -11.087888) (xy 130.426044 -11.106842) (xy 130.506608 -11.134961)
			(xy 130.583532 -11.171893) (xy 130.620008 -11.194034) (xy 130.630439 -11.199827) (xy 130.654176 -11.201938)
			(xy 130.665474 -11.198098) (xy 130.696302 -11.178748) (xy 130.760988 -11.145367) (xy 130.828558 -11.118295)
			(xy 130.898398 -11.097779) (xy 130.969874 -11.084004) (xy 131.042336 -11.077097) (xy 131.078732 -11.076686)
			(xy 131.094754 -11.076793) (xy 131.126769 -11.078192) (xy 131.14274 -11.07948) (xy 131.166108 -11.067288)
			(xy 131.220718 -10.978388) (xy 131.225056 -10.970396) (xy 131.228454 -10.952547) (xy 131.225437 -10.93463)
			(xy 131.221226 -10.926572) (xy 131.221226 -10.926064) (xy 131.208774 -10.904056) (xy 131.18914 -10.857458)
			(xy 131.175834 -10.808674) (xy 131.169091 -10.75856) (xy 131.168648 -10.733278) (xy 131.169207 -10.705124)
			(xy 131.177522 -10.649433) (xy 131.193923 -10.595566) (xy 131.218057 -10.544691) (xy 131.249398 -10.497911)
			(xy 131.267962 -10.476738) (xy 131.27593 -10.466914) (xy 131.282075 -10.442413) (xy 131.279646 -10.430002)
			(xy 131.268831 -10.384218) (xy 131.257241 -10.290858) (xy 131.256532 -10.24382) (xy 131.256532 -10.243312)
			(xy 131.257039 -10.20331) (xy 131.2654 -10.123746) (xy 131.282033 -10.045491) (xy 131.306755 -9.969403)
			(xy 131.339294 -9.896316) (xy 131.379295 -9.827031) (xy 131.42632 -9.762307) (xy 131.479852 -9.702853)
			(xy 131.539306 -9.649321) (xy 131.60403 -9.602296) (xy 131.673314 -9.562295) (xy 131.746401 -9.529755)
			(xy 131.822489 -9.505034) (xy 131.900744 -9.488401) (xy 131.980308 -9.480039) (xy 132.02031 -9.479534)
			(xy 132.063 -9.480135) (xy 132.147843 -9.489699) (xy 132.231091 -9.508661) (xy 132.311706 -9.536786)
			(xy 132.388683 -9.573723) (xy 132.425186 -9.595866) (xy 132.433447 -9.600562) (xy 132.45211 -9.60407)
			(xy 132.470773 -9.600562) (xy 132.479034 -9.595866) (xy 132.515528 -9.573706) (xy 132.592504 -9.536763)
			(xy 132.673121 -9.508638) (xy 132.756373 -9.489684) (xy 132.841219 -9.480137) (xy 132.88391 -9.479534)
			(xy 132.923912 -9.480018) (xy 133.003478 -9.488382) (xy 133.081733 -9.505017) (xy 133.157821 -9.52974)
			(xy 133.230908 -9.562282) (xy 133.300193 -9.602285) (xy 133.364917 -9.649311) (xy 133.424371 -9.702845)
			(xy 133.477903 -9.7623) (xy 133.524927 -9.827026) (xy 133.564928 -9.896312) (xy 133.597468 -9.969399)
			(xy 133.622189 -10.045488) (xy 133.638822 -10.123744) (xy 133.647183 -10.20331) (xy 133.647688 -10.243312)
			(xy 133.647688 -10.24382) (xy 133.646924 -10.29158) (xy 133.634947 -10.386346) (xy 133.623812 -10.432796)
			(xy 133.621329 -10.445123) (xy 133.627324 -10.46951) (xy 133.635242 -10.479278) (xy 133.653357 -10.500376)
			(xy 133.683946 -10.546812) (xy 133.707473 -10.597195) (xy 133.723441 -10.650458) (xy 133.731512 -10.705475)
			(xy 133.732016 -10.733278) (xy 133.731578 -10.760551) (xy 133.727935 -10.7859) (xy 169.57315 -10.7859)
			(xy 169.577062 -10.708754) (xy 169.588759 -10.6324) (xy 169.608121 -10.55762) (xy 169.634949 -10.485183)
			(xy 169.668967 -10.415832) (xy 169.709827 -10.350279) (xy 169.75711 -10.289195) (xy 169.810329 -10.233209)
			(xy 169.86894 -10.182893) (xy 169.93234 -10.138766) (xy 169.999879 -10.101279) (xy 170.070864 -10.070817)
			(xy 170.144567 -10.047692) (xy 170.220231 -10.032143) (xy 170.297079 -10.024329) (xy 170.335702 -10.023856)
			(xy 170.378393 -10.02445) (xy 170.463241 -10.033993) (xy 170.546493 -10.052948) (xy 170.627109 -10.081079)
			(xy 170.704081 -10.118033) (xy 170.740578 -10.140188) (xy 170.748834 -10.144902) (xy 170.767502 -10.148429)
			(xy 170.78617 -10.144902) (xy 170.794426 -10.140188) (xy 170.830905 -10.117999) (xy 170.90787 -10.081018)
			(xy 170.988489 -10.05288) (xy 171.07175 -10.033938) (xy 171.156608 -10.02443) (xy 171.199302 -10.023856)
			(xy 171.237919 -10.024433) (xy 171.314757 -10.032247) (xy 171.390411 -10.047794) (xy 171.464103 -10.070916)
			(xy 171.535078 -10.101374) (xy 171.602607 -10.138856) (xy 171.665998 -10.182977) (xy 171.7246 -10.233286)
			(xy 171.777812 -10.289265) (xy 171.825088 -10.35034) (xy 171.865942 -10.415884) (xy 171.899955 -10.485226)
			(xy 171.926779 -10.557652) (xy 171.946138 -10.632421) (xy 171.957834 -10.708765) (xy 171.961746 -10.7859)
			(xy 171.957834 -10.863035) (xy 171.946138 -10.939379) (xy 171.926779 -11.014148) (xy 171.899955 -11.086574)
			(xy 171.865942 -11.155916) (xy 171.825088 -11.22146) (xy 171.777812 -11.282535) (xy 171.7246 -11.338514)
			(xy 171.665998 -11.388823) (xy 171.602607 -11.432944) (xy 171.535078 -11.470426) (xy 171.464103 -11.500884)
			(xy 171.390411 -11.524006) (xy 171.314757 -11.539553) (xy 171.237919 -11.547367) (xy 171.199302 -11.547856)
			(xy 171.15661 -11.547273) (xy 171.071762 -11.53773) (xy 170.988509 -11.518773) (xy 170.907893 -11.490639)
			(xy 170.830923 -11.453681) (xy 170.794426 -11.431524) (xy 170.78617 -11.42681) (xy 170.767502 -11.423283)
			(xy 170.748834 -11.42681) (xy 170.740578 -11.431524) (xy 170.704098 -11.453713) (xy 170.627133 -11.490693)
			(xy 170.546514 -11.518831) (xy 170.463254 -11.537773) (xy 170.378396 -11.547281) (xy 170.335702 -11.547856)
			(xy 170.297079 -11.547471) (xy 170.220231 -11.539657) (xy 170.144567 -11.524108) (xy 170.070864 -11.500983)
			(xy 169.999879 -11.470521) (xy 169.93234 -11.433034) (xy 169.86894 -11.388907) (xy 169.810329 -11.338591)
			(xy 169.75711 -11.282605) (xy 169.709827 -11.221521) (xy 169.668967 -11.155968) (xy 169.634949 -11.086617)
			(xy 169.608121 -11.01418) (xy 169.588759 -10.9394) (xy 169.577062 -10.863046) (xy 169.57315 -10.7859)
			(xy 133.727935 -10.7859) (xy 133.723818 -10.814541) (xy 133.708452 -10.866877) (xy 133.685793 -10.916493)
			(xy 133.656304 -10.962379) (xy 133.620583 -11.0036) (xy 133.57936 -11.039318) (xy 133.533472 -11.068805)
			(xy 133.483854 -11.09146) (xy 133.431517 -11.106823) (xy 133.377527 -11.11458) (xy 133.350254 -11.11504)
			(xy 133.320564 -11.11445) (xy 133.261901 -11.105245) (xy 133.205373 -11.087066) (xy 133.152342 -11.060349)
			(xy 133.104089 -11.025742) (xy 133.082538 -11.005312) (xy 133.073181 -10.996983) (xy 133.049214 -10.989791)
			(xy 133.036818 -10.991596) (xy 132.999007 -10.998842) (xy 132.922406 -11.006599) (xy 132.88391 -11.00709)
			(xy 132.841221 -11.006476) (xy 132.756378 -10.996915) (xy 132.67313 -10.977955) (xy 132.592515 -10.949833)
			(xy 132.515538 -10.9129) (xy 132.479034 -10.890758) (xy 132.470773 -10.886062) (xy 132.45211 -10.882554)
			(xy 132.433447 -10.886062) (xy 132.425186 -10.890758) (xy 132.388682 -10.912901) (xy 132.31171 -10.949849)
			(xy 132.231095 -10.977978) (xy 132.147846 -10.996936) (xy 132.063 -11.006486) (xy 132.02031 -11.00709)
			(xy 132.019802 -11.00709) (xy 131.980849 -11.006554) (xy 131.903354 -10.998538) (xy 131.865116 -10.991088)
			(xy 131.852654 -10.989216) (xy 131.828536 -10.996405) (xy 131.819142 -11.004804) (xy 131.797568 -11.025348)
			(xy 131.749189 -11.060112) (xy 131.696005 -11.086951) (xy 131.639301 -11.105216) (xy 131.58045 -11.114466)
			(xy 131.550664 -11.11504) (xy 131.55041 -11.11504) (xy 131.534662 -11.114786) (xy 131.524493 -11.114951)
			(xy 131.505496 -11.122139) (xy 131.490774 -11.136135) (xy 131.482635 -11.154745) (xy 131.482352 -11.175055)
			(xy 131.48997 -11.193884) (xy 131.496816 -11.2014) (xy 131.528192 -11.222509) (xy 131.587043 -11.270003)
			(xy 131.640908 -11.323086) (xy 131.689257 -11.381237) (xy 131.731616 -11.443886) (xy 131.767569 -11.510419)
			(xy 131.796765 -11.580181) (xy 131.818916 -11.65249) (xy 131.833805 -11.726635) (xy 131.841286 -11.801889)
			(xy 131.841748 -11.839702) (xy 131.841195 -11.879662) (xy 131.832841 -11.959143) (xy 131.816225 -12.037316)
			(xy 131.79153 -12.113323) (xy 131.759024 -12.186333) (xy 131.719065 -12.255546) (xy 131.672091 -12.320202)
			(xy 131.618616 -12.379595) (xy 131.559226 -12.433072) (xy 131.494571 -12.480049) (xy 131.468639 -12.495022)
			(xy 134.764018 -12.495022) (xy 134.764574 -12.465509) (xy 134.773662 -12.407188) (xy 134.791625 -12.350962)
			(xy 134.818034 -12.298174) (xy 134.852259 -12.250084) (xy 134.872476 -12.228576) (xy 134.878497 -12.221781)
			(xy 134.885815 -12.205181) (xy 134.886933 -12.187075) (xy 134.884668 -12.178284) (xy 134.874112 -12.142106)
			(xy 134.859315 -12.068207) (xy 134.851864 -11.993209) (xy 134.851394 -11.955526) (xy 134.851394 -11.955018)
			(xy 134.851962 -11.915019) (xy 134.860323 -11.835458) (xy 134.876953 -11.757208) (xy 134.901672 -11.681124)
			(xy 134.934208 -11.608041) (xy 134.974206 -11.538759) (xy 135.021226 -11.474038) (xy 135.074753 -11.414586)
			(xy 135.134202 -11.361055) (xy 135.198921 -11.314031) (xy 135.2682 -11.274029) (xy 135.341281 -11.241489)
			(xy 135.417363 -11.216765) (xy 135.495613 -11.20013) (xy 135.575173 -11.191765) (xy 135.615172 -11.19124)
			(xy 135.658037 -11.191827) (xy 135.743229 -11.201424) (xy 135.826811 -11.2205) (xy 135.90773 -11.248817)
			(xy 135.98497 -11.286017) (xy 136.021572 -11.308334) (xy 136.031867 -11.314075) (xy 136.055291 -11.316461)
			(xy 136.06653 -11.312906) (xy 136.097322 -11.293682) (xy 136.161861 -11.260447) (xy 136.229265 -11.233491)
			(xy 136.298924 -11.213057) (xy 136.370209 -11.19933) (xy 136.442475 -11.192434) (xy 136.478772 -11.192002)
			(xy 136.518734 -11.192516) (xy 136.598219 -11.200867) (xy 136.676396 -11.217482) (xy 136.752408 -11.242178)
			(xy 136.825422 -11.274684) (xy 136.894639 -11.314644) (xy 136.959298 -11.361621) (xy 137.018693 -11.4151)
			(xy 137.072173 -11.474494) (xy 137.11915 -11.539153) (xy 137.159112 -11.608369) (xy 137.191619 -11.681382)
			(xy 137.216316 -11.757394) (xy 137.232931 -11.835571) (xy 137.241284 -11.915056) (xy 137.241788 -11.955018)
			(xy 137.241316 -11.994475) (xy 137.233204 -12.07297) (xy 137.217026 -12.150208) (xy 137.205466 -12.187936)
			(xy 137.204752 -12.199206) (xy 137.212025 -12.22056) (xy 137.219436 -12.229084) (xy 137.239582 -12.250561)
			(xy 137.273645 -12.298593) (xy 137.299926 -12.351287) (xy 137.317799 -12.407394) (xy 137.326842 -12.46558)
			(xy 137.327386 -12.495022) (xy 137.326896 -12.522291) (xy 137.319132 -12.576273) (xy 137.303765 -12.628601)
			(xy 137.281108 -12.67821) (xy 137.251622 -12.724089) (xy 137.215907 -12.765306) (xy 137.174691 -12.801021)
			(xy 137.128811 -12.830507) (xy 137.079203 -12.853164) (xy 137.026875 -12.868532) (xy 136.972893 -12.876296)
			(xy 136.945624 -12.876784) (xy 136.916464 -12.876283) (xy 136.858823 -12.867409) (xy 136.803204 -12.849864)
			(xy 136.750905 -12.824056) (xy 136.703144 -12.790588) (xy 136.661034 -12.75024) (xy 136.642856 -12.727432)
			(xy 136.635612 -12.718959) (xy 136.615853 -12.708686) (xy 136.604756 -12.70762) (xy 136.573489 -12.712504)
			(xy 136.510416 -12.717721) (xy 136.478772 -12.718034) (xy 136.442474 -12.717605) (xy 136.370207 -12.71071)
			(xy 136.298921 -12.696985) (xy 136.22926 -12.676555) (xy 136.161854 -12.649602) (xy 136.097311 -12.616372)
			(xy 136.06653 -12.59713) (xy 136.055295 -12.593522) (xy 136.031849 -12.595904) (xy 136.021572 -12.601702)
			(xy 135.984977 -12.624031) (xy 135.907735 -12.66123) (xy 135.826814 -12.689546) (xy 135.743231 -12.708622)
			(xy 135.658038 -12.718219) (xy 135.615172 -12.718796) (xy 135.614156 -12.718796) (xy 135.584438 -12.718468)
			(xy 135.525189 -12.713763) (xy 135.495792 -12.709398) (xy 135.486762 -12.708385) (xy 135.468982 -12.712068)
			(xy 135.453603 -12.721722) (xy 135.447786 -12.728702) (xy 135.429581 -12.751334) (xy 135.387475 -12.791338)
			(xy 135.339798 -12.824506) (xy 135.287649 -12.850075) (xy 135.232231 -12.867454) (xy 135.17482 -12.876244)
			(xy 135.14578 -12.876784) (xy 135.118511 -12.876294) (xy 135.064529 -12.86853) (xy 135.012201 -12.853164)
			(xy 134.962592 -12.830507) (xy 134.916712 -12.801021) (xy 134.875495 -12.765306) (xy 134.83978 -12.724089)
			(xy 134.810294 -12.67821) (xy 134.787637 -12.628601) (xy 134.77227 -12.576273) (xy 134.764506 -12.522291)
			(xy 134.764018 -12.495022) (xy 131.468639 -12.495022) (xy 131.42536 -12.520011) (xy 131.352351 -12.552519)
			(xy 131.276345 -12.577218) (xy 131.198172 -12.593837) (xy 131.118692 -12.602193) (xy 131.078732 -12.602718)
			(xy 131.042335 -12.602339) (xy 130.96987 -12.595436) (xy 130.898392 -12.58166) (xy 130.828552 -12.561136)
			(xy 130.760984 -12.534053) (xy 130.696304 -12.500655) (xy 130.665474 -12.481306) (xy 130.654174 -12.477509)
			(xy 130.630459 -12.479635) (xy 130.620008 -12.48537) (xy 130.58354 -12.507528) (xy 130.506626 -12.544496)
			(xy 130.426062 -12.572632) (xy 130.342857 -12.591584) (xy 130.258054 -12.601113) (xy 130.215386 -12.601702)
			(xy 130.215132 -12.601702) (xy 130.176511 -12.601227) (xy 130.099664 -12.593415) (xy 130.024002 -12.577869)
			(xy 129.950302 -12.554748) (xy 129.879318 -12.52429) (xy 129.81178 -12.486806) (xy 129.748381 -12.442681)
			(xy 129.689772 -12.392369) (xy 129.636553 -12.336385) (xy 129.589272 -12.275304) (xy 129.548412 -12.209754)
			(xy 129.514394 -12.140406) (xy 129.487567 -12.067971) (xy 129.468205 -11.993195) (xy 129.456508 -11.916843)
			(xy 129.452596 -11.8397) (xy 126.960963 -11.8397) (xy 126.908663 -11.91202) (xy 126.80485 -12.042159)
			(xy 126.695009 -12.167251) (xy 126.579383 -12.287018) (xy 126.458232 -12.401192) (xy 126.331825 -12.509518)
			(xy 126.200445 -12.611755) (xy 126.064384 -12.707675) (xy 125.923945 -12.797064) (xy 125.779443 -12.879722)
			(xy 125.6312 -12.955465) (xy 125.479545 -13.024125) (xy 125.324818 -13.085547) (xy 125.167363 -13.139596)
			(xy 125.007532 -13.18615) (xy 124.845681 -13.225106) (xy 124.682172 -13.256376) (xy 124.517368 -13.279892)
			(xy 124.351638 -13.2956) (xy 124.18535 -13.303465) (xy 124.102114 -13.304012) (xy 83.70189 -13.304012)
			(xy 83.618015 -13.303513) (xy 83.450455 -13.29553) (xy 83.283465 -13.279584) (xy 83.117423 -13.255711)
			(xy 82.952705 -13.223964) (xy 82.789684 -13.184415) (xy 82.628729 -13.137154) (xy 82.470206 -13.082288)
			(xy 82.314472 -13.019942) (xy 82.161882 -12.950256) (xy 82.01278 -12.873388) (xy 81.867505 -12.789514)
			(xy 81.726385 -12.698821) (xy 81.58974 -12.601517) (xy 81.45788 -12.497821) (xy 81.331103 -12.387968)
			(xy 81.209696 -12.272208) (xy 81.093936 -12.150802) (xy 80.984083 -12.024025) (xy 80.880387 -11.892165)
			(xy 80.783082 -11.75552) (xy 80.69239 -11.6144) (xy 80.608514 -11.469125) (xy 80.531647 -11.320023)
			(xy 80.461961 -11.167433) (xy 80.399614 -11.0117) (xy 80.344748 -10.853176) (xy 80.297487 -10.692222)
			(xy 80.257938 -10.529201) (xy 80.22619 -10.364483) (xy 80.202316 -10.198441) (xy 80.18637 -10.031451)
			(xy 80.178388 -9.863891) (xy 80.177894 -9.780016) (xy 80.177894 -7.292594) (xy 80.177543 -7.283865)
			(xy 80.171662 -7.267428) (xy 80.160561 -7.253954) (xy 80.153256 -7.24916) (xy 80.07858 -7.203948)
			(xy 80.072859 -7.200702) (xy 80.060254 -7.196961) (xy 80.053688 -7.196582) (xy 80.040734 -7.196328)
			(xy 80.028796 -7.202678) (xy 79.986657 -7.224456) (xy 79.899501 -7.261909) (xy 79.809595 -7.292173)
			(xy 79.717531 -7.315048) (xy 79.623916 -7.330383) (xy 79.529365 -7.338077) (xy 79.481934 -7.338568)
			(xy 79.433617 -7.338084) (xy 79.337312 -7.330106) (xy 79.241995 -7.314203) (xy 79.148317 -7.290483)
			(xy 79.056918 -7.259108) (xy 78.968421 -7.220292) (xy 78.883433 -7.174301) (xy 78.802533 -7.121448)
			(xy 78.726274 -7.062096) (xy 78.655176 -6.996648) (xy 78.589726 -6.925552) (xy 78.530371 -6.849295)
			(xy 78.477516 -6.768396) (xy 78.431523 -6.683409) (xy 78.392704 -6.594914) (xy 78.361327 -6.503516)
			(xy 78.337604 -6.409838) (xy 78.321698 -6.314522) (xy 78.313718 -6.218217) (xy 78.313718 -6.121583)
			(xy 78.321698 -6.025278) (xy 78.337604 -5.929962) (xy 78.361327 -5.836284) (xy 78.392704 -5.744886)
			(xy 78.431523 -5.656391) (xy 78.477516 -5.571404) (xy 78.530371 -5.490505) (xy 78.589726 -5.414248)
			(xy 78.655176 -5.343152) (xy 78.726274 -5.277704) (xy 78.802533 -5.218352) (xy 78.883433 -5.165499)
			(xy 78.968421 -5.119508) (xy 79.056918 -5.080692) (xy 79.148317 -5.049317) (xy 79.241995 -5.025597)
			(xy 79.337312 -5.009694) (xy 79.433617 -5.001716) (xy 79.481934 -5.00126) (xy 79.529366 -5.001734)
			(xy 79.623919 -5.009422) (xy 79.717537 -5.024754) (xy 79.809603 -5.047628) (xy 79.899511 -5.077893)
			(xy 79.986668 -5.11535) (xy 80.028796 -5.13715) (xy 80.034733 -5.140039) (xy 80.047594 -5.14301)
			(xy 80.054196 -5.142992) (xy 80.06715 -5.142738) (xy 80.153256 -5.090668) (xy 80.16053 -5.085852)
			(xy 80.171569 -5.072356) (xy 80.177467 -5.05595) (xy 80.177894 -5.047234) (xy 80.177894 -1.5748)
			(xy 80.177474 -1.564779) (xy 80.169804 -1.546263) (xy 80.155632 -1.532092) (xy 80.137115 -1.524424)
			(xy 80.127094 -1.524) (xy 14.676882 -1.524) (xy 14.666877 -1.524491) (xy 14.648391 -1.532154) (xy 14.634244 -1.546306)
			(xy 14.626588 -1.564795) (xy 14.626082 -1.5748) (xy 14.626082 -4.044442) (xy 14.626439 -4.053139)
			(xy 14.632265 -4.06953) (xy 14.643232 -4.083033) (xy 14.650466 -4.087876) (xy 14.725142 -4.133088)
			(xy 14.731746 -4.13639) (xy 14.742304 -4.140239) (xy 14.764728 -4.13933) (xy 14.774926 -4.134612)
			(xy 14.816763 -4.113243) (xy 14.90323 -4.076493) (xy 14.992367 -4.0468) (xy 15.083599 -4.024357)
			(xy 15.176338 -4.009308) (xy 15.269986 -4.001749) (xy 15.316962 -4.001262) (xy 15.365277 -4.001761)
			(xy 15.461578 -4.009741) (xy 15.556891 -4.025646) (xy 15.650565 -4.049368) (xy 15.741959 -4.080744)
			(xy 15.830451 -4.11956) (xy 15.915435 -4.165551) (xy 15.996331 -4.218403) (xy 16.072586 -4.277755)
			(xy 16.14368 -4.343202) (xy 16.209126 -4.414295) (xy 16.268478 -4.49055) (xy 16.32133 -4.571446)
			(xy 16.367321 -4.656431) (xy 16.406137 -4.744922) (xy 16.437513 -4.836317) (xy 16.461234 -4.929991)
			(xy 16.477139 -5.025304) (xy 16.485119 -5.121605) (xy 16.485119 -5.218235) (xy 16.477139 -5.314536)
			(xy 16.461234 -5.409849) (xy 16.437513 -5.503523) (xy 16.406137 -5.594918) (xy 16.367321 -5.683409)
			(xy 16.32133 -5.768394) (xy 16.268478 -5.84929) (xy 16.209126 -5.925545) (xy 16.14368 -5.996638)
			(xy 16.072586 -6.062085) (xy 15.996331 -6.121437) (xy 15.915435 -6.174289) (xy 15.830451 -6.22028)
			(xy 15.741959 -6.259096) (xy 15.650565 -6.290472) (xy 15.556891 -6.314194) (xy 15.461578 -6.330099)
			(xy 15.365277 -6.338079) (xy 15.316962 -6.33857) (xy 15.269985 -6.338102) (xy 15.176334 -6.330558)
			(xy 15.083591 -6.315514) (xy 14.992358 -6.293068) (xy 14.903222 -6.263364) (xy 14.816762 -6.226594)
			(xy 14.774926 -6.20522) (xy 14.764708 -6.200573) (xy 14.742306 -6.19964) (xy 14.731746 -6.203442)
			(xy 14.725142 -6.206744) (xy 14.650466 -6.251956) (xy 14.643213 -6.256778) (xy 14.632234 -6.270282)
			(xy 14.626423 -6.286687) (xy 14.626082 -6.29539) (xy 14.626082 -6.598158) (xy 17.928336 -6.598158)
			(xy 17.928785 -6.570888) (xy 17.936553 -6.516903) (xy 17.951923 -6.464573) (xy 17.974584 -6.414963)
			(xy 18.004074 -6.369082) (xy 18.039793 -6.327865) (xy 18.081014 -6.29215) (xy 18.126898 -6.262665)
			(xy 18.17651 -6.240009) (xy 18.228842 -6.224644) (xy 18.282828 -6.216883) (xy 18.310098 -6.216396)
			(xy 18.310352 -6.216396) (xy 18.32991 -6.216904) (xy 18.340832 -6.217412) (xy 18.360898 -6.210046)
			(xy 18.429732 -6.140958) (xy 18.437352 -6.121146) (xy 18.436844 -6.110224) (xy 18.436336 -6.091174)
			(xy 18.4368 -6.063904) (xy 18.444565 -6.00992) (xy 18.459934 -5.95759) (xy 18.482593 -5.90798) (xy 18.512081 -5.862099)
			(xy 18.547799 -5.820882) (xy 18.589018 -5.785167) (xy 18.634901 -5.755682) (xy 18.684513 -5.733026)
			(xy 18.736843 -5.71766) (xy 18.790828 -5.709899) (xy 18.818098 -5.709412) (xy 18.846912 -5.709957)
			(xy 18.903884 -5.718626) (xy 18.958908 -5.735753) (xy 19.010736 -5.76095) (xy 19.058192 -5.793644)
			(xy 19.1002 -5.833094) (xy 19.135807 -5.878405) (xy 19.164205 -5.92855) (xy 19.174968 -5.955284)
			(xy 19.179948 -5.966342) (xy 19.197982 -5.98251) (xy 19.209512 -5.986272) (xy 19.246608 -5.996497)
			(xy 19.318699 -6.023417) (xy 19.387713 -6.057457) (xy 19.420586 -6.077458) (xy 19.428842 -6.082172)
			(xy 19.44751 -6.085699) (xy 19.466178 -6.082172) (xy 19.474434 -6.077458) (xy 19.507314 -6.05747)
			(xy 19.576331 -6.023439) (xy 19.648417 -5.99651) (xy 19.685508 -5.986272) (xy 19.697074 -5.982575)
			(xy 19.715116 -5.966379) (xy 19.720052 -5.955284) (xy 19.730809 -5.928545) (xy 19.759195 -5.878388)
			(xy 19.794796 -5.833065) (xy 19.836803 -5.793607) (xy 19.884262 -5.760909) (xy 19.936095 -5.735713)
			(xy 19.991127 -5.718592) (xy 20.048106 -5.709935) (xy 20.076922 -5.709412) (xy 20.087678 -5.709518)
			(xy 20.109154 -5.710789) (xy 20.119848 -5.711952) (xy 20.13077 -5.713222) (xy 20.151598 -5.706364)
			(xy 20.216368 -5.646674) (xy 20.224001 -5.639002) (xy 20.232543 -5.619137) (xy 20.232878 -5.60832)
			(xy 20.232878 -5.608066) (xy 20.232624 -5.597652) (xy 20.232624 -5.597398) (xy 20.233012 -5.572667)
			(xy 20.239384 -5.523618) (xy 20.245324 -5.499608) (xy 20.24796 -5.487606) (xy 20.242636 -5.463643)
			(xy 20.235164 -5.453888) (xy 20.218328 -5.43358) (xy 20.187184 -5.390997) (xy 20.172934 -5.368798)
			(xy 20.167913 -5.361485) (xy 20.153944 -5.350571) (xy 20.137101 -5.345041) (xy 20.12823 -5.344922)
			(xy 20.114768 -5.345176) (xy 20.087501 -5.344659) (xy 20.033523 -5.336894) (xy 19.981199 -5.321527)
			(xy 19.931595 -5.29887) (xy 19.88572 -5.269384) (xy 19.844507 -5.23367) (xy 19.808797 -5.192455)
			(xy 19.779315 -5.146577) (xy 19.756662 -5.096971) (xy 19.741299 -5.044646) (xy 19.733538 -4.990667)
			(xy 19.733538 -4.936133) (xy 19.741299 -4.882154) (xy 19.756662 -4.829829) (xy 19.779315 -4.780223)
			(xy 19.808797 -4.734345) (xy 19.844507 -4.69313) (xy 19.88572 -4.657416) (xy 19.931595 -4.62793)
			(xy 19.981199 -4.605273) (xy 20.033523 -4.589906) (xy 20.087501 -4.582141) (xy 20.114768 -4.581652)
			(xy 20.12823 -4.581906) (xy 20.137115 -4.581887) (xy 20.153993 -4.576362) (xy 20.167961 -4.565394)
			(xy 20.172934 -4.55803) (xy 20.187197 -4.53584) (xy 20.218338 -4.493256) (xy 20.235164 -4.47294)
			(xy 20.242454 -4.4631) (xy 20.247752 -4.439224) (xy 20.245324 -4.42722) (xy 20.239402 -4.403401)
			(xy 20.233034 -4.354733) (xy 20.232624 -4.330192) (xy 20.232624 -4.32943) (xy 20.233129 -4.30216)
			(xy 20.240887 -4.248176) (xy 20.256249 -4.195845) (xy 20.278902 -4.146233) (xy 20.308385 -4.100349)
			(xy 20.344098 -4.059129) (xy 20.385314 -4.023411) (xy 20.431194 -3.993923) (xy 20.480803 -3.971264)
			(xy 20.533133 -3.955896) (xy 20.587116 -3.948132) (xy 20.614386 -3.947668) (xy 20.643064 -3.948223)
			(xy 20.699774 -3.956808) (xy 20.754564 -3.973774) (xy 20.806203 -3.998738) (xy 20.85353 -4.03114)
			(xy 20.895483 -4.070252) (xy 20.931118 -4.115195) (xy 20.959635 -4.16496) (xy 20.970494 -4.191508)
			(xy 20.975545 -4.202654) (xy 20.99387 -4.218826) (xy 21.005546 -4.222496) (xy 21.044187 -4.232718)
			(xy 21.119277 -4.260121) (xy 21.191097 -4.295212) (xy 21.225256 -4.315968) (xy 21.233517 -4.320664)
			(xy 21.25218 -4.324172) (xy 21.270843 -4.320664) (xy 21.279104 -4.315968) (xy 21.3116 -4.29617) (xy 21.379787 -4.262386)
			(xy 21.450997 -4.235554) (xy 21.487638 -4.22529) (xy 21.499187 -4.221553) (xy 21.517238 -4.205386)
			(xy 21.522182 -4.194302) (xy 21.532946 -4.167515) (xy 21.561283 -4.117224) (xy 21.596866 -4.07177)
			(xy 21.638884 -4.032189) (xy 21.686379 -3.999381) (xy 21.738271 -3.974094) (xy 21.793378 -3.956905)
			(xy 21.850444 -3.948204) (xy 21.879306 -3.947668) (xy 21.906579 -3.948096) (xy 21.960568 -3.95586)
			(xy 22.012903 -3.971228) (xy 22.062519 -3.993889) (xy 22.108404 -4.02338) (xy 22.149624 -4.059101)
			(xy 22.185342 -4.100325) (xy 22.214829 -4.146213) (xy 22.237484 -4.19583) (xy 22.252848 -4.248167)
			(xy 22.260607 -4.302157) (xy 22.261068 -4.32943) (xy 22.261068 -4.329684) (xy 22.260713 -4.352127)
			(xy 22.255359 -4.396693) (xy 22.2504 -4.418584) (xy 22.248259 -4.430576) (xy 22.254089 -4.454188)
			(xy 22.261576 -4.463796) (xy 22.280605 -4.486153) (xy 22.31557 -4.533321) (xy 22.331426 -4.55803)
			(xy 22.336491 -4.56531) (xy 22.350438 -4.576235) (xy 22.367265 -4.581779) (xy 22.37613 -4.581906)
			(xy 22.389592 -4.581652) (xy 22.416864 -4.582087) (xy 22.470854 -4.589848) (xy 22.52319 -4.605215)
			(xy 22.572806 -4.627873) (xy 22.618692 -4.657361) (xy 22.659915 -4.69308) (xy 22.695634 -4.734302)
			(xy 22.725124 -4.780187) (xy 22.747783 -4.829803) (xy 22.76315 -4.882138) (xy 22.770912 -4.936128)
			(xy 22.770912 -4.990672) (xy 22.76315 -5.044662) (xy 22.747783 -5.096997) (xy 22.725124 -5.146613)
			(xy 22.695634 -5.192498) (xy 22.659915 -5.23372) (xy 22.618692 -5.269439) (xy 22.572806 -5.298927)
			(xy 22.52319 -5.321585) (xy 22.470854 -5.336952) (xy 22.416864 -5.344713) (xy 22.389592 -5.345176)
			(xy 22.37613 -5.344922) (xy 22.367246 -5.344972) (xy 22.350369 -5.35048) (xy 22.3364 -5.361438) (xy 22.331426 -5.368798)
			(xy 22.315577 -5.393512) (xy 22.280611 -5.44068) (xy 22.261576 -5.463032) (xy 22.254138 -5.472667)
			(xy 22.248292 -5.496257) (xy 22.2504 -5.508244) (xy 22.255355 -5.5302) (xy 22.260707 -5.574893) (xy 22.261068 -5.597398)
			(xy 22.261068 -5.597652) (xy 22.260814 -5.60832) (xy 22.261087 -5.619209) (xy 22.26963 -5.639219)
			(xy 22.277324 -5.646928) (xy 22.333966 -5.698998) (xy 22.342353 -5.705912) (xy 22.362998 -5.712636)
			(xy 22.373844 -5.711952) (xy 22.374352 -5.711952) (xy 22.385235 -5.710768) (xy 22.407093 -5.709497)
			(xy 22.41804 -5.709412) (xy 22.446855 -5.709921) (xy 22.503829 -5.718597) (xy 22.558854 -5.735729)
			(xy 22.610682 -5.760931) (xy 22.658138 -5.79363) (xy 22.700145 -5.833085) (xy 22.735751 -5.8784)
			(xy 22.764148 -5.928549) (xy 22.77491 -5.955284) (xy 22.77987 -5.966354) (xy 22.797917 -5.982517)
			(xy 22.809454 -5.986272) (xy 22.846546 -5.996509) (xy 22.918638 -6.023424) (xy 22.987654 -6.05746)
			(xy 23.020528 -6.077458) (xy 23.028784 -6.082172) (xy 23.047452 -6.085699) (xy 23.06612 -6.082172)
			(xy 23.074376 -6.077458) (xy 23.107251 -6.057462) (xy 23.17627 -6.023434) (xy 23.248358 -5.996508)
			(xy 23.28545 -5.986272) (xy 23.297006 -5.98255) (xy 23.315054 -5.966372) (xy 23.319994 -5.955284)
			(xy 23.330716 -5.92853) (xy 23.359106 -5.878371) (xy 23.394712 -5.833048) (xy 23.436723 -5.79359)
			(xy 23.484188 -5.760893) (xy 23.536027 -5.735701) (xy 23.591063 -5.718584) (xy 23.648046 -5.709932)
			(xy 23.676864 -5.709412) (xy 23.687684 -5.709512) (xy 23.709287 -5.710781) (xy 23.720044 -5.711952)
			(xy 23.730966 -5.713222) (xy 23.751794 -5.706364) (xy 23.816564 -5.646674) (xy 23.824196 -5.639002)
			(xy 23.832739 -5.619137) (xy 23.833074 -5.60832) (xy 23.833074 -5.608066) (xy 23.83282 -5.597398)
			(xy 23.83282 -5.59689) (xy 23.833164 -5.572356) (xy 23.83941 -5.523689) (xy 23.845266 -5.499862)
			(xy 23.84769 -5.487921) (xy 23.842376 -5.464176) (xy 23.835106 -5.454396) (xy 23.818263 -5.433961)
			(xy 23.787121 -5.391122) (xy 23.772876 -5.368798) (xy 23.76783 -5.361505) (xy 23.753872 -5.350587)
			(xy 23.737039 -5.345048) (xy 23.728172 -5.344922) (xy 23.71471 -5.345176) (xy 23.68744 -5.344685)
			(xy 23.633454 -5.336925) (xy 23.581122 -5.32156) (xy 23.531509 -5.298904) (xy 23.485626 -5.269417)
			(xy 23.444406 -5.233701) (xy 23.408689 -5.192482) (xy 23.379201 -5.1466) (xy 23.356544 -5.096988)
			(xy 23.341178 -5.044656) (xy 23.333415 -4.99067) (xy 23.333415 -4.93613) (xy 23.341178 -4.882144)
			(xy 23.356544 -4.829812) (xy 23.379201 -4.7802) (xy 23.408689 -4.734318) (xy 23.444406 -4.693099)
			(xy 23.485626 -4.657383) (xy 23.531509 -4.627896) (xy 23.581122 -4.60524) (xy 23.633454 -4.589875)
			(xy 23.68744 -4.582115) (xy 23.71471 -4.581652) (xy 23.728172 -4.581906) (xy 23.737055 -4.581845)
			(xy 23.75393 -4.576339) (xy 23.767901 -4.565388) (xy 23.772876 -4.55803) (xy 23.787116 -4.535702)
			(xy 23.818259 -4.492864) (xy 23.835106 -4.472432) (xy 23.842383 -4.462655) (xy 23.847696 -4.438909)
			(xy 23.845266 -4.426966) (xy 23.839442 -4.403133) (xy 23.8332 -4.354469) (xy 23.83282 -4.329938)
			(xy 23.83282 -4.32943) (xy 23.833329 -4.302161) (xy 23.841087 -4.248176) (xy 23.856448 -4.195846)
			(xy 23.879101 -4.146234) (xy 23.908584 -4.100351) (xy 23.944297 -4.059131) (xy 23.985512 -4.023413)
			(xy 24.031391 -3.993924) (xy 24.081 -3.971265) (xy 24.133329 -3.955897) (xy 24.187313 -3.948133)
			(xy 24.214582 -3.947668) (xy 24.24326 -3.948226) (xy 24.29997 -3.956811) (xy 24.35476 -3.973776)
			(xy 24.406398 -3.99874) (xy 24.453726 -4.031142) (xy 24.495678 -4.070253) (xy 24.531314 -4.115196)
			(xy 24.559831 -4.16496) (xy 24.57069 -4.191508) (xy 24.575743 -4.202653) (xy 24.594066 -4.218825)
			(xy 24.605742 -4.222496) (xy 24.644338 -4.232673) (xy 24.719335 -4.260005) (xy 24.791074 -4.295008)
			(xy 24.825198 -4.315714) (xy 24.833454 -4.320428) (xy 24.852122 -4.323955) (xy 24.87079 -4.320428)
			(xy 24.879046 -4.315714) (xy 24.911614 -4.295883) (xy 24.979971 -4.262085) (xy 25.051355 -4.235267)
			(xy 25.088088 -4.225036) (xy 25.09957 -4.221272) (xy 25.11747 -4.205091) (xy 25.122378 -4.194048)
			(xy 25.133104 -4.167257) (xy 25.161475 -4.117007) (xy 25.197082 -4.071595) (xy 25.239113 -4.032055)
			(xy 25.286614 -3.999287) (xy 25.338502 -3.974035) (xy 25.393598 -3.956874) (xy 25.450649 -3.948195)
			(xy 25.479502 -3.947668) (xy 25.506774 -3.9481) (xy 25.560764 -3.955863) (xy 25.613099 -3.971231)
			(xy 25.662714 -3.993891) (xy 25.708599 -4.023382) (xy 25.74982 -4.059102) (xy 25.785538 -4.100326)
			(xy 25.815024 -4.146214) (xy 25.83768 -4.195831) (xy 25.853044 -4.248167) (xy 25.860803 -4.302158)
			(xy 25.861264 -4.32943) (xy 25.861264 -4.330192) (xy 25.860889 -4.352571) (xy 25.855541 -4.397009)
			(xy 25.850596 -4.418838) (xy 25.84842 -4.430826) (xy 25.854274 -4.454444) (xy 25.861772 -4.46405)
			(xy 25.880728 -4.486352) (xy 25.915564 -4.533394) (xy 25.931368 -4.55803) (xy 25.936407 -4.56533)
			(xy 25.950366 -4.576252) (xy 25.967203 -4.581786) (xy 25.976072 -4.581906) (xy 25.989534 -4.581652)
			(xy 26.016803 -4.582113) (xy 26.070785 -4.589879) (xy 26.123112 -4.605248) (xy 26.17272 -4.627906)
			(xy 26.218598 -4.657394) (xy 26.259813 -4.693111) (xy 26.295526 -4.734329) (xy 26.32501 -4.78021)
			(xy 26.347664 -4.82982) (xy 26.363029 -4.882149) (xy 26.37079 -4.936131) (xy 26.37079 -4.990669)
			(xy 26.363029 -5.044651) (xy 26.347664 -5.09698) (xy 26.32501 -5.14659) (xy 26.295526 -5.192471)
			(xy 26.259813 -5.233689) (xy 26.218598 -5.269406) (xy 26.17272 -5.298894) (xy 26.123112 -5.321552)
			(xy 26.070785 -5.336921) (xy 26.016803 -5.344687) (xy 25.989534 -5.345176) (xy 25.976072 -5.344922)
			(xy 25.967186 -5.34493) (xy 25.950306 -5.350457) (xy 25.936339 -5.361431) (xy 25.931368 -5.368798)
			(xy 25.915572 -5.39344) (xy 25.880735 -5.440481) (xy 25.861772 -5.462778) (xy 25.854307 -5.472396)
			(xy 25.848478 -5.496) (xy 25.850596 -5.50799) (xy 25.855535 -5.52982) (xy 25.860884 -5.574258) (xy 25.861264 -5.596636)
			(xy 25.861264 -5.597398) (xy 25.86101 -5.608066) (xy 25.86101 -5.60832) (xy 25.861295 -5.619147)
			(xy 25.869856 -5.63902) (xy 25.87752 -5.646674) (xy 25.934162 -5.698998) (xy 25.94255 -5.70591) (xy 25.963194 -5.712636)
			(xy 25.97404 -5.711952) (xy 25.974548 -5.711952) (xy 25.985304 -5.710775) (xy 26.006908 -5.709507)
			(xy 26.017728 -5.709412) (xy 26.017982 -5.709412) (xy 26.046798 -5.709885) (xy 26.103774 -5.718566)
			(xy 26.1588 -5.735705) (xy 26.210628 -5.760912) (xy 26.258084 -5.793616) (xy 26.30009 -5.833075)
			(xy 26.335695 -5.878395) (xy 26.364091 -5.928547) (xy 26.374852 -5.955284) (xy 26.37984 -5.966337)
			(xy 26.397868 -5.982508) (xy 26.409396 -5.986272) (xy 26.446491 -5.9965) (xy 26.518582 -6.023419)
			(xy 26.587597 -6.057458) (xy 26.62047 -6.077458) (xy 26.628726 -6.082172) (xy 26.647394 -6.085699)
			(xy 26.666062 -6.082172) (xy 26.674318 -6.077458) (xy 26.7072 -6.057474) (xy 26.776216 -6.023441)
			(xy 26.848301 -5.996511) (xy 26.885392 -5.986272) (xy 26.896955 -5.982568) (xy 26.914999 -5.966377)
			(xy 26.919936 -5.955284) (xy 26.930706 -5.928551) (xy 26.959091 -5.878394) (xy 26.99469 -5.833072)
			(xy 27.036695 -5.793613) (xy 27.084152 -5.760914) (xy 27.135984 -5.735718) (xy 27.191013 -5.718596)
			(xy 27.24799 -5.709937) (xy 27.276806 -5.709412) (xy 27.287626 -5.709509) (xy 27.309229 -5.71078)
			(xy 27.319986 -5.711952) (xy 27.330908 -5.713222) (xy 27.351736 -5.706364) (xy 27.416506 -5.646674)
			(xy 27.424129 -5.638994) (xy 27.432679 -5.619136) (xy 27.433016 -5.60832) (xy 27.433016 -5.608066)
			(xy 27.432762 -5.597398) (xy 27.432762 -5.59689) (xy 27.433108 -5.572356) (xy 27.439353 -5.523689)
			(xy 27.445208 -5.499862) (xy 27.447623 -5.48792) (xy 27.442313 -5.464177) (xy 27.435048 -5.454396)
			(xy 27.418207 -5.433959) (xy 27.387064 -5.391122) (xy 27.372818 -5.368798) (xy 27.367807 -5.361477)
			(xy 27.353833 -5.350565) (xy 27.336986 -5.345039) (xy 27.328114 -5.344922) (xy 27.314652 -5.345176)
			(xy 27.287386 -5.344658) (xy 27.233409 -5.336891) (xy 27.181088 -5.321522) (xy 27.131485 -5.298864)
			(xy 27.085612 -5.269378) (xy 27.044402 -5.233664) (xy 27.008693 -5.192449) (xy 26.979213 -5.146573)
			(xy 26.956561 -5.096967) (xy 26.941198 -5.044644) (xy 26.933438 -4.990666) (xy 26.933438 -4.936134)
			(xy 26.941198 -4.882156) (xy 26.956561 -4.829833) (xy 26.979213 -4.780227) (xy 27.008693 -4.734351)
			(xy 27.044402 -4.693136) (xy 27.085612 -4.657422) (xy 27.131485 -4.627936) (xy 27.181088 -4.605278)
			(xy 27.233409 -4.589909) (xy 27.287386 -4.582142) (xy 27.314652 -4.581652) (xy 27.328114 -4.581906)
			(xy 27.336998 -4.581875) (xy 27.353876 -4.576356) (xy 27.367844 -4.565392) (xy 27.372818 -4.55803)
			(xy 27.387061 -4.535704) (xy 27.418202 -4.492865) (xy 27.435048 -4.472432) (xy 27.442321 -4.462652)
			(xy 27.447639 -4.438908) (xy 27.445208 -4.426966) (xy 27.439383 -4.403133) (xy 27.433142 -4.354469)
			(xy 27.432762 -4.329938) (xy 27.432762 -4.32943) (xy 27.433229 -4.302159) (xy 27.440988 -4.248171)
			(xy 27.456352 -4.195837) (xy 27.479008 -4.146222) (xy 27.508494 -4.100337) (xy 27.544212 -4.059116)
			(xy 27.585432 -4.023398) (xy 27.631317 -3.993911) (xy 27.680931 -3.971254) (xy 27.733265 -3.955889)
			(xy 27.787253 -3.94813) (xy 27.814524 -3.947668) (xy 27.843203 -3.94819) (xy 27.899915 -3.956781)
			(xy 27.954706 -3.973752) (xy 28.006345 -3.998721) (xy 28.053672 -4.031127) (xy 28.095623 -4.070244)
			(xy 28.131258 -4.11519) (xy 28.159774 -4.164958) (xy 28.170632 -4.191508) (xy 28.175713 -4.202637)
			(xy 28.194017 -4.218816) (xy 28.205684 -4.222496) (xy 28.244276 -4.232686) (xy 28.319274 -4.260013)
			(xy 28.391015 -4.29501) (xy 28.42514 -4.315714) (xy 28.433396 -4.320428) (xy 28.452064 -4.323955)
			(xy 28.470732 -4.320428) (xy 28.478988 -4.315714) (xy 28.511563 -4.295895) (xy 28.579917 -4.262092)
			(xy 28.651299 -4.235269) (xy 28.68803 -4.225036) (xy 28.699502 -4.221247) (xy 28.717408 -4.205084)
			(xy 28.72232 -4.194048) (xy 28.733011 -4.167242) (xy 28.761386 -4.11699) (xy 28.796998 -4.071578)
			(xy 28.839034 -4.032038) (xy 28.88654 -3.999271) (xy 28.938433 -3.974022) (xy 28.993534 -3.956866)
			(xy 29.050589 -3.948192) (xy 29.079444 -3.947668) (xy 29.106716 -3.948084) (xy 29.160704 -3.955852)
			(xy 29.213036 -3.971224) (xy 29.262649 -3.993888) (xy 29.308531 -4.023381) (xy 29.349749 -4.059104)
			(xy 29.385463 -4.100329) (xy 29.414948 -4.146217) (xy 29.437601 -4.195833) (xy 29.452964 -4.248169)
			(xy 29.460722 -4.302158) (xy 29.461206 -4.32943) (xy 29.461206 -4.330192) (xy 29.46083 -4.352571)
			(xy 29.455483 -4.397009) (xy 29.450538 -4.418838) (xy 29.448352 -4.430826) (xy 29.454211 -4.454445)
			(xy 29.461714 -4.46405) (xy 29.480672 -4.48635) (xy 29.515507 -4.533393) (xy 29.53131 -4.55803) (xy 29.536324 -4.56535)
			(xy 29.550294 -4.576268) (xy 29.567141 -4.581793) (xy 29.576014 -4.581906) (xy 29.589476 -4.581652)
			(xy 29.616749 -4.582086) (xy 29.670741 -4.589846) (xy 29.723078 -4.60521) (xy 29.772696 -4.627867)
			(xy 29.818584 -4.657355) (xy 29.859809 -4.693074) (xy 29.89553 -4.734296) (xy 29.925021 -4.780183)
			(xy 29.947681 -4.829799) (xy 29.963049 -4.882136) (xy 29.970812 -4.936127) (xy 29.970812 -4.990673)
			(xy 29.963049 -5.044664) (xy 29.947681 -5.097001) (xy 29.925021 -5.146617) (xy 29.89553 -5.192504)
			(xy 29.859809 -5.233726) (xy 29.818584 -5.269445) (xy 29.772696 -5.298933) (xy 29.723078 -5.32159)
			(xy 29.670741 -5.336954) (xy 29.616749 -5.344714) (xy 29.589476 -5.345176) (xy 29.576014 -5.344922)
			(xy 29.56713 -5.34496) (xy 29.550251 -5.350474) (xy 29.536283 -5.361435) (xy 29.53131 -5.368798)
			(xy 29.515512 -5.393438) (xy 29.480676 -5.440481) (xy 29.461714 -5.462778) (xy 29.454252 -5.472398)
			(xy 29.448419 -5.496001) (xy 29.450538 -5.50799) (xy 29.4555 -5.529945) (xy 29.460848 -5.574638)
			(xy 29.461206 -5.597144) (xy 29.461206 -5.597652) (xy 29.460952 -5.60832) (xy 29.461214 -5.619211)
			(xy 29.469764 -5.639221) (xy 29.477462 -5.646928) (xy 29.534104 -5.698998) (xy 29.542477 -5.705932)
			(xy 29.563133 -5.712644) (xy 29.573982 -5.711952) (xy 29.57449 -5.711952) (xy 29.585373 -5.710764)
			(xy 29.607231 -5.709496) (xy 29.618178 -5.709412) (xy 29.646994 -5.709888) (xy 29.70397 -5.718569)
			(xy 29.758995 -5.735707) (xy 29.810824 -5.760914) (xy 29.858279 -5.793617) (xy 29.900286 -5.833076)
			(xy 29.935891 -5.878395) (xy 29.964287 -5.928547) (xy 29.975048 -5.955284) (xy 29.980038 -5.966336)
			(xy 29.998065 -5.982507) (xy 30.009592 -5.986272) (xy 30.046687 -5.996501) (xy 30.118778 -6.023419)
			(xy 30.187793 -6.057458) (xy 30.220666 -6.077458) (xy 30.228922 -6.082172) (xy 30.24759 -6.085699)
			(xy 30.266258 -6.082172) (xy 30.274514 -6.077458) (xy 30.307396 -6.057474) (xy 30.376413 -6.023442)
			(xy 30.448497 -5.996511) (xy 30.485588 -5.986272) (xy 30.49715 -5.982567) (xy 30.515195 -5.966377)
			(xy 30.520132 -5.955284) (xy 30.530906 -5.928553) (xy 30.55929 -5.878396) (xy 30.594888 -5.833074)
			(xy 30.636893 -5.793615) (xy 30.684349 -5.760916) (xy 30.736181 -5.735719) (xy 30.791209 -5.718596)
			(xy 30.848186 -5.709937) (xy 30.877002 -5.709412) (xy 30.877256 -5.709412) (xy 30.88814 -5.709508)
			(xy 30.90987 -5.710777) (xy 30.92069 -5.711952) (xy 30.920944 -5.711952) (xy 30.931795 -5.712656)
			(xy 30.952457 -5.705945) (xy 30.960822 -5.698998) (xy 31.017464 -5.646674) (xy 31.025096 -5.639002)
			(xy 31.033639 -5.619137) (xy 31.033974 -5.60832) (xy 31.033974 -5.608066) (xy 31.03372 -5.597398)
			(xy 31.03372 -5.59689) (xy 31.034129 -5.572549) (xy 31.040367 -5.524268) (xy 31.046166 -5.500624)
			(xy 31.048485 -5.488652) (xy 31.043061 -5.464917) (xy 31.035752 -5.455158) (xy 31.018754 -5.434553)
			(xy 30.987355 -5.391333) (xy 30.973014 -5.368798) (xy 30.968005 -5.361475) (xy 30.95403 -5.350563)
			(xy 30.937182 -5.345038) (xy 30.92831 -5.344922) (xy 30.914848 -5.345176) (xy 30.887576 -5.344688)
			(xy 30.833586 -5.336932) (xy 30.781249 -5.32157) (xy 30.731632 -5.298916) (xy 30.685744 -5.269431)
			(xy 30.644519 -5.233715) (xy 30.608798 -5.192495) (xy 30.579307 -5.14661) (xy 30.556647 -5.096996)
			(xy 30.541279 -5.044661) (xy 30.533516 -4.990672) (xy 30.533516 -4.936128) (xy 30.541279 -4.882139)
			(xy 30.556647 -4.829804) (xy 30.579307 -4.78019) (xy 30.608798 -4.734305) (xy 30.644519 -4.693085)
			(xy 30.685744 -4.657369) (xy 30.731632 -4.627884) (xy 30.781249 -4.60523) (xy 30.833586 -4.589868)
			(xy 30.887576 -4.582112) (xy 30.914848 -4.581652) (xy 30.92831 -4.581906) (xy 30.937194 -4.581872)
			(xy 30.954071 -4.576354) (xy 30.96804 -4.565392) (xy 30.973014 -4.55803) (xy 30.987363 -4.5355) (xy 31.018763 -4.492283)
			(xy 31.035752 -4.47167) (xy 31.043099 -4.461927) (xy 31.048535 -4.438175) (xy 31.046166 -4.426204)
			(xy 31.040385 -4.402557) (xy 31.034139 -4.354278) (xy 31.03372 -4.329938) (xy 31.03372 -4.32943)
			(xy 31.034229 -4.302161) (xy 31.041987 -4.248176) (xy 31.057348 -4.195846) (xy 31.080001 -4.146234)
			(xy 31.109484 -4.100351) (xy 31.145197 -4.059131) (xy 31.186412 -4.023413) (xy 31.232291 -3.993924)
			(xy 31.2819 -3.971265) (xy 31.334229 -3.955897) (xy 31.388213 -3.948133) (xy 31.415482 -3.947668)
			(xy 31.44416 -3.948226) (xy 31.50087 -3.956811) (xy 31.55566 -3.973776) (xy 31.607298 -3.99874) (xy 31.654626 -4.031142)
			(xy 31.696578 -4.070253) (xy 31.732214 -4.115196) (xy 31.760731 -4.16496) (xy 31.77159 -4.191508)
			(xy 31.776488 -4.202765) (xy 31.794873 -4.218998) (xy 31.806642 -4.222496) (xy 31.845103 -4.232719)
			(xy 31.919839 -4.260073) (xy 31.99133 -4.295043) (xy 32.025336 -4.315714) (xy 32.033591 -4.320416)
			(xy 32.052227 -4.324018) (xy 32.0709 -4.320614) (xy 32.079184 -4.315968) (xy 32.111824 -4.296072)
			(xy 32.180345 -4.262174) (xy 32.251908 -4.235288) (xy 32.288734 -4.225036) (xy 32.300294 -4.221324)
			(xy 32.318342 -4.20514) (xy 32.323278 -4.194048) (xy 32.334004 -4.167257) (xy 32.362375 -4.117007)
			(xy 32.397982 -4.071595) (xy 32.440013 -4.032055) (xy 32.487514 -3.999287) (xy 32.539402 -3.974035)
			(xy 32.594498 -3.956874) (xy 32.651549 -3.948195) (xy 32.680402 -3.947668) (xy 32.707674 -3.9481)
			(xy 32.761664 -3.955863) (xy 32.813999 -3.971231) (xy 32.863614 -3.993891) (xy 32.909499 -4.023382)
			(xy 32.95072 -4.059102) (xy 32.986438 -4.100326) (xy 33.015924 -4.146214) (xy 33.03858 -4.195831)
			(xy 33.053944 -4.248167) (xy 33.061703 -4.302158) (xy 33.062164 -4.32943) (xy 33.062164 -4.329684)
			(xy 33.06185 -4.352318) (xy 33.0565 -4.39727) (xy 33.051496 -4.419346) (xy 33.04925 -4.431308) (xy 33.054971 -4.454929)
			(xy 33.062418 -4.464558) (xy 33.081235 -4.486744) (xy 33.115815 -4.533533) (xy 33.131506 -4.55803)
			(xy 33.136522 -4.565348) (xy 33.150491 -4.576267) (xy 33.167338 -4.581792) (xy 33.17621 -4.581906)
			(xy 33.189672 -4.581652) (xy 33.216945 -4.582086) (xy 33.270937 -4.589845) (xy 33.323275 -4.605209)
			(xy 33.372894 -4.627866) (xy 33.418782 -4.657354) (xy 33.460007 -4.693073) (xy 33.495729 -4.734295)
			(xy 33.525221 -4.780182) (xy 33.547881 -4.829799) (xy 33.563249 -4.882135) (xy 33.571012 -4.936127)
			(xy 33.571012 -4.990673) (xy 33.563249 -5.044665) (xy 33.547881 -5.097001) (xy 33.525221 -5.146618)
			(xy 33.495729 -5.192505) (xy 33.460007 -5.233727) (xy 33.418782 -5.269446) (xy 33.372894 -5.298934)
			(xy 33.323275 -5.321591) (xy 33.270937 -5.336955) (xy 33.216945 -5.344714) (xy 33.189672 -5.345176)
			(xy 33.17621 -5.344922) (xy 33.167325 -5.344957) (xy 33.150447 -5.350472) (xy 33.136479 -5.361435)
			(xy 33.131506 -5.368798) (xy 33.115819 -5.393297) (xy 33.081233 -5.440082) (xy 33.062418 -5.46227)
			(xy 33.054994 -5.471903) (xy 33.049306 -5.495517) (xy 33.051496 -5.507482) (xy 33.056478 -5.529562)
			(xy 33.061828 -5.574511) (xy 33.062164 -5.597144) (xy 33.062164 -5.597398) (xy 33.061674 -5.624667)
			(xy 33.053912 -5.678651) (xy 33.038547 -5.73098) (xy 33.015892 -5.78059) (xy 32.986406 -5.826471)
			(xy 32.950691 -5.867688) (xy 32.909474 -5.903404) (xy 32.863593 -5.93289) (xy 32.813984 -5.955546)
			(xy 32.761655 -5.970912) (xy 32.707671 -5.978673) (xy 32.680402 -5.97916) (xy 32.651551 -5.9786)
			(xy 32.594504 -5.969923) (xy 32.539411 -5.952764) (xy 32.487526 -5.927516) (xy 32.440028 -5.894751)
			(xy 32.397997 -5.855215) (xy 32.362391 -5.809809) (xy 32.334018 -5.759563) (xy 32.323278 -5.73278)
			(xy 32.318301 -5.721719) (xy 32.300267 -5.705549) (xy 32.288734 -5.701792) (xy 32.251903 -5.691556)
			(xy 32.18034 -5.664668) (xy 32.111823 -5.630759) (xy 32.079184 -5.61086) (xy 32.070921 -5.606153)
			(xy 32.052226 -5.602724) (xy 32.03357 -5.606353) (xy 32.025336 -5.611114) (xy 31.991332 -5.63179)
			(xy 31.919845 -5.666771) (xy 31.845106 -5.694122) (xy 31.806642 -5.704332) (xy 31.794981 -5.708029)
			(xy 31.776675 -5.724196) (xy 31.77159 -5.73532) (xy 31.760705 -5.76186) (xy 31.732208 -5.811642)
			(xy 31.696586 -5.856601) (xy 31.654641 -5.895726) (xy 31.607315 -5.928138) (xy 31.555673 -5.953106)
			(xy 31.500878 -5.97007) (xy 31.444162 -5.978646) (xy 31.415482 -5.97916) (xy 31.415228 -5.97916)
			(xy 31.404344 -5.979066) (xy 31.382614 -5.977796) (xy 31.371794 -5.97662) (xy 31.37154 -5.97662)
			(xy 31.360688 -5.975889) (xy 31.340024 -5.982616) (xy 31.331662 -5.989574) (xy 31.27502 -6.041898)
			(xy 31.267398 -6.049579) (xy 31.25885 -6.069437) (xy 31.25851 -6.080252) (xy 31.25851 -6.080506)
			(xy 31.258764 -6.09092) (xy 31.258764 -6.091428) (xy 31.258256 -6.110224) (xy 31.257748 -6.121146)
			(xy 31.265368 -6.140958) (xy 31.334202 -6.210046) (xy 31.354268 -6.217412) (xy 31.36519 -6.216904)
			(xy 31.384748 -6.216396) (xy 31.385002 -6.216396) (xy 31.41227 -6.216922) (xy 31.466249 -6.224683)
			(xy 31.518576 -6.240047) (xy 31.568183 -6.2627) (xy 31.614062 -6.292182) (xy 31.655278 -6.327893)
			(xy 31.690994 -6.369106) (xy 31.720481 -6.414982) (xy 31.743139 -6.464587) (xy 31.758508 -6.516911)
			(xy 31.766275 -6.570891) (xy 31.766764 -6.598158) (xy 37.83838 -6.598158) (xy 37.838786 -6.570886)
			(xy 37.846554 -6.516897) (xy 37.861927 -6.464563) (xy 37.884591 -6.41495) (xy 37.914085 -6.369068)
			(xy 37.949809 -6.327849) (xy 37.991035 -6.292135) (xy 38.036924 -6.262651) (xy 38.086542 -6.239997)
			(xy 38.138879 -6.224636) (xy 38.19287 -6.21688) (xy 38.220142 -6.216396) (xy 38.220396 -6.216396)
			(xy 38.239954 -6.216904) (xy 38.250876 -6.217412) (xy 38.270942 -6.210046) (xy 38.339776 -6.140958)
			(xy 38.347396 -6.121146) (xy 38.346888 -6.110224) (xy 38.34638 -6.091174) (xy 38.346777 -6.0639)
			(xy 38.354544 -6.009909) (xy 38.369916 -5.957573) (xy 38.39258 -5.907957) (xy 38.422074 -5.862071)
			(xy 38.457798 -5.82085) (xy 38.499025 -5.785133) (xy 38.544916 -5.755647) (xy 38.594536 -5.732992)
			(xy 38.646876 -5.71763) (xy 38.700868 -5.709873) (xy 38.728142 -5.709412) (xy 38.756957 -5.709919)
			(xy 38.813931 -5.718595) (xy 38.868956 -5.735728) (xy 38.920784 -5.76093) (xy 38.96824 -5.793629)
			(xy 39.010248 -5.833084) (xy 39.045853 -5.8784) (xy 39.07425 -5.928548) (xy 39.085012 -5.955284)
			(xy 39.089971 -5.966354) (xy 39.108019 -5.982518) (xy 39.119556 -5.986272) (xy 39.156649 -5.996509)
			(xy 39.22874 -6.023424) (xy 39.297756 -6.05746) (xy 39.33063 -6.077458) (xy 39.338886 -6.082172)
			(xy 39.357554 -6.085699) (xy 39.376222 -6.082172) (xy 39.384478 -6.077458) (xy 39.417353 -6.057462)
			(xy 39.486372 -6.023434) (xy 39.55846 -5.996508) (xy 39.595552 -5.986272) (xy 39.607108 -5.98255)
			(xy 39.625156 -5.966373) (xy 39.630096 -5.955284) (xy 39.640816 -5.92853) (xy 39.669207 -5.87837)
			(xy 39.704812 -5.833047) (xy 39.746824 -5.793589) (xy 39.794289 -5.760893) (xy 39.846128 -5.7357)
			(xy 39.901164 -5.718584) (xy 39.958148 -5.709932) (xy 39.986966 -5.709412) (xy 39.997722 -5.709514)
			(xy 40.019198 -5.710787) (xy 40.029892 -5.711952) (xy 40.040814 -5.713222) (xy 40.061642 -5.706364)
			(xy 40.126412 -5.646674) (xy 40.134036 -5.638995) (xy 40.142585 -5.619136) (xy 40.142922 -5.60832)
			(xy 40.142922 -5.608066) (xy 40.142668 -5.597652) (xy 40.142668 -5.597398) (xy 40.143057 -5.572667)
			(xy 40.149429 -5.523618) (xy 40.155368 -5.499608) (xy 40.158016 -5.487607) (xy 40.152686 -5.463641)
			(xy 40.145208 -5.453888) (xy 40.128369 -5.433582) (xy 40.097227 -5.390998) (xy 40.082978 -5.368798)
			(xy 40.07793 -5.361506) (xy 40.063973 -5.350588) (xy 40.047141 -5.345049) (xy 40.038274 -5.344922)
			(xy 40.024812 -5.345176) (xy 39.997541 -5.344685) (xy 39.943555 -5.336925) (xy 39.891223 -5.32156)
			(xy 39.84161 -5.298904) (xy 39.795727 -5.269418) (xy 39.754507 -5.233702) (xy 39.718789 -5.192483)
			(xy 39.689302 -5.1466) (xy 39.666644 -5.096988) (xy 39.651278 -5.044656) (xy 39.643515 -4.990671)
			(xy 39.643515 -4.936129) (xy 39.651278 -4.882144) (xy 39.666644 -4.829812) (xy 39.689302 -4.7802)
			(xy 39.718789 -4.734317) (xy 39.754507 -4.693098) (xy 39.795727 -4.657382) (xy 39.84161 -4.627896)
			(xy 39.891223 -4.60524) (xy 39.943555 -4.589875) (xy 39.997541 -4.582115) (xy 40.024812 -4.581652)
			(xy 40.038274 -4.581906) (xy 40.047157 -4.581847) (xy 40.064033 -4.57634) (xy 40.078003 -4.565388)
			(xy 40.082978 -4.55803) (xy 40.097239 -4.535838) (xy 40.128382 -4.493255) (xy 40.145208 -4.47294)
			(xy 40.152494 -4.463097) (xy 40.157797 -4.439224) (xy 40.155368 -4.42722) (xy 40.149448 -4.4034)
			(xy 40.143078 -4.354733) (xy 40.142668 -4.330192) (xy 40.142668 -4.32943) (xy 40.143129 -4.302158)
			(xy 40.150888 -4.24817) (xy 40.166252 -4.195835) (xy 40.188909 -4.14622) (xy 40.218396 -4.100335)
			(xy 40.254114 -4.059114) (xy 40.295335 -4.023396) (xy 40.34122 -3.993909) (xy 40.390835 -3.971252)
			(xy 40.44317 -3.955888) (xy 40.497158 -3.948129) (xy 40.52443 -3.947668) (xy 40.553109 -3.948184)
			(xy 40.609821 -3.956777) (xy 40.664612 -3.973748) (xy 40.716251 -3.998718) (xy 40.763578 -4.031126)
			(xy 40.80553 -4.070242) (xy 40.841164 -4.11519) (xy 40.86968 -4.164958) (xy 40.880538 -4.191508)
			(xy 40.885617 -4.202638) (xy 40.903922 -4.218816) (xy 40.91559 -4.222496) (xy 40.954234 -4.232708)
			(xy 41.029323 -4.260115) (xy 41.101142 -4.29521) (xy 41.1353 -4.315968) (xy 41.143561 -4.320664)
			(xy 41.162224 -4.324172) (xy 41.180887 -4.320664) (xy 41.189148 -4.315968) (xy 41.221638 -4.296161)
			(xy 41.289828 -4.26238) (xy 41.36104 -4.235552) (xy 41.397682 -4.22529) (xy 41.409239 -4.221573)
			(xy 41.427285 -4.205391) (xy 41.432226 -4.194302) (xy 41.442954 -4.1675) (xy 41.471295 -4.117207)
			(xy 41.506882 -4.071752) (xy 41.548905 -4.032171) (xy 41.596407 -3.999365) (xy 41.648304 -3.974081)
			(xy 41.703416 -3.956896) (xy 41.760486 -3.9482) (xy 41.78935 -3.947668) (xy 41.816622 -3.948078)
			(xy 41.87061 -3.955847) (xy 41.922943 -3.97122) (xy 41.972555 -3.993885) (xy 42.018437 -4.023379)
			(xy 42.059655 -4.059102) (xy 42.095369 -4.100327) (xy 42.124854 -4.146215) (xy 42.147507 -4.195832)
			(xy 42.16287 -4.248168) (xy 42.170628 -4.302158) (xy 42.171112 -4.32943) (xy 42.171112 -4.329684)
			(xy 42.170756 -4.352127) (xy 42.165403 -4.396693) (xy 42.160444 -4.418584) (xy 42.158317 -4.430577)
			(xy 42.16414 -4.454186) (xy 42.17162 -4.463796) (xy 42.190646 -4.486155) (xy 42.225613 -4.533322)
			(xy 42.24147 -4.55803) (xy 42.246508 -4.565331) (xy 42.260467 -4.576253) (xy 42.277305 -4.581786)
			(xy 42.286174 -4.581906) (xy 42.299636 -4.581652) (xy 42.326905 -4.582113) (xy 42.380886 -4.589879)
			(xy 42.433214 -4.605248) (xy 42.482821 -4.627907) (xy 42.528699 -4.657395) (xy 42.569914 -4.693112)
			(xy 42.605627 -4.73433) (xy 42.63511 -4.780211) (xy 42.657765 -4.82982) (xy 42.673129 -4.882149)
			(xy 42.68089 -4.936131) (xy 42.68089 -4.990669) (xy 42.673129 -5.044651) (xy 42.657765 -5.09698)
			(xy 42.63511 -5.146589) (xy 42.605627 -5.19247) (xy 42.569914 -5.233688) (xy 42.528699 -5.269405)
			(xy 42.482821 -5.298893) (xy 42.433213 -5.321552) (xy 42.380886 -5.336921) (xy 42.326905 -5.344687)
			(xy 42.299636 -5.345176) (xy 42.286174 -5.344922) (xy 42.277288 -5.344932) (xy 42.260408 -5.350458)
			(xy 42.246441 -5.361431) (xy 42.24147 -5.368798) (xy 42.225619 -5.39351) (xy 42.190654 -5.440679)
			(xy 42.17162 -5.463032) (xy 42.164186 -5.47267) (xy 42.158336 -5.496258) (xy 42.160444 -5.508244)
			(xy 42.165398 -5.5302) (xy 42.170751 -5.574893) (xy 42.171112 -5.597398) (xy 42.171112 -5.597652)
			(xy 42.170858 -5.60832) (xy 42.171118 -5.619211) (xy 42.179669 -5.639222) (xy 42.187368 -5.646928)
			(xy 42.24401 -5.698998) (xy 42.252381 -5.705935) (xy 42.273038 -5.712646) (xy 42.283888 -5.711952)
			(xy 42.284396 -5.711952) (xy 42.295279 -5.710764) (xy 42.317137 -5.709496) (xy 42.328084 -5.709412)
			(xy 42.3569 -5.709883) (xy 42.413876 -5.718565) (xy 42.468902 -5.735704) (xy 42.52073 -5.760911)
			(xy 42.568186 -5.793615) (xy 42.610192 -5.833075) (xy 42.645797 -5.878394) (xy 42.674193 -5.928547)
			(xy 42.684954 -5.955284) (xy 42.689941 -5.966338) (xy 42.70797 -5.982508) (xy 42.719498 -5.986272)
			(xy 42.756593 -5.9965) (xy 42.828684 -6.023419) (xy 42.897699 -6.057458) (xy 42.930572 -6.077458)
			(xy 42.938828 -6.082172) (xy 42.957496 -6.085699) (xy 42.976164 -6.082172) (xy 42.98442 -6.077458)
			(xy 43.017302 -6.057473) (xy 43.086318 -6.023441) (xy 43.158403 -5.996511) (xy 43.195494 -5.986272)
			(xy 43.207057 -5.982569) (xy 43.225101 -5.966377) (xy 43.230038 -5.955284) (xy 43.240807 -5.92855)
			(xy 43.269191 -5.878393) (xy 43.30479 -5.833071) (xy 43.346796 -5.793612) (xy 43.394253 -5.760914)
			(xy 43.446085 -5.735717) (xy 43.501115 -5.718595) (xy 43.558092 -5.709937) (xy 43.586908 -5.709412)
			(xy 43.597728 -5.709509) (xy 43.619331 -5.71078) (xy 43.630088 -5.711952) (xy 43.64101 -5.713222)
			(xy 43.661838 -5.706364) (xy 43.726608 -5.646674) (xy 43.734232 -5.638994) (xy 43.742781 -5.619136)
			(xy 43.743118 -5.60832) (xy 43.743118 -5.608066) (xy 43.742864 -5.597398) (xy 43.742864 -5.59689)
			(xy 43.74321 -5.572356) (xy 43.749455 -5.523689) (xy 43.75531 -5.499862) (xy 43.757724 -5.48792)
			(xy 43.752415 -5.464177) (xy 43.74515 -5.454396) (xy 43.728309 -5.433959) (xy 43.697166 -5.391122)
			(xy 43.68292 -5.368798) (xy 43.677908 -5.361478) (xy 43.663934 -5.350566) (xy 43.647088 -5.345039)
			(xy 43.638216 -5.344922) (xy 43.624754 -5.345176) (xy 43.597488 -5.344658) (xy 43.543511 -5.336892)
			(xy 43.491189 -5.321523) (xy 43.441586 -5.298865) (xy 43.395713 -5.269379) (xy 43.354502 -5.233665)
			(xy 43.318793 -5.19245) (xy 43.289313 -5.146573) (xy 43.266661 -5.096968) (xy 43.251298 -5.044644)
			(xy 43.243538 -4.990666) (xy 43.243538 -4.936134) (xy 43.251298 -4.882156) (xy 43.266661 -4.829832)
			(xy 43.289313 -4.780227) (xy 43.318793 -4.73435) (xy 43.354502 -4.693135) (xy 43.395713 -4.657421)
			(xy 43.441586 -4.627935) (xy 43.491189 -4.605277) (xy 43.543511 -4.589908) (xy 43.597488 -4.582142)
			(xy 43.624754 -4.581652) (xy 43.638216 -4.581906) (xy 43.647101 -4.581876) (xy 43.663978 -4.576356)
			(xy 43.677946 -4.565393) (xy 43.68292 -4.55803) (xy 43.697163 -4.535704) (xy 43.728304 -4.492865)
			(xy 43.74515 -4.472432) (xy 43.752423 -4.462652) (xy 43.75774 -4.438908) (xy 43.75531 -4.426966)
			(xy 43.749485 -4.403133) (xy 43.743244 -4.354469) (xy 43.742864 -4.329938) (xy 43.742864 -4.32943)
			(xy 43.743329 -4.302159) (xy 43.751088 -4.24817) (xy 43.766452 -4.195836) (xy 43.789108 -4.146221)
			(xy 43.818595 -4.100336) (xy 43.854312 -4.059115) (xy 43.895533 -4.023397) (xy 43.941418 -3.99391)
			(xy 43.991032 -3.971253) (xy 44.043366 -3.955889) (xy 44.097355 -3.94813) (xy 44.124626 -3.947668)
			(xy 44.153305 -3.948188) (xy 44.210017 -3.956779) (xy 44.264808 -3.97375) (xy 44.316447 -3.99872)
			(xy 44.363774 -4.031127) (xy 44.405726 -4.070243) (xy 44.44136 -4.11519) (xy 44.469876 -4.164958)
			(xy 44.480734 -4.191508) (xy 44.485814 -4.202637) (xy 44.504118 -4.218816) (xy 44.515786 -4.222496)
			(xy 44.554378 -4.232686) (xy 44.629376 -4.260013) (xy 44.701117 -4.29501) (xy 44.735242 -4.315714)
			(xy 44.743498 -4.320428) (xy 44.762166 -4.323955) (xy 44.780834 -4.320428) (xy 44.78909 -4.315714)
			(xy 44.821665 -4.295895) (xy 44.890019 -4.262092) (xy 44.9614 -4.235269) (xy 44.998132 -4.225036)
			(xy 45.009604 -4.221247) (xy 45.027511 -4.205085) (xy 45.032422 -4.194048) (xy 45.043111 -4.167242)
			(xy 45.071487 -4.116989) (xy 45.107098 -4.071577) (xy 45.149135 -4.032037) (xy 45.196641 -3.999271)
			(xy 45.248535 -3.974022) (xy 45.303636 -3.956866) (xy 45.360691 -3.948192) (xy 45.389546 -3.947668)
			(xy 45.416818 -3.948082) (xy 45.470806 -3.95585) (xy 45.523138 -3.971223) (xy 45.572751 -3.993887)
			(xy 45.618633 -4.02338) (xy 45.659851 -4.059103) (xy 45.695565 -4.100328) (xy 45.72505 -4.146216)
			(xy 45.747703 -4.195833) (xy 45.763066 -4.248169) (xy 45.770824 -4.302158) (xy 45.771308 -4.32943)
			(xy 45.771308 -4.330192) (xy 45.770932 -4.352571) (xy 45.765585 -4.397009) (xy 45.76064 -4.418838)
			(xy 45.758454 -4.430826) (xy 45.764313 -4.454445) (xy 45.771816 -4.46405) (xy 45.790775 -4.48635)
			(xy 45.825613 -4.533391) (xy 45.841412 -4.55803) (xy 45.846424 -4.565351) (xy 45.860395 -4.576269)
			(xy 45.877243 -4.581793) (xy 45.886116 -4.581906) (xy 45.899578 -4.581652) (xy 45.926851 -4.582086)
			(xy 45.980842 -4.589846) (xy 46.033179 -4.605211) (xy 46.082797 -4.627868) (xy 46.128685 -4.657356)
			(xy 46.16991 -4.693075) (xy 46.205631 -4.734297) (xy 46.235121 -4.780183) (xy 46.257781 -4.8298)
			(xy 46.273149 -4.882136) (xy 46.280912 -4.936127) (xy 46.280912 -4.990673) (xy 46.273149 -5.044664)
			(xy 46.257781 -5.097) (xy 46.235121 -5.146617) (xy 46.205631 -5.192503) (xy 46.16991 -5.233725) (xy 46.128685 -5.269444)
			(xy 46.082797 -5.298932) (xy 46.033179 -5.321589) (xy 45.980842 -5.336954) (xy 45.926851 -5.344714)
			(xy 45.899578 -5.345176) (xy 45.886116 -5.344922) (xy 45.877232 -5.344961) (xy 45.860353 -5.350474)
			(xy 45.846385 -5.361436) (xy 45.841412 -5.368798) (xy 45.825614 -5.393438) (xy 45.790778 -5.440481)
			(xy 45.771816 -5.462778) (xy 45.764354 -5.472398) (xy 45.758521 -5.496001) (xy 45.76064 -5.50799)
			(xy 45.765579 -5.52982) (xy 45.770927 -5.574258) (xy 45.771308 -5.596636) (xy 45.771308 -5.597398)
			(xy 45.770774 -5.624665) (xy 45.763014 -5.678645) (xy 45.747651 -5.730971) (xy 45.724998 -5.780578)
			(xy 45.695517 -5.826456) (xy 45.659807 -5.867673) (xy 45.618595 -5.903388) (xy 45.57272 -5.932875)
			(xy 45.523116 -5.955534) (xy 45.470792 -5.970903) (xy 45.416813 -5.97867) (xy 45.389546 -5.97916)
			(xy 45.360696 -5.978563) (xy 45.303651 -5.969891) (xy 45.248559 -5.952739) (xy 45.196674 -5.927496)
			(xy 45.149175 -5.894736) (xy 45.107144 -5.855206) (xy 45.071536 -5.809803) (xy 45.043162 -5.759561)
			(xy 45.032422 -5.73278) (xy 45.027489 -5.721756) (xy 45.009598 -5.705584) (xy 44.998132 -5.701792)
			(xy 44.961402 -5.691552) (xy 44.890018 -5.664735) (xy 44.82166 -5.630941) (xy 44.78909 -5.611114)
			(xy 44.780834 -5.6064) (xy 44.762166 -5.602873) (xy 44.743498 -5.6064) (xy 44.735242 -5.611114) (xy 44.701118 -5.63182)
			(xy 44.62938 -5.666824) (xy 44.554381 -5.694152) (xy 44.515786 -5.704332) (xy 44.504084 -5.707945)
			(xy 44.485775 -5.724156) (xy 44.480734 -5.73532) (xy 44.469895 -5.761881) (xy 44.441393 -5.811664)
			(xy 44.405765 -5.856624) (xy 44.363813 -5.895749) (xy 44.31648 -5.928158) (xy 44.264831 -5.953123)
			(xy 44.21003 -5.970081) (xy 44.153309 -5.97865) (xy 44.124626 -5.97916) (xy 44.113806 -5.979061)
			(xy 44.092203 -5.977791) (xy 44.081446 -5.97662) (xy 44.070524 -5.97535) (xy 44.049696 -5.982208)
			(xy 43.984926 -6.041898) (xy 43.977305 -6.049579) (xy 43.968756 -6.069437) (xy 43.968416 -6.080252)
			(xy 43.968416 -6.080506) (xy 43.96867 -6.09092) (xy 43.96867 -6.091428) (xy 43.968162 -6.110224)
			(xy 43.967654 -6.121146) (xy 43.975274 -6.140958) (xy 44.044108 -6.210046) (xy 44.064174 -6.217412)
			(xy 44.075096 -6.216904) (xy 44.094654 -6.216396) (xy 44.094908 -6.216396) (xy 44.122176 -6.216917)
			(xy 44.176156 -6.224679) (xy 44.228482 -6.240043) (xy 44.27809 -6.262697) (xy 44.323968 -6.29218)
			(xy 44.365185 -6.327891) (xy 44.4009 -6.369104) (xy 44.430387 -6.414981) (xy 44.453045 -6.464586)
			(xy 44.468414 -6.516911) (xy 44.476181 -6.57089) (xy 44.47667 -6.598158) (xy 49.048416 -6.598158)
			(xy 49.048885 -6.570889) (xy 49.056652 -6.516906) (xy 49.072022 -6.464577) (xy 49.094681 -6.414968)
			(xy 49.124169 -6.369089) (xy 49.159886 -6.327872) (xy 49.201105 -6.292157) (xy 49.246986 -6.262672)
			(xy 49.296596 -6.240015) (xy 49.348925 -6.224648) (xy 49.402909 -6.216884) (xy 49.430178 -6.216396)
			(xy 49.430432 -6.216396) (xy 49.44999 -6.216904) (xy 49.460912 -6.217412) (xy 49.480978 -6.210046)
			(xy 49.549812 -6.140958) (xy 49.557432 -6.121146) (xy 49.556924 -6.110224) (xy 49.556416 -6.091174)
			(xy 49.5569 -6.063905) (xy 49.564665 -6.009922) (xy 49.580032 -5.957594) (xy 49.60269 -5.907985)
			(xy 49.632177 -5.862106) (xy 49.667892 -5.820889) (xy 49.709109 -5.785174) (xy 49.754989 -5.755688)
			(xy 49.804598 -5.733031) (xy 49.856926 -5.717664) (xy 49.910909 -5.7099) (xy 49.938178 -5.709412)
			(xy 49.966994 -5.709888) (xy 50.02397 -5.718569) (xy 50.078995 -5.735707) (xy 50.130824 -5.760914)
			(xy 50.178279 -5.793617) (xy 50.220286 -5.833076) (xy 50.255891 -5.878395) (xy 50.284287 -5.928547)
			(xy 50.295048 -5.955284) (xy 50.300038 -5.966336) (xy 50.318065 -5.982507) (xy 50.329592 -5.986272)
			(xy 50.366687 -5.996501) (xy 50.438778 -6.023419) (xy 50.507793 -6.057458) (xy 50.540666 -6.077458)
			(xy 50.548922 -6.082172) (xy 50.56759 -6.085699) (xy 50.586258 -6.082172) (xy 50.594514 -6.077458)
			(xy 50.627396 -6.057474) (xy 50.696413 -6.023442) (xy 50.768497 -5.996511) (xy 50.805588 -5.986272)
			(xy 50.81715 -5.982567) (xy 50.835195 -5.966377) (xy 50.840132 -5.955284) (xy 50.850906 -5.928553)
			(xy 50.87929 -5.878396) (xy 50.914888 -5.833074) (xy 50.956893 -5.793615) (xy 51.004349 -5.760916)
			(xy 51.056181 -5.735719) (xy 51.111209 -5.718596) (xy 51.168186 -5.709937) (xy 51.197002 -5.709412)
			(xy 51.207758 -5.709519) (xy 51.229234 -5.710789) (xy 51.239928 -5.711952) (xy 51.25085 -5.713222)
			(xy 51.271678 -5.706364) (xy 51.336448 -5.646674) (xy 51.344078 -5.639) (xy 51.352622 -5.619137)
			(xy 51.352958 -5.60832) (xy 51.352958 -5.608066) (xy 51.352704 -5.597652) (xy 51.352704 -5.597398)
			(xy 51.353092 -5.572667) (xy 51.359464 -5.523618) (xy 51.365404 -5.499608) (xy 51.368044 -5.487606)
			(xy 51.362718 -5.463643) (xy 51.355244 -5.453888) (xy 51.338407 -5.433581) (xy 51.307264 -5.390997)
			(xy 51.293014 -5.368798) (xy 51.288005 -5.361475) (xy 51.27403 -5.350563) (xy 51.257182 -5.345038)
			(xy 51.24831 -5.344922) (xy 51.234848 -5.345176) (xy 51.207576 -5.344688) (xy 51.153586 -5.336932)
			(xy 51.101249 -5.32157) (xy 51.051632 -5.298916) (xy 51.005744 -5.269431) (xy 50.964519 -5.233715)
			(xy 50.928798 -5.192495) (xy 50.899307 -5.14661) (xy 50.876647 -5.096996) (xy 50.861279 -5.044661)
			(xy 50.853516 -4.990672) (xy 50.853516 -4.936128) (xy 50.861279 -4.882139) (xy 50.876647 -4.829804)
			(xy 50.899307 -4.78019) (xy 50.928798 -4.734305) (xy 50.964519 -4.693085) (xy 51.005744 -4.657369)
			(xy 51.051632 -4.627884) (xy 51.101249 -4.60523) (xy 51.153586 -4.589868) (xy 51.207576 -4.582112)
			(xy 51.234848 -4.581652) (xy 51.24831 -4.581906) (xy 51.257194 -4.581872) (xy 51.274071 -4.576354)
			(xy 51.28804 -4.565392) (xy 51.293014 -4.55803) (xy 51.307278 -4.535841) (xy 51.338419 -4.493256)
			(xy 51.355244 -4.47294) (xy 51.362533 -4.463099) (xy 51.367832 -4.439224) (xy 51.365404 -4.42722)
			(xy 51.359484 -4.4034) (xy 51.353114 -4.354733) (xy 51.352704 -4.330192) (xy 51.352704 -4.32943)
			(xy 51.353252 -4.302163) (xy 51.361009 -4.248183) (xy 51.376369 -4.195857) (xy 51.399019 -4.146249)
			(xy 51.428499 -4.10037) (xy 51.464207 -4.059153) (xy 51.505418 -4.023437) (xy 51.551293 -3.99395)
			(xy 51.600897 -3.971291) (xy 51.653221 -3.955923) (xy 51.707199 -3.948157) (xy 51.734466 -3.947668)
			(xy 51.763144 -3.94824) (xy 51.819853 -3.956823) (xy 51.874642 -3.973785) (xy 51.926281 -3.998747)
			(xy 51.973608 -4.031147) (xy 52.015561 -4.070257) (xy 52.051197 -4.115198) (xy 52.079715 -4.164961)
			(xy 52.090574 -4.191508) (xy 52.095635 -4.202648) (xy 52.113953 -4.218822) (xy 52.125626 -4.222496)
			(xy 52.164272 -4.2327) (xy 52.239361 -4.260111) (xy 52.311179 -4.295208) (xy 52.345336 -4.315968)
			(xy 52.353597 -4.320664) (xy 52.37226 -4.324172) (xy 52.390923 -4.320664) (xy 52.399184 -4.315968)
			(xy 52.431682 -4.296174) (xy 52.499868 -4.262388) (xy 52.571077 -4.235555) (xy 52.607718 -4.22529)
			(xy 52.619264 -4.221544) (xy 52.637317 -4.205384) (xy 52.642262 -4.194302) (xy 52.653043 -4.167523)
			(xy 52.681378 -4.117232) (xy 52.716958 -4.071778) (xy 52.758974 -4.032197) (xy 52.806467 -3.999388)
			(xy 52.858357 -3.9741) (xy 52.913461 -3.956909) (xy 52.970524 -3.948205) (xy 52.999386 -3.947668)
			(xy 53.026658 -3.948115) (xy 53.080647 -3.955876) (xy 53.132982 -3.971242) (xy 53.182597 -3.9939)
			(xy 53.228482 -4.023389) (xy 53.269703 -4.059108) (xy 53.305421 -4.100331) (xy 53.334908 -4.146217)
			(xy 53.357564 -4.195833) (xy 53.372928 -4.248169) (xy 53.380687 -4.302158) (xy 53.381148 -4.32943)
			(xy 53.381148 -4.329684) (xy 53.380793 -4.352127) (xy 53.375439 -4.396693) (xy 53.37048 -4.418584)
			(xy 53.368344 -4.430576) (xy 53.374172 -4.454187) (xy 53.381656 -4.463796) (xy 53.400684 -4.486154)
			(xy 53.43565 -4.533322) (xy 53.451506 -4.55803) (xy 53.456522 -4.565348) (xy 53.470491 -4.576267)
			(xy 53.487338 -4.581792) (xy 53.49621 -4.581906) (xy 53.509672 -4.581652) (xy 53.536945 -4.582086)
			(xy 53.590937 -4.589845) (xy 53.643275 -4.605209) (xy 53.692894 -4.627866) (xy 53.738782 -4.657354)
			(xy 53.780007 -4.693073) (xy 53.815729 -4.734295) (xy 53.845221 -4.780182) (xy 53.867881 -4.829799)
			(xy 53.883249 -4.882135) (xy 53.891012 -4.936127) (xy 53.891012 -4.990673) (xy 53.883249 -5.044665)
			(xy 53.867881 -5.097001) (xy 53.845221 -5.146618) (xy 53.815729 -5.192505) (xy 53.780007 -5.233727)
			(xy 53.738782 -5.269446) (xy 53.692894 -5.298934) (xy 53.643275 -5.321591) (xy 53.590937 -5.336955)
			(xy 53.536945 -5.344714) (xy 53.509672 -5.345176) (xy 53.49621 -5.344922) (xy 53.487325 -5.344957)
			(xy 53.470447 -5.350472) (xy 53.456479 -5.361435) (xy 53.451506 -5.368798) (xy 53.435659 -5.393513)
			(xy 53.400692 -5.44068) (xy 53.381656 -5.463032) (xy 53.374216 -5.472666) (xy 53.368373 -5.496257)
			(xy 53.37048 -5.508244) (xy 53.375434 -5.5302) (xy 53.380787 -5.574893) (xy 53.381148 -5.597398)
			(xy 53.381148 -5.597652) (xy 53.380894 -5.60832) (xy 53.381173 -5.619208) (xy 53.389713 -5.639218)
			(xy 53.397404 -5.646928) (xy 53.454046 -5.698998) (xy 53.46244 -5.705902) (xy 53.483079 -5.712632)
			(xy 53.493924 -5.711952) (xy 53.494432 -5.711952) (xy 53.505315 -5.710769) (xy 53.527173 -5.709498)
			(xy 53.53812 -5.709412) (xy 53.566934 -5.709938) (xy 53.623908 -5.718611) (xy 53.678932 -5.735741)
			(xy 53.73076 -5.76094) (xy 53.778216 -5.793636) (xy 53.820224 -5.833089) (xy 53.85583 -5.878403)
			(xy 53.884228 -5.92855) (xy 53.89499 -5.955284) (xy 53.899959 -5.966348) (xy 53.918 -5.982514) (xy 53.929534 -5.986272)
			(xy 53.966632 -5.996492) (xy 54.038722 -6.023414) (xy 54.107735 -6.057456) (xy 54.140608 -6.077458)
			(xy 54.148864 -6.082172) (xy 54.167532 -6.085699) (xy 54.1862 -6.082172) (xy 54.194456 -6.077458)
			(xy 54.227333 -6.057466) (xy 54.296352 -6.023437) (xy 54.368438 -5.996509) (xy 54.40553 -5.986272)
			(xy 54.417082 -5.98254) (xy 54.435132 -5.96637) (xy 54.440074 -5.955284) (xy 54.450813 -5.928538)
			(xy 54.479201 -5.878379) (xy 54.514804 -5.833056) (xy 54.556814 -5.793598) (xy 54.604275 -5.760901)
			(xy 54.656112 -5.735707) (xy 54.711145 -5.718588) (xy 54.768127 -5.709934) (xy 54.796944 -5.709412)
			(xy 54.807764 -5.709514) (xy 54.829367 -5.710782) (xy 54.840124 -5.711952) (xy 54.851046 -5.713222)
			(xy 54.871874 -5.706364) (xy 54.936644 -5.646674) (xy 54.944273 -5.638999) (xy 54.952818 -5.619137)
			(xy 54.953154 -5.60832) (xy 54.953154 -5.608066) (xy 54.9529 -5.597398) (xy 54.9529 -5.59689) (xy 54.953244 -5.572356)
			(xy 54.959491 -5.523689) (xy 54.965346 -5.499862) (xy 54.967775 -5.487921) (xy 54.962458 -5.464175)
			(xy 54.955186 -5.454396) (xy 54.938346 -5.433958) (xy 54.907202 -5.391121) (xy 54.892956 -5.368798)
			(xy 54.887922 -5.361495) (xy 54.873958 -5.35058) (xy 54.857121 -5.345045) (xy 54.848252 -5.344922)
			(xy 54.83479 -5.345176) (xy 54.807522 -5.344661) (xy 54.753542 -5.336898) (xy 54.701215 -5.321533)
			(xy 54.651608 -5.298877) (xy 54.60573 -5.269392) (xy 54.564515 -5.233678) (xy 54.528802 -5.192462)
			(xy 54.499318 -5.146583) (xy 54.476664 -5.096975) (xy 54.461299 -5.044649) (xy 54.453538 -4.990668)
			(xy 54.453538 -4.936132) (xy 54.461299 -4.882151) (xy 54.476664 -4.829825) (xy 54.499318 -4.780217)
			(xy 54.528802 -4.734338) (xy 54.564515 -4.693122) (xy 54.60573 -4.657408) (xy 54.651608 -4.627923)
			(xy 54.701215 -4.605267) (xy 54.753542 -4.589902) (xy 54.807522 -4.582139) (xy 54.83479 -4.581652)
			(xy 54.848252 -4.581906) (xy 54.857138 -4.581902) (xy 54.874017 -4.576371) (xy 54.887984 -4.565397)
			(xy 54.892956 -4.55803) (xy 54.907197 -4.535703) (xy 54.938339 -4.492864) (xy 54.955186 -4.472432)
			(xy 54.962462 -4.462654) (xy 54.967776 -4.438908) (xy 54.965346 -4.426966) (xy 54.959522 -4.403133)
			(xy 54.95328 -4.354469) (xy 54.9529 -4.329938) (xy 54.9529 -4.32943) (xy 54.953452 -4.302163) (xy 54.961209 -4.248184)
			(xy 54.976568 -4.195858) (xy 54.999218 -4.14625) (xy 55.028698 -4.100371) (xy 55.064406 -4.059154)
			(xy 55.105617 -4.023438) (xy 55.151491 -3.993951) (xy 55.201094 -3.971292) (xy 55.253417 -3.955923)
			(xy 55.307395 -3.948157) (xy 55.334662 -3.947668) (xy 55.363339 -3.948243) (xy 55.420049 -3.956825)
			(xy 55.474838 -3.973788) (xy 55.526477 -3.998749) (xy 55.573804 -4.031148) (xy 55.615757 -4.070258)
			(xy 55.651393 -4.115198) (xy 55.679911 -4.164961) (xy 55.69077 -4.191508) (xy 55.695833 -4.202647)
			(xy 55.714149 -4.218822) (xy 55.725822 -4.222496) (xy 55.764416 -4.232677) (xy 55.839414 -4.260008)
			(xy 55.911154 -4.295008) (xy 55.945278 -4.315714) (xy 55.953534 -4.320428) (xy 55.972202 -4.323955)
			(xy 55.99087 -4.320428) (xy 55.999126 -4.315714) (xy 56.031697 -4.295887) (xy 56.100052 -4.262087)
			(xy 56.171436 -4.235268) (xy 56.208168 -4.225036) (xy 56.219647 -4.221263) (xy 56.237549 -4.205088)
			(xy 56.242458 -4.194048) (xy 56.2532 -4.167264) (xy 56.28157 -4.117015) (xy 56.317174 -4.071603)
			(xy 56.359204 -4.032063) (xy 56.406701 -3.999294) (xy 56.458587 -3.974041) (xy 56.513681 -3.956878)
			(xy 56.570729 -3.948197) (xy 56.599582 -3.947668) (xy 56.626854 -3.948118) (xy 56.680843 -3.955879)
			(xy 56.733178 -3.971244) (xy 56.782793 -3.993902) (xy 56.828678 -4.02339) (xy 56.869899 -4.059109)
			(xy 56.905617 -4.100332) (xy 56.935104 -4.146218) (xy 56.95776 -4.195834) (xy 56.973124 -4.248169)
			(xy 56.980883 -4.302158) (xy 56.981344 -4.32943) (xy 56.981344 -4.330192) (xy 56.980967 -4.352571)
			(xy 56.975621 -4.397009) (xy 56.970676 -4.418838) (xy 56.968505 -4.430827) (xy 56.974357 -4.454443)
			(xy 56.981852 -4.46405) (xy 57.000807 -4.486353) (xy 57.035644 -4.533394) (xy 57.051448 -4.55803)
			(xy 57.0565 -4.56532) (xy 57.070452 -4.576244) (xy 57.087285 -4.581783) (xy 57.096152 -4.581906)
			(xy 57.109614 -4.581652) (xy 57.136884 -4.582111) (xy 57.190868 -4.589875) (xy 57.243198 -4.605242)
			(xy 57.292808 -4.6279) (xy 57.338689 -4.657387) (xy 57.379906 -4.693104) (xy 57.415621 -4.734323)
			(xy 57.445107 -4.780205) (xy 57.467763 -4.829816) (xy 57.483128 -4.882146) (xy 57.49089 -4.93613)
			(xy 57.49089 -4.99067) (xy 57.483128 -5.044654) (xy 57.467763 -5.096984) (xy 57.445107 -5.146595)
			(xy 57.415621 -5.192477) (xy 57.379906 -5.233696) (xy 57.338689 -5.269413) (xy 57.292808 -5.2989)
			(xy 57.243198 -5.321558) (xy 57.190868 -5.336925) (xy 57.136884 -5.344689) (xy 57.109614 -5.345176)
			(xy 57.096152 -5.344922) (xy 57.087265 -5.344915) (xy 57.070384 -5.350449) (xy 57.056418 -5.361428)
			(xy 57.051448 -5.368798) (xy 57.035654 -5.393441) (xy 57.000815 -5.440482) (xy 56.981852 -5.462778)
			(xy 56.974385 -5.472394) (xy 56.968558 -5.496) (xy 56.970676 -5.50799) (xy 56.975615 -5.52982) (xy 56.980963 -5.574258)
			(xy 56.981344 -5.596636) (xy 56.981344 -5.597398) (xy 56.980897 -5.62467) (xy 56.973134 -5.678658)
			(xy 56.957767 -5.730992) (xy 56.935109 -5.780607) (xy 56.90562 -5.826491) (xy 56.8699 -5.867712)
			(xy 56.828678 -5.903429) (xy 56.782793 -5.932916) (xy 56.733177 -5.955573) (xy 56.680842 -5.970938)
			(xy 56.626854 -5.978698) (xy 56.599582 -5.97916) (xy 56.57073 -5.978618) (xy 56.513683 -5.969937)
			(xy 56.45859 -5.952776) (xy 56.406704 -5.927524) (xy 56.359206 -5.894757) (xy 56.317176 -5.85522)
			(xy 56.28157 -5.809811) (xy 56.253198 -5.759564) (xy 56.242458 -5.73278) (xy 56.237556 -5.721739)
			(xy 56.219643 -5.705574) (xy 56.208168 -5.701792) (xy 56.171434 -5.691566) (xy 56.100051 -5.664743)
			(xy 56.031695 -5.630943) (xy 55.999126 -5.611114) (xy 55.99087 -5.6064) (xy 55.972202 -5.602873)
			(xy 55.953534 -5.6064) (xy 55.945278 -5.611114) (xy 55.911161 -5.631833) (xy 55.83942 -5.666832)
			(xy 55.764418 -5.694155) (xy 55.725822 -5.704332) (xy 55.714127 -5.70796) (xy 55.695813 -5.72416)
			(xy 55.69077 -5.73532) (xy 55.679902 -5.761868) (xy 55.651403 -5.81165) (xy 55.615779 -5.856609)
			(xy 55.573831 -5.895734) (xy 55.526502 -5.928145) (xy 55.474858 -5.953112) (xy 55.420061 -5.970073)
			(xy 55.363343 -5.978648) (xy 55.334662 -5.97916) (xy 55.323842 -5.979066) (xy 55.302239 -5.977793)
			(xy 55.291482 -5.97662) (xy 55.28056 -5.97535) (xy 55.259732 -5.982208) (xy 55.194962 -6.041898)
			(xy 55.187346 -6.049584) (xy 55.178793 -6.069438) (xy 55.178452 -6.080252) (xy 55.178452 -6.080506)
			(xy 55.178706 -6.09092) (xy 55.178706 -6.091428) (xy 55.178198 -6.110224) (xy 55.17769 -6.121146)
			(xy 55.18531 -6.140958) (xy 55.254144 -6.210046) (xy 55.27421 -6.217412) (xy 55.285132 -6.216904)
			(xy 55.30469 -6.216396) (xy 55.304944 -6.216396) (xy 55.332213 -6.216883) (xy 55.386194 -6.22465)
			(xy 55.438521 -6.240019) (xy 55.488128 -6.262677) (xy 55.534007 -6.292164) (xy 55.575223 -6.327878)
			(xy 55.610938 -6.369095) (xy 55.640424 -6.414973) (xy 55.663082 -6.464581) (xy 55.67845 -6.516908)
			(xy 55.686217 -6.570889) (xy 55.686706 -6.598158) (xy 55.686209 -6.624997) (xy 55.678676 -6.678144)
			(xy 55.66378 -6.729713) (xy 55.641815 -6.778691) (xy 55.613212 -6.824114) (xy 55.578535 -6.865087)
			(xy 55.538466 -6.900805) (xy 55.493792 -6.930565) (xy 55.46979 -6.942582) (xy 55.461154 -6.946646)
			(xy 55.447946 -6.96087) (xy 55.415942 -7.043928) (xy 55.416196 -7.063232) (xy 55.419752 -7.072122)
			(xy 55.428492 -7.094807) (xy 55.44079 -7.141841) (xy 55.447024 -7.190055) (xy 55.447438 -7.214362)
			(xy 55.447438 -7.215124) (xy 56.484012 -7.215124) (xy 56.484548 -7.186969) (xy 56.492869 -7.131277)
			(xy 56.509277 -7.077411) (xy 56.533415 -7.026536) (xy 56.564761 -6.979757) (xy 56.583326 -6.958584)
			(xy 56.591324 -6.948779) (xy 56.597452 -6.924263) (xy 56.59501 -6.911848) (xy 56.584203 -6.866063)
			(xy 56.572607 -6.772704) (xy 56.571896 -6.725666) (xy 56.571896 -6.725158) (xy 56.572406 -6.685158)
			(xy 56.580772 -6.605595) (xy 56.597408 -6.527344) (xy 56.622133 -6.451259) (xy 56.654674 -6.378176)
			(xy 56.694676 -6.308894) (xy 56.741701 -6.244173) (xy 56.795233 -6.184722) (xy 56.854685 -6.131191)
			(xy 56.919408 -6.084168) (xy 56.98869 -6.044167) (xy 57.061774 -6.011627) (xy 57.137859 -5.986904)
			(xy 57.216111 -5.970269) (xy 57.295674 -5.961905) (xy 57.335674 -5.96138) (xy 57.378363 -5.962006)
			(xy 57.463205 -5.971565) (xy 57.546452 -5.990523) (xy 57.627068 -6.018642) (xy 57.704046 -6.055572)
			(xy 57.74055 -6.077712) (xy 57.748811 -6.082408) (xy 57.767474 -6.085916) (xy 57.786137 -6.082408)
			(xy 57.794398 -6.077712) (xy 57.830904 -6.055572) (xy 57.907876 -6.018624) (xy 57.98849 -5.990495)
			(xy 58.071739 -5.971536) (xy 58.156584 -5.961985) (xy 58.199274 -5.96138) (xy 58.239273 -5.96197)
			(xy 58.318832 -5.970329) (xy 58.397081 -5.986959) (xy 58.473164 -6.011676) (xy 58.546247 -6.044211)
			(xy 58.615528 -6.084207) (xy 58.680249 -6.131225) (xy 58.739701 -6.184751) (xy 58.793232 -6.244198)
			(xy 58.840256 -6.308915) (xy 58.880258 -6.378193) (xy 58.912799 -6.451272) (xy 58.937524 -6.527353)
			(xy 58.950312 -6.5875) (xy 70.567784 -6.5875) (xy 70.571696 -6.510357) (xy 70.583393 -6.434005) (xy 70.602754 -6.359229)
			(xy 70.629581 -6.286795) (xy 70.663599 -6.217446) (xy 70.704457 -6.151895) (xy 70.751738 -6.090814)
			(xy 70.804956 -6.03483) (xy 70.863565 -5.984517) (xy 70.926963 -5.940391) (xy 70.9945 -5.902906)
			(xy 71.065483 -5.872446) (xy 71.139183 -5.849323) (xy 71.214845 -5.833775) (xy 71.291691 -5.825962)
			(xy 71.330312 -5.82549) (xy 71.330566 -5.82549) (xy 71.373232 -5.826087) (xy 71.458027 -5.835648)
			(xy 71.541227 -5.854611) (xy 71.621791 -5.882738) (xy 71.698713 -5.919678) (xy 71.735188 -5.941822)
			(xy 71.745624 -5.947602) (xy 71.769355 -5.949718) (xy 71.780654 -5.945886) (xy 71.811487 -5.926543)
			(xy 71.876171 -5.893161) (xy 71.94374 -5.866088) (xy 72.013579 -5.845571) (xy 72.085055 -5.831795)
			(xy 72.157517 -5.824886) (xy 72.193912 -5.824474) (xy 72.223435 -5.824754) (xy 72.282303 -5.829331)
			(xy 72.311514 -5.833618) (xy 72.32118 -5.832927) (xy 72.338941 -5.82521) (xy 72.346058 -5.818632)
			(xy 72.36773 -5.797565) (xy 72.416478 -5.76184) (xy 72.470243 -5.734236) (xy 72.527683 -5.71544)
			(xy 72.587366 -5.705923) (xy 72.617584 -5.705348) (xy 72.644855 -5.705816) (xy 72.698842 -5.713577)
			(xy 72.751175 -5.728941) (xy 72.800789 -5.751598) (xy 72.846673 -5.781085) (xy 72.887894 -5.816802)
			(xy 72.923612 -5.858022) (xy 72.953099 -5.903905) (xy 72.975757 -5.953519) (xy 72.991122 -6.005852)
			(xy 72.998883 -6.059839) (xy 72.999346 -6.08711) (xy 72.999346 -6.087364) (xy 72.998767 -6.11719)
			(xy 72.989471 -6.176114) (xy 72.971129 -6.232878) (xy 72.944188 -6.2861) (xy 72.92721 -6.31063) (xy 72.921932 -6.318552)
			(xy 72.917106 -6.336951) (xy 72.917812 -6.346444) (xy 72.930229 -6.385403) (xy 72.947642 -6.4653)
			(xy 72.956394 -6.546604) (xy 72.956928 -6.58749) (xy 72.956384 -6.62745) (xy 72.948031 -6.706932)
			(xy 72.931416 -6.785106) (xy 72.90672 -6.861115) (xy 72.874215 -6.934126) (xy 72.834256 -7.003339)
			(xy 72.787281 -7.067996) (xy 72.733805 -7.127389) (xy 72.674413 -7.180867) (xy 72.609757 -7.227844)
			(xy 72.540545 -7.267805) (xy 72.467535 -7.300312) (xy 72.391527 -7.32501) (xy 72.313354 -7.341627)
			(xy 72.233872 -7.349982) (xy 72.193912 -7.350506) (xy 72.157516 -7.35009) (xy 72.085052 -7.343194)
			(xy 72.013575 -7.329425) (xy 71.943734 -7.308908) (xy 71.876166 -7.281831) (xy 71.811485 -7.24844)
			(xy 71.780654 -7.229094) (xy 71.769357 -7.225285) (xy 71.745639 -7.227419) (xy 71.735188 -7.233158)
			(xy 71.698724 -7.255324) (xy 71.62181 -7.29229) (xy 71.541244 -7.320425) (xy 71.458038 -7.339375)
			(xy 71.373234 -7.348902) (xy 71.330566 -7.34949) (xy 71.330312 -7.34949) (xy 71.291691 -7.349038)
			(xy 71.214845 -7.341225) (xy 71.139183 -7.325677) (xy 71.065483 -7.302554) (xy 70.9945 -7.272094)
			(xy 70.926963 -7.234609) (xy 70.863565 -7.190483) (xy 70.804956 -7.14017) (xy 70.751738 -7.084186)
			(xy 70.704457 -7.023105) (xy 70.663599 -6.957554) (xy 70.629581 -6.888205) (xy 70.602754 -6.815771)
			(xy 70.583393 -6.740995) (xy 70.571696 -6.664643) (xy 70.567784 -6.5875) (xy 58.950312 -6.5875) (xy 58.95416 -6.605601)
			(xy 58.962526 -6.685159) (xy 58.963052 -6.725158) (xy 58.963052 -6.725666) (xy 58.962279 -6.773425)
			(xy 58.950309 -6.868192) (xy 58.939176 -6.914642) (xy 58.93667 -6.926966) (xy 58.942682 -6.951356)
			(xy 58.950606 -6.961124) (xy 58.968737 -6.982209) (xy 58.999324 -7.028648) (xy 59.022849 -7.079034)
			(xy 59.038814 -7.132301) (xy 59.04688 -7.18732) (xy 59.04738 -7.215124) (xy 59.046898 -7.242393)
			(xy 59.039133 -7.296376) (xy 59.023766 -7.348704) (xy 59.001108 -7.398314) (xy 58.971622 -7.444193)
			(xy 58.935906 -7.48541) (xy 58.894689 -7.521125) (xy 58.848808 -7.550611) (xy 58.799199 -7.573268)
			(xy 58.74687 -7.588635) (xy 58.692887 -7.596398) (xy 58.665618 -7.596886) (xy 58.635926 -7.596334)
			(xy 58.577261 -7.587122) (xy 58.520731 -7.568934) (xy 58.467701 -7.542209) (xy 58.419451 -7.507592)
			(xy 58.397902 -7.487158) (xy 58.388556 -7.478813) (xy 58.36458 -7.471628) (xy 58.352182 -7.473442)
			(xy 58.314369 -7.480678) (xy 58.23777 -7.488442) (xy 58.199274 -7.488936) (xy 58.156584 -7.488347)
			(xy 58.07174 -7.478781) (xy 57.988492 -7.459816) (xy 57.907877 -7.431688) (xy 57.830901 -7.394749)
			(xy 57.794398 -7.372604) (xy 57.786137 -7.367908) (xy 57.767474 -7.3644) (xy 57.748811 -7.367908)
			(xy 57.74055 -7.372604) (xy 57.704058 -7.394767) (xy 57.627082 -7.431711) (xy 57.546464 -7.459835)
			(xy 57.463212 -7.478788) (xy 57.378365 -7.488334) (xy 57.335674 -7.488936) (xy 57.335166 -7.488936)
			(xy 57.296212 -7.488407) (xy 57.218718 -7.480387) (xy 57.18048 -7.472934) (xy 57.168019 -7.471053)
			(xy 57.143901 -7.478251) (xy 57.134506 -7.48665) (xy 57.112895 -7.507154) (xy 57.064528 -7.541925)
			(xy 57.011353 -7.568773) (xy 56.954657 -7.587047) (xy 56.895812 -7.596307) (xy 56.866028 -7.596886)
			(xy 56.865774 -7.596886) (xy 56.838505 -7.5964) (xy 56.784523 -7.588635) (xy 56.732195 -7.573268)
			(xy 56.682586 -7.55061) (xy 56.636706 -7.521124) (xy 56.59549 -7.485409) (xy 56.559775 -7.444192)
			(xy 56.530289 -7.398312) (xy 56.507631 -7.348703) (xy 56.492264 -7.296375) (xy 56.4845 -7.242393)
			(xy 56.484012 -7.215124) (xy 55.447438 -7.215124) (xy 55.446998 -7.242395) (xy 55.439232 -7.296382)
			(xy 55.423863 -7.348713) (xy 55.401202 -7.398325) (xy 55.371711 -7.444207) (xy 55.335991 -7.485425)
			(xy 55.294769 -7.52114) (xy 55.248883 -7.550625) (xy 55.199268 -7.573279) (xy 55.146935 -7.588642)
			(xy 55.092947 -7.596401) (xy 55.065676 -7.596886) (xy 55.035986 -7.596298) (xy 54.977322 -7.587095)
			(xy 54.920793 -7.568916) (xy 54.867762 -7.542199) (xy 54.81951 -7.507589) (xy 54.79796 -7.487158)
			(xy 54.78859 -7.478846) (xy 54.764634 -7.471642) (xy 54.75224 -7.473442) (xy 54.714428 -7.480684)
			(xy 54.637828 -7.488444) (xy 54.599332 -7.488936) (xy 54.556643 -7.48832) (xy 54.4718 -7.47876) (xy 54.388552 -7.459801)
			(xy 54.307937 -7.43168) (xy 54.230959 -7.394746) (xy 54.194456 -7.372604) (xy 54.186195 -7.367908)
			(xy 54.167532 -7.3644) (xy 54.148869 -7.367908) (xy 54.140608 -7.372604) (xy 54.104102 -7.394743)
			(xy 54.02713 -7.431691) (xy 53.946516 -7.45982) (xy 53.863267 -7.478779) (xy 53.778422 -7.488331)
			(xy 53.735732 -7.488936) (xy 53.735224 -7.488936) (xy 53.696271 -7.488398) (xy 53.618776 -7.480384)
			(xy 53.580538 -7.472934) (xy 53.568075 -7.471092) (xy 53.543961 -7.478263) (xy 53.534564 -7.48665)
			(xy 53.512972 -7.507175) (xy 53.464599 -7.541943) (xy 53.411419 -7.568786) (xy 53.354719 -7.587056)
			(xy 53.295871 -7.59631) (xy 53.266086 -7.596886) (xy 53.265832 -7.596886) (xy 53.238563 -7.596369)
			(xy 53.184579 -7.588612) (xy 53.132249 -7.573251) (xy 53.082638 -7.550599) (xy 53.036755 -7.521117)
			(xy 52.995535 -7.485405) (xy 52.959817 -7.44419) (xy 52.930328 -7.398312) (xy 52.907669 -7.348704)
			(xy 52.8923 -7.296376) (xy 52.884535 -7.242393) (xy 52.88407 -7.215124) (xy 52.884458 -7.190503)
			(xy 52.890779 -7.141668) (xy 52.903333 -7.094053) (xy 52.912264 -7.071106) (xy 52.91582 -7.062216)
			(xy 52.916074 -7.042912) (xy 52.88788 -6.968744) (xy 52.884118 -6.959996) (xy 52.87133 -6.945904)
			(xy 52.862988 -6.941312) (xy 52.862734 -6.941312) (xy 52.838974 -6.929205) (xy 52.794776 -6.899372)
			(xy 52.755158 -6.863681) (xy 52.720889 -6.822825) (xy 52.692637 -6.7776) (xy 52.670951 -6.728884)
			(xy 52.656252 -6.677625) (xy 52.648826 -6.62482) (xy 52.648358 -6.598158) (xy 52.648785 -6.570887)
			(xy 52.656553 -6.5169) (xy 52.671925 -6.464568) (xy 52.694588 -6.414956) (xy 52.72408 -6.369075)
			(xy 52.759801 -6.327857) (xy 52.801024 -6.292142) (xy 52.846911 -6.262658) (xy 52.896526 -6.240003)
			(xy 52.948861 -6.22464) (xy 53.002849 -6.216881) (xy 53.03012 -6.216396) (xy 53.030374 -6.216396)
			(xy 53.049932 -6.216904) (xy 53.060854 -6.217412) (xy 53.08092 -6.210046) (xy 53.149754 -6.140958)
			(xy 53.157374 -6.121146) (xy 53.156866 -6.110224) (xy 53.156358 -6.091174) (xy 53.156358 -6.09092)
			(xy 53.156612 -6.080252) (xy 53.156347 -6.069362) (xy 53.147797 -6.049353) (xy 53.140102 -6.041644)
			(xy 53.08346 -5.989574) (xy 53.075102 -5.982619) (xy 53.054434 -5.97592) (xy 53.043582 -5.97662)
			(xy 53.043074 -5.97662) (xy 53.03219 -5.977801) (xy 53.010333 -5.979074) (xy 52.999386 -5.97916)
			(xy 52.970519 -5.978608) (xy 52.913441 -5.969939) (xy 52.858319 -5.952772) (xy 52.806413 -5.927498)
			(xy 52.758905 -5.894694) (xy 52.716881 -5.855107) (xy 52.681299 -5.809643) (xy 52.652971 -5.759338)
			(xy 52.642262 -5.732526) (xy 52.637263 -5.721478) (xy 52.619243 -5.705305) (xy 52.607718 -5.701538)
			(xy 52.571075 -5.69128) (xy 52.499867 -5.664443) (xy 52.431679 -5.630659) (xy 52.399184 -5.61086)
			(xy 52.390923 -5.606164) (xy 52.37226 -5.602656) (xy 52.353597 -5.606164) (xy 52.345336 -5.61086)
			(xy 52.31119 -5.631639) (xy 52.239371 -5.66674) (xy 52.164277 -5.694141) (xy 52.125626 -5.704332)
			(xy 52.113931 -5.707963) (xy 52.095618 -5.724161) (xy 52.090574 -5.73532) (xy 52.079702 -5.761866)
			(xy 52.051204 -5.811648) (xy 52.01558 -5.856608) (xy 51.973633 -5.895733) (xy 51.926305 -5.928144)
			(xy 51.874661 -5.953111) (xy 51.819864 -5.970073) (xy 51.763147 -5.978648) (xy 51.734466 -5.97916)
			(xy 51.72371 -5.979055) (xy 51.702234 -5.977783) (xy 51.69154 -5.97662) (xy 51.680618 -5.97535) (xy 51.65979 -5.982208)
			(xy 51.59502 -6.041898) (xy 51.587398 -6.049579) (xy 51.57885 -6.069437) (xy 51.57851 -6.080252)
			(xy 51.57851 -6.080506) (xy 51.578764 -6.090666) (xy 51.578764 -6.091174) (xy 51.578256 -6.110224)
			(xy 51.577748 -6.121146) (xy 51.585368 -6.140958) (xy 51.654202 -6.210046) (xy 51.674268 -6.217412)
			(xy 51.68519 -6.216904) (xy 51.704748 -6.216396) (xy 51.705002 -6.216396) (xy 51.73227 -6.216922)
			(xy 51.786249 -6.224683) (xy 51.838576 -6.240047) (xy 51.888183 -6.2627) (xy 51.934062 -6.292182)
			(xy 51.975278 -6.327893) (xy 52.010994 -6.369106) (xy 52.040481 -6.414982) (xy 52.063139 -6.464587)
			(xy 52.078508 -6.516911) (xy 52.086275 -6.570891) (xy 52.086764 -6.598158) (xy 52.086291 -6.624998)
			(xy 52.078757 -6.678147) (xy 52.063859 -6.729718) (xy 52.041891 -6.778697) (xy 52.013285 -6.82412)
			(xy 51.978604 -6.865093) (xy 51.93853 -6.900809) (xy 51.893853 -6.930566) (xy 51.869848 -6.942582)
			(xy 51.861212 -6.946646) (xy 51.848004 -6.96087) (xy 51.816 -7.043928) (xy 51.816254 -7.063232) (xy 51.81981 -7.072122)
			(xy 51.828553 -7.094806) (xy 51.840849 -7.141841) (xy 51.847082 -7.190055) (xy 51.847496 -7.214362)
			(xy 51.847496 -7.215124) (xy 51.846998 -7.242392) (xy 51.839234 -7.296374) (xy 51.823867 -7.348701)
			(xy 51.801211 -7.398309) (xy 51.771726 -7.444188) (xy 51.736012 -7.485405) (xy 51.694796 -7.52112)
			(xy 51.648918 -7.550606) (xy 51.59931 -7.573264) (xy 51.546984 -7.588632) (xy 51.493002 -7.596397)
			(xy 51.465734 -7.596886) (xy 51.436043 -7.596324) (xy 51.377378 -7.587115) (xy 51.320848 -7.568929)
			(xy 51.267818 -7.542206) (xy 51.219568 -7.507591) (xy 51.198018 -7.487158) (xy 51.188665 -7.478822)
			(xy 51.164695 -7.471632) (xy 51.152298 -7.473442) (xy 51.114485 -7.480675) (xy 51.037886 -7.488441)
			(xy 50.99939 -7.488936) (xy 50.9567 -7.48834) (xy 50.871857 -7.478775) (xy 50.788609 -7.459812) (xy 50.707994 -7.431686)
			(xy 50.631017 -7.394748) (xy 50.594514 -7.372604) (xy 50.586253 -7.367908) (xy 50.56759 -7.3644)
			(xy 50.548927 -7.367908) (xy 50.540666 -7.372604) (xy 50.50417 -7.39476) (xy 50.427195 -7.431705)
			(xy 50.346578 -7.459831) (xy 50.263327 -7.478786) (xy 50.178481 -7.488333) (xy 50.13579 -7.488936)
			(xy 50.096582 -7.488445) (xy 50.018577 -7.480425) (xy 49.980088 -7.472934) (xy 49.967597 -7.470977)
			(xy 49.94335 -7.478041) (xy 49.93386 -7.486396) (xy 49.912309 -7.506947) (xy 49.864012 -7.54178)
			(xy 49.810888 -7.568684) (xy 49.754228 -7.587004) (xy 49.69541 -7.596295) (xy 49.665636 -7.596886)
			(xy 49.638367 -7.596365) (xy 49.584383 -7.588609) (xy 49.532053 -7.573248) (xy 49.482442 -7.550596)
			(xy 49.436559 -7.521115) (xy 49.395339 -7.485403) (xy 49.359621 -7.444189) (xy 49.330132 -7.398311)
			(xy 49.307473 -7.348703) (xy 49.292104 -7.296375) (xy 49.284339 -7.242393) (xy 49.283874 -7.215124)
			(xy 49.284294 -7.190453) (xy 49.290699 -7.141529) (xy 49.303343 -7.093834) (xy 49.312322 -7.070852)
			(xy 49.312322 -7.070598) (xy 49.315411 -7.061658) (xy 49.315526 -7.042757) (xy 49.312576 -7.033768)
			(xy 49.284382 -6.959346) (xy 49.271682 -6.945376) (xy 49.262792 -6.941058) (xy 49.239019 -6.928999)
			(xy 49.194814 -6.89921) (xy 49.155188 -6.863556) (xy 49.120913 -6.822731) (xy 49.092657 -6.777531)
			(xy 49.070969 -6.728837) (xy 49.056274 -6.677598) (xy 49.048857 -6.624811) (xy 49.048416 -6.598158)
			(xy 44.47667 -6.598158) (xy 44.476194 -6.624998) (xy 44.46866 -6.678146) (xy 44.453762 -6.729717)
			(xy 44.431795 -6.778696) (xy 44.403189 -6.824119) (xy 44.368508 -6.865092) (xy 44.328435 -6.900809)
			(xy 44.283758 -6.930566) (xy 44.259754 -6.942582) (xy 44.251118 -6.946646) (xy 44.23791 -6.96087)
			(xy 44.205906 -7.043928) (xy 44.20616 -7.063232) (xy 44.209716 -7.072122) (xy 44.218459 -7.094806)
			(xy 44.230755 -7.141841) (xy 44.236988 -7.190055) (xy 44.237402 -7.214362) (xy 44.237402 -7.215124)
			(xy 44.236898 -7.242392) (xy 44.229134 -7.296373) (xy 44.213768 -7.3487) (xy 44.191112 -7.398307)
			(xy 44.161627 -7.444186) (xy 44.125914 -7.485403) (xy 44.084699 -7.521117) (xy 44.038821 -7.550604)
			(xy 43.989215 -7.573262) (xy 43.936889 -7.588631) (xy 43.882908 -7.596397) (xy 43.85564 -7.596886)
			(xy 43.825949 -7.59632) (xy 43.767285 -7.587112) (xy 43.710755 -7.568927) (xy 43.657724 -7.542205)
			(xy 43.609474 -7.507591) (xy 43.587924 -7.487158) (xy 43.578569 -7.478826) (xy 43.554601 -7.471633)
			(xy 43.542204 -7.473442) (xy 43.504391 -7.480674) (xy 43.427792 -7.48844) (xy 43.389296 -7.488936)
			(xy 43.346606 -7.488337) (xy 43.261763 -7.478773) (xy 43.178515 -7.459811) (xy 43.0979 -7.431685)
			(xy 43.020923 -7.394748) (xy 42.98442 -7.372604) (xy 42.976159 -7.367908) (xy 42.957496 -7.3644)
			(xy 42.938833 -7.367908) (xy 42.930572 -7.372604) (xy 42.894075 -7.394758) (xy 42.8171 -7.431703)
			(xy 42.736484 -7.459829) (xy 42.653233 -7.478785) (xy 42.568387 -7.488333) (xy 42.525696 -7.488936)
			(xy 42.525188 -7.488936) (xy 42.486235 -7.488403) (xy 42.40874 -7.480385) (xy 42.370502 -7.472934)
			(xy 42.35804 -7.471067) (xy 42.333924 -7.478255) (xy 42.324528 -7.48665) (xy 42.302908 -7.507144)
			(xy 42.254543 -7.541916) (xy 42.20137 -7.568766) (xy 42.144676 -7.587043) (xy 42.085833 -7.596305)
			(xy 42.05605 -7.596886) (xy 42.055796 -7.596886) (xy 42.028528 -7.596379) (xy 41.974546 -7.588618)
			(xy 41.922218 -7.573253) (xy 41.87261 -7.550598) (xy 41.82673 -7.521114) (xy 41.785513 -7.485401)
			(xy 41.749798 -7.444186) (xy 41.720311 -7.398308) (xy 41.697654 -7.3487) (xy 41.682286 -7.296374)
			(xy 41.674522 -7.242392) (xy 41.674034 -7.215124) (xy 41.674424 -7.190503) (xy 41.680745 -7.141668)
			(xy 41.693297 -7.094053) (xy 41.702228 -7.071106) (xy 41.705784 -7.062216) (xy 41.706038 -7.042912)
			(xy 41.677844 -6.968744) (xy 41.674095 -6.959989) (xy 41.661299 -6.9459) (xy 41.652952 -6.941312)
			(xy 41.652698 -6.941312) (xy 41.628953 -6.929177) (xy 41.584753 -6.89935) (xy 41.545131 -6.863665)
			(xy 41.51086 -6.822813) (xy 41.482606 -6.777592) (xy 41.460917 -6.728879) (xy 41.446217 -6.677622)
			(xy 41.43879 -6.624819) (xy 41.438322 -6.598158) (xy 41.438785 -6.570888) (xy 41.446552 -6.516905)
			(xy 41.461922 -6.464576) (xy 41.484582 -6.414966) (xy 41.514071 -6.369087) (xy 41.549788 -6.32787)
			(xy 41.591007 -6.292155) (xy 41.636889 -6.26267) (xy 41.6865 -6.240013) (xy 41.73883 -6.224647) (xy 41.792814 -6.216883)
			(xy 41.820084 -6.216396) (xy 41.820338 -6.216396) (xy 41.839896 -6.216904) (xy 41.850818 -6.217412)
			(xy 41.870884 -6.210046) (xy 41.939718 -6.140958) (xy 41.947338 -6.121146) (xy 41.94683 -6.110224)
			(xy 41.946322 -6.091174) (xy 41.946322 -6.09092) (xy 41.946576 -6.080252) (xy 41.946322 -6.069361)
			(xy 41.937766 -6.049351) (xy 41.930066 -6.041644) (xy 41.873424 -5.989574) (xy 41.865043 -5.982651)
			(xy 41.844393 -5.975933) (xy 41.833546 -5.97662) (xy 41.833038 -5.97662) (xy 41.822155 -5.977805)
			(xy 41.800297 -5.979075) (xy 41.78935 -5.97916) (xy 41.760482 -5.978639) (xy 41.703402 -5.969965)
			(xy 41.64828 -5.952793) (xy 41.596373 -5.927514) (xy 41.548866 -5.894705) (xy 41.506843 -5.855115)
			(xy 41.471262 -5.809647) (xy 41.442935 -5.759339) (xy 41.432226 -5.732526) (xy 41.427245 -5.721468)
			(xy 41.409212 -5.705299) (xy 41.397682 -5.701538) (xy 41.361043 -5.691267) (xy 41.289833 -5.664435)
			(xy 41.221645 -5.630656) (xy 41.189148 -5.61086) (xy 41.180887 -5.606164) (xy 41.162224 -5.602656)
			(xy 41.143561 -5.606164) (xy 41.1353 -5.61086) (xy 41.101158 -5.631647) (xy 41.029338 -5.666745)
			(xy 40.954242 -5.694143) (xy 40.91559 -5.704332) (xy 40.903889 -5.707946) (xy 40.885579 -5.724157)
			(xy 40.880538 -5.73532) (xy 40.869696 -5.761879) (xy 40.841194 -5.811663) (xy 40.805567 -5.856622)
			(xy 40.763615 -5.895747) (xy 40.716282 -5.928157) (xy 40.664634 -5.953121) (xy 40.609834 -5.97008)
			(xy 40.553113 -5.97865) (xy 40.52443 -5.97916) (xy 40.513674 -5.979058) (xy 40.492198 -5.977784)
			(xy 40.481504 -5.97662) (xy 40.470582 -5.97535) (xy 40.449754 -5.982208) (xy 40.384984 -6.041898)
			(xy 40.377372 -6.049587) (xy 40.368816 -6.069439) (xy 40.368474 -6.080252) (xy 40.368474 -6.080506)
			(xy 40.368728 -6.090666) (xy 40.368728 -6.091174) (xy 40.36822 -6.110224) (xy 40.367712 -6.121146)
			(xy 40.375332 -6.140958) (xy 40.444166 -6.210046) (xy 40.464232 -6.217412) (xy 40.475154 -6.216904)
			(xy 40.494712 -6.216396) (xy 40.494966 -6.216396) (xy 40.522233 -6.216956) (xy 40.576211 -6.224712)
			(xy 40.628537 -6.240071) (xy 40.678144 -6.26272) (xy 40.724023 -6.292198) (xy 40.76524 -6.327906)
			(xy 40.800956 -6.369116) (xy 40.830444 -6.414989) (xy 40.853103 -6.464592) (xy 40.868472 -6.516914)
			(xy 40.876239 -6.570891) (xy 40.876728 -6.598158) (xy 40.876275 -6.624999) (xy 40.86874 -6.678149)
			(xy 40.853841 -6.729722) (xy 40.831871 -6.778703) (xy 40.803262 -6.824126) (xy 40.768577 -6.865098)
			(xy 40.7285 -6.900813) (xy 40.683818 -6.930568) (xy 40.659812 -6.942582) (xy 40.651176 -6.946646)
			(xy 40.637968 -6.96087) (xy 40.605964 -7.043928) (xy 40.606218 -7.063232) (xy 40.609774 -7.072122)
			(xy 40.618515 -7.094807) (xy 40.630813 -7.141841) (xy 40.637046 -7.190055) (xy 40.63746 -7.214362)
			(xy 40.63746 -7.215124) (xy 40.636998 -7.242394) (xy 40.629233 -7.296379) (xy 40.613864 -7.348709)
			(xy 40.591205 -7.398319) (xy 40.561717 -7.4442) (xy 40.525999 -7.485417) (xy 40.484779 -7.521132)
			(xy 40.438896 -7.550618) (xy 40.389284 -7.573274) (xy 40.336953 -7.588638) (xy 40.282968 -7.5964)
			(xy 40.255698 -7.596886) (xy 40.226006 -7.596346) (xy 40.16734 -7.587132) (xy 40.11081 -7.568941)
			(xy 40.05778 -7.542213) (xy 40.009531 -7.507593) (xy 39.987982 -7.487158) (xy 39.978644 -7.478802)
			(xy 39.954662 -7.471623) (xy 39.942262 -7.473442) (xy 39.90445 -7.480681) (xy 39.82785 -7.488443)
			(xy 39.789354 -7.488936) (xy 39.746665 -7.488309) (xy 39.661823 -7.478752) (xy 39.578575 -7.459796)
			(xy 39.497959 -7.431677) (xy 39.420982 -7.394745) (xy 39.384478 -7.372604) (xy 39.376217 -7.367908)
			(xy 39.357554 -7.3644) (xy 39.338891 -7.367908) (xy 39.33063 -7.372604) (xy 39.294118 -7.394734)
			(xy 39.217148 -7.431683) (xy 39.136535 -7.459814) (xy 39.053287 -7.478775) (xy 38.968444 -7.48833)
			(xy 38.925754 -7.488936) (xy 38.886546 -7.488435) (xy 38.808541 -7.480422) (xy 38.770052 -7.472934)
			(xy 38.757562 -7.470953) (xy 38.733313 -7.478033) (xy 38.723824 -7.486396) (xy 38.702288 -7.506964)
			(xy 38.653987 -7.541795) (xy 38.600859 -7.568695) (xy 38.544196 -7.587011) (xy 38.485375 -7.596298)
			(xy 38.4556 -7.596886) (xy 38.428332 -7.596376) (xy 38.37435 -7.588615) (xy 38.322023 -7.57325) (xy 38.272414 -7.550596)
			(xy 38.226534 -7.521112) (xy 38.185317 -7.4854) (xy 38.149602 -7.444185) (xy 38.120115 -7.398307)
			(xy 38.097458 -7.3487) (xy 38.082091 -7.296373) (xy 38.074326 -7.242392) (xy 38.073838 -7.215124)
			(xy 38.07426 -7.190454) (xy 38.080665 -7.141529) (xy 38.093308 -7.093834) (xy 38.102286 -7.070852)
			(xy 38.102286 -7.070598) (xy 38.105377 -7.061658) (xy 38.105492 -7.042756) (xy 38.10254 -7.033768)
			(xy 38.074346 -6.959346) (xy 38.061646 -6.945376) (xy 38.052756 -6.941058) (xy 38.028998 -6.928971)
			(xy 37.984791 -6.899189) (xy 37.945162 -6.86354) (xy 37.910884 -6.82272) (xy 37.882625 -6.777524)
			(xy 37.860936 -6.728832) (xy 37.846239 -6.677595) (xy 37.838821 -6.62481) (xy 37.83838 -6.598158)
			(xy 31.766764 -6.598158) (xy 31.766291 -6.624998) (xy 31.758757 -6.678147) (xy 31.743859 -6.729718)
			(xy 31.721891 -6.778697) (xy 31.693285 -6.82412) (xy 31.658604 -6.865093) (xy 31.61853 -6.900809)
			(xy 31.573853 -6.930566) (xy 31.549848 -6.942582) (xy 31.541212 -6.946646) (xy 31.528004 -6.96087)
			(xy 31.496 -7.043928) (xy 31.496254 -7.063232) (xy 31.49981 -7.072122) (xy 31.508553 -7.094806) (xy 31.520849 -7.141841)
			(xy 31.527082 -7.190055) (xy 31.527496 -7.214362) (xy 31.527496 -7.215124) (xy 31.526998 -7.242392)
			(xy 31.519234 -7.296374) (xy 31.503867 -7.348701) (xy 31.481211 -7.398309) (xy 31.451726 -7.444188)
			(xy 31.416012 -7.485405) (xy 31.374796 -7.52112) (xy 31.328918 -7.550606) (xy 31.27931 -7.573264)
			(xy 31.226984 -7.588632) (xy 31.173002 -7.596397) (xy 31.145734 -7.596886) (xy 31.116043 -7.596324)
			(xy 31.057378 -7.587115) (xy 31.000848 -7.568929) (xy 30.947818 -7.542206) (xy 30.899568 -7.507591)
			(xy 30.878018 -7.487158) (xy 30.868665 -7.478822) (xy 30.844695 -7.471632) (xy 30.832298 -7.473442)
			(xy 30.794485 -7.480675) (xy 30.717886 -7.488441) (xy 30.67939 -7.488936) (xy 30.6367 -7.48834) (xy 30.551857 -7.478775)
			(xy 30.468609 -7.459812) (xy 30.387994 -7.431686) (xy 30.311017 -7.394748) (xy 30.274514 -7.372604)
			(xy 30.266253 -7.367908) (xy 30.24759 -7.3644) (xy 30.228927 -7.367908) (xy 30.220666 -7.372604)
			(xy 30.18417 -7.39476) (xy 30.107195 -7.431705) (xy 30.026578 -7.459831) (xy 29.943327 -7.478786)
			(xy 29.858481 -7.488333) (xy 29.81579 -7.488936) (xy 29.776582 -7.488445) (xy 29.698577 -7.480425)
			(xy 29.660088 -7.472934) (xy 29.647597 -7.470977) (xy 29.62335 -7.478041) (xy 29.61386 -7.486396)
			(xy 29.592309 -7.506947) (xy 29.544012 -7.54178) (xy 29.490888 -7.568684) (xy 29.434228 -7.587004)
			(xy 29.37541 -7.596295) (xy 29.345636 -7.596886) (xy 29.318367 -7.596365) (xy 29.264383 -7.588609)
			(xy 29.212053 -7.573248) (xy 29.162442 -7.550596) (xy 29.116559 -7.521115) (xy 29.075339 -7.485403)
			(xy 29.039621 -7.444189) (xy 29.010132 -7.398311) (xy 28.987473 -7.348703) (xy 28.972104 -7.296375)
			(xy 28.964339 -7.242393) (xy 28.963874 -7.215124) (xy 28.964294 -7.190453) (xy 28.970699 -7.141529)
			(xy 28.983343 -7.093834) (xy 28.992322 -7.070852) (xy 28.992322 -7.070598) (xy 28.995411 -7.061658)
			(xy 28.995526 -7.042757) (xy 28.992576 -7.033768) (xy 28.964382 -6.959346) (xy 28.951682 -6.945376)
			(xy 28.942792 -6.941058) (xy 28.919019 -6.928999) (xy 28.874814 -6.89921) (xy 28.835188 -6.863556)
			(xy 28.800913 -6.822731) (xy 28.772657 -6.777531) (xy 28.750969 -6.728837) (xy 28.736274 -6.677598)
			(xy 28.728857 -6.624811) (xy 28.728416 -6.598158) (xy 28.728885 -6.570889) (xy 28.736652 -6.516906)
			(xy 28.752022 -6.464577) (xy 28.774681 -6.414968) (xy 28.804169 -6.369089) (xy 28.839886 -6.327872)
			(xy 28.881105 -6.292157) (xy 28.926986 -6.262672) (xy 28.976596 -6.240015) (xy 29.028925 -6.224648)
			(xy 29.082909 -6.216884) (xy 29.110178 -6.216396) (xy 29.110432 -6.216396) (xy 29.12999 -6.216904)
			(xy 29.140912 -6.217412) (xy 29.160978 -6.210046) (xy 29.229812 -6.140958) (xy 29.237432 -6.121146)
			(xy 29.236924 -6.110224) (xy 29.236416 -6.091174) (xy 29.236416 -6.09092) (xy 29.23667 -6.080252)
			(xy 29.236417 -6.069361) (xy 29.22786 -6.04935) (xy 29.22016 -6.041644) (xy 29.163518 -5.989574)
			(xy 29.15514 -5.982648) (xy 29.134488 -5.975932) (xy 29.12364 -5.97662) (xy 29.123132 -5.97662) (xy 29.112249 -5.977805)
			(xy 29.090391 -5.979075) (xy 29.079444 -5.97916) (xy 29.050594 -5.978564) (xy 28.993549 -5.969893)
			(xy 28.938457 -5.95274) (xy 28.886572 -5.927497) (xy 28.839073 -5.894737) (xy 28.797042 -5.855206)
			(xy 28.761434 -5.809803) (xy 28.73306 -5.759562) (xy 28.72232 -5.73278) (xy 28.717388 -5.721756)
			(xy 28.699496 -5.705584) (xy 28.68803 -5.701792) (xy 28.6513 -5.691553) (xy 28.579916 -5.664735)
			(xy 28.511558 -5.630941) (xy 28.478988 -5.611114) (xy 28.470732 -5.6064) (xy 28.452064 -5.602873)
			(xy 28.433396 -5.6064) (xy 28.42514 -5.611114) (xy 28.391016 -5.63182) (xy 28.319278 -5.666824) (xy 28.244279 -5.694152)
			(xy 28.205684 -5.704332) (xy 28.193982 -5.707943) (xy 28.175672 -5.724156) (xy 28.170632 -5.73532)
			(xy 28.159795 -5.761881) (xy 28.131293 -5.811665) (xy 28.095664 -5.856625) (xy 28.053712 -5.89575)
			(xy 28.006378 -5.928159) (xy 27.95473 -5.953123) (xy 27.899928 -5.970081) (xy 27.843207 -5.978651)
			(xy 27.814524 -5.97916) (xy 27.803704 -5.979061) (xy 27.782101 -5.977791) (xy 27.771344 -5.97662)
			(xy 27.760422 -5.97535) (xy 27.739594 -5.982208) (xy 27.674824 -6.041898) (xy 27.667203 -6.049579)
			(xy 27.658654 -6.069437) (xy 27.658314 -6.080252) (xy 27.658314 -6.080506) (xy 27.658568 -6.09092)
			(xy 27.658568 -6.091428) (xy 27.65806 -6.110224) (xy 27.657552 -6.121146) (xy 27.665172 -6.140958)
			(xy 27.734006 -6.210046) (xy 27.754072 -6.217412) (xy 27.764994 -6.216904) (xy 27.784552 -6.216396)
			(xy 27.784806 -6.216396) (xy 27.812074 -6.216919) (xy 27.866054 -6.22468) (xy 27.91838 -6.240044)
			(xy 27.967987 -6.262698) (xy 28.013866 -6.292181) (xy 28.055083 -6.327892) (xy 28.090798 -6.369105)
			(xy 28.120285 -6.414981) (xy 28.142943 -6.464586) (xy 28.158312 -6.516911) (xy 28.166079 -6.57089)
			(xy 28.166568 -6.598158) (xy 28.166061 -6.624973) (xy 28.158548 -6.678075) (xy 28.143678 -6.729603)
			(xy 28.121744 -6.778544) (xy 28.093177 -6.823933) (xy 28.058539 -6.864878) (xy 28.018513 -6.900573)
			(xy 27.973885 -6.930316) (xy 27.949906 -6.942328) (xy 27.94127 -6.946392) (xy 27.928062 -6.960616)
			(xy 27.895804 -7.043928) (xy 27.896058 -7.062724) (xy 27.899614 -7.071614) (xy 27.899614 -7.072122)
			(xy 27.908419 -7.094882) (xy 27.920844 -7.142076) (xy 27.927136 -7.19047) (xy 27.927554 -7.21487)
			(xy 27.927554 -7.215124) (xy 27.927098 -7.242394) (xy 27.919333 -7.296379) (xy 27.903964 -7.34871)
			(xy 27.881304 -7.398321) (xy 27.851815 -7.444202) (xy 27.816097 -7.48542) (xy 27.774876 -7.521134)
			(xy 27.728993 -7.55062) (xy 27.67938 -7.573275) (xy 27.627048 -7.58864) (xy 27.573062 -7.5964) (xy 27.545792 -7.596886)
			(xy 27.516078 -7.596328) (xy 27.457368 -7.587116) (xy 27.400791 -7.568929) (xy 27.347709 -7.542207)
			(xy 27.299402 -7.507592) (xy 27.277822 -7.487158) (xy 27.268468 -7.478824) (xy 27.244499 -7.471633)
			(xy 27.232102 -7.473442) (xy 27.194289 -7.480675) (xy 27.11769 -7.488441) (xy 27.079194 -7.488936)
			(xy 27.036504 -7.488338) (xy 26.951661 -7.478774) (xy 26.868413 -7.459811) (xy 26.787798 -7.431685)
			(xy 26.710821 -7.394748) (xy 26.674318 -7.372604) (xy 26.666057 -7.367908) (xy 26.647394 -7.3644)
			(xy 26.628731 -7.367908) (xy 26.62047 -7.372604) (xy 26.583973 -7.394759) (xy 26.506998 -7.431704)
			(xy 26.426382 -7.45983) (xy 26.343131 -7.478785) (xy 26.258285 -7.488333) (xy 26.215594 -7.488936)
			(xy 26.215086 -7.488936) (xy 26.176133 -7.488403) (xy 26.098638 -7.480386) (xy 26.0604 -7.472934)
			(xy 26.047939 -7.471066) (xy 26.023822 -7.478255) (xy 26.014426 -7.48665) (xy 25.992807 -7.507145)
			(xy 25.944442 -7.541917) (xy 25.891268 -7.568766) (xy 25.834574 -7.587043) (xy 25.775731 -7.596305)
			(xy 25.745948 -7.596886) (xy 25.745694 -7.596886) (xy 25.718426 -7.596381) (xy 25.664444 -7.588619)
			(xy 25.612116 -7.573254) (xy 25.562508 -7.550599) (xy 25.516628 -7.521115) (xy 25.475411 -7.485402)
			(xy 25.439696 -7.444187) (xy 25.410209 -7.398308) (xy 25.387552 -7.348701) (xy 25.372184 -7.296374)
			(xy 25.36442 -7.242392) (xy 25.363932 -7.215124) (xy 25.364322 -7.190503) (xy 25.370643 -7.141668)
			(xy 25.383195 -7.094053) (xy 25.392126 -7.071106) (xy 25.395682 -7.062216) (xy 25.395936 -7.042912)
			(xy 25.367742 -6.968744) (xy 25.363994 -6.959989) (xy 25.351197 -6.9459) (xy 25.34285 -6.941312)
			(xy 25.342596 -6.941312) (xy 25.318851 -6.929178) (xy 25.27465 -6.899351) (xy 25.235029 -6.863665)
			(xy 25.200758 -6.822814) (xy 25.172503 -6.777592) (xy 25.150815 -6.728879) (xy 25.136115 -6.677623)
			(xy 25.128688 -6.624819) (xy 25.12822 -6.598158) (xy 25.128685 -6.570888) (xy 25.136452 -6.516905)
			(xy 25.151822 -6.464576) (xy 25.174482 -6.414967) (xy 25.20397 -6.369087) (xy 25.239688 -6.327871)
			(xy 25.280906 -6.292156) (xy 25.326788 -6.26267) (xy 25.376399 -6.240014) (xy 25.428728 -6.224647)
			(xy 25.482712 -6.216884) (xy 25.509982 -6.216396) (xy 25.510236 -6.216396) (xy 25.529794 -6.216904)
			(xy 25.540716 -6.217412) (xy 25.560782 -6.210046) (xy 25.629616 -6.140958) (xy 25.637236 -6.121146)
			(xy 25.636728 -6.110224) (xy 25.63622 -6.091428) (xy 25.63622 -6.09092) (xy 25.636474 -6.080506)
			(xy 25.636474 -6.080252) (xy 25.636153 -6.069429) (xy 25.627618 -6.049555) (xy 25.619964 -6.041898)
			(xy 25.563322 -5.989574) (xy 25.554942 -5.98265) (xy 25.534292 -5.975933) (xy 25.523444 -5.97662)
			(xy 25.522936 -5.97662) (xy 25.512179 -5.977789) (xy 25.490576 -5.979062) (xy 25.479756 -5.97916)
			(xy 25.479502 -5.97916) (xy 25.450651 -5.9786) (xy 25.393604 -5.969923) (xy 25.338511 -5.952764)
			(xy 25.286626 -5.927516) (xy 25.239128 -5.894751) (xy 25.197097 -5.855215) (xy 25.161491 -5.809809)
			(xy 25.133118 -5.759563) (xy 25.122378 -5.73278) (xy 25.117466 -5.721744) (xy 25.09956 -5.705577)
			(xy 25.088088 -5.701792) (xy 25.051355 -5.691562) (xy 24.979972 -5.66474) (xy 24.911615 -5.630943)
			(xy 24.879046 -5.611114) (xy 24.87079 -5.6064) (xy 24.852122 -5.602873) (xy 24.833454 -5.6064) (xy 24.825198 -5.611114)
			(xy 24.791079 -5.631829) (xy 24.719339 -5.66683) (xy 24.644338 -5.694154) (xy 24.605742 -5.704332)
			(xy 24.59405 -5.70797) (xy 24.575735 -5.724163) (xy 24.57069 -5.73532) (xy 24.559805 -5.76186) (xy 24.531308 -5.811642)
			(xy 24.495686 -5.856601) (xy 24.453741 -5.895726) (xy 24.406415 -5.928138) (xy 24.354773 -5.953106)
			(xy 24.299978 -5.97007) (xy 24.243262 -5.978646) (xy 24.214582 -5.97916) (xy 24.203762 -5.979064)
			(xy 24.182159 -5.977792) (xy 24.171402 -5.97662) (xy 24.16048 -5.97535) (xy 24.139652 -5.982208)
			(xy 24.074882 -6.041898) (xy 24.067269 -6.049587) (xy 24.058714 -6.069438) (xy 24.058372 -6.080252)
			(xy 24.058372 -6.080506) (xy 24.058626 -6.09092) (xy 24.058626 -6.091428) (xy 24.058118 -6.110224)
			(xy 24.05761 -6.121146) (xy 24.06523 -6.140958) (xy 24.134064 -6.210046) (xy 24.15413 -6.217412)
			(xy 24.165052 -6.216904) (xy 24.18461 -6.216396) (xy 24.184864 -6.216396) (xy 24.212131 -6.216958)
			(xy 24.266109 -6.224713) (xy 24.318435 -6.240072) (xy 24.368042 -6.262721) (xy 24.413921 -6.292199)
			(xy 24.455138 -6.327907) (xy 24.490854 -6.369116) (xy 24.520342 -6.414989) (xy 24.543001 -6.464592)
			(xy 24.55837 -6.516914) (xy 24.566137 -6.570892) (xy 24.566626 -6.598158) (xy 24.566174 -6.624999)
			(xy 24.558639 -6.67815) (xy 24.54374 -6.729723) (xy 24.52177 -6.778703) (xy 24.49316 -6.824126) (xy 24.458476 -6.865099)
			(xy 24.418398 -6.900813) (xy 24.373716 -6.930568) (xy 24.34971 -6.942582) (xy 24.341074 -6.946646)
			(xy 24.327866 -6.96087) (xy 24.295862 -7.043928) (xy 24.296116 -7.063232) (xy 24.299672 -7.072122)
			(xy 24.308413 -7.094807) (xy 24.320711 -7.141841) (xy 24.326944 -7.190055) (xy 24.327358 -7.214362)
			(xy 24.327358 -7.215124) (xy 24.326898 -7.242394) (xy 24.319133 -7.296379) (xy 24.303764 -7.348709)
			(xy 24.281105 -7.39832) (xy 24.251616 -7.444201) (xy 24.215898 -7.485418) (xy 24.174678 -7.521133)
			(xy 24.128795 -7.550618) (xy 24.079183 -7.573274) (xy 24.026851 -7.588639) (xy 23.972866 -7.5964)
			(xy 23.945596 -7.596886) (xy 23.915904 -7.596347) (xy 23.857238 -7.587133) (xy 23.800708 -7.568942)
			(xy 23.747678 -7.542213) (xy 23.699429 -7.507593) (xy 23.67788 -7.487158) (xy 23.668543 -7.4788)
			(xy 23.64456 -7.471623) (xy 23.63216 -7.473442) (xy 23.594348 -7.480681) (xy 23.517748 -7.488443)
			(xy 23.479252 -7.488936) (xy 23.436563 -7.48831) (xy 23.351721 -7.478753) (xy 23.268473 -7.459796)
			(xy 23.187857 -7.431677) (xy 23.11088 -7.394745) (xy 23.074376 -7.372604) (xy 23.066115 -7.367908)
			(xy 23.047452 -7.3644) (xy 23.028789 -7.367908) (xy 23.020528 -7.372604) (xy 22.984017 -7.394735)
			(xy 22.907046 -7.431684) (xy 22.826434 -7.459815) (xy 22.743186 -7.478776) (xy 22.658342 -7.48833)
			(xy 22.615652 -7.488936) (xy 22.615144 -7.488936) (xy 22.576191 -7.488395) (xy 22.498696 -7.480383)
			(xy 22.460458 -7.472934) (xy 22.447998 -7.471038) (xy 22.423878 -7.478246) (xy 22.414484 -7.48665)
			(xy 22.392883 -7.507165) (xy 22.344513 -7.541934) (xy 22.291335 -7.56878) (xy 22.234637 -7.587052)
			(xy 22.175791 -7.596308) (xy 22.146006 -7.596886) (xy 22.145752 -7.596886) (xy 22.118483 -7.59642)
			(xy 22.064499 -7.588653) (xy 22.012171 -7.573282) (xy 21.962562 -7.550622) (xy 21.916683 -7.521134)
			(xy 21.875466 -7.485417) (xy 21.839752 -7.444198) (xy 21.810266 -7.398317) (xy 21.787609 -7.348706)
			(xy 21.772242 -7.296377) (xy 21.764478 -7.242393) (xy 21.76399 -7.215124) (xy 21.764383 -7.190503)
			(xy 21.770703 -7.141669) (xy 21.783254 -7.094053) (xy 21.792184 -7.071106) (xy 21.79574 -7.062216)
			(xy 21.795994 -7.042912) (xy 21.7678 -6.968744) (xy 21.764067 -6.959981) (xy 21.75126 -6.945895)
			(xy 21.742908 -6.941312) (xy 21.742654 -6.941312) (xy 21.718899 -6.929197) (xy 21.6747 -6.899365)
			(xy 21.635081 -6.863676) (xy 21.600811 -6.822821) (xy 21.572559 -6.777597) (xy 21.550872 -6.728882)
			(xy 21.536172 -6.677624) (xy 21.528746 -6.62482) (xy 21.528278 -6.598158) (xy 21.528686 -6.570886)
			(xy 21.536454 -6.516897) (xy 21.551827 -6.464564) (xy 21.574491 -6.414951) (xy 21.603985 -6.369068)
			(xy 21.639708 -6.32785) (xy 21.680934 -6.292135) (xy 21.726823 -6.262651) (xy 21.776441 -6.239998)
			(xy 21.828778 -6.224636) (xy 21.882768 -6.21688) (xy 21.91004 -6.216396) (xy 21.910294 -6.216396)
			(xy 21.929852 -6.216904) (xy 21.940774 -6.217412) (xy 21.96084 -6.210046) (xy 22.029674 -6.140958)
			(xy 22.037294 -6.121146) (xy 22.036786 -6.110224) (xy 22.036278 -6.091174) (xy 22.036278 -6.09092)
			(xy 22.036532 -6.080252) (xy 22.036291 -6.069359) (xy 22.027727 -6.049348) (xy 22.020022 -6.041644)
			(xy 21.96338 -5.989574) (xy 21.955015 -5.982629) (xy 21.934353 -5.975924) (xy 21.923502 -5.97662)
			(xy 21.922994 -5.97662) (xy 21.91211 -5.9778) (xy 21.890253 -5.979073) (xy 21.879306 -5.97916) (xy 21.85044 -5.97859)
			(xy 21.793362 -5.969925) (xy 21.738241 -5.952761) (xy 21.686334 -5.927489) (xy 21.638827 -5.894687)
			(xy 21.596802 -5.855103) (xy 21.56122 -5.809641) (xy 21.532892 -5.759337) (xy 21.522182 -5.732526)
			(xy 21.517223 -5.721456) (xy 21.499175 -5.705292) (xy 21.487638 -5.701538) (xy 21.450996 -5.691276)
			(xy 21.379787 -5.664441) (xy 21.3116 -5.630658) (xy 21.279104 -5.61086) (xy 21.270843 -5.606164)
			(xy 21.25218 -5.602656) (xy 21.233517 -5.606164) (xy 21.225256 -5.61086) (xy 21.191098 -5.631619)
			(xy 21.119283 -5.666721) (xy 21.044191 -5.694123) (xy 21.005546 -5.704332) (xy 20.993855 -5.707971)
			(xy 20.975539 -5.724163) (xy 20.970494 -5.73532) (xy 20.959606 -5.761859) (xy 20.931109 -5.81164)
			(xy 20.895488 -5.856599) (xy 20.853543 -5.895725) (xy 20.806217 -5.928136) (xy 20.754576 -5.953105)
			(xy 20.699782 -5.970069) (xy 20.643066 -5.978646) (xy 20.614386 -5.97916) (xy 20.60363 -5.979053)
			(xy 20.582154 -5.977783) (xy 20.57146 -5.97662) (xy 20.560538 -5.97535) (xy 20.53971 -5.982208) (xy 20.47494 -6.041898)
			(xy 20.467321 -6.049581) (xy 20.45877 -6.069437) (xy 20.45843 -6.080252) (xy 20.45843 -6.080506)
			(xy 20.458684 -6.090666) (xy 20.458684 -6.091174) (xy 20.458176 -6.110224) (xy 20.457668 -6.121146)
			(xy 20.465288 -6.140958) (xy 20.534122 -6.210046) (xy 20.554188 -6.217412) (xy 20.56511 -6.216904)
			(xy 20.584668 -6.216396) (xy 20.584922 -6.216396) (xy 20.61219 -6.216904) (xy 20.666171 -6.224667)
			(xy 20.718497 -6.240033) (xy 20.768105 -6.262689) (xy 20.813983 -6.292173) (xy 20.8552 -6.327886)
			(xy 20.890915 -6.369101) (xy 20.920401 -6.414978) (xy 20.94306 -6.464584) (xy 20.958428 -6.51691)
			(xy 20.966195 -6.57089) (xy 20.966684 -6.598158) (xy 20.9662 -6.624997) (xy 20.958666 -6.678145)
			(xy 20.943769 -6.729716) (xy 20.921803 -6.778694) (xy 20.893198 -6.824117) (xy 20.858519 -6.86509)
			(xy 20.818447 -6.900807) (xy 20.773772 -6.930565) (xy 20.749768 -6.942582) (xy 20.741132 -6.946646)
			(xy 20.727924 -6.96087) (xy 20.69592 -7.043928) (xy 20.696174 -7.063232) (xy 20.69973 -7.072122)
			(xy 20.708469 -7.094807) (xy 20.720768 -7.141841) (xy 20.727002 -7.190055) (xy 20.727416 -7.214362)
			(xy 20.727416 -7.215124) (xy 20.727021 -7.242398) (xy 20.719254 -7.296389) (xy 20.703882 -7.348726)
			(xy 20.681219 -7.398342) (xy 20.651724 -7.444228) (xy 20.616 -7.485449) (xy 20.574772 -7.521166)
			(xy 20.528881 -7.550652) (xy 20.47926 -7.573307) (xy 20.426921 -7.588669) (xy 20.372928 -7.596426)
			(xy 20.345654 -7.596886) (xy 20.315963 -7.596311) (xy 20.257299 -7.587105) (xy 20.20077 -7.568923)
			(xy 20.147739 -7.542203) (xy 20.099488 -7.50759) (xy 20.077938 -7.487158) (xy 20.068577 -7.478834)
			(xy 20.044613 -7.471637) (xy 20.032218 -7.473442) (xy 19.994407 -7.480687) (xy 19.917806 -7.488445)
			(xy 19.87931 -7.488936) (xy 19.83662 -7.48833) (xy 19.751777 -7.478768) (xy 19.668529 -7.459807)
			(xy 19.587914 -7.431683) (xy 19.510937 -7.394747) (xy 19.474434 -7.372604) (xy 19.466173 -7.367908)
			(xy 19.44751 -7.3644) (xy 19.428847 -7.367908) (xy 19.420586 -7.372604) (xy 19.384085 -7.394752)
			(xy 19.307112 -7.431698) (xy 19.226496 -7.459825) (xy 19.143246 -7.478782) (xy 19.0584 -7.488332)
			(xy 19.01571 -7.488936) (xy 19.015202 -7.488936) (xy 18.976249 -7.488401) (xy 18.898754 -7.480385)
			(xy 18.860516 -7.472934) (xy 18.848054 -7.471077) (xy 18.823939 -7.478258) (xy 18.814542 -7.48665)
			(xy 18.792959 -7.507185) (xy 18.744584 -7.541952) (xy 18.691402 -7.568794) (xy 18.6347 -7.587061)
			(xy 18.57585 -7.596312) (xy 18.546064 -7.596886) (xy 18.54581 -7.596886) (xy 18.518542 -7.596366)
			(xy 18.464561 -7.588607) (xy 18.412233 -7.573244) (xy 18.362625 -7.550591) (xy 18.316745 -7.521108)
			(xy 18.275528 -7.485396) (xy 18.239812 -7.444182) (xy 18.210326 -7.398305) (xy 18.187668 -7.348699)
			(xy 18.172301 -7.296372) (xy 18.164536 -7.242392) (xy 18.164048 -7.215124) (xy 18.164437 -7.190503)
			(xy 18.170758 -7.141668) (xy 18.183311 -7.094053) (xy 18.192242 -7.071106) (xy 18.195798 -7.062216)
			(xy 18.196052 -7.042912) (xy 18.167858 -6.968744) (xy 18.164104 -6.959992) (xy 18.151311 -6.945901)
			(xy 18.142966 -6.941312) (xy 18.142712 -6.941312) (xy 18.118971 -6.92917) (xy 18.07477 -6.899345)
			(xy 18.035148 -6.863661) (xy 18.000876 -6.822811) (xy 17.972621 -6.77759) (xy 17.950932 -6.728878)
			(xy 17.936231 -6.677622) (xy 17.928805 -6.624819) (xy 17.928336 -6.598158) (xy 14.626082 -6.598158)
			(xy 14.626082 -9.780016) (xy 14.625583 -9.863891) (xy 14.617601 -10.03145) (xy 14.601655 -10.198441)
			(xy 14.577781 -10.364483) (xy 14.546034 -10.529201) (xy 14.506486 -10.692222) (xy 14.459225 -10.853176)
			(xy 14.404359 -11.0117) (xy 14.342013 -11.167433) (xy 14.272327 -11.320024) (xy 14.195459 -11.469125)
			(xy 14.111585 -11.614401) (xy 14.020892 -11.755521) (xy 13.923588 -11.892166) (xy 13.819892 -12.024026)
			(xy 13.710039 -12.150802) (xy 13.594279 -12.272209) (xy 13.4866 -12.37488) (xy 56.486552 -12.37488)
			(xy 56.487006 -12.34761) (xy 56.494771 -12.293624) (xy 56.510139 -12.241293) (xy 56.532799 -12.191682)
			(xy 56.562288 -12.1458) (xy 56.598007 -12.104583) (xy 56.639228 -12.068868) (xy 56.685112 -12.039382)
			(xy 56.734725 -12.016727) (xy 56.787057 -12.001363) (xy 56.841043 -11.993603) (xy 56.868314 -11.993118)
			(xy 56.898004 -11.993712) (xy 56.956667 -12.002913) (xy 57.013197 -12.021091) (xy 57.066228 -12.047807)
			(xy 57.11448 -12.082416) (xy 57.13603 -12.102846) (xy 57.145404 -12.111153) (xy 57.169357 -12.11836)
			(xy 57.18175 -12.116562) (xy 57.219562 -12.109322) (xy 57.296162 -12.101561) (xy 57.334658 -12.101068)
			(xy 57.377347 -12.101704) (xy 57.462188 -12.111261) (xy 57.545435 -12.130216) (xy 57.626051 -12.158333)
			(xy 57.70303 -12.195261) (xy 57.739534 -12.2174) (xy 57.747795 -12.222096) (xy 57.766458 -12.225604)
			(xy 57.785121 -12.222096) (xy 57.793382 -12.2174) (xy 57.829891 -12.195266) (xy 57.906862 -12.158317)
			(xy 57.987475 -12.130187) (xy 58.070724 -12.111227) (xy 58.155568 -12.101674) (xy 58.198258 -12.101068)
			(xy 58.198766 -12.101068) (xy 58.237719 -12.101608) (xy 58.315214 -12.109621) (xy 58.353452 -12.11707)
			(xy 58.365915 -12.118932) (xy 58.390033 -12.111751) (xy 58.399426 -12.103354) (xy 58.421023 -12.082835)
			(xy 58.469394 -12.048066) (xy 58.522573 -12.021221) (xy 58.579272 -12.00295) (xy 58.638119 -11.993695)
			(xy 58.667904 -11.993118) (xy 58.668158 -11.993118) (xy 58.695427 -11.99364) (xy 58.749411 -12.001396)
			(xy 58.801741 -12.016756) (xy 58.851353 -12.039408) (xy 58.897236 -12.068889) (xy 58.938456 -12.1046)
			(xy 58.974174 -12.145815) (xy 59.003663 -12.191693) (xy 59.026322 -12.241301) (xy 59.04169 -12.293629)
			(xy 59.049455 -12.347611) (xy 59.04992 -12.37488) (xy 59.049404 -12.403036) (xy 59.044311 -12.43711)
			(xy 62.309756 -12.43711) (xy 62.310222 -12.396003) (xy 62.317806 -12.314139) (xy 62.332909 -12.233324)
			(xy 62.355404 -12.154247) (xy 62.385098 -12.077583) (xy 62.421737 -12.003984) (xy 62.46501 -11.93408)
			(xy 62.514548 -11.868466) (xy 62.569927 -11.807701) (xy 62.630676 -11.752305) (xy 62.696277 -11.70275)
			(xy 62.766169 -11.659457) (xy 62.839757 -11.622797) (xy 62.916414 -11.593082) (xy 62.995485 -11.570566)
			(xy 63.076295 -11.55544) (xy 63.158157 -11.547833) (xy 63.199264 -11.547348) (xy 63.243059 -11.547873)
			(xy 63.330225 -11.556491) (xy 63.416121 -11.573637) (xy 63.499915 -11.599145) (xy 63.580795 -11.632768)
			(xy 63.619634 -11.653012) (xy 63.6311 -11.65843) (xy 63.656428 -11.65843) (xy 63.667894 -11.653012)
			(xy 63.706738 -11.632781) (xy 63.787623 -11.599174) (xy 63.871416 -11.573672) (xy 63.957309 -11.556521)
			(xy 64.04447 -11.547888) (xy 64.088264 -11.547348) (xy 64.132059 -11.547873) (xy 64.219225 -11.556491)
			(xy 64.305121 -11.573637) (xy 64.388915 -11.599145) (xy 64.469795 -11.632768) (xy 64.508634 -11.653012)
			(xy 64.5201 -11.65843) (xy 64.545428 -11.65843) (xy 64.556894 -11.653012) (xy 64.595738 -11.632781)
			(xy 64.676623 -11.599174) (xy 64.760416 -11.573672) (xy 64.846309 -11.556521) (xy 64.93347 -11.547888)
			(xy 64.977264 -11.547348) (xy 65.021059 -11.547873) (xy 65.108225 -11.556491) (xy 65.194121 -11.573637)
			(xy 65.277915 -11.599145) (xy 65.358795 -11.632768) (xy 65.397634 -11.653012) (xy 65.4091 -11.65843)
			(xy 65.434428 -11.65843) (xy 65.445894 -11.653012) (xy 65.484738 -11.632781) (xy 65.565623 -11.599174)
			(xy 65.649416 -11.573672) (xy 65.735309 -11.556521) (xy 65.82247 -11.547888) (xy 65.866264 -11.547348)
			(xy 65.904554 -11.547763) (xy 65.980848 -11.554368) (xy 66.05629 -11.567515) (xy 66.130321 -11.587105)
			(xy 66.166492 -11.599672) (xy 66.174929 -11.602323) (xy 66.192599 -11.602323) (xy 66.201036 -11.599672)
			(xy 66.237216 -11.587135) (xy 66.311248 -11.56756) (xy 66.386687 -11.554411) (xy 66.462976 -11.547785)
			(xy 66.501264 -11.547348) (xy 66.54268 -11.547848) (xy 66.625149 -11.555593) (xy 66.706543 -11.570964)
			(xy 66.786158 -11.593827) (xy 66.863305 -11.623986) (xy 66.937318 -11.661178) (xy 66.972688 -11.68273)
			(xy 66.980074 -11.686987) (xy 66.996689 -11.690769) (xy 67.013625 -11.688896) (xy 67.021456 -11.685524)
			(xy 67.057233 -11.668994) (xy 67.131154 -11.641645) (xy 67.207206 -11.620946) (xy 67.284791 -11.607058)
			(xy 67.363301 -11.600092) (xy 67.40271 -11.599672) (xy 67.443826 -11.600089) (xy 67.525707 -11.607677)
			(xy 67.606539 -11.622789) (xy 67.685632 -11.645294) (xy 67.76231 -11.675001) (xy 67.835921 -11.711656)
			(xy 67.905835 -11.754947) (xy 67.971457 -11.804505) (xy 68.032226 -11.859906) (xy 68.087623 -11.920677)
			(xy 68.137178 -11.986301) (xy 68.180465 -12.056218) (xy 68.217117 -12.12983) (xy 68.24682 -12.20651)
			(xy 68.269321 -12.285604) (xy 68.284429 -12.366436) (xy 68.285211 -12.37488) (xy 70.481444 -12.37488)
			(xy 70.481906 -12.34761) (xy 70.48967 -12.293625) (xy 70.505039 -12.241295) (xy 70.527698 -12.191684)
			(xy 70.557186 -12.145803) (xy 70.592904 -12.104585) (xy 70.634124 -12.06887) (xy 70.680007 -12.039385)
			(xy 70.729619 -12.016729) (xy 70.781951 -12.001365) (xy 70.835936 -11.993604) (xy 70.863206 -11.993118)
			(xy 70.89292 -11.993676) (xy 70.95163 -12.002888) (xy 71.008208 -12.021075) (xy 71.061289 -12.047797)
			(xy 71.109596 -12.082412) (xy 71.131176 -12.102846) (xy 71.140531 -12.111179) (xy 71.164499 -12.11837)
			(xy 71.176896 -12.116562) (xy 71.214709 -12.10933) (xy 71.291308 -12.101564) (xy 71.329804 -12.101068)
			(xy 71.372493 -12.101682) (xy 71.457336 -12.111244) (xy 71.540583 -12.130204) (xy 71.621198 -12.158326)
			(xy 71.698176 -12.195259) (xy 71.73468 -12.2174) (xy 71.742941 -12.222096) (xy 71.761604 -12.225604)
			(xy 71.780267 -12.222096) (xy 71.788528 -12.2174) (xy 71.825026 -12.195247) (xy 71.902 -12.158301)
			(xy 71.982616 -12.130175) (xy 72.065867 -12.111219) (xy 72.150713 -12.101671) (xy 72.193404 -12.101068)
			(xy 72.193912 -12.101068) (xy 72.232865 -12.101601) (xy 72.31036 -12.109618) (xy 72.348598 -12.11707)
			(xy 72.361059 -12.118963) (xy 72.385181 -12.111761) (xy 72.394572 -12.103354) (xy 72.416193 -12.082861)
			(xy 72.464557 -12.048088) (xy 72.51773 -12.021239) (xy 72.574424 -12.002961) (xy 72.633267 -11.993699)
			(xy 72.66305 -11.993118) (xy 72.663304 -11.993118) (xy 72.690573 -11.993621) (xy 72.744555 -12.001382)
			(xy 72.796883 -12.016747) (xy 72.846491 -12.039402) (xy 72.892371 -12.068887) (xy 72.933588 -12.1046)
			(xy 72.969304 -12.145816) (xy 72.99879 -12.191695) (xy 73.021447 -12.241302) (xy 73.036814 -12.29363)
			(xy 73.044578 -12.347611) (xy 73.045066 -12.37488) (xy 73.044538 -12.403035) (xy 73.036215 -12.458728)
			(xy 73.019806 -12.512595) (xy 72.995666 -12.563469) (xy 72.964318 -12.610248) (xy 72.945752 -12.63142)
			(xy 72.93775 -12.641221) (xy 72.931625 -12.665741) (xy 72.934068 -12.678156) (xy 72.944876 -12.723941)
			(xy 72.956471 -12.8173) (xy 72.957182 -12.864338) (xy 72.957182 -12.864846) (xy 72.956615 -12.906728)
			(xy 72.947438 -12.989988) (xy 72.9292 -13.071742) (xy 72.902121 -13.151008) (xy 72.866525 -13.226832)
			(xy 72.845168 -13.262864) (xy 72.840715 -13.270912) (xy 72.837355 -13.288984) (xy 72.840563 -13.307083)
			(xy 72.844914 -13.315188) (xy 72.85761 -13.337389) (xy 72.877642 -13.384446) (xy 72.891212 -13.433755)
			(xy 72.898078 -13.484435) (xy 72.898508 -13.510006) (xy 72.898508 -13.510514) (xy 72.897989 -13.537782)
			(xy 72.890226 -13.591762) (xy 72.874862 -13.644088) (xy 72.852207 -13.693695) (xy 72.822724 -13.739574)
			(xy 72.787012 -13.78079) (xy 72.745799 -13.816505) (xy 72.699923 -13.845992) (xy 72.650318 -13.86865)
			(xy 72.597993 -13.88402) (xy 72.544014 -13.891786) (xy 72.516746 -13.892276) (xy 72.488603 -13.891794)
			(xy 72.432928 -13.883522) (xy 72.379071 -13.867166) (xy 72.328198 -13.84308) (xy 72.281414 -13.811786)
			(xy 72.23973 -13.773962) (xy 72.204052 -13.730428) (xy 72.175152 -13.682128) (xy 72.16394 -13.65631)
			(xy 72.16002 -13.647995) (xy 72.147384 -13.634661) (xy 72.130881 -13.626592) (xy 72.121776 -13.625322)
			(xy 72.086458 -13.621561) (xy 72.01667 -13.608331) (xy 71.948413 -13.588672) (xy 71.88228 -13.562755)
			(xy 71.818841 -13.530802) (xy 71.788528 -13.512292) (xy 71.780267 -13.507596) (xy 71.761604 -13.504088)
			(xy 71.742941 -13.507596) (xy 71.73468 -13.512292) (xy 71.69818 -13.534441) (xy 71.621206 -13.571388)
			(xy 71.540591 -13.599515) (xy 71.45734 -13.618471) (xy 71.372495 -13.62802) (xy 71.329804 -13.628624)
			(xy 71.289805 -13.628051) (xy 71.210246 -13.61969) (xy 71.131996 -13.603058) (xy 71.055913 -13.578339)
			(xy 70.982831 -13.545802) (xy 70.91355 -13.505805) (xy 70.848829 -13.458785) (xy 70.789377 -13.405258)
			(xy 70.735846 -13.34581) (xy 70.688822 -13.281092) (xy 70.648821 -13.211814) (xy 70.616279 -13.138734)
			(xy 70.591555 -13.062653) (xy 70.574918 -12.984404) (xy 70.566552 -12.904845) (xy 70.566026 -12.864846)
			(xy 70.56678 -12.817023) (xy 70.578755 -12.722128) (xy 70.589902 -12.675616) (xy 70.592373 -12.663288)
			(xy 70.586386 -12.638903) (xy 70.578472 -12.629134) (xy 70.560306 -12.608033) (xy 70.529636 -12.561564)
			(xy 70.506046 -12.511131) (xy 70.490037 -12.457805) (xy 70.481948 -12.402719) (xy 70.481444 -12.37488)
			(xy 68.285211 -12.37488) (xy 68.292013 -12.448318) (xy 68.292472 -12.489434) (xy 68.291907 -12.533047)
			(xy 68.283357 -12.619854) (xy 68.266352 -12.705408) (xy 68.241056 -12.788886) (xy 68.207711 -12.869488)
			(xy 68.166638 -12.946439) (xy 68.118231 -13.019001) (xy 68.062955 -13.086478) (xy 68.00134 -13.14822)
			(xy 67.933978 -13.203636) (xy 67.861516 -13.252193) (xy 67.823334 -13.273278) (xy 67.814055 -13.278811)
			(xy 67.800889 -13.295908) (xy 67.797934 -13.306298) (xy 67.787525 -13.3474) (xy 67.759881 -13.427561)
			(xy 67.724737 -13.504728) (xy 67.682409 -13.578201) (xy 67.633283 -13.647314) (xy 67.577804 -13.711439)
			(xy 67.516475 -13.769995) (xy 67.449854 -13.82245) (xy 67.378544 -13.868328) (xy 67.303192 -13.907213)
			(xy 67.224482 -13.938753) (xy 67.143129 -13.96266) (xy 67.05987 -13.978719) (xy 66.975461 -13.986784)
			(xy 66.933064 -13.987272) (xy 66.894775 -13.986847) (xy 66.818481 -13.980245) (xy 66.743038 -13.967101)
			(xy 66.669007 -13.947513) (xy 66.632836 -13.934948) (xy 66.624399 -13.932297) (xy 66.606729 -13.932297)
			(xy 66.598292 -13.934948) (xy 66.56211 -13.947478) (xy 66.488079 -13.967055) (xy 66.41264 -13.980205)
			(xy 66.336352 -13.986834) (xy 66.298064 -13.987272) (xy 66.254269 -13.986733) (xy 66.167104 -13.978118)
			(xy 66.081208 -13.960975) (xy 65.997414 -13.93547) (xy 65.916534 -13.90185) (xy 65.877694 -13.881608)
			(xy 65.866228 -13.87619) (xy 65.8409 -13.87619) (xy 65.829434 -13.881608) (xy 65.790581 -13.901822)
			(xy 65.709699 -13.935433) (xy 65.625908 -13.96094) (xy 65.540018 -13.978094) (xy 65.452857 -13.986731)
			(xy 65.409064 -13.987272) (xy 65.365269 -13.986733) (xy 65.278104 -13.978118) (xy 65.192208 -13.960975)
			(xy 65.108414 -13.93547) (xy 65.027534 -13.90185) (xy 64.988694 -13.881608) (xy 64.977228 -13.87619)
			(xy 64.9519 -13.87619) (xy 64.940434 -13.881608) (xy 64.901581 -13.901822) (xy 64.820699 -13.935433)
			(xy 64.736908 -13.96094) (xy 64.651018 -13.978094) (xy 64.563857 -13.986731) (xy 64.520064 -13.987272)
			(xy 64.476269 -13.986733) (xy 64.389104 -13.978118) (xy 64.303208 -13.960975) (xy 64.219414 -13.93547)
			(xy 64.138534 -13.90185) (xy 64.099694 -13.881608) (xy 64.088228 -13.87619) (xy 64.0629 -13.87619)
			(xy 64.051434 -13.881608) (xy 64.012581 -13.901822) (xy 63.931699 -13.935433) (xy 63.847908 -13.96094)
			(xy 63.762018 -13.978094) (xy 63.674857 -13.986731) (xy 63.631064 -13.987272) (xy 63.588804 -13.98679)
			(xy 63.504665 -13.978779) (xy 63.421665 -13.962822) (xy 63.340553 -13.939064) (xy 63.26206 -13.907718)
			(xy 63.186895 -13.869068) (xy 63.115735 -13.823463) (xy 63.049222 -13.771312) (xy 62.987956 -13.713088)
			(xy 62.93249 -13.649314) (xy 62.883323 -13.580566) (xy 62.840899 -13.507464) (xy 62.805601 -13.430668)
			(xy 62.777747 -13.35087) (xy 62.757589 -13.268789) (xy 62.750954 -13.22705) (xy 62.748768 -13.216225)
			(xy 62.736658 -13.197787) (xy 62.727586 -13.19149) (xy 62.693115 -13.169417) (xy 62.628004 -13.119803)
			(xy 62.567725 -13.064419) (xy 62.512788 -13.003732) (xy 62.463657 -12.938255) (xy 62.420747 -12.868543)
			(xy 62.384422 -12.795185) (xy 62.354987 -12.7188) (xy 62.332693 -12.640034) (xy 62.317728 -12.559554)
			(xy 62.310218 -12.47804) (xy 62.309756 -12.43711) (xy 59.044311 -12.43711) (xy 59.04108 -12.458729)
			(xy 59.024669 -12.512597) (xy 59.000526 -12.563471) (xy 58.969174 -12.610249) (xy 58.950606 -12.63142)
			(xy 58.942601 -12.641218) (xy 58.93648 -12.66574) (xy 58.938922 -12.678156) (xy 58.949729 -12.723941)
			(xy 58.961325 -12.8173) (xy 58.962036 -12.864338) (xy 58.962036 -12.864846) (xy 58.961598 -12.904849)
			(xy 58.95323 -12.984415) (xy 58.936592 -13.062672) (xy 58.911864 -13.13876) (xy 58.879319 -13.211847)
			(xy 58.839312 -13.281131) (xy 58.792282 -13.345854) (xy 58.738745 -13.405307) (xy 58.679286 -13.458838)
			(xy 58.614557 -13.50586) (xy 58.545268 -13.545859) (xy 58.472178 -13.578396) (xy 58.396087 -13.603115)
			(xy 58.317828 -13.619744) (xy 58.238261 -13.628103) (xy 58.198258 -13.628624) (xy 58.155569 -13.627982)
			(xy 58.070728 -13.618427) (xy 57.987481 -13.599473) (xy 57.906865 -13.571357) (xy 57.829886 -13.53443)
			(xy 57.793382 -13.512292) (xy 57.785121 -13.507596) (xy 57.766458 -13.504088) (xy 57.747795 -13.507596)
			(xy 57.739534 -13.512292) (xy 57.703045 -13.53446) (xy 57.626068 -13.571403) (xy 57.54545 -13.599526)
			(xy 57.462197 -13.618478) (xy 57.377349 -13.628023) (xy 57.334658 -13.628624) (xy 57.294658 -13.628094)
			(xy 57.215097 -13.619728) (xy 57.136847 -13.603093) (xy 57.060764 -13.578369) (xy 56.987681 -13.545828)
			(xy 56.9184 -13.505828) (xy 56.85368 -13.458804) (xy 56.794229 -13.405274) (xy 56.740698 -13.345823)
			(xy 56.693675 -13.281103) (xy 56.653673 -13.211822) (xy 56.621133 -13.13874) (xy 56.596409 -13.062657)
			(xy 56.579772 -12.984407) (xy 56.571406 -12.904846) (xy 56.57088 -12.864846) (xy 56.57088 -12.864338)
			(xy 56.571655 -12.816579) (xy 56.583625 -12.721812) (xy 56.594756 -12.675362) (xy 56.597276 -12.663039)
			(xy 56.591257 -12.638645) (xy 56.583326 -12.62888) (xy 56.565202 -12.607789) (xy 56.534612 -12.561352)
			(xy 56.511086 -12.510968) (xy 56.49512 -12.457702) (xy 56.487053 -12.402683) (xy 56.486552 -12.37488)
			(xy 13.4866 -12.37488) (xy 13.472872 -12.387969) (xy 13.346096 -12.497822) (xy 13.214236 -12.601518)
			(xy 13.077591 -12.698822) (xy 12.936471 -12.789515) (xy 12.791195 -12.873389) (xy 12.642094 -12.950257)
			(xy 12.489503 -13.019943) (xy 12.33377 -13.082289) (xy 12.175246 -13.137155) (xy 12.014292 -13.184416)
			(xy 11.851271 -13.223964) (xy 11.686553 -13.255711) (xy 11.520511 -13.279585) (xy 11.35352 -13.295531)
			(xy 11.185961 -13.303513) (xy 11.102086 -13.304012) (xy 1.999996 -13.304012) (xy 1.96883 -13.3045)
			(xy 1.907031 -13.312637) (xy 1.846823 -13.32877) (xy 1.789236 -13.352624) (xy 1.735255 -13.383791)
			(xy 1.685804 -13.421737) (xy 1.641729 -13.465813) (xy 1.603784 -13.515265) (xy 1.572619 -13.569247)
			(xy 1.548766 -13.626834) (xy 1.532634 -13.687043) (xy 1.524499 -13.748842) (xy 1.524 -13.780008)
			(xy 1.524 -16.5207) (xy 76.28834 -16.5207) (xy 76.29237 -16.436094) (xy 76.304425 -16.352254) (xy 76.324394 -16.26994)
			(xy 76.352098 -16.189896) (xy 76.387284 -16.112849) (xy 76.429635 -16.039495) (xy 76.478768 -15.970499)
			(xy 76.534236 -15.906485) (xy 76.595538 -15.848035) (xy 76.662118 -15.795676) (xy 76.733375 -15.749883)
			(xy 76.808661 -15.711071) (xy 76.887296 -15.679591) (xy 76.968567 -15.655728) (xy 77.051738 -15.639698)
			(xy 77.136057 -15.631648) (xy 77.178408 -15.63116) (xy 77.178916 -15.63116) (xy 77.224101 -15.631724)
			(xy 77.314005 -15.640873) (xy 77.402518 -15.659097) (xy 77.488725 -15.686205) (xy 77.530452 -15.70355)
			(xy 77.539034 -15.706862) (xy 77.557395 -15.707764) (xy 77.566266 -15.705328) (xy 77.610936 -15.69133)
			(xy 77.702468 -15.671687) (xy 77.795557 -15.661772) (xy 77.842364 -15.661132) (xy 77.84338 -15.661132)
			(xy 77.885732 -15.661539) (xy 77.970052 -15.669589) (xy 78.053225 -15.685618) (xy 78.134498 -15.70948)
			(xy 78.213134 -15.74096) (xy 78.288422 -15.779772) (xy 78.35968 -15.825565) (xy 78.426262 -15.877924)
			(xy 78.487566 -15.936376) (xy 78.543035 -16.00039) (xy 78.592169 -16.069387) (xy 78.634521 -16.142742)
			(xy 78.669709 -16.219791) (xy 78.697413 -16.299835) (xy 78.717383 -16.382151) (xy 78.722326 -16.416528)
			(xy 191.571372 -16.416528) (xy 191.571784 -16.378238) (xy 191.57839 -16.301944) (xy 191.591537 -16.226502)
			(xy 191.611129 -16.152471) (xy 191.623696 -16.1163) (xy 191.626331 -16.10786) (xy 191.62634 -16.090193)
			(xy 191.623696 -16.081756) (xy 191.611158 -16.045577) (xy 191.591583 -15.971544) (xy 191.578434 -15.896105)
			(xy 191.571809 -15.819816) (xy 191.571372 -15.781528) (xy 191.571879 -15.740418) (xy 191.579464 -15.65855)
			(xy 191.594572 -15.577731) (xy 191.617074 -15.498651) (xy 191.646778 -15.421985) (xy 191.68343 -15.348387)
			(xy 191.726718 -15.278486) (xy 191.776272 -15.212878) (xy 191.831669 -15.152124) (xy 191.892437 -15.096741)
			(xy 191.958056 -15.047202) (xy 192.027967 -15.00393) (xy 192.101573 -14.967295) (xy 192.178246 -14.937609)
			(xy 192.257331 -14.915125) (xy 192.338154 -14.900036) (xy 192.420024 -14.89247) (xy 192.461134 -14.89202)
			(xy 192.499451 -14.892376) (xy 192.575804 -14.898912) (xy 192.651311 -14.912) (xy 192.72541 -14.931543)
			(xy 192.761616 -14.94409) (xy 192.769932 -14.946676) (xy 192.787336 -14.946676) (xy 192.795652 -14.94409)
			(xy 192.831863 -14.931562) (xy 192.905965 -14.912041) (xy 192.981469 -14.898959) (xy 193.057819 -14.892413)
			(xy 193.096134 -14.89202) (xy 193.134451 -14.892376) (xy 193.210804 -14.898912) (xy 193.286311 -14.912)
			(xy 193.36041 -14.931543) (xy 193.396616 -14.94409) (xy 193.404932 -14.946676) (xy 193.422336 -14.946676)
			(xy 193.430652 -14.94409) (xy 193.466772 -14.93159) (xy 193.540685 -14.912102) (xy 193.615997 -14.899021)
			(xy 193.692153 -14.892442) (xy 193.730372 -14.89202) (xy 193.731134 -14.89202) (xy 193.772241 -14.89248)
			(xy 193.854104 -14.900067) (xy 193.934917 -14.915174) (xy 194.013993 -14.937671) (xy 194.090656 -14.967367)
			(xy 194.164253 -15.004008) (xy 194.234156 -15.047282) (xy 194.299769 -15.09682) (xy 194.360532 -15.152199)
			(xy 194.415928 -15.212948) (xy 194.465484 -15.278547) (xy 194.508776 -15.348439) (xy 194.545437 -15.422026)
			(xy 194.575153 -15.498681) (xy 194.597672 -15.577751) (xy 194.6128 -15.658561) (xy 194.620409 -15.740421)
			(xy 194.620896 -15.781528) (xy 194.620451 -15.819809) (xy 194.613795 -15.896082) (xy 194.600605 -15.971499)
			(xy 194.591178 -16.008604) (xy 194.588893 -16.019174) (xy 194.592456 -16.040487) (xy 194.598036 -16.049752)
			(xy 194.621836 -16.08633) (xy 194.662956 -16.163308) (xy 194.696348 -16.24394) (xy 194.721691 -16.327453)
			(xy 194.738741 -16.413043) (xy 194.747336 -16.499892) (xy 194.747896 -16.543528) (xy 194.747474 -16.584639)
			(xy 194.739884 -16.666511) (xy 194.72477 -16.747333) (xy 194.702263 -16.826416) (xy 194.672553 -16.903083)
			(xy 194.635895 -16.976682) (xy 194.592602 -17.046584) (xy 194.543042 -17.112192) (xy 194.487639 -17.172947)
			(xy 194.426866 -17.22833) (xy 194.361241 -17.277868) (xy 194.291325 -17.321138) (xy 194.217714 -17.357772)
			(xy 194.141037 -17.387456) (xy 194.061947 -17.409938) (xy 193.98112 -17.425024) (xy 193.899246 -17.432588)
			(xy 193.858134 -17.433036) (xy 193.814503 -17.432505) (xy 193.727659 -17.42397) (xy 193.642069 -17.40697)
			(xy 193.558556 -17.381667) (xy 193.477923 -17.348306) (xy 193.400945 -17.307207) (xy 193.364358 -17.28343)
			(xy 193.355108 -17.277824) (xy 193.333785 -17.274289) (xy 193.32321 -17.276572) (xy 193.286097 -17.285942)
			(xy 193.210677 -17.299046) (xy 193.134409 -17.305624) (xy 193.096134 -17.306036) (xy 193.057818 -17.305656)
			(xy 192.981465 -17.299127) (xy 192.905958 -17.286046) (xy 192.831859 -17.26651) (xy 192.795652 -17.253966)
			(xy 192.787336 -17.25138) (xy 192.769932 -17.25138) (xy 192.761616 -17.253966) (xy 192.725489 -17.266445)
			(xy 192.651578 -17.285939) (xy 192.576269 -17.299026) (xy 192.500115 -17.305611) (xy 192.461896 -17.306036)
			(xy 192.461134 -17.306036) (xy 192.420027 -17.305555) (xy 192.338163 -17.297973) (xy 192.257348 -17.282872)
			(xy 192.178271 -17.260379) (xy 192.101606 -17.230687) (xy 192.028008 -17.194048) (xy 191.958103 -17.150776)
			(xy 191.892489 -17.10124) (xy 191.831724 -17.045861) (xy 191.776328 -16.985113) (xy 191.726772 -16.919513)
			(xy 191.683479 -16.849621) (xy 191.646819 -16.776033) (xy 191.617104 -16.699377) (xy 191.594588 -16.620307)
			(xy 191.579463 -16.539496) (xy 191.571857 -16.457635) (xy 191.571372 -16.416528) (xy 78.722326 -16.416528)
			(xy 78.729438 -16.465992) (xy 78.733468 -16.5506) (xy 78.729438 -16.635208) (xy 78.717383 -16.719049)
			(xy 78.697413 -16.801365) (xy 78.669709 -16.881409) (xy 78.634521 -16.958458) (xy 78.592169 -17.031813)
			(xy 78.543035 -17.10081) (xy 78.487566 -17.164824) (xy 78.426262 -17.223276) (xy 78.35968 -17.275635)
			(xy 78.288422 -17.321428) (xy 78.213134 -17.36024) (xy 78.134498 -17.39172) (xy 78.053225 -17.415582)
			(xy 77.970052 -17.431611) (xy 77.885732 -17.439661) (xy 77.84338 -17.440148) (xy 77.842872 -17.440148)
			(xy 77.797687 -17.439588) (xy 77.707782 -17.430437) (xy 77.61927 -17.412213) (xy 77.533063 -17.385103)
			(xy 77.491336 -17.367758) (xy 77.482756 -17.36444) (xy 77.464393 -17.363542) (xy 77.455522 -17.36598)
			(xy 77.410853 -17.379982) (xy 77.319321 -17.399623) (xy 77.226231 -17.409537) (xy 77.179424 -17.410176)
			(xy 77.178408 -17.410176) (xy 77.136057 -17.409752) (xy 77.051738 -17.401702) (xy 76.968567 -17.385672)
			(xy 76.887296 -17.361809) (xy 76.808661 -17.330329) (xy 76.733375 -17.291517) (xy 76.662118 -17.245724)
			(xy 76.595538 -17.193365) (xy 76.534236 -17.134915) (xy 76.478768 -17.070901) (xy 76.429635 -17.001905)
			(xy 76.387284 -16.928551) (xy 76.352098 -16.851504) (xy 76.324394 -16.77146) (xy 76.304425 -16.689146)
			(xy 76.29237 -16.605306) (xy 76.28834 -16.5207) (xy 1.524 -16.5207) (xy 1.524 -17.639629) (xy 14.466804 -17.639629)
			(xy 14.466804 -17.585091) (xy 14.474566 -17.531107) (xy 14.489931 -17.478778) (xy 14.512587 -17.429168)
			(xy 14.542073 -17.383287) (xy 14.577788 -17.342069) (xy 14.619005 -17.306354) (xy 14.664886 -17.276868)
			(xy 14.714496 -17.254212) (xy 14.766825 -17.238846) (xy 14.820809 -17.231085) (xy 14.848078 -17.230598)
			(xy 14.871954 -17.23136) (xy 14.889691 -17.201217) (xy 14.929888 -17.143978) (xy 14.952218 -17.11706)
			(xy 14.959537 -17.107372) (xy 14.965118 -17.083781) (xy 14.962886 -17.071848) (xy 14.957561 -17.04917)
			(xy 14.951832 -17.002938) (xy 14.951456 -16.979646) (xy 14.951456 -16.979138) (xy 14.951937 -16.951867)
			(xy 14.959694 -16.89788) (xy 14.975057 -16.845546) (xy 14.997711 -16.795932) (xy 15.027196 -16.750047)
			(xy 15.062912 -16.708826) (xy 15.104131 -16.673108) (xy 15.150015 -16.643621) (xy 15.199628 -16.620964)
			(xy 15.25196 -16.605599) (xy 15.305947 -16.597838) (xy 15.333218 -16.597376) (xy 15.361919 -16.597956)
			(xy 15.418673 -16.606566) (xy 15.473499 -16.623573) (xy 15.525161 -16.648594) (xy 15.572496 -16.681067)
			(xy 15.614438 -16.720259) (xy 15.650041 -16.765286) (xy 15.678504 -16.815136) (xy 15.689326 -16.841724)
			(xy 15.694327 -16.852837) (xy 15.712511 -16.869013) (xy 15.724124 -16.872712) (xy 15.761849 -16.882917)
			(xy 15.835171 -16.909975) (xy 15.905346 -16.944381) (xy 15.938754 -16.96466) (xy 15.94701 -16.969374)
			(xy 15.965678 -16.972901) (xy 15.984346 -16.969374) (xy 15.992602 -16.96466) (xy 16.026008 -16.944378)
			(xy 16.096183 -16.909971) (xy 16.169504 -16.882907) (xy 16.207232 -16.872712) (xy 16.218845 -16.869017)
			(xy 16.237017 -16.852832) (xy 16.24203 -16.841724) (xy 16.252832 -16.815122) (xy 16.281277 -16.76525)
			(xy 16.316871 -16.720202) (xy 16.358812 -16.680995) (xy 16.406154 -16.648512) (xy 16.457826 -16.623488)
			(xy 16.512665 -16.606486) (xy 16.569431 -16.597891) (xy 16.598138 -16.597376) (xy 16.62541 -16.597789)
			(xy 16.679398 -16.605557) (xy 16.731731 -16.620929) (xy 16.781344 -16.643593) (xy 16.827227 -16.673086)
			(xy 16.868445 -16.708809) (xy 16.90416 -16.750034) (xy 16.933644 -16.795922) (xy 16.956297 -16.84554)
			(xy 16.971659 -16.897876) (xy 16.979416 -16.951866) (xy 16.9799 -16.979138) (xy 16.9799 -16.979646)
			(xy 16.979521 -17.002938) (xy 16.973787 -17.049168) (xy 16.96847 -17.071848) (xy 16.96619 -17.083783)
			(xy 16.971771 -17.107396) (xy 16.979138 -17.11706) (xy 17.001468 -17.143978) (xy 17.041665 -17.201217)
			(xy 17.059402 -17.23136) (xy 17.083278 -17.230598) (xy 17.110549 -17.231061) (xy 17.164536 -17.238823)
			(xy 17.216869 -17.254189) (xy 17.266483 -17.276847) (xy 17.312366 -17.306334) (xy 17.353587 -17.342052)
			(xy 17.389304 -17.383272) (xy 17.418792 -17.429156) (xy 17.44145 -17.478769) (xy 17.456816 -17.531102)
			(xy 17.464579 -17.585089) (xy 17.464579 -17.639629) (xy 20.054804 -17.639629) (xy 20.054804 -17.585091)
			(xy 20.062566 -17.531107) (xy 20.077931 -17.478778) (xy 20.100587 -17.429168) (xy 20.130073 -17.383287)
			(xy 20.165788 -17.342069) (xy 20.207005 -17.306354) (xy 20.252886 -17.276868) (xy 20.302496 -17.254212)
			(xy 20.354825 -17.238846) (xy 20.408809 -17.231085) (xy 20.436078 -17.230598) (xy 20.459954 -17.23136)
			(xy 20.477691 -17.201217) (xy 20.517888 -17.143978) (xy 20.540218 -17.11706) (xy 20.547537 -17.107372)
			(xy 20.553118 -17.083781) (xy 20.550886 -17.071848) (xy 20.545561 -17.04917) (xy 20.539832 -17.002938)
			(xy 20.539456 -16.979646) (xy 20.539456 -16.979138) (xy 20.539937 -16.951867) (xy 20.547694 -16.89788)
			(xy 20.563057 -16.845546) (xy 20.585711 -16.795932) (xy 20.615196 -16.750047) (xy 20.650912 -16.708826)
			(xy 20.692131 -16.673108) (xy 20.738015 -16.643621) (xy 20.787628 -16.620964) (xy 20.83996 -16.605599)
			(xy 20.893947 -16.597838) (xy 20.921218 -16.597376) (xy 20.949919 -16.597956) (xy 21.006673 -16.606566)
			(xy 21.061499 -16.623573) (xy 21.113161 -16.648594) (xy 21.160496 -16.681067) (xy 21.202438 -16.720259)
			(xy 21.238041 -16.765286) (xy 21.266504 -16.815136) (xy 21.277326 -16.841724) (xy 21.282327 -16.852837)
			(xy 21.300511 -16.869013) (xy 21.312124 -16.872712) (xy 21.349849 -16.882917) (xy 21.423171 -16.909975)
			(xy 21.493346 -16.944381) (xy 21.526754 -16.96466) (xy 21.53501 -16.969374) (xy 21.553678 -16.972901)
			(xy 21.572346 -16.969374) (xy 21.580602 -16.96466) (xy 21.614008 -16.944378) (xy 21.684183 -16.909971)
			(xy 21.757504 -16.882907) (xy 21.795232 -16.872712) (xy 21.806845 -16.869017) (xy 21.825017 -16.852832)
			(xy 21.83003 -16.841724) (xy 21.840832 -16.815122) (xy 21.869277 -16.76525) (xy 21.904871 -16.720202)
			(xy 21.946812 -16.680995) (xy 21.994154 -16.648512) (xy 22.045826 -16.623488) (xy 22.100665 -16.606486)
			(xy 22.157431 -16.597891) (xy 22.186138 -16.597376) (xy 22.21341 -16.597789) (xy 22.267398 -16.605557)
			(xy 22.319731 -16.620929) (xy 22.369344 -16.643593) (xy 22.415227 -16.673086) (xy 22.456445 -16.708809)
			(xy 22.49216 -16.750034) (xy 22.521644 -16.795922) (xy 22.544297 -16.84554) (xy 22.559659 -16.897876)
			(xy 22.567416 -16.951866) (xy 22.5679 -16.979138) (xy 22.5679 -16.979646) (xy 22.567521 -17.002938)
			(xy 22.561787 -17.049168) (xy 22.55647 -17.071848) (xy 22.55419 -17.083783) (xy 22.559771 -17.107396)
			(xy 22.567138 -17.11706) (xy 22.589468 -17.143978) (xy 22.629665 -17.201217) (xy 22.647402 -17.23136)
			(xy 22.671278 -17.230598) (xy 22.698547 -17.23114) (xy 22.752531 -17.238899) (xy 22.804861 -17.254261)
			(xy 22.854471 -17.276915) (xy 22.900353 -17.306399) (xy 22.941571 -17.342113) (xy 22.977287 -17.383329)
			(xy 23.006774 -17.429209) (xy 23.029431 -17.478819) (xy 23.044797 -17.531148) (xy 23.052559 -17.585131)
			(xy 23.052559 -17.639669) (xy 23.052559 -17.639671) (xy 25.642784 -17.639671) (xy 25.642784 -17.585129)
			(xy 25.650546 -17.531141) (xy 25.665912 -17.478808) (xy 25.688569 -17.429194) (xy 25.718056 -17.38331)
			(xy 25.753773 -17.342088) (xy 25.794992 -17.306369) (xy 25.840875 -17.27688) (xy 25.890488 -17.25422)
			(xy 25.94282 -17.238851) (xy 25.996807 -17.231086) (xy 26.024078 -17.230598) (xy 26.047954 -17.23136)
			(xy 26.065691 -17.201217) (xy 26.105888 -17.143978) (xy 26.128218 -17.11706) (xy 26.135537 -17.107372)
			(xy 26.141118 -17.083781) (xy 26.138886 -17.071848) (xy 26.133561 -17.04917) (xy 26.127832 -17.002938)
			(xy 26.127456 -16.979646) (xy 26.127456 -16.979138) (xy 26.127937 -16.951867) (xy 26.135694 -16.89788)
			(xy 26.151057 -16.845546) (xy 26.173711 -16.795932) (xy 26.203196 -16.750047) (xy 26.238912 -16.708826)
			(xy 26.280131 -16.673108) (xy 26.326015 -16.643621) (xy 26.375628 -16.620964) (xy 26.42796 -16.605599)
			(xy 26.481947 -16.597838) (xy 26.509218 -16.597376) (xy 26.537919 -16.597956) (xy 26.594673 -16.606566)
			(xy 26.649499 -16.623573) (xy 26.701161 -16.648594) (xy 26.748496 -16.681067) (xy 26.790438 -16.720259)
			(xy 26.826041 -16.765286) (xy 26.854504 -16.815136) (xy 26.865326 -16.841724) (xy 26.870327 -16.852837)
			(xy 26.888511 -16.869013) (xy 26.900124 -16.872712) (xy 26.937849 -16.882917) (xy 27.011171 -16.909975)
			(xy 27.081346 -16.944381) (xy 27.114754 -16.96466) (xy 27.12301 -16.969374) (xy 27.141678 -16.972901)
			(xy 27.160346 -16.969374) (xy 27.168602 -16.96466) (xy 27.202008 -16.944378) (xy 27.272183 -16.909971)
			(xy 27.345504 -16.882907) (xy 27.383232 -16.872712) (xy 27.394845 -16.869017) (xy 27.413017 -16.852832)
			(xy 27.41803 -16.841724) (xy 27.428832 -16.815122) (xy 27.457277 -16.76525) (xy 27.492871 -16.720202)
			(xy 27.534812 -16.680995) (xy 27.582154 -16.648512) (xy 27.633826 -16.623488) (xy 27.688665 -16.606486)
			(xy 27.745431 -16.597891) (xy 27.774138 -16.597376) (xy 27.80141 -16.597789) (xy 27.855398 -16.605557)
			(xy 27.907731 -16.620929) (xy 27.957344 -16.643593) (xy 28.003227 -16.673086) (xy 28.044445 -16.708809)
			(xy 28.08016 -16.750034) (xy 28.109644 -16.795922) (xy 28.132297 -16.84554) (xy 28.147659 -16.897876)
			(xy 28.155416 -16.951866) (xy 28.1559 -16.979138) (xy 28.1559 -16.979646) (xy 28.155521 -17.002938)
			(xy 28.149787 -17.049168) (xy 28.14447 -17.071848) (xy 28.14219 -17.083783) (xy 28.147771 -17.107396)
			(xy 28.155138 -17.11706) (xy 28.177468 -17.143978) (xy 28.217665 -17.201217) (xy 28.235402 -17.23136)
			(xy 28.259278 -17.230598) (xy 28.286547 -17.23114) (xy 28.340531 -17.238899) (xy 28.392861 -17.254261)
			(xy 28.442471 -17.276915) (xy 28.488353 -17.306399) (xy 28.529571 -17.342113) (xy 28.565287 -17.383329)
			(xy 28.594774 -17.429209) (xy 28.617431 -17.478819) (xy 28.632797 -17.531148) (xy 28.640559 -17.585131)
			(xy 28.640559 -17.639669) (xy 28.640459 -17.640367) (xy 31.230846 -17.640367) (xy 31.230846 -17.585833)
			(xy 31.238607 -17.531855) (xy 31.25397 -17.47953) (xy 31.276624 -17.429924) (xy 31.306106 -17.384047)
			(xy 31.341817 -17.342832) (xy 31.383029 -17.307119) (xy 31.428905 -17.277634) (xy 31.478509 -17.254978)
			(xy 31.530833 -17.239612) (xy 31.584811 -17.231848) (xy 31.612078 -17.23136) (xy 31.634938 -17.232122)
			(xy 31.652824 -17.201757) (xy 31.693403 -17.144133) (xy 31.715964 -17.11706) (xy 31.723278 -17.107368)
			(xy 31.728865 -17.08378) (xy 31.726632 -17.071848) (xy 31.721406 -17.04935) (xy 31.715805 -17.003502)
			(xy 31.715456 -16.980408) (xy 31.715456 -16.9799) (xy 31.715902 -16.952628) (xy 31.723664 -16.89864)
			(xy 31.739031 -16.846306) (xy 31.76169 -16.796691) (xy 31.79118 -16.750807) (xy 31.826899 -16.709586)
			(xy 31.868121 -16.673869) (xy 31.914007 -16.644382) (xy 31.963623 -16.621725) (xy 32.015957 -16.60636)
			(xy 32.069946 -16.5986) (xy 32.097218 -16.598138) (xy 32.125946 -16.59864) (xy 32.182751 -16.607273)
			(xy 32.237623 -16.624312) (xy 32.289327 -16.649373) (xy 32.336697 -16.681891) (xy 32.378665 -16.721134)
			(xy 32.414286 -16.766216) (xy 32.442757 -16.816123) (xy 32.45358 -16.84274) (xy 32.458598 -16.853844)
			(xy 32.47677 -16.870023) (xy 32.488378 -16.873728) (xy 32.525885 -16.883922) (xy 32.598771 -16.910936)
			(xy 32.668528 -16.945227) (xy 32.701738 -16.965422) (xy 32.709994 -16.970136) (xy 32.728662 -16.973663)
			(xy 32.74733 -16.970136) (xy 32.755586 -16.965422) (xy 32.789134 -16.945005) (xy 32.859631 -16.910383)
			(xy 32.933314 -16.883192) (xy 32.971232 -16.872966) (xy 32.982802 -16.869305) (xy 33.000963 -16.853259)
			(xy 33.00603 -16.842232) (xy 33.016885 -16.815667) (xy 33.045361 -16.765847) (xy 33.080972 -16.72085)
			(xy 33.122915 -16.681687) (xy 33.170245 -16.649241) (xy 33.221898 -16.624242) (xy 33.27671 -16.607254)
			(xy 33.333446 -16.598659) (xy 33.362138 -16.598138) (xy 33.389408 -16.598589) (xy 33.443393 -16.606356)
			(xy 33.495723 -16.621726) (xy 33.545334 -16.644387) (xy 33.591214 -16.673877) (xy 33.632432 -16.709595)
			(xy 33.668146 -16.750816) (xy 33.697632 -16.7967) (xy 33.720287 -16.846312) (xy 33.735652 -16.898644)
			(xy 33.743414 -16.95263) (xy 33.7439 -16.9799) (xy 33.743539 -17.003518) (xy 33.737675 -17.05039)
			(xy 33.732216 -17.073372) (xy 33.729903 -17.085344) (xy 33.735324 -17.109078) (xy 33.74263 -17.118838)
			(xy 33.764791 -17.145529) (xy 33.804732 -17.202258) (xy 33.822386 -17.232122) (xy 33.847278 -17.23136)
			(xy 33.874552 -17.231778) (xy 33.928544 -17.239538) (xy 33.980882 -17.254903) (xy 34.030501 -17.277561)
			(xy 34.07639 -17.30705) (xy 34.117615 -17.342769) (xy 34.153337 -17.383992) (xy 34.182828 -17.42988)
			(xy 34.205489 -17.479497) (xy 34.220857 -17.531835) (xy 34.22862 -17.585826) (xy 34.22862 -17.640366)
			(xy 36.817846 -17.640366) (xy 36.817846 -17.585834) (xy 36.825606 -17.531857) (xy 36.840969 -17.479533)
			(xy 36.863621 -17.429928) (xy 36.893102 -17.384052) (xy 36.928811 -17.342838) (xy 36.970022 -17.307125)
			(xy 37.015895 -17.277639) (xy 37.065498 -17.254982) (xy 37.11782 -17.239615) (xy 37.171796 -17.231849)
			(xy 37.199062 -17.23136) (xy 37.222938 -17.232122) (xy 37.240824 -17.201757) (xy 37.281403 -17.144133)
			(xy 37.303964 -17.11706) (xy 37.311278 -17.107368) (xy 37.316865 -17.08378) (xy 37.314632 -17.071848)
			(xy 37.309406 -17.04935) (xy 37.303805 -17.003502) (xy 37.303456 -16.980408) (xy 37.303456 -16.9799)
			(xy 37.303902 -16.952628) (xy 37.311664 -16.89864) (xy 37.327031 -16.846306) (xy 37.34969 -16.796691)
			(xy 37.37918 -16.750807) (xy 37.414899 -16.709586) (xy 37.456121 -16.673869) (xy 37.502007 -16.644382)
			(xy 37.551623 -16.621725) (xy 37.603957 -16.60636) (xy 37.657946 -16.5986) (xy 37.685218 -16.598138)
			(xy 37.713946 -16.59864) (xy 37.770751 -16.607273) (xy 37.825623 -16.624312) (xy 37.877327 -16.649373)
			(xy 37.924697 -16.681891) (xy 37.966665 -16.721134) (xy 38.002286 -16.766216) (xy 38.030757 -16.816123)
			(xy 38.04158 -16.84274) (xy 38.046598 -16.853844) (xy 38.06477 -16.870023) (xy 38.076378 -16.873728)
			(xy 38.113885 -16.883922) (xy 38.186771 -16.910936) (xy 38.256528 -16.945227) (xy 38.289738 -16.965422)
			(xy 38.297994 -16.970136) (xy 38.316662 -16.973663) (xy 38.33533 -16.970136) (xy 38.343586 -16.965422)
			(xy 38.377134 -16.945005) (xy 38.447631 -16.910383) (xy 38.521314 -16.883192) (xy 38.559232 -16.872966)
			(xy 38.570802 -16.869305) (xy 38.588963 -16.853259) (xy 38.59403 -16.842232) (xy 38.604885 -16.815667)
			(xy 38.633361 -16.765847) (xy 38.668972 -16.72085) (xy 38.710915 -16.681687) (xy 38.758245 -16.649241)
			(xy 38.809898 -16.624242) (xy 38.86471 -16.607254) (xy 38.921446 -16.598659) (xy 38.950138 -16.598138)
			(xy 38.977408 -16.598589) (xy 39.031393 -16.606356) (xy 39.083723 -16.621726) (xy 39.133334 -16.644387)
			(xy 39.179214 -16.673877) (xy 39.220432 -16.709595) (xy 39.256146 -16.750816) (xy 39.285632 -16.7967)
			(xy 39.308287 -16.846312) (xy 39.323652 -16.898644) (xy 39.331414 -16.95263) (xy 39.3319 -16.9799)
			(xy 39.331539 -17.003518) (xy 39.325675 -17.05039) (xy 39.320216 -17.073372) (xy 39.317903 -17.085344)
			(xy 39.323324 -17.109078) (xy 39.33063 -17.118838) (xy 39.352791 -17.145529) (xy 39.392732 -17.202258)
			(xy 39.410386 -17.232122) (xy 39.434262 -17.23136) (xy 39.461536 -17.231777) (xy 39.51553 -17.239535)
			(xy 39.567871 -17.254899) (xy 39.617491 -17.277556) (xy 39.663383 -17.307044) (xy 39.70461 -17.342764)
			(xy 39.740333 -17.383987) (xy 39.769826 -17.429875) (xy 39.792488 -17.479494) (xy 39.807857 -17.531832)
			(xy 39.81562 -17.585826) (xy 39.81562 -17.639672) (xy 42.712585 -17.639672) (xy 42.712585 -17.585128)
			(xy 42.720347 -17.531139) (xy 42.735713 -17.478805) (xy 42.758372 -17.42919) (xy 42.78786 -17.383304)
			(xy 42.823578 -17.342083) (xy 42.8648 -17.306364) (xy 42.910685 -17.276875) (xy 42.960299 -17.254216)
			(xy 43.012633 -17.238848) (xy 43.066622 -17.231085) (xy 43.093894 -17.230598) (xy 43.11777 -17.23136)
			(xy 43.135506 -17.201216) (xy 43.175703 -17.143977) (xy 43.198034 -17.11706) (xy 43.205354 -17.107373)
			(xy 43.210934 -17.083781) (xy 43.208702 -17.071848) (xy 43.203376 -17.04917) (xy 43.197648 -17.002938)
			(xy 43.197272 -16.979646) (xy 43.197272 -16.979138) (xy 43.197737 -16.951866) (xy 43.205495 -16.897878)
			(xy 43.220858 -16.845543) (xy 43.243514 -16.795928) (xy 43.273 -16.750042) (xy 43.308718 -16.708821)
			(xy 43.349939 -16.673103) (xy 43.395824 -16.643615) (xy 43.445439 -16.620959) (xy 43.497774 -16.605596)
			(xy 43.551762 -16.597837) (xy 43.579034 -16.597376) (xy 43.607736 -16.597942) (xy 43.66449 -16.606554)
			(xy 43.719316 -16.623564) (xy 43.770979 -16.648587) (xy 43.818314 -16.681062) (xy 43.860255 -16.720255)
			(xy 43.895858 -16.765284) (xy 43.92432 -16.815135) (xy 43.935142 -16.841724) (xy 43.940185 -16.852813)
			(xy 43.958339 -16.868999) (xy 43.96994 -16.872712) (xy 44.007666 -16.882913) (xy 44.080988 -16.909973)
			(xy 44.151163 -16.94438) (xy 44.18457 -16.96466) (xy 44.192826 -16.969374) (xy 44.211494 -16.972901)
			(xy 44.230162 -16.969374) (xy 44.238418 -16.96466) (xy 44.271822 -16.944374) (xy 44.341998 -16.909969)
			(xy 44.41532 -16.882907) (xy 44.453048 -16.872712) (xy 44.464664 -16.869024) (xy 44.482834 -16.852834)
			(xy 44.487846 -16.841724) (xy 44.498635 -16.815117) (xy 44.527081 -16.765244) (xy 44.562677 -16.720196)
			(xy 44.60462 -16.680988) (xy 44.651964 -16.648506) (xy 44.703638 -16.623483) (xy 44.758479 -16.606483)
			(xy 44.815247 -16.59789) (xy 44.843954 -16.597376) (xy 44.871226 -16.597844) (xy 44.925214 -16.605601)
			(xy 44.977549 -16.620964) (xy 45.027165 -16.643619) (xy 45.07305 -16.673105) (xy 45.114272 -16.708822)
			(xy 45.14999 -16.750043) (xy 45.179478 -16.795928) (xy 45.202134 -16.845543) (xy 45.217497 -16.897878)
			(xy 45.225255 -16.951866) (xy 45.225716 -16.979138) (xy 45.225716 -16.979646) (xy 45.225337 -17.002938)
			(xy 45.219603 -17.049168) (xy 45.214286 -17.071848) (xy 45.212003 -17.083783) (xy 45.217585 -17.107397)
			(xy 45.224954 -17.11706) (xy 45.247284 -17.143977) (xy 45.287481 -17.201217) (xy 45.305218 -17.23136)
			(xy 45.329094 -17.230598) (xy 45.356362 -17.231141) (xy 45.410344 -17.238902) (xy 45.462672 -17.254266)
			(xy 45.512281 -17.276921) (xy 45.558161 -17.306405) (xy 45.599377 -17.342119) (xy 45.635091 -17.383335)
			(xy 45.664577 -17.429214) (xy 45.687232 -17.478822) (xy 45.702597 -17.53115) (xy 45.710359 -17.585132)
			(xy 45.710359 -17.639668) (xy 45.710358 -17.639672) (xy 48.300585 -17.639672) (xy 48.300585 -17.585128)
			(xy 48.308347 -17.531139) (xy 48.323713 -17.478805) (xy 48.346372 -17.42919) (xy 48.37586 -17.383304)
			(xy 48.411578 -17.342083) (xy 48.4528 -17.306364) (xy 48.498685 -17.276875) (xy 48.548299 -17.254216)
			(xy 48.600633 -17.238848) (xy 48.654622 -17.231085) (xy 48.681894 -17.230598) (xy 48.70577 -17.23136)
			(xy 48.723506 -17.201216) (xy 48.763703 -17.143977) (xy 48.786034 -17.11706) (xy 48.793354 -17.107373)
			(xy 48.798934 -17.083781) (xy 48.796702 -17.071848) (xy 48.791376 -17.04917) (xy 48.785648 -17.002938)
			(xy 48.785272 -16.979646) (xy 48.785272 -16.979138) (xy 48.785737 -16.951866) (xy 48.793495 -16.897878)
			(xy 48.808858 -16.845543) (xy 48.831514 -16.795928) (xy 48.861 -16.750042) (xy 48.896718 -16.708821)
			(xy 48.937939 -16.673103) (xy 48.983824 -16.643615) (xy 49.033439 -16.620959) (xy 49.085774 -16.605596)
			(xy 49.139762 -16.597837) (xy 49.167034 -16.597376) (xy 49.195736 -16.597942) (xy 49.25249 -16.606554)
			(xy 49.307316 -16.623564) (xy 49.358979 -16.648587) (xy 49.406314 -16.681062) (xy 49.448255 -16.720255)
			(xy 49.483858 -16.765284) (xy 49.51232 -16.815135) (xy 49.523142 -16.841724) (xy 49.528185 -16.852813)
			(xy 49.546339 -16.868999) (xy 49.55794 -16.872712) (xy 49.595666 -16.882913) (xy 49.668988 -16.909973)
			(xy 49.739163 -16.94438) (xy 49.77257 -16.96466) (xy 49.780826 -16.969374) (xy 49.799494 -16.972901)
			(xy 49.818162 -16.969374) (xy 49.826418 -16.96466) (xy 49.859822 -16.944374) (xy 49.929998 -16.909969)
			(xy 50.00332 -16.882907) (xy 50.041048 -16.872712) (xy 50.052664 -16.869024) (xy 50.070834 -16.852834)
			(xy 50.075846 -16.841724) (xy 50.086635 -16.815117) (xy 50.115081 -16.765244) (xy 50.150677 -16.720196)
			(xy 50.19262 -16.680988) (xy 50.239964 -16.648506) (xy 50.291638 -16.623483) (xy 50.346479 -16.606483)
			(xy 50.403247 -16.59789) (xy 50.431954 -16.597376) (xy 50.459226 -16.597844) (xy 50.513214 -16.605601)
			(xy 50.565549 -16.620964) (xy 50.615165 -16.643619) (xy 50.66105 -16.673105) (xy 50.702272 -16.708822)
			(xy 50.73799 -16.750043) (xy 50.767478 -16.795928) (xy 50.790134 -16.845543) (xy 50.805497 -16.897878)
			(xy 50.813255 -16.951866) (xy 50.813716 -16.979138) (xy 50.813716 -16.979646) (xy 50.813337 -17.002938)
			(xy 50.807603 -17.049168) (xy 50.802286 -17.071848) (xy 50.800003 -17.083783) (xy 50.805585 -17.107397)
			(xy 50.812954 -17.11706) (xy 50.835284 -17.143977) (xy 50.875481 -17.201217) (xy 50.893218 -17.23136)
			(xy 50.917094 -17.230598) (xy 50.944362 -17.231141) (xy 50.998344 -17.238902) (xy 51.050672 -17.254266)
			(xy 51.100281 -17.276921) (xy 51.146161 -17.306405) (xy 51.187377 -17.342119) (xy 51.223091 -17.383335)
			(xy 51.252577 -17.429214) (xy 51.275232 -17.478822) (xy 51.290597 -17.53115) (xy 51.298359 -17.585132)
			(xy 51.298359 -17.639668) (xy 51.298258 -17.64037) (xy 53.921623 -17.64037) (xy 53.921623 -17.58583)
			(xy 53.929386 -17.531845) (xy 53.944752 -17.479514) (xy 53.967409 -17.429903) (xy 53.996896 -17.384021)
			(xy 54.032613 -17.342803) (xy 54.073832 -17.307088) (xy 54.119715 -17.277602) (xy 54.169327 -17.254947)
			(xy 54.221659 -17.239583) (xy 54.275644 -17.231822) (xy 54.302914 -17.23136) (xy 54.32679 -17.232122)
			(xy 54.344672 -17.201754) (xy 54.385254 -17.144132) (xy 54.407816 -17.11706) (xy 54.415134 -17.107372)
			(xy 54.420716 -17.083781) (xy 54.418484 -17.071848) (xy 54.413259 -17.04935) (xy 54.407657 -17.003502)
			(xy 54.407308 -16.980408) (xy 54.407308 -16.9799) (xy 54.407824 -16.952632) (xy 54.415585 -16.898651)
			(xy 54.430949 -16.846324) (xy 54.453603 -16.796716) (xy 54.483086 -16.750836) (xy 54.518798 -16.709619)
			(xy 54.560012 -16.673904) (xy 54.605889 -16.644417) (xy 54.655496 -16.62176) (xy 54.707822 -16.606392)
			(xy 54.761802 -16.598626) (xy 54.78907 -16.598138) (xy 54.817797 -16.598681) (xy 54.8746 -16.607307)
			(xy 54.929471 -16.62434) (xy 54.981175 -16.649394) (xy 55.028545 -16.681907) (xy 55.070514 -16.721144)
			(xy 55.106136 -16.766222) (xy 55.134609 -16.816125) (xy 55.145432 -16.84274) (xy 55.150474 -16.85383)
			(xy 55.168629 -16.870014) (xy 55.18023 -16.873728) (xy 55.217734 -16.883933) (xy 55.290621 -16.910942)
			(xy 55.360379 -16.945229) (xy 55.39359 -16.965422) (xy 55.401846 -16.970136) (xy 55.420514 -16.973663)
			(xy 55.439182 -16.970136) (xy 55.447438 -16.965422) (xy 55.480992 -16.945015) (xy 55.551487 -16.91039)
			(xy 55.625167 -16.883194) (xy 55.663084 -16.872966) (xy 55.674645 -16.869284) (xy 55.692811 -16.853254)
			(xy 55.697882 -16.842232) (xy 55.708693 -16.815648) (xy 55.737175 -16.765827) (xy 55.772792 -16.720828)
			(xy 55.814741 -16.681666) (xy 55.862078 -16.649222) (xy 55.913737 -16.624227) (xy 55.968554 -16.607244)
			(xy 56.025296 -16.598655) (xy 56.05399 -16.598138) (xy 56.081261 -16.598611) (xy 56.135247 -16.606372)
			(xy 56.18758 -16.621737) (xy 56.237193 -16.644393) (xy 56.283077 -16.67388) (xy 56.324297 -16.709596)
			(xy 56.360014 -16.750815) (xy 56.389502 -16.796698) (xy 56.41216 -16.846311) (xy 56.427526 -16.898643)
			(xy 56.435289 -16.952629) (xy 56.435752 -16.9799) (xy 56.435392 -17.003518) (xy 56.429527 -17.05039)
			(xy 56.424068 -17.073372) (xy 56.421766 -17.085345) (xy 56.427181 -17.109076) (xy 56.434482 -17.118838)
			(xy 56.45664 -17.145531) (xy 56.496583 -17.202258) (xy 56.514238 -17.232122) (xy 56.538114 -17.23136)
			(xy 56.565384 -17.231803) (xy 56.619369 -17.239567) (xy 56.6717 -17.254935) (xy 56.721312 -17.277593)
			(xy 56.767193 -17.307081) (xy 56.808412 -17.342798) (xy 56.844128 -17.384018) (xy 56.873614 -17.429901)
			(xy 56.89627 -17.479513) (xy 56.911636 -17.531844) (xy 56.919398 -17.58583) (xy 56.919398 -17.64037)
			(xy 56.911636 -17.694356) (xy 56.89627 -17.746687) (xy 56.873614 -17.796299) (xy 56.844128 -17.842182)
			(xy 56.808412 -17.883402) (xy 56.767193 -17.919119) (xy 56.721312 -17.948607) (xy 56.6717 -17.971265)
			(xy 56.619369 -17.986633) (xy 56.565384 -17.994397) (xy 56.538114 -17.994884) (xy 56.514238 -17.994122)
			(xy 56.496538 -18.024122) (xy 56.456468 -18.081105) (xy 56.434228 -18.107914) (xy 56.426897 -18.117668)
			(xy 56.421447 -18.141411) (xy 56.423814 -18.15338) (xy 56.429387 -18.176604) (xy 56.435369 -18.223988)
			(xy 56.435752 -18.247868) (xy 56.435269 -18.275139) (xy 56.427511 -18.329125) (xy 56.412148 -18.381458)
			(xy 56.389493 -18.431072) (xy 56.360008 -18.476956) (xy 56.324293 -18.518177) (xy 56.283074 -18.553895)
			(xy 56.237191 -18.583383) (xy 56.187579 -18.60604) (xy 56.135247 -18.621406) (xy 56.081261 -18.629167)
			(xy 56.05399 -18.62963) (xy 56.025199 -18.629115) (xy 55.968273 -18.620453) (xy 55.913292 -18.603341)
			(xy 55.861504 -18.578169) (xy 55.814083 -18.545505) (xy 55.772103 -18.506092) (xy 55.736518 -18.460822)
			(xy 55.708133 -18.410722) (xy 55.697374 -18.384012) (xy 55.692358 -18.372794) (xy 55.67404 -18.356471)
			(xy 55.662322 -18.35277) (xy 55.624541 -18.342552) (xy 55.551125 -18.315419) (xy 55.480875 -18.280909)
			(xy 55.447438 -18.260568) (xy 55.439177 -18.255872) (xy 55.420514 -18.252364) (xy 55.401851 -18.255872)
			(xy 55.39359 -18.260568) (xy 55.360453 -18.280729) (xy 55.29086 -18.314995) (xy 55.218154 -18.342034)
			(xy 55.180738 -18.352262) (xy 55.169173 -18.356082) (xy 55.151122 -18.37237) (xy 55.146194 -18.383504)
			(xy 55.135396 -18.410252) (xy 55.107009 -18.460462) (xy 55.071397 -18.505835) (xy 55.029368 -18.545338)
			(xy 54.981879 -18.578074) (xy 54.930008 -18.603299) (xy 54.874934 -18.620439) (xy 54.81791 -18.629106)
			(xy 54.78907 -18.62963) (xy 54.761797 -18.629226) (xy 54.707806 -18.621459) (xy 54.65547 -18.606088)
			(xy 54.605855 -18.583424) (xy 54.55997 -18.55393) (xy 54.518749 -18.518207) (xy 54.483032 -18.47698)
			(xy 54.453546 -18.431091) (xy 54.430891 -18.381471) (xy 54.415528 -18.329133) (xy 54.407769 -18.275141)
			(xy 54.407308 -18.247868) (xy 54.407308 -18.24736) (xy 54.407661 -18.223941) (xy 54.413395 -18.177454)
			(xy 54.418738 -18.15465) (xy 54.421006 -18.14265) (xy 54.415454 -18.118909) (xy 54.40807 -18.109184)
			(xy 54.385466 -18.0821) (xy 54.344757 -18.024481) (xy 54.32679 -17.994122) (xy 54.302914 -17.994884)
			(xy 54.275644 -17.994378) (xy 54.221659 -17.986617) (xy 54.169327 -17.971253) (xy 54.119715 -17.948598)
			(xy 54.073832 -17.919112) (xy 54.032613 -17.883397) (xy 53.996896 -17.842179) (xy 53.967409 -17.796297)
			(xy 53.944752 -17.746686) (xy 53.929386 -17.694355) (xy 53.921623 -17.64037) (xy 51.298258 -17.64037)
			(xy 51.290597 -17.69365) (xy 51.275232 -17.745978) (xy 51.252577 -17.795586) (xy 51.223091 -17.841465)
			(xy 51.187377 -17.882681) (xy 51.146161 -17.918395) (xy 51.100281 -17.947879) (xy 51.050672 -17.970534)
			(xy 50.998344 -17.985898) (xy 50.944362 -17.993659) (xy 50.917094 -17.994122) (xy 50.893218 -17.99336)
			(xy 50.875363 -18.023519) (xy 50.83491 -18.080758) (xy 50.812446 -18.10766) (xy 50.805081 -18.117392)
			(xy 50.799656 -18.141153) (xy 50.802032 -18.153126) (xy 50.80748 -18.17611) (xy 50.813344 -18.22298)
			(xy 50.813716 -18.246598) (xy 50.813716 -18.247106) (xy 50.813304 -18.274379) (xy 50.80554 -18.32837)
			(xy 50.79017 -18.380707) (xy 50.767509 -18.430323) (xy 50.738016 -18.476209) (xy 50.702293 -18.51743)
			(xy 50.661067 -18.553147) (xy 50.615177 -18.582634) (xy 50.565558 -18.605289) (xy 50.513219 -18.620651)
			(xy 50.459227 -18.628408) (xy 50.431954 -18.628868) (xy 50.403141 -18.628313) (xy 50.346172 -18.619639)
			(xy 50.291151 -18.60251) (xy 50.239325 -18.577313) (xy 50.19187 -18.544621) (xy 50.149862 -18.505174)
			(xy 50.114253 -18.459867) (xy 50.08585 -18.409727) (xy 50.075084 -18.382996) (xy 50.070145 -18.371795)
			(xy 50.05195 -18.355474) (xy 50.040286 -18.351754) (xy 50.00269 -18.341522) (xy 49.929627 -18.314444)
			(xy 49.859704 -18.280059) (xy 49.826418 -18.259806) (xy 49.818157 -18.25511) (xy 49.799494 -18.251602)
			(xy 49.780831 -18.25511) (xy 49.77257 -18.259806) (xy 49.739275 -18.280043) (xy 49.669353 -18.314427)
			(xy 49.596297 -18.341522) (xy 49.558702 -18.351754) (xy 49.547063 -18.355508) (xy 49.528896 -18.371831)
			(xy 49.523904 -18.382996) (xy 49.513173 -18.409746) (xy 49.484785 -18.459906) (xy 49.449182 -18.50523)
			(xy 49.407171 -18.544689) (xy 49.359708 -18.577386) (xy 49.30787 -18.602579) (xy 49.252835 -18.619696)
			(xy 49.195852 -18.628348) (xy 49.167034 -18.628868) (xy 49.139764 -18.628367) (xy 49.085779 -18.62061)
			(xy 49.033447 -18.605248) (xy 48.983835 -18.582595) (xy 48.937951 -18.553111) (xy 48.896731 -18.517398)
			(xy 48.861013 -18.476181) (xy 48.831524 -18.430301) (xy 48.808866 -18.38069) (xy 48.793499 -18.32836)
			(xy 48.785736 -18.274376) (xy 48.785272 -18.247106) (xy 48.785272 -18.246598) (xy 48.785631 -18.22298)
			(xy 48.791496 -18.176108) (xy 48.796956 -18.153126) (xy 48.799276 -18.141154) (xy 48.793852 -18.117419)
			(xy 48.786542 -18.10766) (xy 48.764086 -18.080752) (xy 48.723634 -18.023513) (xy 48.70577 -17.99336)
			(xy 48.681894 -17.994122) (xy 48.654622 -17.993715) (xy 48.600633 -17.985952) (xy 48.548299 -17.970584)
			(xy 48.498685 -17.947925) (xy 48.4528 -17.918436) (xy 48.411578 -17.882717) (xy 48.37586 -17.841496)
			(xy 48.346372 -17.79561) (xy 48.323713 -17.745995) (xy 48.308347 -17.693661) (xy 48.300585 -17.639672)
			(xy 45.710358 -17.639672) (xy 45.702597 -17.69365) (xy 45.687232 -17.745978) (xy 45.664577 -17.795586)
			(xy 45.635091 -17.841465) (xy 45.599377 -17.882681) (xy 45.558161 -17.918395) (xy 45.512281 -17.947879)
			(xy 45.462672 -17.970534) (xy 45.410344 -17.985898) (xy 45.356362 -17.993659) (xy 45.329094 -17.994122)
			(xy 45.305218 -17.99336) (xy 45.287363 -18.023519) (xy 45.24691 -18.080758) (xy 45.224446 -18.10766)
			(xy 45.217081 -18.117392) (xy 45.211656 -18.141153) (xy 45.214032 -18.153126) (xy 45.21948 -18.17611)
			(xy 45.225344 -18.22298) (xy 45.225716 -18.246598) (xy 45.225716 -18.247106) (xy 45.225304 -18.274379)
			(xy 45.21754 -18.32837) (xy 45.20217 -18.380707) (xy 45.179509 -18.430323) (xy 45.150016 -18.476209)
			(xy 45.114293 -18.51743) (xy 45.073067 -18.553147) (xy 45.027177 -18.582634) (xy 44.977558 -18.605289)
			(xy 44.925219 -18.620651) (xy 44.871227 -18.628408) (xy 44.843954 -18.628868) (xy 44.815141 -18.628313)
			(xy 44.758172 -18.619639) (xy 44.703151 -18.60251) (xy 44.651325 -18.577313) (xy 44.60387 -18.544621)
			(xy 44.561862 -18.505174) (xy 44.526253 -18.459867) (xy 44.49785 -18.409727) (xy 44.487084 -18.382996)
			(xy 44.482145 -18.371795) (xy 44.46395 -18.355474) (xy 44.452286 -18.351754) (xy 44.41469 -18.341522)
			(xy 44.341627 -18.314444) (xy 44.271704 -18.280059) (xy 44.238418 -18.259806) (xy 44.230157 -18.25511)
			(xy 44.211494 -18.251602) (xy 44.192831 -18.25511) (xy 44.18457 -18.259806) (xy 44.151275 -18.280043)
			(xy 44.081353 -18.314427) (xy 44.008297 -18.341522) (xy 43.970702 -18.351754) (xy 43.959063 -18.355508)
			(xy 43.940896 -18.371831) (xy 43.935904 -18.382996) (xy 43.925173 -18.409746) (xy 43.896785 -18.459906)
			(xy 43.861182 -18.50523) (xy 43.819171 -18.544689) (xy 43.771708 -18.577386) (xy 43.71987 -18.602579)
			(xy 43.664835 -18.619696) (xy 43.607852 -18.628348) (xy 43.579034 -18.628868) (xy 43.551764 -18.628367)
			(xy 43.497779 -18.62061) (xy 43.445447 -18.605248) (xy 43.395835 -18.582595) (xy 43.349951 -18.553111)
			(xy 43.308731 -18.517398) (xy 43.273013 -18.476181) (xy 43.243524 -18.430301) (xy 43.220866 -18.38069)
			(xy 43.205499 -18.32836) (xy 43.197736 -18.274376) (xy 43.197272 -18.247106) (xy 43.197272 -18.246598)
			(xy 43.197631 -18.22298) (xy 43.203496 -18.176108) (xy 43.208956 -18.153126) (xy 43.211276 -18.141154)
			(xy 43.205852 -18.117419) (xy 43.198542 -18.10766) (xy 43.176086 -18.080752) (xy 43.135634 -18.023513)
			(xy 43.11777 -17.99336) (xy 43.093894 -17.994122) (xy 43.066622 -17.993715) (xy 43.012633 -17.985952)
			(xy 42.960299 -17.970584) (xy 42.910685 -17.947925) (xy 42.8648 -17.918436) (xy 42.823578 -17.882717)
			(xy 42.78786 -17.841496) (xy 42.758372 -17.79561) (xy 42.735713 -17.745995) (xy 42.720347 -17.693661)
			(xy 42.712585 -17.639672) (xy 39.81562 -17.639672) (xy 39.81562 -17.640374) (xy 39.807857 -17.694368)
			(xy 39.792488 -17.746706) (xy 39.769826 -17.796325) (xy 39.740333 -17.842213) (xy 39.70461 -17.883436)
			(xy 39.663383 -17.919156) (xy 39.617491 -17.948644) (xy 39.567871 -17.971301) (xy 39.51553 -17.986665)
			(xy 39.461536 -17.994423) (xy 39.434262 -17.994884) (xy 39.410386 -17.994122) (xy 39.392682 -18.02412)
			(xy 39.352615 -18.081105) (xy 39.330376 -18.107914) (xy 39.323041 -18.117665) (xy 39.317596 -18.14141)
			(xy 39.319962 -18.15338) (xy 39.325534 -18.176604) (xy 39.331517 -18.223988) (xy 39.3319 -18.247868)
			(xy 39.331346 -18.275135) (xy 39.32359 -18.329114) (xy 39.30823 -18.38144) (xy 39.285581 -18.431048)
			(xy 39.256102 -18.476927) (xy 39.220393 -18.518144) (xy 39.179183 -18.55386) (xy 39.133309 -18.583347)
			(xy 39.083706 -18.606006) (xy 39.031383 -18.621375) (xy 38.977405 -18.629141) (xy 38.950138 -18.62963)
			(xy 38.921349 -18.629074) (xy 38.864424 -18.620419) (xy 38.809444 -18.603314) (xy 38.757656 -18.578147)
			(xy 38.710235 -18.545489) (xy 38.668255 -18.506081) (xy 38.632668 -18.460816) (xy 38.604282 -18.41072)
			(xy 38.593522 -18.384012) (xy 38.588532 -18.372779) (xy 38.570196 -18.356462) (xy 38.55847 -18.35277)
			(xy 38.520686 -18.342564) (xy 38.447271 -18.315426) (xy 38.377022 -18.280911) (xy 38.343586 -18.260568)
			(xy 38.335325 -18.255872) (xy 38.316662 -18.252364) (xy 38.297999 -18.255872) (xy 38.289738 -18.260568)
			(xy 38.256607 -18.28074) (xy 38.187011 -18.315001) (xy 38.114303 -18.342036) (xy 38.076886 -18.352262)
			(xy 38.065311 -18.356059) (xy 38.047266 -18.372364) (xy 38.042342 -18.383504) (xy 38.031587 -18.410271)
			(xy 38.003195 -18.460483) (xy 37.967577 -18.505856) (xy 37.925542 -18.545359) (xy 37.878046 -18.578093)
			(xy 37.826169 -18.603314) (xy 37.771089 -18.62045) (xy 37.71406 -18.62911) (xy 37.685218 -18.62963)
			(xy 37.657946 -18.629182) (xy 37.603957 -18.621421) (xy 37.551622 -18.606056) (xy 37.502007 -18.583398)
			(xy 37.456121 -18.553909) (xy 37.4149 -18.51819) (xy 37.379183 -18.476967) (xy 37.349696 -18.431081)
			(xy 37.32704 -18.381465) (xy 37.311676 -18.329129) (xy 37.303917 -18.27514) (xy 37.303456 -18.247868)
			(xy 37.303456 -18.24736) (xy 37.303811 -18.223941) (xy 37.309543 -18.177454) (xy 37.314886 -18.15465)
			(xy 37.317143 -18.142649) (xy 37.311596 -18.118911) (xy 37.304218 -18.109184) (xy 37.281611 -18.082102)
			(xy 37.240904 -18.024482) (xy 37.222938 -17.994122) (xy 37.199062 -17.994884) (xy 37.171796 -17.994351)
			(xy 37.11782 -17.986585) (xy 37.065498 -17.971218) (xy 37.015895 -17.948561) (xy 36.970022 -17.919075)
			(xy 36.928811 -17.883362) (xy 36.893102 -17.842148) (xy 36.863621 -17.796272) (xy 36.840969 -17.746667)
			(xy 36.825606 -17.694343) (xy 36.817846 -17.640366) (xy 34.22862 -17.640366) (xy 34.22862 -17.640374)
			(xy 34.220857 -17.694365) (xy 34.205489 -17.746703) (xy 34.182828 -17.79632) (xy 34.153337 -17.842208)
			(xy 34.117615 -17.883431) (xy 34.07639 -17.91915) (xy 34.030501 -17.948639) (xy 33.980882 -17.971297)
			(xy 33.928544 -17.986662) (xy 33.874552 -17.994422) (xy 33.847278 -17.994884) (xy 33.822386 -17.994122)
			(xy 33.804682 -18.02412) (xy 33.764615 -18.081105) (xy 33.742376 -18.107914) (xy 33.735041 -18.117665)
			(xy 33.729596 -18.14141) (xy 33.731962 -18.15338) (xy 33.737534 -18.176604) (xy 33.743517 -18.223988)
			(xy 33.7439 -18.247868) (xy 33.743346 -18.275135) (xy 33.73559 -18.329114) (xy 33.72023 -18.38144)
			(xy 33.697581 -18.431048) (xy 33.668102 -18.476927) (xy 33.632393 -18.518144) (xy 33.591183 -18.55386)
			(xy 33.545309 -18.583347) (xy 33.495706 -18.606006) (xy 33.443383 -18.621375) (xy 33.389405 -18.629141)
			(xy 33.362138 -18.62963) (xy 33.333349 -18.629074) (xy 33.276424 -18.620419) (xy 33.221444 -18.603314)
			(xy 33.169656 -18.578147) (xy 33.122235 -18.545489) (xy 33.080255 -18.506081) (xy 33.044668 -18.460816)
			(xy 33.016282 -18.41072) (xy 33.005522 -18.384012) (xy 33.000532 -18.372779) (xy 32.982196 -18.356462)
			(xy 32.97047 -18.35277) (xy 32.932686 -18.342564) (xy 32.859271 -18.315426) (xy 32.789022 -18.280911)
			(xy 32.755586 -18.260568) (xy 32.747325 -18.255872) (xy 32.728662 -18.252364) (xy 32.709999 -18.255872)
			(xy 32.701738 -18.260568) (xy 32.668607 -18.28074) (xy 32.599011 -18.315001) (xy 32.526303 -18.342036)
			(xy 32.488886 -18.352262) (xy 32.477311 -18.356059) (xy 32.459266 -18.372364) (xy 32.454342 -18.383504)
			(xy 32.443587 -18.410271) (xy 32.415195 -18.460483) (xy 32.379577 -18.505856) (xy 32.337542 -18.545359)
			(xy 32.290046 -18.578093) (xy 32.238169 -18.603314) (xy 32.183089 -18.62045) (xy 32.12606 -18.62911)
			(xy 32.097218 -18.62963) (xy 32.069946 -18.629182) (xy 32.015957 -18.621421) (xy 31.963622 -18.606056)
			(xy 31.914007 -18.583398) (xy 31.868121 -18.553909) (xy 31.8269 -18.51819) (xy 31.791183 -18.476967)
			(xy 31.761696 -18.431081) (xy 31.73904 -18.381465) (xy 31.723676 -18.329129) (xy 31.715917 -18.27514)
			(xy 31.715456 -18.247868) (xy 31.715456 -18.24736) (xy 31.715811 -18.223941) (xy 31.721543 -18.177454)
			(xy 31.726886 -18.15465) (xy 31.729143 -18.142649) (xy 31.723596 -18.118911) (xy 31.716218 -18.109184)
			(xy 31.693611 -18.082102) (xy 31.652904 -18.024482) (xy 31.634938 -17.994122) (xy 31.612078 -17.994884)
			(xy 31.584811 -17.994352) (xy 31.530833 -17.986588) (xy 31.478509 -17.971222) (xy 31.428905 -17.948566)
			(xy 31.383029 -17.919081) (xy 31.341817 -17.883368) (xy 31.306106 -17.842153) (xy 31.276624 -17.796276)
			(xy 31.25397 -17.74667) (xy 31.238607 -17.694345) (xy 31.230846 -17.640367) (xy 28.640459 -17.640367)
			(xy 28.632797 -17.693652) (xy 28.617431 -17.745981) (xy 28.594774 -17.795591) (xy 28.565287 -17.841471)
			(xy 28.529571 -17.882687) (xy 28.488353 -17.918401) (xy 28.442471 -17.947885) (xy 28.392861 -17.970539)
			(xy 28.340531 -17.985901) (xy 28.286547 -17.99366) (xy 28.259278 -17.994122) (xy 28.235402 -17.99336)
			(xy 28.217542 -18.023515) (xy 28.177092 -18.080757) (xy 28.15463 -18.10766) (xy 28.147271 -18.117397)
			(xy 28.141838 -18.141154) (xy 28.144216 -18.153126) (xy 28.149664 -18.17611) (xy 28.155528 -18.22298)
			(xy 28.1559 -18.246598) (xy 28.1559 -18.247106) (xy 28.155381 -18.274374) (xy 28.14762 -18.328354)
			(xy 28.132256 -18.380681) (xy 28.109601 -18.430289) (xy 28.080118 -18.476168) (xy 28.044407 -18.517384)
			(xy 28.003193 -18.553099) (xy 27.957317 -18.582586) (xy 27.907711 -18.605244) (xy 27.855386 -18.620613)
			(xy 27.801406 -18.628379) (xy 27.774138 -18.628868) (xy 27.745325 -18.628327) (xy 27.688355 -18.619651)
			(xy 27.633333 -18.602519) (xy 27.581508 -18.57732) (xy 27.534053 -18.544626) (xy 27.492045 -18.505178)
			(xy 27.456436 -18.459869) (xy 27.428033 -18.409728) (xy 27.417268 -18.382996) (xy 27.412286 -18.371819)
			(xy 27.394121 -18.355489) (xy 27.38247 -18.351754) (xy 27.344873 -18.341525) (xy 27.27181 -18.314446)
			(xy 27.201888 -18.280059) (xy 27.168602 -18.259806) (xy 27.160341 -18.25511) (xy 27.141678 -18.251602)
			(xy 27.123015 -18.25511) (xy 27.114754 -18.259806) (xy 27.081461 -18.280046) (xy 27.011538 -18.314429)
			(xy 26.938481 -18.341523) (xy 26.900886 -18.351754) (xy 26.889244 -18.355501) (xy 26.871079 -18.371829)
			(xy 26.866088 -18.382996) (xy 26.85537 -18.409752) (xy 26.826981 -18.459912) (xy 26.791376 -18.505236)
			(xy 26.749363 -18.544695) (xy 26.701898 -18.577392) (xy 26.650058 -18.602584) (xy 26.595021 -18.619699)
			(xy 26.538037 -18.628349) (xy 26.509218 -18.628868) (xy 26.481948 -18.628382) (xy 26.427962 -18.620622)
			(xy 26.37563 -18.605259) (xy 26.326017 -18.582604) (xy 26.280134 -18.553118) (xy 26.238914 -18.517403)
			(xy 26.203196 -18.476185) (xy 26.173708 -18.430304) (xy 26.15105 -18.380692) (xy 26.135683 -18.328362)
			(xy 26.12792 -18.274376) (xy 26.127456 -18.247106) (xy 26.127456 -18.246598) (xy 26.127815 -18.22298)
			(xy 26.133681 -18.176108) (xy 26.13914 -18.153126) (xy 26.141442 -18.141153) (xy 26.136026 -18.117422)
			(xy 26.128726 -18.10766) (xy 26.106269 -18.080752) (xy 26.065817 -18.023513) (xy 26.047954 -17.99336)
			(xy 26.024078 -17.994122) (xy 25.996807 -17.993714) (xy 25.94282 -17.985949) (xy 25.890488 -17.97058)
			(xy 25.840875 -17.94792) (xy 25.794992 -17.918431) (xy 25.753773 -17.882712) (xy 25.718056 -17.84149)
			(xy 25.688569 -17.795606) (xy 25.665912 -17.745992) (xy 25.650546 -17.693659) (xy 25.642784 -17.639671)
			(xy 23.052559 -17.639671) (xy 23.044797 -17.693652) (xy 23.029431 -17.745981) (xy 23.006774 -17.795591)
			(xy 22.977287 -17.841471) (xy 22.941571 -17.882687) (xy 22.900353 -17.918401) (xy 22.854471 -17.947885)
			(xy 22.804861 -17.970539) (xy 22.752531 -17.985901) (xy 22.698547 -17.99366) (xy 22.671278 -17.994122)
			(xy 22.647402 -17.99336) (xy 22.629542 -18.023515) (xy 22.589092 -18.080757) (xy 22.56663 -18.10766)
			(xy 22.559271 -18.117397) (xy 22.553838 -18.141154) (xy 22.556216 -18.153126) (xy 22.561664 -18.17611)
			(xy 22.567528 -18.22298) (xy 22.5679 -18.246598) (xy 22.5679 -18.247106) (xy 22.567381 -18.274374)
			(xy 22.55962 -18.328354) (xy 22.544256 -18.380681) (xy 22.521601 -18.430289) (xy 22.492118 -18.476168)
			(xy 22.456407 -18.517384) (xy 22.415193 -18.553099) (xy 22.369317 -18.582586) (xy 22.319711 -18.605244)
			(xy 22.267386 -18.620613) (xy 22.213406 -18.628379) (xy 22.186138 -18.628868) (xy 22.157325 -18.628327)
			(xy 22.100355 -18.619651) (xy 22.045333 -18.602519) (xy 21.993508 -18.57732) (xy 21.946053 -18.544626)
			(xy 21.904045 -18.505178) (xy 21.868436 -18.459869) (xy 21.840033 -18.409728) (xy 21.829268 -18.382996)
			(xy 21.824286 -18.371819) (xy 21.806121 -18.355489) (xy 21.79447 -18.351754) (xy 21.756873 -18.341525)
			(xy 21.68381 -18.314446) (xy 21.613888 -18.280059) (xy 21.580602 -18.259806) (xy 21.572341 -18.25511)
			(xy 21.553678 -18.251602) (xy 21.535015 -18.25511) (xy 21.526754 -18.259806) (xy 21.493461 -18.280046)
			(xy 21.423538 -18.314429) (xy 21.350481 -18.341523) (xy 21.312886 -18.351754) (xy 21.301244 -18.355501)
			(xy 21.283079 -18.371829) (xy 21.278088 -18.382996) (xy 21.26737 -18.409752) (xy 21.238981 -18.459912)
			(xy 21.203376 -18.505236) (xy 21.161363 -18.544695) (xy 21.113898 -18.577392) (xy 21.062058 -18.602584)
			(xy 21.007021 -18.619699) (xy 20.950037 -18.628349) (xy 20.921218 -18.628868) (xy 20.893948 -18.628382)
			(xy 20.839962 -18.620622) (xy 20.78763 -18.605259) (xy 20.738017 -18.582604) (xy 20.692134 -18.553118)
			(xy 20.650914 -18.517403) (xy 20.615196 -18.476185) (xy 20.585708 -18.430304) (xy 20.56305 -18.380692)
			(xy 20.547683 -18.328362) (xy 20.53992 -18.274376) (xy 20.539456 -18.247106) (xy 20.539456 -18.246598)
			(xy 20.539815 -18.22298) (xy 20.545681 -18.176108) (xy 20.55114 -18.153126) (xy 20.553442 -18.141153)
			(xy 20.548026 -18.117422) (xy 20.540726 -18.10766) (xy 20.518269 -18.080752) (xy 20.477817 -18.023513)
			(xy 20.459954 -17.99336) (xy 20.436078 -17.994122) (xy 20.408809 -17.993635) (xy 20.354825 -17.985874)
			(xy 20.302496 -17.970508) (xy 20.252886 -17.947852) (xy 20.207005 -17.918366) (xy 20.165788 -17.882651)
			(xy 20.130073 -17.841433) (xy 20.100587 -17.795552) (xy 20.077931 -17.745942) (xy 20.062566 -17.693613)
			(xy 20.054804 -17.639629) (xy 17.464579 -17.639629) (xy 17.464579 -17.639631) (xy 17.456816 -17.693618)
			(xy 17.44145 -17.745951) (xy 17.418792 -17.795564) (xy 17.389304 -17.841448) (xy 17.353587 -17.882668)
			(xy 17.312366 -17.918386) (xy 17.266483 -17.947873) (xy 17.216869 -17.970531) (xy 17.164536 -17.985897)
			(xy 17.110549 -17.993659) (xy 17.083278 -17.994122) (xy 17.059402 -17.99336) (xy 17.041542 -18.023515)
			(xy 17.001092 -18.080757) (xy 16.97863 -18.10766) (xy 16.971271 -18.117397) (xy 16.965838 -18.141154)
			(xy 16.968216 -18.153126) (xy 16.973664 -18.17611) (xy 16.979528 -18.22298) (xy 16.9799 -18.246598)
			(xy 16.9799 -18.247106) (xy 16.979381 -18.274374) (xy 16.97162 -18.328354) (xy 16.956256 -18.380681)
			(xy 16.933601 -18.430289) (xy 16.904118 -18.476168) (xy 16.868407 -18.517384) (xy 16.827193 -18.553099)
			(xy 16.781317 -18.582586) (xy 16.731711 -18.605244) (xy 16.679386 -18.620613) (xy 16.625406 -18.628379)
			(xy 16.598138 -18.628868) (xy 16.569325 -18.628327) (xy 16.512355 -18.619651) (xy 16.457333 -18.602519)
			(xy 16.405508 -18.57732) (xy 16.358053 -18.544626) (xy 16.316045 -18.505178) (xy 16.280436 -18.459869)
			(xy 16.252033 -18.409728) (xy 16.241268 -18.382996) (xy 16.236286 -18.371819) (xy 16.218121 -18.355489)
			(xy 16.20647 -18.351754) (xy 16.168873 -18.341525) (xy 16.09581 -18.314446) (xy 16.025888 -18.280059)
			(xy 15.992602 -18.259806) (xy 15.984341 -18.25511) (xy 15.965678 -18.251602) (xy 15.947015 -18.25511)
			(xy 15.938754 -18.259806) (xy 15.905461 -18.280046) (xy 15.835538 -18.314429) (xy 15.762481 -18.341523)
			(xy 15.724886 -18.351754) (xy 15.713244 -18.355501) (xy 15.695079 -18.371829) (xy 15.690088 -18.382996)
			(xy 15.67937 -18.409752) (xy 15.650981 -18.459912) (xy 15.615376 -18.505236) (xy 15.573363 -18.544695)
			(xy 15.525898 -18.577392) (xy 15.474058 -18.602584) (xy 15.419021 -18.619699) (xy 15.362037 -18.628349)
			(xy 15.333218 -18.628868) (xy 15.305948 -18.628382) (xy 15.251962 -18.620622) (xy 15.19963 -18.605259)
			(xy 15.150017 -18.582604) (xy 15.104134 -18.553118) (xy 15.062914 -18.517403) (xy 15.027196 -18.476185)
			(xy 14.997708 -18.430304) (xy 14.97505 -18.380692) (xy 14.959683 -18.328362) (xy 14.95192 -18.274376)
			(xy 14.951456 -18.247106) (xy 14.951456 -18.246598) (xy 14.951815 -18.22298) (xy 14.957681 -18.176108)
			(xy 14.96314 -18.153126) (xy 14.965442 -18.141153) (xy 14.960026 -18.117422) (xy 14.952726 -18.10766)
			(xy 14.930269 -18.080752) (xy 14.889817 -18.023513) (xy 14.871954 -17.99336) (xy 14.848078 -17.994122)
			(xy 14.820809 -17.993635) (xy 14.766825 -17.985874) (xy 14.714496 -17.970508) (xy 14.664886 -17.947852)
			(xy 14.619005 -17.918366) (xy 14.577788 -17.882651) (xy 14.542073 -17.841433) (xy 14.512587 -17.795552)
			(xy 14.489931 -17.745942) (xy 14.474566 -17.693613) (xy 14.466804 -17.639629) (xy 1.524 -17.639629)
			(xy 1.524 -19.164391) (xy 17.259763 -19.164391) (xy 17.259763 -19.109849) (xy 17.267526 -19.055862)
			(xy 17.282892 -19.00353) (xy 17.30555 -18.953917) (xy 17.335037 -18.908033) (xy 17.370755 -18.866813)
			(xy 17.411975 -18.831096) (xy 17.457858 -18.801609) (xy 17.507472 -18.778951) (xy 17.559804 -18.763585)
			(xy 17.613791 -18.755823) (xy 17.641062 -18.75536) (xy 17.664938 -18.756122) (xy 17.682824 -18.725757)
			(xy 17.723403 -18.668133) (xy 17.745964 -18.64106) (xy 17.753278 -18.631368) (xy 17.758865 -18.60778)
			(xy 17.756632 -18.595848) (xy 17.751406 -18.57335) (xy 17.745805 -18.527502) (xy 17.745456 -18.504408)
			(xy 17.745456 -18.5039) (xy 17.745902 -18.476628) (xy 17.753664 -18.42264) (xy 17.769031 -18.370306)
			(xy 17.79169 -18.320691) (xy 17.82118 -18.274807) (xy 17.856899 -18.233586) (xy 17.898121 -18.197869)
			(xy 17.944007 -18.168382) (xy 17.993623 -18.145725) (xy 18.045957 -18.13036) (xy 18.099946 -18.1226)
			(xy 18.127218 -18.122138) (xy 18.155946 -18.12264) (xy 18.212751 -18.131273) (xy 18.267623 -18.148312)
			(xy 18.319327 -18.173373) (xy 18.366697 -18.205891) (xy 18.408665 -18.245134) (xy 18.444286 -18.290216)
			(xy 18.472757 -18.340123) (xy 18.48358 -18.36674) (xy 18.488598 -18.377844) (xy 18.50677 -18.394023)
			(xy 18.518378 -18.397728) (xy 18.555885 -18.407922) (xy 18.628771 -18.434936) (xy 18.698528 -18.469227)
			(xy 18.731738 -18.489422) (xy 18.739994 -18.494136) (xy 18.758662 -18.497663) (xy 18.77733 -18.494136)
			(xy 18.785586 -18.489422) (xy 18.819134 -18.469005) (xy 18.889631 -18.434383) (xy 18.963314 -18.407192)
			(xy 19.001232 -18.396966) (xy 19.012802 -18.393305) (xy 19.030963 -18.377259) (xy 19.03603 -18.366232)
			(xy 19.046885 -18.339667) (xy 19.075361 -18.289847) (xy 19.110972 -18.24485) (xy 19.152915 -18.205687)
			(xy 19.200245 -18.173241) (xy 19.251898 -18.148242) (xy 19.30671 -18.131254) (xy 19.363446 -18.122659)
			(xy 19.392138 -18.122138) (xy 19.419408 -18.122589) (xy 19.473393 -18.130356) (xy 19.525723 -18.145726)
			(xy 19.575334 -18.168387) (xy 19.621214 -18.197877) (xy 19.662432 -18.233595) (xy 19.698146 -18.274816)
			(xy 19.727632 -18.3207) (xy 19.750287 -18.370312) (xy 19.765652 -18.422644) (xy 19.773414 -18.47663)
			(xy 19.7739 -18.5039) (xy 19.773539 -18.527518) (xy 19.767675 -18.57439) (xy 19.762216 -18.597372)
			(xy 19.759903 -18.609344) (xy 19.765324 -18.633078) (xy 19.77263 -18.642838) (xy 19.794791 -18.669529)
			(xy 19.834732 -18.726258) (xy 19.852386 -18.756122) (xy 19.876262 -18.75536) (xy 19.903531 -18.755843)
			(xy 19.957515 -18.763605) (xy 20.009845 -18.77897) (xy 20.059455 -18.801627) (xy 20.105336 -18.831113)
			(xy 20.146553 -18.866828) (xy 20.182269 -18.908046) (xy 20.211754 -18.953927) (xy 20.234411 -19.003537)
			(xy 20.249776 -19.055867) (xy 20.257538 -19.109851) (xy 20.257538 -19.163671) (xy 22.848784 -19.163671)
			(xy 22.848784 -19.109129) (xy 22.856546 -19.055141) (xy 22.871912 -19.002808) (xy 22.894569 -18.953194)
			(xy 22.924056 -18.90731) (xy 22.959773 -18.866088) (xy 23.000992 -18.830369) (xy 23.046875 -18.80088)
			(xy 23.096488 -18.77822) (xy 23.14882 -18.762851) (xy 23.202807 -18.755086) (xy 23.230078 -18.754598)
			(xy 23.253954 -18.75536) (xy 23.271691 -18.725217) (xy 23.311888 -18.667978) (xy 23.334218 -18.64106)
			(xy 23.341537 -18.631372) (xy 23.347118 -18.607781) (xy 23.344886 -18.595848) (xy 23.339561 -18.57317)
			(xy 23.333832 -18.526938) (xy 23.333456 -18.503646) (xy 23.333456 -18.503138) (xy 23.333937 -18.475867)
			(xy 23.341694 -18.42188) (xy 23.357057 -18.369546) (xy 23.379711 -18.319932) (xy 23.409196 -18.274047)
			(xy 23.444912 -18.232826) (xy 23.486131 -18.197108) (xy 23.532015 -18.167621) (xy 23.581628 -18.144964)
			(xy 23.63396 -18.129599) (xy 23.687947 -18.121838) (xy 23.715218 -18.121376) (xy 23.743919 -18.121956)
			(xy 23.800673 -18.130566) (xy 23.855499 -18.147573) (xy 23.907161 -18.172594) (xy 23.954496 -18.205067)
			(xy 23.996438 -18.244259) (xy 24.032041 -18.289286) (xy 24.060504 -18.339136) (xy 24.071326 -18.365724)
			(xy 24.076327 -18.376837) (xy 24.094511 -18.393013) (xy 24.106124 -18.396712) (xy 24.143849 -18.406917)
			(xy 24.217171 -18.433975) (xy 24.287346 -18.468381) (xy 24.320754 -18.48866) (xy 24.32901 -18.493374)
			(xy 24.347678 -18.496901) (xy 24.366346 -18.493374) (xy 24.374602 -18.48866) (xy 24.408008 -18.468378)
			(xy 24.478183 -18.433971) (xy 24.551504 -18.406907) (xy 24.589232 -18.396712) (xy 24.600845 -18.393017)
			(xy 24.619017 -18.376832) (xy 24.62403 -18.365724) (xy 24.634832 -18.339122) (xy 24.663277 -18.28925)
			(xy 24.698871 -18.244202) (xy 24.740812 -18.204995) (xy 24.788154 -18.172512) (xy 24.839826 -18.147488)
			(xy 24.894665 -18.130486) (xy 24.951431 -18.121891) (xy 24.980138 -18.121376) (xy 25.00741 -18.121789)
			(xy 25.061398 -18.129557) (xy 25.113731 -18.144929) (xy 25.163344 -18.167593) (xy 25.209227 -18.197086)
			(xy 25.250445 -18.232809) (xy 25.28616 -18.274034) (xy 25.315644 -18.319922) (xy 25.338297 -18.36954)
			(xy 25.353659 -18.421876) (xy 25.361416 -18.475866) (xy 25.3619 -18.503138) (xy 25.3619 -18.503646)
			(xy 25.361521 -18.526938) (xy 25.355787 -18.573168) (xy 25.35047 -18.595848) (xy 25.34819 -18.607783)
			(xy 25.353771 -18.631396) (xy 25.361138 -18.64106) (xy 25.383468 -18.667978) (xy 25.423665 -18.725217)
			(xy 25.441402 -18.75536) (xy 25.465278 -18.754598) (xy 25.492547 -18.75514) (xy 25.546531 -18.762899)
			(xy 25.598861 -18.778261) (xy 25.648471 -18.800915) (xy 25.694353 -18.830399) (xy 25.735571 -18.866113)
			(xy 25.771287 -18.907329) (xy 25.800774 -18.953209) (xy 25.823431 -19.002819) (xy 25.838797 -19.055148)
			(xy 25.846559 -19.109131) (xy 25.846559 -19.163669) (xy 25.846559 -19.163671) (xy 28.436784 -19.163671)
			(xy 28.436784 -19.109129) (xy 28.444546 -19.055141) (xy 28.459912 -19.002808) (xy 28.482569 -18.953194)
			(xy 28.512056 -18.90731) (xy 28.547773 -18.866088) (xy 28.588992 -18.830369) (xy 28.634875 -18.80088)
			(xy 28.684488 -18.77822) (xy 28.73682 -18.762851) (xy 28.790807 -18.755086) (xy 28.818078 -18.754598)
			(xy 28.841954 -18.75536) (xy 28.859691 -18.725217) (xy 28.899888 -18.667978) (xy 28.922218 -18.64106)
			(xy 28.929537 -18.631372) (xy 28.935118 -18.607781) (xy 28.932886 -18.595848) (xy 28.927561 -18.57317)
			(xy 28.921832 -18.526938) (xy 28.921456 -18.503646) (xy 28.921456 -18.503138) (xy 28.921937 -18.475867)
			(xy 28.929694 -18.42188) (xy 28.945057 -18.369546) (xy 28.967711 -18.319932) (xy 28.997196 -18.274047)
			(xy 29.032912 -18.232826) (xy 29.074131 -18.197108) (xy 29.120015 -18.167621) (xy 29.169628 -18.144964)
			(xy 29.22196 -18.129599) (xy 29.275947 -18.121838) (xy 29.303218 -18.121376) (xy 29.331919 -18.121956)
			(xy 29.388673 -18.130566) (xy 29.443499 -18.147573) (xy 29.495161 -18.172594) (xy 29.542496 -18.205067)
			(xy 29.584438 -18.244259) (xy 29.620041 -18.289286) (xy 29.648504 -18.339136) (xy 29.659326 -18.365724)
			(xy 29.664327 -18.376837) (xy 29.682511 -18.393013) (xy 29.694124 -18.396712) (xy 29.731849 -18.406917)
			(xy 29.805171 -18.433975) (xy 29.875346 -18.468381) (xy 29.908754 -18.48866) (xy 29.91701 -18.493374)
			(xy 29.935678 -18.496901) (xy 29.954346 -18.493374) (xy 29.962602 -18.48866) (xy 29.996008 -18.468378)
			(xy 30.066183 -18.433971) (xy 30.139504 -18.406907) (xy 30.177232 -18.396712) (xy 30.188845 -18.393017)
			(xy 30.207017 -18.376832) (xy 30.21203 -18.365724) (xy 30.222832 -18.339122) (xy 30.251277 -18.28925)
			(xy 30.286871 -18.244202) (xy 30.328812 -18.204995) (xy 30.376154 -18.172512) (xy 30.427826 -18.147488)
			(xy 30.482665 -18.130486) (xy 30.539431 -18.121891) (xy 30.568138 -18.121376) (xy 30.59541 -18.121789)
			(xy 30.649398 -18.129557) (xy 30.701731 -18.144929) (xy 30.751344 -18.167593) (xy 30.797227 -18.197086)
			(xy 30.838445 -18.232809) (xy 30.87416 -18.274034) (xy 30.903644 -18.319922) (xy 30.926297 -18.36954)
			(xy 30.941659 -18.421876) (xy 30.949416 -18.475866) (xy 30.9499 -18.503138) (xy 30.9499 -18.503646)
			(xy 30.949521 -18.526938) (xy 30.943787 -18.573168) (xy 30.93847 -18.595848) (xy 30.93619 -18.607783)
			(xy 30.941771 -18.631396) (xy 30.949138 -18.64106) (xy 30.971468 -18.667978) (xy 31.011665 -18.725217)
			(xy 31.029402 -18.75536) (xy 31.053278 -18.754598) (xy 31.080547 -18.75514) (xy 31.134531 -18.762899)
			(xy 31.186861 -18.778261) (xy 31.236471 -18.800915) (xy 31.282353 -18.830399) (xy 31.323571 -18.866113)
			(xy 31.359287 -18.907329) (xy 31.388774 -18.953209) (xy 31.411431 -19.002819) (xy 31.426797 -19.055148)
			(xy 31.434559 -19.109131) (xy 31.434559 -19.163669) (xy 31.434559 -19.163671) (xy 34.024784 -19.163671)
			(xy 34.024784 -19.109129) (xy 34.032546 -19.055141) (xy 34.047912 -19.002808) (xy 34.070569 -18.953194)
			(xy 34.100056 -18.90731) (xy 34.135773 -18.866088) (xy 34.176992 -18.830369) (xy 34.222875 -18.80088)
			(xy 34.272488 -18.77822) (xy 34.32482 -18.762851) (xy 34.378807 -18.755086) (xy 34.406078 -18.754598)
			(xy 34.429954 -18.75536) (xy 34.447691 -18.725217) (xy 34.487888 -18.667978) (xy 34.510218 -18.64106)
			(xy 34.517537 -18.631372) (xy 34.523118 -18.607781) (xy 34.520886 -18.595848) (xy 34.515561 -18.57317)
			(xy 34.509832 -18.526938) (xy 34.509456 -18.503646) (xy 34.509456 -18.503138) (xy 34.509937 -18.475867)
			(xy 34.517694 -18.42188) (xy 34.533057 -18.369546) (xy 34.555711 -18.319932) (xy 34.585196 -18.274047)
			(xy 34.620912 -18.232826) (xy 34.662131 -18.197108) (xy 34.708015 -18.167621) (xy 34.757628 -18.144964)
			(xy 34.80996 -18.129599) (xy 34.863947 -18.121838) (xy 34.891218 -18.121376) (xy 34.919919 -18.121956)
			(xy 34.976673 -18.130566) (xy 35.031499 -18.147573) (xy 35.083161 -18.172594) (xy 35.130496 -18.205067)
			(xy 35.172438 -18.244259) (xy 35.208041 -18.289286) (xy 35.236504 -18.339136) (xy 35.247326 -18.365724)
			(xy 35.252327 -18.376837) (xy 35.270511 -18.393013) (xy 35.282124 -18.396712) (xy 35.319849 -18.406917)
			(xy 35.393171 -18.433975) (xy 35.463346 -18.468381) (xy 35.496754 -18.48866) (xy 35.50501 -18.493374)
			(xy 35.523678 -18.496901) (xy 35.542346 -18.493374) (xy 35.550602 -18.48866) (xy 35.584008 -18.468378)
			(xy 35.654183 -18.433971) (xy 35.727504 -18.406907) (xy 35.765232 -18.396712) (xy 35.776845 -18.393017)
			(xy 35.795017 -18.376832) (xy 35.80003 -18.365724) (xy 35.810832 -18.339122) (xy 35.839277 -18.28925)
			(xy 35.874871 -18.244202) (xy 35.916812 -18.204995) (xy 35.964154 -18.172512) (xy 36.015826 -18.147488)
			(xy 36.070665 -18.130486) (xy 36.127431 -18.121891) (xy 36.156138 -18.121376) (xy 36.18341 -18.121789)
			(xy 36.237398 -18.129557) (xy 36.289731 -18.144929) (xy 36.339344 -18.167593) (xy 36.385227 -18.197086)
			(xy 36.426445 -18.232809) (xy 36.46216 -18.274034) (xy 36.491644 -18.319922) (xy 36.514297 -18.36954)
			(xy 36.529659 -18.421876) (xy 36.537416 -18.475866) (xy 36.5379 -18.503138) (xy 36.5379 -18.503646)
			(xy 36.537521 -18.526938) (xy 36.531787 -18.573168) (xy 36.52647 -18.595848) (xy 36.52419 -18.607783)
			(xy 36.529771 -18.631396) (xy 36.537138 -18.64106) (xy 36.559468 -18.667978) (xy 36.599665 -18.725217)
			(xy 36.617402 -18.75536) (xy 36.641278 -18.754598) (xy 36.668547 -18.75514) (xy 36.722531 -18.762899)
			(xy 36.774861 -18.778261) (xy 36.824471 -18.800915) (xy 36.870353 -18.830399) (xy 36.911571 -18.866113)
			(xy 36.947287 -18.907329) (xy 36.976774 -18.953209) (xy 36.999431 -19.002819) (xy 37.014797 -19.055148)
			(xy 37.022559 -19.109131) (xy 37.022559 -19.163669) (xy 37.022559 -19.163672) (xy 39.918585 -19.163672)
			(xy 39.918585 -19.109128) (xy 39.926347 -19.055139) (xy 39.941713 -19.002805) (xy 39.964372 -18.95319)
			(xy 39.99386 -18.907304) (xy 40.029578 -18.866083) (xy 40.0708 -18.830364) (xy 40.116685 -18.800875)
			(xy 40.166299 -18.778216) (xy 40.218633 -18.762848) (xy 40.272622 -18.755085) (xy 40.299894 -18.754598)
			(xy 40.32377 -18.75536) (xy 40.341506 -18.725216) (xy 40.381703 -18.667977) (xy 40.404034 -18.64106)
			(xy 40.411354 -18.631373) (xy 40.416934 -18.607781) (xy 40.414702 -18.595848) (xy 40.409376 -18.57317)
			(xy 40.403648 -18.526938) (xy 40.403272 -18.503646) (xy 40.403272 -18.503138) (xy 40.403737 -18.475866)
			(xy 40.411495 -18.421878) (xy 40.426858 -18.369543) (xy 40.449514 -18.319928) (xy 40.479 -18.274042)
			(xy 40.514718 -18.232821) (xy 40.555939 -18.197103) (xy 40.601824 -18.167615) (xy 40.651439 -18.144959)
			(xy 40.703774 -18.129596) (xy 40.757762 -18.121837) (xy 40.785034 -18.121376) (xy 40.813736 -18.121942)
			(xy 40.87049 -18.130554) (xy 40.925316 -18.147564) (xy 40.976979 -18.172587) (xy 41.024314 -18.205062)
			(xy 41.066255 -18.244255) (xy 41.101858 -18.289284) (xy 41.13032 -18.339135) (xy 41.141142 -18.365724)
			(xy 41.146185 -18.376813) (xy 41.164339 -18.392999) (xy 41.17594 -18.396712) (xy 41.213666 -18.406913)
			(xy 41.286988 -18.433973) (xy 41.357163 -18.46838) (xy 41.39057 -18.48866) (xy 41.398826 -18.493374)
			(xy 41.417494 -18.496901) (xy 41.436162 -18.493374) (xy 41.444418 -18.48866) (xy 41.477822 -18.468374)
			(xy 41.547998 -18.433969) (xy 41.62132 -18.406907) (xy 41.659048 -18.396712) (xy 41.670664 -18.393024)
			(xy 41.688834 -18.376834) (xy 41.693846 -18.365724) (xy 41.704635 -18.339117) (xy 41.733081 -18.289244)
			(xy 41.768677 -18.244196) (xy 41.81062 -18.204988) (xy 41.857964 -18.172506) (xy 41.909638 -18.147483)
			(xy 41.964479 -18.130483) (xy 42.021247 -18.12189) (xy 42.049954 -18.121376) (xy 42.077226 -18.121844)
			(xy 42.131214 -18.129601) (xy 42.183549 -18.144964) (xy 42.233165 -18.167619) (xy 42.27905 -18.197105)
			(xy 42.320272 -18.232822) (xy 42.35599 -18.274043) (xy 42.385478 -18.319928) (xy 42.408134 -18.369543)
			(xy 42.423497 -18.421878) (xy 42.431255 -18.475866) (xy 42.431716 -18.503138) (xy 42.431716 -18.503646)
			(xy 42.431337 -18.526938) (xy 42.425603 -18.573168) (xy 42.420286 -18.595848) (xy 42.418003 -18.607783)
			(xy 42.423585 -18.631397) (xy 42.430954 -18.64106) (xy 42.453284 -18.667977) (xy 42.493481 -18.725217)
			(xy 42.511218 -18.75536) (xy 42.535094 -18.754598) (xy 42.562362 -18.755141) (xy 42.616344 -18.762902)
			(xy 42.668672 -18.778266) (xy 42.718281 -18.800921) (xy 42.764161 -18.830405) (xy 42.805377 -18.866119)
			(xy 42.841091 -18.907335) (xy 42.870577 -18.953214) (xy 42.893232 -19.002822) (xy 42.908597 -19.05515)
			(xy 42.916359 -19.109132) (xy 42.916359 -19.163668) (xy 42.916258 -19.164367) (xy 45.505646 -19.164367)
			(xy 45.505646 -19.109833) (xy 45.513407 -19.055855) (xy 45.52877 -19.00353) (xy 45.551424 -18.953924)
			(xy 45.580906 -18.908047) (xy 45.616617 -18.866832) (xy 45.657829 -18.831119) (xy 45.703705 -18.801634)
			(xy 45.753309 -18.778978) (xy 45.805633 -18.763612) (xy 45.859611 -18.755848) (xy 45.886878 -18.75536)
			(xy 45.910754 -18.756122) (xy 45.928638 -18.725756) (xy 45.969218 -18.668133) (xy 45.99178 -18.64106)
			(xy 45.999096 -18.63137) (xy 46.004681 -18.607781) (xy 46.002448 -18.595848) (xy 45.997222 -18.57335)
			(xy 45.991621 -18.527502) (xy 45.991272 -18.504408) (xy 45.991272 -18.5039) (xy 45.991702 -18.476627)
			(xy 45.999465 -18.422638) (xy 46.014833 -18.370302) (xy 46.037493 -18.320687) (xy 46.066983 -18.274801)
			(xy 46.102705 -18.23358) (xy 46.143929 -18.197863) (xy 46.189817 -18.168376) (xy 46.239434 -18.145721)
			(xy 46.291771 -18.130357) (xy 46.345761 -18.122599) (xy 46.373034 -18.122138) (xy 46.40176 -18.122712)
			(xy 46.458561 -18.131333) (xy 46.513432 -18.14836) (xy 46.565135 -18.17341) (xy 46.612506 -18.205918)
			(xy 46.654475 -18.245152) (xy 46.690099 -18.290227) (xy 46.718572 -18.340126) (xy 46.729396 -18.36674)
			(xy 46.734406 -18.377848) (xy 46.752584 -18.394025) (xy 46.764194 -18.397728) (xy 46.801702 -18.407919)
			(xy 46.874587 -18.434934) (xy 46.944345 -18.469226) (xy 46.977554 -18.489422) (xy 46.985802 -18.494137)
			(xy 47.004442 -18.497734) (xy 47.023117 -18.494325) (xy 47.031402 -18.489676) (xy 47.069036 -18.466836)
			(xy 47.148534 -18.429009) (xy 47.231849 -18.400564) (xy 47.274734 -18.390616) (xy 47.286764 -18.387415)
			(xy 47.305809 -18.371426) (xy 47.311056 -18.360136) (xy 47.322167 -18.33413) (xy 47.350959 -18.285457)
			(xy 47.386616 -18.241564) (xy 47.428358 -18.203411) (xy 47.475272 -18.171834) (xy 47.526331 -18.147522)
			(xy 47.580418 -18.131009) (xy 47.636348 -18.122656) (xy 47.664624 -18.122138) (xy 47.691894 -18.122602)
			(xy 47.745878 -18.130367) (xy 47.798208 -18.145735) (xy 47.847819 -18.168394) (xy 47.893699 -18.197883)
			(xy 47.934917 -18.2336) (xy 47.970632 -18.27482) (xy 48.000117 -18.320703) (xy 48.022773 -18.370314)
			(xy 48.038138 -18.422645) (xy 48.0459 -18.47663) (xy 48.046386 -18.5039) (xy 48.046386 -18.504154)
			(xy 48.045808 -18.533325) (xy 48.036873 -18.590981) (xy 48.028606 -18.618962) (xy 48.025505 -18.630975)
			(xy 48.030038 -18.655342) (xy 48.037242 -18.665444) (xy 48.053888 -18.687136) (xy 48.084399 -18.732518)
			(xy 48.098202 -18.756122) (xy 48.122078 -18.75536) (xy 48.149352 -18.755778) (xy 48.203344 -18.763538)
			(xy 48.255682 -18.778903) (xy 48.305301 -18.801561) (xy 48.35119 -18.83105) (xy 48.392415 -18.866769)
			(xy 48.428137 -18.907992) (xy 48.457628 -18.95388) (xy 48.480289 -19.003497) (xy 48.495657 -19.055835)
			(xy 48.50342 -19.109826) (xy 48.50342 -19.163675) (xy 51.128562 -19.163675) (xy 51.128562 -19.109125)
			(xy 51.136325 -19.05513) (xy 51.151695 -19.002789) (xy 51.174357 -18.953169) (xy 51.20385 -18.907279)
			(xy 51.239575 -18.866054) (xy 51.280803 -18.830332) (xy 51.326695 -18.800843) (xy 51.376317 -18.778184)
			(xy 51.428659 -18.762819) (xy 51.482655 -18.75506) (xy 51.50993 -18.754598) (xy 51.533806 -18.75536)
			(xy 51.551546 -18.725219) (xy 51.591741 -18.667978) (xy 51.61407 -18.64106) (xy 51.621385 -18.631369)
			(xy 51.626971 -18.60778) (xy 51.624738 -18.595848) (xy 51.619412 -18.57317) (xy 51.613684 -18.526938)
			(xy 51.613308 -18.503646) (xy 51.613308 -18.503138) (xy 51.613837 -18.475869) (xy 51.621593 -18.421886)
			(xy 51.636953 -18.369557) (xy 51.659604 -18.319946) (xy 51.689085 -18.274063) (xy 51.724795 -18.232843)
			(xy 51.766009 -18.197125) (xy 51.811886 -18.167636) (xy 51.861493 -18.144977) (xy 51.91382 -18.129607)
			(xy 51.967801 -18.121842) (xy 51.99507 -18.121376) (xy 52.023773 -18.121912) (xy 52.080528 -18.130529)
			(xy 52.135355 -18.147543) (xy 52.187018 -18.172571) (xy 52.234353 -18.20505) (xy 52.276294 -18.244247)
			(xy 52.311896 -18.28928) (xy 52.340357 -18.339134) (xy 52.351178 -18.365724) (xy 52.356203 -18.376824)
			(xy 52.37437 -18.393005) (xy 52.385976 -18.396712) (xy 52.423705 -18.406905) (xy 52.497026 -18.433968)
			(xy 52.567199 -18.468379) (xy 52.600606 -18.48866) (xy 52.608862 -18.493374) (xy 52.62753 -18.496901)
			(xy 52.646198 -18.493374) (xy 52.654454 -18.48866) (xy 52.687866 -18.468387) (xy 52.758039 -18.433977)
			(xy 52.831357 -18.40691) (xy 52.869084 -18.396712) (xy 52.880706 -18.39304) (xy 52.898873 -18.376838)
			(xy 52.903882 -18.365724) (xy 52.914641 -18.339104) (xy 52.943091 -18.28923) (xy 52.978691 -18.244181)
			(xy 53.020638 -18.204974) (xy 53.067986 -18.172493) (xy 53.119665 -18.147472) (xy 53.174509 -18.130476)
			(xy 53.231281 -18.121888) (xy 53.25999 -18.121376) (xy 53.287262 -18.121811) (xy 53.341252 -18.129573)
			(xy 53.393588 -18.14494) (xy 53.443204 -18.167599) (xy 53.489089 -18.197089) (xy 53.53031 -18.23281)
			(xy 53.566028 -18.274033) (xy 53.595515 -18.319921) (xy 53.61817 -18.369538) (xy 53.633533 -18.421875)
			(xy 53.641291 -18.475865) (xy 53.641752 -18.503138) (xy 53.641752 -18.503646) (xy 53.641372 -18.526938)
			(xy 53.635639 -18.573168) (xy 53.630322 -18.595848) (xy 53.62803 -18.607782) (xy 53.633616 -18.631398)
			(xy 53.64099 -18.64106) (xy 53.663323 -18.667976) (xy 53.703518 -18.725217) (xy 53.721254 -18.75536)
			(xy 53.74513 -18.754598) (xy 53.772395 -18.755166) (xy 53.82637 -18.762931) (xy 53.87869 -18.778297)
			(xy 53.928291 -18.800953) (xy 53.974164 -18.830436) (xy 54.015374 -18.866148) (xy 54.051082 -18.90736)
			(xy 54.080562 -18.953235) (xy 54.103213 -19.002838) (xy 54.118576 -19.05516) (xy 54.126336 -19.109135)
			(xy 54.126336 -19.163665) (xy 54.126335 -19.163675) (xy 56.716562 -19.163675) (xy 56.716562 -19.109125)
			(xy 56.724325 -19.05513) (xy 56.739695 -19.002789) (xy 56.762357 -18.953169) (xy 56.79185 -18.907279)
			(xy 56.827575 -18.866054) (xy 56.868803 -18.830332) (xy 56.914695 -18.800843) (xy 56.964317 -18.778184)
			(xy 57.016659 -18.762819) (xy 57.070655 -18.75506) (xy 57.09793 -18.754598) (xy 57.121806 -18.75536)
			(xy 57.139546 -18.725219) (xy 57.179741 -18.667978) (xy 57.20207 -18.64106) (xy 57.209385 -18.631369)
			(xy 57.214971 -18.60778) (xy 57.212738 -18.595848) (xy 57.207412 -18.57317) (xy 57.201684 -18.526938)
			(xy 57.201308 -18.503646) (xy 57.201308 -18.503138) (xy 57.201837 -18.475869) (xy 57.209593 -18.421886)
			(xy 57.224953 -18.369557) (xy 57.247604 -18.319946) (xy 57.277085 -18.274063) (xy 57.312795 -18.232843)
			(xy 57.354009 -18.197125) (xy 57.399886 -18.167636) (xy 57.449493 -18.144977) (xy 57.50182 -18.129607)
			(xy 57.555801 -18.121842) (xy 57.58307 -18.121376) (xy 57.611773 -18.121912) (xy 57.668528 -18.130529)
			(xy 57.723355 -18.147543) (xy 57.775018 -18.172571) (xy 57.822353 -18.20505) (xy 57.864294 -18.244247)
			(xy 57.899896 -18.28928) (xy 57.928357 -18.339134) (xy 57.939178 -18.365724) (xy 57.944203 -18.376824)
			(xy 57.96237 -18.393005) (xy 57.973976 -18.396712) (xy 58.011705 -18.406905) (xy 58.085026 -18.433968)
			(xy 58.155199 -18.468379) (xy 58.188606 -18.48866) (xy 58.196862 -18.493374) (xy 58.21553 -18.496901)
			(xy 58.234198 -18.493374) (xy 58.242454 -18.48866) (xy 58.275866 -18.468387) (xy 58.346039 -18.433977)
			(xy 58.419357 -18.40691) (xy 58.457084 -18.396712) (xy 58.468706 -18.39304) (xy 58.486873 -18.376838)
			(xy 58.491882 -18.365724) (xy 58.502641 -18.339104) (xy 58.531091 -18.28923) (xy 58.566691 -18.244181)
			(xy 58.608638 -18.204974) (xy 58.655986 -18.172493) (xy 58.707665 -18.147472) (xy 58.762509 -18.130476)
			(xy 58.819281 -18.121888) (xy 58.84799 -18.121376) (xy 58.875262 -18.121811) (xy 58.929252 -18.129573)
			(xy 58.981588 -18.14494) (xy 59.031204 -18.167599) (xy 59.077089 -18.197089) (xy 59.11831 -18.23281)
			(xy 59.154028 -18.274033) (xy 59.183515 -18.319921) (xy 59.20617 -18.369538) (xy 59.221533 -18.421875)
			(xy 59.229291 -18.475865) (xy 59.229752 -18.503138) (xy 59.229752 -18.503646) (xy 59.229372 -18.526938)
			(xy 59.223639 -18.573168) (xy 59.218322 -18.595848) (xy 59.21603 -18.607782) (xy 59.221616 -18.631398)
			(xy 59.22899 -18.64106) (xy 59.251323 -18.667976) (xy 59.291518 -18.725217) (xy 59.309254 -18.75536)
			(xy 59.33313 -18.754598) (xy 59.360395 -18.755166) (xy 59.41437 -18.762931) (xy 59.46669 -18.778297)
			(xy 59.516291 -18.800953) (xy 59.562164 -18.830436) (xy 59.603374 -18.866148) (xy 59.639082 -18.90736)
			(xy 59.668562 -18.953235) (xy 59.691213 -19.002838) (xy 59.706576 -19.05516) (xy 59.714336 -19.109135)
			(xy 59.714336 -19.163665) (xy 59.706576 -19.21764) (xy 59.691213 -19.269962) (xy 59.668562 -19.319565)
			(xy 59.639082 -19.36544) (xy 59.603374 -19.406652) (xy 59.562164 -19.442364) (xy 59.516291 -19.471847)
			(xy 59.46669 -19.494503) (xy 59.41437 -19.509869) (xy 59.360395 -19.517634) (xy 59.33313 -19.518122)
			(xy 59.309254 -19.51736) (xy 59.291397 -19.547517) (xy 59.250946 -19.604758) (xy 59.228482 -19.63166)
			(xy 59.22112 -19.641394) (xy 59.215691 -19.665153) (xy 59.218068 -19.677126) (xy 59.223515 -19.70011)
			(xy 59.22938 -19.74698) (xy 59.229752 -19.770598) (xy 59.229752 -19.771106) (xy 59.229304 -19.798378)
			(xy 59.221541 -19.852366) (xy 59.206173 -19.904699) (xy 59.183514 -19.954313) (xy 59.154025 -20.000197)
			(xy 59.118306 -20.041417) (xy 59.077084 -20.077135) (xy 59.031199 -20.106622) (xy 58.981584 -20.129279)
			(xy 58.92925 -20.144644) (xy 58.875262 -20.152405) (xy 58.84799 -20.152868) (xy 58.819178 -20.152282)
			(xy 58.76221 -20.143613) (xy 58.70719 -20.126489) (xy 58.655365 -20.101297) (xy 58.60791 -20.068609)
			(xy 58.565901 -20.029166) (xy 58.530291 -19.983863) (xy 58.501887 -19.933726) (xy 58.49112 -19.906996)
			(xy 58.486163 -19.895806) (xy 58.46798 -19.879481) (xy 58.456322 -19.875754) (xy 58.418722 -19.865536)
			(xy 58.34566 -19.838452) (xy 58.275739 -19.804061) (xy 58.242454 -19.783806) (xy 58.234193 -19.77911)
			(xy 58.21553 -19.775602) (xy 58.196867 -19.77911) (xy 58.188606 -19.783806) (xy 58.155319 -19.804056)
			(xy 58.085393 -19.838435) (xy 58.012334 -19.865525) (xy 57.974738 -19.875754) (xy 57.963105 -19.879524)
			(xy 57.944935 -19.895835) (xy 57.93994 -19.906996) (xy 57.929179 -19.933733) (xy 57.900795 -19.983892)
			(xy 57.865195 -20.029215) (xy 57.823189 -20.068674) (xy 57.77573 -20.101373) (xy 57.723897 -20.126569)
			(xy 57.668865 -20.143689) (xy 57.611886 -20.152345) (xy 57.58307 -20.152868) (xy 57.5558 -20.152403)
			(xy 57.501816 -20.144638) (xy 57.449487 -20.129269) (xy 57.399877 -20.10661) (xy 57.353996 -20.077121)
			(xy 57.312779 -20.041404) (xy 57.277064 -20.000185) (xy 57.247579 -19.954302) (xy 57.224923 -19.904691)
			(xy 57.209557 -19.85236) (xy 57.201795 -19.798376) (xy 57.201308 -19.771106) (xy 57.201308 -19.770598)
			(xy 57.201669 -19.74698) (xy 57.207533 -19.700108) (xy 57.212992 -19.677126) (xy 57.215305 -19.665154)
			(xy 57.209884 -19.64142) (xy 57.202578 -19.63166) (xy 57.180118 -19.604755) (xy 57.139668 -19.547514)
			(xy 57.121806 -19.51736) (xy 57.09793 -19.518122) (xy 57.070655 -19.51774) (xy 57.016659 -19.509981)
			(xy 56.964317 -19.494616) (xy 56.914695 -19.471957) (xy 56.868803 -19.442468) (xy 56.827575 -19.406746)
			(xy 56.79185 -19.365521) (xy 56.762357 -19.319631) (xy 56.739695 -19.270011) (xy 56.724325 -19.21767)
			(xy 56.716562 -19.163675) (xy 54.126335 -19.163675) (xy 54.118576 -19.21764) (xy 54.103213 -19.269962)
			(xy 54.080562 -19.319565) (xy 54.051082 -19.36544) (xy 54.015374 -19.406652) (xy 53.974164 -19.442364)
			(xy 53.928291 -19.471847) (xy 53.87869 -19.494503) (xy 53.82637 -19.509869) (xy 53.772395 -19.517634)
			(xy 53.74513 -19.518122) (xy 53.721254 -19.51736) (xy 53.703397 -19.547517) (xy 53.662946 -19.604758)
			(xy 53.640482 -19.63166) (xy 53.63312 -19.641394) (xy 53.627691 -19.665153) (xy 53.630068 -19.677126)
			(xy 53.635515 -19.70011) (xy 53.64138 -19.74698) (xy 53.641752 -19.770598) (xy 53.641752 -19.771106)
			(xy 53.641304 -19.798378) (xy 53.633541 -19.852366) (xy 53.618173 -19.904699) (xy 53.595514 -19.954313)
			(xy 53.566025 -20.000197) (xy 53.530306 -20.041417) (xy 53.489084 -20.077135) (xy 53.443199 -20.106622)
			(xy 53.393584 -20.129279) (xy 53.34125 -20.144644) (xy 53.287262 -20.152405) (xy 53.25999 -20.152868)
			(xy 53.231178 -20.152282) (xy 53.17421 -20.143613) (xy 53.11919 -20.126489) (xy 53.067365 -20.101297)
			(xy 53.01991 -20.068609) (xy 52.977901 -20.029166) (xy 52.942291 -19.983863) (xy 52.913887 -19.933726)
			(xy 52.90312 -19.906996) (xy 52.898163 -19.895806) (xy 52.87998 -19.879481) (xy 52.868322 -19.875754)
			(xy 52.830722 -19.865536) (xy 52.75766 -19.838452) (xy 52.687739 -19.804061) (xy 52.654454 -19.783806)
			(xy 52.646193 -19.77911) (xy 52.62753 -19.775602) (xy 52.608867 -19.77911) (xy 52.600606 -19.783806)
			(xy 52.567319 -19.804056) (xy 52.497393 -19.838435) (xy 52.424334 -19.865525) (xy 52.386738 -19.875754)
			(xy 52.375105 -19.879524) (xy 52.356935 -19.895835) (xy 52.35194 -19.906996) (xy 52.341179 -19.933733)
			(xy 52.312795 -19.983892) (xy 52.277195 -20.029215) (xy 52.235189 -20.068674) (xy 52.18773 -20.101373)
			(xy 52.135897 -20.126569) (xy 52.080865 -20.143689) (xy 52.023886 -20.152345) (xy 51.99507 -20.152868)
			(xy 51.9678 -20.152403) (xy 51.913816 -20.144638) (xy 51.861487 -20.129269) (xy 51.811877 -20.10661)
			(xy 51.765996 -20.077121) (xy 51.724779 -20.041404) (xy 51.689064 -20.000185) (xy 51.659579 -19.954302)
			(xy 51.636923 -19.904691) (xy 51.621557 -19.85236) (xy 51.613795 -19.798376) (xy 51.613308 -19.771106)
			(xy 51.613308 -19.770598) (xy 51.613669 -19.74698) (xy 51.619533 -19.700108) (xy 51.624992 -19.677126)
			(xy 51.627305 -19.665154) (xy 51.621884 -19.64142) (xy 51.614578 -19.63166) (xy 51.592118 -19.604755)
			(xy 51.551668 -19.547514) (xy 51.533806 -19.51736) (xy 51.50993 -19.518122) (xy 51.482655 -19.51774)
			(xy 51.428659 -19.509981) (xy 51.376317 -19.494616) (xy 51.326695 -19.471957) (xy 51.280803 -19.442468)
			(xy 51.239575 -19.406746) (xy 51.20385 -19.365521) (xy 51.174357 -19.319631) (xy 51.151695 -19.270011)
			(xy 51.136325 -19.21767) (xy 51.128562 -19.163675) (xy 48.50342 -19.163675) (xy 48.50342 -19.164374)
			(xy 48.495657 -19.218365) (xy 48.480289 -19.270703) (xy 48.457628 -19.32032) (xy 48.428137 -19.366208)
			(xy 48.392415 -19.407431) (xy 48.35119 -19.44315) (xy 48.305301 -19.472639) (xy 48.255682 -19.495297)
			(xy 48.203344 -19.510662) (xy 48.149352 -19.518422) (xy 48.122078 -19.518884) (xy 48.098202 -19.518122)
			(xy 48.08428 -19.5418) (xy 48.053519 -19.587312) (xy 48.036734 -19.609054) (xy 48.029535 -19.619303)
			(xy 48.025148 -19.643935) (xy 48.028352 -19.656044) (xy 48.036796 -19.684251) (xy 48.045847 -19.742429)
			(xy 48.046386 -19.771868) (xy 48.045869 -19.799137) (xy 48.038112 -19.853121) (xy 48.022751 -19.905451)
			(xy 48.000099 -19.955062) (xy 47.970617 -20.000945) (xy 47.934905 -20.042165) (xy 47.89369 -20.077883)
			(xy 47.847812 -20.107372) (xy 47.798204 -20.130031) (xy 47.745876 -20.1454) (xy 47.691893 -20.153165)
			(xy 47.664624 -20.15363) (xy 47.636235 -20.153138) (xy 47.580081 -20.144745) (xy 47.525791 -20.128125)
			(xy 47.474561 -20.103645) (xy 47.427524 -20.071846) (xy 47.385717 -20.033429) (xy 47.350063 -19.989243)
			(xy 47.321348 -19.940261) (xy 47.310294 -19.914108) (xy 47.305008 -19.902847) (xy 47.285982 -19.886865)
			(xy 47.273972 -19.883628) (xy 47.231226 -19.873682) (xy 47.148177 -19.845297) (xy 47.068929 -19.807579)
			(xy 47.031402 -19.784822) (xy 47.023173 -19.780068) (xy 47.00452 -19.77648) (xy 46.985838 -19.779908)
			(xy 46.977554 -19.784568) (xy 46.944421 -19.804736) (xy 46.874826 -19.838999) (xy 46.802118 -19.866035)
			(xy 46.764702 -19.876262) (xy 46.75313 -19.880067) (xy 46.735084 -19.896366) (xy 46.730158 -19.907504)
			(xy 46.71939 -19.934265) (xy 46.691 -19.984477) (xy 46.655383 -20.02985) (xy 46.61335 -20.069352)
			(xy 46.565856 -20.102087) (xy 46.513981 -20.127309) (xy 46.458903 -20.144446) (xy 46.401875 -20.153108)
			(xy 46.373034 -20.15363) (xy 46.345762 -20.153167) (xy 46.291774 -20.145408) (xy 46.239439 -20.130045)
			(xy 46.189824 -20.107389) (xy 46.143939 -20.077902) (xy 46.102717 -20.042184) (xy 46.066999 -20.000963)
			(xy 46.037512 -19.955078) (xy 46.014856 -19.905463) (xy 45.999492 -19.853128) (xy 45.991733 -19.79914)
			(xy 45.991272 -19.771868) (xy 45.991272 -19.77136) (xy 45.991626 -19.747941) (xy 45.997359 -19.701454)
			(xy 46.002702 -19.67865) (xy 46.004955 -19.666649) (xy 45.99941 -19.642912) (xy 45.992034 -19.633184)
			(xy 45.969428 -19.606102) (xy 45.92872 -19.548481) (xy 45.910754 -19.518122) (xy 45.886878 -19.518884)
			(xy 45.859611 -19.518352) (xy 45.805633 -19.510588) (xy 45.753309 -19.495222) (xy 45.703705 -19.472566)
			(xy 45.657829 -19.443081) (xy 45.616617 -19.407368) (xy 45.580906 -19.366153) (xy 45.551424 -19.320276)
			(xy 45.52877 -19.27067) (xy 45.513407 -19.218345) (xy 45.505646 -19.164367) (xy 42.916258 -19.164367)
			(xy 42.908597 -19.21765) (xy 42.893232 -19.269978) (xy 42.870577 -19.319586) (xy 42.841091 -19.365465)
			(xy 42.805377 -19.406681) (xy 42.764161 -19.442395) (xy 42.718281 -19.471879) (xy 42.668672 -19.494534)
			(xy 42.616344 -19.509898) (xy 42.562362 -19.517659) (xy 42.535094 -19.518122) (xy 42.511218 -19.51736)
			(xy 42.493363 -19.547519) (xy 42.45291 -19.604758) (xy 42.430446 -19.63166) (xy 42.423081 -19.641392)
			(xy 42.417656 -19.665153) (xy 42.420032 -19.677126) (xy 42.42548 -19.70011) (xy 42.431344 -19.74698)
			(xy 42.431716 -19.770598) (xy 42.431716 -19.771106) (xy 42.431304 -19.798379) (xy 42.42354 -19.85237)
			(xy 42.40817 -19.904707) (xy 42.385509 -19.954323) (xy 42.356016 -20.000209) (xy 42.320293 -20.04143)
			(xy 42.279067 -20.077147) (xy 42.233177 -20.106634) (xy 42.183558 -20.129289) (xy 42.131219 -20.144651)
			(xy 42.077227 -20.152408) (xy 42.049954 -20.152868) (xy 42.021141 -20.152313) (xy 41.964172 -20.143639)
			(xy 41.909151 -20.12651) (xy 41.857325 -20.101313) (xy 41.80987 -20.068621) (xy 41.767862 -20.029174)
			(xy 41.732253 -19.983867) (xy 41.70385 -19.933727) (xy 41.693084 -19.906996) (xy 41.688145 -19.895795)
			(xy 41.66995 -19.879474) (xy 41.658286 -19.875754) (xy 41.62069 -19.865522) (xy 41.547627 -19.838444)
			(xy 41.477704 -19.804059) (xy 41.444418 -19.783806) (xy 41.436157 -19.77911) (xy 41.417494 -19.775602)
			(xy 41.398831 -19.77911) (xy 41.39057 -19.783806) (xy 41.357275 -19.804043) (xy 41.287353 -19.838427)
			(xy 41.214297 -19.865522) (xy 41.176702 -19.875754) (xy 41.165063 -19.879508) (xy 41.146896 -19.895831)
			(xy 41.141904 -19.906996) (xy 41.131173 -19.933746) (xy 41.102785 -19.983906) (xy 41.067182 -20.02923)
			(xy 41.025171 -20.068689) (xy 40.977708 -20.101386) (xy 40.92587 -20.126579) (xy 40.870835 -20.143696)
			(xy 40.813852 -20.152348) (xy 40.785034 -20.152868) (xy 40.757764 -20.152367) (xy 40.703779 -20.14461)
			(xy 40.651447 -20.129248) (xy 40.601835 -20.106595) (xy 40.555951 -20.077111) (xy 40.514731 -20.041398)
			(xy 40.479013 -20.000181) (xy 40.449524 -19.954301) (xy 40.426866 -19.90469) (xy 40.411499 -19.85236)
			(xy 40.403736 -19.798376) (xy 40.403272 -19.771106) (xy 40.403272 -19.770598) (xy 40.403631 -19.74698)
			(xy 40.409496 -19.700108) (xy 40.414956 -19.677126) (xy 40.417276 -19.665154) (xy 40.411852 -19.641419)
			(xy 40.404542 -19.63166) (xy 40.382086 -19.604752) (xy 40.341634 -19.547513) (xy 40.32377 -19.51736)
			(xy 40.299894 -19.518122) (xy 40.272622 -19.517715) (xy 40.218633 -19.509952) (xy 40.166299 -19.494584)
			(xy 40.116685 -19.471925) (xy 40.0708 -19.442436) (xy 40.029578 -19.406717) (xy 39.99386 -19.365496)
			(xy 39.964372 -19.31961) (xy 39.941713 -19.269995) (xy 39.926347 -19.217661) (xy 39.918585 -19.163672)
			(xy 37.022559 -19.163672) (xy 37.014797 -19.217652) (xy 36.999431 -19.269981) (xy 36.976774 -19.319591)
			(xy 36.947287 -19.365471) (xy 36.911571 -19.406687) (xy 36.870353 -19.442401) (xy 36.824471 -19.471885)
			(xy 36.774861 -19.494539) (xy 36.722531 -19.509901) (xy 36.668547 -19.51766) (xy 36.641278 -19.518122)
			(xy 36.617402 -19.51736) (xy 36.599542 -19.547515) (xy 36.559092 -19.604757) (xy 36.53663 -19.63166)
			(xy 36.529271 -19.641397) (xy 36.523838 -19.665154) (xy 36.526216 -19.677126) (xy 36.531664 -19.70011)
			(xy 36.537528 -19.74698) (xy 36.5379 -19.770598) (xy 36.5379 -19.771106) (xy 36.537381 -19.798374)
			(xy 36.52962 -19.852354) (xy 36.514256 -19.904681) (xy 36.491601 -19.954289) (xy 36.462118 -20.000168)
			(xy 36.426407 -20.041384) (xy 36.385193 -20.077099) (xy 36.339317 -20.106586) (xy 36.289711 -20.129244)
			(xy 36.237386 -20.144613) (xy 36.183406 -20.152379) (xy 36.156138 -20.152868) (xy 36.127325 -20.152327)
			(xy 36.070355 -20.143651) (xy 36.015333 -20.126519) (xy 35.963508 -20.10132) (xy 35.916053 -20.068626)
			(xy 35.874045 -20.029178) (xy 35.838436 -19.983869) (xy 35.810033 -19.933728) (xy 35.799268 -19.906996)
			(xy 35.794286 -19.895819) (xy 35.776121 -19.879489) (xy 35.76447 -19.875754) (xy 35.726873 -19.865525)
			(xy 35.65381 -19.838446) (xy 35.583888 -19.804059) (xy 35.550602 -19.783806) (xy 35.542341 -19.77911)
			(xy 35.523678 -19.775602) (xy 35.505015 -19.77911) (xy 35.496754 -19.783806) (xy 35.463461 -19.804046)
			(xy 35.393538 -19.838429) (xy 35.320481 -19.865523) (xy 35.282886 -19.875754) (xy 35.271244 -19.879501)
			(xy 35.253079 -19.895829) (xy 35.248088 -19.906996) (xy 35.23737 -19.933752) (xy 35.208981 -19.983912)
			(xy 35.173376 -20.029236) (xy 35.131363 -20.068695) (xy 35.083898 -20.101392) (xy 35.032058 -20.126584)
			(xy 34.977021 -20.143699) (xy 34.920037 -20.152349) (xy 34.891218 -20.152868) (xy 34.863948 -20.152382)
			(xy 34.809962 -20.144622) (xy 34.75763 -20.129259) (xy 34.708017 -20.106604) (xy 34.662134 -20.077118)
			(xy 34.620914 -20.041403) (xy 34.585196 -20.000185) (xy 34.555708 -19.954304) (xy 34.53305 -19.904692)
			(xy 34.517683 -19.852362) (xy 34.50992 -19.798376) (xy 34.509456 -19.771106) (xy 34.509456 -19.770598)
			(xy 34.509815 -19.74698) (xy 34.515681 -19.700108) (xy 34.52114 -19.677126) (xy 34.523442 -19.665153)
			(xy 34.518026 -19.641422) (xy 34.510726 -19.63166) (xy 34.488269 -19.604752) (xy 34.447817 -19.547513)
			(xy 34.429954 -19.51736) (xy 34.406078 -19.518122) (xy 34.378807 -19.517714) (xy 34.32482 -19.509949)
			(xy 34.272488 -19.49458) (xy 34.222875 -19.47192) (xy 34.176992 -19.442431) (xy 34.135773 -19.406712)
			(xy 34.100056 -19.36549) (xy 34.070569 -19.319606) (xy 34.047912 -19.269992) (xy 34.032546 -19.217659)
			(xy 34.024784 -19.163671) (xy 31.434559 -19.163671) (xy 31.426797 -19.217652) (xy 31.411431 -19.269981)
			(xy 31.388774 -19.319591) (xy 31.359287 -19.365471) (xy 31.323571 -19.406687) (xy 31.282353 -19.442401)
			(xy 31.236471 -19.471885) (xy 31.186861 -19.494539) (xy 31.134531 -19.509901) (xy 31.080547 -19.51766)
			(xy 31.053278 -19.518122) (xy 31.029402 -19.51736) (xy 31.011542 -19.547515) (xy 30.971092 -19.604757)
			(xy 30.94863 -19.63166) (xy 30.941271 -19.641397) (xy 30.935838 -19.665154) (xy 30.938216 -19.677126)
			(xy 30.943664 -19.70011) (xy 30.949528 -19.74698) (xy 30.9499 -19.770598) (xy 30.9499 -19.771106)
			(xy 30.949381 -19.798374) (xy 30.94162 -19.852354) (xy 30.926256 -19.904681) (xy 30.903601 -19.954289)
			(xy 30.874118 -20.000168) (xy 30.838407 -20.041384) (xy 30.797193 -20.077099) (xy 30.751317 -20.106586)
			(xy 30.701711 -20.129244) (xy 30.649386 -20.144613) (xy 30.595406 -20.152379) (xy 30.568138 -20.152868)
			(xy 30.539325 -20.152327) (xy 30.482355 -20.143651) (xy 30.427333 -20.126519) (xy 30.375508 -20.10132)
			(xy 30.328053 -20.068626) (xy 30.286045 -20.029178) (xy 30.250436 -19.983869) (xy 30.222033 -19.933728)
			(xy 30.211268 -19.906996) (xy 30.206286 -19.895819) (xy 30.188121 -19.879489) (xy 30.17647 -19.875754)
			(xy 30.138873 -19.865525) (xy 30.06581 -19.838446) (xy 29.995888 -19.804059) (xy 29.962602 -19.783806)
			(xy 29.954341 -19.77911) (xy 29.935678 -19.775602) (xy 29.917015 -19.77911) (xy 29.908754 -19.783806)
			(xy 29.875461 -19.804046) (xy 29.805538 -19.838429) (xy 29.732481 -19.865523) (xy 29.694886 -19.875754)
			(xy 29.683244 -19.879501) (xy 29.665079 -19.895829) (xy 29.660088 -19.906996) (xy 29.64937 -19.933752)
			(xy 29.620981 -19.983912) (xy 29.585376 -20.029236) (xy 29.543363 -20.068695) (xy 29.495898 -20.101392)
			(xy 29.444058 -20.126584) (xy 29.389021 -20.143699) (xy 29.332037 -20.152349) (xy 29.303218 -20.152868)
			(xy 29.275948 -20.152382) (xy 29.221962 -20.144622) (xy 29.16963 -20.129259) (xy 29.120017 -20.106604)
			(xy 29.074134 -20.077118) (xy 29.032914 -20.041403) (xy 28.997196 -20.000185) (xy 28.967708 -19.954304)
			(xy 28.94505 -19.904692) (xy 28.929683 -19.852362) (xy 28.92192 -19.798376) (xy 28.921456 -19.771106)
			(xy 28.921456 -19.770598) (xy 28.921815 -19.74698) (xy 28.927681 -19.700108) (xy 28.93314 -19.677126)
			(xy 28.935442 -19.665153) (xy 28.930026 -19.641422) (xy 28.922726 -19.63166) (xy 28.900269 -19.604752)
			(xy 28.859817 -19.547513) (xy 28.841954 -19.51736) (xy 28.818078 -19.518122) (xy 28.790807 -19.517714)
			(xy 28.73682 -19.509949) (xy 28.684488 -19.49458) (xy 28.634875 -19.47192) (xy 28.588992 -19.442431)
			(xy 28.547773 -19.406712) (xy 28.512056 -19.36549) (xy 28.482569 -19.319606) (xy 28.459912 -19.269992)
			(xy 28.444546 -19.217659) (xy 28.436784 -19.163671) (xy 25.846559 -19.163671) (xy 25.838797 -19.217652)
			(xy 25.823431 -19.269981) (xy 25.800774 -19.319591) (xy 25.771287 -19.365471) (xy 25.735571 -19.406687)
			(xy 25.694353 -19.442401) (xy 25.648471 -19.471885) (xy 25.598861 -19.494539) (xy 25.546531 -19.509901)
			(xy 25.492547 -19.51766) (xy 25.465278 -19.518122) (xy 25.441402 -19.51736) (xy 25.423542 -19.547515)
			(xy 25.383092 -19.604757) (xy 25.36063 -19.63166) (xy 25.353271 -19.641397) (xy 25.347838 -19.665154)
			(xy 25.350216 -19.677126) (xy 25.355664 -19.70011) (xy 25.361528 -19.74698) (xy 25.3619 -19.770598)
			(xy 25.3619 -19.771106) (xy 25.361381 -19.798374) (xy 25.35362 -19.852354) (xy 25.338256 -19.904681)
			(xy 25.315601 -19.954289) (xy 25.286118 -20.000168) (xy 25.250407 -20.041384) (xy 25.209193 -20.077099)
			(xy 25.163317 -20.106586) (xy 25.113711 -20.129244) (xy 25.061386 -20.144613) (xy 25.007406 -20.152379)
			(xy 24.980138 -20.152868) (xy 24.951325 -20.152327) (xy 24.894355 -20.143651) (xy 24.839333 -20.126519)
			(xy 24.787508 -20.10132) (xy 24.740053 -20.068626) (xy 24.698045 -20.029178) (xy 24.662436 -19.983869)
			(xy 24.634033 -19.933728) (xy 24.623268 -19.906996) (xy 24.618286 -19.895819) (xy 24.600121 -19.879489)
			(xy 24.58847 -19.875754) (xy 24.550873 -19.865525) (xy 24.47781 -19.838446) (xy 24.407888 -19.804059)
			(xy 24.374602 -19.783806) (xy 24.366341 -19.77911) (xy 24.347678 -19.775602) (xy 24.329015 -19.77911)
			(xy 24.320754 -19.783806) (xy 24.287461 -19.804046) (xy 24.217538 -19.838429) (xy 24.144481 -19.865523)
			(xy 24.106886 -19.875754) (xy 24.095244 -19.879501) (xy 24.077079 -19.895829) (xy 24.072088 -19.906996)
			(xy 24.06137 -19.933752) (xy 24.032981 -19.983912) (xy 23.997376 -20.029236) (xy 23.955363 -20.068695)
			(xy 23.907898 -20.101392) (xy 23.856058 -20.126584) (xy 23.801021 -20.143699) (xy 23.744037 -20.152349)
			(xy 23.715218 -20.152868) (xy 23.687948 -20.152382) (xy 23.633962 -20.144622) (xy 23.58163 -20.129259)
			(xy 23.532017 -20.106604) (xy 23.486134 -20.077118) (xy 23.444914 -20.041403) (xy 23.409196 -20.000185)
			(xy 23.379708 -19.954304) (xy 23.35705 -19.904692) (xy 23.341683 -19.852362) (xy 23.33392 -19.798376)
			(xy 23.333456 -19.771106) (xy 23.333456 -19.770598) (xy 23.333815 -19.74698) (xy 23.339681 -19.700108)
			(xy 23.34514 -19.677126) (xy 23.347442 -19.665153) (xy 23.342026 -19.641422) (xy 23.334726 -19.63166)
			(xy 23.312269 -19.604752) (xy 23.271817 -19.547513) (xy 23.253954 -19.51736) (xy 23.230078 -19.518122)
			(xy 23.202807 -19.517714) (xy 23.14882 -19.509949) (xy 23.096488 -19.49458) (xy 23.046875 -19.47192)
			(xy 23.000992 -19.442431) (xy 22.959773 -19.406712) (xy 22.924056 -19.36549) (xy 22.894569 -19.319606)
			(xy 22.871912 -19.269992) (xy 22.856546 -19.217659) (xy 22.848784 -19.163671) (xy 20.257538 -19.163671)
			(xy 20.257538 -19.164389) (xy 20.249776 -19.218373) (xy 20.234411 -19.270703) (xy 20.211754 -19.320313)
			(xy 20.182269 -19.366194) (xy 20.146553 -19.407412) (xy 20.105336 -19.443127) (xy 20.059455 -19.472613)
			(xy 20.009845 -19.49527) (xy 19.957515 -19.510635) (xy 19.903531 -19.518397) (xy 19.876262 -19.518884)
			(xy 19.852386 -19.518122) (xy 19.834682 -19.54812) (xy 19.794615 -19.605105) (xy 19.772376 -19.631914)
			(xy 19.765041 -19.641665) (xy 19.759596 -19.66541) (xy 19.761962 -19.67738) (xy 19.767534 -19.700604)
			(xy 19.773517 -19.747988) (xy 19.7739 -19.771868) (xy 19.773346 -19.799135) (xy 19.76559 -19.853114)
			(xy 19.75023 -19.90544) (xy 19.727581 -19.955048) (xy 19.698102 -20.000927) (xy 19.662393 -20.042144)
			(xy 19.621183 -20.07786) (xy 19.575309 -20.107347) (xy 19.525706 -20.130006) (xy 19.473383 -20.145375)
			(xy 19.419405 -20.153141) (xy 19.392138 -20.15363) (xy 19.363349 -20.153074) (xy 19.306424 -20.144419)
			(xy 19.251444 -20.127314) (xy 19.199656 -20.102147) (xy 19.152235 -20.069489) (xy 19.110255 -20.030081)
			(xy 19.074668 -19.984816) (xy 19.046282 -19.93472) (xy 19.035522 -19.908012) (xy 19.030532 -19.896779)
			(xy 19.012196 -19.880462) (xy 19.00047 -19.87677) (xy 18.962686 -19.866564) (xy 18.889271 -19.839426)
			(xy 18.819022 -19.804911) (xy 18.785586 -19.784568) (xy 18.777325 -19.779872) (xy 18.758662 -19.776364)
			(xy 18.739999 -19.779872) (xy 18.731738 -19.784568) (xy 18.698607 -19.80474) (xy 18.629011 -19.839001)
			(xy 18.556303 -19.866036) (xy 18.518886 -19.876262) (xy 18.507311 -19.880059) (xy 18.489266 -19.896364)
			(xy 18.484342 -19.907504) (xy 18.473587 -19.934271) (xy 18.445195 -19.984483) (xy 18.409577 -20.029856)
			(xy 18.367542 -20.069359) (xy 18.320046 -20.102093) (xy 18.268169 -20.127314) (xy 18.213089 -20.14445)
			(xy 18.15606 -20.15311) (xy 18.127218 -20.15363) (xy 18.099946 -20.153182) (xy 18.045957 -20.145421)
			(xy 17.993622 -20.130056) (xy 17.944007 -20.107398) (xy 17.898121 -20.077909) (xy 17.8569 -20.04219)
			(xy 17.821183 -20.000967) (xy 17.791696 -19.955081) (xy 17.76904 -19.905465) (xy 17.753676 -19.853129)
			(xy 17.745917 -19.79914) (xy 17.745456 -19.771868) (xy 17.745456 -19.77136) (xy 17.745811 -19.747941)
			(xy 17.751543 -19.701454) (xy 17.756886 -19.67865) (xy 17.759143 -19.666649) (xy 17.753596 -19.642911)
			(xy 17.746218 -19.633184) (xy 17.723611 -19.606102) (xy 17.682904 -19.548482) (xy 17.664938 -19.518122)
			(xy 17.641062 -19.518884) (xy 17.613791 -19.518417) (xy 17.559804 -19.510655) (xy 17.507472 -19.495289)
			(xy 17.457858 -19.472631) (xy 17.411975 -19.443144) (xy 17.370755 -19.407427) (xy 17.335037 -19.366207)
			(xy 17.30555 -19.320323) (xy 17.282892 -19.27071) (xy 17.267526 -19.218378) (xy 17.259763 -19.164391)
			(xy 1.524 -19.164391) (xy 1.524 -20.327366) (xy 65.88506 -20.327366) (xy 65.885484 -20.289077) (xy 65.892086 -20.212783)
			(xy 65.90523 -20.13734) (xy 65.924819 -20.063309) (xy 65.937384 -20.027138) (xy 65.940051 -20.018705)
			(xy 65.94004 -20.001031) (xy 65.937384 -19.992594) (xy 65.924856 -19.956411) (xy 65.905279 -19.88238)
			(xy 65.892127 -19.806942) (xy 65.885498 -19.730654) (xy 65.88506 -19.692366) (xy 65.885582 -19.650174)
			(xy 65.893576 -19.56617) (xy 65.909488 -19.483301) (xy 65.933176 -19.402311) (xy 65.964427 -19.323927)
			(xy 66.00296 -19.248856) (xy 66.048429 -19.17777) (xy 66.074036 -19.144234) (xy 66.079883 -19.13601)
			(xy 66.085128 -19.116537) (xy 66.082515 -19.096539) (xy 66.077846 -19.087592) (xy 66.058798 -19.053767)
			(xy 66.026006 -18.983399) (xy 65.999468 -18.910441) (xy 65.979384 -18.83545) (xy 65.965909 -18.758994)
			(xy 65.959144 -18.681655) (xy 65.95872 -18.642838) (xy 65.95872 -18.642584) (xy 65.959137 -18.60148)
			(xy 65.966724 -18.519622) (xy 65.981831 -18.438814) (xy 66.00433 -18.359744) (xy 66.034029 -18.283087)
			(xy 66.070674 -18.209498) (xy 66.113953 -18.139604) (xy 66.163496 -18.074001) (xy 66.218881 -18.01325)
			(xy 66.279635 -17.957868) (xy 66.34524 -17.908328) (xy 66.415137 -17.865053) (xy 66.488728 -17.828411)
			(xy 66.565386 -17.798716) (xy 66.644456 -17.776221) (xy 66.725266 -17.761118) (xy 66.807124 -17.753535)
			(xy 66.848228 -17.753076) (xy 66.889911 -17.753577) (xy 66.972911 -17.761363) (xy 67.054819 -17.776882)
			(xy 67.134915 -17.799999) (xy 67.212496 -17.830511) (xy 67.286881 -17.868149) (xy 67.357417 -17.912584)
			(xy 67.423485 -17.963425) (xy 67.484504 -18.020226) (xy 67.53994 -18.082488) (xy 67.565016 -18.115788)
			(xy 67.56527 -18.116042) (xy 67.570757 -18.122776) (xy 67.585223 -18.132372) (xy 67.602063 -18.136587)
			(xy 67.610736 -18.136108) (xy 67.697858 -18.127726) (xy 67.706567 -18.126584) (xy 67.722478 -18.119178)
			(xy 67.734922 -18.1068) (xy 67.739006 -18.099024) (xy 67.739006 -18.098516) (xy 67.757258 -18.060702)
			(xy 67.799884 -17.988356) (xy 67.849141 -17.920351) (xy 67.90459 -17.857291) (xy 67.965736 -17.79974)
			(xy 68.032035 -17.748209) (xy 68.102897 -17.703158) (xy 68.17769 -17.664987) (xy 68.255748 -17.634037)
			(xy 68.336377 -17.610583) (xy 68.418857 -17.594835) (xy 68.502455 -17.586933) (xy 68.54444 -17.586452)
			(xy 68.5868 -17.58693) (xy 68.671136 -17.594986) (xy 68.754325 -17.611023) (xy 68.835612 -17.634895)
			(xy 68.914262 -17.666384) (xy 68.989563 -17.705208) (xy 69.060833 -17.751013) (xy 69.127426 -17.803385)
			(xy 69.18874 -17.86185) (xy 69.244218 -17.925878) (xy 69.293359 -17.99489) (xy 69.335718 -18.068261)
			(xy 69.370911 -18.145325) (xy 69.39862 -18.225386) (xy 69.401856 -18.238724) (xy 79.0321 -18.238724)
			(xy 79.032651 -18.193954) (xy 79.041664 -18.104869) (xy 79.059573 -18.017137) (xy 79.086195 -17.931647)
			(xy 79.10322 -17.890236) (xy 79.106772 -17.880641) (xy 79.106781 -17.860202) (xy 79.10322 -17.850612)
			(xy 79.086184 -17.809205) (xy 79.059551 -17.723717) (xy 79.041646 -17.635983) (xy 79.032653 -17.546895)
			(xy 79.0321 -17.502124) (xy 79.032604 -17.459763) (xy 79.040657 -17.375426) (xy 79.056691 -17.292236)
			(xy 79.080559 -17.210946) (xy 79.112047 -17.132294) (xy 79.150869 -17.056991) (xy 79.196672 -16.985719)
			(xy 79.249043 -16.919123) (xy 79.307508 -16.857808) (xy 79.371536 -16.802327) (xy 79.440548 -16.753184)
			(xy 79.513918 -16.710824) (xy 79.590983 -16.675629) (xy 79.671045 -16.64792) (xy 79.753378 -16.627946)
			(xy 79.837237 -16.615889) (xy 79.921862 -16.611858) (xy 80.006487 -16.615889) (xy 80.090346 -16.627946)
			(xy 80.172679 -16.64792) (xy 80.252741 -16.675629) (xy 80.329806 -16.710824) (xy 80.403176 -16.753184)
			(xy 80.472188 -16.802327) (xy 80.536216 -16.857808) (xy 80.594681 -16.919123) (xy 80.647052 -16.985719)
			(xy 80.692855 -17.056991) (xy 80.731677 -17.132294) (xy 80.763165 -17.210946) (xy 80.787033 -17.292236)
			(xy 80.803067 -17.375426) (xy 80.81112 -17.459763) (xy 80.811624 -17.502124) (xy 80.811054 -17.546893)
			(xy 80.802046 -17.635978) (xy 80.79821 -17.654778) (xy 131.166616 -17.654778) (xy 131.167104 -17.627509)
			(xy 131.174868 -17.573527) (xy 131.190235 -17.521199) (xy 131.212892 -17.47159) (xy 131.242378 -17.42571)
			(xy 131.278093 -17.384493) (xy 131.31931 -17.348778) (xy 131.36519 -17.319292) (xy 131.414799 -17.296635)
			(xy 131.467127 -17.281268) (xy 131.521109 -17.273504) (xy 131.548378 -17.273016) (xy 131.57807 -17.27357)
			(xy 131.636735 -17.282781) (xy 131.693264 -17.300968) (xy 131.746295 -17.327693) (xy 131.794545 -17.36231)
			(xy 131.816094 -17.382744) (xy 131.825442 -17.391087) (xy 131.849416 -17.398273) (xy 131.861814 -17.39646)
			(xy 131.899627 -17.389225) (xy 131.976226 -17.381461) (xy 132.014722 -17.380966) (xy 132.057412 -17.381557)
			(xy 132.142256 -17.391122) (xy 132.225504 -17.410087) (xy 132.306119 -17.438214) (xy 132.383095 -17.475153)
			(xy 132.419598 -17.497298) (xy 132.427859 -17.501994) (xy 132.446522 -17.505502) (xy 132.465185 -17.501994)
			(xy 132.473446 -17.497298) (xy 132.509939 -17.475137) (xy 132.586915 -17.438193) (xy 132.667532 -17.410068)
			(xy 132.750784 -17.391115) (xy 132.835631 -17.381568) (xy 132.878322 -17.380966) (xy 132.87883 -17.380966)
			(xy 132.917784 -17.381496) (xy 132.995278 -17.389516) (xy 133.033516 -17.396968) (xy 133.045976 -17.398874)
			(xy 133.0701 -17.391664) (xy 133.07949 -17.383252) (xy 133.101103 -17.36275) (xy 133.14947 -17.327979)
			(xy 133.202644 -17.301131) (xy 133.25934 -17.282855) (xy 133.318184 -17.273596) (xy 133.347968 -17.273016)
			(xy 133.348222 -17.273016) (xy 133.375491 -17.273504) (xy 133.429473 -17.281268) (xy 133.481801 -17.296635)
			(xy 133.53141 -17.319292) (xy 133.57729 -17.348778) (xy 133.618507 -17.384493) (xy 133.654222 -17.42571)
			(xy 133.683708 -17.47159) (xy 133.706365 -17.521199) (xy 133.721732 -17.573527) (xy 133.729496 -17.627509)
			(xy 133.729984 -17.654778) (xy 133.72945 -17.682933) (xy 133.721128 -17.738625) (xy 133.70472 -17.792492)
			(xy 133.680582 -17.843366) (xy 133.649235 -17.890145) (xy 133.63067 -17.911318) (xy 133.622671 -17.921122)
			(xy 133.616543 -17.945639) (xy 133.618986 -17.958054) (xy 133.629794 -18.003839) (xy 133.641389 -18.097198)
			(xy 133.6421 -18.144236) (xy 133.6421 -18.144744) (xy 133.641757 -18.171946) (xy 137.033822 -18.171946)
			(xy 137.033822 -18.117454) (xy 137.041577 -18.063516) (xy 137.056928 -18.01123) (xy 137.079564 -17.961661)
			(xy 137.109023 -17.915818) (xy 137.144706 -17.874633) (xy 137.185887 -17.838946) (xy 137.231728 -17.809482)
			(xy 137.281294 -17.786841) (xy 137.333578 -17.771485) (xy 137.387516 -17.763725) (xy 137.414762 -17.763236)
			(xy 138.278362 -17.763236) (xy 138.30562 -17.763608) (xy 138.359581 -17.771362) (xy 138.41189 -17.786716)
			(xy 138.46148 -17.809359) (xy 138.507344 -17.83883) (xy 138.548546 -17.874528) (xy 138.584247 -17.915726)
			(xy 138.613722 -17.961586) (xy 138.63637 -18.011175) (xy 138.65173 -18.063482) (xy 138.659489 -18.117442)
			(xy 138.659489 -18.17195) (xy 140.633699 -18.17195) (xy 140.633699 -18.11745) (xy 140.641455 -18.063505)
			(xy 140.65681 -18.011213) (xy 140.67945 -17.961638) (xy 140.708915 -17.91579) (xy 140.744605 -17.874602)
			(xy 140.785793 -17.838913) (xy 140.831642 -17.809448) (xy 140.881217 -17.786808) (xy 140.933509 -17.771455)
			(xy 140.987454 -17.763699) (xy 141.014704 -17.763236) (xy 141.878304 -17.763236) (xy 141.905558 -17.763634)
			(xy 141.959512 -17.771392) (xy 142.011812 -17.786749) (xy 142.061394 -17.809393) (xy 142.10725 -17.838863)
			(xy 142.148444 -17.874559) (xy 142.184139 -17.915754) (xy 142.213609 -17.961609) (xy 142.236252 -18.011192)
			(xy 142.251609 -18.063492) (xy 142.259366 -18.117446) (xy 142.259366 -18.171954) (xy 142.251609 -18.225908)
			(xy 142.236252 -18.278208) (xy 142.213609 -18.327791) (xy 142.184139 -18.373646) (xy 142.148444 -18.414841)
			(xy 142.10725 -18.450537) (xy 142.061394 -18.480007) (xy 142.011812 -18.502651) (xy 141.959512 -18.518008)
			(xy 141.905558 -18.525766) (xy 141.878304 -18.526252) (xy 141.014704 -18.526252) (xy 140.987454 -18.525701)
			(xy 140.933509 -18.517945) (xy 140.881217 -18.502592) (xy 140.831642 -18.479952) (xy 140.785793 -18.450487)
			(xy 140.744605 -18.414798) (xy 140.708915 -18.37361) (xy 140.67945 -18.327762) (xy 140.65681 -18.278187)
			(xy 140.641455 -18.225895) (xy 140.633699 -18.17195) (xy 138.659489 -18.17195) (xy 138.659489 -18.171958)
			(xy 138.65173 -18.225918) (xy 138.63637 -18.278225) (xy 138.613722 -18.327814) (xy 138.584247 -18.373674)
			(xy 138.548546 -18.414872) (xy 138.507344 -18.45057) (xy 138.46148 -18.480041) (xy 138.41189 -18.502684)
			(xy 138.359581 -18.518038) (xy 138.30562 -18.525792) (xy 138.278362 -18.526252) (xy 137.414762 -18.526252)
			(xy 137.387516 -18.525675) (xy 137.333578 -18.517915) (xy 137.281294 -18.502559) (xy 137.231728 -18.479918)
			(xy 137.185887 -18.450454) (xy 137.144706 -18.414767) (xy 137.109023 -18.373582) (xy 137.079564 -18.327739)
			(xy 137.056928 -18.27817) (xy 137.041577 -18.225884) (xy 137.033822 -18.171946) (xy 133.641757 -18.171946)
			(xy 133.641596 -18.184745) (xy 133.63323 -18.264307) (xy 133.616593 -18.342559) (xy 133.591868 -18.418644)
			(xy 133.559326 -18.491727) (xy 133.519324 -18.561009) (xy 133.472299 -18.625731) (xy 133.418766 -18.685182)
			(xy 133.359313 -18.738713) (xy 133.294591 -18.785736) (xy 133.225308 -18.825736) (xy 133.152223 -18.858276)
			(xy 133.076138 -18.882999) (xy 132.997885 -18.899633) (xy 132.918323 -18.907997) (xy 132.878322 -18.908522)
			(xy 132.835633 -18.907897) (xy 132.750791 -18.898338) (xy 132.667544 -18.87938) (xy 132.586928 -18.851261)
			(xy 132.50995 -18.81433) (xy 132.473446 -18.79219) (xy 132.465185 -18.787494) (xy 132.446522 -18.783986)
			(xy 132.427859 -18.787494) (xy 132.419598 -18.79219) (xy 132.383093 -18.814332) (xy 132.306121 -18.851279)
			(xy 132.225507 -18.879408) (xy 132.142257 -18.898366) (xy 132.057412 -18.907917) (xy 132.014722 -18.908522)
			(xy 131.974723 -18.907934) (xy 131.895164 -18.899574) (xy 131.816915 -18.882944) (xy 131.740832 -18.858227)
			(xy 131.66775 -18.825691) (xy 131.598469 -18.785696) (xy 131.533748 -18.738677) (xy 131.474296 -18.685151)
			(xy 131.420765 -18.625704) (xy 131.37374 -18.560987) (xy 131.333739 -18.491709) (xy 131.301197 -18.41863)
			(xy 131.276473 -18.342549) (xy 131.259836 -18.264301) (xy 131.25147 -18.184743) (xy 131.250944 -18.144744)
			(xy 131.250944 -18.144236) (xy 131.251717 -18.096477) (xy 131.263688 -18.00171) (xy 131.27482 -17.95526)
			(xy 131.277326 -17.942936) (xy 131.271314 -17.918546) (xy 131.26339 -17.908778) (xy 131.24526 -17.887693)
			(xy 131.214672 -17.841254) (xy 131.191147 -17.790868) (xy 131.175183 -17.737601) (xy 131.167117 -17.682582)
			(xy 131.166616 -17.654778) (xy 80.79821 -17.654778) (xy 80.784143 -17.723709) (xy 80.757526 -17.809201)
			(xy 80.740504 -17.850612) (xy 80.736924 -17.860198) (xy 80.736933 -17.880645) (xy 80.740504 -17.890236)
			(xy 80.757551 -17.931638) (xy 80.784182 -18.017129) (xy 80.802084 -18.104863) (xy 80.811074 -18.193953)
			(xy 80.811624 -18.238724) (xy 80.81112 -18.281085) (xy 80.803067 -18.365422) (xy 80.787033 -18.448612)
			(xy 80.763165 -18.529902) (xy 80.731677 -18.608554) (xy 80.692855 -18.683857) (xy 80.647052 -18.755129)
			(xy 80.594681 -18.821725) (xy 80.536216 -18.88304) (xy 80.472188 -18.938521) (xy 80.403176 -18.987664)
			(xy 80.329806 -19.030024) (xy 80.252741 -19.065219) (xy 80.172679 -19.092928) (xy 80.090346 -19.112902)
			(xy 80.006487 -19.124959) (xy 79.921862 -19.128991) (xy 79.837237 -19.124959) (xy 79.753378 -19.112902)
			(xy 79.671045 -19.092928) (xy 79.590983 -19.065219) (xy 79.513918 -19.030024) (xy 79.440548 -18.987664)
			(xy 79.371536 -18.938521) (xy 79.307508 -18.88304) (xy 79.249043 -18.821725) (xy 79.196672 -18.755129)
			(xy 79.150869 -18.683857) (xy 79.112047 -18.608554) (xy 79.080559 -18.529902) (xy 79.056691 -18.448612)
			(xy 79.040657 -18.365422) (xy 79.032604 -18.281085) (xy 79.0321 -18.238724) (xy 69.401856 -18.238724)
			(xy 69.418593 -18.307718) (xy 69.430649 -18.391576) (xy 69.434681 -18.4762) (xy 69.430649 -18.560824)
			(xy 69.418593 -18.644682) (xy 69.39862 -18.727014) (xy 69.370911 -18.807075) (xy 69.335718 -18.884139)
			(xy 69.293359 -18.95751) (xy 69.244218 -19.026522) (xy 69.18874 -19.09055) (xy 69.127426 -19.149015)
			(xy 69.060833 -19.201387) (xy 68.989563 -19.247192) (xy 68.914262 -19.286016) (xy 68.835612 -19.317505)
			(xy 68.754325 -19.341377) (xy 68.671136 -19.357414) (xy 68.5868 -19.36547) (xy 68.54444 -19.365976)
			(xy 68.502753 -19.365468) (xy 68.419745 -19.357644) (xy 68.337834 -19.342089) (xy 68.257737 -19.31894)
			(xy 68.180157 -19.288398) (xy 68.105774 -19.250734) (xy 68.035242 -19.206275) (xy 67.969177 -19.155414)
			(xy 67.90816 -19.098595) (xy 67.852727 -19.036317) (xy 67.827652 -19.00301) (xy 67.827398 -19.002756)
			(xy 67.821873 -18.996058) (xy 67.807425 -18.986454) (xy 67.790601 -18.982223) (xy 67.781932 -18.98269)
			(xy 67.69481 -18.991072) (xy 67.686098 -18.992195) (xy 67.670187 -18.999611) (xy 67.657745 -19.011995)
			(xy 67.653662 -19.019774) (xy 67.653662 -19.020282) (xy 67.63179 -19.065383) (xy 67.579339 -19.150805)
			(xy 67.549014 -19.190716) (xy 67.543272 -19.198996) (xy 67.538026 -19.218428) (xy 67.540615 -19.238388)
			(xy 67.545204 -19.247358) (xy 67.564269 -19.281203) (xy 67.597117 -19.351604) (xy 67.623706 -19.424598)
			(xy 67.643834 -19.499632) (xy 67.657349 -19.576134) (xy 67.664146 -19.653523) (xy 67.664584 -19.692366)
			(xy 67.664167 -19.730656) (xy 67.657563 -19.806949) (xy 67.644416 -19.882392) (xy 67.624826 -19.956423)
			(xy 67.61226 -19.992594) (xy 67.609626 -20.001035) (xy 67.609615 -20.018702) (xy 67.61226 -20.027138)
			(xy 67.624799 -20.063317) (xy 67.644373 -20.13735) (xy 67.653158 -20.187755) (xy 138.765443 -20.187755)
			(xy 138.765443 -20.133245) (xy 138.773201 -20.079289) (xy 138.788559 -20.026987) (xy 138.811205 -19.977403)
			(xy 138.840677 -19.931547) (xy 138.876376 -19.890352) (xy 138.917574 -19.854657) (xy 138.963433 -19.825189)
			(xy 139.013019 -19.802547) (xy 139.065322 -19.787194) (xy 139.119279 -19.779441) (xy 139.146534 -19.77898)
			(xy 140.137134 -19.77898) (xy 140.164383 -19.779493) (xy 140.218325 -19.787253) (xy 140.270614 -19.80261)
			(xy 140.320185 -19.825253) (xy 140.36603 -19.854719) (xy 140.407215 -19.890409) (xy 140.442901 -19.931597)
			(xy 140.449617 -19.942048) (xy 175.988472 -19.942048) (xy 175.988976 -19.899687) (xy 175.997029 -19.81535)
			(xy 176.013063 -19.73216) (xy 176.036931 -19.65087) (xy 176.068419 -19.572218) (xy 176.107241 -19.496915)
			(xy 176.153044 -19.425643) (xy 176.205415 -19.359047) (xy 176.26388 -19.297732) (xy 176.327908 -19.242251)
			(xy 176.39692 -19.193108) (xy 176.47029 -19.150748) (xy 176.547355 -19.115553) (xy 176.627417 -19.087844)
			(xy 176.70975 -19.06787) (xy 176.793609 -19.055813) (xy 176.878234 -19.051782) (xy 176.962859 -19.055813)
			(xy 177.046718 -19.06787) (xy 177.129051 -19.087844) (xy 177.209113 -19.115553) (xy 177.286178 -19.150748)
			(xy 177.359548 -19.193108) (xy 177.42856 -19.242251) (xy 177.492588 -19.297732) (xy 177.551053 -19.359047)
			(xy 177.603424 -19.425643) (xy 177.649227 -19.496915) (xy 177.688049 -19.572218) (xy 177.719537 -19.65087)
			(xy 177.743405 -19.73216) (xy 177.759439 -19.81535) (xy 177.767492 -19.899687) (xy 177.767996 -19.942048)
			(xy 177.767398 -19.98792) (xy 177.757891 -20.079169) (xy 177.739034 -20.168954) (xy 177.725578 -20.212812)
			(xy 177.722752 -20.223379) (xy 177.72523 -20.245087) (xy 177.730404 -20.254722) (xy 177.750836 -20.289402)
			(xy 177.786035 -20.361795) (xy 177.814552 -20.437071) (xy 177.836153 -20.514616) (xy 177.850661 -20.593794)
			(xy 177.857958 -20.67396) (xy 177.85842 -20.714208) (xy 177.85842 -20.715224) (xy 177.857839 -20.760561)
			(xy 177.84856 -20.850758) (xy 177.830152 -20.939544) (xy 177.817018 -20.98294) (xy 177.81462 -20.991841)
			(xy 177.815621 -21.010233) (xy 177.823067 -21.02708) (xy 177.835994 -21.040201) (xy 177.844196 -21.044408)
			(xy 177.8824 -21.062505) (xy 177.955518 -21.104946) (xy 178.024281 -21.15413) (xy 178.088069 -21.209614)
			(xy 178.146306 -21.270898) (xy 178.198469 -21.337429) (xy 178.244087 -21.408608) (xy 178.282748 -21.483792)
			(xy 178.314103 -21.562305) (xy 178.337871 -21.643437) (xy 178.353837 -21.726458) (xy 178.361856 -21.810619)
			(xy 178.362356 -21.85289) (xy 178.361892 -21.894005) (xy 178.354306 -21.975884) (xy 178.339197 -22.056714)
			(xy 178.316694 -22.135805) (xy 178.28699 -22.212482) (xy 178.250337 -22.286091) (xy 178.207049 -22.356005)
			(xy 178.157495 -22.421626) (xy 178.102097 -22.482394) (xy 178.041329 -22.537792) (xy 177.975708 -22.587347)
			(xy 177.905795 -22.630635) (xy 177.832186 -22.667288) (xy 177.755509 -22.696993) (xy 177.676418 -22.719496)
			(xy 177.595588 -22.734605) (xy 177.513709 -22.742192) (xy 177.472594 -22.742652) (xy 177.429071 -22.742084)
			(xy 177.34244 -22.73358) (xy 177.257055 -22.716655) (xy 177.173731 -22.69147) (xy 177.093266 -22.658267)
			(xy 177.016429 -22.617362) (xy 176.943956 -22.569146) (xy 176.876538 -22.514083) (xy 176.814822 -22.452697)
			(xy 176.759398 -22.385575) (xy 176.710795 -22.313361) (xy 176.669479 -22.236745) (xy 176.652174 -22.196806)
			(xy 176.647921 -22.187866) (xy 176.633936 -22.17388) (xy 176.624996 -22.169628) (xy 176.585068 -22.152314)
			(xy 176.508472 -22.110985) (xy 176.436278 -22.062372) (xy 176.369178 -22.006941) (xy 176.307813 -21.945221)
			(xy 176.252769 -21.877802) (xy 176.204574 -21.80533) (xy 176.163687 -21.728496) (xy 176.1305 -21.648037)
			(xy 176.105331 -21.564721) (xy 176.088419 -21.479345) (xy 176.079928 -21.392725) (xy 176.079404 -21.349208)
			(xy 176.079404 -21.348446) (xy 176.079814 -21.310226) (xy 176.086378 -21.234067) (xy 176.099462 -21.158755)
			(xy 176.118968 -21.084845) (xy 176.131474 -21.048726) (xy 176.134055 -21.040409) (xy 176.134058 -21.023006)
			(xy 176.131474 -21.01469) (xy 176.118957 -20.978475) (xy 176.099434 -20.904375) (xy 176.086349 -20.828871)
			(xy 176.079799 -20.752523) (xy 176.079404 -20.714208) (xy 176.07999 -20.668344) (xy 176.089425 -20.577104)
			(xy 176.108186 -20.487316) (xy 176.121568 -20.443444) (xy 176.124428 -20.432883) (xy 176.121929 -20.411168)
			(xy 176.116742 -20.401534) (xy 176.096312 -20.366847) (xy 176.06107 -20.294464) (xy 176.032509 -20.219194)
			(xy 176.010862 -20.141652) (xy 175.996306 -20.062472) (xy 175.988959 -19.982301) (xy 175.988472 -19.942048)
			(xy 140.449617 -19.942048) (xy 140.472364 -19.977445) (xy 140.495002 -20.027018) (xy 140.510354 -20.079308)
			(xy 140.51811 -20.133251) (xy 140.51811 -20.187749) (xy 140.510354 -20.241692) (xy 140.495002 -20.293982)
			(xy 140.472364 -20.343555) (xy 140.442901 -20.389403) (xy 140.407215 -20.430591) (xy 140.36603 -20.466281)
			(xy 140.320185 -20.495747) (xy 140.270614 -20.51839) (xy 140.218325 -20.533747) (xy 140.164383 -20.541507)
			(xy 140.137134 -20.541996) (xy 139.146534 -20.541996) (xy 139.119279 -20.541559) (xy 139.065322 -20.533806)
			(xy 139.013019 -20.518453) (xy 138.963433 -20.495811) (xy 138.917574 -20.466343) (xy 138.876376 -20.430648)
			(xy 138.840677 -20.389453) (xy 138.811205 -20.343597) (xy 138.788559 -20.294013) (xy 138.773201 -20.241711)
			(xy 138.765443 -20.187755) (xy 67.653158 -20.187755) (xy 67.657521 -20.212789) (xy 67.664147 -20.289078)
			(xy 67.664584 -20.327366) (xy 67.66408 -20.369727) (xy 67.656027 -20.454064) (xy 67.639993 -20.537254)
			(xy 67.616125 -20.618544) (xy 67.584637 -20.697196) (xy 67.545815 -20.772499) (xy 67.500012 -20.843771)
			(xy 67.447641 -20.910367) (xy 67.389176 -20.971682) (xy 67.325148 -21.027163) (xy 67.256136 -21.076306)
			(xy 67.182766 -21.118666) (xy 67.105701 -21.153861) (xy 67.025639 -21.18157) (xy 66.943306 -21.201544)
			(xy 66.859447 -21.213601) (xy 66.774822 -21.217633) (xy 66.690197 -21.213601) (xy 66.606338 -21.201544)
			(xy 66.524005 -21.18157) (xy 66.443943 -21.153861) (xy 66.366878 -21.118666) (xy 66.293508 -21.076306)
			(xy 66.224496 -21.027163) (xy 66.160468 -20.971682) (xy 66.102003 -20.910367) (xy 66.049632 -20.843771)
			(xy 66.003829 -20.772499) (xy 65.965007 -20.697196) (xy 65.933519 -20.618544) (xy 65.909651 -20.537254)
			(xy 65.893617 -20.454064) (xy 65.885564 -20.369727) (xy 65.88506 -20.327366) (xy 1.524 -20.327366)
			(xy 1.524 -22.309271) (xy 65.993006 -22.309271) (xy 65.993006 -22.224549) (xy 66.001059 -22.140212)
			(xy 66.017093 -22.057022) (xy 66.040961 -21.975732) (xy 66.072449 -21.89708) (xy 66.111271 -21.821777)
			(xy 66.157074 -21.750505) (xy 66.209445 -21.683909) (xy 66.26791 -21.622594) (xy 66.331938 -21.567113)
			(xy 66.40095 -21.51797) (xy 66.47432 -21.47561) (xy 66.551385 -21.440415) (xy 66.631447 -21.412706)
			(xy 66.71378 -21.392732) (xy 66.797639 -21.380675) (xy 66.882264 -21.376644) (xy 66.966889 -21.380675)
			(xy 67.050748 -21.392732) (xy 67.133081 -21.412706) (xy 67.213143 -21.440415) (xy 67.290208 -21.47561)
			(xy 67.363578 -21.51797) (xy 67.43259 -21.567113) (xy 67.496618 -21.622594) (xy 67.555083 -21.683909)
			(xy 67.607454 -21.750505) (xy 67.653257 -21.821777) (xy 67.692079 -21.89708) (xy 67.723567 -21.975732)
			(xy 67.747435 -22.057022) (xy 67.755872 -22.100794) (xy 113.944146 -22.100794) (xy 113.944596 -22.073522)
			(xy 113.952359 -22.019535) (xy 113.967727 -21.967201) (xy 113.990385 -21.917588) (xy 114.019874 -21.871704)
			(xy 114.055593 -21.830483) (xy 114.096815 -21.794766) (xy 114.1427 -21.765279) (xy 114.192314 -21.742622)
			(xy 114.244648 -21.727256) (xy 114.298636 -21.719495) (xy 114.325908 -21.719032) (xy 114.326162 -21.719032)
			(xy 114.351127 -21.719444) (xy 114.400629 -21.725969) (xy 114.448859 -21.738886) (xy 114.494995 -21.757977)
			(xy 114.538252 -21.782914) (xy 114.558318 -21.797772) (xy 114.568495 -21.804638) (xy 114.592638 -21.808884)
			(xy 114.604546 -21.8059) (xy 114.641649 -21.794704) (xy 114.717549 -21.779017) (xy 114.794648 -21.771102)
			(xy 114.8334 -21.770594) (xy 114.833908 -21.770594) (xy 114.876509 -21.771197) (xy 114.96118 -21.780683)
			(xy 115.044267 -21.799546) (xy 115.124734 -21.827551) (xy 115.201578 -21.86435) (xy 115.238022 -21.886418)
			(xy 115.246278 -21.891132) (xy 115.264946 -21.894659) (xy 115.283614 -21.891132) (xy 115.29187 -21.886418)
			(xy 115.328407 -21.86415) (xy 115.405501 -21.82702) (xy 115.486268 -21.798759) (xy 115.569692 -21.779723)
			(xy 115.654724 -21.77015) (xy 115.697508 -21.769578) (xy 115.697762 -21.769578) (xy 115.736732 -21.770084)
			(xy 115.814264 -21.778043) (xy 115.890583 -21.793853) (xy 115.927886 -21.805138) (xy 115.93973 -21.808095)
			(xy 115.963735 -21.803834) (xy 115.97386 -21.79701) (xy 115.998952 -21.778645) (xy 116.053876 -21.749498)
			(xy 116.1128 -21.729646) (xy 116.174164 -21.719617) (xy 116.205254 -21.719032) (xy 116.205508 -21.719032)
			(xy 116.232777 -21.719517) (xy 116.286761 -21.72728) (xy 116.33909 -21.742646) (xy 116.3887 -21.765302)
			(xy 116.43458 -21.794788) (xy 116.475798 -21.830504) (xy 116.511513 -21.871721) (xy 116.540999 -21.917602)
			(xy 116.563655 -21.967212) (xy 116.579021 -22.019541) (xy 116.586783 -22.073525) (xy 116.58727 -22.100794)
			(xy 116.586815 -22.126656) (xy 116.579834 -22.177906) (xy 116.565987 -22.227741) (xy 116.545527 -22.275245)
			(xy 116.518831 -22.319547) (xy 116.486389 -22.359831) (xy 116.46789 -22.377908) (xy 116.459429 -22.386861)
			(xy 116.451334 -22.410085) (xy 116.452396 -22.422358) (xy 116.456178 -22.449761) (xy 116.460249 -22.504933)
			(xy 116.460524 -22.532594) (xy 116.460132 -22.569503) (xy 116.453003 -22.642975) (xy 116.438812 -22.715415)
			(xy 116.417691 -22.786146) (xy 116.389838 -22.854507) (xy 116.355512 -22.919858) (xy 116.315035 -22.981588)
			(xy 116.28659 -23.016972) (xy 135.942324 -23.016972) (xy 135.942784 -22.97749) (xy 135.950922 -22.898947)
			(xy 135.967131 -22.821665) (xy 135.991235 -22.746471) (xy 136.022978 -22.674168) (xy 136.062019 -22.605531)
			(xy 136.107941 -22.541294) (xy 136.160253 -22.482144) (xy 136.218395 -22.428714) (xy 136.281744 -22.381576)
			(xy 136.349625 -22.341233) (xy 136.421309 -22.308118) (xy 136.49603 -22.282585) (xy 136.534398 -22.27326)
			(xy 136.543557 -22.270706) (xy 136.559251 -22.260005) (xy 136.569976 -22.244325) (xy 136.572498 -22.23516)
			(xy 136.581857 -22.196805) (xy 136.60741 -22.1221) (xy 136.640539 -22.050432) (xy 136.68089 -21.982567)
			(xy 136.728032 -21.919231) (xy 136.781461 -21.861101) (xy 136.840606 -21.808797) (xy 136.904834 -21.762879)
			(xy 136.97346 -21.723837) (xy 137.04575 -21.692089) (xy 137.120932 -21.667973) (xy 137.198201 -21.651749)
			(xy 137.276733 -21.643588) (xy 137.31621 -21.643086) (xy 137.356684 -21.643608) (xy 137.437176 -21.652188)
			(xy 137.516308 -21.669239) (xy 137.59319 -21.694571) (xy 137.666959 -21.727899) (xy 137.736785 -21.768848)
			(xy 137.801885 -21.816958) (xy 137.861527 -21.871688) (xy 137.915041 -21.932424) (xy 137.961825 -21.998483)
			(xy 138.001354 -22.069123) (xy 138.017758 -22.106128) (xy 138.02342 -22.117541) (xy 138.043436 -22.133258)
			(xy 138.055858 -22.1361) (xy 138.082217 -22.140996) (xy 138.133316 -22.157218) (xy 138.181642 -22.180431)
			(xy 138.226245 -22.210177) (xy 138.266247 -22.245872) (xy 138.30086 -22.286813) (xy 138.329405 -22.332194)
			(xy 138.351319 -22.381123) (xy 138.366171 -22.432637) (xy 138.373668 -22.485722) (xy 138.37412 -22.512528)
			(xy 138.373724 -22.539802) (xy 138.365957 -22.593793) (xy 138.350585 -22.64613) (xy 138.327922 -22.695746)
			(xy 138.298427 -22.741631) (xy 138.262702 -22.782852) (xy 138.221475 -22.818569) (xy 138.175584 -22.848055)
			(xy 138.125964 -22.87071) (xy 138.073625 -22.886072) (xy 138.019632 -22.893829) (xy 137.992358 -22.89429)
			(xy 137.991596 -22.89429) (xy 137.97796 -22.894197) (xy 137.950756 -22.892287) (xy 137.93724 -22.89048)
			(xy 137.924556 -22.889324) (xy 137.900692 -22.898147) (xy 137.891774 -22.907244) (xy 137.865133 -22.937054)
			(xy 137.806596 -22.991514) (xy 137.742689 -23.039561) (xy 137.674112 -23.080668) (xy 137.601617 -23.114387)
			(xy 137.525995 -23.140346) (xy 137.487152 -23.149814) (xy 137.477967 -23.152291) (xy 137.462272 -23.163026)
			(xy 137.451561 -23.178736) (xy 137.449052 -23.187914) (xy 137.439539 -23.226989) (xy 137.413339 -23.30303)
			(xy 137.379296 -23.375898) (xy 137.337786 -23.444786) (xy 137.28927 -23.508932) (xy 137.234283 -23.567627)
			(xy 137.205055 -23.593552) (xy 189.619128 -23.593552) (xy 189.619128 -23.593298) (xy 189.619711 -23.54856)
			(xy 189.628722 -23.459539) (xy 189.646623 -23.371871) (xy 189.673232 -23.286444) (xy 189.690248 -23.245064)
			(xy 189.69384 -23.235481) (xy 189.693822 -23.215031) (xy 189.690248 -23.20544) (xy 189.673222 -23.164064)
			(xy 189.646604 -23.078637) (xy 189.6287 -22.990968) (xy 189.619692 -22.901945) (xy 189.619128 -22.857206)
			(xy 189.619128 -22.856952) (xy 189.619632 -22.814604) (xy 189.627683 -22.73029) (xy 189.643712 -22.647124)
			(xy 189.667573 -22.565857) (xy 189.699052 -22.487227) (xy 189.737863 -22.411946) (xy 189.783653 -22.340694)
			(xy 189.836009 -22.274118) (xy 189.894457 -22.21282) (xy 189.958467 -22.157355) (xy 190.027459 -22.108226)
			(xy 190.100809 -22.065877) (xy 190.177852 -22.030693) (xy 190.257891 -22.002991) (xy 190.3402 -21.983023)
			(xy 190.424035 -21.97097) (xy 190.508636 -21.96694) (xy 190.593237 -21.97097) (xy 190.677072 -21.983023)
			(xy 190.759381 -22.002991) (xy 190.83942 -22.030693) (xy 190.916463 -22.065877) (xy 190.989813 -22.108226)
			(xy 191.058805 -22.157355) (xy 191.122815 -22.21282) (xy 191.181263 -22.274118) (xy 191.233619 -22.340694)
			(xy 191.279409 -22.411946) (xy 191.31822 -22.487227) (xy 191.349699 -22.565857) (xy 191.37356 -22.647124)
			(xy 191.389589 -22.73029) (xy 191.39764 -22.814604) (xy 191.398144 -22.856952) (xy 191.398144 -22.857206)
			(xy 191.397557 -22.901944) (xy 191.388547 -22.990965) (xy 191.370647 -23.078632) (xy 191.344039 -23.16406)
			(xy 191.327024 -23.20544) (xy 191.323489 -23.215039) (xy 191.323471 -23.235473) (xy 191.327024 -23.245064)
			(xy 191.344055 -23.286438) (xy 191.370671 -23.371866) (xy 191.388573 -23.459535) (xy 191.39758 -23.548559)
			(xy 191.398144 -23.593298) (xy 191.398144 -23.593552) (xy 191.39764 -23.6359) (xy 191.389589 -23.720214)
			(xy 191.37356 -23.80338) (xy 191.349699 -23.884647) (xy 191.31822 -23.963277) (xy 191.279409 -24.038558)
			(xy 191.233619 -24.10981) (xy 191.181263 -24.176386) (xy 191.122815 -24.237684) (xy 191.058805 -24.293149)
			(xy 190.989813 -24.342278) (xy 190.916463 -24.384627) (xy 190.83942 -24.419811) (xy 190.759381 -24.447513)
			(xy 190.677072 -24.467481) (xy 190.593237 -24.479534) (xy 190.508636 -24.483565) (xy 190.424035 -24.479534)
			(xy 190.3402 -24.467481) (xy 190.257891 -24.447513) (xy 190.177852 -24.419811) (xy 190.100809 -24.384627)
			(xy 190.027459 -24.342278) (xy 189.958467 -24.293149) (xy 189.894457 -24.237684) (xy 189.836009 -24.176386)
			(xy 189.783653 -24.10981) (xy 189.737863 -24.038558) (xy 189.699052 -23.963277) (xy 189.667573 -23.884647)
			(xy 189.643712 -23.80338) (xy 189.627683 -23.720214) (xy 189.619632 -23.6359) (xy 189.619128 -23.593552)
			(xy 137.205055 -23.593552) (xy 137.204196 -23.594314) (xy 137.19793 -23.600084) (xy 137.189428 -23.614837)
			(xy 137.186249 -23.631565) (xy 137.187178 -23.640034) (xy 137.189076 -23.653798) (xy 137.191108 -23.681512)
			(xy 137.191242 -23.695406) (xy 137.190804 -23.722678) (xy 137.183041 -23.776667) (xy 137.167673 -23.829001)
			(xy 137.145013 -23.878616) (xy 137.115523 -23.9245) (xy 137.079803 -23.965721) (xy 137.03858 -24.001438)
			(xy 136.992693 -24.030925) (xy 136.943077 -24.053582) (xy 136.890741 -24.068946) (xy 136.836752 -24.076706)
			(xy 136.80948 -24.077168) (xy 136.78252 -24.076708) (xy 136.729138 -24.069118) (xy 136.677354 -24.054093)
			(xy 136.628199 -24.031932) (xy 136.582652 -24.003074) (xy 136.541618 -23.968095) (xy 136.505914 -23.927691)
			(xy 136.47625 -23.882664) (xy 136.453217 -23.833912) (xy 136.437272 -23.782404) (xy 136.432544 -23.755858)
			(xy 136.430855 -23.747498) (xy 136.422804 -23.732476) (xy 136.410262 -23.720935) (xy 136.402572 -23.71725)
			(xy 136.365758 -23.700764) (xy 136.295503 -23.661125) (xy 136.229822 -23.614294) (xy 136.169448 -23.560795)
			(xy 136.115056 -23.501225) (xy 136.067252 -23.436249) (xy 136.02657 -23.366592) (xy 135.993464 -23.293032)
			(xy 135.968304 -23.21639) (xy 135.951371 -23.137521) (xy 135.942852 -23.057305) (xy 135.942324 -23.016972)
			(xy 116.28659 -23.016972) (xy 116.268786 -23.03912) (xy 116.217197 -23.091917) (xy 116.189252 -23.116032)
			(xy 116.182705 -23.12205) (xy 116.173861 -23.137463) (xy 116.170806 -23.154969) (xy 116.17198 -23.163784)
			(xy 116.190014 -23.262844) (xy 116.207794 -23.283418) (xy 116.220494 -23.28799) (xy 116.243348 -23.296557)
			(xy 116.286862 -23.318661) (xy 116.327195 -23.346144) (xy 116.363686 -23.378554) (xy 116.380006 -23.396702)
			(xy 116.386314 -23.403343) (xy 116.402399 -23.412071) (xy 116.420525 -23.41459) (xy 116.429536 -23.412958)
			(xy 116.471439 -23.403945) (xy 116.556605 -23.394267) (xy 116.599462 -23.393654) (xy 116.600224 -23.393654)
			(xy 116.642916 -23.394238) (xy 116.727764 -23.403783) (xy 116.811016 -23.422741) (xy 116.891632 -23.450874)
			(xy 116.968603 -23.48783) (xy 117.0051 -23.509986) (xy 117.013356 -23.5147) (xy 117.032024 -23.518227)
			(xy 117.050692 -23.5147) (xy 117.058948 -23.509986) (xy 117.095446 -23.487829) (xy 117.172406 -23.450843)
			(xy 117.25302 -23.422698) (xy 117.336277 -23.403749) (xy 117.421131 -23.394233) (xy 117.463824 -23.393654)
			(xy 117.464586 -23.393654) (xy 117.507443 -23.394265) (xy 117.59261 -23.40394) (xy 117.634512 -23.412958)
			(xy 117.643528 -23.414579) (xy 117.661658 -23.412076) (xy 117.677751 -23.403359) (xy 117.684042 -23.396702)
			(xy 117.702268 -23.376545) (xy 117.743441 -23.341077) (xy 117.789226 -23.311804) (xy 117.838698 -23.289316)
			(xy 117.890858 -23.274069) (xy 117.944652 -23.266369) (xy 117.971824 -23.265892) (xy 117.999092 -23.266402)
			(xy 118.053072 -23.274166) (xy 118.105398 -23.289532) (xy 118.155006 -23.312187) (xy 118.200884 -23.341672)
			(xy 118.2421 -23.377384) (xy 118.277815 -23.418598) (xy 118.307302 -23.464475) (xy 118.329961 -23.514081)
			(xy 118.34533 -23.566406) (xy 118.353096 -23.620386) (xy 118.353586 -23.647654) (xy 118.353103 -23.674825)
			(xy 118.345397 -23.728617) (xy 118.330146 -23.780774) (xy 118.30766 -23.830245) (xy 118.278391 -23.87603)
			(xy 118.24293 -23.917207) (xy 118.222776 -23.935436) (xy 118.216114 -23.941724) (xy 118.207393 -23.957819)
			(xy 118.204883 -23.975952) (xy 118.20652 -23.984966) (xy 118.215538 -24.026868) (xy 118.225213 -24.112035)
			(xy 118.225824 -24.154892) (xy 118.225824 -24.155654) (xy 118.225252 -24.195561) (xy 118.216914 -24.274937)
			(xy 118.200324 -24.353007) (xy 118.175665 -24.428915) (xy 118.143205 -24.50183) (xy 118.103302 -24.570952)
			(xy 118.056392 -24.635525) (xy 118.00299 -24.69484) (xy 117.994649 -24.702351) (xy 130.235962 -24.702351)
			(xy 130.235962 -24.647849) (xy 130.243717 -24.593903) (xy 130.259071 -24.541609) (xy 130.28171 -24.492033)
			(xy 130.311174 -24.446182) (xy 130.346863 -24.404991) (xy 130.38805 -24.369298) (xy 130.433897 -24.33983)
			(xy 130.483472 -24.317185) (xy 130.535764 -24.301826) (xy 130.589709 -24.294065) (xy 130.61696 -24.293576)
			(xy 131.48056 -24.293576) (xy 131.507814 -24.294069) (xy 131.561767 -24.301821) (xy 131.614067 -24.317173)
			(xy 131.66365 -24.339812) (xy 131.709506 -24.369277) (xy 131.750702 -24.40497) (xy 131.786399 -24.446162)
			(xy 131.815869 -24.492015) (xy 131.838513 -24.541595) (xy 131.853871 -24.593894) (xy 131.861629 -24.647846)
			(xy 131.861629 -24.702354) (xy 131.853871 -24.756306) (xy 131.838513 -24.808605) (xy 131.815869 -24.858185)
			(xy 131.786399 -24.904038) (xy 131.750702 -24.94523) (xy 131.709506 -24.980923) (xy 131.66365 -25.010388)
			(xy 131.614067 -25.033027) (xy 131.561767 -25.048379) (xy 131.507814 -25.056131) (xy 131.48056 -25.056592)
			(xy 130.61696 -25.056592) (xy 130.589709 -25.056135) (xy 130.535764 -25.048374) (xy 130.483472 -25.033015)
			(xy 130.433897 -25.01037) (xy 130.38805 -24.980902) (xy 130.346863 -24.945209) (xy 130.311174 -24.904018)
			(xy 130.28171 -24.858167) (xy 130.259071 -24.808591) (xy 130.243717 -24.756297) (xy 130.235962 -24.702351)
			(xy 117.994649 -24.702351) (xy 117.943679 -24.748248) (xy 117.879111 -24.795164) (xy 117.809993 -24.835074)
			(xy 117.737081 -24.867539) (xy 117.661175 -24.892206) (xy 117.583106 -24.908803) (xy 117.503731 -24.917148)
			(xy 117.463824 -24.917654) (xy 117.421133 -24.917046) (xy 117.336286 -24.907506) (xy 117.253034 -24.888554)
			(xy 117.172418 -24.860427) (xy 117.095446 -24.823476) (xy 117.058948 -24.801322) (xy 117.050692 -24.796608)
			(xy 117.032024 -24.793081) (xy 117.013356 -24.796608) (xy 117.0051 -24.801322) (xy 116.968615 -24.823502)
			(xy 116.891651 -24.860484) (xy 116.811034 -24.888623) (xy 116.727774 -24.907568) (xy 116.642918 -24.917078)
			(xy 116.600224 -24.917654) (xy 116.560315 -24.917173) (xy 116.480933 -24.908831) (xy 116.402858 -24.892238)
			(xy 116.326946 -24.867573) (xy 116.254027 -24.835109) (xy 116.184902 -24.795199) (xy 116.120328 -24.748283)
			(xy 116.061012 -24.694873) (xy 116.007604 -24.635555) (xy 115.960689 -24.570979) (xy 115.920781 -24.501853)
			(xy 115.888319 -24.428934) (xy 115.863657 -24.353021) (xy 115.847065 -24.274945) (xy 115.838726 -24.195563)
			(xy 115.838224 -24.155654) (xy 115.838224 -24.154892) (xy 115.838832 -24.112035) (xy 115.848509 -24.026868)
			(xy 115.857528 -23.984966) (xy 115.859177 -23.975954) (xy 115.856665 -23.957818) (xy 115.847936 -23.941724)
			(xy 115.841272 -23.935436) (xy 115.821098 -23.917227) (xy 115.785633 -23.87605) (xy 115.756363 -23.830261)
			(xy 115.733878 -23.780786) (xy 115.718634 -23.728623) (xy 115.710937 -23.674826) (xy 115.710462 -23.647654)
			(xy 115.711037 -23.617471) (xy 115.720524 -23.557855) (xy 115.739272 -23.500473) (xy 115.766812 -23.446755)
			(xy 115.80246 -23.398039) (xy 115.823492 -23.376382) (xy 115.830046 -23.36933) (xy 115.837713 -23.351681)
			(xy 115.838349 -23.33245) (xy 115.831863 -23.314334) (xy 115.819166 -23.299876) (xy 115.80204 -23.291104)
			(xy 115.792504 -23.289768) (xy 115.768853 -23.29253) (xy 115.72132 -23.295452) (xy 115.697508 -23.29561)
			(xy 115.654727 -23.295008) (xy 115.569705 -23.285402) (xy 115.486289 -23.266355) (xy 115.405525 -23.238105)
			(xy 115.328423 -23.201007) (xy 115.29187 -23.17877) (xy 115.283614 -23.174056) (xy 115.264946 -23.170529)
			(xy 115.246278 -23.174056) (xy 115.238022 -23.17877) (xy 115.201578 -23.200841) (xy 115.124741 -23.237662)
			(xy 115.044275 -23.26568) (xy 114.961186 -23.284544) (xy 114.87651 -23.294019) (xy 114.833908 -23.294594)
			(xy 114.794 -23.294088) (xy 114.71462 -23.285746) (xy 114.636547 -23.269152) (xy 114.560637 -23.244488)
			(xy 114.487721 -23.212024) (xy 114.418597 -23.172116) (xy 114.354024 -23.125201) (xy 114.294708 -23.071793)
			(xy 114.241301 -23.012478) (xy 114.194386 -22.947905) (xy 114.154477 -22.878781) (xy 114.122013 -22.805865)
			(xy 114.097349 -22.729955) (xy 114.080754 -22.651882) (xy 114.072412 -22.572502) (xy 114.071908 -22.532594)
			(xy 114.071908 -22.531832) (xy 114.072167 -22.504557) (xy 114.076109 -22.450148) (xy 114.079782 -22.42312)
			(xy 114.080869 -22.410845) (xy 114.072766 -22.387614) (xy 114.064288 -22.37867) (xy 114.04569 -22.360564)
			(xy 114.013044 -22.320212) (xy 113.986172 -22.275806) (xy 113.965571 -22.228165) (xy 113.951622 -22.178171)
			(xy 113.944583 -22.126746) (xy 113.944146 -22.100794) (xy 67.755872 -22.100794) (xy 67.763469 -22.140212)
			(xy 67.771522 -22.224549) (xy 67.772026 -22.26691) (xy 67.771522 -22.309271) (xy 67.763469 -22.393608)
			(xy 67.747435 -22.476798) (xy 67.723567 -22.558088) (xy 67.692079 -22.63674) (xy 67.653257 -22.712043)
			(xy 67.607454 -22.783315) (xy 67.555083 -22.849911) (xy 67.496618 -22.911226) (xy 67.43259 -22.966707)
			(xy 67.363578 -23.01585) (xy 67.290208 -23.05821) (xy 67.213143 -23.093405) (xy 67.133081 -23.121114)
			(xy 67.050748 -23.141088) (xy 66.966889 -23.153145) (xy 66.882264 -23.157177) (xy 66.797639 -23.153145)
			(xy 66.71378 -23.141088) (xy 66.631447 -23.121114) (xy 66.551385 -23.093405) (xy 66.47432 -23.05821)
			(xy 66.40095 -23.01585) (xy 66.331938 -22.966707) (xy 66.26791 -22.911226) (xy 66.209445 -22.849911)
			(xy 66.157074 -22.783315) (xy 66.111271 -22.712043) (xy 66.072449 -22.63674) (xy 66.040961 -22.558088)
			(xy 66.017093 -22.476798) (xy 66.001059 -22.393608) (xy 65.993006 -22.309271) (xy 1.524 -22.309271)
			(xy 1.524 -25.56891) (xy 65.510156 -25.56891) (xy 65.510621 -25.527206) (xy 65.518403 -25.444163)
			(xy 65.533928 -25.362214) (xy 65.557059 -25.282079) (xy 65.587593 -25.204462) (xy 65.625262 -25.130046)
			(xy 65.669734 -25.059485) (xy 65.720619 -24.993398) (xy 65.777469 -24.932368) (xy 65.839786 -24.876929)
			(xy 65.873122 -24.851868) (xy 65.88167 -24.844931) (xy 65.892346 -24.825708) (xy 65.893696 -24.814784)
			(xy 65.897332 -24.773398) (xy 65.911399 -24.69151) (xy 65.933041 -24.611291) (xy 65.962067 -24.53344)
			(xy 65.998226 -24.458634) (xy 66.041203 -24.387525) (xy 66.090622 -24.320733) (xy 66.146054 -24.25884)
			(xy 66.207015 -24.202385) (xy 66.272974 -24.15186) (xy 66.343357 -24.107705) (xy 66.41755 -24.070304)
			(xy 66.494907 -24.039985) (xy 66.574755 -24.01701) (xy 66.656396 -24.00158) (xy 66.739121 -23.99383)
			(xy 66.780664 -23.993348) (xy 66.824459 -23.993873) (xy 66.911625 -24.002491) (xy 66.997521 -24.019637)
			(xy 67.081315 -24.045145) (xy 67.162195 -24.078768) (xy 67.201034 -24.099012) (xy 67.2125 -24.10443)
			(xy 67.237828 -24.10443) (xy 67.249294 -24.099012) (xy 67.288138 -24.078781) (xy 67.369023 -24.045174)
			(xy 67.452816 -24.019672) (xy 67.538709 -24.002521) (xy 67.62587 -23.993888) (xy 67.669664 -23.993348)
			(xy 67.713459 -23.993873) (xy 67.800625 -24.002491) (xy 67.886521 -24.019637) (xy 67.970315 -24.045145)
			(xy 68.051195 -24.078768) (xy 68.090034 -24.099012) (xy 68.1015 -24.10443) (xy 68.126828 -24.10443)
			(xy 68.138294 -24.099012) (xy 68.177138 -24.078781) (xy 68.258023 -24.045174) (xy 68.341816 -24.019672)
			(xy 68.427709 -24.002521) (xy 68.51487 -23.993888) (xy 68.558664 -23.993348) (xy 68.607651 -23.994055)
			(xy 68.705028 -24.00487) (xy 68.752974 -24.014938) (xy 68.762324 -24.016604) (xy 68.781086 -24.013776)
			(xy 68.797533 -24.004314) (xy 68.803774 -23.997158) (xy 68.831851 -23.962886) (xy 68.893786 -23.899527)
			(xy 68.961714 -23.842641) (xy 69.034963 -23.792791) (xy 69.112805 -23.750472) (xy 69.19447 -23.716104)
			(xy 69.279148 -23.690027) (xy 69.365999 -23.672499) (xy 69.454163 -23.663695) (xy 69.498464 -23.663148)
			(xy 69.540827 -23.663615) (xy 69.625169 -23.671665) (xy 69.708365 -23.687697) (xy 69.789659 -23.711564)
			(xy 69.868317 -23.743051) (xy 69.943625 -23.781873) (xy 70.014902 -23.827677) (xy 70.081502 -23.880049)
			(xy 70.142823 -23.938516) (xy 70.198307 -24.002546) (xy 70.247454 -24.071561) (xy 70.250564 -24.076947)
			(xy 112.652614 -24.076947) (xy 112.652614 -24.022453) (xy 112.660369 -23.968515) (xy 112.67572 -23.916228)
			(xy 112.698356 -23.866659) (xy 112.727815 -23.820815) (xy 112.763499 -23.77963) (xy 112.80468 -23.743942)
			(xy 112.85052 -23.714477) (xy 112.900087 -23.691836) (xy 112.952372 -23.676478) (xy 113.006309 -23.668717)
			(xy 113.033556 -23.668228) (xy 113.897156 -23.668228) (xy 113.924413 -23.668616) (xy 113.978374 -23.676369)
			(xy 114.030682 -23.691722) (xy 114.080273 -23.714364) (xy 114.126136 -23.743834) (xy 114.167338 -23.779531)
			(xy 114.20304 -23.820729) (xy 114.232514 -23.866588) (xy 114.255162 -23.916176) (xy 114.270522 -23.968483)
			(xy 114.278281 -24.022443) (xy 114.278281 -24.076957) (xy 114.270522 -24.130917) (xy 114.255162 -24.183224)
			(xy 114.232514 -24.232812) (xy 114.20304 -24.278671) (xy 114.167338 -24.319869) (xy 114.126136 -24.355566)
			(xy 114.080273 -24.385036) (xy 114.030682 -24.407678) (xy 113.978374 -24.423031) (xy 113.924414 -24.430784)
			(xy 113.897156 -24.431244) (xy 113.033556 -24.431244) (xy 113.006309 -24.430683) (xy 112.952372 -24.422922)
			(xy 112.900087 -24.407564) (xy 112.85052 -24.384923) (xy 112.80468 -24.355458) (xy 112.763499 -24.31977)
			(xy 112.727815 -24.278585) (xy 112.698356 -24.232741) (xy 112.67572 -24.183172) (xy 112.660369 -24.130885)
			(xy 112.652614 -24.076947) (xy 70.250564 -24.076947) (xy 70.289818 -24.144935) (xy 70.325015 -24.222004)
			(xy 70.352727 -24.302069) (xy 70.372702 -24.384407) (xy 70.38476 -24.46827) (xy 70.388792 -24.5529)
			(xy 70.38476 -24.63753) (xy 70.372702 -24.721393) (xy 70.352727 -24.803731) (xy 70.325015 -24.883796)
			(xy 70.289818 -24.960865) (xy 70.247454 -25.034239) (xy 70.198307 -25.103254) (xy 70.142823 -25.167284)
			(xy 70.081502 -25.225751) (xy 70.014902 -25.278123) (xy 69.943625 -25.323927) (xy 69.868317 -25.362749)
			(xy 69.789659 -25.394236) (xy 69.708365 -25.418103) (xy 69.625169 -25.434135) (xy 69.540827 -25.442185)
			(xy 69.498464 -25.442672) (xy 69.449476 -25.441976) (xy 69.3521 -25.431154) (xy 69.304154 -25.421082)
			(xy 69.294812 -25.41935) (xy 69.276039 -25.422204) (xy 69.259591 -25.431693) (xy 69.253354 -25.438862)
			(xy 69.228687 -25.46901) (xy 69.174875 -25.52534) (xy 69.116354 -25.57676) (xy 69.085206 -25.600152)
			(xy 69.076637 -25.607067) (xy 69.065975 -25.626306) (xy 69.065849 -25.62733) (xy 133.339332 -25.62733)
			(xy 133.339332 -24.76373) (xy 133.339818 -24.736479) (xy 133.347574 -24.682531) (xy 133.362929 -24.630236)
			(xy 133.385571 -24.580659) (xy 133.415037 -24.534809) (xy 133.450728 -24.493618) (xy 133.491919 -24.457927)
			(xy 133.537769 -24.428461) (xy 133.587346 -24.405819) (xy 133.639641 -24.390464) (xy 133.693589 -24.382708)
			(xy 133.748091 -24.382708) (xy 133.802039 -24.390464) (xy 133.854334 -24.405819) (xy 133.903911 -24.428461)
			(xy 133.949761 -24.457927) (xy 133.990952 -24.493618) (xy 134.026643 -24.534809) (xy 134.056109 -24.580659)
			(xy 134.078751 -24.630236) (xy 134.094106 -24.682531) (xy 134.101862 -24.736479) (xy 134.102348 -24.76373)
			(xy 134.102348 -25.62733) (xy 134.101862 -25.654581) (xy 134.094106 -25.708529) (xy 134.078751 -25.760824)
			(xy 134.056109 -25.810401) (xy 134.026643 -25.856251) (xy 133.990952 -25.897442) (xy 133.949761 -25.933133)
			(xy 133.903911 -25.962599) (xy 133.854334 -25.985241) (xy 133.802039 -26.000596) (xy 133.748091 -26.008352)
			(xy 133.693589 -26.008352) (xy 133.639641 -26.000596) (xy 133.587346 -25.985241) (xy 133.537769 -25.962599)
			(xy 133.491919 -25.933133) (xy 133.450728 -25.897442) (xy 133.415037 -25.856251) (xy 133.385571 -25.810401)
			(xy 133.362929 -25.760824) (xy 133.347574 -25.708529) (xy 133.339818 -25.654581) (xy 133.339332 -25.62733)
			(xy 69.065849 -25.62733) (xy 69.064632 -25.637236) (xy 69.060986 -25.678621) (xy 69.046917 -25.760507)
			(xy 69.025275 -25.840725) (xy 68.996248 -25.918575) (xy 68.960089 -25.99338) (xy 68.917113 -26.064488)
			(xy 68.867694 -26.131279) (xy 68.812263 -26.193171) (xy 68.751303 -26.249626) (xy 68.685345 -26.300151)
			(xy 68.614964 -26.344307) (xy 68.540772 -26.381708) (xy 68.463416 -26.412028) (xy 68.38357 -26.435004)
			(xy 68.30193 -26.450436) (xy 68.219207 -26.458189) (xy 68.177664 -26.458672) (xy 68.133869 -26.458133)
			(xy 68.046704 -26.449518) (xy 67.960808 -26.432375) (xy 67.877014 -26.40687) (xy 67.796134 -26.37325)
			(xy 67.757294 -26.353008) (xy 67.745828 -26.34759) (xy 67.7205 -26.34759) (xy 67.709034 -26.353008)
			(xy 67.670181 -26.373222) (xy 67.589299 -26.406833) (xy 67.505508 -26.43234) (xy 67.419618 -26.449494)
			(xy 67.332457 -26.458131) (xy 67.288664 -26.458672) (xy 67.244869 -26.458133) (xy 67.157704 -26.449518)
			(xy 67.071808 -26.432375) (xy 66.988014 -26.40687) (xy 66.907134 -26.37325) (xy 66.868294 -26.353008)
			(xy 66.856828 -26.34759) (xy 66.8315 -26.34759) (xy 66.820034 -26.353008) (xy 66.781181 -26.373222)
			(xy 66.700299 -26.406833) (xy 66.616508 -26.43234) (xy 66.530618 -26.449494) (xy 66.443457 -26.458131)
			(xy 66.399664 -26.458672) (xy 66.358552 -26.458282) (xy 66.276678 -26.45069) (xy 66.195855 -26.435576)
			(xy 66.116771 -26.413067) (xy 66.040102 -26.383356) (xy 65.966502 -26.346696) (xy 65.8966 -26.3034)
			(xy 65.830991 -26.253838) (xy 65.770236 -26.198433) (xy 65.714853 -26.137658) (xy 65.665316 -26.072031)
			(xy 65.622046 -26.002113) (xy 65.585413 -25.928499) (xy 65.55573 -25.85182) (xy 65.53325 -25.772728)
			(xy 65.518165 -25.691899) (xy 65.510603 -25.610022) (xy 65.510156 -25.56891) (xy 1.524 -25.56891)
			(xy 1.524 -29.026161) (xy 11.140205 -29.026161) (xy 11.147539 -28.866724) (xy 11.162812 -28.70785)
			(xy 11.185984 -28.549934) (xy 11.216999 -28.39337) (xy 11.255779 -28.238547) (xy 11.302228 -28.085849)
			(xy 11.35623 -27.935656) (xy 11.417652 -27.788341) (xy 11.48634 -27.644271) (xy 11.562123 -27.503804)
			(xy 11.644814 -27.367289) (xy 11.734207 -27.235065) (xy 11.830079 -27.107461) (xy 11.932193 -26.984794)
			(xy 12.040293 -26.86737) (xy 12.154112 -26.75548) (xy 12.273367 -26.649402) (xy 12.397761 -26.5494)
			(xy 12.526985 -26.455723) (xy 12.660717 -26.368604) (xy 12.798626 -26.288258) (xy 12.940368 -26.214886)
			(xy 13.085591 -26.148671) (xy 13.233934 -26.089776) (xy 13.385028 -26.038349) (xy 13.538498 -25.994517)
			(xy 13.693962 -25.958388) (xy 13.851033 -25.930054) (xy 14.009321 -25.909584) (xy 14.168433 -25.897029)
			(xy 14.327973 -25.892421) (xy 14.487544 -25.895771) (xy 14.64675 -25.90707) (xy 14.805195 -25.92629)
			(xy 14.962485 -25.953385) (xy 15.118229 -25.988285) (xy 15.272039 -26.030905) (xy 15.423535 -26.081139)
			(xy 15.572338 -26.138862) (xy 15.718078 -26.203929) (xy 15.860395 -26.27618) (xy 15.998933 -26.355436)
			(xy 16.133349 -26.441497) (xy 16.263308 -26.534152) (xy 16.388487 -26.633169) (xy 16.508575 -26.738303)
			(xy 16.623273 -26.849292) (xy 16.678148 -26.907236) (xy 17.770856 -28.07589) (xy 17.824996 -28.134528)
			(xy 17.928078 -28.256394) (xy 18.024957 -28.383247) (xy 18.115392 -28.514772) (xy 18.199158 -28.650641)
			(xy 18.276047 -28.790516) (xy 18.345869 -28.934051) (xy 18.408448 -29.080887) (xy 18.463631 -29.230661)
			(xy 18.511279 -29.382999) (xy 18.551274 -29.537523) (xy 18.583516 -29.693848) (xy 18.607926 -29.851586)
			(xy 18.624443 -30.010345) (xy 18.633025 -30.16973) (xy 18.633652 -30.329344) (xy 18.626321 -30.488792)
			(xy 18.611051 -30.647675) (xy 18.587881 -30.8056) (xy 18.556867 -30.962174) (xy 18.518086 -31.117007)
			(xy 18.471636 -31.269714) (xy 18.417631 -31.419917) (xy 18.356206 -31.56724) (xy 18.287514 -31.711318)
			(xy 18.211725 -31.851793) (xy 18.129028 -31.988316) (xy 18.039629 -32.120546) (xy 17.943749 -32.248156)
			(xy 17.841627 -32.370828) (xy 17.733517 -32.488256) (xy 17.619688 -32.60015) (xy 17.500423 -32.70623)
			(xy 17.376019 -32.806234) (xy 17.246784 -32.899911) (xy 17.11304 -32.98703) (xy 16.975119 -33.067374)
			(xy 16.833366 -33.140743) (xy 16.688131 -33.206955) (xy 16.539776 -33.265845) (xy 16.38867 -33.317266)
			(xy 16.235188 -33.361091) (xy 16.079713 -33.397211) (xy 15.922631 -33.425536) (xy 15.764332 -33.445995)
			(xy 15.605209 -33.458538) (xy 15.44566 -33.463134) (xy 15.286079 -33.459771) (xy 15.126865 -33.448457)
			(xy 14.968413 -33.42922) (xy 14.811116 -33.402109) (xy 14.655367 -33.367191) (xy 14.501552 -33.324553)
			(xy 14.350053 -33.2743) (xy 14.201248 -33.216557) (xy 14.055506 -33.151469) (xy 13.91319 -33.079197)
			(xy 13.774653 -32.999921) (xy 13.64024 -32.913837) (xy 13.510286 -32.82116) (xy 13.385112 -32.72212)
			(xy 13.265032 -32.616964) (xy 13.150342 -32.505953) (xy 13.095478 -32.447992) (xy 12.00277 -31.279592)
			(xy 11.948692 -31.220903) (xy 11.845626 -31.099035) (xy 11.748763 -30.972182) (xy 11.658343 -30.840658)
			(xy 11.574591 -30.704792) (xy 11.497716 -30.564919) (xy 11.427907 -30.421388) (xy 11.36534 -30.274557)
			(xy 11.310169 -30.124789) (xy 11.262532 -29.972457) (xy 11.222547 -29.81794) (xy 11.190314 -29.661623)
			(xy 11.165912 -29.503893) (xy 11.149402 -29.345143) (xy 11.140826 -29.185767) (xy 11.140205 -29.026161)
			(xy 1.524 -29.026161) (xy 1.524 -39.23137) (xy 9.080235 -39.23137) (xy 9.080235 -39.10223) (xy 9.088185 -38.973335)
			(xy 9.104055 -38.845175) (xy 9.127784 -38.718234) (xy 9.159283 -38.592995) (xy 9.198432 -38.469932)
			(xy 9.245083 -38.349513) (xy 9.299058 -38.232194) (xy 9.360153 -38.11842) (xy 9.428136 -38.008623)
			(xy 9.50275 -37.90322) (xy 9.583711 -37.80261) (xy 9.670711 -37.707175) (xy 9.763422 -37.617276)
			(xy 9.861492 -37.533255) (xy 9.964547 -37.455431) (xy 10.072198 -37.384099) (xy 10.184037 -37.319529)
			(xy 10.299638 -37.261967) (xy 10.418563 -37.21163) (xy 10.540362 -37.16871) (xy 10.664572 -37.133369)
			(xy 10.790721 -37.105742) (xy 10.918333 -37.085933) (xy 11.046922 -37.074017) (xy 11.176 -37.070041)
			(xy 11.305078 -37.074017) (xy 11.433667 -37.085933) (xy 11.561279 -37.105742) (xy 11.687428 -37.133369)
			(xy 11.811638 -37.16871) (xy 11.933437 -37.21163) (xy 12.052362 -37.261967) (xy 12.167963 -37.319529)
			(xy 12.279802 -37.384099) (xy 12.387453 -37.455431) (xy 12.490508 -37.533255) (xy 12.588578 -37.617276)
			(xy 12.681289 -37.707175) (xy 12.768289 -37.80261) (xy 12.84925 -37.90322) (xy 12.923864 -38.008623)
			(xy 12.991847 -38.11842) (xy 13.052942 -38.232194) (xy 13.106917 -38.349513) (xy 13.153568 -38.469932)
			(xy 13.192717 -38.592995) (xy 13.224216 -38.718234) (xy 13.247945 -38.845175) (xy 13.263815 -38.973335)
			(xy 13.271765 -39.10223) (xy 13.272262 -39.1668) (xy 13.271765 -39.23137) (xy 13.263815 -39.360265)
			(xy 13.247945 -39.488425) (xy 13.224216 -39.615366) (xy 13.192717 -39.740605) (xy 13.153568 -39.863668)
			(xy 13.106917 -39.984087) (xy 13.052942 -40.101406) (xy 12.991847 -40.21518) (xy 12.923864 -40.324977)
			(xy 12.84925 -40.43038) (xy 12.768289 -40.53099) (xy 12.681289 -40.626425) (xy 12.588578 -40.716324)
			(xy 12.490508 -40.800345) (xy 12.413317 -40.858637) (xy 24.936192 -40.858637) (xy 24.936192 -40.773915)
			(xy 24.944245 -40.689578) (xy 24.960279 -40.606388) (xy 24.984147 -40.525098) (xy 25.015635 -40.446446)
			(xy 25.054457 -40.371143) (xy 25.10026 -40.299871) (xy 25.152631 -40.233275) (xy 25.211096 -40.17196)
			(xy 25.275124 -40.116479) (xy 25.344136 -40.067336) (xy 25.417506 -40.024976) (xy 25.494571 -39.989781)
			(xy 25.574633 -39.962072) (xy 25.656966 -39.942098) (xy 25.740825 -39.930041) (xy 25.82545 -39.92601)
			(xy 25.910075 -39.930041) (xy 25.993934 -39.942098) (xy 26.076267 -39.962072) (xy 26.156329 -39.989781)
			(xy 26.233394 -40.024976) (xy 26.306764 -40.067336) (xy 26.375776 -40.116479) (xy 26.439804 -40.17196)
			(xy 26.498269 -40.233275) (xy 26.55064 -40.299871) (xy 26.596443 -40.371143) (xy 26.635265 -40.446446)
			(xy 26.666753 -40.525098) (xy 26.690621 -40.606388) (xy 26.706655 -40.689578) (xy 26.714708 -40.773915)
			(xy 26.715212 -40.816276) (xy 26.714708 -40.858637) (xy 26.706655 -40.942974) (xy 26.690621 -41.026164)
			(xy 26.666753 -41.107454) (xy 26.635265 -41.186106) (xy 26.596443 -41.261409) (xy 26.55064 -41.332681)
			(xy 26.498269 -41.399277) (xy 26.439804 -41.460592) (xy 26.375776 -41.516073) (xy 26.306764 -41.565216)
			(xy 26.233394 -41.607576) (xy 26.156329 -41.642771) (xy 26.076267 -41.67048) (xy 25.993934 -41.690454)
			(xy 25.910075 -41.702511) (xy 25.82545 -41.706543) (xy 25.740825 -41.702511) (xy 25.656966 -41.690454)
			(xy 25.574633 -41.67048) (xy 25.494571 -41.642771) (xy 25.417506 -41.607576) (xy 25.344136 -41.565216)
			(xy 25.275124 -41.516073) (xy 25.211096 -41.460592) (xy 25.152631 -41.399277) (xy 25.10026 -41.332681)
			(xy 25.054457 -41.261409) (xy 25.015635 -41.186106) (xy 24.984147 -41.107454) (xy 24.960279 -41.026164)
			(xy 24.944245 -40.942974) (xy 24.936192 -40.858637) (xy 12.413317 -40.858637) (xy 12.387453 -40.878169)
			(xy 12.279802 -40.949501) (xy 12.167963 -41.014071) (xy 12.052362 -41.071633) (xy 11.933437 -41.12197)
			(xy 11.811638 -41.16489) (xy 11.687428 -41.200231) (xy 11.561279 -41.227858) (xy 11.433667 -41.247667)
			(xy 11.305078 -41.259583) (xy 11.176 -41.26356) (xy 11.046922 -41.259583) (xy 10.918333 -41.247667)
			(xy 10.790721 -41.227858) (xy 10.664572 -41.200231) (xy 10.540362 -41.16489) (xy 10.418563 -41.12197)
			(xy 10.299638 -41.071633) (xy 10.184037 -41.014071) (xy 10.072198 -40.949501) (xy 9.964547 -40.878169)
			(xy 9.861492 -40.800345) (xy 9.763422 -40.716324) (xy 9.670711 -40.626425) (xy 9.583711 -40.53099)
			(xy 9.50275 -40.43038) (xy 9.428136 -40.324977) (xy 9.360153 -40.21518) (xy 9.299058 -40.101406)
			(xy 9.245083 -39.984087) (xy 9.198432 -39.863668) (xy 9.159283 -39.740605) (xy 9.127784 -39.615366)
			(xy 9.104055 -39.488425) (xy 9.088185 -39.360265) (xy 9.080235 -39.23137) (xy 1.524 -39.23137) (xy 1.524 -74.760836)
			(xy 39.554404 -74.760836) (xy 39.554404 -66.060828) (xy 39.554909 -65.955304) (xy 39.562993 -65.74441)
			(xy 39.579149 -65.533981) (xy 39.603352 -65.324324) (xy 39.635569 -65.115749) (xy 39.675751 -64.908561)
			(xy 39.723839 -64.703064) (xy 39.779763 -64.49956) (xy 39.84344 -64.298347) (xy 39.914778 -64.09972)
			(xy 39.993672 -63.903972) (xy 40.080005 -63.71139) (xy 40.173652 -63.522255) (xy 40.274474 -63.336846)
			(xy 40.382324 -63.155435) (xy 40.497043 -62.978288) (xy 40.618463 -62.805666) (xy 40.746406 -62.63782)
			(xy 40.880684 -62.474998) (xy 41.0211 -62.317439) (xy 41.167448 -62.165374) (xy 41.319513 -62.019026)
			(xy 41.477072 -61.87861) (xy 41.639894 -61.744332) (xy 41.80774 -61.616389) (xy 41.980362 -61.494969)
			(xy 42.157509 -61.38025) (xy 42.33892 -61.2724) (xy 42.524329 -61.171578) (xy 42.713464 -61.077931)
			(xy 42.906046 -60.991598) (xy 43.101794 -60.912704) (xy 43.300421 -60.841366) (xy 43.501634 -60.777689)
			(xy 43.705138 -60.721765) (xy 43.910635 -60.673677) (xy 44.117823 -60.633495) (xy 44.326398 -60.601278)
			(xy 44.536055 -60.577075) (xy 44.746484 -60.560919) (xy 44.957378 -60.552835) (xy 45.168426 -60.552835)
			(xy 45.37932 -60.560919) (xy 45.589749 -60.577075) (xy 45.799406 -60.601278) (xy 46.007981 -60.633495)
			(xy 46.215169 -60.673677) (xy 46.420666 -60.721765) (xy 46.62417 -60.777689) (xy 46.825383 -60.841366)
			(xy 47.02401 -60.912704) (xy 47.219758 -60.991598) (xy 47.41234 -61.077931) (xy 47.601475 -61.171578)
			(xy 47.786884 -61.2724) (xy 47.968295 -61.38025) (xy 48.145442 -61.494969) (xy 48.318064 -61.616389)
			(xy 48.48591 -61.744332) (xy 48.648732 -61.87861) (xy 48.806291 -62.019026) (xy 48.958356 -62.165374)
			(xy 49.104704 -62.317439) (xy 49.24512 -62.474998) (xy 49.379398 -62.63782) (xy 49.507341 -62.805666)
			(xy 49.628761 -62.978288) (xy 49.74348 -63.155435) (xy 49.85133 -63.336846) (xy 49.952152 -63.522255)
			(xy 50.045799 -63.71139) (xy 50.132132 -63.903972) (xy 50.211026 -64.09972) (xy 50.282364 -64.298347)
			(xy 50.346041 -64.49956) (xy 50.401965 -64.703064) (xy 50.450053 -64.908561) (xy 50.490235 -65.115749)
			(xy 50.522452 -65.324324) (xy 50.546655 -65.533981) (xy 50.562811 -65.74441) (xy 50.570895 -65.955304)
			(xy 50.5714 -66.060828) (xy 50.5714 -74.760836) (xy 50.570895 -74.86636) (xy 50.562811 -75.077254)
			(xy 50.546655 -75.287683) (xy 50.522452 -75.49734) (xy 50.490235 -75.705915) (xy 50.450053 -75.913103)
			(xy 50.401965 -76.1186) (xy 50.346041 -76.322104) (xy 50.282364 -76.523317) (xy 50.211026 -76.721944)
			(xy 50.132132 -76.917692) (xy 50.045799 -77.110274) (xy 49.952152 -77.299409) (xy 49.85133 -77.484818)
			(xy 49.74348 -77.666229) (xy 49.628761 -77.843376) (xy 49.507341 -78.015998) (xy 49.379398 -78.183844)
			(xy 49.24512 -78.346666) (xy 49.104704 -78.504225) (xy 48.958356 -78.65629) (xy 48.806291 -78.802638)
			(xy 48.648732 -78.943054) (xy 48.48591 -79.077332) (xy 48.318064 -79.205275) (xy 48.145442 -79.326695)
			(xy 47.968295 -79.441414) (xy 47.786884 -79.549264) (xy 47.601475 -79.650086) (xy 47.41234 -79.743733)
			(xy 47.219758 -79.830066) (xy 47.02401 -79.90896) (xy 46.825383 -79.980298) (xy 46.62417 -80.043975)
			(xy 46.420666 -80.099899) (xy 46.215169 -80.147987) (xy 46.007981 -80.188169) (xy 45.799406 -80.220386)
			(xy 45.589749 -80.244589) (xy 45.37932 -80.260745) (xy 45.168426 -80.268829) (xy 44.957378 -80.268829)
			(xy 44.746484 -80.260745) (xy 44.536055 -80.244589) (xy 44.326398 -80.220386) (xy 44.117823 -80.188169)
			(xy 43.910635 -80.147987) (xy 43.705138 -80.099899) (xy 43.501634 -80.043975) (xy 43.300421 -79.980298)
			(xy 43.101794 -79.90896) (xy 42.906046 -79.830066) (xy 42.713464 -79.743733) (xy 42.524329 -79.650086)
			(xy 42.33892 -79.549264) (xy 42.157509 -79.441414) (xy 41.980362 -79.326695) (xy 41.80774 -79.205275)
			(xy 41.639894 -79.077332) (xy 41.477072 -78.943054) (xy 41.319513 -78.802638) (xy 41.167448 -78.65629)
			(xy 41.0211 -78.504225) (xy 40.880684 -78.346666) (xy 40.746406 -78.183844) (xy 40.618463 -78.015998)
			(xy 40.497043 -77.843376) (xy 40.382324 -77.666229) (xy 40.274474 -77.484818) (xy 40.173652 -77.299409)
			(xy 40.080005 -77.110274) (xy 39.993672 -76.917692) (xy 39.914778 -76.721944) (xy 39.84344 -76.523317)
			(xy 39.779763 -76.322104) (xy 39.723839 -76.1186) (xy 39.675751 -75.913103) (xy 39.635569 -75.705915)
			(xy 39.603352 -75.49734) (xy 39.579149 -75.287683) (xy 39.562993 -75.077254) (xy 39.554909 -74.86636)
			(xy 39.554404 -74.760836) (xy 1.524 -74.760836) (xy 1.524 -77.671676) (xy 1.524528 -77.702818) (xy 1.532691 -77.764566)
			(xy 1.548839 -77.824722) (xy 1.572695 -77.882257) (xy 1.603853 -77.936189) (xy 1.64178 -77.985596)
			(xy 1.663446 -78.007972) (xy 2.49174 -78.836266) (xy 2.492248 -78.836774) (xy 2.506726 -78.851506)
			(xy 2.566693 -78.91292) (xy 2.681269 -79.040756) (xy 2.789483 -79.17402) (xy 2.891079 -79.312396)
			(xy 2.985816 -79.455556) (xy 3.073468 -79.603159) (xy 3.153829 -79.754856) (xy 3.226706 -79.910286)
			(xy 3.291927 -80.069081) (xy 3.349338 -80.230864) (xy 3.398801 -80.395251) (xy 3.440201 -80.561852)
			(xy 3.473438 -80.730271) (xy 3.498433 -80.900109) (xy 3.515128 -81.070962) (xy 3.523482 -81.242426)
			(xy 3.523996 -81.32826) (xy 3.523996 -90.854276) (xy 57.149492 -90.854276) (xy 57.149492 -30.10662)
			(xy 57.149903 -30.096549) (xy 57.157631 -30.077949) (xy 57.164478 -30.070552) (xy 58.356246 -28.879038)
			(xy 58.360056 -28.869894) (xy 58.374793 -28.836236) (xy 58.409783 -28.77162) (xy 58.450827 -28.710671)
			(xy 58.497543 -28.653952) (xy 58.5495 -28.601991) (xy 58.606214 -28.555269) (xy 58.66716 -28.51422)
			(xy 58.731772 -28.479224) (xy 58.76544 -28.46451) (xy 58.774584 -28.4607) (xy 59.009534 -28.22575)
			(xy 59.013344 -28.21432) (xy 59.026183 -28.17696) (xy 59.058603 -28.104915) (xy 59.0983 -28.03661)
			(xy 59.144847 -27.972775) (xy 59.197746 -27.914096) (xy 59.25643 -27.861203) (xy 59.320269 -27.814661)
			(xy 59.388578 -27.774971) (xy 59.460626 -27.742558) (xy 59.497976 -27.729688) (xy 59.503496 -27.727672)
			(xy 59.513502 -27.721516) (xy 59.517788 -27.717496) (xy 59.823604 -27.411426) (xy 59.831012 -27.404596)
			(xy 59.849605 -27.39687) (xy 59.859672 -27.39644) (xy 64.219328 -27.39644) (xy 64.2294 -27.39684)
			(xy 64.247998 -27.404577) (xy 64.255396 -27.411426) (xy 64.457072 -27.613102) (xy 64.464363 -27.619762)
			(xy 64.482522 -27.627475) (xy 64.492378 -27.628088) (xy 64.492632 -27.628088) (xy 64.531985 -27.629034)
			(xy 64.610191 -27.638031) (xy 64.687054 -27.655036) (xy 64.761756 -27.67987) (xy 64.833502 -27.712269)
			(xy 64.901528 -27.751887) (xy 64.905217 -27.75458) (xy 130.305302 -27.75458) (xy 130.30588 -27.712975)
			(xy 130.314932 -27.630259) (xy 130.332926 -27.549018) (xy 130.359649 -27.470216) (xy 130.394784 -27.394788)
			(xy 130.437914 -27.323628) (xy 130.462782 -27.290268) (xy 130.469143 -27.28108) (xy 130.473968 -27.259284)
			(xy 130.469129 -27.237491) (xy 130.462782 -27.228292) (xy 130.437901 -27.194943) (xy 130.394789 -27.123772)
			(xy 130.359664 -27.04834) (xy 130.332942 -26.969537) (xy 130.314939 -26.888299) (xy 130.305869 -26.805585)
			(xy 130.305302 -26.76398) (xy 130.305801 -26.725155) (xy 130.313687 -26.647905) (xy 130.329376 -26.571856)
			(xy 130.352705 -26.497793) (xy 130.383434 -26.426481) (xy 130.421245 -26.358658) (xy 130.465746 -26.295024)
			(xy 130.516479 -26.236237) (xy 130.572918 -26.182906) (xy 130.63448 -26.13558) (xy 130.667252 -26.114756)
			(xy 130.676537 -26.108282) (xy 130.688814 -26.089308) (xy 130.690874 -26.07818) (xy 130.694998 -26.051051)
			(xy 130.710017 -25.998274) (xy 130.732441 -25.948192) (xy 130.761807 -25.901838) (xy 130.79751 -25.860169)
			(xy 130.838813 -25.824042) (xy 130.884865 -25.794205) (xy 130.934715 -25.771271) (xy 130.987336 -25.755714)
			(xy 131.041644 -25.747854) (xy 131.096516 -25.747854) (xy 131.150824 -25.755714) (xy 131.203445 -25.771271)
			(xy 131.253295 -25.794205) (xy 131.299347 -25.824042) (xy 131.34065 -25.860169) (xy 131.376353 -25.901838)
			(xy 131.405719 -25.948192) (xy 131.428143 -25.998274) (xy 131.443162 -26.051051) (xy 131.447286 -26.07818)
			(xy 131.449384 -26.089293) (xy 131.461644 -26.108268) (xy 131.470908 -26.114756) (xy 131.503657 -26.135617)
			(xy 131.565225 -26.182934) (xy 131.621671 -26.236258) (xy 131.672409 -26.295038) (xy 131.716916 -26.358667)
			(xy 131.754732 -26.426487) (xy 131.785465 -26.497797) (xy 131.808797 -26.571858) (xy 131.824489 -26.647906)
			(xy 131.832376 -26.725155) (xy 131.832858 -26.76398) (xy 131.832807 -26.76779) (xy 141.239748 -26.76779)
			(xy 141.240347 -26.7251) (xy 141.249911 -26.640257) (xy 141.268874 -26.557009) (xy 141.296999 -26.476394)
			(xy 141.333936 -26.399417) (xy 141.35608 -26.362914) (xy 141.360784 -26.354657) (xy 141.36429 -26.335991)
			(xy 141.360778 -26.317327) (xy 141.35608 -26.309066) (xy 141.333922 -26.272571) (xy 141.296978 -26.195596)
			(xy 141.268853 -26.114979) (xy 141.249898 -26.031727) (xy 141.240351 -25.946881) (xy 141.239748 -25.90419)
			(xy 141.240218 -25.864188) (xy 141.248582 -25.784621) (xy 141.265217 -25.706365) (xy 141.289941 -25.630276)
			(xy 141.322484 -25.557188) (xy 141.362488 -25.487903) (xy 141.409515 -25.423178) (xy 141.46305 -25.363724)
			(xy 141.522506 -25.310192) (xy 141.587233 -25.263168) (xy 141.65652 -25.223167) (xy 141.729609 -25.190628)
			(xy 141.805699 -25.165908) (xy 141.883957 -25.149276) (xy 141.963524 -25.140916) (xy 142.003526 -25.140412)
			(xy 142.004034 -25.140412) (xy 142.040445 -25.140846) (xy 142.112937 -25.147779) (xy 142.184441 -25.161578)
			(xy 142.254306 -25.182119) (xy 142.28826 -25.195276) (xy 142.296243 -25.198111) (xy 142.313148 -25.198984)
			(xy 142.329415 -25.194298) (xy 142.33652 -25.189688) (xy 142.360823 -25.173138) (xy 142.413459 -25.146939)
			(xy 142.469492 -25.129126) (xy 142.527594 -25.120119) (xy 142.556992 -25.119584) (xy 142.584265 -25.120009)
			(xy 142.638256 -25.127771) (xy 142.690592 -25.143139) (xy 142.740208 -25.165799) (xy 142.786094 -25.19529)
			(xy 142.827315 -25.231012) (xy 142.863033 -25.272237) (xy 142.892519 -25.318125) (xy 142.915174 -25.367744)
			(xy 142.930537 -25.420082) (xy 142.938294 -25.474073) (xy 142.938754 -25.501346) (xy 142.938161 -25.530911)
			(xy 142.929033 -25.589334) (xy 142.911016 -25.645653) (xy 142.88454 -25.698526) (xy 142.850238 -25.746691)
			(xy 142.808927 -25.788999) (xy 142.785592 -25.807162) (xy 142.779066 -25.812543) (xy 142.769642 -25.826573)
			(xy 142.765283 -25.842903) (xy 142.765526 -25.851358) (xy 142.767304 -25.903936) (xy 142.767304 -25.90419)
			(xy 142.766688 -25.946879) (xy 142.757127 -26.031722) (xy 142.738167 -26.114969) (xy 142.710046 -26.195584)
			(xy 142.673113 -26.272562) (xy 142.650972 -26.309066) (xy 142.646288 -26.317332) (xy 142.642779 -26.335991)
			(xy 142.646281 -26.354652) (xy 142.650972 -26.362914) (xy 142.673117 -26.399417) (xy 142.710064 -26.47639)
			(xy 142.738192 -26.557004) (xy 142.755942 -26.634948) (xy 175.442372 -26.634948) (xy 175.442817 -26.593237)
			(xy 175.450618 -26.510181) (xy 175.466165 -26.428221) (xy 175.489321 -26.348077) (xy 175.519883 -26.270455)
			(xy 175.557582 -26.196038) (xy 175.602086 -26.125479) (xy 175.653004 -26.059399) (xy 175.709888 -25.99838)
			(xy 175.772239 -25.942957) (xy 175.805592 -25.917906) (xy 175.814178 -25.911009) (xy 175.82483 -25.891756)
			(xy 175.826166 -25.880822) (xy 175.829855 -25.839448) (xy 175.843941 -25.757582) (xy 175.865598 -25.677385)
			(xy 175.894637 -25.599556) (xy 175.930804 -25.524774) (xy 175.973785 -25.453688) (xy 176.023205 -25.386918)
			(xy 176.078634 -25.325046) (xy 176.13959 -25.268611) (xy 176.205541 -25.218103) (xy 176.275913 -25.173964)
			(xy 176.350094 -25.136576) (xy 176.427436 -25.106267) (xy 176.507267 -25.083299) (xy 176.588892 -25.067873)
			(xy 176.671599 -25.060123) (xy 176.713134 -25.05964) (xy 176.713642 -25.05964) (xy 176.757406 -25.060139)
			(xy 176.844513 -25.068717) (xy 176.930355 -25.085818) (xy 177.0141 -25.111273) (xy 177.094937 -25.144838)
			(xy 177.133758 -25.16505) (xy 177.145111 -25.170377) (xy 177.170157 -25.170377) (xy 177.18151 -25.16505)
			(xy 177.22038 -25.144826) (xy 177.301322 -25.111257) (xy 177.38517 -25.085803) (xy 177.471113 -25.068709)
			(xy 177.55832 -25.060143) (xy 177.602134 -25.05964) (xy 177.645949 -25.060116) (xy 177.733161 -25.068665)
			(xy 177.819109 -25.085756) (xy 177.902957 -25.111222) (xy 177.983891 -25.144816) (xy 178.022758 -25.16505)
			(xy 178.034111 -25.170377) (xy 178.059157 -25.170377) (xy 178.07051 -25.16505) (xy 178.10938 -25.144826)
			(xy 178.190322 -25.111257) (xy 178.27417 -25.085803) (xy 178.360113 -25.068709) (xy 178.44732 -25.060143)
			(xy 178.491134 -25.05964) (xy 178.541288 -25.060291) (xy 178.640969 -25.071493) (xy 178.690016 -25.081992)
			(xy 178.700529 -25.083816) (xy 178.72144 -25.079687) (xy 178.7389 -25.067462) (xy 178.74488 -25.058624)
			(xy 178.766746 -25.023211) (xy 178.816155 -24.956227) (xy 178.871604 -24.894151) (xy 178.932608 -24.837525)
			(xy 178.998633 -24.786843) (xy 179.069104 -24.742549) (xy 179.143403 -24.705031) (xy 179.220882 -24.674615)
			(xy 179.300862 -24.651569) (xy 179.382645 -24.636093) (xy 179.465517 -24.628322) (xy 179.507134 -24.62784)
			(xy 179.549484 -24.628249) (xy 179.633799 -24.636303) (xy 179.716968 -24.652336) (xy 179.798236 -24.676201)
			(xy 179.876867 -24.707683) (xy 179.95215 -24.746496) (xy 180.023403 -24.79229) (xy 180.08998 -24.844649)
			(xy 180.151278 -24.9031) (xy 180.206744 -24.967112) (xy 180.255873 -25.036107) (xy 180.298222 -25.10946)
			(xy 180.333407 -25.186506) (xy 180.361109 -25.266547) (xy 180.381077 -25.348859) (xy 180.39313 -25.432696)
			(xy 180.397161 -25.5173) (xy 180.39313 -25.601904) (xy 180.381077 -25.685741) (xy 180.361109 -25.768053)
			(xy 180.333407 -25.848094) (xy 180.298222 -25.92514) (xy 180.255873 -25.998493) (xy 180.206744 -26.067488)
			(xy 180.151278 -26.1315) (xy 180.08998 -26.189951) (xy 180.023403 -26.24231) (xy 179.95215 -26.288104)
			(xy 179.876867 -26.326917) (xy 179.798236 -26.358399) (xy 179.716968 -26.382264) (xy 179.633799 -26.398297)
			(xy 179.549484 -26.406351) (xy 179.507134 -26.406856) (xy 179.505864 -26.406856) (xy 179.456029 -26.406131)
			(xy 179.35699 -26.394927) (xy 179.308252 -26.384504) (xy 179.297742 -26.382653) (xy 179.276827 -26.386794)
			(xy 179.259367 -26.39903) (xy 179.253388 -26.407872) (xy 179.230217 -26.445289) (xy 179.177598 -26.515842)
			(xy 179.118275 -26.58086) (xy 179.052827 -26.639708) (xy 179.017676 -26.66619) (xy 179.009104 -26.673102)
			(xy 178.998441 -26.692343) (xy 178.997102 -26.703274) (xy 178.993441 -26.744651) (xy 178.979354 -26.826519)
			(xy 178.957697 -26.906717) (xy 178.928657 -26.984547) (xy 178.892489 -27.059331) (xy 178.849506 -27.130418)
			(xy 178.835198 -27.149749) (xy 180.032656 -27.149749) (xy 180.032656 -27.065027) (xy 180.040709 -26.98069)
			(xy 180.056743 -26.8975) (xy 180.080611 -26.81621) (xy 180.112099 -26.737558) (xy 180.150921 -26.662255)
			(xy 180.196724 -26.590983) (xy 180.249095 -26.524387) (xy 180.30756 -26.463072) (xy 180.371588 -26.407591)
			(xy 180.4406 -26.358448) (xy 180.51397 -26.316088) (xy 180.591035 -26.280893) (xy 180.671097 -26.253184)
			(xy 180.75343 -26.23321) (xy 180.837289 -26.221153) (xy 180.921914 -26.217122) (xy 181.006539 -26.221153)
			(xy 181.090398 -26.23321) (xy 181.172731 -26.253184) (xy 181.252793 -26.280893) (xy 181.329858 -26.316088)
			(xy 181.403228 -26.358448) (xy 181.47224 -26.407591) (xy 181.536268 -26.463072) (xy 181.594733 -26.524387)
			(xy 181.647104 -26.590983) (xy 181.692907 -26.662255) (xy 181.731729 -26.737558) (xy 181.763217 -26.81621)
			(xy 181.787085 -26.8975) (xy 181.803119 -26.98069) (xy 181.811172 -27.065027) (xy 181.811676 -27.107388)
			(xy 181.811172 -27.149749) (xy 181.803119 -27.234086) (xy 181.787085 -27.317276) (xy 181.763217 -27.398566)
			(xy 181.731729 -27.477218) (xy 181.692907 -27.552521) (xy 181.647104 -27.623793) (xy 181.594733 -27.690389)
			(xy 181.536268 -27.751704) (xy 181.47224 -27.807185) (xy 181.403228 -27.856328) (xy 181.329858 -27.898688)
			(xy 181.252793 -27.933883) (xy 181.172731 -27.961592) (xy 181.090398 -27.981566) (xy 181.006539 -27.993623)
			(xy 180.921914 -27.997655) (xy 180.837289 -27.993623) (xy 180.75343 -27.981566) (xy 180.671097 -27.961592)
			(xy 180.591035 -27.933883) (xy 180.51397 -27.898688) (xy 180.4406 -27.856328) (xy 180.371588 -27.807185)
			(xy 180.30756 -27.751704) (xy 180.249095 -27.690389) (xy 180.196724 -27.623793) (xy 180.150921 -27.552521)
			(xy 180.112099 -27.477218) (xy 180.080611 -27.398566) (xy 180.056743 -27.317276) (xy 180.040709 -27.234086)
			(xy 180.032656 -27.149749) (xy 178.835198 -27.149749) (xy 178.800084 -27.197189) (xy 178.744653 -27.259061)
			(xy 178.683695 -27.315497) (xy 178.617742 -27.366004) (xy 178.547367 -27.410143) (xy 178.473184 -27.447529)
			(xy 178.395839 -27.477837) (xy 178.316006 -27.500803) (xy 178.234379 -27.516227) (xy 178.15167 -27.523974)
			(xy 178.110134 -27.524456) (xy 178.109626 -27.524456) (xy 178.065862 -27.523929) (xy 177.978756 -27.515357)
			(xy 177.892915 -27.498263) (xy 177.809169 -27.472814) (xy 177.728331 -27.439255) (xy 177.68951 -27.419046)
			(xy 177.678157 -27.413719) (xy 177.653111 -27.413719) (xy 177.641758 -27.419046) (xy 177.602894 -27.439282)
			(xy 177.521951 -27.472849) (xy 177.438101 -27.498301) (xy 177.352156 -27.515391) (xy 177.264948 -27.523955)
			(xy 177.221134 -27.524456) (xy 177.177318 -27.523994) (xy 177.090106 -27.515442) (xy 177.004158 -27.498348)
			(xy 176.920311 -27.472879) (xy 176.839376 -27.439281) (xy 176.80051 -27.419046) (xy 176.789157 -27.413719)
			(xy 176.764111 -27.413719) (xy 176.752758 -27.419046) (xy 176.713921 -27.439222) (xy 176.633081 -27.472767)
			(xy 176.549339 -27.498216) (xy 176.463504 -27.515325) (xy 176.376404 -27.523927) (xy 176.332642 -27.524456)
			(xy 176.332134 -27.524456) (xy 176.291028 -27.523955) (xy 176.209165 -27.516374) (xy 176.128351 -27.501273)
			(xy 176.049275 -27.47878) (xy 175.972611 -27.449089) (xy 175.899013 -27.412452) (xy 175.829109 -27.369181)
			(xy 175.763495 -27.319646) (xy 175.702731 -27.264268) (xy 175.647335 -27.203522) (xy 175.597779 -27.137923)
			(xy 175.554486 -27.068033) (xy 175.517825 -26.994447) (xy 175.488109 -26.917792) (xy 175.465592 -26.838723)
			(xy 175.450465 -26.757914) (xy 175.442858 -26.676054) (xy 175.442372 -26.634948) (xy 142.755942 -26.634948)
			(xy 142.75715 -26.640254) (xy 142.7667 -26.7251) (xy 142.767304 -26.76779) (xy 142.767243 -26.781773)
			(xy 142.766226 -26.80972) (xy 142.765272 -26.82367) (xy 142.764947 -26.832178) (xy 142.769236 -26.848641)
			(xy 142.778724 -26.862761) (xy 142.785338 -26.86812) (xy 142.808723 -26.886274) (xy 142.850119 -26.928594)
			(xy 142.884492 -26.976793) (xy 142.911018 -27.029717) (xy 142.929064 -27.086099) (xy 142.938197 -27.14459)
			(xy 142.938754 -27.17419) (xy 142.938289 -27.201461) (xy 142.930528 -27.255448) (xy 142.915163 -27.307782)
			(xy 142.892506 -27.357395) (xy 142.863018 -27.403279) (xy 142.827301 -27.4445) (xy 142.786081 -27.480217)
			(xy 142.740197 -27.509705) (xy 142.690583 -27.532362) (xy 142.63825 -27.547728) (xy 142.584263 -27.555489)
			(xy 142.556992 -27.555952) (xy 142.527164 -27.555371) (xy 142.468235 -27.546096) (xy 142.411468 -27.527758)
			(xy 142.35825 -27.500804) (xy 142.333726 -27.483816) (xy 142.326655 -27.479026) (xy 142.310312 -27.474099)
			(xy 142.293258 -27.474852) (xy 142.285212 -27.47772) (xy 142.251526 -27.490621) (xy 142.182266 -27.510792)
			(xy 142.111411 -27.524342) (xy 142.039595 -27.531148) (xy 142.003526 -27.531568) (xy 141.963525 -27.531048)
			(xy 141.88396 -27.522688) (xy 141.805705 -27.506056) (xy 141.729618 -27.481336) (xy 141.656531 -27.448798)
			(xy 141.587246 -27.408798) (xy 141.522522 -27.361775) (xy 141.463068 -27.308243) (xy 141.409536 -27.24879)
			(xy 141.362511 -27.184067) (xy 141.322509 -27.114783) (xy 141.28997 -27.041697) (xy 141.265248 -26.96561)
			(xy 141.248615 -26.887356) (xy 141.240253 -26.807791) (xy 141.239748 -26.76779) (xy 131.832807 -26.76779)
			(xy 131.832301 -26.805585) (xy 131.823244 -26.888302) (xy 131.805244 -26.969543) (xy 131.778517 -27.048345)
			(xy 131.743379 -27.123773) (xy 131.700246 -27.194932) (xy 131.675378 -27.228292) (xy 131.669056 -27.237502)
			(xy 131.664224 -27.259284) (xy 131.669043 -27.281068) (xy 131.675378 -27.290268) (xy 131.700235 -27.323635)
			(xy 131.743351 -27.394801) (xy 131.778481 -27.470229) (xy 131.805207 -27.549028) (xy 131.823214 -27.630264)
			(xy 131.832289 -27.712976) (xy 131.832858 -27.75458) (xy 131.832379 -27.793406) (xy 131.824487 -27.870655)
			(xy 131.808794 -27.946704) (xy 131.785461 -28.020766) (xy 131.754729 -28.092077) (xy 131.716917 -28.1599)
			(xy 131.672414 -28.223533) (xy 131.621681 -28.28232) (xy 131.565242 -28.335652) (xy 131.50368 -28.382979)
			(xy 131.470908 -28.403804) (xy 131.461593 -28.410241) (xy 131.449333 -28.429243) (xy 131.447286 -28.44038)
			(xy 131.443162 -28.467509) (xy 131.428143 -28.520286) (xy 131.405719 -28.570368) (xy 131.376353 -28.616722)
			(xy 131.34065 -28.658391) (xy 131.299347 -28.694518) (xy 131.253295 -28.724355) (xy 131.203445 -28.747289)
			(xy 131.150824 -28.762846) (xy 131.096516 -28.770706) (xy 131.041644 -28.770706) (xy 130.987336 -28.762846)
			(xy 130.934715 -28.747289) (xy 130.884865 -28.724355) (xy 130.838813 -28.694518) (xy 130.79751 -28.658391)
			(xy 130.761807 -28.616722) (xy 130.732441 -28.570368) (xy 130.710017 -28.520286) (xy 130.694998 -28.467509)
			(xy 130.690874 -28.44038) (xy 130.688761 -28.42927) (xy 130.676513 -28.410293) (xy 130.667252 -28.403804)
			(xy 130.634476 -28.382985) (xy 130.572909 -28.335663) (xy 130.516465 -28.282333) (xy 130.465729 -28.223547)
			(xy 130.421224 -28.159913) (xy 130.383412 -28.092089) (xy 130.352682 -28.020775) (xy 130.329353 -27.946709)
			(xy 130.313665 -27.870658) (xy 130.305782 -27.793406) (xy 130.305302 -27.75458) (xy 64.905217 -27.75458)
			(xy 64.965111 -27.798302) (xy 65.023573 -27.851021) (xy 65.076293 -27.909483) (xy 65.122709 -27.973065)
			(xy 65.162327 -28.041091) (xy 65.194727 -28.112836) (xy 65.219562 -28.187538) (xy 65.236568 -28.264401)
			(xy 65.245565 -28.342607) (xy 65.246504 -28.38196) (xy 65.246504 -28.382214) (xy 65.247086 -28.392076)
			(xy 65.254807 -28.410243) (xy 65.26149 -28.41752) (xy 66.511424 -29.667454) (xy 66.518827 -29.674291)
			(xy 66.537424 -29.682014) (xy 66.547492 -29.68244) (xy 100.466398 -29.68244) (xy 100.477293 -29.681941)
			(xy 100.497163 -29.673001) (xy 100.504752 -29.665168) (xy 100.56241 -29.599382) (xy 100.56876 -29.578554)
			(xy 100.567236 -29.567886) (xy 100.565793 -29.555682) (xy 100.564265 -29.531153) (xy 100.564188 -29.518864)
			(xy 100.564188 -29.51861) (xy 100.564657 -29.491321) (xy 100.572423 -29.437298) (xy 100.587798 -29.38493)
			(xy 100.61047 -29.335284) (xy 100.639977 -29.28937) (xy 100.675718 -29.248122) (xy 100.716965 -29.21238)
			(xy 100.762879 -29.182873) (xy 100.812525 -29.160201) (xy 100.864892 -29.144824) (xy 100.918915 -29.137057)
			(xy 100.946204 -29.136594) (xy 100.961574 -29.136723) (xy 100.992218 -29.13914) (xy 101.007418 -29.14142)
			(xy 101.017368 -29.142597) (xy 101.036861 -29.13804) (xy 101.053109 -29.126347) (xy 101.058726 -29.118052)
			(xy 101.062028 -29.112972) (xy 101.066703 -29.104697) (xy 101.070243 -29.086041) (xy 101.066733 -29.06738)
			(xy 101.062028 -29.059124) (xy 101.039958 -29.022679) (xy 101.003136 -28.945843) (xy 100.975118 -28.865377)
			(xy 100.956254 -28.782288) (xy 100.946779 -28.697612) (xy 100.946204 -28.65501) (xy 100.946693 -28.616391)
			(xy 100.954507 -28.539548) (xy 100.970055 -28.46389) (xy 100.993178 -28.390193) (xy 101.023637 -28.319214)
			(xy 101.061122 -28.25168) (xy 101.105246 -28.188286) (xy 101.155557 -28.12968) (xy 101.211539 -28.076465)
			(xy 101.272618 -28.029186) (xy 101.338166 -27.98833) (xy 101.407512 -27.954314) (xy 101.479943 -27.927489)
			(xy 101.554716 -27.908129) (xy 101.631064 -27.896433) (xy 101.708204 -27.892521) (xy 101.785344 -27.896433)
			(xy 101.861692 -27.908129) (xy 101.936465 -27.927489) (xy 102.008896 -27.954314) (xy 102.078242 -27.98833)
			(xy 102.14379 -28.029186) (xy 102.204869 -28.076465) (xy 102.260851 -28.12968) (xy 102.311162 -28.188286)
			(xy 102.355286 -28.25168) (xy 102.392771 -28.319214) (xy 102.42323 -28.390193) (xy 102.446353 -28.46389)
			(xy 102.461901 -28.539548) (xy 102.469715 -28.616391) (xy 102.470204 -28.65501) (xy 102.469602 -28.697611)
			(xy 102.460116 -28.782282) (xy 102.441253 -28.865369) (xy 102.413247 -28.945836) (xy 102.376448 -29.02268)
			(xy 102.35438 -29.059124) (xy 102.349626 -29.067361) (xy 102.346112 -29.086041) (xy 102.349656 -29.104716)
			(xy 102.35438 -29.112972) (xy 102.376649 -29.149509) (xy 102.413779 -29.226602) (xy 102.442039 -29.307369)
			(xy 102.461076 -29.390794) (xy 102.470648 -29.475826) (xy 102.47122 -29.51861) (xy 102.47122 -29.519118)
			(xy 102.471151 -29.532974) (xy 102.470135 -29.560667) (xy 102.469188 -29.57449) (xy 102.468426 -29.584904)
			(xy 102.475284 -29.605224) (xy 102.532434 -29.666184) (xy 102.539938 -29.673472) (xy 102.559073 -29.68187)
			(xy 102.569518 -29.68244) (xy 121.488962 -29.68244) (xy 121.493646 -29.682274) (xy 121.502845 -29.680486)
			(xy 121.50725 -29.678884) (xy 121.540384 -29.666454) (xy 121.608439 -29.647034) (xy 121.678 -29.633999)
			(xy 121.74847 -29.627461) (xy 121.783856 -29.627068) (xy 121.784364 -29.627068) (xy 121.819751 -29.627448)
			(xy 121.890224 -29.633972) (xy 121.959788 -29.647004) (xy 122.027844 -29.666431) (xy 122.06097 -29.678884)
			(xy 122.065365 -29.680523) (xy 122.074569 -29.682317) (xy 122.079258 -29.68244) (xy 135.138414 -29.68244)
			(xy 135.150953 -29.681743) (xy 135.173061 -29.669894) (xy 135.180578 -29.659834) (xy 135.23468 -29.578554)
			(xy 135.236966 -29.553154) (xy 135.231886 -29.541216) (xy 135.217333 -29.505814) (xy 135.1946 -29.432719)
			(xy 135.17932 -29.357711) (xy 135.171647 -29.281548) (xy 135.17118 -29.243274) (xy 135.17118 -29.242512)
			(xy 135.17174 -29.201073) (xy 135.180776 -29.118689) (xy 135.198698 -29.037772) (xy 135.225295 -28.959278)
			(xy 135.260253 -28.884134) (xy 135.303159 -28.813227) (xy 135.327898 -28.779978) (xy 135.334286 -28.770792)
			(xy 135.339055 -28.748953) (xy 135.334075 -28.727161) (xy 135.327644 -28.718002) (xy 135.302658 -28.684572)
			(xy 135.259316 -28.613246) (xy 135.224005 -28.53762) (xy 135.197146 -28.458597) (xy 135.17906 -28.377117)
			(xy 135.169962 -28.294151) (xy 135.169402 -28.25242) (xy 135.169853 -28.213594) (xy 135.177745 -28.136343)
			(xy 135.19344 -28.060292) (xy 135.216775 -27.986228) (xy 135.247509 -27.914916) (xy 135.285325 -27.847093)
			(xy 135.329831 -27.78346) (xy 135.380568 -27.724674) (xy 135.437012 -27.671344) (xy 135.498578 -27.624019)
			(xy 135.531352 -27.603196) (xy 135.540659 -27.596749) (xy 135.552925 -27.577755) (xy 135.554974 -27.56662)
			(xy 135.559098 -27.539491) (xy 135.574117 -27.486714) (xy 135.596541 -27.436632) (xy 135.625907 -27.390278)
			(xy 135.66161 -27.348609) (xy 135.702913 -27.312482) (xy 135.748965 -27.282645) (xy 135.798815 -27.259711)
			(xy 135.851436 -27.244154) (xy 135.905744 -27.236294) (xy 135.960616 -27.236294) (xy 136.014924 -27.244154)
			(xy 136.067545 -27.259711) (xy 136.117395 -27.282645) (xy 136.163447 -27.312482) (xy 136.20475 -27.348609)
			(xy 136.240453 -27.390278) (xy 136.269819 -27.436632) (xy 136.292243 -27.486714) (xy 136.307262 -27.539491)
			(xy 136.311386 -27.56662) (xy 136.313514 -27.577726) (xy 136.325752 -27.596704) (xy 136.335008 -27.603196)
			(xy 136.367775 -27.62403) (xy 136.429344 -27.671349) (xy 136.485788 -27.724676) (xy 136.536526 -27.78346)
			(xy 136.581032 -27.847092) (xy 136.618846 -27.914915) (xy 136.649576 -27.986228) (xy 136.672906 -28.060292)
			(xy 136.688594 -28.136343) (xy 136.696478 -28.213594) (xy 136.696958 -28.25242) (xy 136.696407 -28.294152)
			(xy 136.687308 -28.377118) (xy 136.669221 -28.458598) (xy 136.642361 -28.537622) (xy 136.607048 -28.613247)
			(xy 136.563703 -28.684573) (xy 136.538716 -28.718002) (xy 136.532387 -28.727202) (xy 136.527467 -28.748953)
			(xy 136.532179 -28.77075) (xy 136.538462 -28.779978) (xy 136.563182 -28.813239) (xy 136.606075 -28.88415)
			(xy 136.641026 -28.959294) (xy 136.667623 -29.037784) (xy 136.671001 -29.053028) (xy 139.446508 -29.053028)
			(xy 139.447064 -29.023199) (xy 139.456347 -28.964269) (xy 139.474693 -28.907503) (xy 139.501653 -28.854285)
			(xy 139.518644 -28.829762) (xy 139.523407 -28.822675) (xy 139.528346 -28.806341) (xy 139.527603 -28.789292)
			(xy 139.52474 -28.781248) (xy 139.511818 -28.74757) (xy 139.491652 -28.678306) (xy 139.478109 -28.60745)
			(xy 139.471309 -28.535632) (xy 139.470892 -28.499562) (xy 139.471409 -28.459562) (xy 139.479775 -28.38)
			(xy 139.496411 -28.301748) (xy 139.521135 -28.225664) (xy 139.553676 -28.152581) (xy 139.593678 -28.0833)
			(xy 139.640702 -28.018579) (xy 139.694233 -27.959127) (xy 139.753685 -27.905597) (xy 139.818406 -27.858573)
			(xy 139.887688 -27.818572) (xy 139.960772 -27.786032) (xy 140.036856 -27.761309) (xy 140.115108 -27.744674)
			(xy 140.19467 -27.736309) (xy 140.23467 -27.735784) (xy 140.277359 -27.736411) (xy 140.362201 -27.74597)
			(xy 140.445448 -27.764927) (xy 140.526064 -27.793046) (xy 140.603042 -27.829976) (xy 140.639546 -27.852116)
			(xy 140.647807 -27.856812) (xy 140.66647 -27.86032) (xy 140.685133 -27.856812) (xy 140.693394 -27.852116)
			(xy 140.729901 -27.829978) (xy 140.806873 -27.79303) (xy 140.887486 -27.7649) (xy 140.970735 -27.745941)
			(xy 141.05558 -27.736389) (xy 141.09827 -27.735784) (xy 141.138269 -27.736374) (xy 141.217828 -27.744733)
			(xy 141.296078 -27.761362) (xy 141.372161 -27.786079) (xy 141.445243 -27.818614) (xy 141.514525 -27.85861)
			(xy 141.579246 -27.905628) (xy 141.638698 -27.959154) (xy 141.692229 -28.018601) (xy 141.739253 -28.083318)
			(xy 141.779255 -28.152596) (xy 141.811796 -28.225676) (xy 141.836521 -28.301756) (xy 141.853157 -28.380005)
			(xy 141.861523 -28.459563) (xy 141.862048 -28.499562) (xy 141.862048 -28.50007) (xy 141.861621 -28.536481)
			(xy 141.854686 -28.608973) (xy 141.840884 -28.680477) (xy 141.820342 -28.750342) (xy 141.807184 -28.784296)
			(xy 141.804312 -28.792269) (xy 141.803449 -28.809183) (xy 141.808151 -28.825453) (xy 141.812772 -28.832556)
			(xy 141.829332 -28.856852) (xy 141.85553 -28.90949) (xy 141.873341 -28.965525) (xy 141.882343 -29.023629)
			(xy 141.882876 -29.053028) (xy 141.882402 -29.080297) (xy 141.874637 -29.134281) (xy 141.859268 -29.18661)
			(xy 141.83661 -29.236219) (xy 141.807122 -29.282099) (xy 141.771406 -29.323316) (xy 141.730188 -29.359031)
			(xy 141.684307 -29.388517) (xy 141.634696 -29.411173) (xy 141.582367 -29.42654) (xy 141.528383 -29.434303)
			(xy 141.501114 -29.43479) (xy 141.471546 -29.434252) (xy 141.41312 -29.425115) (xy 141.356798 -29.407089)
			(xy 141.303925 -29.380603) (xy 141.255762 -29.34629) (xy 141.213458 -29.304969) (xy 141.195298 -29.281628)
			(xy 141.187038 -29.271911) (xy 141.163853 -29.261372) (xy 141.151102 -29.261562) (xy 141.098524 -29.26334)
			(xy 141.09827 -29.26334) (xy 141.05558 -29.262752) (xy 140.970736 -29.253186) (xy 140.887488 -29.234221)
			(xy 140.806873 -29.206093) (xy 140.729897 -29.169153) (xy 140.693394 -29.147008) (xy 140.685133 -29.142312)
			(xy 140.66647 -29.138804) (xy 140.647807 -29.142312) (xy 140.639546 -29.147008) (xy 140.603055 -29.169173)
			(xy 140.526079 -29.206116) (xy 140.445461 -29.23424) (xy 140.362208 -29.253193) (xy 140.277361 -29.262738)
			(xy 140.23467 -29.26334) (xy 140.220687 -29.263281) (xy 140.19274 -29.262263) (xy 140.17879 -29.261308)
			(xy 140.170281 -29.26094) (xy 140.153814 -29.265245) (xy 140.139695 -29.274751) (xy 140.13434 -29.281374)
			(xy 140.116192 -29.304765) (xy 140.073873 -29.346163) (xy 140.025673 -29.380537) (xy 139.972748 -29.407064)
			(xy 139.916363 -29.425107) (xy 139.857871 -29.434236) (xy 139.82827 -29.43479) (xy 139.801001 -29.434304)
			(xy 139.747019 -29.426539) (xy 139.694691 -29.411171) (xy 139.645083 -29.388513) (xy 139.599203 -29.359027)
			(xy 139.557987 -29.323312) (xy 139.522272 -29.282095) (xy 139.492786 -29.236215) (xy 139.470129 -29.186607)
			(xy 139.454761 -29.134279) (xy 139.446996 -29.080297) (xy 139.446508 -29.053028) (xy 136.671001 -29.053028)
			(xy 136.685552 -29.118696) (xy 136.694602 -29.201075) (xy 136.69518 -29.242512) (xy 136.69518 -29.243274)
			(xy 136.694686 -29.281546) (xy 136.686994 -29.357703) (xy 136.671714 -29.432708) (xy 136.649001 -29.505805)
			(xy 136.634474 -29.541216) (xy 136.630152 -29.553113) (xy 136.632409 -29.578292) (xy 136.638792 -29.589222)
			(xy 136.685782 -29.659834) (xy 136.693293 -29.669909) (xy 136.715399 -29.681784) (xy 136.727946 -29.68244)
			(xy 144.898364 -29.68244) (xy 144.90446 -29.680916) (xy 144.927504 -29.675447) (xy 144.974504 -29.669589)
			(xy 144.998186 -29.669232) (xy 144.998694 -29.669232) (xy 145.022376 -29.669587) (xy 145.069376 -29.675445)
			(xy 145.09242 -29.680916) (xy 145.098516 -29.68244) (xy 156.526738 -29.68244) (xy 156.531555 -29.682354)
			(xy 156.54102 -29.680567) (xy 156.545534 -29.678884) (xy 156.578906 -29.666207) (xy 156.647503 -29.646423)
			(xy 156.717649 -29.633137) (xy 156.78873 -29.626467) (xy 156.824426 -29.626052) (xy 156.824934 -29.626052)
			(xy 156.860631 -29.626452) (xy 156.931711 -29.633129) (xy 157.001856 -29.646421) (xy 157.070451 -29.666213)
			(xy 157.103826 -29.678884) (xy 157.108355 -29.680515) (xy 157.11781 -29.682313) (xy 157.122622 -29.68244)
			(xy 171.321476 -29.68244) (xy 171.333438 -29.681726) (xy 171.354766 -29.670872) (xy 171.36237 -29.661612)
			(xy 171.41825 -29.585666) (xy 171.42206 -29.562044) (xy 171.41825 -29.550106) (xy 171.406903 -29.512682)
			(xy 171.390976 -29.436115) (xy 171.38295 -29.358323) (xy 171.382436 -29.31922) (xy 171.382436 -29.318712)
			(xy 171.382925 -29.280041) (xy 171.39075 -29.203096) (xy 171.406319 -29.127337) (xy 171.429472 -29.053542)
			(xy 171.459972 -28.982468) (xy 171.497507 -28.914845) (xy 171.54169 -28.851365) (xy 171.592068 -28.792681)
			(xy 171.648125 -28.739395) (xy 171.709285 -28.692054) (xy 171.774921 -28.651143) (xy 171.844359 -28.617082)
			(xy 171.916886 -28.59022) (xy 171.991759 -28.570835) (xy 172.068209 -28.559123) (xy 172.145452 -28.555206)
			(xy 172.222695 -28.559123) (xy 172.299145 -28.570835) (xy 172.374018 -28.59022) (xy 172.446545 -28.617082)
			(xy 172.515983 -28.651143) (xy 172.581619 -28.692054) (xy 172.642779 -28.739395) (xy 172.698836 -28.792681)
			(xy 172.749214 -28.851365) (xy 172.793397 -28.914845) (xy 172.830932 -28.982468) (xy 172.861432 -29.053542)
			(xy 172.884585 -29.127337) (xy 172.900154 -29.203096) (xy 172.907979 -29.280041) (xy 172.908468 -29.318712)
			(xy 172.908468 -29.318966) (xy 172.907987 -29.358113) (xy 172.899989 -29.435997) (xy 172.884041 -29.512649)
			(xy 172.872654 -29.550106) (xy 172.869578 -29.561748) (xy 172.873438 -29.585486) (xy 172.88002 -29.595572)
			(xy 172.92828 -29.661612) (xy 172.935912 -29.670949) (xy 172.957386 -29.681834) (xy 172.969428 -29.68244)
			(xy 174.12208 -29.68244) (xy 174.12823 -29.682243) (xy 174.14017 -29.679292) (xy 174.145702 -29.676598)
			(xy 174.178371 -29.660093) (xy 174.246245 -29.632686) (xy 174.316431 -29.611905) (xy 174.388286 -29.597943)
			(xy 174.461147 -29.590926) (xy 174.497746 -29.590492) (xy 174.498254 -29.590492) (xy 174.534854 -29.590917)
			(xy 174.607718 -29.597921) (xy 174.679575 -29.61188) (xy 174.749762 -29.632664) (xy 174.817633 -29.660083)
			(xy 174.850298 -29.676598) (xy 174.855823 -29.679312) (xy 174.867767 -29.682269) (xy 174.87392 -29.68244)
			(xy 177.249328 -29.68244) (xy 177.2594 -29.68284) (xy 177.277998 -29.690577) (xy 177.285396 -29.697426)
			(xy 177.72177 -30.1338) (xy 197.595716 -30.1338) (xy 197.599747 -30.049172) (xy 197.611805 -29.965311)
			(xy 197.631779 -29.882976) (xy 197.65949 -29.802912) (xy 197.694686 -29.725844) (xy 197.737048 -29.652472)
			(xy 197.786193 -29.583458) (xy 197.841676 -29.519429) (xy 197.902994 -29.460963) (xy 197.969592 -29.408591)
			(xy 198.040866 -29.362787) (xy 198.116172 -29.323965) (xy 198.194827 -29.292477) (xy 198.276119 -29.268609)
			(xy 198.359312 -29.252576) (xy 198.443652 -29.244524) (xy 198.486014 -29.244036) (xy 198.524304 -29.244437)
			(xy 198.600598 -29.251046) (xy 198.676041 -29.264197) (xy 198.750071 -29.283791) (xy 198.786242 -29.29636)
			(xy 198.794679 -29.299011) (xy 198.812349 -29.299011) (xy 198.820786 -29.29636) (xy 198.856961 -29.283808)
			(xy 198.930995 -29.264238) (xy 199.006435 -29.251093) (xy 199.082726 -29.244471) (xy 199.121014 -29.244036)
			(xy 199.159304 -29.244437) (xy 199.235598 -29.251046) (xy 199.311041 -29.264197) (xy 199.385071 -29.283791)
			(xy 199.421242 -29.29636) (xy 199.429679 -29.299011) (xy 199.447349 -29.299011) (xy 199.455786 -29.29636)
			(xy 199.491961 -29.283808) (xy 199.565995 -29.264238) (xy 199.641435 -29.251093) (xy 199.717726 -29.244471)
			(xy 199.756014 -29.244036) (xy 199.794304 -29.244437) (xy 199.870598 -29.251046) (xy 199.946041 -29.264197)
			(xy 200.020071 -29.283791) (xy 200.056242 -29.29636) (xy 200.064679 -29.299011) (xy 200.082349 -29.299011)
			(xy 200.090786 -29.29636) (xy 200.126961 -29.283808) (xy 200.200995 -29.264238) (xy 200.276435 -29.251093)
			(xy 200.352726 -29.244471) (xy 200.391014 -29.244036) (xy 200.431702 -29.244422) (xy 200.512738 -29.251848)
			(xy 200.592757 -29.266645) (xy 200.67109 -29.288689) (xy 200.747082 -29.317797) (xy 200.820096 -29.353725)
			(xy 200.889524 -29.396173) (xy 200.954784 -29.444785) (xy 201.015331 -29.499155) (xy 201.070657 -29.558829)
			(xy 201.120302 -29.623307) (xy 201.163849 -29.69205) (xy 201.200934 -29.764484) (xy 201.216514 -29.802074)
			(xy 201.22098 -29.811942) (xy 201.236608 -29.826918) (xy 201.256995 -29.83419) (xy 201.267822 -29.833824)
			(xy 201.286077 -29.832403) (xy 201.322664 -29.83088) (xy 201.340974 -29.830776) (xy 201.383338 -29.831187)
			(xy 201.467682 -29.839239) (xy 201.550879 -29.855272) (xy 201.632176 -29.87914) (xy 201.710835 -29.910629)
			(xy 201.786145 -29.949452) (xy 201.857423 -29.995258) (xy 201.924025 -30.047632) (xy 201.985346 -30.1061)
			(xy 202.040832 -30.170132) (xy 202.08998 -30.239149) (xy 202.132344 -30.312525) (xy 202.167542 -30.389596)
			(xy 202.195254 -30.469663) (xy 202.21523 -30.552003) (xy 202.227288 -30.635868) (xy 202.23132 -30.7205)
			(xy 202.227288 -30.805132) (xy 202.21523 -30.888997) (xy 202.195254 -30.971337) (xy 202.167542 -31.051404)
			(xy 202.132344 -31.128475) (xy 202.08998 -31.201851) (xy 202.040832 -31.270868) (xy 201.985346 -31.3349)
			(xy 201.924025 -31.393368) (xy 201.857423 -31.445742) (xy 201.786145 -31.491548) (xy 201.710835 -31.530371)
			(xy 201.632176 -31.56186) (xy 201.550879 -31.585728) (xy 201.467682 -31.601761) (xy 201.383338 -31.609813)
			(xy 201.340974 -31.6103) (xy 201.302684 -31.609905) (xy 201.226389 -31.603295) (xy 201.150947 -31.590142)
			(xy 201.076917 -31.570546) (xy 201.040746 -31.557976) (xy 201.032309 -31.555325) (xy 201.014639 -31.555325)
			(xy 201.006202 -31.557976) (xy 200.970027 -31.570528) (xy 200.895993 -31.590099) (xy 200.820553 -31.603244)
			(xy 200.744262 -31.609866) (xy 200.705974 -31.6103) (xy 200.667684 -31.609905) (xy 200.591389 -31.603295)
			(xy 200.515947 -31.590142) (xy 200.441917 -31.570546) (xy 200.405746 -31.557976) (xy 200.397309 -31.555325)
			(xy 200.379639 -31.555325) (xy 200.371202 -31.557976) (xy 200.335027 -31.570528) (xy 200.260993 -31.590099)
			(xy 200.185553 -31.603244) (xy 200.109262 -31.609866) (xy 200.070974 -31.6103) (xy 200.032684 -31.609905)
			(xy 199.956389 -31.603295) (xy 199.880947 -31.590142) (xy 199.806917 -31.570546) (xy 199.770746 -31.557976)
			(xy 199.762309 -31.555325) (xy 199.744639 -31.555325) (xy 199.736202 -31.557976) (xy 199.700027 -31.570528)
			(xy 199.625993 -31.590099) (xy 199.550553 -31.603244) (xy 199.474262 -31.609866) (xy 199.435974 -31.6103)
			(xy 199.395288 -31.609814) (xy 199.314256 -31.602396) (xy 199.23424 -31.587608) (xy 199.15591 -31.565572)
			(xy 199.07992 -31.536472) (xy 199.006906 -31.500553) (xy 198.937478 -31.458114) (xy 198.872217 -31.40951)
			(xy 198.81167 -31.355148) (xy 198.756341 -31.295482) (xy 198.706694 -31.231012) (xy 198.663144 -31.162275)
			(xy 198.626056 -31.089848) (xy 198.610474 -31.052262) (xy 198.605924 -31.042441) (xy 198.590335 -31.027459)
			(xy 198.569982 -31.020164) (xy 198.559166 -31.020512) (xy 198.540911 -31.021927) (xy 198.504324 -31.023454)
			(xy 198.486014 -31.02356) (xy 198.443652 -31.023076) (xy 198.359312 -31.015024) (xy 198.276119 -30.998991)
			(xy 198.194827 -30.975123) (xy 198.116172 -30.943635) (xy 198.040866 -30.904813) (xy 197.969592 -30.859009)
			(xy 197.902994 -30.806637) (xy 197.841676 -30.748171) (xy 197.786193 -30.684142) (xy 197.737048 -30.615128)
			(xy 197.694686 -30.541756) (xy 197.65949 -30.464688) (xy 197.631779 -30.384624) (xy 197.611805 -30.302289)
			(xy 197.599747 -30.218428) (xy 197.595716 -30.1338) (xy 177.72177 -30.1338) (xy 178.749452 -31.161482)
			(xy 178.776376 -31.168594) (xy 178.78933 -31.164784) (xy 178.822909 -31.155741) (xy 178.891296 -31.143091)
			(xy 178.960551 -31.136732) (xy 178.995324 -31.136336) (xy 178.996086 -31.136336) (xy 179.036022 -31.13681)
			(xy 179.115457 -31.145158) (xy 179.193584 -31.161764) (xy 179.269547 -31.186445) (xy 179.342514 -31.218932)
			(xy 179.411685 -31.258869) (xy 179.476302 -31.305817) (xy 179.535658 -31.359263) (xy 179.589101 -31.418621)
			(xy 179.636047 -31.48324) (xy 179.675981 -31.552413) (xy 179.708465 -31.625381) (xy 179.733144 -31.701345)
			(xy 179.749747 -31.779473) (xy 179.758091 -31.858908) (xy 179.758594 -31.898844) (xy 179.758594 -31.899606)
			(xy 179.758172 -31.934378) (xy 179.751804 -32.00363) (xy 179.739166 -32.072016) (xy 179.730146 -32.1056)
			(xy 179.726336 -32.118554) (xy 179.733448 -32.145478) (xy 184.915973 -37.328094) (xy 197.270624 -37.328094)
			(xy 197.271107 -37.28698) (xy 197.278695 -37.205103) (xy 197.293804 -37.124275) (xy 197.316307 -37.045187)
			(xy 197.346011 -36.968512) (xy 197.382664 -36.894904) (xy 197.425951 -36.824993) (xy 197.475504 -36.759373)
			(xy 197.5309 -36.698606) (xy 197.591667 -36.643209) (xy 197.657286 -36.593655) (xy 197.727197 -36.550367)
			(xy 197.800804 -36.513715) (xy 197.877479 -36.48401) (xy 197.956568 -36.461506) (xy 198.037395 -36.446396)
			(xy 198.119272 -36.438808) (xy 198.160386 -36.438332) (xy 198.203952 -36.438853) (xy 198.290667 -36.447372)
			(xy 198.376134 -36.464329) (xy 198.459533 -36.489562) (xy 198.540065 -36.522829) (xy 198.616958 -36.563811)
			(xy 198.689475 -36.612116) (xy 198.756921 -36.66728) (xy 198.81865 -36.728775) (xy 198.87407 -36.796011)
			(xy 198.922649 -36.868345) (xy 198.963923 -36.945081) (xy 198.997496 -37.025486) (xy 199.010778 -37.066982)
			(xy 199.013703 -37.075249) (xy 199.024271 -37.089233) (xy 199.038923 -37.098854) (xy 199.047354 -37.101272)
			(xy 199.088321 -37.111837) (xy 199.168226 -37.13965) (xy 199.24513 -37.174922) (xy 199.318339 -37.217334)
			(xy 199.387193 -37.266504) (xy 199.451068 -37.321986) (xy 199.509389 -37.383281) (xy 199.529427 -37.408809)
			(xy 207.619596 -37.408809) (xy 207.619596 -37.324087) (xy 207.627649 -37.23975) (xy 207.643683 -37.15656)
			(xy 207.667551 -37.07527) (xy 207.699039 -36.996618) (xy 207.737861 -36.921315) (xy 207.783664 -36.850043)
			(xy 207.836035 -36.783447) (xy 207.8945 -36.722132) (xy 207.958528 -36.666651) (xy 208.02754 -36.617508)
			(xy 208.10091 -36.575148) (xy 208.177975 -36.539953) (xy 208.258037 -36.512244) (xy 208.34037 -36.49227)
			(xy 208.424229 -36.480213) (xy 208.508854 -36.476182) (xy 208.593479 -36.480213) (xy 208.677338 -36.49227)
			(xy 208.759671 -36.512244) (xy 208.839733 -36.539953) (xy 208.916798 -36.575148) (xy 208.990168 -36.617508)
			(xy 209.05918 -36.666651) (xy 209.123208 -36.722132) (xy 209.181673 -36.783447) (xy 209.234044 -36.850043)
			(xy 209.279847 -36.921315) (xy 209.318669 -36.996618) (xy 209.350157 -37.07527) (xy 209.374025 -37.15656)
			(xy 209.390059 -37.23975) (xy 209.398112 -37.324087) (xy 209.398616 -37.366448) (xy 209.398112 -37.408809)
			(xy 209.390059 -37.493146) (xy 209.374025 -37.576336) (xy 209.350157 -37.657626) (xy 209.318669 -37.736278)
			(xy 209.279847 -37.811581) (xy 209.234044 -37.882853) (xy 209.181673 -37.949449) (xy 209.123208 -38.010764)
			(xy 209.05918 -38.066245) (xy 208.990168 -38.115388) (xy 208.916798 -38.157748) (xy 208.839733 -38.192943)
			(xy 208.759671 -38.220652) (xy 208.677338 -38.240626) (xy 208.593479 -38.252683) (xy 208.508854 -38.256715)
			(xy 208.424229 -38.252683) (xy 208.34037 -38.240626) (xy 208.258037 -38.220652) (xy 208.177975 -38.192943)
			(xy 208.10091 -38.157748) (xy 208.02754 -38.115388) (xy 207.958528 -38.066245) (xy 207.8945 -38.010764)
			(xy 207.836035 -37.949449) (xy 207.783664 -37.882853) (xy 207.737861 -37.811581) (xy 207.699039 -37.736278)
			(xy 207.667551 -37.657626) (xy 207.643683 -37.576336) (xy 207.627649 -37.493146) (xy 207.619596 -37.408809)
			(xy 199.529427 -37.408809) (xy 199.561629 -37.449835) (xy 199.607316 -37.521047) (xy 199.646037 -37.596273)
			(xy 199.677444 -37.674835) (xy 199.701252 -37.756024) (xy 199.717247 -37.839106) (xy 199.725284 -37.92333)
			(xy 199.725788 -37.965634) (xy 199.72532 -38.006748) (xy 199.71773 -38.088625) (xy 199.702618 -38.169453)
			(xy 199.680113 -38.248541) (xy 199.650407 -38.325216) (xy 199.613754 -38.398823) (xy 199.570465 -38.468734)
			(xy 199.520911 -38.534353) (xy 199.465514 -38.595119) (xy 199.404746 -38.650516) (xy 199.339127 -38.70007)
			(xy 199.269216 -38.743357) (xy 199.195608 -38.78001) (xy 199.118933 -38.809716) (xy 199.039845 -38.83222)
			(xy 198.959017 -38.847331) (xy 198.87714 -38.85492) (xy 198.836026 -38.855396) (xy 198.792461 -38.854844)
			(xy 198.705747 -38.846327) (xy 198.620282 -38.829372) (xy 198.536884 -38.804141) (xy 198.456353 -38.770876)
			(xy 198.379461 -38.729896) (xy 198.306944 -38.681594) (xy 198.239498 -38.626432) (xy 198.177769 -38.56494)
			(xy 198.122348 -38.497707) (xy 198.073767 -38.425377) (xy 198.032492 -38.348643) (xy 197.998917 -38.26824)
			(xy 197.985634 -38.226746) (xy 197.982688 -38.218487) (xy 197.97213 -38.204501) (xy 197.957486 -38.194877)
			(xy 197.949058 -38.192456) (xy 197.908101 -38.181857) (xy 197.828197 -38.154046) (xy 197.751293 -38.118776)
			(xy 197.678085 -38.076367) (xy 197.609232 -38.0272) (xy 197.545356 -37.97172) (xy 197.487035 -37.910428)
			(xy 197.434795 -37.843877) (xy 197.389107 -37.772668) (xy 197.350384 -37.697444) (xy 197.318976 -37.618885)
			(xy 197.295165 -37.537699) (xy 197.279169 -37.454619) (xy 197.271129 -37.370397) (xy 197.270624 -37.328094)
			(xy 184.915973 -37.328094) (xy 187.011125 -39.423283) (xy 254.45872 -39.423283) (xy 254.45872 -39.338561)
			(xy 254.466773 -39.254224) (xy 254.482807 -39.171034) (xy 254.506675 -39.089744) (xy 254.538163 -39.011092)
			(xy 254.576985 -38.935789) (xy 254.622788 -38.864517) (xy 254.675159 -38.797921) (xy 254.733624 -38.736606)
			(xy 254.797652 -38.681125) (xy 254.866664 -38.631982) (xy 254.940034 -38.589622) (xy 255.017099 -38.554427)
			(xy 255.097161 -38.526718) (xy 255.179494 -38.506744) (xy 255.263353 -38.494687) (xy 255.347978 -38.490656)
			(xy 255.432603 -38.494687) (xy 255.516462 -38.506744) (xy 255.598795 -38.526718) (xy 255.678857 -38.554427)
			(xy 255.755922 -38.589622) (xy 255.829292 -38.631982) (xy 255.898304 -38.681125) (xy 255.962332 -38.736606)
			(xy 256.020797 -38.797921) (xy 256.073168 -38.864517) (xy 256.118971 -38.935789) (xy 256.157793 -39.011092)
			(xy 256.189281 -39.089744) (xy 256.213149 -39.171034) (xy 256.229183 -39.254224) (xy 256.237236 -39.338561)
			(xy 256.23774 -39.380922) (xy 256.237236 -39.423283) (xy 256.229183 -39.50762) (xy 256.213149 -39.59081)
			(xy 256.189281 -39.6721) (xy 256.157793 -39.750752) (xy 256.118971 -39.826055) (xy 256.073168 -39.897327)
			(xy 256.020797 -39.963923) (xy 255.962332 -40.025238) (xy 255.898304 -40.080719) (xy 255.829292 -40.129862)
			(xy 255.755922 -40.172222) (xy 255.678857 -40.207417) (xy 255.598795 -40.235126) (xy 255.516462 -40.2551)
			(xy 255.432603 -40.267157) (xy 255.347978 -40.271189) (xy 255.263353 -40.267157) (xy 255.179494 -40.2551)
			(xy 255.097161 -40.235126) (xy 255.017099 -40.207417) (xy 254.940034 -40.172222) (xy 254.866664 -40.129862)
			(xy 254.797652 -40.080719) (xy 254.733624 -40.025238) (xy 254.675159 -39.963923) (xy 254.622788 -39.897327)
			(xy 254.576985 -39.826055) (xy 254.538163 -39.750752) (xy 254.506675 -39.6721) (xy 254.482807 -39.59081)
			(xy 254.466773 -39.50762) (xy 254.45872 -39.423283) (xy 187.011125 -39.423283) (xy 188.381025 -40.793207)
			(xy 234.882173 -40.793207) (xy 234.882173 -40.696597) (xy 234.890151 -40.600318) (xy 234.906052 -40.505026)
			(xy 234.929769 -40.411373) (xy 234.961138 -40.319998) (xy 234.999945 -40.231525) (xy 235.045926 -40.14656)
			(xy 235.098767 -40.065682) (xy 235.158105 -39.989443) (xy 235.223537 -39.918365) (xy 235.294615 -39.852933)
			(xy 235.370854 -39.793595) (xy 235.451732 -39.740754) (xy 235.536697 -39.694773) (xy 235.62517 -39.655966)
			(xy 235.716545 -39.624597) (xy 235.810198 -39.60088) (xy 235.90549 -39.584979) (xy 236.001769 -39.577001)
			(xy 236.098379 -39.577001) (xy 236.194658 -39.584979) (xy 236.28995 -39.60088) (xy 236.383603 -39.624597)
			(xy 236.474978 -39.655966) (xy 236.563451 -39.694773) (xy 236.648416 -39.740754) (xy 236.729294 -39.793595)
			(xy 236.805533 -39.852933) (xy 236.876611 -39.918365) (xy 236.942043 -39.989443) (xy 237.001381 -40.065682)
			(xy 237.054222 -40.14656) (xy 237.100203 -40.231525) (xy 237.13901 -40.319998) (xy 237.170379 -40.411373)
			(xy 237.194096 -40.505026) (xy 237.209997 -40.600318) (xy 237.217975 -40.696597) (xy 237.218474 -40.744902)
			(xy 237.217975 -40.793207) (xy 237.209997 -40.889486) (xy 237.199916 -40.9499) (xy 246.935452 -40.9499)
			(xy 246.939482 -40.865295) (xy 246.951537 -40.781456) (xy 246.971506 -40.699142) (xy 246.999209 -40.619099)
			(xy 247.034396 -40.542053) (xy 247.076747 -40.468699) (xy 247.125879 -40.399704) (xy 247.181347 -40.335692)
			(xy 247.242648 -40.277242) (xy 247.309228 -40.224883) (xy 247.380484 -40.179091) (xy 247.45577 -40.14028)
			(xy 247.534404 -40.1088) (xy 247.615675 -40.084938) (xy 247.698846 -40.06891) (xy 247.783163 -40.060859)
			(xy 247.825514 -40.060372) (xy 247.868043 -40.060872) (xy 247.952713 -40.068982) (xy 248.036223 -40.085137)
			(xy 248.11781 -40.109189) (xy 248.196728 -40.140918) (xy 248.272258 -40.180035) (xy 248.343709 -40.226182)
			(xy 248.41043 -40.278938) (xy 248.441464 -40.308022) (xy 248.441718 -40.308276) (xy 248.44904 -40.314652)
			(xy 248.467069 -40.321822) (xy 248.47677 -40.322246) (xy 248.557288 -40.321992) (xy 248.575576 -40.314626)
			(xy 248.582688 -40.307514) (xy 248.613778 -40.278057) (xy 248.680689 -40.224588) (xy 248.752429 -40.177798)
			(xy 248.828335 -40.13812) (xy 248.907704 -40.105923) (xy 248.9898 -40.081504) (xy 249.073863 -40.065089)
			(xy 249.159115 -40.056831) (xy 249.20194 -40.056308) (xy 249.202448 -40.056308) (xy 249.244796 -40.056782)
			(xy 249.329107 -40.064837) (xy 249.412272 -40.08087) (xy 249.493536 -40.104735) (xy 249.572163 -40.136216)
			(xy 249.647442 -40.175029) (xy 249.718691 -40.220821) (xy 249.785265 -40.273178) (xy 249.84656 -40.331627)
			(xy 249.902022 -40.395637) (xy 249.951149 -40.464629) (xy 249.993496 -40.537978) (xy 250.028678 -40.615021)
			(xy 250.056379 -40.695058) (xy 250.076346 -40.777367) (xy 250.088399 -40.8612) (xy 250.092429 -40.9458)
			(xy 250.088399 -41.0304) (xy 250.076346 -41.114233) (xy 250.056379 -41.196542) (xy 250.028678 -41.276579)
			(xy 249.993496 -41.353622) (xy 249.951149 -41.426971) (xy 249.902022 -41.495963) (xy 249.84656 -41.559973)
			(xy 249.785265 -41.618422) (xy 249.718691 -41.670779) (xy 249.647442 -41.716571) (xy 249.572163 -41.755384)
			(xy 249.493536 -41.786865) (xy 249.412272 -41.81073) (xy 249.329107 -41.826763) (xy 249.244796 -41.834818)
			(xy 249.202448 -41.835324) (xy 249.159919 -41.834822) (xy 249.07525 -41.826709) (xy 248.991741 -41.810552)
			(xy 248.910155 -41.7865) (xy 248.831237 -41.754771) (xy 248.755707 -41.715655) (xy 248.684255 -41.66951)
			(xy 248.617533 -41.616756) (xy 248.586498 -41.587674) (xy 248.586244 -41.58742) (xy 248.578903 -41.58107)
			(xy 248.560888 -41.573885) (xy 248.551192 -41.57345) (xy 248.470674 -41.573704) (xy 248.452386 -41.58107)
			(xy 248.445274 -41.588182) (xy 248.414201 -41.617657) (xy 248.347287 -41.671125) (xy 248.275544 -41.717913)
			(xy 248.199635 -41.757589) (xy 248.120264 -41.789784) (xy 248.038166 -41.8142) (xy 247.954101 -41.830612)
			(xy 247.868848 -41.838866) (xy 247.826022 -41.839388) (xy 247.825514 -41.839388) (xy 247.783163 -41.838941)
			(xy 247.698846 -41.83089) (xy 247.615675 -41.814862) (xy 247.534404 -41.791) (xy 247.45577 -41.75952)
			(xy 247.380484 -41.720709) (xy 247.309228 -41.674917) (xy 247.242648 -41.622558) (xy 247.181347 -41.564108)
			(xy 247.125879 -41.500096) (xy 247.076747 -41.431101) (xy 247.034396 -41.357747) (xy 246.999209 -41.280701)
			(xy 246.971506 -41.200658) (xy 246.951537 -41.118344) (xy 246.939482 -41.034505) (xy 246.935452 -40.9499)
			(xy 237.199916 -40.9499) (xy 237.194096 -40.984778) (xy 237.170379 -41.078431) (xy 237.13901 -41.169806)
			(xy 237.100203 -41.258279) (xy 237.054222 -41.343244) (xy 237.001381 -41.424122) (xy 236.942043 -41.500361)
			(xy 236.876611 -41.571439) (xy 236.805533 -41.636871) (xy 236.729294 -41.696209) (xy 236.648416 -41.74905)
			(xy 236.563451 -41.795031) (xy 236.474978 -41.833838) (xy 236.383603 -41.865207) (xy 236.28995 -41.888924)
			(xy 236.194658 -41.904825) (xy 236.098379 -41.912803) (xy 236.001769 -41.912803) (xy 235.90549 -41.904825)
			(xy 235.810198 -41.888924) (xy 235.716545 -41.865207) (xy 235.62517 -41.833838) (xy 235.536697 -41.795031)
			(xy 235.451732 -41.74905) (xy 235.370854 -41.696209) (xy 235.294615 -41.636871) (xy 235.223537 -41.571439)
			(xy 235.158105 -41.500361) (xy 235.098767 -41.424122) (xy 235.045926 -41.343244) (xy 234.999945 -41.258279)
			(xy 234.961138 -41.169806) (xy 234.929769 -41.078431) (xy 234.906052 -40.984778) (xy 234.890151 -40.889486)
			(xy 234.882173 -40.793207) (xy 188.381025 -40.793207) (xy 191.613327 -44.025566) (xy 236.740192 -44.025566)
			(xy 236.74068 -43.984453) (xy 236.74827 -43.902577) (xy 236.763381 -43.82175) (xy 236.785886 -43.742663)
			(xy 236.815591 -43.665989) (xy 236.852243 -43.592383) (xy 236.895531 -43.522473) (xy 236.945083 -43.456854)
			(xy 237.000479 -43.396088) (xy 237.061245 -43.340691) (xy 237.126863 -43.291137) (xy 237.196773 -43.247849)
			(xy 237.270378 -43.211196) (xy 237.347052 -43.181489) (xy 237.426139 -43.158984) (xy 237.506965 -43.143872)
			(xy 237.588841 -43.136281) (xy 237.629954 -43.135804) (xy 237.672596 -43.136331) (xy 237.757484 -43.144543)
			(xy 237.841197 -43.160838) (xy 237.922968 -43.185068) (xy 237.962694 -43.200574) (xy 237.971356 -43.203655)
			(xy 237.989722 -43.204046) (xy 237.998508 -43.201336) (xy 238.034032 -43.189272) (xy 238.106663 -43.170452)
			(xy 238.18062 -43.157817) (xy 238.25538 -43.151455) (xy 238.292894 -43.151044) (xy 238.332166 -43.151496)
			(xy 238.410399 -43.158477) (xy 238.487712 -43.172332) (xy 238.563501 -43.192954) (xy 238.600488 -43.206162)
			(xy 238.609037 -43.208926) (xy 238.626991 -43.208926) (xy 238.63554 -43.206162) (xy 238.672533 -43.192975)
			(xy 238.748323 -43.172363) (xy 238.825633 -43.158506) (xy 238.903863 -43.151512) (xy 238.943134 -43.151044)
			(xy 238.981423 -43.151469) (xy 239.057717 -43.158071) (xy 239.133159 -43.171215) (xy 239.207191 -43.190803)
			(xy 239.243362 -43.203368) (xy 239.251799 -43.206019) (xy 239.269469 -43.206019) (xy 239.277906 -43.203368)
			(xy 239.314089 -43.190839) (xy 239.38812 -43.171262) (xy 239.463558 -43.158111) (xy 239.539846 -43.151482)
			(xy 239.578134 -43.151044) (xy 239.616423 -43.151469) (xy 239.692717 -43.158071) (xy 239.768159 -43.171215)
			(xy 239.842191 -43.190803) (xy 239.878362 -43.203368) (xy 239.886799 -43.206019) (xy 239.904469 -43.206019)
			(xy 239.912906 -43.203368) (xy 239.949089 -43.190839) (xy 240.02312 -43.171262) (xy 240.098558 -43.158111)
			(xy 240.174846 -43.151482) (xy 240.213134 -43.151044) (xy 240.25606 -43.151581) (xy 240.341511 -43.159862)
			(xy 240.425768 -43.176335) (xy 240.508046 -43.200846) (xy 240.587581 -43.233168) (xy 240.613613 -43.246802)
			(xy 243.62918 -43.246802) (xy 243.629584 -43.208512) (xy 243.636192 -43.132218) (xy 243.649342 -43.056775)
			(xy 243.668936 -42.982745) (xy 243.681504 -42.946574) (xy 243.684156 -42.938137) (xy 243.684156 -42.920466)
			(xy 243.681504 -42.91203) (xy 243.668959 -42.875853) (xy 243.649386 -42.80182) (xy 243.636239 -42.72638)
			(xy 243.629616 -42.65009) (xy 243.62918 -42.611802) (xy 243.629684 -42.569441) (xy 243.637737 -42.485104)
			(xy 243.653771 -42.401914) (xy 243.677639 -42.320624) (xy 243.709127 -42.241972) (xy 243.747949 -42.166669)
			(xy 243.793752 -42.095397) (xy 243.846123 -42.028801) (xy 243.904588 -41.967486) (xy 243.968616 -41.912005)
			(xy 244.037628 -41.862862) (xy 244.110998 -41.820502) (xy 244.188063 -41.785307) (xy 244.268125 -41.757598)
			(xy 244.350458 -41.737624) (xy 244.434317 -41.725567) (xy 244.518942 -41.721536) (xy 244.603567 -41.725567)
			(xy 244.687426 -41.737624) (xy 244.769759 -41.757598) (xy 244.849821 -41.785307) (xy 244.926886 -41.820502)
			(xy 245.000256 -41.862862) (xy 245.069268 -41.912005) (xy 245.133296 -41.967486) (xy 245.191761 -42.028801)
			(xy 245.244132 -42.095397) (xy 245.289935 -42.166669) (xy 245.328757 -42.241972) (xy 245.360245 -42.320624)
			(xy 245.384113 -42.401914) (xy 245.400147 -42.485104) (xy 245.4082 -42.569441) (xy 245.408704 -42.611802)
			(xy 245.408302 -42.650092) (xy 245.401694 -42.726386) (xy 245.388543 -42.801829) (xy 245.368949 -42.875859)
			(xy 245.35638 -42.91203) (xy 245.353727 -42.920466) (xy 245.353728 -42.938137) (xy 245.35638 -42.946574)
			(xy 245.368926 -42.982751) (xy 245.388499 -43.056784) (xy 245.401645 -43.132224) (xy 245.408269 -43.208514)
			(xy 245.408704 -43.246802) (xy 245.4082 -43.289163) (xy 245.400147 -43.3735) (xy 245.384113 -43.45669)
			(xy 245.360245 -43.53798) (xy 245.328757 -43.616632) (xy 245.289935 -43.691935) (xy 245.244132 -43.763207)
			(xy 245.191761 -43.829803) (xy 245.133296 -43.891118) (xy 245.069268 -43.946599) (xy 245.000256 -43.995742)
			(xy 244.926886 -44.038102) (xy 244.849821 -44.073297) (xy 244.769759 -44.101006) (xy 244.687426 -44.12098)
			(xy 244.603567 -44.133037) (xy 244.518942 -44.137069) (xy 244.434317 -44.133037) (xy 244.350458 -44.12098)
			(xy 244.268125 -44.101006) (xy 244.188063 -44.073297) (xy 244.110998 -44.038102) (xy 244.037628 -43.995742)
			(xy 243.968616 -43.946599) (xy 243.904588 -43.891118) (xy 243.846123 -43.829803) (xy 243.793752 -43.763207)
			(xy 243.747949 -43.691935) (xy 243.709127 -43.616632) (xy 243.677639 -43.53798) (xy 243.653771 -43.45669)
			(xy 243.637737 -43.3735) (xy 243.629684 -43.289163) (xy 243.62918 -43.246802) (xy 240.613613 -43.246802)
			(xy 240.663633 -43.272999) (xy 240.735496 -43.31997) (xy 240.802501 -43.373643) (xy 240.864025 -43.433521)
			(xy 240.919496 -43.499046) (xy 240.968398 -43.569608) (xy 241.010277 -43.644552) (xy 241.044744 -43.723182)
			(xy 241.071477 -43.804765) (xy 241.090229 -43.888544) (xy 241.096038 -43.931078) (xy 241.097792 -43.94092)
			(xy 241.107661 -43.958279) (xy 241.123386 -43.970587) (xy 241.132868 -43.97375) (xy 241.172506 -43.985287)
			(xy 241.249638 -44.014728) (xy 241.32371 -44.051189) (xy 241.394086 -44.094356) (xy 241.460159 -44.143858)
			(xy 241.521362 -44.199269) (xy 241.577167 -44.260112) (xy 241.627095 -44.325864) (xy 241.670716 -44.395959)
			(xy 241.707655 -44.469795) (xy 241.737594 -44.546735) (xy 241.760276 -44.626118) (xy 241.775505 -44.707261)
			(xy 241.78315 -44.789466) (xy 241.783616 -44.830746) (xy 241.783231 -44.871862) (xy 241.775639 -44.953744)
			(xy 241.760525 -45.034576) (xy 241.738017 -45.113668) (xy 241.708307 -45.190346) (xy 241.671649 -45.263956)
			(xy 241.628355 -45.333869) (xy 241.578796 -45.39949) (xy 241.523393 -45.460258) (xy 241.462619 -45.515654)
			(xy 241.396993 -45.565207) (xy 241.327075 -45.608494) (xy 241.253462 -45.645144) (xy 241.176781 -45.674846)
			(xy 241.097686 -45.697346) (xy 241.016853 -45.712452) (xy 240.93497 -45.720035) (xy 240.893854 -45.720508)
			(xy 240.848047 -45.719908) (xy 240.756919 -45.710469) (xy 240.667241 -45.691726) (xy 240.579961 -45.663878)
			(xy 240.537746 -45.646086) (xy 240.528923 -45.642621) (xy 240.509997 -45.641842) (xy 240.500916 -45.644562)
			(xy 240.454475 -45.659757) (xy 240.359116 -45.681105) (xy 240.261993 -45.691873) (xy 240.213134 -45.692568)
			(xy 240.174844 -45.692152) (xy 240.09855 -45.685547) (xy 240.023108 -45.672401) (xy 239.949077 -45.652811)
			(xy 239.912906 -45.640244) (xy 239.904469 -45.637593) (xy 239.886799 -45.637593) (xy 239.878362 -45.640244)
			(xy 239.842183 -45.652782) (xy 239.76815 -45.672357) (xy 239.692711 -45.685505) (xy 239.616422 -45.692131)
			(xy 239.578134 -45.692568) (xy 239.539844 -45.692152) (xy 239.46355 -45.685547) (xy 239.388108 -45.672401)
			(xy 239.314077 -45.652811) (xy 239.277906 -45.640244) (xy 239.269469 -45.637593) (xy 239.251799 -45.637593)
			(xy 239.243362 -45.640244) (xy 239.207183 -45.652782) (xy 239.13315 -45.672357) (xy 239.057711 -45.685505)
			(xy 238.981422 -45.692131) (xy 238.943134 -45.692568) (xy 238.903862 -45.692107) (xy 238.825629 -45.685129)
			(xy 238.748316 -45.671276) (xy 238.672527 -45.650657) (xy 238.63554 -45.63745) (xy 238.626991 -45.634686)
			(xy 238.609037 -45.634686) (xy 238.600488 -45.63745) (xy 238.563502 -45.650659) (xy 238.48771 -45.671265)
			(xy 238.410397 -45.685115) (xy 238.332165 -45.692103) (xy 238.292894 -45.692568) (xy 238.24936 -45.692039)
			(xy 238.16271 -45.683524) (xy 238.077306 -45.666586) (xy 237.993965 -45.641387) (xy 237.913484 -45.608168)
			(xy 237.87481 -45.588174) (xy 237.86657 -45.584248) (xy 237.848476 -45.581916) (xy 237.839504 -45.583602)
			(xy 237.790336 -45.594179) (xy 237.690402 -45.605511) (xy 237.640114 -45.606208) (xy 237.599001 -45.605674)
			(xy 237.517127 -45.598088) (xy 237.436301 -45.582981) (xy 237.357214 -45.560481) (xy 237.280541 -45.53078)
			(xy 237.206935 -45.494131) (xy 237.137024 -45.450847) (xy 237.071406 -45.401297) (xy 237.010639 -45.345904)
			(xy 236.955242 -45.285141) (xy 236.905687 -45.219525) (xy 236.862399 -45.149618) (xy 236.825745 -45.076014)
			(xy 236.796038 -44.999343) (xy 236.773533 -44.920257) (xy 236.75842 -44.839433) (xy 236.750829 -44.757559)
			(xy 236.750352 -44.716446) (xy 236.750814 -44.676228) (xy 236.758123 -44.596123) (xy 236.772622 -44.517004)
			(xy 236.794193 -44.439513) (xy 236.80801 -44.40174) (xy 236.811025 -44.392621) (xy 236.810769 -44.373433)
			(xy 236.807502 -44.364402) (xy 236.791394 -44.324025) (xy 236.766206 -44.240819) (xy 236.749266 -44.15555)
			(xy 236.740738 -44.069034) (xy 236.740192 -44.025566) (xy 191.613327 -44.025566) (xy 194.186302 -46.598586)
			(xy 194.194757 -46.606142) (xy 194.216125 -46.613652) (xy 194.22745 -46.613064) (xy 194.227958 -46.613064)
			(xy 194.248403 -46.610951) (xy 194.289447 -46.608663) (xy 194.31 -46.608492) (xy 194.349934 -46.609015)
			(xy 194.429364 -46.617363) (xy 194.507487 -46.633969) (xy 194.583446 -46.658649) (xy 194.656409 -46.691134)
			(xy 194.725576 -46.731068) (xy 194.790191 -46.778014) (xy 194.849544 -46.831456) (xy 194.902986 -46.890809)
			(xy 194.949932 -46.955424) (xy 194.989866 -47.024591) (xy 195.022351 -47.097554) (xy 195.047031 -47.173513)
			(xy 195.063637 -47.251636) (xy 195.071985 -47.331066) (xy 195.072508 -47.371) (xy 195.072338 -47.390915)
			(xy 195.070177 -47.430686) (xy 195.06819 -47.450502) (xy 195.067936 -47.453042) (xy 195.067936 -47.45355)
			(xy 195.067364 -47.464873) (xy 195.074872 -47.486234) (xy 195.082414 -47.494698) (xy 201.566272 -53.978302)
			(xy 201.574415 -53.985759) (xy 201.595112 -53.993386) (xy 201.60615 -53.993034) (xy 201.645266 -53.99151)
			(xy 201.675998 -53.99197) (xy 201.737014 -53.999375) (xy 201.796693 -54.014081) (xy 201.854164 -54.035874)
			(xy 201.908589 -54.064436) (xy 201.959174 -54.09935) (xy 202.005181 -54.140107) (xy 202.04594 -54.186113)
			(xy 202.080856 -54.236697) (xy 202.109419 -54.291121) (xy 202.131214 -54.348591) (xy 202.145922 -54.40827)
			(xy 202.153329 -54.469286) (xy 202.153774 -54.500018) (xy 202.15225 -54.539134) (xy 202.151939 -54.550161)
			(xy 202.159579 -54.570833) (xy 202.166982 -54.579012) (xy 202.909424 -55.321454) (xy 202.916827 -55.328291)
			(xy 202.935424 -55.336014) (xy 202.945492 -55.33644) (xy 203.670154 -55.33644) (xy 203.679243 -55.336109)
			(xy 203.696282 -55.329775) (xy 203.710034 -55.317888) (xy 203.718769 -55.301947) (xy 203.720446 -55.293006)
			(xy 203.737972 -55.17515) (xy 203.717652 -55.1434) (xy 203.699618 -55.137812) (xy 203.622621 -55.114136)
			(xy 203.470842 -55.060112) (xy 203.321901 -54.998696) (xy 203.176158 -54.930035) (xy 203.033964 -54.854297)
			(xy 202.895663 -54.771664) (xy 202.761589 -54.682335) (xy 202.632066 -54.586526) (xy 202.507408 -54.48447)
			(xy 202.387914 -54.376411) (xy 202.273873 -54.262612) (xy 202.165562 -54.143347) (xy 202.063242 -54.018905)
			(xy 201.967159 -53.889585) (xy 201.877547 -53.755701) (xy 201.794621 -53.617575) (xy 201.718582 -53.475542)
			(xy 201.649613 -53.329944) (xy 201.587882 -53.181133) (xy 201.533536 -53.029469) (xy 201.486708 -52.875318)
			(xy 201.447511 -52.719052) (xy 201.416039 -52.561049) (xy 201.392368 -52.401691) (xy 201.376556 -52.241362)
			(xy 201.36864 -52.080449) (xy 201.368152 -51.999896) (xy 201.368646 -51.91946) (xy 201.376539 -51.758781)
			(xy 201.392308 -51.598683) (xy 201.415913 -51.439551) (xy 201.447297 -51.281769) (xy 201.486386 -51.125718)
			(xy 201.533085 -50.971772) (xy 201.587281 -50.820303) (xy 201.648845 -50.671676) (xy 201.717627 -50.526249)
			(xy 201.793462 -50.384372) (xy 201.876167 -50.246387) (xy 201.965543 -50.112626) (xy 202.061375 -49.983412)
			(xy 202.163431 -49.859056) (xy 202.271467 -49.739857) (xy 202.385221 -49.626103) (xy 202.50442 -49.518067)
			(xy 202.628776 -49.416011) (xy 202.75799 -49.320179) (xy 202.891751 -49.230803) (xy 203.029736 -49.148098)
			(xy 203.171613 -49.072263) (xy 203.31704 -49.003481) (xy 203.465667 -48.941917) (xy 203.617136 -48.887721)
			(xy 203.771082 -48.841022) (xy 203.927133 -48.801933) (xy 204.084915 -48.770549) (xy 204.244047 -48.746944)
			(xy 204.404145 -48.731175) (xy 204.564824 -48.723282) (xy 204.725696 -48.723282) (xy 204.886375 -48.731175)
			(xy 205.046473 -48.746944) (xy 205.205605 -48.770549) (xy 205.363387 -48.801933) (xy 205.519438 -48.841022)
			(xy 205.673384 -48.887721) (xy 205.824853 -48.941917) (xy 205.97348 -49.003481) (xy 206.118907 -49.072263)
			(xy 206.260784 -49.148098) (xy 206.398769 -49.230803) (xy 206.53253 -49.320179) (xy 206.661744 -49.416011)
			(xy 206.7861 -49.518067) (xy 206.905299 -49.626103) (xy 207.019053 -49.739857) (xy 207.127089 -49.859056)
			(xy 207.229145 -49.983412) (xy 207.324977 -50.112626) (xy 207.414353 -50.246387) (xy 207.497058 -50.384372)
			(xy 207.572893 -50.526249) (xy 207.641675 -50.671676) (xy 207.703239 -50.820303) (xy 207.757435 -50.971772)
			(xy 207.804134 -51.125718) (xy 207.843223 -51.281769) (xy 207.874607 -51.439551) (xy 207.898212 -51.598683)
			(xy 207.913981 -51.758781) (xy 207.921874 -51.91946) (xy 207.922368 -51.999896) (xy 207.921892 -52.080449)
			(xy 207.920844 -52.10175) (xy 244.67947 -52.10175) (xy 244.679975 -52.075243) (xy 244.687334 -52.022743)
			(xy 244.701889 -51.971767) (xy 244.723361 -51.923297) (xy 244.751335 -51.878265) (xy 244.785274 -51.837539)
			(xy 244.824523 -51.801903) (xy 244.868327 -51.772043) (xy 244.915843 -51.748534) (xy 244.966156 -51.731829)
			(xy 244.992144 -51.726592) (xy 245.000543 -51.724726) (xy 245.015476 -51.716197) (xy 245.026755 -51.703216)
			(xy 245.030244 -51.69535) (xy 245.045663 -51.657494) (xy 245.082559 -51.584546) (xy 245.125992 -51.515291)
			(xy 245.175596 -51.450313) (xy 245.230952 -51.39016) (xy 245.291595 -51.335341) (xy 245.357011 -51.286316)
			(xy 245.426649 -51.2435) (xy 245.499922 -51.207254) (xy 245.576211 -51.177884) (xy 245.654873 -51.155637)
			(xy 245.735245 -51.140701) (xy 245.816648 -51.133203) (xy 245.857522 -51.13274) (xy 245.899843 -51.133258)
			(xy 245.984099 -51.14133) (xy 246.067208 -51.157371) (xy 246.148416 -51.181236) (xy 246.226989 -51.212708)
			(xy 246.302217 -51.251503) (xy 246.33809 -51.273964) (xy 246.346484 -51.278827) (xy 246.365522 -51.28248)
			(xy 246.38456 -51.278827) (xy 246.392954 -51.273964) (xy 246.42883 -51.25151) (xy 246.504063 -51.212731)
			(xy 246.582638 -51.181268) (xy 246.663845 -51.157405) (xy 246.74695 -51.141356) (xy 246.831202 -51.133268)
			(xy 246.873522 -51.13274) (xy 246.926862 -51.134518) (xy 246.938638 -51.134618) (xy 246.960306 -51.125466)
			(xy 246.975671 -51.107657) (xy 246.979186 -51.096418) (xy 246.990138 -51.056039) (xy 247.018713 -50.977397)
			(xy 247.054545 -50.901785) (xy 247.097317 -50.829872) (xy 247.146653 -50.762292) (xy 247.202115 -50.699642)
			(xy 247.263214 -50.642477) (xy 247.329411 -50.5913) (xy 247.40012 -50.546564) (xy 247.474717 -50.508665)
			(xy 247.552542 -50.477936) (xy 247.632909 -50.45465) (xy 247.715107 -50.439012) (xy 247.79841 -50.431161)
			(xy 247.840246 -50.430684) (xy 247.883752 -50.431235) (xy 247.970347 -50.439729) (xy 248.055699 -50.456641)
			(xy 248.138991 -50.481809) (xy 248.219426 -50.514992) (xy 248.296235 -50.555874) (xy 248.332752 -50.579528)
			(xy 248.341308 -50.584744) (xy 248.360946 -50.588653) (xy 248.380584 -50.584744) (xy 248.38914 -50.579528)
			(xy 248.425663 -50.555885) (xy 248.50248 -50.515022) (xy 248.582916 -50.481847) (xy 248.666204 -50.456676)
			(xy 248.751551 -50.439749) (xy 248.838142 -50.431227) (xy 248.881646 -50.430684) (xy 248.926403 -50.431259)
			(xy 249.015462 -50.440266) (xy 249.103167 -50.458165) (xy 249.188634 -50.484775) (xy 249.270999 -50.519828)
			(xy 249.349431 -50.562968) (xy 249.386598 -50.58791) (xy 249.394939 -50.593062) (xy 249.414052 -50.597328)
			(xy 249.433374 -50.594144) (xy 249.44197 -50.589434) (xy 249.4758 -50.569354) (xy 249.546346 -50.534523)
			(xy 249.619688 -50.506051) (xy 249.695257 -50.484158) (xy 249.772462 -50.469016) (xy 249.850701 -50.460742)
			(xy 249.890026 -50.45964) (xy 249.889772 -50.4444) (xy 249.889772 -50.443892) (xy 249.89024 -50.405527)
			(xy 249.896983 -50.329093) (xy 249.903234 -50.291238) (xy 249.904413 -50.282319) (xy 249.901131 -50.26464)
			(xy 249.891952 -50.249179) (xy 249.8852 -50.243232) (xy 249.851748 -50.215094) (xy 249.789907 -50.153305)
			(xy 249.734424 -50.08575) (xy 249.685833 -50.01308) (xy 249.644603 -49.935995) (xy 249.61113 -49.855239)
			(xy 249.585738 -49.771589) (xy 249.568671 -49.685852) (xy 249.560094 -49.598855) (xy 249.559572 -49.555146)
			(xy 249.560076 -49.512785) (xy 249.568129 -49.428448) (xy 249.584163 -49.345258) (xy 249.608031 -49.263968)
			(xy 249.639519 -49.185316) (xy 249.678341 -49.110013) (xy 249.724144 -49.038741) (xy 249.776515 -48.972145)
			(xy 249.83498 -48.91083) (xy 249.899008 -48.855349) (xy 249.96802 -48.806206) (xy 250.04139 -48.763846)
			(xy 250.118455 -48.728651) (xy 250.198517 -48.700942) (xy 250.28085 -48.680968) (xy 250.364709 -48.668911)
			(xy 250.449334 -48.66488) (xy 250.533959 -48.668911) (xy 250.617818 -48.680968) (xy 250.700151 -48.700942)
			(xy 250.780213 -48.728651) (xy 250.857278 -48.763846) (xy 250.930648 -48.806206) (xy 250.99966 -48.855349)
			(xy 251.063688 -48.91083) (xy 251.122153 -48.972145) (xy 251.174524 -49.038741) (xy 251.220327 -49.110013)
			(xy 251.259149 -49.185316) (xy 251.290637 -49.263968) (xy 251.314505 -49.345258) (xy 251.330539 -49.428448)
			(xy 251.338592 -49.512785) (xy 251.339096 -49.555146) (xy 251.338636 -49.593574) (xy 251.331894 -49.670136)
			(xy 251.325634 -49.708054) (xy 251.324473 -49.716974) (xy 251.32775 -49.73465) (xy 251.336921 -49.750111)
			(xy 251.343668 -49.75606) (xy 251.362142 -49.771471) (xy 251.397596 -49.803999) (xy 251.414534 -49.821084)
			(xy 251.422676 -49.828571) (xy 251.443355 -49.836348) (xy 251.454412 -49.83607) (xy 251.469822 -49.835031)
			(xy 251.50069 -49.833886) (xy 251.516134 -49.833784) (xy 251.557251 -49.834166) (xy 251.639133 -49.841757)
			(xy 251.719966 -49.85687) (xy 251.79906 -49.879378) (xy 251.875739 -49.909087) (xy 251.94935 -49.945745)
			(xy 252.019265 -49.989039) (xy 252.084886 -50.038598) (xy 252.145655 -50.094001) (xy 252.201053 -50.154775)
			(xy 252.250607 -50.220401) (xy 252.293894 -50.29032) (xy 252.330545 -50.363934) (xy 252.360248 -50.440616)
			(xy 252.382748 -50.519712) (xy 252.397854 -50.600546) (xy 252.405438 -50.682429) (xy 252.405896 -50.723546)
			(xy 252.405358 -50.767341) (xy 252.396743 -50.854506) (xy 252.379599 -50.940401) (xy 252.354094 -51.024196)
			(xy 252.320474 -51.105076) (xy 252.300232 -51.143916) (xy 252.29478 -51.15537) (xy 252.2948 -51.18071)
			(xy 252.300232 -51.192176) (xy 252.320452 -51.231026) (xy 252.354062 -51.311909) (xy 252.379567 -51.3957)
			(xy 252.39672 -51.481592) (xy 252.405355 -51.568752) (xy 252.405896 -51.612546) (xy 252.405358 -51.656341)
			(xy 252.396743 -51.743506) (xy 252.379599 -51.829401) (xy 252.354094 -51.913196) (xy 252.320474 -51.994076)
			(xy 252.300232 -52.032916) (xy 252.29478 -52.04437) (xy 252.2948 -52.06971) (xy 252.300232 -52.081176)
			(xy 252.320452 -52.120026) (xy 252.354062 -52.200909) (xy 252.379567 -52.2847) (xy 252.39672 -52.370592)
			(xy 252.405355 -52.457752) (xy 252.405896 -52.501546) (xy 252.405431 -52.54266) (xy 252.39784 -52.624537)
			(xy 252.382728 -52.705364) (xy 252.360222 -52.784452) (xy 252.330515 -52.861127) (xy 252.293861 -52.934733)
			(xy 252.250573 -53.004644) (xy 252.201018 -53.070263) (xy 252.145621 -53.131029) (xy 252.084853 -53.186426)
			(xy 252.019234 -53.235979) (xy 251.949323 -53.279267) (xy 251.875716 -53.31592) (xy 251.799041 -53.345626)
			(xy 251.719952 -53.36813) (xy 251.639125 -53.383242) (xy 251.557248 -53.390832) (xy 251.516134 -53.391308)
			(xy 251.471924 -53.390745) (xy 251.383942 -53.381965) (xy 251.297264 -53.3645) (xy 251.212747 -53.33852)
			(xy 251.131225 -53.304282) (xy 251.053503 -53.262125) (xy 250.980346 -53.212465) (xy 250.912478 -53.15579)
			(xy 250.881134 -53.124608) (xy 250.873005 -53.117104) (xy 250.852316 -53.109337) (xy 250.841256 -53.109622)
			(xy 250.825846 -53.110663) (xy 250.794978 -53.111806) (xy 250.779534 -53.111908) (xy 250.737779 -53.111492)
			(xy 250.654637 -53.103677) (xy 250.572592 -53.088104) (xy 250.492369 -53.064909) (xy 250.414673 -53.034297)
			(xy 250.340188 -52.996537) (xy 250.269571 -52.951961) (xy 250.203442 -52.900963) (xy 250.142385 -52.843991)
			(xy 250.086937 -52.781547) (xy 250.037585 -52.714181) (xy 249.994765 -52.642486) (xy 249.958854 -52.567092)
			(xy 249.930167 -52.488665) (xy 249.908958 -52.407894) (xy 249.895413 -52.32549) (xy 249.892058 -52.283868)
			(xy 249.891061 -52.274773) (xy 249.88348 -52.258135) (xy 249.870549 -52.245209) (xy 249.853908 -52.237634)
			(xy 249.844814 -52.236624) (xy 249.805225 -52.23352) (xy 249.726783 -52.221122) (xy 249.649759 -52.201775)
			(xy 249.574769 -52.175634) (xy 249.50241 -52.142907) (xy 249.433259 -52.103855) (xy 249.400314 -52.081684)
			(xy 249.392012 -52.076461) (xy 249.372875 -52.072218) (xy 249.353539 -52.075433) (xy 249.344942 -52.08016)
			(xy 249.312459 -52.099495) (xy 249.244799 -52.133223) (xy 249.174522 -52.161088) (xy 249.13844 -52.172362)
			(xy 249.128616 -52.175851) (xy 249.112727 -52.189319) (xy 249.103444 -52.207965) (xy 249.102372 -52.218336)
			(xy 249.099675 -52.260463) (xy 249.087279 -52.34397) (xy 249.067027 -52.425926) (xy 249.039099 -52.505595)
			(xy 249.003748 -52.582258) (xy 248.961291 -52.655227) (xy 248.912112 -52.723845) (xy 248.856651 -52.787493)
			(xy 248.795409 -52.8456) (xy 248.728936 -52.897642) (xy 248.657831 -52.943151) (xy 248.582733 -52.981717)
			(xy 248.504319 -53.012994) (xy 248.423294 -53.036699) (xy 248.340387 -53.052621) (xy 248.256345 -53.060614)
			(xy 248.214134 -53.061108) (xy 248.171669 -53.060607) (xy 248.087125 -53.052507) (xy 248.003739 -53.036385)
			(xy 247.922268 -53.01239) (xy 247.843456 -52.98074) (xy 247.768018 -52.941722) (xy 247.696643 -52.895693)
			(xy 247.629979 -52.84307) (xy 247.568634 -52.784334) (xy 247.540526 -52.752498) (xy 247.534176 -52.745132)
			(xy 247.517412 -52.736496) (xy 247.429274 -52.726336) (xy 247.410986 -52.731416) (xy 247.403112 -52.737258)
			(xy 247.370277 -52.761024) (xy 247.301045 -52.803187) (xy 247.228263 -52.838875) (xy 247.152535 -52.867791)
			(xy 247.07449 -52.889697) (xy 246.994775 -52.904409) (xy 246.914052 -52.911805) (xy 246.873522 -52.912264)
			(xy 246.831202 -52.911724) (xy 246.746946 -52.903656) (xy 246.663838 -52.887619) (xy 246.58263 -52.863758)
			(xy 246.504056 -52.83229) (xy 246.428827 -52.793499) (xy 246.392954 -52.77104) (xy 246.38456 -52.766177)
			(xy 246.365522 -52.762524) (xy 246.346484 -52.766177) (xy 246.33809 -52.77104) (xy 246.302222 -52.793507)
			(xy 246.226987 -52.832285) (xy 246.148411 -52.863747) (xy 246.067203 -52.887609) (xy 245.984096 -52.903654)
			(xy 245.899842 -52.911738) (xy 245.857522 -52.912264) (xy 245.813221 -52.911666) (xy 245.725058 -52.90285)
			(xy 245.638208 -52.885314) (xy 245.553531 -52.85923) (xy 245.471867 -52.824858) (xy 245.394025 -52.782538)
			(xy 245.320775 -52.732689) (xy 245.252843 -52.675806) (xy 245.190903 -52.61245) (xy 245.135568 -52.543252)
			(xy 245.111016 -52.506372) (xy 245.106055 -52.499361) (xy 245.092457 -52.488884) (xy 245.076169 -52.483465)
			(xy 245.067582 -52.483258) (xy 245.060978 -52.483258) (xy 245.033722 -52.482865) (xy 244.979766 -52.475104)
			(xy 244.927464 -52.459743) (xy 244.87788 -52.437094) (xy 244.832025 -52.407619) (xy 244.790831 -52.371918)
			(xy 244.755138 -52.330717) (xy 244.725671 -52.284856) (xy 244.703032 -52.235269) (xy 244.68768 -52.182963)
			(xy 244.679929 -52.129006) (xy 244.67947 -52.10175) (xy 207.920844 -52.10175) (xy 207.913976 -52.241361)
			(xy 207.898164 -52.40169) (xy 207.874493 -52.561048) (xy 207.84302 -52.71905) (xy 207.803822 -52.875315)
			(xy 207.756994 -53.029466) (xy 207.702647 -53.181129) (xy 207.640915 -53.329939) (xy 207.571945 -53.475536)
			(xy 207.495905 -53.617568) (xy 207.412978 -53.755693) (xy 207.323364 -53.889576) (xy 207.22728 -54.018894)
			(xy 207.124959 -54.143335) (xy 207.016646 -54.262598) (xy 206.902605 -54.376396) (xy 206.783109 -54.484452)
			(xy 206.658449 -54.586506) (xy 206.528925 -54.682312) (xy 206.39485 -54.771639) (xy 206.256548 -54.854269)
			(xy 206.114353 -54.930005) (xy 205.968608 -54.998662) (xy 205.819666 -55.060075) (xy 205.667886 -55.114095)
			(xy 205.590902 -55.137812) (xy 205.572868 -55.1434) (xy 205.552548 -55.17515) (xy 205.570074 -55.293006)
			(xy 205.571789 -55.301931) (xy 205.580529 -55.31785) (xy 205.594269 -55.329724) (xy 205.611286 -55.336064)
			(xy 205.620366 -55.33644) (xy 211.837778 -55.33644) (xy 211.846696 -55.336107) (xy 211.863445 -55.329974)
			(xy 211.877083 -55.318477) (xy 211.885959 -55.303006) (xy 211.887816 -55.294276) (xy 211.895118 -55.255481)
			(xy 211.916702 -55.179542) (xy 211.946017 -55.10624) (xy 211.982749 -55.03636) (xy 212.026505 -54.970648)
			(xy 212.076816 -54.90981) (xy 212.133144 -54.854495) (xy 212.194886 -54.805297) (xy 212.261381 -54.762741)
			(xy 212.331917 -54.727284) (xy 212.405739 -54.699304) (xy 212.482056 -54.679102) (xy 212.560053 -54.666894)
			(xy 212.638894 -54.66281) (xy 212.717735 -54.666894) (xy 212.795732 -54.679102) (xy 212.872049 -54.699304)
			(xy 212.945871 -54.727284) (xy 213.016407 -54.762741) (xy 213.082902 -54.805297) (xy 213.144644 -54.854495)
			(xy 213.200972 -54.90981) (xy 213.251283 -54.970648) (xy 213.295039 -55.03636) (xy 213.331771 -55.10624)
			(xy 213.361086 -55.179542) (xy 213.38267 -55.255481) (xy 213.389972 -55.294276) (xy 213.391835 -55.303005)
			(xy 213.400699 -55.318484) (xy 213.414337 -55.32998) (xy 213.431091 -55.336098) (xy 213.44001 -55.33644)
			(xy 248.620788 -55.33644) (xy 248.63096 -55.335983) (xy 248.649699 -55.328059) (xy 248.663897 -55.313487)
			(xy 248.668032 -55.304182) (xy 248.67829 -55.279357) (xy 248.704771 -55.232624) (xy 248.737544 -55.190066)
			(xy 248.775961 -55.152525) (xy 248.819263 -55.120742) (xy 248.866595 -55.095346) (xy 248.91702 -55.076839)
			(xy 248.969543 -55.065586) (xy 249.023124 -55.06181) (xy 249.076705 -55.065586) (xy 249.129228 -55.076839)
			(xy 249.179653 -55.095346) (xy 249.226985 -55.120742) (xy 249.270287 -55.152525) (xy 249.308704 -55.190066)
			(xy 249.341477 -55.232624) (xy 249.367958 -55.279357) (xy 249.378216 -55.304182) (xy 249.382334 -55.3135)
			(xy 249.396527 -55.328089) (xy 249.415282 -55.335996) (xy 249.42546 -55.33644) (xy 253.111508 -55.33644)
			(xy 253.12158 -55.336035) (xy 253.140179 -55.328302) (xy 253.147576 -55.321454) (xy 253.470664 -54.998366)
			(xy 253.475998 -54.966616) (xy 253.468886 -54.951884) (xy 253.450704 -54.912967) (xy 253.422198 -54.831933)
			(xy 253.402978 -54.74821) (xy 253.39329 -54.662856) (xy 253.392686 -54.619906) (xy 253.39322 -54.579972)
			(xy 253.401568 -54.500543) (xy 253.418173 -54.42242) (xy 253.442853 -54.346462) (xy 253.475337 -54.273499)
			(xy 253.51527 -54.204332) (xy 253.562214 -54.139717) (xy 253.615656 -54.080364) (xy 253.675008 -54.026922)
			(xy 253.739622 -53.979977) (xy 253.808789 -53.940042) (xy 253.881751 -53.907557) (xy 253.957709 -53.882876)
			(xy 254.035831 -53.86627) (xy 254.11526 -53.857921) (xy 254.155194 -53.857398) (xy 254.194125 -53.857863)
			(xy 254.271583 -53.865801) (xy 254.347827 -53.881594) (xy 254.422064 -53.905078) (xy 254.49352 -53.936008)
			(xy 254.56145 -53.974062) (xy 254.625146 -54.018843) (xy 254.683946 -54.069885) (xy 254.710946 -54.097936)
			(xy 254.711708 -54.098698) (xy 254.711962 -54.098952) (xy 254.719536 -54.106188) (xy 254.73883 -54.114303)
			(xy 254.7493 -54.1147) (xy 254.824738 -54.113684) (xy 254.835323 -54.112975) (xy 254.85461 -54.104201)
			(xy 254.862076 -54.096666) (xy 254.889232 -54.066856) (xy 254.948768 -54.012465) (xy 255.01371 -53.964657)
			(xy 255.083333 -53.923966) (xy 255.156859 -53.890846) (xy 255.233468 -53.865667) (xy 255.312307 -53.848709)
			(xy 255.392494 -53.840162) (xy 255.432814 -53.839618) (xy 255.471407 -53.840114) (xy 255.548199 -53.847895)
			(xy 255.623812 -53.863396) (xy 255.697471 -53.886458) (xy 255.768423 -53.916846) (xy 255.835941 -53.954248)
			(xy 255.899335 -53.998281) (xy 255.957954 -54.048494) (xy 256.011198 -54.104374) (xy 256.058524 -54.165348)
			(xy 256.099446 -54.230793) (xy 256.133545 -54.300038) (xy 256.160473 -54.372373) (xy 256.170684 -54.409594)
			(xy 256.175002 -54.426358) (xy 256.202434 -54.44744) (xy 265.095482 -54.44744) (xy 265.107307 -54.4469)
			(xy 265.128498 -54.436412) (xy 265.142756 -54.417549) (xy 265.14552 -54.406038) (xy 265.151928 -54.374659)
			(xy 265.1716 -54.313709) (xy 265.198766 -54.25571) (xy 265.232999 -54.20158) (xy 265.273755 -54.152176)
			(xy 265.320391 -54.108278) (xy 265.372168 -54.070582) (xy 265.428268 -54.039683) (xy 265.487802 -54.016071)
			(xy 265.54983 -54.000119) (xy 265.613369 -53.99208) (xy 265.677415 -53.99208) (xy 265.740954 -54.000119)
			(xy 265.802982 -54.016071) (xy 265.862516 -54.039683) (xy 265.918616 -54.070582) (xy 265.970393 -54.108278)
			(xy 266.017029 -54.152176) (xy 266.057785 -54.20158) (xy 266.092018 -54.25571) (xy 266.119184 -54.313709)
			(xy 266.138856 -54.374659) (xy 266.145264 -54.406038) (xy 266.148093 -54.417512) (xy 266.162369 -54.436308)
			(xy 266.183502 -54.446819) (xy 266.195302 -54.44744) (xy 266.213844 -54.44744) (xy 266.223775 -54.446937)
			(xy 266.242144 -54.439378) (xy 266.256266 -54.42541) (xy 266.26058 -54.416452) (xy 266.303252 -54.316376)
			(xy 266.297664 -54.286404) (xy 266.286996 -54.275482) (xy 266.232723 -54.218611) (xy 266.129107 -54.100364)
			(xy 266.031279 -53.977284) (xy 265.939466 -53.849656) (xy 265.853877 -53.717773) (xy 265.774709 -53.581937)
			(xy 265.702146 -53.442462) (xy 265.636353 -53.299669) (xy 265.577481 -53.153885) (xy 265.525668 -53.005446)
			(xy 265.48103 -52.854694) (xy 265.443672 -52.701975) (xy 265.413679 -52.54764) (xy 265.39112 -52.392045)
			(xy 265.376047 -52.235547) (xy 265.368495 -52.078507) (xy 265.368024 -51.999896) (xy 265.368518 -51.919453)
			(xy 265.376412 -51.758762) (xy 265.392181 -51.598651) (xy 265.415788 -51.439508) (xy 265.447175 -51.281714)
			(xy 265.486267 -51.12565) (xy 265.53297 -50.971693) (xy 265.58717 -50.820212) (xy 265.648739 -50.671574)
			(xy 265.717526 -50.526135) (xy 265.793367 -50.384247) (xy 265.876078 -50.246251) (xy 265.965461 -50.11248)
			(xy 266.0613 -49.983256) (xy 266.163365 -49.85889) (xy 266.271409 -49.739682) (xy 266.385172 -49.625919)
			(xy 266.50438 -49.517875) (xy 266.628746 -49.41581) (xy 266.75797 -49.319971) (xy 266.891741 -49.230588)
			(xy 267.029737 -49.147877) (xy 267.171625 -49.072036) (xy 267.317064 -49.003249) (xy 267.465702 -48.94168)
			(xy 267.617183 -48.88748) (xy 267.77114 -48.840777) (xy 267.927204 -48.801685) (xy 268.084998 -48.770298)
			(xy 268.244141 -48.746691) (xy 268.404252 -48.730922) (xy 268.564943 -48.723028) (xy 268.725829 -48.723028)
			(xy 268.88652 -48.730922) (xy 269.046631 -48.746691) (xy 269.205774 -48.770298) (xy 269.363568 -48.801685)
			(xy 269.519632 -48.840777) (xy 269.673589 -48.88748) (xy 269.82507 -48.94168) (xy 269.973708 -49.003249)
			(xy 270.119147 -49.072036) (xy 270.261035 -49.147877) (xy 270.399031 -49.230588) (xy 270.532802 -49.319971)
			(xy 270.662026 -49.41581) (xy 270.786392 -49.517875) (xy 270.9056 -49.625919) (xy 271.019363 -49.739682)
			(xy 271.127407 -49.85889) (xy 271.229472 -49.983256) (xy 271.325311 -50.11248) (xy 271.414694 -50.246251)
			(xy 271.497405 -50.384247) (xy 271.573246 -50.526135) (xy 271.642033 -50.671574) (xy 271.703602 -50.820212)
			(xy 271.757802 -50.971693) (xy 271.804505 -51.12565) (xy 271.843597 -51.281714) (xy 271.874984 -51.439508)
			(xy 271.898591 -51.598651) (xy 271.91436 -51.758762) (xy 271.922254 -51.919453) (xy 271.922748 -51.999896)
			(xy 271.922313 -52.078508) (xy 271.914769 -52.23555) (xy 271.899702 -52.39205) (xy 271.877147 -52.547648)
			(xy 271.847157 -52.701985) (xy 271.809799 -52.854705) (xy 271.765161 -53.005459) (xy 271.713345 -53.153899)
			(xy 271.654469 -53.299683) (xy 271.58867 -53.442476) (xy 271.516099 -53.581949) (xy 271.436923 -53.717781)
			(xy 271.351325 -53.84966) (xy 271.2595 -53.977283) (xy 271.161661 -54.100355) (xy 271.058032 -54.218593)
			(xy 271.003776 -54.275482) (xy 270.993108 -54.286404) (xy 270.98752 -54.316376) (xy 271.030192 -54.416452)
			(xy 271.034517 -54.42541) (xy 271.04862 -54.439405) (xy 271.066993 -54.446967) (xy 271.076928 -54.44744)
			(xy 271.09547 -54.44744) (xy 271.107294 -54.446891) (xy 271.128485 -54.436407) (xy 271.142743 -54.417548)
			(xy 271.145508 -54.406038) (xy 271.151916 -54.374659) (xy 271.171588 -54.313709) (xy 271.198754 -54.25571)
			(xy 271.232987 -54.20158) (xy 271.273743 -54.152176) (xy 271.320379 -54.108278) (xy 271.372156 -54.070582)
			(xy 271.428256 -54.039683) (xy 271.48779 -54.016071) (xy 271.549818 -54.000119) (xy 271.613357 -53.99208)
			(xy 271.677403 -53.99208) (xy 271.740942 -54.000119) (xy 271.80297 -54.016071) (xy 271.862504 -54.039683)
			(xy 271.918604 -54.070582) (xy 271.970381 -54.108278) (xy 272.017017 -54.152176) (xy 272.057773 -54.20158)
			(xy 272.092006 -54.25571) (xy 272.119172 -54.313709) (xy 272.138844 -54.374659) (xy 272.145252 -54.406038)
			(xy 272.148091 -54.417508) (xy 272.162363 -54.436303) (xy 272.183492 -54.446817) (xy 272.19529 -54.44744)
			(xy 297.540172 -54.44744) (xy 297.54877 -54.447065) (xy 297.564996 -54.44137) (xy 297.571922 -54.436264)
			(xy 297.60527 -54.410148) (xy 297.675879 -54.363348) (xy 297.75041 -54.323087) (xy 297.82826 -54.289693)
			(xy 297.908797 -54.263434) (xy 297.991369 -54.244524) (xy 298.075308 -54.233117) (xy 298.159932 -54.229304)
			(xy 298.244556 -54.233117) (xy 298.328495 -54.244524) (xy 298.411067 -54.263434) (xy 298.491604 -54.289693)
			(xy 298.569454 -54.323087) (xy 298.643985 -54.363348) (xy 298.714594 -54.410148) (xy 298.747942 -54.436264)
			(xy 298.754873 -54.441369) (xy 298.771092 -54.447097) (xy 298.779692 -54.44744) (xy 300.080172 -54.44744)
			(xy 300.08877 -54.447065) (xy 300.104996 -54.44137) (xy 300.111922 -54.436264) (xy 300.14527 -54.410148)
			(xy 300.215879 -54.363348) (xy 300.29041 -54.323087) (xy 300.36826 -54.289693) (xy 300.448797 -54.263434)
			(xy 300.531369 -54.244524) (xy 300.615308 -54.233117) (xy 300.699932 -54.229304) (xy 300.784556 -54.233117)
			(xy 300.868495 -54.244524) (xy 300.951067 -54.263434) (xy 301.031604 -54.289693) (xy 301.109454 -54.323087)
			(xy 301.183985 -54.363348) (xy 301.254594 -54.410148) (xy 301.287942 -54.436264) (xy 301.294873 -54.441369)
			(xy 301.311092 -54.447097) (xy 301.319692 -54.44744) (xy 302.620172 -54.44744) (xy 302.62877 -54.447065)
			(xy 302.644996 -54.44137) (xy 302.651922 -54.436264) (xy 302.68527 -54.410148) (xy 302.755879 -54.363348)
			(xy 302.83041 -54.323087) (xy 302.90826 -54.289693) (xy 302.988797 -54.263434) (xy 303.071369 -54.244524)
			(xy 303.155308 -54.233117) (xy 303.239932 -54.229304) (xy 303.324556 -54.233117) (xy 303.408495 -54.244524)
			(xy 303.491067 -54.263434) (xy 303.571604 -54.289693) (xy 303.649454 -54.323087) (xy 303.723985 -54.363348)
			(xy 303.794594 -54.410148) (xy 303.827942 -54.436264) (xy 303.834873 -54.441369) (xy 303.851092 -54.447097)
			(xy 303.859692 -54.44744) (xy 384.943858 -54.44744) (xy 384.953412 -54.447037) (xy 384.971168 -54.439978)
			(xy 384.978402 -54.433724) (xy 385.008675 -54.406368) (xy 385.074041 -54.357529) (xy 385.144245 -54.315943)
			(xy 385.218486 -54.282088) (xy 385.295916 -54.256349) (xy 385.375651 -54.23902) (xy 385.45678 -54.230299)
			(xy 385.497578 -54.229762) (xy 385.498086 -54.229762) (xy 385.538888 -54.230265) (xy 385.620026 -54.23896)
			(xy 385.699771 -54.256275) (xy 385.77721 -54.28201) (xy 385.851456 -54.315871) (xy 385.92166 -54.35747)
			(xy 385.987018 -54.406332) (xy 386.017262 -54.433724) (xy 386.024509 -54.439953) (xy 386.04226 -54.446996)
			(xy 386.051806 -54.44744) (xy 421.740584 -54.44744) (xy 421.750301 -54.44704) (xy 421.768342 -54.439812)
			(xy 421.782395 -54.426388) (xy 421.786812 -54.417722) (xy 421.803709 -54.381864) (xy 421.843888 -54.313529)
			(xy 421.890939 -54.24973) (xy 421.944355 -54.191156) (xy 422.003559 -54.13844) (xy 422.067913 -54.09215)
			(xy 422.136721 -54.052786) (xy 422.209242 -54.020772) (xy 422.284693 -53.996455) (xy 422.362259 -53.980096)
			(xy 422.441104 -53.971873) (xy 422.520376 -53.971873) (xy 422.599221 -53.980096) (xy 422.676787 -53.996455)
			(xy 422.752238 -54.020772) (xy 422.824759 -54.052786) (xy 422.893567 -54.09215) (xy 422.957921 -54.13844)
			(xy 423.017125 -54.191156) (xy 423.070541 -54.24973) (xy 423.117592 -54.313529) (xy 423.157771 -54.381864)
			(xy 423.174668 -54.417722) (xy 423.179085 -54.426384) (xy 423.193146 -54.439789) (xy 423.211182 -54.44701)
			(xy 423.220896 -54.44744) (xy 442.696854 -54.44744) (xy 442.706922 -54.447879) (xy 442.725521 -54.455589)
			(xy 442.732922 -54.462426) (xy 449.829682 -61.559186) (xy 449.837096 -61.566009) (xy 449.855684 -61.573739)
			(xy 449.86575 -61.574172) (xy 457.902056 -61.574172) (xy 457.912125 -61.574601) (xy 457.930724 -61.582317)
			(xy 457.938124 -61.589158) (xy 459.913482 -63.56477) (xy 459.920299 -63.572188) (xy 459.928033 -63.590773)
			(xy 459.928468 -63.600838) (xy 459.928468 -71.825358) (xy 459.928029 -71.835426) (xy 459.920319 -71.854024)
			(xy 459.913482 -71.861426) (xy 457.658978 -74.11593) (xy 457.651583 -74.122776) (xy 457.63298 -74.130492)
			(xy 457.62291 -74.130916) (xy 453.393556 -74.130916) (xy 453.383484 -74.131314) (xy 453.364886 -74.139053)
			(xy 453.357488 -74.145902) (xy 452.561198 -74.942192) (xy 452.554369 -74.949601) (xy 452.546643 -74.968193)
			(xy 452.546212 -74.97826) (xy 452.546212 -95.875348) (xy 452.545783 -95.885417) (xy 452.538067 -95.904017)
			(xy 452.531226 -95.911416) (xy 449.37045 -99.072446) (xy 449.362993 -99.079205) (xy 449.344433 -99.086926)
			(xy 449.334382 -99.087432) (xy 436.775352 -99.087432) (xy 436.764717 -99.087814) (xy 436.745252 -99.096382)
			(xy 436.73776 -99.103942) (xy 436.710653 -99.132915) (xy 436.651429 -99.185719) (xy 436.587043 -99.232089)
			(xy 436.51819 -99.271524) (xy 436.445615 -99.303598) (xy 436.370103 -99.327963) (xy 436.292469 -99.344358)
			(xy 436.213553 -99.352604) (xy 436.17388 -99.353116) (xy 436.137124 -99.352674) (xy 436.063949 -99.345634)
			(xy 435.991794 -99.331573) (xy 435.921331 -99.310622) (xy 435.853215 -99.282977) (xy 435.788081 -99.248895)
			(xy 435.757066 -99.229164) (xy 435.748614 -99.224186) (xy 435.72938 -99.220432) (xy 435.710146 -99.224186)
			(xy 435.701694 -99.229164) (xy 435.670663 -99.248864) (xy 435.605518 -99.282915) (xy 435.537401 -99.310546)
			(xy 435.466944 -99.3315) (xy 435.394799 -99.345585) (xy 435.321634 -99.352668) (xy 435.28488 -99.353116)
			(xy 435.245204 -99.35265) (xy 435.166281 -99.344415) (xy 435.088639 -99.328027) (xy 435.013121 -99.303663)
			(xy 434.940541 -99.271585) (xy 434.871687 -99.232142) (xy 434.807301 -99.185761) (xy 434.748083 -99.132941)
			(xy 434.721 -99.103942) (xy 434.713422 -99.096508) (xy 434.694009 -99.087978) (xy 434.683408 -99.087432)
			(xy 332.337918 -99.087432) (xy 332.311248 -99.10699) (xy 332.306168 -99.122992) (xy 332.293675 -99.16133)
			(xy 332.261699 -99.235357) (xy 332.222089 -99.305596) (xy 332.175288 -99.371262) (xy 332.121818 -99.431623)
			(xy 332.062276 -99.486003) (xy 331.997328 -99.533797) (xy 331.927699 -99.574469) (xy 331.854166 -99.607565)
			(xy 331.777552 -99.632717) (xy 331.69871 -99.649642) (xy 331.618523 -99.658153) (xy 331.578204 -99.658678)
			(xy 331.538294 -99.658174) (xy 331.458911 -99.649842) (xy 331.380836 -99.63325) (xy 331.304925 -99.608578)
			(xy 331.232014 -99.576098) (xy 331.197204 -99.55657) (xy 331.189309 -99.552473) (xy 331.171804 -99.549398)
			(xy 331.154299 -99.552473) (xy 331.146404 -99.55657) (xy 331.111578 -99.57606) (xy 331.03866 -99.608503)
			(xy 330.962751 -99.633151) (xy 330.884683 -99.649734) (xy 330.805309 -99.658072) (xy 330.725499 -99.658072)
			(xy 330.646125 -99.649734) (xy 330.568057 -99.633151) (xy 330.492148 -99.608503) (xy 330.41923 -99.57606)
			(xy 330.384404 -99.55657) (xy 330.376509 -99.552473) (xy 330.359004 -99.549398) (xy 330.341499 -99.552473)
			(xy 330.333604 -99.55657) (xy 330.298776 -99.576058) (xy 330.225856 -99.608503) (xy 330.149948 -99.633163)
			(xy 330.071882 -99.649768) (xy 329.99251 -99.658138) (xy 329.952604 -99.658678) (xy 329.912785 -99.658191)
			(xy 329.833582 -99.649887) (xy 329.755676 -99.633368) (xy 329.679918 -99.608815) (xy 329.607133 -99.576496)
			(xy 329.572366 -99.557078) (xy 329.563587 -99.552561) (xy 329.544034 -99.54994) (xy 329.524933 -99.554868)
			(xy 329.51674 -99.56038) (xy 329.483829 -99.584217) (xy 329.413833 -99.625506) (xy 329.339841 -99.659112)
			(xy 329.262693 -99.684655) (xy 329.183265 -99.701843) (xy 329.102459 -99.710482) (xy 329.061826 -99.711002)
			(xy 329.022655 -99.71053) (xy 328.944727 -99.70248) (xy 328.868034 -99.686483) (xy 328.793386 -99.662708)
			(xy 328.721569 -99.631405) (xy 328.65334 -99.592905) (xy 328.589417 -99.547612) (xy 328.530474 -99.496004)
			(xy 328.477133 -99.438625) (xy 328.429956 -99.37608) (xy 328.38944 -99.309028) (xy 328.356011 -99.238175)
			(xy 328.330023 -99.164268) (xy 328.3204 -99.126294) (xy 328.317169 -99.115413) (xy 328.30292 -99.097786)
			(xy 328.282458 -99.088035) (xy 328.271124 -99.087432) (xy 320.737484 -99.087432) (xy 320.726418 -99.087922)
			(xy 320.706312 -99.097162) (xy 320.691961 -99.114005) (xy 320.688462 -99.124516) (xy 320.688462 -99.12477)
			(xy 320.677403 -99.162909) (xy 320.648428 -99.236847) (xy 320.611925 -99.307374) (xy 320.568291 -99.373725)
			(xy 320.517997 -99.435182) (xy 320.461589 -99.49108) (xy 320.399677 -99.540813) (xy 320.332931 -99.583842)
			(xy 320.262075 -99.619702) (xy 320.187877 -99.648003) (xy 320.111138 -99.668441) (xy 320.032692 -99.680792)
			(xy 319.953386 -99.684925) (xy 319.87408 -99.680792) (xy 319.795634 -99.668441) (xy 319.718895 -99.648003)
			(xy 319.644697 -99.619702) (xy 319.573841 -99.583842) (xy 319.507095 -99.540813) (xy 319.445183 -99.49108)
			(xy 319.388775 -99.435182) (xy 319.338481 -99.373725) (xy 319.294847 -99.307374) (xy 319.258344 -99.236847)
			(xy 319.229369 -99.162909) (xy 319.21831 -99.12477) (xy 319.21831 -99.124516) (xy 319.214773 -99.114035)
			(xy 319.200402 -99.097247) (xy 319.180336 -99.087988) (xy 319.169288 -99.087432) (xy 304.14976 -99.087432)
			(xy 304.139687 -99.087828) (xy 304.121089 -99.095568) (xy 304.113692 -99.102418) (xy 300.670214 -102.545896)
			(xy 300.666404 -102.554024) (xy 300.64988 -102.588842) (xy 300.610749 -102.655244) (xy 300.56512 -102.71736)
			(xy 300.513457 -102.774557) (xy 300.456289 -102.826251) (xy 300.394198 -102.871915) (xy 300.327818 -102.911083)
			(xy 300.293024 -102.927658) (xy 300.284642 -102.931468) (xy 298.872442 -104.343651) (xy 326.803 -104.343651)
			(xy 326.803 -104.258929) (xy 326.811053 -104.174592) (xy 326.827087 -104.091402) (xy 326.850955 -104.010112)
			(xy 326.882443 -103.93146) (xy 326.921265 -103.856157) (xy 326.967068 -103.784885) (xy 327.019439 -103.718289)
			(xy 327.077904 -103.656974) (xy 327.141932 -103.601493) (xy 327.210944 -103.55235) (xy 327.284314 -103.50999)
			(xy 327.361379 -103.474795) (xy 327.441441 -103.447086) (xy 327.523774 -103.427112) (xy 327.607633 -103.415055)
			(xy 327.692258 -103.411024) (xy 327.776883 -103.415055) (xy 327.860742 -103.427112) (xy 327.943075 -103.447086)
			(xy 328.023137 -103.474795) (xy 328.100202 -103.50999) (xy 328.173572 -103.55235) (xy 328.242584 -103.601493)
			(xy 328.306612 -103.656974) (xy 328.365077 -103.718289) (xy 328.417448 -103.784885) (xy 328.463251 -103.856157)
			(xy 328.502073 -103.93146) (xy 328.533561 -104.010112) (xy 328.557429 -104.091402) (xy 328.573463 -104.174592)
			(xy 328.581516 -104.258929) (xy 328.58202 -104.30129) (xy 328.581516 -104.343651) (xy 328.573463 -104.427988)
			(xy 328.557429 -104.511178) (xy 328.533561 -104.592468) (xy 328.502073 -104.67112) (xy 328.463251 -104.746423)
			(xy 328.417448 -104.817695) (xy 328.365077 -104.884291) (xy 328.306612 -104.945606) (xy 328.242584 -105.001087)
			(xy 328.173572 -105.05023) (xy 328.100202 -105.09259) (xy 328.023137 -105.127785) (xy 327.943075 -105.155494)
			(xy 327.860742 -105.175468) (xy 327.776883 -105.187525) (xy 327.692258 -105.191557) (xy 327.607633 -105.187525)
			(xy 327.523774 -105.175468) (xy 327.441441 -105.155494) (xy 327.361379 -105.127785) (xy 327.284314 -105.09259)
			(xy 327.210944 -105.05023) (xy 327.141932 -105.001087) (xy 327.077904 -104.945606) (xy 327.019439 -104.884291)
			(xy 326.967068 -104.817695) (xy 326.921265 -104.746423) (xy 326.882443 -104.67112) (xy 326.850955 -104.592468)
			(xy 326.827087 -104.511178) (xy 326.811053 -104.427988) (xy 326.803 -104.343651) (xy 298.872442 -104.343651)
			(xy 278.897588 -124.318268) (xy 278.89178 -124.324493) (xy 278.884392 -124.339822) (xy 278.88311 -124.34824)
			(xy 278.88311 -124.348494) (xy 278.879334 -124.376737) (xy 278.864533 -124.43176) (xy 278.841712 -124.483968)
			(xy 278.811378 -124.532201) (xy 278.774207 -124.575385) (xy 278.731026 -124.61256) (xy 278.682796 -124.642897)
			(xy 278.630589 -124.665723) (xy 278.575568 -124.680528) (xy 278.547322 -124.684282) (xy 278.547068 -124.684282)
			(xy 278.538674 -124.685633) (xy 278.523377 -124.693029) (xy 278.517096 -124.69876) (xy 274.99564 -128.22047)
			(xy 274.988217 -128.227281) (xy 274.969635 -128.235018) (xy 274.959572 -128.235456) (xy 251.619004 -128.235456)
			(xy 251.609642 -128.235921) (xy 251.592168 -128.242646) (xy 251.578277 -128.255199) (xy 251.569823 -128.271905)
			(xy 251.568458 -128.281176) (xy 251.564097 -128.319596) (xy 251.548572 -128.39535) (xy 251.525459 -128.469144)
			(xy 251.494997 -128.540219) (xy 251.457498 -128.607847) (xy 251.413347 -128.671332) (xy 251.362997 -128.730023)
			(xy 251.306966 -128.783316) (xy 251.245829 -128.830665) (xy 251.180214 -128.871583) (xy 251.110794 -128.905651)
			(xy 251.038283 -128.932517) (xy 250.963425 -128.951908) (xy 250.886989 -128.963622) (xy 250.80976 -128.96754)
			(xy 250.732531 -128.963622) (xy 250.656095 -128.951908) (xy 250.581237 -128.932517) (xy 250.508726 -128.905651)
			(xy 250.439306 -128.871583) (xy 250.373691 -128.830665) (xy 250.312554 -128.783316) (xy 250.256523 -128.730023)
			(xy 250.206173 -128.671332) (xy 250.162022 -128.607847) (xy 250.124523 -128.540219) (xy 250.094061 -128.469144)
			(xy 250.070948 -128.39535) (xy 250.055423 -128.319596) (xy 250.051062 -128.281176) (xy 250.04972 -128.271897)
			(xy 250.041263 -128.25518) (xy 250.027366 -128.242616) (xy 250.009883 -128.235881) (xy 250.000516 -128.235456)
			(xy 235.485178 -128.235456) (xy 235.476471 -128.235755) (xy 235.46006 -128.241579) (xy 235.44656 -128.252577)
			(xy 235.441744 -128.25984) (xy 235.421049 -128.293095) (xy 235.373869 -128.355623) (xy 235.320527 -128.412984)
			(xy 235.261585 -128.464574) (xy 235.197664 -128.509849) (xy 235.129438 -128.548331) (xy 235.057626 -128.579616)
			(xy 234.982985 -128.603373) (xy 234.906301 -128.619352) (xy 234.828383 -128.627385) (xy 234.789218 -128.627886)
			(xy 234.75204 -128.627447) (xy 234.678039 -128.620196) (xy 234.605097 -128.605772) (xy 234.533906 -128.584311)
			(xy 234.465143 -128.556019) (xy 234.432094 -128.538986) (xy 234.420738 -128.533677) (xy 234.395698 -128.533677)
			(xy 234.384342 -128.538986) (xy 234.35129 -128.556012) (xy 234.282523 -128.584286) (xy 234.211332 -128.605737)
			(xy 234.138392 -128.620162) (xy 234.064394 -128.627425) (xy 234.027218 -128.627886) (xy 233.988053 -128.627396)
			(xy 233.910135 -128.619358) (xy 233.833453 -128.603375) (xy 233.758812 -128.579615) (xy 233.687001 -128.548328)
			(xy 233.618775 -128.509845) (xy 233.554854 -128.464571) (xy 233.49591 -128.412982) (xy 233.442566 -128.355623)
			(xy 233.395382 -128.293098) (xy 233.374692 -128.25984) (xy 233.369847 -128.252608) (xy 233.356344 -128.241642)
			(xy 233.339955 -128.235815) (xy 233.331258 -128.235456) (xy 219.179648 -128.235456) (xy 219.167704 -128.236074)
			(xy 219.146367 -128.246806) (xy 219.138754 -128.25603) (xy 219.114795 -128.287416) (xy 219.061384 -128.345576)
			(xy 219.00225 -128.397907) (xy 218.938026 -128.443849) (xy 218.8694 -128.48291) (xy 218.797106 -128.514673)
			(xy 218.721917 -128.538797) (xy 218.644638 -128.555025) (xy 218.566096 -128.563183) (xy 218.487132 -128.563183)
			(xy 218.40859 -128.555025) (xy 218.331311 -128.538797) (xy 218.256122 -128.514673) (xy 218.183828 -128.48291)
			(xy 218.115202 -128.443849) (xy 218.050978 -128.397907) (xy 217.991844 -128.345576) (xy 217.938433 -128.287416)
			(xy 217.914474 -128.25603) (xy 217.906833 -128.246839) (xy 217.885514 -128.236104) (xy 217.87358 -128.235456)
			(xy 216.09812 -128.235456) (xy 216.089661 -128.235782) (xy 216.073654 -128.241246) (xy 216.060314 -128.251646)
			(xy 216.055448 -128.25857) (xy 216.033232 -128.29167) (xy 215.982942 -128.353528) (xy 215.926474 -128.409803)
			(xy 215.864445 -128.459882) (xy 215.797531 -128.503218) (xy 215.726461 -128.539338) (xy 215.652012 -128.567848)
			(xy 215.574995 -128.588438) (xy 215.496251 -128.600882) (xy 215.416638 -128.605046) (xy 215.337025 -128.600882)
			(xy 215.258281 -128.588438) (xy 215.181264 -128.567848) (xy 215.106815 -128.539338) (xy 215.035745 -128.503218)
			(xy 214.968831 -128.459882) (xy 214.906802 -128.409803) (xy 214.850334 -128.353528) (xy 214.800044 -128.29167)
			(xy 214.777828 -128.25857) (xy 214.770285 -128.248287) (xy 214.74789 -128.236155) (xy 214.735156 -128.235456)
			(xy 212.291676 -128.235456) (xy 212.282661 -128.235842) (xy 212.26573 -128.242038) (xy 212.251977 -128.253695)
			(xy 212.247226 -128.261364) (xy 212.227997 -128.294729) (xy 212.183796 -128.357796) (xy 212.133461 -128.416085)
			(xy 212.077506 -128.469001) (xy 212.016501 -128.516006) (xy 211.951067 -128.556621) (xy 211.881871 -128.590431)
			(xy 211.809619 -128.617092) (xy 211.735047 -128.636332) (xy 211.658916 -128.647954) (xy 211.582 -128.651842)
			(xy 211.505084 -128.647954) (xy 211.428953 -128.636332) (xy 211.354381 -128.617092) (xy 211.282129 -128.590431)
			(xy 211.212933 -128.556621) (xy 211.147499 -128.516006) (xy 211.086494 -128.469001) (xy 211.030539 -128.416085)
			(xy 210.980204 -128.357796) (xy 210.936003 -128.294729) (xy 210.916774 -128.261364) (xy 210.912092 -128.253634)
			(xy 210.898334 -128.24193) (xy 210.881358 -128.235757) (xy 210.872324 -128.235456) (xy 206.712566 -128.235456)
			(xy 206.701156 -128.23614) (xy 206.680579 -128.246006) (xy 206.672942 -128.254506) (xy 206.65471 -128.276413)
			(xy 206.612853 -128.315096) (xy 206.565712 -128.347128) (xy 206.514333 -128.371796) (xy 206.459858 -128.388552)
			(xy 206.403497 -128.397024) (xy 206.346503 -128.397024) (xy 206.290142 -128.388552) (xy 206.235667 -128.371796)
			(xy 206.184288 -128.347128) (xy 206.137147 -128.315096) (xy 206.09529 -128.276413) (xy 206.077058 -128.254506)
			(xy 206.069513 -128.245884) (xy 206.04888 -128.235973) (xy 206.037434 -128.235456) (xy 204.132434 -128.235456)
			(xy 204.10551 -128.255268) (xy 204.100684 -128.271524) (xy 204.088872 -128.308587) (xy 204.058718 -128.3803)
			(xy 204.021421 -128.448571) (xy 203.977367 -128.51269) (xy 203.927015 -128.571991) (xy 203.870887 -128.625858)
			(xy 203.809567 -128.673731) (xy 203.743692 -128.715113) (xy 203.673947 -128.749574) (xy 203.601055 -128.776755)
			(xy 203.525775 -128.796375) (xy 203.448889 -128.808228) (xy 203.371196 -128.812193) (xy 203.293503 -128.808228)
			(xy 203.216617 -128.796375) (xy 203.141337 -128.776755) (xy 203.068445 -128.749574) (xy 202.9987 -128.715113)
			(xy 202.932825 -128.673731) (xy 202.871505 -128.625858) (xy 202.815377 -128.571991) (xy 202.765025 -128.51269)
			(xy 202.720971 -128.448571) (xy 202.683674 -128.3803) (xy 202.65352 -128.308587) (xy 202.641708 -128.271524)
			(xy 202.636882 -128.255268) (xy 202.609958 -128.235456) (xy 198.199756 -128.235456) (xy 198.187935 -128.236028)
			(xy 198.166745 -128.246501) (xy 198.152485 -128.265351) (xy 198.149718 -128.276858) (xy 198.142318 -128.313895)
			(xy 198.121217 -128.386419) (xy 198.093047 -128.456501) (xy 198.058084 -128.523453) (xy 198.016672 -128.58662)
			(xy 197.969216 -128.645381) (xy 197.916182 -128.699162) (xy 197.858089 -128.747434) (xy 197.795507 -128.789725)
			(xy 197.729049 -128.825619) (xy 197.659368 -128.854766) (xy 197.587146 -128.876879) (xy 197.513091 -128.891741)
			(xy 197.43793 -128.899207) (xy 197.400164 -128.899666) (xy 197.361243 -128.899143) (xy 197.283807 -128.891208)
			(xy 197.207583 -128.875426) (xy 197.133363 -128.85196) (xy 197.06192 -128.821054) (xy 196.993997 -128.78303)
			(xy 196.930302 -128.738284) (xy 196.871497 -128.687282) (xy 196.818195 -128.630554) (xy 196.770949 -128.56869)
			(xy 196.730252 -128.502335) (xy 196.696527 -128.432178) (xy 196.682868 -128.39573) (xy 196.67823 -128.384803)
			(xy 196.661017 -128.368504) (xy 196.649848 -128.364488) (xy 196.608205 -128.35098) (xy 196.528086 -128.315682)
			(xy 196.45254 -128.271434) (xy 196.417184 -128.245616) (xy 196.410446 -128.240944) (xy 196.394898 -128.235765)
			(xy 196.386704 -128.235456) (xy 191.933068 -128.235456) (xy 191.906398 -128.255014) (xy 191.901318 -128.271016)
			(xy 191.889278 -128.30775) (xy 191.85879 -128.378791) (xy 191.82127 -128.446384) (xy 191.777105 -128.509834)
			(xy 191.726748 -128.568491) (xy 191.670715 -128.621752) (xy 191.609582 -128.669071) (xy 191.543975 -128.709963)
			(xy 191.474567 -128.744008) (xy 191.402072 -128.770857) (xy 191.327232 -128.790233) (xy 191.250816 -128.80194)
			(xy 191.173608 -128.805855) (xy 191.0964 -128.80194) (xy 191.019984 -128.790233) (xy 190.945144 -128.770857)
			(xy 190.872649 -128.744008) (xy 190.803241 -128.709963) (xy 190.737634 -128.669071) (xy 190.676501 -128.621752)
			(xy 190.620468 -128.568491) (xy 190.570111 -128.509834) (xy 190.525946 -128.446384) (xy 190.488426 -128.378791)
			(xy 190.457938 -128.30775) (xy 190.445898 -128.271016) (xy 190.440818 -128.255014) (xy 190.414148 -128.235456)
			(xy 173.6344 -128.235456) (xy 173.605444 -128.262126) (xy 173.603666 -128.281684) (xy 173.599771 -128.320511)
			(xy 173.585058 -128.39715) (xy 173.562594 -128.471885) (xy 173.532616 -128.543935) (xy 173.495436 -128.612547)
			(xy 173.451444 -128.677003) (xy 173.401098 -128.736629) (xy 173.344927 -128.790802) (xy 173.283517 -128.838955)
			(xy 173.21751 -128.880584) (xy 173.147597 -128.915255) (xy 173.074508 -128.942605) (xy 172.999009 -128.962347)
			(xy 172.921888 -128.974276) (xy 172.843952 -128.978266) (xy 172.766016 -128.974276) (xy 172.688895 -128.962347)
			(xy 172.613396 -128.942605) (xy 172.540307 -128.915255) (xy 172.470394 -128.880584) (xy 172.404387 -128.838955)
			(xy 172.342977 -128.790802) (xy 172.286806 -128.736629) (xy 172.23646 -128.677003) (xy 172.192468 -128.612547)
			(xy 172.155288 -128.543935) (xy 172.12531 -128.471885) (xy 172.102846 -128.39715) (xy 172.088133 -128.320511)
			(xy 172.084238 -128.281684) (xy 172.08246 -128.262126) (xy 172.053504 -128.235456) (xy 163.93287 -128.235456)
			(xy 163.922348 -128.235951) (xy 163.903056 -128.244341) (xy 163.895532 -128.251712) (xy 163.868483 -128.280256)
			(xy 163.809444 -128.332209) (xy 163.745372 -128.37781) (xy 163.676948 -128.416576) (xy 163.604897 -128.448095)
			(xy 163.529986 -128.472031) (xy 163.453009 -128.488132) (xy 163.374783 -128.496225) (xy 163.296141 -128.496225)
			(xy 163.217915 -128.488132) (xy 163.140938 -128.472031) (xy 163.066027 -128.448095) (xy 162.993976 -128.416576)
			(xy 162.925552 -128.37781) (xy 162.86148 -128.332209) (xy 162.802441 -128.280256) (xy 162.775392 -128.251712)
			(xy 162.767863 -128.244354) (xy 162.74857 -128.235973) (xy 162.738054 -128.235456) (xy 161.384488 -128.235456)
			(xy 161.374417 -128.235049) (xy 161.355818 -128.227317) (xy 161.34842 -128.22047) (xy 156.031438 -122.903234)
			(xy 156.024015 -122.896423) (xy 156.005433 -122.888685) (xy 155.99537 -122.888248) (xy 152.56764 -122.888248)
			(xy 152.558694 -122.888571) (xy 152.541907 -122.894765) (xy 152.528265 -122.906343) (xy 152.519424 -122.9219)
			(xy 152.517602 -122.930666) (xy 152.517602 -122.93092) (xy 152.510989 -122.968756) (xy 152.491143 -123.042961)
			(xy 152.463936 -123.114795) (xy 152.429643 -123.183528) (xy 152.388612 -123.248465) (xy 152.341259 -123.308946)
			(xy 152.288065 -123.364359) (xy 152.229568 -123.414143) (xy 152.166361 -123.457791) (xy 152.099086 -123.494863)
			(xy 152.028423 -123.524981) (xy 151.95509 -123.547841) (xy 151.879831 -123.563211) (xy 151.803407 -123.570935)
			(xy 151.726593 -123.570935) (xy 151.650169 -123.563211) (xy 151.57491 -123.547841) (xy 151.501577 -123.524981)
			(xy 151.430914 -123.494863) (xy 151.363639 -123.457791) (xy 151.300432 -123.414143) (xy 151.241935 -123.364359)
			(xy 151.188741 -123.308946) (xy 151.141388 -123.248465) (xy 151.100357 -123.183528) (xy 151.066064 -123.114795)
			(xy 151.038857 -123.042961) (xy 151.019011 -122.968756) (xy 151.012398 -122.93092) (xy 151.012398 -122.930666)
			(xy 151.010578 -122.921897) (xy 151.001759 -122.906325) (xy 150.988111 -122.89475) (xy 150.971308 -122.888592)
			(xy 150.96236 -122.888248) (xy 142.479776 -122.888248) (xy 142.467925 -122.888836) (xy 142.446734 -122.899452)
			(xy 142.439136 -122.908568) (xy 142.415181 -122.93982) (xy 142.361811 -122.997722) (xy 142.302756 -123.049815)
			(xy 142.238646 -123.095542) (xy 142.170164 -123.134418) (xy 142.098039 -123.166027) (xy 142.023041 -123.190033)
			(xy 141.945967 -123.206181) (xy 141.86764 -123.214298) (xy 141.788892 -123.214298) (xy 141.710565 -123.206181)
			(xy 141.633491 -123.190033) (xy 141.558493 -123.166027) (xy 141.486368 -123.134418) (xy 141.417886 -123.095542)
			(xy 141.353776 -123.049815) (xy 141.294721 -122.997722) (xy 141.241351 -122.93982) (xy 141.217396 -122.908568)
			(xy 141.209804 -122.899451) (xy 141.188605 -122.888859) (xy 141.176756 -122.888248) (xy 130.331718 -122.888248)
			(xy 130.321648 -122.887827) (xy 130.303049 -122.880105) (xy 130.29565 -122.873262) (xy 103.795576 -96.373442)
			(xy 103.788173 -96.366605) (xy 103.769576 -96.358882) (xy 103.759508 -96.358456) (xy 65.444878 -96.358456)
			(xy 65.418716 -96.377252) (xy 65.413382 -96.392746) (xy 65.400132 -96.42985) (xy 65.366965 -96.501322)
			(xy 65.326603 -96.568993) (xy 65.279479 -96.632141) (xy 65.226095 -96.690092) (xy 65.167019 -96.74223)
			(xy 65.102881 -96.787998) (xy 65.034366 -96.826908) (xy 64.962203 -96.858545) (xy 64.887163 -96.882573)
			(xy 64.810046 -96.898734) (xy 64.731672 -96.906857) (xy 64.692276 -96.90735) (xy 64.651247 -96.906808)
			(xy 64.569664 -96.898) (xy 64.4895 -96.88048) (xy 64.411681 -96.854448) (xy 64.33711 -96.820207)
			(xy 64.266648 -96.778153) (xy 64.201112 -96.728772) (xy 64.170814 -96.701102) (xy 64.163496 -96.694862)
			(xy 64.145623 -96.687807) (xy 64.136016 -96.687386) (xy 64.105536 -96.687386) (xy 64.095922 -96.687792)
			(xy 64.078032 -96.694828) (xy 64.070738 -96.701102) (xy 64.040423 -96.728753) (xy 63.974886 -96.778127)
			(xy 63.904425 -96.820177) (xy 63.829857 -96.854418) (xy 63.752042 -96.880454) (xy 63.671882 -96.897983)
			(xy 63.590303 -96.906802) (xy 63.549276 -96.90735) (xy 63.511035 -96.906847) (xy 63.434941 -96.899153)
			(xy 63.36 -96.883875) (xy 63.286967 -96.861167) (xy 63.251588 -96.846644) (xy 63.241995 -96.843091)
			(xy 63.221557 -96.843091) (xy 63.211964 -96.846644) (xy 63.17658 -96.861153) (xy 63.103546 -96.883859)
			(xy 63.028608 -96.899143) (xy 62.952516 -96.906853) (xy 62.914276 -96.90735) (xy 62.874343 -96.906808)
			(xy 62.794915 -96.898458) (xy 62.716794 -96.881851) (xy 62.640838 -96.85717) (xy 62.567877 -96.824685)
			(xy 62.498711 -96.784752) (xy 62.434098 -96.737808) (xy 62.374745 -96.684368) (xy 62.321303 -96.625016)
			(xy 62.274358 -96.560404) (xy 62.234423 -96.49124) (xy 62.201936 -96.418279) (xy 62.177253 -96.342323)
			(xy 62.160645 -96.264203) (xy 62.152293 -96.184775) (xy 62.151768 -96.144842) (xy 62.152166 -96.110552)
			(xy 62.15835 -96.042252) (xy 62.170655 -95.974786) (xy 62.179454 -95.941642) (xy 62.179454 -95.941388)
			(xy 62.18145 -95.932684) (xy 62.179998 -95.914899) (xy 62.172539 -95.898689) (xy 62.1665 -95.892112)
			(xy 57.164478 -90.890344) (xy 57.157661 -90.882926) (xy 57.149929 -90.86434) (xy 57.149492 -90.854276)
			(xy 3.523996 -90.854276) (xy 3.523996 -105.457244) (xy 11.331956 -105.457244) (xy 11.331956 -105.456736)
			(xy 11.332424 -105.418096) (xy 11.340242 -105.341211) (xy 11.355792 -105.265511) (xy 11.378914 -105.19177)
			(xy 11.409372 -105.120744) (xy 11.446853 -105.05316) (xy 11.490973 -104.989712) (xy 11.541281 -104.931048)
			(xy 11.597261 -104.87777) (xy 11.65834 -104.830423) (xy 11.690858 -104.809544) (xy 11.700548 -104.802778)
			(xy 11.712868 -104.782644) (xy 11.71448 -104.770936) (xy 11.717264 -104.74406) (xy 11.729441 -104.691418)
			(xy 11.748916 -104.641018) (xy 11.7753 -104.593867) (xy 11.808067 -104.550905) (xy 11.846563 -104.51299)
			(xy 11.890018 -104.480879) (xy 11.937565 -104.455214) (xy 11.988255 -104.436507) (xy 12.041075 -104.425131)
			(xy 12.094972 -104.421314) (xy 12.148869 -104.425131) (xy 12.201689 -104.436507) (xy 12.252379 -104.455214)
			(xy 12.299926 -104.480879) (xy 12.343381 -104.51299) (xy 12.381877 -104.550905) (xy 12.414644 -104.593867)
			(xy 12.441028 -104.641018) (xy 12.453737 -104.673908) (xy 15.191232 -104.673908) (xy 15.191232 -104.6734)
			(xy 15.191695 -104.634324) (xy 15.199684 -104.556582) (xy 15.215579 -104.480064) (xy 15.239212 -104.405571)
			(xy 15.270336 -104.333885) (xy 15.308626 -104.265756) (xy 15.353679 -104.201897) (xy 15.405024 -104.142979)
			(xy 15.462123 -104.089619) (xy 15.524378 -104.042374) (xy 15.5575 -104.021636) (xy 15.566798 -104.015228)
			(xy 15.579196 -103.996392) (xy 15.581376 -103.985314) (xy 15.585608 -103.958266) (xy 15.600787 -103.905666)
			(xy 15.623323 -103.855773) (xy 15.652753 -103.80961) (xy 15.688475 -103.768124) (xy 15.729756 -103.732165)
			(xy 15.775749 -103.702471) (xy 15.825512 -103.67965) (xy 15.878024 -103.664169) (xy 15.932209 -103.656348)
			(xy 15.959582 -103.655876) (xy 15.98727 -103.656456) (xy 16.042064 -103.664455) (xy 16.095128 -103.680286)
			(xy 16.145348 -103.703619) (xy 16.19167 -103.733963) (xy 16.233121 -103.770682) (xy 16.268831 -103.813004)
			(xy 16.298052 -103.860042) (xy 16.32017 -103.910808) (xy 16.334721 -103.964238) (xy 16.33855 -103.991664)
			(xy 16.340492 -104.002796) (xy 16.352478 -104.021915) (xy 16.361664 -104.028494) (xy 16.39393 -104.049387)
			(xy 16.45448 -104.096751) (xy 16.509958 -104.149967) (xy 16.5598 -104.208494) (xy 16.603501 -104.271739)
			(xy 16.640618 -104.339059) (xy 16.670773 -104.409772) (xy 16.693662 -104.48316) (xy 16.709051 -104.558478)
			(xy 16.716785 -104.634963) (xy 16.717264 -104.6734) (xy 16.716727 -104.714986) (xy 16.707666 -104.797664)
			(xy 16.689663 -104.878866) (xy 16.662932 -104.957626) (xy 16.62779 -105.03301) (xy 16.584653 -105.104123)
			(xy 16.559784 -105.137458) (xy 16.553403 -105.146633) (xy 16.548589 -105.168437) (xy 16.553434 -105.190234)
			(xy 16.559784 -105.199434) (xy 16.584672 -105.232763) (xy 16.627841 -105.30387) (xy 16.663019 -105.37925)
			(xy 16.689789 -105.45801) (xy 16.707833 -105.539215) (xy 16.716937 -105.6219) (xy 16.717518 -105.663492)
			(xy 16.717518 -105.664) (xy 16.717009 -105.704049) (xy 16.708618 -105.783708) (xy 16.691928 -105.862048)
			(xy 16.667123 -105.93821) (xy 16.634477 -106.011354) (xy 16.594348 -106.080675) (xy 16.547177 -106.145411)
			(xy 16.493485 -106.20485) (xy 16.433861 -106.258337) (xy 16.368962 -106.305283) (xy 16.334486 -106.32567)
			(xy 16.334994 -106.343196) (xy 16.334994 -106.343704) (xy 16.334505 -106.370961) (xy 16.326708 -106.424916)
			(xy 16.311316 -106.477214) (xy 16.288642 -106.52679) (xy 16.259147 -106.572637) (xy 16.22343 -106.613823)
			(xy 16.182219 -106.64951) (xy 16.136351 -106.678972) (xy 16.086758 -106.701611) (xy 16.03445 -106.716966)
			(xy 15.98049 -106.724724) (xy 15.953232 -106.725212) (xy 15.925966 -106.724646) (xy 15.871988 -106.71689)
			(xy 15.819663 -106.701531) (xy 15.770056 -106.678882) (xy 15.724177 -106.649404) (xy 15.68296 -106.613698)
			(xy 15.647245 -106.572489) (xy 15.617757 -106.526616) (xy 15.595097 -106.477014) (xy 15.579727 -106.424693)
			(xy 15.57196 -106.370716) (xy 15.57147 -106.34345) (xy 15.571978 -106.324146) (xy 15.537713 -106.303696)
			(xy 15.473213 -106.256709) (xy 15.41397 -106.203246) (xy 15.360632 -106.14389) (xy 15.313783 -106.07929)
			(xy 15.273933 -106.010152) (xy 15.241519 -105.937232) (xy 15.216895 -105.861326) (xy 15.200329 -105.783265)
			(xy 15.192003 -105.7039) (xy 15.191486 -105.664) (xy 15.192013 -105.622413) (xy 15.201074 -105.539735)
			(xy 15.219078 -105.458533) (xy 15.245811 -105.379772) (xy 15.280956 -105.304389) (xy 15.324095 -105.233277)
			(xy 15.348966 -105.199942) (xy 15.355352 -105.190768) (xy 15.360171 -105.168963) (xy 15.355321 -105.147165)
			(xy 15.348966 -105.137966) (xy 15.324085 -105.104632) (xy 15.280914 -105.033527) (xy 15.245734 -104.958148)
			(xy 15.218962 -104.879389) (xy 15.200917 -104.798185) (xy 15.191813 -104.7155) (xy 15.191232 -104.673908)
			(xy 12.453737 -104.673908) (xy 12.460503 -104.691418) (xy 12.47268 -104.74406) (xy 12.475464 -104.770936)
			(xy 12.477095 -104.782635) (xy 12.489417 -104.802758) (xy 12.499086 -104.809544) (xy 12.531623 -104.830393)
			(xy 12.592702 -104.877742) (xy 12.648682 -104.931023) (xy 12.698988 -104.98969) (xy 12.743106 -105.053143)
			(xy 12.780583 -105.12073) (xy 12.811035 -105.19176) (xy 12.834151 -105.265504) (xy 12.849693 -105.341208)
			(xy 12.857502 -105.418095) (xy 12.857988 -105.456736) (xy 12.857411 -105.498321) (xy 12.848357 -105.580998)
			(xy 12.830362 -105.662198) (xy 12.803638 -105.740958) (xy 12.768503 -105.816343) (xy 12.725374 -105.887457)
			(xy 12.700508 -105.920794) (xy 12.694182 -105.930003) (xy 12.689347 -105.951786) (xy 12.69417 -105.973571)
			(xy 12.700508 -105.98277) (xy 12.725402 -106.016095) (xy 12.768572 -106.087202) (xy 12.803751 -106.162583)
			(xy 12.83052 -106.241344) (xy 12.848562 -106.322549) (xy 12.857663 -106.405236) (xy 12.858242 -106.446828)
			(xy 12.858242 -106.447336) (xy 12.857752 -106.485976) (xy 12.849937 -106.56286) (xy 12.83439 -106.63856)
			(xy 12.81127 -106.7123) (xy 12.780815 -106.783326) (xy 12.743337 -106.85091) (xy 12.699218 -106.914359)
			(xy 12.648912 -106.973023) (xy 12.592934 -107.026302) (xy 12.531857 -107.073649) (xy 12.49934 -107.094528)
			(xy 12.489661 -107.101307) (xy 12.477335 -107.121431) (xy 12.475718 -107.133136) (xy 12.472934 -107.160012)
			(xy 12.460757 -107.212654) (xy 12.441282 -107.263054) (xy 12.414898 -107.310205) (xy 12.382131 -107.353167)
			(xy 12.343635 -107.391082) (xy 12.30018 -107.423193) (xy 12.252633 -107.448858) (xy 12.201943 -107.467565)
			(xy 12.149123 -107.478941) (xy 12.095226 -107.482758) (xy 12.041329 -107.478941) (xy 11.988509 -107.467565)
			(xy 11.937819 -107.448858) (xy 11.890272 -107.423193) (xy 11.846817 -107.391082) (xy 11.808321 -107.353167)
			(xy 11.775554 -107.310205) (xy 11.74917 -107.263054) (xy 11.729695 -107.212654) (xy 11.717518 -107.160012)
			(xy 11.714734 -107.133136) (xy 11.713119 -107.121433) (xy 11.700786 -107.101312) (xy 11.691112 -107.094528)
			(xy 11.658597 -107.073646) (xy 11.597516 -107.026302) (xy 11.541534 -106.973026) (xy 11.491226 -106.914363)
			(xy 11.447106 -106.850914) (xy 11.409627 -106.783331) (xy 11.379172 -106.712304) (xy 11.356054 -106.638562)
			(xy 11.340509 -106.562861) (xy 11.332698 -106.485976) (xy 11.33221 -106.447336) (xy 11.332772 -106.40575)
			(xy 11.341829 -106.323073) (xy 11.359827 -106.241873) (xy 11.386554 -106.163113) (xy 11.421692 -106.087728)
			(xy 11.464823 -106.016614) (xy 11.48969 -105.983278) (xy 11.496041 -105.974084) (xy 11.500868 -105.952292)
			(xy 11.496034 -105.930501) (xy 11.48969 -105.921302) (xy 11.464829 -105.887953) (xy 11.421654 -105.816852)
			(xy 11.386471 -105.741476) (xy 11.359696 -105.66272) (xy 11.341647 -105.581518) (xy 11.332539 -105.498835)
			(xy 11.331956 -105.457244) (xy 3.523996 -105.457244) (xy 3.523996 -108.91672) (xy 10.911355 -108.91672)
			(xy 10.915267 -108.839581) (xy 10.926963 -108.763233) (xy 10.946323 -108.68846) (xy 10.973148 -108.616029)
			(xy 11.007163 -108.546684) (xy 11.04802 -108.481136) (xy 11.095298 -108.420058) (xy 11.148513 -108.364076)
			(xy 11.207118 -108.313765) (xy 11.270513 -108.269641) (xy 11.338046 -108.232157) (xy 11.409025 -108.201698)
			(xy 11.482721 -108.178575) (xy 11.558379 -108.163027) (xy 11.635221 -108.155213) (xy 11.67384 -108.154724)
			(xy 11.716531 -108.155337) (xy 11.801378 -108.164874) (xy 11.884631 -108.183824) (xy 11.965247 -108.211951)
			(xy 12.042218 -108.248902) (xy 12.078716 -108.271056) (xy 12.086972 -108.27577) (xy 12.10564 -108.279297)
			(xy 12.124308 -108.27577) (xy 12.132564 -108.271056) (xy 12.169057 -108.248889) (xy 12.246018 -108.211905)
			(xy 12.326634 -108.183763) (xy 12.409892 -108.164816) (xy 12.494746 -108.155302) (xy 12.53744 -108.154724)
			(xy 12.57606 -108.155205) (xy 12.652903 -108.163019) (xy 12.728561 -108.178567) (xy 12.802258 -108.20169)
			(xy 12.873238 -108.23215) (xy 12.940772 -108.269634) (xy 13.004167 -108.313759) (xy 13.062773 -108.36407)
			(xy 13.115988 -108.420053) (xy 13.163267 -108.481132) (xy 13.204124 -108.54668) (xy 13.238139 -108.616026)
			(xy 13.264965 -108.688458) (xy 13.284325 -108.763231) (xy 13.296021 -108.83958) (xy 13.299934 -108.91672)
			(xy 13.296021 -108.99386) (xy 13.284325 -109.070209) (xy 13.264965 -109.144982) (xy 13.238139 -109.217414)
			(xy 13.204124 -109.28676) (xy 13.163267 -109.352308) (xy 13.115988 -109.413387) (xy 13.105215 -109.42472)
			(xy 14.711428 -109.42472) (xy 14.71534 -109.347579) (xy 14.727037 -109.271229) (xy 14.746397 -109.196454)
			(xy 14.773223 -109.124022) (xy 14.80724 -109.054675) (xy 14.848097 -108.989126) (xy 14.895377 -108.928046)
			(xy 14.948593 -108.872063) (xy 15.0072 -108.82175) (xy 15.070596 -108.777626) (xy 15.138131 -108.740141)
			(xy 15.209112 -108.709681) (xy 15.28281 -108.686558) (xy 15.35847 -108.67101) (xy 15.435314 -108.663196)
			(xy 15.473934 -108.662724) (xy 15.515549 -108.663267) (xy 15.598284 -108.672338) (xy 15.679539 -108.690368)
			(xy 15.758345 -108.717142) (xy 15.833766 -108.752342) (xy 15.904904 -108.795549) (xy 15.938246 -108.820458)
			(xy 15.947436 -108.826826) (xy 15.969234 -108.831681) (xy 15.991032 -108.826826) (xy 16.000222 -108.820458)
			(xy 16.033551 -108.795531) (xy 16.104692 -108.752329) (xy 16.180116 -108.717134) (xy 16.258925 -108.690366)
			(xy 16.340182 -108.672342) (xy 16.422918 -108.663279) (xy 16.464534 -108.662724) (xy 16.503154 -108.663205)
			(xy 16.579996 -108.67102) (xy 16.655654 -108.686568) (xy 16.729351 -108.709691) (xy 16.80033 -108.740151)
			(xy 16.867864 -108.777636) (xy 16.931259 -108.82176) (xy 16.989864 -108.872072) (xy 17.043079 -108.928054)
			(xy 17.090358 -108.989133) (xy 17.131214 -109.054682) (xy 17.16523 -109.124027) (xy 17.192055 -109.196458)
			(xy 17.211415 -109.271232) (xy 17.223111 -109.34758) (xy 17.227024 -109.42472) (xy 17.223111 -109.50186)
			(xy 17.211415 -109.578208) (xy 17.192055 -109.652982) (xy 17.16523 -109.725413) (xy 17.131214 -109.794758)
			(xy 17.090358 -109.860307) (xy 17.043079 -109.921386) (xy 16.989864 -109.977368) (xy 16.931259 -110.02768)
			(xy 16.867864 -110.071804) (xy 16.80033 -110.109289) (xy 16.729351 -110.139749) (xy 16.655654 -110.162872)
			(xy 16.579996 -110.17842) (xy 16.503154 -110.186235) (xy 16.464534 -110.186724) (xy 16.422919 -110.186154)
			(xy 16.340185 -110.17709) (xy 16.258931 -110.159066) (xy 16.180124 -110.132297) (xy 16.104702 -110.097101)
			(xy 16.033565 -110.053897) (xy 16.000222 -110.02899) (xy 15.991032 -110.022622) (xy 15.969234 -110.017767)
			(xy 15.947436 -110.022622) (xy 15.938246 -110.02899) (xy 15.904889 -110.053878) (xy 15.833755 -110.097087)
			(xy 15.758338 -110.132288) (xy 15.679533 -110.159064) (xy 15.598281 -110.177095) (xy 15.515548 -110.186166)
			(xy 15.473934 -110.186724) (xy 15.435314 -110.186244) (xy 15.35847 -110.17843) (xy 15.28281 -110.162882)
			(xy 15.209112 -110.139759) (xy 15.138131 -110.109299) (xy 15.070596 -110.071814) (xy 15.0072 -110.02769)
			(xy 14.948593 -109.977377) (xy 14.895377 -109.921394) (xy 14.848097 -109.860314) (xy 14.80724 -109.794765)
			(xy 14.773223 -109.725418) (xy 14.746397 -109.652986) (xy 14.727037 -109.578211) (xy 14.71534 -109.501861)
			(xy 14.711428 -109.42472) (xy 13.105215 -109.42472) (xy 13.062773 -109.46937) (xy 13.004167 -109.519681)
			(xy 12.940772 -109.563806) (xy 12.873238 -109.60129) (xy 12.802258 -109.63175) (xy 12.728561 -109.654873)
			(xy 12.652903 -109.670421) (xy 12.57606 -109.678235) (xy 12.53744 -109.678724) (xy 12.494749 -109.678113)
			(xy 12.409902 -109.668574) (xy 12.32665 -109.649623) (xy 12.246034 -109.621496) (xy 12.169062 -109.584546)
			(xy 12.132564 -109.562392) (xy 12.124308 -109.557678) (xy 12.10564 -109.554151) (xy 12.086972 -109.557678)
			(xy 12.078716 -109.562392) (xy 12.042225 -109.584562) (xy 11.965263 -109.621546) (xy 11.884647 -109.649688)
			(xy 11.801389 -109.668635) (xy 11.716534 -109.678147) (xy 11.67384 -109.678724) (xy 11.635221 -109.678227)
			(xy 11.558379 -109.670413) (xy 11.482721 -109.654865) (xy 11.409025 -109.631742) (xy 11.338046 -109.601283)
			(xy 11.270513 -109.563799) (xy 11.207118 -109.519675) (xy 11.148513 -109.469364) (xy 11.095298 -109.413382)
			(xy 11.04802 -109.352304) (xy 11.007163 -109.286756) (xy 10.973148 -109.217411) (xy 10.946323 -109.14498)
			(xy 10.926963 -109.070207) (xy 10.915267 -108.993859) (xy 10.911355 -108.91672) (xy 3.523996 -108.91672)
			(xy 3.523996 -114.706908) (xy 10.87247 -114.706908) (xy 10.87247 -114.706654) (xy 10.87298 -114.66817)
			(xy 10.880745 -114.591595) (xy 10.896173 -114.516189) (xy 10.919107 -114.442718) (xy 10.949314 -114.371925)
			(xy 10.986488 -114.30453) (xy 11.030251 -114.241214) (xy 11.054842 -114.211608) (xy 11.062165 -114.20185)
			(xy 11.067616 -114.17811) (xy 11.065256 -114.166142) (xy 11.059881 -114.143214) (xy 11.054145 -114.096471)
			(xy 11.053826 -114.072924) (xy 11.054324 -114.045654) (xy 11.062082 -113.991669) (xy 11.077445 -113.939338)
			(xy 11.100099 -113.889726) (xy 11.129583 -113.843842) (xy 11.165297 -113.802622) (xy 11.206513 -113.766904)
			(xy 11.252394 -113.737416) (xy 11.302004 -113.714758) (xy 11.354334 -113.69939) (xy 11.408318 -113.691626)
			(xy 11.435588 -113.691162) (xy 11.464348 -113.691607) (xy 11.521219 -113.700227) (xy 11.57615 -113.71729)
			(xy 11.627897 -113.742408) (xy 11.675284 -113.775011) (xy 11.717239 -113.814361) (xy 11.75281 -113.859564)
			(xy 11.781189 -113.909596) (xy 11.79195 -113.936272) (xy 11.796971 -113.947373) (xy 11.815142 -113.963552)
			(xy 11.826748 -113.96726) (xy 11.86443 -113.977473) (xy 11.937662 -114.004548) (xy 12.007754 -114.038944)
			(xy 12.041124 -114.059208) (xy 12.04938 -114.063922) (xy 12.068048 -114.067449) (xy 12.086716 -114.063922)
			(xy 12.094972 -114.059208) (xy 12.128342 -114.038941) (xy 12.198427 -114.00453) (xy 12.271662 -113.97746)
			(xy 12.309348 -113.96726) (xy 12.320954 -113.963549) (xy 12.339127 -113.947374) (xy 12.344146 -113.936272)
			(xy 12.354927 -113.909611) (xy 12.383331 -113.859608) (xy 12.418914 -113.814432) (xy 12.460871 -113.775104)
			(xy 12.508252 -113.742514) (xy 12.559985 -113.7174) (xy 12.6149 -113.70033) (xy 12.671755 -113.69169)
			(xy 12.700508 -113.691162) (xy 12.72778 -113.691594) (xy 12.78177 -113.699358) (xy 12.834104 -113.714726)
			(xy 12.883719 -113.737387) (xy 12.929604 -113.766877) (xy 12.970824 -113.802598) (xy 13.006542 -113.843822)
			(xy 13.036029 -113.889709) (xy 13.058685 -113.939326) (xy 13.074049 -113.991662) (xy 13.081808 -114.045652)
			(xy 13.08227 -114.072924) (xy 13.081951 -114.096471) (xy 13.076219 -114.143215) (xy 13.07084 -114.166142)
			(xy 13.068475 -114.178109) (xy 13.07393 -114.201851) (xy 13.081254 -114.211608) (xy 13.105842 -114.241217)
			(xy 13.149611 -114.30453) (xy 13.18679 -114.371924) (xy 13.217001 -114.442716) (xy 13.239938 -114.516187)
			(xy 13.255368 -114.591594) (xy 13.263134 -114.66817) (xy 13.263626 -114.706654) (xy 13.263626 -114.706908)
			(xy 13.263062 -114.746907) (xy 13.2547 -114.826467) (xy 13.238067 -114.904717) (xy 13.213347 -114.980799)
			(xy 13.180809 -115.053882) (xy 13.140811 -115.123163) (xy 13.093791 -115.187883) (xy 13.040263 -115.247335)
			(xy 12.980814 -115.300865) (xy 12.916096 -115.347889) (xy 12.846817 -115.387891) (xy 12.773737 -115.420432)
			(xy 12.697655 -115.445157) (xy 12.619406 -115.461793) (xy 12.539847 -115.47016) (xy 12.499848 -115.470686)
			(xy 12.457159 -115.470054) (xy 12.372317 -115.460497) (xy 12.28907 -115.441542) (xy 12.208454 -115.413424)
			(xy 12.131476 -115.376494) (xy 12.094972 -115.354354) (xy 12.086711 -115.349658) (xy 12.068048 -115.34615)
			(xy 12.049385 -115.349658) (xy 12.041124 -115.354354) (xy 12.004617 -115.376492) (xy 11.927645 -115.413439)
			(xy 11.847031 -115.441568) (xy 11.763782 -115.460527) (xy 11.678938 -115.47008) (xy 11.636248 -115.470686)
			(xy 11.596248 -115.470127) (xy 11.516685 -115.461769) (xy 11.438432 -115.445141) (xy 11.362346 -115.420423)
			(xy 11.28926 -115.387888) (xy 11.219976 -115.347891) (xy 11.155252 -115.30087) (xy 11.095798 -115.247342)
			(xy 11.042265 -115.187892) (xy 10.99524 -115.123171) (xy 10.955238 -115.05389) (xy 10.922697 -114.980807)
			(xy 10.897974 -114.904722) (xy 10.881339 -114.82647) (xy 10.872976 -114.746908) (xy 10.87247 -114.706908)
			(xy 3.523996 -114.706908) (xy 3.523996 -133.480302) (xy 19.798792 -133.480302) (xy 19.799341 -133.438687)
			(xy 19.808409 -133.355951) (xy 19.826436 -133.274697) (xy 19.85321 -133.19589) (xy 19.88841 -133.120469)
			(xy 19.931617 -133.049332) (xy 19.956526 -133.01599) (xy 19.962893 -133.006799) (xy 19.967749 -132.985002)
			(xy 19.962894 -132.963204) (xy 19.956526 -132.954014) (xy 19.931625 -132.920666) (xy 19.888418 -132.849531)
			(xy 19.853218 -132.774111) (xy 19.826445 -132.695305) (xy 19.808417 -132.614051) (xy 19.799349 -132.531317)
			(xy 19.798792 -132.489702) (xy 19.799281 -132.451083) (xy 19.807095 -132.37424) (xy 19.822643 -132.298582)
			(xy 19.845766 -132.224885) (xy 19.876225 -132.153906) (xy 19.91371 -132.086372) (xy 19.957834 -132.022978)
			(xy 20.008145 -131.964372) (xy 20.064127 -131.911157) (xy 20.125206 -131.863878) (xy 20.190754 -131.823022)
			(xy 20.2601 -131.789006) (xy 20.332531 -131.762181) (xy 20.407304 -131.742821) (xy 20.483652 -131.731125)
			(xy 20.560792 -131.727213) (xy 20.637932 -131.731125) (xy 20.71428 -131.742821) (xy 20.789053 -131.762181)
			(xy 20.861484 -131.789006) (xy 20.93083 -131.823022) (xy 20.996378 -131.863878) (xy 21.057457 -131.911157)
			(xy 21.113439 -131.964372) (xy 21.16375 -132.022978) (xy 21.207874 -132.086372) (xy 21.245359 -132.153906)
			(xy 21.275818 -132.224885) (xy 21.298941 -132.298582) (xy 21.314489 -132.37424) (xy 21.322303 -132.451083)
			(xy 21.322792 -132.489702) (xy 21.322228 -132.531317) (xy 21.313161 -132.614051) (xy 21.295135 -132.695305)
			(xy 21.268364 -132.774112) (xy 21.233168 -132.849533) (xy 21.189965 -132.920671) (xy 21.165058 -132.954014)
			(xy 21.158689 -132.963204) (xy 21.153835 -132.985002) (xy 21.158691 -133.006799) (xy 21.165058 -133.01599)
			(xy 21.189973 -133.049328) (xy 21.233176 -133.120467) (xy 21.268372 -133.195889) (xy 21.295143 -133.274697)
			(xy 21.313169 -133.355952) (xy 21.322236 -133.438687) (xy 21.322792 -133.480302) (xy 21.322303 -133.518921)
			(xy 21.314489 -133.595764) (xy 21.298941 -133.671422) (xy 21.275818 -133.745119) (xy 21.245359 -133.816098)
			(xy 21.207874 -133.883632) (xy 21.16375 -133.947026) (xy 21.113439 -134.005632) (xy 21.057457 -134.058847)
			(xy 20.996378 -134.106126) (xy 20.93083 -134.146982) (xy 20.861484 -134.180998) (xy 20.789053 -134.207823)
			(xy 20.71428 -134.227183) (xy 20.637932 -134.238879) (xy 20.560792 -134.242792) (xy 20.483652 -134.238879)
			(xy 20.407304 -134.227183) (xy 20.332531 -134.207823) (xy 20.2601 -134.180998) (xy 20.190754 -134.146982)
			(xy 20.125206 -134.106126) (xy 20.064127 -134.058847) (xy 20.008145 -134.005632) (xy 19.957834 -133.947026)
			(xy 19.91371 -133.883632) (xy 19.876225 -133.816098) (xy 19.845766 -133.745119) (xy 19.822643 -133.671422)
			(xy 19.807095 -133.595764) (xy 19.799281 -133.518921) (xy 19.798792 -133.480302) (xy 3.523996 -133.480302)
			(xy 3.523996 -138.293856) (xy 19.36242 -138.293856) (xy 19.362914 -138.264803) (xy 19.371712 -138.207366)
			(xy 19.389113 -138.151926) (xy 19.414716 -138.099764) (xy 19.447928 -138.052085) (xy 19.487983 -138.00999)
			(xy 19.533956 -137.974452) (xy 19.584783 -137.946292) (xy 19.611848 -137.935716) (xy 19.620314 -137.932186)
			(xy 19.634173 -137.92019) (xy 19.642948 -137.904096) (xy 19.644614 -137.895076) (xy 19.650568 -137.856288)
			(xy 19.669396 -137.780102) (xy 19.695946 -137.706251) (xy 19.729938 -137.635517) (xy 19.771012 -137.568646)
			(xy 19.794474 -137.53719) (xy 19.800816 -137.527991) (xy 19.805648 -137.506202) (xy 19.800818 -137.484412)
			(xy 19.794474 -137.475214) (xy 19.769602 -137.441858) (xy 19.726489 -137.370689) (xy 19.691363 -137.295258)
			(xy 19.664639 -137.216457) (xy 19.646634 -137.135219) (xy 19.637562 -137.052506) (xy 19.636994 -137.010902)
			(xy 19.636994 -137.000742) (xy 19.636639 -136.990778) (xy 19.629277 -136.972268) (xy 19.615443 -136.957936)
			(xy 19.606514 -136.953498) (xy 19.581281 -136.942013) (xy 19.534172 -136.912787) (xy 19.491784 -136.877056)
			(xy 19.455008 -136.835572) (xy 19.424616 -136.789206) (xy 19.401248 -136.738933) (xy 19.385394 -136.685809)
			(xy 19.377388 -136.630951) (xy 19.376898 -136.603232) (xy 19.377454 -136.575965) (xy 19.38521 -136.521986)
			(xy 19.40057 -136.46966) (xy 19.423219 -136.420053) (xy 19.452698 -136.374174) (xy 19.488406 -136.332957)
			(xy 19.529616 -136.297241) (xy 19.57549 -136.267754) (xy 19.625093 -136.245095) (xy 19.677416 -136.229726)
			(xy 19.731393 -136.221959) (xy 19.75866 -136.22147) (xy 19.786202 -136.221975) (xy 19.840708 -136.229942)
			(xy 19.893503 -136.245658) (xy 19.943492 -136.268798) (xy 19.989637 -136.298881) (xy 20.010628 -136.31672)
			(xy 20.018435 -136.322974) (xy 20.037347 -136.329438) (xy 20.057298 -136.328248) (xy 20.066508 -136.32434)
			(xy 20.105658 -136.305913) (xy 20.187222 -136.277019) (xy 20.271533 -136.257544) (xy 20.357507 -136.247735)
			(xy 20.400772 -136.247124) (xy 20.440773 -136.247654) (xy 20.520337 -136.256014) (xy 20.598591 -136.272645)
			(xy 20.674678 -136.297364) (xy 20.747764 -136.329902) (xy 20.817049 -136.369902) (xy 20.881773 -136.416924)
			(xy 20.941227 -136.470455) (xy 20.99476 -136.529907) (xy 21.041784 -136.594629) (xy 21.081786 -136.663912)
			(xy 21.114326 -136.736998) (xy 21.139049 -136.813084) (xy 21.155682 -136.891337) (xy 21.164045 -136.970901)
			(xy 21.16455 -137.010902) (xy 21.164007 -137.052508) (xy 21.154947 -137.135225) (xy 21.136945 -137.216466)
			(xy 21.110215 -137.295268) (xy 21.075075 -137.370696) (xy 21.03194 -137.441855) (xy 21.00707 -137.475214)
			(xy 21.00073 -137.484413) (xy 20.995904 -137.506202) (xy 21.000731 -137.52799) (xy 21.00707 -137.53719)
			(xy 21.031936 -137.57055) (xy 21.075051 -137.641717) (xy 21.110179 -137.717148) (xy 21.136904 -137.795948)
			(xy 21.15491 -137.877185) (xy 21.163982 -137.959898) (xy 21.16455 -138.001502) (xy 21.164074 -138.041504)
			(xy 21.155711 -138.121071) (xy 21.139077 -138.199327) (xy 21.114353 -138.275416) (xy 21.081811 -138.348504)
			(xy 21.041808 -138.417789) (xy 20.994781 -138.482514) (xy 20.941247 -138.541968) (xy 20.88179 -138.5955)
			(xy 20.817064 -138.642524) (xy 20.747777 -138.682525) (xy 20.674688 -138.715064) (xy 20.598598 -138.739784)
			(xy 20.520341 -138.756416) (xy 20.440774 -138.764776) (xy 20.400772 -138.76528) (xy 20.363005 -138.764817)
			(xy 20.287841 -138.757356) (xy 20.21378 -138.74251) (xy 20.141547 -138.720424) (xy 20.071848 -138.691313)
			(xy 20.005364 -138.655463) (xy 19.973798 -138.634724) (xy 19.965977 -138.629959) (xy 19.948169 -138.625746)
			(xy 19.930011 -138.628024) (xy 19.921728 -138.63193) (xy 19.894232 -138.64571) (xy 19.835893 -138.66518)
			(xy 19.775187 -138.675037) (xy 19.744436 -138.675618) (xy 19.744182 -138.675618) (xy 19.716909 -138.675215)
			(xy 19.662917 -138.667449) (xy 19.610581 -138.652079) (xy 19.560965 -138.629416) (xy 19.515079 -138.599922)
			(xy 19.473858 -138.564198) (xy 19.438141 -138.522971) (xy 19.408655 -138.477081) (xy 19.386 -138.427461)
			(xy 19.370637 -138.375122) (xy 19.36288 -138.32113) (xy 19.36242 -138.293856) (xy 3.523996 -138.293856)
			(xy 3.523996 -178.618388) (xy 8.34263 -178.618388) (xy 8.343231 -178.575698) (xy 8.352795 -178.490855)
			(xy 8.371757 -178.407607) (xy 8.399882 -178.326992) (xy 8.436819 -178.250015) (xy 8.458962 -178.213512)
			(xy 8.463669 -178.205256) (xy 8.467176 -178.18659) (xy 8.463662 -178.167925) (xy 8.458962 -178.159664)
			(xy 8.436801 -178.123171) (xy 8.399858 -178.046195) (xy 8.371734 -177.965577) (xy 8.35278 -177.882326)
			(xy 8.343233 -177.797479) (xy 8.34263 -177.754788) (xy 8.343169 -177.715964) (xy 8.351054 -177.638717)
			(xy 8.36674 -177.56267) (xy 8.390066 -177.488608) (xy 8.420791 -177.417298) (xy 8.458597 -177.349475)
			(xy 8.503094 -177.285841) (xy 8.553821 -177.227053) (xy 8.610254 -177.173719) (xy 8.671811 -177.12639)
			(xy 8.70458 -177.105564) (xy 8.713867 -177.099093) (xy 8.726142 -177.080116) (xy 8.728202 -177.068988)
			(xy 8.732385 -177.041468) (xy 8.747702 -176.987954) (xy 8.770643 -176.93724) (xy 8.800721 -176.890403)
			(xy 8.818626 -176.86909) (xy 8.81888 -176.868836) (xy 8.824467 -176.86175) (xy 8.830711 -176.844832)
			(xy 8.831072 -176.835816) (xy 8.831072 -176.76876) (xy 8.83074 -176.75974) (xy 8.824476 -176.742823)
			(xy 8.81888 -176.73574) (xy 8.818626 -176.735486) (xy 8.800579 -176.714037) (xy 8.770345 -176.666837)
			(xy 8.747339 -176.615722) (xy 8.732054 -176.561793) (xy 8.727948 -176.534064) (xy 8.725926 -176.522923)
			(xy 8.713637 -176.503935) (xy 8.704326 -176.497488) (xy 8.671573 -176.476649) (xy 8.610045 -176.429304)
			(xy 8.553639 -176.375959) (xy 8.502938 -176.317166) (xy 8.458466 -176.25353) (xy 8.420682 -176.18571)
			(xy 8.389975 -176.114405) (xy 8.366664 -176.040353) (xy 8.350988 -175.964316) (xy 8.343109 -175.887082)
			(xy 8.34263 -175.848264) (xy 8.343219 -175.805574) (xy 8.352786 -175.72073) (xy 8.371751 -175.637482)
			(xy 8.399879 -175.556868) (xy 8.436818 -175.479891) (xy 8.458962 -175.443388) (xy 8.463688 -175.435141)
			(xy 8.467189 -175.416469) (xy 8.463666 -175.397801) (xy 8.458962 -175.38954) (xy 8.436791 -175.353053)
			(xy 8.39985 -175.276075) (xy 8.371728 -175.195456) (xy 8.352776 -175.112203) (xy 8.343231 -175.027355)
			(xy 8.34263 -174.984664) (xy 8.34311 -174.945847) (xy 8.350992 -174.868613) (xy 8.36667 -174.792578)
			(xy 8.389983 -174.718526) (xy 8.42069 -174.647222) (xy 8.458474 -174.579402) (xy 8.502945 -174.515766)
			(xy 8.553644 -174.456972) (xy 8.610047 -174.403625) (xy 8.671572 -174.356278) (xy 8.704326 -174.33544)
			(xy 8.713613 -174.328974) (xy 8.725874 -174.309988) (xy 8.727948 -174.298864) (xy 8.73204 -174.271133)
			(xy 8.747328 -174.217204) (xy 8.770342 -174.166092) (xy 8.800587 -174.118898) (xy 8.818626 -174.097442)
			(xy 8.81888 -174.097188) (xy 8.824487 -174.090116) (xy 8.830719 -174.073188) (xy 8.831072 -174.064168)
			(xy 8.831072 -173.997112) (xy 8.830715 -173.988095) (xy 8.824468 -173.971178) (xy 8.81888 -173.964092)
			(xy 8.818626 -173.963838) (xy 8.800759 -173.942498) (xy 8.770706 -173.895654) (xy 8.747763 -173.844948)
			(xy 8.732414 -173.791452) (xy 8.728202 -173.76394) (xy 8.726098 -173.752828) (xy 8.713843 -173.733853)
			(xy 8.70458 -173.727364) (xy 8.671806 -173.706542) (xy 8.610238 -173.65922) (xy 8.553794 -173.605891)
			(xy 8.503058 -173.547106) (xy 8.458553 -173.483472) (xy 8.42074 -173.415648) (xy 8.39001 -173.344334)
			(xy 8.366681 -173.270269) (xy 8.350994 -173.194218) (xy 8.34311 -173.116966) (xy 8.34263 -173.07814)
			(xy 8.343255 -173.035451) (xy 8.352813 -172.950609) (xy 8.37177 -172.867361) (xy 8.39989 -172.786746)
			(xy 8.436821 -172.709768) (xy 8.458962 -172.673264) (xy 8.463627 -172.664987) (xy 8.467148 -172.646334)
			(xy 8.463652 -172.627677) (xy 8.458962 -172.619416) (xy 8.436823 -172.58291) (xy 8.399876 -172.505938)
			(xy 8.371747 -172.425324) (xy 8.352788 -172.342075) (xy 8.343235 -172.25723) (xy 8.34263 -172.21454)
			(xy 8.343131 -172.175715) (xy 8.35102 -172.098467) (xy 8.366711 -172.022419) (xy 8.390042 -171.948357)
			(xy 8.420771 -171.877046) (xy 8.458582 -171.809223) (xy 8.503082 -171.745589) (xy 8.553813 -171.686802)
			(xy 8.61025 -171.633469) (xy 8.67181 -171.586142) (xy 8.70458 -171.565316) (xy 8.713885 -171.558867)
			(xy 8.726151 -171.539874) (xy 8.728202 -171.52874) (xy 8.732408 -171.501224) (xy 8.747717 -171.44771)
			(xy 8.770652 -171.396994) (xy 8.800724 -171.350157) (xy 8.818626 -171.328842) (xy 8.81888 -171.328588)
			(xy 8.824487 -171.321516) (xy 8.830719 -171.304588) (xy 8.831072 -171.295568) (xy 8.831072 -171.228766)
			(xy 8.830684 -171.219576) (xy 8.824156 -171.202392) (xy 8.818372 -171.195238) (xy 8.799035 -171.172234)
			(xy 8.767134 -171.121308) (xy 8.743622 -171.066006) (xy 8.729082 -171.007699) (xy 8.725916 -170.977814)
			(xy 8.724266 -170.966119) (xy 8.711958 -170.945994) (xy 8.702294 -170.939206) (xy 8.669874 -170.918316)
			(xy 8.60896 -170.871006) (xy 8.553135 -170.817787) (xy 8.502969 -170.759203) (xy 8.458976 -170.695852)
			(xy 8.421605 -170.628383) (xy 8.391239 -170.557484) (xy 8.368188 -170.483882) (xy 8.352687 -170.408327)
			(xy 8.344895 -170.331594) (xy 8.344408 -170.29303) (xy 8.345009 -170.250339) (xy 8.35455 -170.165491)
			(xy 8.373503 -170.082239) (xy 8.401632 -170.001623) (xy 8.438585 -169.924651) (xy 8.46074 -169.888154)
			(xy 8.465429 -169.879886) (xy 8.468963 -169.861226) (xy 8.465448 -169.842562) (xy 8.46074 -169.834306)
			(xy 8.438569 -169.797815) (xy 8.401584 -169.720854) (xy 8.373442 -169.640238) (xy 8.354496 -169.556979)
			(xy 8.344984 -169.472124) (xy 8.344408 -169.42943) (xy 8.344872 -169.390864) (xy 8.352659 -169.314127)
			(xy 8.368157 -169.238569) (xy 8.391206 -169.164963) (xy 8.421573 -169.09406) (xy 8.458945 -169.026588)
			(xy 8.50294 -168.963235) (xy 8.553109 -168.904649) (xy 8.608939 -168.85143) (xy 8.669859 -168.804122)
			(xy 8.702294 -168.783254) (xy 8.711987 -168.776492) (xy 8.724304 -168.756355) (xy 8.725916 -168.744646)
			(xy 8.7289 -168.716453) (xy 8.742132 -168.661328) (xy 8.763368 -168.608763) (xy 8.792139 -168.559916)
			(xy 8.827815 -168.515857) (xy 8.869612 -168.477556) (xy 8.916611 -168.445854) (xy 8.967779 -168.421447)
			(xy 9.021994 -168.404872) (xy 9.078062 -168.396492) (xy 9.134754 -168.396492) (xy 9.190822 -168.404872)
			(xy 9.245037 -168.421447) (xy 9.296205 -168.445854) (xy 9.343204 -168.477556) (xy 9.385001 -168.515857)
			(xy 9.420677 -168.559916) (xy 9.449448 -168.608763) (xy 9.470684 -168.661328) (xy 9.483916 -168.716453)
			(xy 9.4869 -168.744646) (xy 9.488551 -168.75634) (xy 9.500861 -168.776462) (xy 9.510522 -168.783254)
			(xy 9.542955 -168.804125) (xy 9.603868 -168.851437) (xy 9.659692 -168.904659) (xy 9.709856 -168.963246)
			(xy 9.753847 -169.026599) (xy 9.791217 -169.094071) (xy 9.821581 -169.164971) (xy 9.844631 -169.238575)
			(xy 9.860131 -169.314131) (xy 9.867922 -169.390866) (xy 9.868408 -169.42943) (xy 9.867833 -169.472122)
			(xy 9.858286 -169.556971) (xy 9.839327 -169.640223) (xy 9.811192 -169.720839) (xy 9.774233 -169.797809)
			(xy 9.752076 -169.834306) (xy 9.747337 -169.84255) (xy 9.743818 -169.861226) (xy 9.747356 -169.879898)
			(xy 9.752076 -169.888154) (xy 9.774232 -169.924653) (xy 9.811219 -170.001612) (xy 9.839364 -170.082226)
			(xy 9.858314 -170.165483) (xy 9.86783 -170.250337) (xy 9.868408 -170.29303) (xy 9.867905 -170.331595)
			(xy 9.860122 -170.40833) (xy 9.844629 -170.483887) (xy 9.821583 -170.557493) (xy 9.791221 -170.628395)
			(xy 9.753853 -170.695867) (xy 9.709862 -170.759221) (xy 9.659697 -170.817807) (xy 9.603871 -170.871027)
			(xy 9.542956 -170.918337) (xy 9.510522 -170.939206) (xy 9.500808 -170.945944) (xy 9.488501 -170.966099)
			(xy 9.4869 -170.977814) (xy 9.483637 -171.00768) (xy 9.469062 -171.065961) (xy 9.445561 -171.121248)
			(xy 9.41371 -171.172185) (xy 9.394444 -171.195238) (xy 9.388642 -171.202379) (xy 9.382132 -171.219573)
			(xy 9.381744 -171.228766) (xy 9.381744 -171.295568) (xy 9.382107 -171.304584) (xy 9.388349 -171.321502)
			(xy 9.393936 -171.328588) (xy 9.39419 -171.328842) (xy 9.412089 -171.350157) (xy 9.442134 -171.397009)
			(xy 9.465069 -171.447723) (xy 9.480408 -171.501226) (xy 9.484614 -171.52874) (xy 9.486721 -171.539851)
			(xy 9.498973 -171.558828) (xy 9.508236 -171.565316) (xy 9.541018 -171.586126) (xy 9.602586 -171.633449)
			(xy 9.65903 -171.686779) (xy 9.709766 -171.745566) (xy 9.754271 -171.809201) (xy 9.792083 -171.877027)
			(xy 9.822811 -171.948342) (xy 9.846139 -172.022408) (xy 9.861825 -172.098461) (xy 9.869707 -172.175713)
			(xy 9.870186 -172.21454) (xy 9.869596 -172.25723) (xy 9.860029 -172.342073) (xy 9.841064 -172.425321)
			(xy 9.812937 -172.505936) (xy 9.775998 -172.582913) (xy 9.753854 -172.619416) (xy 9.749123 -172.627661)
			(xy 9.745623 -172.646334) (xy 9.749148 -172.665003) (xy 9.753854 -172.673264) (xy 9.776028 -172.709749)
			(xy 9.812969 -172.786728) (xy 9.84109 -172.867347) (xy 9.860041 -172.950601) (xy 9.869585 -173.035449)
			(xy 9.870186 -173.07814) (xy 9.869709 -173.116966) (xy 9.86182 -173.194216) (xy 9.846129 -173.270266)
			(xy 9.822798 -173.34433) (xy 9.792067 -173.415642) (xy 9.754254 -173.483465) (xy 9.70975 -173.547099)
			(xy 9.659015 -173.605885) (xy 9.602574 -173.659216) (xy 9.541009 -173.70654) (xy 9.508236 -173.727364)
			(xy 9.498941 -173.733826) (xy 9.48667 -173.752809) (xy 9.484614 -173.76394) (xy 9.48044 -173.791461)
			(xy 9.46512 -173.844975) (xy 9.442176 -173.895689) (xy 9.412096 -173.942525) (xy 9.39419 -173.963838)
			(xy 9.393936 -173.964092) (xy 9.388339 -173.971171) (xy 9.3821 -173.988094) (xy 9.381744 -173.997112)
			(xy 9.381744 -174.064168) (xy 9.382107 -174.073184) (xy 9.388349 -174.090102) (xy 9.393936 -174.097188)
			(xy 9.39419 -174.097442) (xy 9.412213 -174.11891) (xy 9.442451 -174.166104) (xy 9.465464 -174.217213)
			(xy 9.480757 -174.271137) (xy 9.484868 -174.298864) (xy 9.486959 -174.309986) (xy 9.499201 -174.328979)
			(xy 9.50849 -174.33544) (xy 9.541248 -174.356271) (xy 9.602776 -174.403617) (xy 9.659182 -174.456963)
			(xy 9.709882 -174.515758) (xy 9.754354 -174.579394) (xy 9.792137 -174.647215) (xy 9.822843 -174.71852)
			(xy 9.846154 -174.792574) (xy 9.861829 -174.868611) (xy 9.869707 -174.945846) (xy 9.870186 -174.984664)
			(xy 9.86956 -175.027353) (xy 9.860002 -175.112195) (xy 9.841045 -175.195443) (xy 9.812925 -175.276058)
			(xy 9.775995 -175.353036) (xy 9.753854 -175.38954) (xy 9.749185 -175.397815) (xy 9.745664 -175.416469)
			(xy 9.749162 -175.435128) (xy 9.753854 -175.443388) (xy 9.775997 -175.479892) (xy 9.812943 -175.556865)
			(xy 9.841071 -175.63748) (xy 9.860029 -175.720729) (xy 9.869581 -175.805574) (xy 9.870186 -175.848264)
			(xy 9.869721 -175.887082) (xy 9.861836 -175.964316) (xy 9.846156 -176.040351) (xy 9.822841 -176.114403)
			(xy 9.792132 -176.185707) (xy 9.754347 -176.253526) (xy 9.709874 -176.317162) (xy 9.659174 -176.375956)
			(xy 9.60277 -176.429303) (xy 9.541244 -176.47665) (xy 9.50849 -176.497488) (xy 9.499196 -176.503946)
			(xy 9.486938 -176.522937) (xy 9.484868 -176.534064) (xy 9.48074 -176.561789) (xy 9.465463 -176.615718)
			(xy 9.442459 -176.666831) (xy 9.412225 -176.714028) (xy 9.39419 -176.735486) (xy 9.393936 -176.73574)
			(xy 9.388361 -176.742834) (xy 9.382109 -176.759745) (xy 9.381744 -176.76876) (xy 9.381744 -176.835816)
			(xy 9.382084 -176.844835) (xy 9.388342 -176.861752) (xy 9.393936 -176.868836) (xy 9.39419 -176.86909)
			(xy 9.41207 -176.89042) (xy 9.44212 -176.937267) (xy 9.465059 -176.987976) (xy 9.480404 -177.041475)
			(xy 9.484614 -177.068988) (xy 9.486697 -177.080106) (xy 9.498967 -177.099079) (xy 9.508236 -177.105564)
			(xy 9.541013 -177.126382) (xy 9.602581 -177.173704) (xy 9.659025 -177.227034) (xy 9.709761 -177.28582)
			(xy 9.754266 -177.349454) (xy 9.792078 -177.417278) (xy 9.822808 -177.488592) (xy 9.846137 -177.562658)
			(xy 9.861824 -177.63871) (xy 9.869706 -177.715962) (xy 9.870186 -177.754788) (xy 9.869572 -177.797477)
			(xy 9.86001 -177.88232) (xy 9.841051 -177.965568) (xy 9.812929 -178.046183) (xy 9.775996 -178.12316)
			(xy 9.753854 -178.159664) (xy 9.749166 -178.167929) (xy 9.745651 -178.18659) (xy 9.749158 -178.205251)
			(xy 9.753854 -178.213512) (xy 9.776007 -178.25001) (xy 9.812951 -178.326985) (xy 9.841077 -178.407601)
			(xy 9.860033 -178.490852) (xy 9.869582 -178.575697) (xy 9.870186 -178.618388) (xy 9.86966 -178.657204)
			(xy 9.861783 -178.734436) (xy 9.84611 -178.81047) (xy 9.822802 -178.884521) (xy 9.792101 -178.955824)
			(xy 9.754322 -179.023644) (xy 9.709856 -179.087281) (xy 9.659161 -179.146076) (xy 9.602763 -179.199424)
			(xy 9.541242 -179.246773) (xy 9.50849 -179.267612) (xy 9.499187 -179.274059) (xy 9.486934 -179.293058)
			(xy 9.484868 -179.304188) (xy 9.480838 -179.331413) (xy 9.465967 -179.3844) (xy 9.44364 -179.434703)
			(xy 9.414319 -179.481276) (xy 9.378613 -179.523155) (xy 9.337261 -179.559472) (xy 9.291123 -179.589472)
			(xy 9.241153 -179.612534) (xy 9.188389 -179.62818) (xy 9.133925 -179.636085) (xy 9.078891 -179.636085)
			(xy 9.024427 -179.62818) (xy 8.971663 -179.612534) (xy 8.921693 -179.589472) (xy 8.875555 -179.559472)
			(xy 8.834203 -179.523155) (xy 8.798497 -179.481276) (xy 8.769176 -179.434703) (xy 8.746849 -179.3844)
			(xy 8.731978 -179.331413) (xy 8.727948 -179.304188) (xy 8.725914 -179.29305) (xy 8.713634 -179.274061)
			(xy 8.704326 -179.267612) (xy 8.671575 -179.24677) (xy 8.610046 -179.199426) (xy 8.55364 -179.146082)
			(xy 8.502938 -179.087289) (xy 8.458466 -179.023654) (xy 8.420681 -178.955834) (xy 8.389974 -178.884529)
			(xy 8.366663 -178.810477) (xy 8.350987 -178.73444) (xy 8.343109 -178.657206) (xy 8.34263 -178.618388)
			(xy 3.523996 -178.618388) (xy 3.523996 -194.581526) (xy 13.285216 -194.581526) (xy 13.285216 -185.851546)
			(xy 13.285662 -185.841479) (xy 13.293368 -185.822881) (xy 13.300202 -185.815478) (xy 15.518638 -183.597042)
			(xy 15.526036 -183.590199) (xy 15.544637 -183.58248) (xy 15.554706 -183.582056) (xy 24.49576 -183.582056)
			(xy 24.505828 -183.581621) (xy 24.524427 -183.573908) (xy 24.531828 -183.56707) (xy 33.543494 -174.555404)
			(xy 33.549844 -174.527464) (xy 33.545018 -174.513494) (xy 33.531554 -174.473086) (xy 33.512677 -174.390029)
			(xy 33.503185 -174.305384) (xy 33.5026 -174.262796) (xy 33.503093 -174.222861) (xy 33.511442 -174.143428)
			(xy 33.528049 -174.065303) (xy 33.55273 -173.989342) (xy 33.585217 -173.916377) (xy 33.625153 -173.847207)
			(xy 33.6721 -173.782591) (xy 33.725544 -173.723236) (xy 33.7849 -173.669792) (xy 33.849517 -173.622846)
			(xy 33.918687 -173.582912) (xy 33.991653 -173.550426) (xy 34.067614 -173.525746) (xy 34.14574 -173.50914)
			(xy 34.225173 -173.500792) (xy 34.265108 -173.500288) (xy 34.307694 -173.500894) (xy 34.392335 -173.510397)
			(xy 34.475393 -173.529263) (xy 34.515806 -173.542706) (xy 34.529776 -173.547532) (xy 34.557716 -173.541182)
			(xy 35.01517 -173.083982) (xy 35.022006 -173.076579) (xy 35.029729 -173.057982) (xy 35.030156 -173.047914)
			(xy 35.030156 -170.706542) (xy 35.029946 -170.699732) (xy 35.026334 -170.6866) (xy 35.023044 -170.680634)
			(xy 35.002814 -170.645345) (xy 34.969134 -170.571299) (xy 34.943535 -170.494087) (xy 34.926308 -170.414586)
			(xy 34.917648 -170.333703) (xy 34.917126 -170.29303) (xy 34.917666 -170.252359) (xy 34.926345 -170.171481)
			(xy 34.943578 -170.091984) (xy 34.969167 -170.014772) (xy 35.002824 -169.940719) (xy 35.023044 -169.905426)
			(xy 35.026327 -169.899457) (xy 35.029936 -169.886327) (xy 35.030156 -169.879518) (xy 35.030156 -156.369766)
			(xy 35.029501 -156.35848) (xy 35.019828 -156.338085) (xy 35.002357 -156.323792) (xy 34.991548 -156.32049)
			(xy 34.895536 -156.296614) (xy 34.884393 -156.294413) (xy 34.862169 -156.298975) (xy 34.84411 -156.312708)
			(xy 34.838386 -156.322522) (xy 34.789966 -156.41394) (xy 34.68718 -156.593497) (xy 34.577728 -156.769072)
			(xy 34.461766 -156.940415) (xy 34.339457 -157.107287) (xy 34.210971 -157.269452) (xy 34.076492 -157.426682)
			(xy 33.936208 -157.578755) (xy 33.790316 -157.725457) (xy 33.639022 -157.866582) (xy 33.482539 -158.00193)
			(xy 33.321088 -158.131311) (xy 33.154897 -158.254543) (xy 32.984198 -158.371452) (xy 32.809232 -158.481874)
			(xy 32.630247 -158.585653) (xy 32.447493 -158.682643) (xy 32.261229 -158.772708) (xy 32.071716 -158.855719)
			(xy 31.879222 -158.931561) (xy 31.684018 -159.000127) (xy 31.486379 -159.06132) (xy 31.286583 -159.115055)
			(xy 31.084911 -159.161254) (xy 30.881648 -159.199853) (xy 30.677079 -159.230799) (xy 30.471493 -159.254047)
			(xy 30.26518 -159.269564) (xy 30.05843 -159.277329) (xy 29.954982 -159.277812) (xy 29.849385 -159.277307)
			(xy 29.638345 -159.269217) (xy 29.42777 -159.25305) (xy 29.217969 -159.22883) (xy 29.00925 -159.196591)
			(xy 28.801918 -159.156382) (xy 28.596279 -159.10826) (xy 28.392634 -159.052298) (xy 28.191282 -158.988576)
			(xy 27.992518 -158.917188) (xy 27.796634 -158.83824) (xy 27.603919 -158.751847) (xy 27.414653 -158.658136)
			(xy 27.229116 -158.557244) (xy 27.04758 -158.44932) (xy 26.87031 -158.334521) (xy 26.697568 -158.213017)
			(xy 26.529606 -158.084986) (xy 26.366672 -157.950615) (xy 26.209004 -157.810101) (xy 26.056834 -157.663652)
			(xy 25.910385 -157.511482) (xy 25.769871 -157.353814) (xy 25.6355 -157.19088) (xy 25.507469 -157.022918)
			(xy 25.385965 -156.850176) (xy 25.271166 -156.672906) (xy 25.163242 -156.49137) (xy 25.06235 -156.305833)
			(xy 24.968639 -156.116567) (xy 24.882246 -155.923852) (xy 24.803298 -155.727968) (xy 24.73191 -155.529204)
			(xy 24.668188 -155.327852) (xy 24.612226 -155.124207) (xy 24.564104 -154.918568) (xy 24.523895 -154.711236)
			(xy 24.491656 -154.502517) (xy 24.467436 -154.292716) (xy 24.451269 -154.082141) (xy 24.443179 -153.871101)
			(xy 24.443179 -153.659907) (xy 24.451269 -153.448867) (xy 24.467436 -153.238292) (xy 24.491656 -153.028491)
			(xy 24.523895 -152.819772) (xy 24.564104 -152.61244) (xy 24.612226 -152.406801) (xy 24.668188 -152.203156)
			(xy 24.73191 -152.001804) (xy 24.803298 -151.80304) (xy 24.882246 -151.607156) (xy 24.968639 -151.414441)
			(xy 25.06235 -151.225175) (xy 25.163242 -151.039638) (xy 25.271166 -150.858102) (xy 25.385965 -150.680832)
			(xy 25.507469 -150.50809) (xy 25.6355 -150.340128) (xy 25.769871 -150.177194) (xy 25.910385 -150.019526)
			(xy 26.056834 -149.867356) (xy 26.209004 -149.720907) (xy 26.366672 -149.580393) (xy 26.529606 -149.446022)
			(xy 26.697568 -149.317991) (xy 26.87031 -149.196487) (xy 27.04758 -149.081688) (xy 27.229116 -148.973764)
			(xy 27.414653 -148.872872) (xy 27.603919 -148.779161) (xy 27.796634 -148.692768) (xy 27.992518 -148.61382)
			(xy 28.191282 -148.542432) (xy 28.392634 -148.47871) (xy 28.596279 -148.422748) (xy 28.801918 -148.374626)
			(xy 29.00925 -148.334417) (xy 29.217969 -148.302178) (xy 29.42777 -148.277958) (xy 29.638345 -148.261791)
			(xy 29.849385 -148.253701) (xy 29.954982 -148.253196) (xy 30.06136 -148.253701) (xy 30.273959 -148.261904)
			(xy 30.486082 -148.278305) (xy 30.697415 -148.302878) (xy 30.907642 -148.335588) (xy 31.11645 -148.376384)
			(xy 31.323529 -148.425207) (xy 31.52857 -148.481983) (xy 31.731268 -148.546629) (xy 31.93132 -148.619047)
			(xy 32.128429 -148.699131) (xy 32.322301 -148.78676) (xy 32.512648 -148.881804) (xy 32.699186 -148.984123)
			(xy 32.881637 -149.093562) (xy 33.059729 -149.20996) (xy 33.233198 -149.333143) (xy 33.401784 -149.462927)
			(xy 33.565238 -149.599119) (xy 33.723314 -149.741517) (xy 33.875779 -149.889908) (xy 34.022404 -150.044072)
			(xy 34.162972 -150.203778) (xy 34.297273 -150.368789) (xy 34.425107 -150.538859) (xy 34.546283 -150.713734)
			(xy 34.660622 -150.893156) (xy 34.767953 -151.076855) (xy 34.868116 -151.264559) (xy 34.960962 -151.455987)
			(xy 35.046353 -151.650856) (xy 35.124161 -151.848874) (xy 35.194271 -152.049747) (xy 35.256578 -152.253176)
			(xy 35.310989 -152.458857) (xy 35.334702 -152.56256) (xy 35.33775 -152.576022) (xy 35.356546 -152.596596)
			(xy 35.455606 -152.625044) (xy 35.464428 -152.627194) (xy 35.482519 -152.625863) (xy 35.498994 -152.618269)
			(xy 35.505644 -152.61209) (xy 42.28084 -145.836894) (xy 42.288232 -145.830043) (xy 42.306837 -145.82233)
			(xy 42.316908 -145.821908) (xy 60.03036 -145.821908) (xy 60.040427 -145.822352) (xy 60.059025 -145.830059)
			(xy 60.066428 -145.836894) (xy 66.962528 -152.732994) (xy 66.969925 -152.739838) (xy 66.988527 -152.747556)
			(xy 66.998596 -152.74798) (xy 76.569316 -152.74798) (xy 76.579389 -152.748376) (xy 76.597988 -152.756115)
			(xy 76.605384 -152.762966) (xy 78.299056 -154.456892) (xy 78.303328 -154.460929) (xy 78.313341 -154.467082)
			(xy 78.318868 -154.469084) (xy 78.34657 -154.478943) (xy 78.398796 -154.505952) (xy 78.44626 -154.540655)
			(xy 78.487836 -154.582231) (xy 78.522541 -154.629693) (xy 78.549552 -154.681919) (xy 78.559406 -154.709622)
			(xy 78.561437 -154.715136) (xy 78.567583 -154.725145) (xy 78.571598 -154.729434) (xy 81.52892 -157.686502)
			(xy 81.536319 -157.693344) (xy 81.554919 -157.701062) (xy 81.564988 -157.701488) (xy 91.85021 -157.701488)
			(xy 91.86028 -157.701071) (xy 91.878878 -157.693345) (xy 91.886278 -157.686502) (xy 97.582736 -151.990298)
			(xy 97.590656 -151.981484) (xy 97.598151 -151.959036) (xy 97.594806 -151.935608) (xy 97.588578 -151.925528)
			(xy 97.572635 -151.901516) (xy 97.54742 -151.849687) (xy 97.530267 -151.794661) (xy 97.521564 -151.737684)
			(xy 97.521014 -151.708866) (xy 97.521446 -151.681613) (xy 97.529208 -151.627662) (xy 97.544569 -151.575365)
			(xy 97.567215 -151.525786) (xy 97.596687 -151.479935) (xy 97.632384 -151.438745) (xy 97.67358 -151.403053)
			(xy 97.719435 -151.373588) (xy 97.769018 -151.350949) (xy 97.821317 -151.335596) (xy 97.875269 -151.327842)
			(xy 97.902522 -151.327358) (xy 97.931341 -151.327922) (xy 97.988322 -151.336598) (xy 98.043348 -151.353749)
			(xy 98.095168 -151.378984) (xy 98.119184 -151.394922) (xy 98.134424 -151.405336) (xy 98.170746 -151.402034)
			(xy 102.75697 -146.816064) (xy 102.764336 -146.79295) (xy 102.762558 -146.781012) (xy 102.75829 -146.751799)
			(xy 102.753711 -146.692932) (xy 102.753414 -146.66341) (xy 102.753917 -146.624739) (xy 102.761736 -146.547792)
			(xy 102.777306 -146.472033) (xy 102.800465 -146.398239) (xy 102.830976 -146.327169) (xy 102.868526 -146.259553)
			(xy 102.912728 -146.196086) (xy 102.963129 -146.137421) (xy 103.01921 -146.084159) (xy 103.080395 -146.036849)
			(xy 103.146056 -145.995977) (xy 103.215517 -145.961962) (xy 103.288065 -145.935154) (xy 103.362955 -145.915829)
			(xy 103.401114 -145.909538) (xy 103.413306 -145.90776) (xy 103.432356 -145.894044) (xy 103.476552 -145.811494)
			(xy 103.481561 -145.800803) (xy 103.48223 -145.777234) (xy 103.477822 -145.766282) (xy 103.477822 -145.765774)
			(xy 103.460601 -145.72773) (xy 103.433602 -145.648703) (xy 103.415415 -145.567196) (xy 103.406259 -145.484188)
			(xy 103.405686 -145.442432) (xy 103.406227 -145.402498) (xy 103.414572 -145.323067) (xy 103.431175 -145.244943)
			(xy 103.455853 -145.168983) (xy 103.488336 -145.096019) (xy 103.528268 -145.02685) (xy 103.575211 -144.962234)
			(xy 103.628652 -144.902879) (xy 103.688004 -144.849435) (xy 103.752618 -144.802489) (xy 103.821785 -144.762553)
			(xy 103.894748 -144.730067) (xy 103.970707 -144.705385) (xy 104.048829 -144.688778) (xy 104.12826 -144.680429)
			(xy 104.168194 -144.679924) (xy 104.205779 -144.680371) (xy 104.280585 -144.687761) (xy 104.354302 -144.702469)
			(xy 104.426216 -144.724354) (xy 104.49563 -144.753203) (xy 104.561871 -144.788737) (xy 104.624298 -144.830611)
			(xy 104.653588 -144.854168) (xy 104.661099 -144.859787) (xy 104.678849 -144.865778) (xy 104.697564 -144.864953)
			(xy 104.714718 -144.857424) (xy 104.72166 -144.85112) (xy 106.735626 -142.837154) (xy 106.743018 -142.830304)
			(xy 106.761624 -142.822591) (xy 106.771694 -142.822168) (xy 113.754408 -142.822168) (xy 113.76448 -142.822571)
			(xy 113.783079 -142.830306) (xy 113.790476 -142.837154) (xy 115.415822 -144.4625) (xy 115.422658 -144.469903)
			(xy 115.430379 -144.4885) (xy 115.430808 -144.498568) (xy 115.430808 -146.553428) (xy 115.431217 -146.563499)
			(xy 115.438949 -146.582097) (xy 115.445794 -146.589496) (xy 115.863624 -147.007326) (xy 115.871019 -147.014173)
			(xy 115.889622 -147.021888) (xy 115.899692 -147.022312) (xy 121.046748 -147.022312) (xy 121.056817 -147.021883)
			(xy 121.075417 -147.014167) (xy 121.082816 -147.007326) (xy 121.386346 -146.703796) (xy 121.393187 -146.696397)
			(xy 121.400905 -146.677797) (xy 121.401332 -146.667728) (xy 121.401332 -143.042132) (xy 121.401766 -143.032064)
			(xy 121.40948 -143.013465) (xy 121.416318 -143.006064) (xy 123.138438 -141.284198) (xy 123.145831 -141.277349)
			(xy 123.164436 -141.269634) (xy 123.174506 -141.269212) (xy 138.633454 -141.269212) (xy 138.643521 -141.269659)
			(xy 138.662119 -141.277364) (xy 138.669522 -141.284198) (xy 142.462257 -145.0769) (xy 162.918736 -145.0769)
			(xy 162.922648 -144.999766) (xy 162.934343 -144.923423) (xy 162.953701 -144.848655) (xy 162.980524 -144.776228)
			(xy 163.014536 -144.706887) (xy 163.055388 -144.641343) (xy 163.102662 -144.580267) (xy 163.155871 -144.524288)
			(xy 163.214471 -144.473978) (xy 163.27786 -144.429855) (xy 163.345387 -144.392371) (xy 163.41636 -144.36191)
			(xy 163.490051 -144.338786) (xy 163.565703 -144.323235) (xy 163.642539 -144.315417) (xy 163.681156 -144.314926)
			(xy 163.72277 -144.315512) (xy 163.805504 -144.324574) (xy 163.886757 -144.342596) (xy 163.965564 -144.369362)
			(xy 164.040986 -144.404555) (xy 164.112125 -144.447755) (xy 164.145468 -144.47266) (xy 164.154658 -144.479028)
			(xy 164.176456 -144.483883) (xy 164.198254 -144.479028) (xy 164.207444 -144.47266) (xy 164.240799 -144.447769)
			(xy 164.311934 -144.404562) (xy 164.387352 -144.369362) (xy 164.466157 -144.342587) (xy 164.547409 -144.324556)
			(xy 164.630142 -144.315485) (xy 164.671756 -144.314926) (xy 164.710379 -144.315345) (xy 164.787229 -144.323155)
			(xy 164.862895 -144.338701) (xy 164.936599 -144.361822) (xy 165.007587 -144.392282) (xy 165.075128 -144.429767)
			(xy 165.13853 -144.473893) (xy 165.197143 -144.524207) (xy 165.250364 -144.580193) (xy 165.297649 -144.641276)
			(xy 165.33851 -144.706829) (xy 165.37253 -144.776181) (xy 165.399359 -144.848618) (xy 165.418722 -144.923398)
			(xy 165.430419 -144.999753) (xy 165.434332 -145.0769) (xy 165.430419 -145.154047) (xy 165.418722 -145.230402)
			(xy 165.399359 -145.305182) (xy 165.37253 -145.377619) (xy 165.33851 -145.446971) (xy 165.297649 -145.512524)
			(xy 165.250364 -145.573607) (xy 165.197143 -145.629593) (xy 165.13853 -145.679907) (xy 165.075128 -145.724033)
			(xy 165.007587 -145.761518) (xy 164.936599 -145.791978) (xy 164.862895 -145.815099) (xy 164.787229 -145.830645)
			(xy 164.710379 -145.838455) (xy 164.671756 -145.838926) (xy 164.63014 -145.838399) (xy 164.547404 -145.829326)
			(xy 164.466149 -145.811294) (xy 164.387342 -145.784517) (xy 164.311922 -145.749313) (xy 164.240786 -145.706102)
			(xy 164.207444 -145.681192) (xy 164.198254 -145.674824) (xy 164.176456 -145.669969) (xy 164.154658 -145.674824)
			(xy 164.145468 -145.681192) (xy 164.112137 -145.706116) (xy 164.040997 -145.74932) (xy 163.965574 -145.784516)
			(xy 163.886765 -145.811285) (xy 163.805508 -145.829309) (xy 163.722772 -145.838372) (xy 163.681156 -145.838926)
			(xy 163.642539 -145.838383) (xy 163.565703 -145.830565) (xy 163.490051 -145.815014) (xy 163.41636 -145.79189)
			(xy 163.345387 -145.761429) (xy 163.27786 -145.723945) (xy 163.214471 -145.679822) (xy 163.155871 -145.629512)
			(xy 163.102662 -145.573533) (xy 163.055388 -145.512457) (xy 163.014536 -145.446913) (xy 162.980524 -145.377572)
			(xy 162.953701 -145.305145) (xy 162.934343 -145.230377) (xy 162.922648 -145.154034) (xy 162.918736 -145.0769)
			(xy 142.462257 -145.0769) (xy 147.373399 -149.988) (xy 160.475226 -149.988) (xy 160.479138 -149.910863)
			(xy 160.490834 -149.834518) (xy 160.510193 -149.759748) (xy 160.537017 -149.68732) (xy 160.57103 -149.617977)
			(xy 160.611884 -149.552431) (xy 160.65916 -149.491354) (xy 160.712372 -149.435373) (xy 160.770974 -149.385063)
			(xy 160.834366 -149.340939) (xy 160.901896 -149.303455) (xy 160.972872 -149.272995) (xy 161.046565 -149.249872)
			(xy 161.122219 -149.234322) (xy 161.199058 -149.226506) (xy 161.237676 -149.226016) (xy 161.27929 -149.226593)
			(xy 161.362024 -149.235657) (xy 161.443278 -149.253681) (xy 161.522085 -149.280449) (xy 161.597506 -149.315643)
			(xy 161.668645 -149.358844) (xy 161.701988 -149.38375) (xy 161.711178 -149.390118) (xy 161.732976 -149.394973)
			(xy 161.754774 -149.390118) (xy 161.763964 -149.38375) (xy 161.797311 -149.358849) (xy 161.868448 -149.315643)
			(xy 161.943868 -149.280445) (xy 162.022674 -149.253672) (xy 162.103927 -149.235643) (xy 162.186661 -149.226574)
			(xy 162.228276 -149.226016) (xy 162.266898 -149.226456) (xy 162.343746 -149.234268) (xy 162.419409 -149.249815)
			(xy 162.49311 -149.272937) (xy 162.564095 -149.303397) (xy 162.631634 -149.340882) (xy 162.695033 -149.385008)
			(xy 162.753643 -149.435321) (xy 162.806863 -149.491306) (xy 162.854145 -149.552388) (xy 162.895005 -149.61794)
			(xy 162.929023 -149.687289) (xy 162.955851 -149.759725) (xy 162.975213 -149.834502) (xy 162.98691 -149.910855)
			(xy 162.988403 -149.9403) (xy 163.412358 -149.9403) (xy 163.416271 -149.863153) (xy 163.427968 -149.786797)
			(xy 163.447331 -149.712017) (xy 163.474159 -149.63958) (xy 163.508179 -149.570228) (xy 163.54904 -149.504674)
			(xy 163.596324 -149.44359) (xy 163.649546 -149.387604) (xy 163.708158 -149.337289) (xy 163.77156 -149.293162)
			(xy 163.839101 -149.255676) (xy 163.910088 -149.225216) (xy 163.983793 -149.202094) (xy 164.059459 -149.186547)
			(xy 164.136309 -149.178735) (xy 164.174932 -149.178264) (xy 164.216548 -149.1788) (xy 164.299283 -149.187871)
			(xy 164.380538 -149.205902) (xy 164.459345 -149.232677) (xy 164.534765 -149.267879) (xy 164.605902 -149.311088)
			(xy 164.639244 -149.335998) (xy 164.648434 -149.342366) (xy 164.670232 -149.347221) (xy 164.69203 -149.342366)
			(xy 164.70122 -149.335998) (xy 164.734553 -149.311078) (xy 164.805693 -149.267874) (xy 164.881116 -149.232677)
			(xy 164.959924 -149.205907) (xy 165.04118 -149.187883) (xy 165.123916 -149.178819) (xy 165.165532 -149.178264)
			(xy 165.204149 -149.178827) (xy 165.280985 -149.186643) (xy 165.356637 -149.202193) (xy 165.430327 -149.225316)
			(xy 165.5013 -149.255776) (xy 165.568828 -149.293259) (xy 165.632217 -149.337382) (xy 165.690817 -149.387691)
			(xy 165.744027 -149.44367) (xy 165.791301 -149.504745) (xy 165.832154 -149.570289) (xy 165.866166 -149.63963)
			(xy 165.892989 -149.712055) (xy 165.912347 -149.786823) (xy 165.924042 -149.863166) (xy 165.927954 -149.9403)
			(xy 165.924042 -150.017434) (xy 165.912347 -150.093777) (xy 165.892989 -150.168545) (xy 165.866166 -150.24097)
			(xy 165.832154 -150.310311) (xy 165.791301 -150.375855) (xy 165.744027 -150.43693) (xy 165.690817 -150.492909)
			(xy 165.632217 -150.543218) (xy 165.568828 -150.587341) (xy 165.5013 -150.624824) (xy 165.430327 -150.655284)
			(xy 165.356637 -150.678407) (xy 165.280985 -150.693957) (xy 165.204149 -150.701773) (xy 165.165532 -150.702264)
			(xy 165.123918 -150.701687) (xy 165.041184 -150.692623) (xy 164.95993 -150.6746) (xy 164.881123 -150.647832)
			(xy 164.805701 -150.612638) (xy 164.734563 -150.569436) (xy 164.70122 -150.54453) (xy 164.69203 -150.538162)
			(xy 164.670232 -150.533307) (xy 164.648434 -150.538162) (xy 164.639244 -150.54453) (xy 164.605892 -150.569425)
			(xy 164.534757 -150.612632) (xy 164.459338 -150.647832) (xy 164.380533 -150.674606) (xy 164.29928 -150.692635)
			(xy 164.216547 -150.701706) (xy 164.174932 -150.702264) (xy 164.136309 -150.701865) (xy 164.059459 -150.694053)
			(xy 163.983793 -150.678506) (xy 163.910088 -150.655384) (xy 163.839101 -150.624924) (xy 163.77156 -150.587438)
			(xy 163.708158 -150.543311) (xy 163.649546 -150.492996) (xy 163.596324 -150.43701) (xy 163.54904 -150.375926)
			(xy 163.508179 -150.310372) (xy 163.474159 -150.24102) (xy 163.447331 -150.168583) (xy 163.427968 -150.093803)
			(xy 163.416271 -150.017447) (xy 163.412358 -149.9403) (xy 162.988403 -149.9403) (xy 162.990822 -149.988)
			(xy 162.98691 -150.065145) (xy 162.975213 -150.141498) (xy 162.955851 -150.216275) (xy 162.929023 -150.288711)
			(xy 162.895005 -150.35806) (xy 162.854145 -150.423612) (xy 162.806863 -150.484694) (xy 162.753643 -150.540679)
			(xy 162.695033 -150.590992) (xy 162.631634 -150.635118) (xy 162.564095 -150.672603) (xy 162.49311 -150.703063)
			(xy 162.419409 -150.726185) (xy 162.343746 -150.741732) (xy 162.266898 -150.749544) (xy 162.228276 -150.750016)
			(xy 162.18666 -150.74948) (xy 162.103925 -150.740409) (xy 162.02267 -150.722379) (xy 161.943863 -150.695603)
			(xy 161.868442 -150.660401) (xy 161.797306 -150.617192) (xy 161.763964 -150.592282) (xy 161.754774 -150.585914)
			(xy 161.732976 -150.581059) (xy 161.711178 -150.585914) (xy 161.701988 -150.592282) (xy 161.66865 -150.617196)
			(xy 161.597512 -150.660401) (xy 161.52209 -150.695599) (xy 161.443282 -150.72237) (xy 161.362027 -150.740395)
			(xy 161.279291 -150.749461) (xy 161.237676 -150.750016) (xy 161.199058 -150.749494) (xy 161.122219 -150.741678)
			(xy 161.046565 -150.726128) (xy 160.972872 -150.703005) (xy 160.901896 -150.672545) (xy 160.834366 -150.635061)
			(xy 160.770974 -150.590937) (xy 160.712372 -150.540627) (xy 160.65916 -150.484646) (xy 160.611884 -150.423569)
			(xy 160.57103 -150.358023) (xy 160.537017 -150.28868) (xy 160.510193 -150.216252) (xy 160.490834 -150.141482)
			(xy 160.479138 -150.065137) (xy 160.475226 -149.988) (xy 147.373399 -149.988) (xy 151.160334 -153.774902)
			(xy 188.441847 -153.774902) (xy 188.445843 -153.565016) (xy 188.457828 -153.355434) (xy 188.477782 -153.14646)
			(xy 188.505678 -152.938398) (xy 188.541475 -152.731548) (xy 188.58512 -152.526211) (xy 188.636552 -152.322685)
			(xy 188.695694 -152.121264) (xy 188.762462 -151.922241) (xy 188.836758 -151.725904) (xy 188.918476 -151.532538)
			(xy 189.007495 -151.342423) (xy 189.103688 -151.155835) (xy 189.206915 -150.973044) (xy 189.317026 -150.794316)
			(xy 189.433861 -150.619909) (xy 189.557251 -150.450077) (xy 189.687018 -150.285065) (xy 189.822972 -150.125114)
			(xy 189.964918 -149.970454) (xy 190.112648 -149.82131) (xy 190.26595 -149.677899) (xy 190.4246 -149.540428)
			(xy 190.588369 -149.409096) (xy 190.757019 -149.284095) (xy 190.930305 -149.165604) (xy 191.107977 -149.053797)
			(xy 191.289777 -148.948835) (xy 191.475441 -148.85087) (xy 191.664699 -148.760045) (xy 191.857279 -148.676491)
			(xy 192.0529 -148.600328) (xy 192.251278 -148.531669) (xy 192.452127 -148.470612) (xy 192.655154 -148.417245)
			(xy 192.860067 -148.371647) (xy 193.066566 -148.333882) (xy 193.274353 -148.304007) (xy 193.483128 -148.282064)
			(xy 193.692586 -148.268085) (xy 193.902425 -148.26209) (xy 194.112339 -148.264089) (xy 194.322026 -148.274077)
			(xy 194.53118 -148.292042) (xy 194.739498 -148.317956) (xy 194.946679 -148.351781) (xy 195.152423 -148.39347)
			(xy 195.356429 -148.442962) (xy 195.558404 -148.500184) (xy 195.758054 -148.565054) (xy 195.955089 -148.637478)
			(xy 196.149225 -148.717351) (xy 196.340178 -148.804557) (xy 196.527674 -148.898969) (xy 196.711439 -149.000451)
			(xy 196.891207 -149.108855) (xy 197.066718 -149.224025) (xy 197.237717 -149.345793) (xy 197.403957 -149.473982)
			(xy 197.565196 -149.608408) (xy 197.7212 -149.748875) (xy 197.871743 -149.895179) (xy 198.016607 -150.047108)
			(xy 198.155582 -150.204442) (xy 198.288467 -150.366953) (xy 198.415068 -150.534406) (xy 198.535203 -150.706556)
			(xy 198.648697 -150.883156) (xy 198.755385 -151.063948) (xy 198.855112 -151.248671) (xy 198.947735 -151.437057)
			(xy 199.033119 -151.628832) (xy 199.11114 -151.823719) (xy 199.181685 -152.021435) (xy 199.244652 -152.221693)
			(xy 199.299949 -152.424203) (xy 199.347496 -152.628672) (xy 199.387224 -152.834803) (xy 199.419076 -153.042296)
			(xy 199.443006 -153.250852) (xy 199.458978 -153.460168) (xy 199.46697 -153.66994) (xy 199.467428 -153.766012)
			(xy 272.382243 -153.766012) (xy 272.386239 -153.556126) (xy 272.398224 -153.346544) (xy 272.418178 -153.13757)
			(xy 272.446074 -152.929508) (xy 272.481871 -152.722658) (xy 272.525516 -152.517321) (xy 272.576948 -152.313795)
			(xy 272.63609 -152.112374) (xy 272.702858 -151.913351) (xy 272.777154 -151.717014) (xy 272.858872 -151.523648)
			(xy 272.947891 -151.333533) (xy 273.044084 -151.146945) (xy 273.147311 -150.964154) (xy 273.257422 -150.785426)
			(xy 273.374257 -150.611019) (xy 273.497647 -150.441187) (xy 273.627414 -150.276175) (xy 273.763368 -150.116224)
			(xy 273.905314 -149.961564) (xy 274.053044 -149.81242) (xy 274.206346 -149.669009) (xy 274.364996 -149.531538)
			(xy 274.528765 -149.400206) (xy 274.697415 -149.275205) (xy 274.870701 -149.156714) (xy 275.048373 -149.044907)
			(xy 275.230173 -148.939945) (xy 275.415837 -148.84198) (xy 275.605095 -148.751155) (xy 275.797675 -148.667601)
			(xy 275.993296 -148.591438) (xy 276.191674 -148.522779) (xy 276.392523 -148.461722) (xy 276.59555 -148.408355)
			(xy 276.800463 -148.362757) (xy 277.006962 -148.324992) (xy 277.214749 -148.295117) (xy 277.423524 -148.273174)
			(xy 277.632982 -148.259195) (xy 277.842821 -148.2532) (xy 278.052735 -148.255199) (xy 278.262422 -148.265187)
			(xy 278.471576 -148.283152) (xy 278.679894 -148.309066) (xy 278.887075 -148.342891) (xy 279.092819 -148.38458)
			(xy 279.296825 -148.434072) (xy 279.4988 -148.491294) (xy 279.69845 -148.556164) (xy 279.895485 -148.628588)
			(xy 280.089621 -148.708461) (xy 280.280574 -148.795667) (xy 280.46807 -148.890079) (xy 280.651835 -148.991561)
			(xy 280.831603 -149.099965) (xy 281.007114 -149.215135) (xy 281.178113 -149.336903) (xy 281.344353 -149.465092)
			(xy 281.505592 -149.599518) (xy 281.661596 -149.739985) (xy 281.812139 -149.886289) (xy 281.957003 -150.038218)
			(xy 282.095978 -150.195552) (xy 282.228863 -150.358063) (xy 282.355464 -150.525516) (xy 282.475599 -150.697666)
			(xy 282.589093 -150.874266) (xy 282.695781 -151.055058) (xy 282.795508 -151.239781) (xy 282.888131 -151.428167)
			(xy 282.973515 -151.619942) (xy 283.051536 -151.814829) (xy 283.122081 -152.012545) (xy 283.185048 -152.212803)
			(xy 283.240345 -152.415313) (xy 283.287892 -152.619782) (xy 283.32762 -152.825913) (xy 283.359472 -153.033406)
			(xy 283.383402 -153.241962) (xy 283.399374 -153.451278) (xy 283.407366 -153.66105) (xy 283.407866 -153.766012)
			(xy 283.407366 -153.870974) (xy 283.399374 -154.080746) (xy 283.383402 -154.290062) (xy 283.359472 -154.498618)
			(xy 283.32762 -154.706111) (xy 283.287892 -154.912242) (xy 283.240345 -155.116711) (xy 283.185048 -155.319221)
			(xy 283.122081 -155.519479) (xy 283.051536 -155.717195) (xy 282.973515 -155.912082) (xy 282.888131 -156.103857)
			(xy 282.795508 -156.292243) (xy 282.695781 -156.476966) (xy 282.589093 -156.657758) (xy 282.475599 -156.834358)
			(xy 282.355464 -157.006508) (xy 282.228863 -157.173961) (xy 282.095978 -157.336472) (xy 281.957003 -157.493806)
			(xy 281.812139 -157.645735) (xy 281.661596 -157.792039) (xy 281.505592 -157.932506) (xy 281.344353 -158.066932)
			(xy 281.178113 -158.195121) (xy 281.007114 -158.316889) (xy 280.831603 -158.432059) (xy 280.651835 -158.540463)
			(xy 280.46807 -158.641945) (xy 280.280574 -158.736357) (xy 280.089621 -158.823563) (xy 279.895485 -158.903436)
			(xy 279.69845 -158.97586) (xy 279.4988 -159.04073) (xy 279.296825 -159.097952) (xy 279.092819 -159.147444)
			(xy 278.887075 -159.189133) (xy 278.679894 -159.222958) (xy 278.471576 -159.248872) (xy 278.262422 -159.266837)
			(xy 278.052735 -159.276825) (xy 277.842821 -159.278824) (xy 277.632982 -159.272829) (xy 277.423524 -159.25885)
			(xy 277.214749 -159.236907) (xy 277.006962 -159.207032) (xy 276.800463 -159.169267) (xy 276.59555 -159.123669)
			(xy 276.392523 -159.070302) (xy 276.191674 -159.009245) (xy 275.993296 -158.940586) (xy 275.797675 -158.864423)
			(xy 275.605095 -158.780869) (xy 275.415837 -158.690044) (xy 275.230173 -158.592079) (xy 275.048373 -158.487117)
			(xy 274.870701 -158.37531) (xy 274.697415 -158.256819) (xy 274.528765 -158.131818) (xy 274.364996 -158.000486)
			(xy 274.206346 -157.863015) (xy 274.053044 -157.719604) (xy 273.905314 -157.57046) (xy 273.763368 -157.4158)
			(xy 273.627414 -157.255849) (xy 273.497647 -157.090837) (xy 273.374257 -156.921005) (xy 273.257422 -156.746598)
			(xy 273.147311 -156.56787) (xy 273.044084 -156.385079) (xy 272.947891 -156.198491) (xy 272.858872 -156.008376)
			(xy 272.777154 -155.81501) (xy 272.702858 -155.618673) (xy 272.63609 -155.41965) (xy 272.576948 -155.218229)
			(xy 272.525516 -155.014703) (xy 272.481871 -154.809366) (xy 272.446074 -154.602516) (xy 272.418178 -154.394454)
			(xy 272.398224 -154.18548) (xy 272.386239 -153.975898) (xy 272.382243 -153.766012) (xy 199.467428 -153.766012)
			(xy 199.46747 -153.774902) (xy 199.46697 -153.879864) (xy 199.458978 -154.089636) (xy 199.443006 -154.298952)
			(xy 199.419076 -154.507508) (xy 199.387224 -154.715001) (xy 199.347496 -154.921132) (xy 199.299949 -155.125601)
			(xy 199.244652 -155.328111) (xy 199.181685 -155.528369) (xy 199.11114 -155.726085) (xy 199.033119 -155.920972)
			(xy 198.947735 -156.112747) (xy 198.855112 -156.301133) (xy 198.755385 -156.485856) (xy 198.648697 -156.666648)
			(xy 198.535203 -156.843248) (xy 198.415068 -157.015398) (xy 198.288467 -157.182851) (xy 198.155582 -157.345362)
			(xy 198.016607 -157.502696) (xy 197.871743 -157.654625) (xy 197.7212 -157.800929) (xy 197.565196 -157.941396)
			(xy 197.403957 -158.075822) (xy 197.237717 -158.204011) (xy 197.066718 -158.325779) (xy 196.891207 -158.440949)
			(xy 196.711439 -158.549353) (xy 196.527674 -158.650835) (xy 196.340178 -158.745247) (xy 196.149225 -158.832453)
			(xy 195.955089 -158.912326) (xy 195.758054 -158.98475) (xy 195.558404 -159.04962) (xy 195.356429 -159.106842)
			(xy 195.152423 -159.156334) (xy 194.946679 -159.198023) (xy 194.739498 -159.231848) (xy 194.53118 -159.257762)
			(xy 194.322026 -159.275727) (xy 194.112339 -159.285715) (xy 193.902425 -159.287714) (xy 193.692586 -159.281719)
			(xy 193.483128 -159.26774) (xy 193.274353 -159.245797) (xy 193.066566 -159.215922) (xy 192.860067 -159.178157)
			(xy 192.655154 -159.132559) (xy 192.452127 -159.079192) (xy 192.251278 -159.018135) (xy 192.0529 -158.949476)
			(xy 191.857279 -158.873313) (xy 191.664699 -158.789759) (xy 191.475441 -158.698934) (xy 191.289777 -158.600969)
			(xy 191.107977 -158.496007) (xy 190.930305 -158.3842) (xy 190.757019 -158.265709) (xy 190.588369 -158.140708)
			(xy 190.4246 -158.009376) (xy 190.26595 -157.871905) (xy 190.112648 -157.728494) (xy 189.964918 -157.57935)
			(xy 189.822972 -157.42469) (xy 189.687018 -157.264739) (xy 189.557251 -157.099727) (xy 189.433861 -156.929895)
			(xy 189.317026 -156.755488) (xy 189.206915 -156.57676) (xy 189.103688 -156.393969) (xy 189.007495 -156.207381)
			(xy 188.918476 -156.017266) (xy 188.836758 -155.8239) (xy 188.762462 -155.627563) (xy 188.695694 -155.42854)
			(xy 188.636552 -155.227119) (xy 188.58512 -155.023593) (xy 188.541475 -154.818256) (xy 188.505678 -154.611406)
			(xy 188.477782 -154.403344) (xy 188.457828 -154.19437) (xy 188.445843 -153.984788) (xy 188.441847 -153.774902)
			(xy 151.160334 -153.774902) (xy 168.043352 -170.657774) (xy 168.070276 -170.664378) (xy 168.083992 -170.660314)
			(xy 168.12028 -170.649658) (xy 168.19443 -170.634738) (xy 168.269694 -170.627246) (xy 168.307512 -170.626786)
			(xy 168.347446 -170.627303) (xy 168.426876 -170.635653) (xy 168.504999 -170.652259) (xy 168.580957 -170.676941)
			(xy 168.65392 -170.709427) (xy 168.723088 -170.749361) (xy 168.787702 -170.796307) (xy 168.847055 -170.849749)
			(xy 168.900497 -170.909103) (xy 168.947442 -170.973718) (xy 168.987376 -171.042885) (xy 169.019861 -171.115848)
			(xy 169.044542 -171.191807) (xy 169.061148 -171.26993) (xy 169.069497 -171.34936) (xy 169.07002 -171.389294)
			(xy 169.069543 -171.427111) (xy 169.062039 -171.502371) (xy 169.047133 -171.576522) (xy 169.036492 -171.612814)
			(xy 169.034166 -171.621729) (xy 169.035313 -171.6401) (xy 169.042932 -171.656856) (xy 169.049192 -171.663614)
			(xy 182.548022 -185.162698) (xy 182.555421 -185.16954) (xy 182.574021 -185.177259) (xy 182.58409 -185.177684)
			(xy 205.71333 -185.177684) (xy 205.723404 -185.178071) (xy 205.742003 -185.185816) (xy 205.749398 -185.19267)
			(xy 208.219294 -187.662312) (xy 208.226131 -187.669715) (xy 208.233853 -187.688312) (xy 208.23428 -187.69838)
			(xy 208.23428 -190.6199) (xy 220.033398 -190.6199) (xy 220.03731 -190.542762) (xy 220.049006 -190.466416)
			(xy 220.068364 -190.391644) (xy 220.095188 -190.319215) (xy 220.129202 -190.249871) (xy 220.170056 -190.184323)
			(xy 220.217331 -190.123245) (xy 220.270543 -190.067262) (xy 220.329145 -190.01695) (xy 220.392537 -189.972825)
			(xy 220.460067 -189.935338) (xy 220.531043 -189.904876) (xy 220.604736 -189.88175) (xy 220.680391 -189.866198)
			(xy 220.757232 -189.85838) (xy 220.79585 -189.857888) (xy 220.837466 -189.858409) (xy 220.920202 -189.867482)
			(xy 221.001458 -189.885515) (xy 221.080264 -189.912294) (xy 221.155685 -189.947499) (xy 221.226821 -189.990711)
			(xy 221.260162 -190.015622) (xy 221.269352 -190.02199) (xy 221.29115 -190.026845) (xy 221.312948 -190.02199)
			(xy 221.322138 -190.015622) (xy 221.355468 -189.990697) (xy 221.426608 -189.947493) (xy 221.502032 -189.912297)
			(xy 221.580841 -189.885528) (xy 221.662098 -189.867505) (xy 221.744834 -189.858442) (xy 221.78645 -189.857888)
			(xy 221.826358 -189.858375) (xy 221.905736 -189.866722) (xy 221.983807 -189.883321) (xy 222.059715 -189.90799)
			(xy 222.132629 -189.940457) (xy 222.20175 -189.980367) (xy 222.266321 -190.027284) (xy 222.325634 -190.080693)
			(xy 222.37904 -190.140009) (xy 222.425953 -190.204582) (xy 222.465861 -190.273705) (xy 222.498324 -190.346621)
			(xy 222.522989 -190.42253) (xy 222.539584 -190.500602) (xy 222.547927 -190.57998) (xy 222.54845 -190.619888)
			(xy 222.548035 -190.657331) (xy 222.54069 -190.731856) (xy 222.52607 -190.805302) (xy 222.504315 -190.876959)
			(xy 222.475635 -190.946136) (xy 222.440308 -191.012165) (xy 222.398674 -191.074411) (xy 222.351134 -191.132273)
			(xy 222.298147 -191.185191) (xy 222.240225 -191.232657) (xy 222.177926 -191.274211) (xy 222.145098 -191.292226)
			(xy 222.136576 -191.297399) (xy 222.123923 -191.312776) (xy 222.118027 -191.331797) (xy 222.118428 -191.341756)
			(xy 222.120206 -191.376554) (xy 222.11972 -191.403823) (xy 222.111958 -191.457807) (xy 222.096593 -191.510137)
			(xy 222.073936 -191.559747) (xy 222.04445 -191.605628) (xy 222.008735 -191.646845) (xy 221.967518 -191.68256)
			(xy 221.921637 -191.712046) (xy 221.872027 -191.734703) (xy 221.819697 -191.750068) (xy 221.765713 -191.75783)
			(xy 221.711175 -191.75783) (xy 221.657191 -191.750068) (xy 221.604861 -191.734703) (xy 221.555251 -191.712046)
			(xy 221.50937 -191.68256) (xy 221.468153 -191.646845) (xy 221.432438 -191.605628) (xy 221.402952 -191.559747)
			(xy 221.380295 -191.510137) (xy 221.36493 -191.457807) (xy 221.357168 -191.403823) (xy 221.356682 -191.376554)
			(xy 221.356682 -191.375792) (xy 221.356934 -191.355115) (xy 221.36139 -191.314001) (xy 221.365572 -191.29375)
			(xy 221.367257 -191.28395) (xy 221.363905 -191.264374) (xy 221.353327 -191.247565) (xy 221.345506 -191.241426)
			(xy 221.322138 -191.224154) (xy 221.312948 -191.217786) (xy 221.29115 -191.212931) (xy 221.269352 -191.217786)
			(xy 221.260162 -191.224154) (xy 221.22684 -191.24909) (xy 221.155697 -191.292291) (xy 221.080272 -191.327484)
			(xy 221.001461 -191.354251) (xy 220.920203 -191.372272) (xy 220.837466 -191.381334) (xy 220.79585 -191.381888)
			(xy 220.757232 -191.38142) (xy 220.680391 -191.373602) (xy 220.604736 -191.35805) (xy 220.531043 -191.334924)
			(xy 220.460067 -191.304462) (xy 220.392537 -191.266975) (xy 220.329145 -191.22285) (xy 220.270543 -191.172538)
			(xy 220.217331 -191.116555) (xy 220.170056 -191.055477) (xy 220.129202 -190.989929) (xy 220.095188 -190.920585)
			(xy 220.068364 -190.848156) (xy 220.049006 -190.773384) (xy 220.03731 -190.697038) (xy 220.033398 -190.6199)
			(xy 208.23428 -190.6199) (xy 208.23428 -192.589658) (xy 208.233838 -192.599725) (xy 208.226129 -192.618324)
			(xy 208.219294 -192.625726) (xy 207.677766 -193.167254) (xy 207.671157 -193.174606) (xy 207.663553 -193.19283)
			(xy 207.663397 -193.212576) (xy 207.670713 -193.230917) (xy 207.684417 -193.245135) (xy 207.69326 -193.24955)
			(xy 207.729072 -193.265921) (xy 207.79739 -193.305081) (xy 207.861226 -193.351188) (xy 207.919877 -193.403733)
			(xy 207.972696 -193.462136) (xy 208.019102 -193.525755) (xy 208.058583 -193.593888) (xy 208.090704 -193.665785)
			(xy 208.115111 -193.740652) (xy 208.131535 -193.817666) (xy 208.139795 -193.895977) (xy 208.1403 -193.93535)
			(xy 208.139804 -193.97299) (xy 208.13226 -194.047892) (xy 208.117242 -194.121659) (xy 208.094903 -194.193548)
			(xy 208.065468 -194.262835) (xy 208.029232 -194.328821) (xy 207.986562 -194.39084) (xy 207.937888 -194.448268)
			(xy 207.8837 -194.500525) (xy 207.824545 -194.547085) (xy 207.76102 -194.587478) (xy 207.693763 -194.621297)
			(xy 207.623455 -194.648201) (xy 207.550802 -194.667919) (xy 207.476539 -194.680251) (xy 207.439006 -194.683126)
			(xy 207.429453 -194.684189) (xy 207.412107 -194.692435) (xy 207.39899 -194.706464) (xy 207.391926 -194.724324)
			(xy 207.391508 -194.733926) (xy 207.391508 -194.80911) (xy 207.391 -194.809618) (xy 207.391 -210.116166)
			(xy 207.414368 -210.14436) (xy 207.432656 -210.147662) (xy 207.459064 -210.153096) (xy 207.510086 -210.170509)
			(xy 207.55803 -210.195166) (xy 207.601873 -210.226539) (xy 207.640681 -210.263961) (xy 207.673628 -210.306634)
			(xy 207.700012 -210.353649) (xy 207.719269 -210.404005) (xy 207.730991 -210.456627) (xy 207.734926 -210.510395)
			(xy 207.730992 -210.564164) (xy 207.719272 -210.616786) (xy 207.700016 -210.667142) (xy 207.673634 -210.714158)
			(xy 207.640688 -210.756832) (xy 207.60188 -210.794255) (xy 207.558038 -210.825629) (xy 207.510095 -210.850287)
			(xy 207.459073 -210.867702) (xy 207.432656 -210.873086) (xy 207.414368 -210.876388) (xy 207.391 -210.904582)
			(xy 207.391 -213.806024) (xy 255.16332 -213.806024) (xy 255.163939 -213.763335) (xy 255.173499 -213.678492)
			(xy 255.192458 -213.595245) (xy 255.220578 -213.514629) (xy 255.257511 -213.437652) (xy 255.279652 -213.401148)
			(xy 255.28433 -213.392878) (xy 255.287848 -213.374221) (xy 255.284345 -213.355561) (xy 255.279652 -213.3473)
			(xy 255.257505 -213.310799) (xy 255.22056 -213.233825) (xy 255.192433 -213.15321) (xy 255.173475 -213.06996)
			(xy 255.163925 -212.985114) (xy 255.16332 -212.942424) (xy 255.163766 -212.903597) (xy 255.171658 -212.826346)
			(xy 255.187352 -212.750295) (xy 255.210688 -212.676231) (xy 255.241422 -212.604918) (xy 255.279239 -212.537095)
			(xy 255.323746 -212.473462) (xy 255.374484 -212.414677) (xy 255.430928 -212.361347) (xy 255.492496 -212.314023)
			(xy 255.52527 -212.2932) (xy 255.534579 -212.286756) (xy 255.546843 -212.26776) (xy 255.548892 -212.256624)
			(xy 255.553093 -212.229107) (xy 255.568404 -212.175594) (xy 255.591341 -212.124878) (xy 255.621414 -212.07804)
			(xy 255.639316 -212.056726) (xy 255.63957 -212.056472) (xy 255.645141 -212.049375) (xy 255.651395 -212.032466)
			(xy 255.651762 -212.023452) (xy 255.651762 -211.956396) (xy 255.651415 -211.947378) (xy 255.645162 -211.930461)
			(xy 255.63957 -211.923376) (xy 255.639316 -211.923122) (xy 255.619442 -211.899446) (xy 255.586881 -211.846907)
			(xy 255.563219 -211.789803) (xy 255.549076 -211.729631) (xy 255.546352 -211.69884) (xy 255.5448 -211.686853)
			(xy 255.532356 -211.666175) (xy 255.522476 -211.659216) (xy 255.489925 -211.638335) (xy 255.428804 -211.590946)
			(xy 255.372787 -211.537622) (xy 255.322446 -211.478909) (xy 255.278297 -211.415408) (xy 255.240794 -211.34777)
			(xy 255.210319 -211.276687) (xy 255.187185 -211.202889) (xy 255.171628 -211.127129) (xy 255.163809 -211.050186)
			(xy 255.16332 -211.011516) (xy 255.163935 -210.968827) (xy 255.173496 -210.883984) (xy 255.192455 -210.800736)
			(xy 255.220577 -210.720121) (xy 255.25751 -210.643144) (xy 255.279652 -210.60664) (xy 255.284337 -210.598373)
			(xy 255.287852 -210.579714) (xy 255.284347 -210.561053) (xy 255.279652 -210.552792) (xy 255.257502 -210.516293)
			(xy 255.220557 -210.439318) (xy 255.192431 -210.358703) (xy 255.173474 -210.275452) (xy 255.163924 -210.190607)
			(xy 255.16332 -210.147916) (xy 255.163795 -210.109245) (xy 255.171604 -210.032298) (xy 255.187153 -209.956536)
			(xy 255.210285 -209.882734) (xy 255.24076 -209.811649) (xy 255.278267 -209.74401) (xy 255.322422 -209.680511)
			(xy 255.372771 -209.621802) (xy 255.428798 -209.568486) (xy 255.48993 -209.521108) (xy 255.522476 -209.500216)
			(xy 255.532389 -209.493286) (xy 255.544847 -209.472594) (xy 255.546352 -209.460592) (xy 255.549098 -209.429807)
			(xy 255.563274 -209.36965) (xy 255.58694 -209.312557) (xy 255.61948 -209.260013) (xy 255.639316 -209.23631)
			(xy 255.63957 -209.236056) (xy 255.645147 -209.228964) (xy 255.651398 -209.212051) (xy 255.651762 -209.203036)
			(xy 255.651762 -209.13598) (xy 255.651423 -209.126961) (xy 255.645164 -209.110044) (xy 255.63957 -209.10296)
			(xy 255.639316 -209.102706) (xy 255.621436 -209.081376) (xy 255.591386 -209.034529) (xy 255.568446 -208.98382)
			(xy 255.553101 -208.930321) (xy 255.548892 -208.902808) (xy 255.546808 -208.891691) (xy 255.534539 -208.872717)
			(xy 255.52527 -208.866232) (xy 255.492511 -208.845387) (xy 255.430943 -208.798068) (xy 255.374498 -208.744742)
			(xy 255.323761 -208.685959) (xy 255.279255 -208.622328) (xy 255.241441 -208.554507) (xy 255.210709 -208.483196)
			(xy 255.187377 -208.409133) (xy 255.171688 -208.333083) (xy 255.163801 -208.255834) (xy 255.16332 -208.217008)
			(xy 255.163932 -208.174318) (xy 255.173493 -208.089476) (xy 255.192453 -208.006228) (xy 255.220576 -207.925613)
			(xy 255.25751 -207.848635) (xy 255.279652 -207.812132) (xy 255.284343 -207.803868) (xy 255.287856 -207.785207)
			(xy 255.284348 -207.766545) (xy 255.279652 -207.758284) (xy 255.257498 -207.721786) (xy 255.220554 -207.644812)
			(xy 255.192428 -207.564195) (xy 255.173473 -207.480945) (xy 255.163924 -207.396099) (xy 255.16332 -207.353408)
			(xy 255.163753 -207.314581) (xy 255.171646 -207.237329) (xy 255.187343 -207.161278) (xy 255.21068 -207.087213)
			(xy 255.241416 -207.015901) (xy 255.279233 -206.948078) (xy 255.323742 -206.884445) (xy 255.374481 -206.82566)
			(xy 255.430927 -206.77233) (xy 255.492495 -206.725007) (xy 255.52527 -206.704184) (xy 255.534585 -206.697747)
			(xy 255.546846 -206.678746) (xy 255.548892 -206.667608) (xy 255.553086 -206.64009) (xy 255.568399 -206.586576)
			(xy 255.591338 -206.535861) (xy 255.621413 -206.489024) (xy 255.639316 -206.46771) (xy 255.63957 -206.467456)
			(xy 255.645147 -206.460364) (xy 255.651398 -206.443451) (xy 255.651762 -206.434436) (xy 255.651762 -206.367634)
			(xy 255.651322 -206.35845) (xy 255.644828 -206.341266) (xy 255.639062 -206.334106) (xy 255.620353 -206.311792)
			(xy 255.589219 -206.262588) (xy 255.565924 -206.209223) (xy 255.551009 -206.152938) (xy 255.547368 -206.124048)
			(xy 255.546084 -206.115048) (xy 255.537998 -206.098778) (xy 255.53162 -206.092298) (xy 255.498385 -206.071602)
			(xy 255.435934 -206.024373) (xy 255.378648 -205.970997) (xy 255.32713 -205.912035) (xy 255.281921 -205.848106)
			(xy 255.243497 -205.779884) (xy 255.212263 -205.708085) (xy 255.188545 -205.633465) (xy 255.172594 -205.556809)
			(xy 255.164578 -205.478921) (xy 255.164082 -205.439772) (xy 255.16448 -205.403376) (xy 255.17138 -205.330911)
			(xy 255.185153 -205.259433) (xy 255.205672 -205.189593) (xy 255.232752 -205.122025) (xy 255.266147 -205.057345)
			(xy 255.285494 -205.026514) (xy 255.288632 -205.017506) (xy 255.288622 -204.998443) (xy 255.285494 -204.98943)
			(xy 255.266145 -204.958601) (xy 255.232764 -204.893915) (xy 255.205692 -204.826346) (xy 255.185175 -204.756506)
			(xy 255.171401 -204.68503) (xy 255.164493 -204.612568) (xy 255.164082 -204.576172) (xy 255.164559 -204.537023)
			(xy 255.17258 -204.459137) (xy 255.188536 -204.382481) (xy 255.212258 -204.307863) (xy 255.243497 -204.236067)
			(xy 255.281924 -204.167847) (xy 255.327136 -204.103921) (xy 255.378657 -204.044961) (xy 255.435945 -203.991588)
			(xy 255.498398 -203.944363) (xy 255.53162 -203.923646) (xy 255.537978 -203.917154) (xy 255.546046 -203.900886)
			(xy 255.547368 -203.891896) (xy 255.551019 -203.863009) (xy 255.565954 -203.806732) (xy 255.589248 -203.753371)
			(xy 255.620365 -203.704159) (xy 255.639062 -203.681838) (xy 255.644875 -203.674705) (xy 255.651378 -203.657505)
			(xy 255.651762 -203.64831) (xy 255.651762 -203.581508) (xy 255.651409 -203.572491) (xy 255.645159 -203.555573)
			(xy 255.63957 -203.548488) (xy 255.639316 -203.548234) (xy 255.621446 -203.526896) (xy 255.591394 -203.480052)
			(xy 255.568451 -203.429345) (xy 255.553103 -203.375848) (xy 255.548892 -203.348336) (xy 255.546794 -203.337222)
			(xy 255.534535 -203.318247) (xy 255.52527 -203.31176) (xy 255.492478 -203.290965) (xy 255.43091 -203.24364)
			(xy 255.374466 -203.190308) (xy 255.32373 -203.13152) (xy 255.279227 -203.067883) (xy 255.241416 -203.000056)
			(xy 255.210688 -202.928739) (xy 255.187361 -202.854671) (xy 255.171677 -202.778617) (xy 255.163798 -202.701363)
			(xy 255.16332 -202.662536) (xy 255.163945 -202.619847) (xy 255.173503 -202.535005) (xy 255.192461 -202.451757)
			(xy 255.22058 -202.371142) (xy 255.257511 -202.294164) (xy 255.279652 -202.25766) (xy 255.284321 -202.249385)
			(xy 255.287841 -202.230731) (xy 255.284343 -202.212073) (xy 255.279652 -202.203812) (xy 255.25751 -202.167308)
			(xy 255.220564 -202.090335) (xy 255.192436 -202.00972) (xy 255.173477 -201.926471) (xy 255.163925 -201.841626)
			(xy 255.16332 -201.798936) (xy 255.163775 -201.76011) (xy 255.171666 -201.682858) (xy 255.18736 -201.606808)
			(xy 255.210694 -201.532744) (xy 255.241427 -201.461431) (xy 255.279243 -201.393608) (xy 255.323749 -201.329975)
			(xy 255.374486 -201.271189) (xy 255.430929 -201.217859) (xy 255.492496 -201.170535) (xy 255.52527 -201.149712)
			(xy 255.534575 -201.143263) (xy 255.546841 -201.12427) (xy 255.548892 -201.113136) (xy 255.553098 -201.08562)
			(xy 255.568408 -201.032107) (xy 255.591343 -200.981391) (xy 255.621414 -200.934553) (xy 255.639316 -200.913238)
			(xy 255.63957 -200.912984) (xy 255.645178 -200.905912) (xy 255.65141 -200.888984) (xy 255.651762 -200.879964)
			(xy 255.651762 -200.812908) (xy 255.651409 -200.803891) (xy 255.645159 -200.786973) (xy 255.63957 -200.779888)
			(xy 255.639316 -200.779634) (xy 255.619447 -200.755955) (xy 255.586884 -200.703416) (xy 255.563221 -200.646314)
			(xy 255.549077 -200.586143) (xy 255.546352 -200.555352) (xy 255.544794 -200.543367) (xy 255.532354 -200.522688)
			(xy 255.522476 -200.515728) (xy 255.489931 -200.494839) (xy 255.42881 -200.447451) (xy 255.372792 -200.394128)
			(xy 255.322451 -200.335415) (xy 255.278302 -200.271915) (xy 255.240798 -200.204278) (xy 255.210322 -200.133197)
			(xy 255.187187 -200.059399) (xy 255.17163 -199.98364) (xy 255.16381 -199.906698) (xy 255.16332 -199.868028)
			(xy 255.163941 -199.825339) (xy 255.173501 -199.740497) (xy 255.192459 -199.657249) (xy 255.220579 -199.576634)
			(xy 255.257511 -199.499656) (xy 255.279652 -199.463152) (xy 255.284327 -199.45488) (xy 255.287846 -199.436224)
			(xy 255.284345 -199.417565) (xy 255.279652 -199.409304) (xy 255.257507 -199.372802) (xy 255.220561 -199.295828)
			(xy 255.192434 -199.215213) (xy 255.173476 -199.131963) (xy 255.163925 -199.047118) (xy 255.16332 -199.004428)
			(xy 255.163804 -198.965757) (xy 255.171612 -198.888811) (xy 255.187161 -198.813048) (xy 255.210291 -198.739247)
			(xy 255.240765 -198.668162) (xy 255.278271 -198.600523) (xy 255.322425 -198.537024) (xy 255.372773 -198.478315)
			(xy 255.4288 -198.424998) (xy 255.489931 -198.37762) (xy 255.522476 -198.356728) (xy 255.532384 -198.349793)
			(xy 255.544845 -198.329104) (xy 255.546352 -198.317104) (xy 255.549104 -198.286319) (xy 255.563279 -198.226163)
			(xy 255.586943 -198.16907) (xy 255.619481 -198.116525) (xy 255.639316 -198.092822) (xy 255.63957 -198.092568)
			(xy 255.645142 -198.085472) (xy 255.651396 -198.068562) (xy 255.651762 -198.059548) (xy 255.651762 -197.992492)
			(xy 255.651417 -197.983474) (xy 255.645162 -197.966556) (xy 255.63957 -197.959472) (xy 255.639316 -197.959218)
			(xy 255.62144 -197.937885) (xy 255.591389 -197.891039) (xy 255.568448 -197.840331) (xy 255.553102 -197.786832)
			(xy 255.548892 -197.75932) (xy 255.546803 -197.748204) (xy 255.534537 -197.72923) (xy 255.52527 -197.722744)
			(xy 255.492516 -197.701891) (xy 255.430948 -197.654573) (xy 255.374504 -197.601247) (xy 255.323766 -197.542466)
			(xy 255.27926 -197.478836) (xy 255.241445 -197.411015) (xy 255.210712 -197.339705) (xy 255.18738 -197.265643)
			(xy 255.171689 -197.189594) (xy 255.163802 -197.112345) (xy 255.16332 -197.07352) (xy 255.163937 -197.030831)
			(xy 255.173498 -196.945988) (xy 255.192457 -196.862741) (xy 255.220578 -196.782125) (xy 255.257511 -196.705148)
			(xy 255.279652 -196.668644) (xy 255.284334 -196.660375) (xy 255.28785 -196.641717) (xy 255.284346 -196.623057)
			(xy 255.279652 -196.614796) (xy 255.257503 -196.578296) (xy 255.220558 -196.501322) (xy 255.192432 -196.420706)
			(xy 255.173475 -196.337456) (xy 255.163924 -196.25261) (xy 255.16332 -196.20992) (xy 255.163762 -196.171093)
			(xy 255.171655 -196.093842) (xy 255.18735 -196.017791) (xy 255.210686 -195.943726) (xy 255.241421 -195.872414)
			(xy 255.279237 -195.804591) (xy 255.323745 -195.740958) (xy 255.374483 -195.682172) (xy 255.430928 -195.628842)
			(xy 255.492496 -195.581519) (xy 255.52527 -195.560696) (xy 255.534581 -195.554254) (xy 255.546844 -195.535256)
			(xy 255.548892 -195.52412) (xy 255.553091 -195.496603) (xy 255.568403 -195.443089) (xy 255.59134 -195.392374)
			(xy 255.621413 -195.345536) (xy 255.639316 -195.324222) (xy 255.63957 -195.323968) (xy 255.645142 -195.316872)
			(xy 255.651396 -195.299962) (xy 255.651762 -195.290948) (xy 255.651762 -195.224146) (xy 255.651316 -195.214963)
			(xy 255.644826 -195.197779) (xy 255.639062 -195.190618) (xy 255.620358 -195.168301) (xy 255.589223 -195.119097)
			(xy 255.565926 -195.065734) (xy 255.55101 -195.00945) (xy 255.547368 -194.98056) (xy 255.546079 -194.971561)
			(xy 255.537996 -194.955291) (xy 255.53162 -194.94881) (xy 255.498391 -194.928105) (xy 255.43594 -194.880878)
			(xy 255.378654 -194.827503) (xy 255.327135 -194.768541) (xy 255.281926 -194.704614) (xy 255.243502 -194.636392)
			(xy 255.212266 -194.564595) (xy 255.188548 -194.489975) (xy 255.172596 -194.41332) (xy 255.164579 -194.335433)
			(xy 255.164082 -194.296284) (xy 255.164514 -194.259986) (xy 255.171408 -194.187719) (xy 255.185132 -194.116433)
			(xy 255.205562 -194.046772) (xy 255.232514 -193.979366) (xy 255.265744 -193.914823) (xy 255.284986 -193.884042)
			(xy 255.288584 -193.872805) (xy 255.286207 -193.849362) (xy 255.280414 -193.839084) (xy 255.258091 -193.802485)
			(xy 255.220891 -193.725245) (xy 255.192574 -193.644324) (xy 255.173496 -193.560742) (xy 255.163898 -193.47555)
			(xy 255.16332 -193.432684) (xy 255.163873 -193.392157) (xy 255.172446 -193.311559) (xy 255.189503 -193.232321)
			(xy 255.214854 -193.155334) (xy 255.248213 -193.081464) (xy 255.289205 -193.01154) (xy 255.33737 -192.94635)
			(xy 255.392166 -192.886626) (xy 255.452978 -192.833038) (xy 255.519121 -192.78619) (xy 255.554226 -192.765934)
			(xy 255.56392 -192.759704) (xy 255.57712 -192.740858) (xy 255.579626 -192.729612) (xy 255.584278 -192.703006)
			(xy 255.600108 -192.651367) (xy 255.623062 -192.602476) (xy 255.652679 -192.55731) (xy 255.688369 -192.516772)
			(xy 255.729419 -192.48167) (xy 255.775007 -192.452707) (xy 255.824224 -192.430461) (xy 255.876086 -192.415377)
			(xy 255.929557 -192.407757) (xy 255.956562 -192.407286) (xy 255.985332 -192.407765) (xy 256.04222 -192.416394)
			(xy 256.097169 -192.433464) (xy 256.148934 -192.458586) (xy 256.196343 -192.491193) (xy 256.238321 -192.530545)
			(xy 256.273918 -192.575751) (xy 256.302327 -192.625787) (xy 256.322906 -192.679521) (xy 256.335187 -192.735734)
			(xy 256.337562 -192.76441) (xy 256.338811 -192.775907) (xy 256.350203 -192.796011) (xy 256.359406 -192.803018)
			(xy 256.392994 -192.826768) (xy 256.455417 -192.880349) (xy 256.511721 -192.940328) (xy 256.561252 -193.006012)
			(xy 256.603436 -193.076638) (xy 256.637786 -193.151389) (xy 256.663903 -193.229398) (xy 256.681485 -193.309763)
			(xy 256.690329 -193.391551) (xy 256.690876 -193.432684) (xy 256.690293 -193.47555) (xy 256.680694 -193.560742)
			(xy 256.661617 -193.644323) (xy 256.6333 -193.725242) (xy 256.5961 -193.802482) (xy 256.573782 -193.839084)
			(xy 256.568034 -193.849375) (xy 256.565656 -193.872802) (xy 256.56921 -193.884042) (xy 256.588441 -193.91483)
			(xy 256.621674 -193.97937) (xy 256.648629 -194.046775) (xy 256.669062 -194.116435) (xy 256.682788 -194.18772)
			(xy 256.689683 -194.259987) (xy 256.690114 -194.296284) (xy 256.689604 -194.335432) (xy 256.681587 -194.413317)
			(xy 256.665636 -194.489972) (xy 256.664792 -194.492626) (xy 259.713222 -194.492626) (xy 259.713799 -194.451012)
			(xy 259.722863 -194.368278) (xy 259.740886 -194.287024) (xy 259.767655 -194.208217) (xy 259.802849 -194.132796)
			(xy 259.84605 -194.061657) (xy 259.870956 -194.028314) (xy 259.877298 -194.019109) (xy 259.882159 -193.997321)
			(xy 259.877316 -193.975529) (xy 259.870956 -193.966338) (xy 259.846056 -193.93299) (xy 259.802851 -193.861853)
			(xy 259.767652 -193.786433) (xy 259.740878 -193.707628) (xy 259.72285 -193.626374) (xy 259.71378 -193.543641)
			(xy 259.713222 -193.502026) (xy 259.713711 -193.463407) (xy 259.721525 -193.386564) (xy 259.737073 -193.310906)
			(xy 259.760196 -193.237209) (xy 259.790655 -193.16623) (xy 259.82814 -193.098696) (xy 259.872264 -193.035302)
			(xy 259.922575 -192.976696) (xy 259.978557 -192.923481) (xy 260.039636 -192.876202) (xy 260.105184 -192.835346)
			(xy 260.17453 -192.80133) (xy 260.246961 -192.774505) (xy 260.321734 -192.755145) (xy 260.398082 -192.743449)
			(xy 260.475222 -192.739537) (xy 260.552362 -192.743449) (xy 260.62871 -192.755145) (xy 260.703483 -192.774505)
			(xy 260.775914 -192.80133) (xy 260.84526 -192.835346) (xy 260.910808 -192.876202) (xy 260.971887 -192.923481)
			(xy 261.027869 -192.976696) (xy 261.07818 -193.035302) (xy 261.122304 -193.098696) (xy 261.159789 -193.16623)
			(xy 261.190248 -193.237209) (xy 261.213371 -193.310906) (xy 261.228919 -193.386564) (xy 261.236733 -193.463407)
			(xy 261.237222 -193.502026) (xy 261.236686 -193.543642) (xy 261.227615 -193.626377) (xy 261.209585 -193.707632)
			(xy 261.182809 -193.786439) (xy 261.147607 -193.86186) (xy 261.104398 -193.932996) (xy 261.079488 -193.966338)
			(xy 261.073095 -193.975514) (xy 261.068245 -193.997321) (xy 261.073112 -194.019124) (xy 261.079488 -194.028314)
			(xy 261.104404 -194.061651) (xy 261.147609 -194.132789) (xy 261.182806 -194.208212) (xy 261.209577 -194.28702)
			(xy 261.227602 -194.368275) (xy 261.236667 -194.451011) (xy 261.237222 -194.492626) (xy 261.236733 -194.531245)
			(xy 261.228919 -194.608088) (xy 261.213371 -194.683746) (xy 261.190248 -194.757443) (xy 261.159789 -194.828422)
			(xy 261.122304 -194.895956) (xy 261.07818 -194.95935) (xy 261.027869 -195.017956) (xy 260.971887 -195.071171)
			(xy 260.910808 -195.11845) (xy 260.84526 -195.159306) (xy 260.775914 -195.193322) (xy 260.703483 -195.220147)
			(xy 260.62871 -195.239507) (xy 260.552362 -195.251203) (xy 260.475222 -195.255116) (xy 260.398082 -195.251203)
			(xy 260.321734 -195.239507) (xy 260.246961 -195.220147) (xy 260.17453 -195.193322) (xy 260.105184 -195.159306)
			(xy 260.039636 -195.11845) (xy 259.978557 -195.071171) (xy 259.922575 -195.017956) (xy 259.872264 -194.95935)
			(xy 259.82814 -194.895956) (xy 259.790655 -194.828422) (xy 259.760196 -194.757443) (xy 259.737073 -194.683746)
			(xy 259.721525 -194.608088) (xy 259.713711 -194.531245) (xy 259.713222 -194.492626) (xy 256.664792 -194.492626)
			(xy 256.641918 -194.56459) (xy 256.610683 -194.636386) (xy 256.572259 -194.704606) (xy 256.52705 -194.768533)
			(xy 256.475532 -194.827493) (xy 256.418247 -194.880867) (xy 256.355797 -194.928093) (xy 256.322576 -194.94881)
			(xy 256.316234 -194.955315) (xy 256.308157 -194.971573) (xy 256.306828 -194.98056) (xy 256.303157 -195.009444)
			(xy 256.288229 -195.065721) (xy 256.26494 -195.119083) (xy 256.233829 -195.168296) (xy 256.215134 -195.190618)
			(xy 256.209339 -195.197764) (xy 256.202825 -195.214954) (xy 256.202434 -195.224146) (xy 256.202434 -195.290948)
			(xy 256.202809 -195.299963) (xy 256.209043 -195.316881) (xy 256.214626 -195.323968) (xy 256.21488 -195.324222)
			(xy 256.23277 -195.345544) (xy 256.262818 -195.392394) (xy 256.285755 -195.443105) (xy 256.301096 -195.496607)
			(xy 256.305304 -195.52412) (xy 256.307425 -195.535227) (xy 256.319668 -195.554205) (xy 256.328926 -195.560696)
			(xy 256.361697 -195.581523) (xy 256.423265 -195.628844) (xy 256.479709 -195.682172) (xy 256.530447 -195.740957)
			(xy 256.574952 -195.80459) (xy 256.612765 -195.872414) (xy 256.643495 -195.943727) (xy 256.666825 -196.017792)
			(xy 256.682512 -196.093843) (xy 256.690396 -196.171094) (xy 256.690876 -196.20992) (xy 256.690278 -196.25261)
			(xy 256.680713 -196.337453) (xy 256.66175 -196.420701) (xy 256.633625 -196.501316) (xy 256.596687 -196.578293)
			(xy 256.574544 -196.614796) (xy 256.56983 -196.623049) (xy 256.566325 -196.641717) (xy 256.569843 -196.660383)
			(xy 256.574544 -196.668644) (xy 256.596709 -196.705135) (xy 256.633651 -196.782112) (xy 256.661775 -196.86273)
			(xy 256.680728 -196.945982) (xy 256.690274 -197.030829) (xy 256.690876 -197.07352) (xy 256.69034 -197.112344)
			(xy 256.682455 -197.189591) (xy 256.666768 -197.265638) (xy 256.643441 -197.3397) (xy 256.612716 -197.41101)
			(xy 256.57491 -197.478833) (xy 256.530413 -197.542467) (xy 256.479685 -197.601255) (xy 256.423252 -197.654589)
			(xy 256.361695 -197.701918) (xy 256.328926 -197.722744) (xy 256.319637 -197.729213) (xy 256.307363 -197.748191)
			(xy 256.305304 -197.75932) (xy 256.301124 -197.78684) (xy 256.285806 -197.840354) (xy 256.262863 -197.891069)
			(xy 256.232785 -197.937905) (xy 256.21488 -197.959218) (xy 256.214626 -197.959472) (xy 256.209036 -197.966556)
			(xy 256.202793 -197.983475) (xy 256.202434 -197.992492) (xy 256.202434 -198.059548) (xy 256.202809 -198.068563)
			(xy 256.209043 -198.085481) (xy 256.214626 -198.092568) (xy 256.21488 -198.092822) (xy 256.23473 -198.116516)
			(xy 256.267297 -198.16905) (xy 256.290965 -198.226147) (xy 256.305116 -198.286314) (xy 256.307844 -198.317104)
			(xy 256.309373 -198.329095) (xy 256.321834 -198.349771) (xy 256.33172 -198.356728) (xy 256.364245 -198.377649)
			(xy 256.425365 -198.425033) (xy 256.481384 -198.478353) (xy 256.531726 -198.537061) (xy 256.575876 -198.600557)
			(xy 256.613383 -198.668191) (xy 256.643861 -198.739269) (xy 256.666999 -198.813064) (xy 256.68256 -198.888819)
			(xy 256.690384 -198.965759) (xy 256.690876 -199.004428) (xy 256.690282 -199.047118) (xy 256.680716 -199.131961)
			(xy 256.661752 -199.215209) (xy 256.633626 -199.295824) (xy 256.596688 -199.372801) (xy 256.574544 -199.409304)
			(xy 256.569824 -199.417554) (xy 256.566321 -199.436224) (xy 256.569841 -199.454891) (xy 256.574544 -199.463152)
			(xy 256.596712 -199.499641) (xy 256.633654 -199.576618) (xy 256.661777 -199.657237) (xy 256.680729 -199.740489)
			(xy 256.690274 -199.825337) (xy 256.690876 -199.868028) (xy 256.690438 -199.9067) (xy 256.682625 -199.983648)
			(xy 256.667071 -200.059412) (xy 256.643935 -200.133214) (xy 256.613456 -200.204299) (xy 256.575945 -200.271937)
			(xy 256.531786 -200.335436) (xy 256.481433 -200.394144) (xy 256.425402 -200.44746) (xy 256.364267 -200.494837)
			(xy 256.33172 -200.515728) (xy 256.321829 -200.522684) (xy 256.309359 -200.543357) (xy 256.307844 -200.555352)
			(xy 256.305121 -200.58614) (xy 256.290938 -200.646297) (xy 256.267265 -200.70339) (xy 256.234719 -200.755932)
			(xy 256.21488 -200.779634) (xy 256.214626 -200.779888) (xy 256.20903 -200.786968) (xy 256.202791 -200.80389)
			(xy 256.202434 -200.812908) (xy 256.202434 -200.879964) (xy 256.202801 -200.88898) (xy 256.209041 -200.905897)
			(xy 256.214626 -200.912984) (xy 256.21488 -200.913238) (xy 256.232776 -200.934555) (xy 256.262822 -200.981407)
			(xy 256.285758 -201.032119) (xy 256.301097 -201.085622) (xy 256.305304 -201.113136) (xy 256.307417 -201.124246)
			(xy 256.319665 -201.143222) (xy 256.328926 -201.149712) (xy 256.361704 -201.170528) (xy 256.423272 -201.21785)
			(xy 256.479717 -201.27118) (xy 256.530453 -201.329966) (xy 256.574958 -201.3936) (xy 256.61277 -201.461425)
			(xy 256.6435 -201.532739) (xy 256.666828 -201.606805) (xy 256.682515 -201.682857) (xy 256.690397 -201.760109)
			(xy 256.690876 -201.798936) (xy 256.690286 -201.841626) (xy 256.680719 -201.926469) (xy 256.661754 -202.009717)
			(xy 256.633627 -202.090332) (xy 256.596688 -202.167309) (xy 256.574544 -202.203812) (xy 256.569817 -202.212059)
			(xy 256.566317 -202.230731) (xy 256.56984 -202.249399) (xy 256.574544 -202.25766) (xy 256.596715 -202.294147)
			(xy 256.633657 -202.371125) (xy 256.661779 -202.451744) (xy 256.68073 -202.534997) (xy 256.690275 -202.619845)
			(xy 256.690876 -202.662536) (xy 256.690353 -202.70136) (xy 256.682466 -202.778608) (xy 256.666778 -202.854655)
			(xy 256.643449 -202.928717) (xy 256.612723 -203.000028) (xy 256.574915 -203.06785) (xy 256.530417 -203.131484)
			(xy 256.479688 -203.190272) (xy 256.423253 -203.243605) (xy 256.361696 -203.290934) (xy 256.328926 -203.31176)
			(xy 256.319631 -203.318221) (xy 256.30736 -203.337205) (xy 256.305304 -203.348336) (xy 256.301131 -203.375857)
			(xy 256.285811 -203.429371) (xy 256.262866 -203.480085) (xy 256.232786 -203.526921) (xy 256.21488 -203.548234)
			(xy 256.214626 -203.548488) (xy 256.20903 -203.555568) (xy 256.202791 -203.57249) (xy 256.202434 -203.581508)
			(xy 256.202434 -203.64831) (xy 256.202854 -203.657496) (xy 256.209363 -203.674679) (xy 256.215134 -203.681838)
			(xy 256.233859 -203.704139) (xy 256.26499 -203.753348) (xy 256.288281 -203.806716) (xy 256.30319 -203.863004)
			(xy 256.306828 -203.891896) (xy 256.308138 -203.90089) (xy 256.316206 -203.917162) (xy 256.322576 -203.923646)
			(xy 256.355785 -203.944383) (xy 256.418236 -203.991607) (xy 256.475522 -204.044978) (xy 256.527042 -204.103936)
			(xy 256.572252 -204.167859) (xy 256.610679 -204.236077) (xy 256.641917 -204.307871) (xy 256.665638 -204.382487)
			(xy 256.681594 -204.45914) (xy 256.689615 -204.537024) (xy 256.690114 -204.576172) (xy 256.689738 -204.612569)
			(xy 256.682834 -204.685034) (xy 256.669057 -204.756512) (xy 256.648534 -204.826353) (xy 256.621449 -204.89392)
			(xy 256.588051 -204.9586) (xy 256.568702 -204.98943) (xy 256.565594 -204.998447) (xy 256.565585 -205.017502)
			(xy 256.568702 -205.026514) (xy 256.588026 -205.057358) (xy 256.621411 -205.12204) (xy 256.648487 -205.189606)
			(xy 256.669008 -205.259443) (xy 256.682788 -205.330917) (xy 256.689701 -205.403377) (xy 256.690114 -205.439772)
			(xy 256.689594 -205.47892) (xy 256.681579 -205.556805) (xy 256.665628 -205.633459) (xy 256.641912 -205.708077)
			(xy 256.610678 -205.779873) (xy 256.572255 -205.848093) (xy 256.527047 -205.91202) (xy 256.47553 -205.97098)
			(xy 256.418246 -206.024354) (xy 256.355797 -206.071581) (xy 256.322576 -206.092298) (xy 256.316201 -206.098775)
			(xy 256.308143 -206.115054) (xy 256.306828 -206.124048) (xy 256.303152 -206.152932) (xy 256.288225 -206.209208)
			(xy 256.264938 -206.26257) (xy 256.233828 -206.311784) (xy 256.215134 -206.334106) (xy 256.209344 -206.341256)
			(xy 256.202827 -206.358443) (xy 256.202434 -206.367634) (xy 256.202434 -206.434436) (xy 256.202766 -206.443456)
			(xy 256.20903 -206.460373) (xy 256.214626 -206.467456) (xy 256.21488 -206.46771) (xy 256.232766 -206.489036)
			(xy 256.262814 -206.535884) (xy 256.285753 -206.586594) (xy 256.301096 -206.640095) (xy 256.305304 -206.667608)
			(xy 256.307431 -206.678714) (xy 256.319669 -206.697692) (xy 256.328926 -206.704184) (xy 256.361692 -206.725019)
			(xy 256.42326 -206.772339) (xy 256.479704 -206.825667) (xy 256.530441 -206.88445) (xy 256.574947 -206.948083)
			(xy 256.612761 -207.015905) (xy 256.643492 -207.087217) (xy 256.666822 -207.161281) (xy 256.682511 -207.237332)
			(xy 256.690395 -207.314582) (xy 256.690876 -207.353408) (xy 256.690273 -207.396098) (xy 256.680709 -207.480941)
			(xy 256.661747 -207.564188) (xy 256.633623 -207.644804) (xy 256.596687 -207.721781) (xy 256.574544 -207.758284)
			(xy 256.56984 -207.766542) (xy 256.566331 -207.785207) (xy 256.569845 -207.803871) (xy 256.574544 -207.812132)
			(xy 256.596704 -207.848626) (xy 256.633647 -207.925602) (xy 256.661771 -208.006219) (xy 256.680726 -208.089471)
			(xy 256.690273 -208.174317) (xy 256.690876 -208.217008) (xy 256.690331 -208.255832) (xy 256.682447 -208.333078)
			(xy 256.666761 -208.409125) (xy 256.643435 -208.483187) (xy 256.612711 -208.554497) (xy 256.574906 -208.62232)
			(xy 256.53041 -208.685954) (xy 256.479683 -208.744742) (xy 256.423251 -208.798076) (xy 256.361695 -208.845406)
			(xy 256.328926 -208.866232) (xy 256.319604 -208.87266) (xy 256.307347 -208.891668) (xy 256.305304 -208.902808)
			(xy 256.301118 -208.930327) (xy 256.285802 -208.983841) (xy 256.262861 -209.034556) (xy 256.232784 -209.081392)
			(xy 256.21488 -209.102706) (xy 256.214626 -209.10296) (xy 256.209041 -209.110048) (xy 256.202795 -209.126964)
			(xy 256.202434 -209.13598) (xy 256.202434 -209.203036) (xy 256.202766 -209.212056) (xy 256.20903 -209.228973)
			(xy 256.214626 -209.236056) (xy 256.21488 -209.23631) (xy 256.234725 -209.260008) (xy 256.267293 -209.31254)
			(xy 256.290963 -209.369637) (xy 256.305115 -209.429803) (xy 256.307844 -209.460592) (xy 256.30938 -209.472582)
			(xy 256.321836 -209.493258) (xy 256.33172 -209.500216) (xy 256.364239 -209.521145) (xy 256.42536 -209.568528)
			(xy 256.481378 -209.621847) (xy 256.531721 -209.680555) (xy 256.575872 -209.74405) (xy 256.613379 -209.811682)
			(xy 256.643858 -209.88276) (xy 256.666996 -209.956553) (xy 256.682558 -210.032308) (xy 256.690383 -210.109248)
			(xy 256.690876 -210.147916) (xy 256.690276 -210.190606) (xy 256.680712 -210.275449) (xy 256.661749 -210.358697)
			(xy 256.633624 -210.439312) (xy 256.596687 -210.516289) (xy 256.574544 -210.552792) (xy 256.569833 -210.561046)
			(xy 256.566327 -210.579714) (xy 256.569843 -210.598379) (xy 256.574544 -210.60664) (xy 256.596707 -210.643132)
			(xy 256.63365 -210.720108) (xy 256.661773 -210.800726) (xy 256.680727 -210.883978) (xy 256.690274 -210.968825)
			(xy 256.690876 -211.011516) (xy 256.690429 -211.050188) (xy 256.682617 -211.127135) (xy 256.667064 -211.202899)
			(xy 256.643929 -211.276701) (xy 256.613451 -211.347786) (xy 256.575941 -211.415425) (xy 256.531783 -211.478923)
			(xy 256.481431 -211.537632) (xy 256.425401 -211.590948) (xy 256.364267 -211.638325) (xy 256.33172 -211.659216)
			(xy 256.321793 -211.666129) (xy 256.309342 -211.686834) (xy 256.307844 -211.69884) (xy 256.305115 -211.729627)
			(xy 256.290934 -211.789784) (xy 256.267263 -211.846877) (xy 256.234718 -211.89942) (xy 256.21488 -211.923122)
			(xy 256.214626 -211.923376) (xy 256.209035 -211.930459) (xy 256.202793 -211.947379) (xy 256.202434 -211.956396)
			(xy 256.202434 -212.023452) (xy 256.202807 -212.032467) (xy 256.209043 -212.049385) (xy 256.214626 -212.056472)
			(xy 256.21488 -212.056726) (xy 256.232772 -212.078047) (xy 256.262819 -212.124897) (xy 256.285756 -212.175609)
			(xy 256.301097 -212.22911) (xy 256.305304 -212.256624) (xy 256.307423 -212.267732) (xy 256.319667 -212.286709)
			(xy 256.328926 -212.2932) (xy 256.361699 -212.314024) (xy 256.423267 -212.361345) (xy 256.479711 -212.414674)
			(xy 256.530448 -212.473459) (xy 256.574953 -212.537093) (xy 256.612766 -212.604916) (xy 256.643496 -212.67623)
			(xy 256.666826 -212.750295) (xy 256.682513 -212.826346) (xy 256.690396 -212.903598) (xy 256.690876 -212.942424)
			(xy 256.69028 -212.985114) (xy 256.680715 -213.069957) (xy 256.661751 -213.153205) (xy 256.633625 -213.23382)
			(xy 256.596688 -213.310797) (xy 256.574544 -213.3473) (xy 256.569827 -213.355551) (xy 256.566323 -213.374221)
			(xy 256.569842 -213.392887) (xy 256.574544 -213.401148) (xy 256.59671 -213.437638) (xy 256.633653 -213.514615)
			(xy 256.661776 -213.595233) (xy 256.680728 -213.678486) (xy 256.690274 -213.763333) (xy 256.690876 -213.806024)
			(xy 256.690343 -213.844848) (xy 256.682458 -213.922095) (xy 256.66677 -213.998142) (xy 256.643443 -214.072204)
			(xy 256.612718 -214.143515) (xy 256.574911 -214.211338) (xy 256.530414 -214.274972) (xy 256.479686 -214.333759)
			(xy 256.423252 -214.387093) (xy 256.361695 -214.434422) (xy 256.328926 -214.455248) (xy 256.319635 -214.461715)
			(xy 256.307362 -214.480695) (xy 256.305304 -214.491824) (xy 256.30118 -214.518953) (xy 256.286161 -214.57173)
			(xy 256.263737 -214.621812) (xy 256.234371 -214.668166) (xy 256.198668 -214.709835) (xy 256.157365 -214.745962)
			(xy 256.111313 -214.775799) (xy 256.061463 -214.798733) (xy 256.008842 -214.81429) (xy 255.954534 -214.82215)
			(xy 255.899662 -214.82215) (xy 255.845354 -214.81429) (xy 255.792733 -214.798733) (xy 255.742883 -214.775799)
			(xy 255.696831 -214.745962) (xy 255.655528 -214.709835) (xy 255.619825 -214.668166) (xy 255.590459 -214.621812)
			(xy 255.568035 -214.57173) (xy 255.553016 -214.518953) (xy 255.548892 -214.491824) (xy 255.5468 -214.480709)
			(xy 255.534536 -214.461735) (xy 255.52527 -214.455248) (xy 255.492518 -214.434392) (xy 255.43095 -214.387074)
			(xy 255.374505 -214.333749) (xy 255.323768 -214.274968) (xy 255.279261 -214.211338) (xy 255.241446 -214.143518)
			(xy 255.210713 -214.072208) (xy 255.187381 -213.998146) (xy 255.17169 -213.922098) (xy 255.163802 -213.844849)
			(xy 255.16332 -213.806024) (xy 207.391 -213.806024) (xy 207.391 -219.46616) (xy 207.414368 -219.494354)
			(xy 207.432656 -219.497656) (xy 207.459062 -219.503101) (xy 207.510083 -219.520514) (xy 207.558026 -219.54517)
			(xy 207.601868 -219.576543) (xy 207.640676 -219.613964) (xy 207.673623 -219.656637) (xy 207.700006 -219.703651)
			(xy 207.719263 -219.754005) (xy 207.730985 -219.806627) (xy 207.73492 -219.860394) (xy 207.730986 -219.914162)
			(xy 207.719267 -219.966783) (xy 207.700011 -220.017138) (xy 207.673629 -220.064154) (xy 207.640684 -220.106827)
			(xy 207.601877 -220.14425) (xy 207.558036 -220.175624) (xy 207.510094 -220.200281) (xy 207.459073 -220.217696)
			(xy 207.432656 -220.22308) (xy 207.414368 -220.226382) (xy 207.391 -220.254576) (xy 207.391 -228.816154)
			(xy 207.414368 -228.844348) (xy 207.432656 -228.84765) (xy 207.459059 -228.853107) (xy 207.51008 -228.870519)
			(xy 207.558022 -228.895175) (xy 207.601864 -228.926547) (xy 207.640671 -228.963967) (xy 207.673617 -229.006639)
			(xy 207.7 -229.053653) (xy 207.719257 -229.104006) (xy 207.730979 -229.156627) (xy 207.734915 -229.210393)
			(xy 207.730981 -229.26416) (xy 207.719261 -229.316781) (xy 207.700006 -229.367135) (xy 207.673625 -229.414149)
			(xy 207.64068 -229.456822) (xy 207.601874 -229.494244) (xy 207.558034 -229.525618) (xy 207.510093 -229.550275)
			(xy 207.459073 -229.56769) (xy 207.432656 -229.573074) (xy 207.414368 -229.576376) (xy 207.391 -229.60457)
			(xy 207.391 -238.166148) (xy 207.414368 -238.194342) (xy 207.432656 -238.197644) (xy 207.459057 -238.203112)
			(xy 207.510077 -238.220524) (xy 207.558018 -238.245179) (xy 207.601859 -238.276551) (xy 207.640666 -238.31397)
			(xy 207.673612 -238.356641) (xy 207.699994 -238.403654) (xy 207.719251 -238.454007) (xy 207.730973 -238.506626)
			(xy 207.734909 -238.560392) (xy 207.730975 -238.614158) (xy 207.719256 -238.666778) (xy 207.700001 -238.717131)
			(xy 207.673621 -238.764145) (xy 207.640677 -238.806818) (xy 207.601871 -238.844239) (xy 207.558032 -238.875613)
			(xy 207.510091 -238.900269) (xy 207.459072 -238.917684) (xy 207.432656 -238.923068) (xy 207.414368 -238.92637)
			(xy 207.391 -238.954564) (xy 207.391 -275.566124) (xy 207.414368 -275.594318) (xy 207.432656 -275.59762)
			(xy 207.459089 -275.602943) (xy 207.510118 -275.620361) (xy 207.558069 -275.645023) (xy 207.601918 -275.676402)
			(xy 207.640731 -275.713831) (xy 207.673682 -275.756512) (xy 207.700068 -275.803535) (xy 207.719327 -275.853898)
			(xy 207.731049 -275.906529) (xy 207.734983 -275.960306) (xy 207.731047 -276.014082) (xy 207.719324 -276.066713)
			(xy 207.700063 -276.117076) (xy 207.673675 -276.164098) (xy 207.640723 -276.206778) (xy 207.601909 -276.244205)
			(xy 207.558059 -276.275584) (xy 207.510108 -276.300243) (xy 207.459078 -276.31766) (xy 207.432656 -276.323044)
			(xy 207.414368 -276.326346) (xy 207.391 -276.35454) (xy 207.391 -284.916118) (xy 207.414368 -284.944312)
			(xy 207.432656 -284.947614) (xy 207.459086 -284.952949) (xy 207.510115 -284.970366) (xy 207.558065 -284.995027)
			(xy 207.601913 -285.026406) (xy 207.640726 -285.063834) (xy 207.673676 -285.106514) (xy 207.700062 -285.153536)
			(xy 207.719321 -285.203899) (xy 207.731043 -285.256529) (xy 207.734977 -285.310305) (xy 207.731041 -285.36408)
			(xy 207.719318 -285.41671) (xy 207.700058 -285.467072) (xy 207.673671 -285.514094) (xy 207.64072 -285.556773)
			(xy 207.601906 -285.5942) (xy 207.558057 -285.625578) (xy 207.510106 -285.650238) (xy 207.459077 -285.667654)
			(xy 207.432656 -285.673038) (xy 207.414368 -285.67634) (xy 207.391 -285.704534) (xy 207.391 -294.266112)
			(xy 207.414368 -294.294306) (xy 207.432656 -294.297608) (xy 207.459084 -294.302954) (xy 207.510112 -294.320371)
			(xy 207.558061 -294.345031) (xy 207.601908 -294.37641) (xy 207.640721 -294.413837) (xy 207.673671 -294.456516)
			(xy 207.700056 -294.503538) (xy 207.719315 -294.5539) (xy 207.731037 -294.606529) (xy 207.734972 -294.660304)
			(xy 207.731036 -294.714078) (xy 207.719313 -294.766707) (xy 207.700053 -294.817069) (xy 207.673667 -294.86409)
			(xy 207.640716 -294.906768) (xy 207.601903 -294.944195) (xy 207.558054 -294.975572) (xy 207.510105 -295.000232)
			(xy 207.459077 -295.017648) (xy 207.432656 -295.023032) (xy 207.414368 -295.026334) (xy 207.391 -295.054528)
			(xy 207.391 -303.616106) (xy 207.414368 -303.6443) (xy 207.432656 -303.647602) (xy 207.459081 -303.652959)
			(xy 207.510109 -303.670376) (xy 207.558057 -303.695036) (xy 207.601904 -303.726414) (xy 207.640716 -303.76384)
			(xy 207.673665 -303.806519) (xy 207.70005 -303.853539) (xy 207.719309 -303.9039) (xy 207.731031 -303.956529)
			(xy 207.734966 -304.010303) (xy 207.73103 -304.064076) (xy 207.719308 -304.116704) (xy 207.700048 -304.167065)
			(xy 207.673662 -304.214086) (xy 207.640712 -304.256763) (xy 207.6019 -304.29419) (xy 207.558052 -304.325567)
			(xy 207.510104 -304.350226) (xy 207.459076 -304.367642) (xy 207.432656 -304.373026) (xy 207.414368 -304.376328)
			(xy 207.391 -304.404522) (xy 207.391 -312.9661) (xy 207.414368 -312.994294) (xy 207.432656 -312.997596)
			(xy 207.459079 -313.002965) (xy 207.510105 -313.020381) (xy 207.558053 -313.04504) (xy 207.601899 -313.076417)
			(xy 207.64071 -313.113843) (xy 207.67366 -313.156521) (xy 207.700045 -313.203541) (xy 207.719303 -313.253901)
			(xy 207.731025 -313.306528) (xy 207.73496 -313.360301) (xy 207.731024 -313.414075) (xy 207.719302 -313.466702)
			(xy 207.700043 -313.517062) (xy 207.673658 -313.564081) (xy 207.640709 -313.606759) (xy 207.601897 -313.644184)
			(xy 207.55805 -313.675561) (xy 207.510103 -313.70022) (xy 207.459076 -313.717636) (xy 207.432656 -313.72302)
			(xy 207.414368 -313.726322) (xy 207.391 -313.754516) (xy 207.391 -317.924749) (xy 262.863443 -317.924749)
			(xy 262.863443 -317.845855) (xy 262.871587 -317.767383) (xy 262.88779 -317.69017) (xy 262.911877 -317.615043)
			(xy 262.943591 -317.542804) (xy 262.982594 -317.474225) (xy 263.028468 -317.410039) (xy 263.080724 -317.350932)
			(xy 263.138802 -317.297535) (xy 263.202083 -317.25042) (xy 263.269889 -317.210089) (xy 263.341497 -317.176975)
			(xy 263.416141 -317.151429) (xy 263.493023 -317.133726) (xy 263.532112 -317.128398) (xy 263.551416 -317.126112)
			(xy 263.576816 -317.09741) (xy 263.576816 -197.575932) (xy 263.576435 -197.566311) (xy 263.569329 -197.548429)
			(xy 263.556141 -197.534418) (xy 263.547606 -197.529958) (xy 263.512372 -197.512737) (xy 263.445217 -197.472229)
			(xy 263.382574 -197.425043) (xy 263.325103 -197.371677) (xy 263.273413 -197.312696) (xy 263.228047 -197.248722)
			(xy 263.189486 -197.180431) (xy 263.158137 -197.108542) (xy 263.134331 -197.033817) (xy 263.118318 -196.957042)
			(xy 263.110268 -196.87903) (xy 263.110266 -196.800604) (xy 263.118312 -196.722591) (xy 263.134322 -196.645816)
			(xy 263.158125 -196.57109) (xy 263.189471 -196.4992) (xy 263.228029 -196.430906) (xy 263.273392 -196.36693)
			(xy 263.32508 -196.307947) (xy 263.382548 -196.254579) (xy 263.445189 -196.20739) (xy 263.512342 -196.166879)
			(xy 263.547606 -196.149722) (xy 263.556167 -196.14531) (xy 263.569339 -196.131275) (xy 263.576413 -196.113373)
			(xy 263.576816 -196.103748) (xy 263.576816 -195.151248) (xy 263.576308 -195.151502) (xy 263.576308 -183.39562)
			(xy 263.576742 -183.385552) (xy 263.584456 -183.366954) (xy 263.591294 -183.359552) (xy 265.956288 -180.994558)
			(xy 265.963693 -180.987725) (xy 265.982289 -180.980002) (xy 265.992356 -180.979572) (xy 291.681916 -180.979572)
			(xy 291.691987 -180.979162) (xy 291.710585 -180.971431) (xy 291.717984 -180.964586) (xy 296.282618 -176.400206)
			(xy 296.28945 -176.3928) (xy 296.297174 -176.374205) (xy 296.297604 -176.364138) (xy 296.297604 -145.8468)
			(xy 296.298002 -145.836727) (xy 296.305739 -145.818128) (xy 296.31259 -145.810732) (xy 307.645816 -134.477506)
			(xy 307.653217 -134.470667) (xy 307.671816 -134.462947) (xy 307.681884 -134.46252) (xy 329.589892 -134.46252)
			(xy 329.598855 -134.462232) (xy 329.61569 -134.456079) (xy 329.629365 -134.444491) (xy 329.634088 -134.436866)
			(xy 329.647734 -134.413831) (xy 329.680489 -134.371478) (xy 329.718847 -134.334125) (xy 329.762054 -134.302507)
			(xy 329.809261 -134.277246) (xy 329.859538 -134.258838) (xy 329.911895 -134.247647) (xy 329.965304 -134.243892)
			(xy 330.018713 -134.247647) (xy 330.07107 -134.258838) (xy 330.121347 -134.277246) (xy 330.168554 -134.302507)
			(xy 330.211761 -134.334125) (xy 330.250119 -134.371478) (xy 330.282874 -134.413831) (xy 330.29652 -134.436866)
			(xy 330.301276 -134.444457) (xy 330.314957 -134.456003) (xy 330.331766 -134.462163) (xy 330.340716 -134.46252)
			(xy 330.731622 -134.46252) (xy 330.741326 -134.462116) (xy 330.759353 -134.454932) (xy 330.766674 -134.44855)
			(xy 330.786089 -134.430682) (xy 330.828955 -134.399914) (xy 330.875653 -134.375352) (xy 330.925293 -134.357465)
			(xy 330.976926 -134.346593) (xy 331.029564 -134.342947) (xy 331.082202 -134.346593) (xy 331.133835 -134.357465)
			(xy 331.183475 -134.375352) (xy 331.230173 -134.399914) (xy 331.273039 -134.430682) (xy 331.292454 -134.44855)
			(xy 331.299799 -134.454895) (xy 331.31781 -134.462084) (xy 331.327506 -134.46252) (xy 344.945716 -134.46252)
			(xy 344.955787 -134.462932) (xy 344.974385 -134.470662) (xy 344.981784 -134.477506) (xy 361.352846 -150.848568)
			(xy 361.359613 -150.856019) (xy 361.367329 -150.874584) (xy 361.367832 -150.884636) (xy 361.367832 -152.648412)
			(xy 361.367578 -152.648412) (xy 361.367578 -152.776428) (xy 361.367832 -152.776428) (xy 361.367832 -154.367992)
			(xy 361.368253 -154.378062) (xy 361.375976 -154.39666) (xy 361.382818 -154.40406) (xy 365.527844 -158.549086)
			(xy 365.535236 -158.555936) (xy 365.553841 -158.56365) (xy 365.563912 -158.564072) (xy 380.590044 -158.564072)
			(xy 380.600117 -158.563677) (xy 380.618715 -158.555936) (xy 380.626112 -158.549086) (xy 386.452364 -152.722834)
			(xy 388.152386 -151.022558) (xy 388.159792 -151.015726) (xy 388.178387 -151.008003) (xy 388.188454 -151.007572)
			(xy 424.751246 -151.007572) (xy 424.761315 -151.008007) (xy 424.779914 -151.015719) (xy 424.787314 -151.022558)
			(xy 425.835826 -152.071324) (xy 425.870878 -152.075388) (xy 425.886118 -152.065736) (xy 425.909032 -152.051909)
			(xy 425.957886 -152.03006) (xy 426.009314 -152.01525) (xy 426.062305 -152.007769) (xy 426.089064 -152.007316)
			(xy 426.116317 -152.007789) (xy 426.170269 -152.015542) (xy 426.222568 -152.030894) (xy 426.27215 -152.053534)
			(xy 426.318004 -152.083001) (xy 426.359198 -152.118694) (xy 426.394892 -152.159886) (xy 426.42436 -152.20574)
			(xy 426.447002 -152.255321) (xy 426.462356 -152.307619) (xy 426.47011 -152.361571) (xy 426.470572 -152.388824)
			(xy 426.47011 -152.415583) (xy 426.462634 -152.468576) (xy 426.447832 -152.520006) (xy 426.425994 -152.568865)
			(xy 426.412152 -152.59177) (xy 426.4025 -152.60701) (xy 426.406564 -152.642062) (xy 427.538896 -153.774394)
			(xy 436.382169 -153.774394) (xy 436.386165 -153.564508) (xy 436.39815 -153.354926) (xy 436.418104 -153.145952)
			(xy 436.446 -152.93789) (xy 436.481797 -152.73104) (xy 436.525442 -152.525703) (xy 436.576874 -152.322177)
			(xy 436.636016 -152.120756) (xy 436.702784 -151.921733) (xy 436.77708 -151.725396) (xy 436.858798 -151.53203)
			(xy 436.947817 -151.341915) (xy 437.04401 -151.155327) (xy 437.147237 -150.972536) (xy 437.257348 -150.793808)
			(xy 437.374183 -150.619401) (xy 437.497573 -150.449569) (xy 437.62734 -150.284557) (xy 437.763294 -150.124606)
			(xy 437.90524 -149.969946) (xy 438.05297 -149.820802) (xy 438.206272 -149.677391) (xy 438.364922 -149.53992)
			(xy 438.528691 -149.408588) (xy 438.697341 -149.283587) (xy 438.870627 -149.165096) (xy 439.048299 -149.053289)
			(xy 439.230099 -148.948327) (xy 439.415763 -148.850362) (xy 439.605021 -148.759537) (xy 439.797601 -148.675983)
			(xy 439.993222 -148.59982) (xy 440.1916 -148.531161) (xy 440.392449 -148.470104) (xy 440.595476 -148.416737)
			(xy 440.800389 -148.371139) (xy 441.006888 -148.333374) (xy 441.214675 -148.303499) (xy 441.42345 -148.281556)
			(xy 441.632908 -148.267577) (xy 441.842747 -148.261582) (xy 442.052661 -148.263581) (xy 442.262348 -148.273569)
			(xy 442.471502 -148.291534) (xy 442.67982 -148.317448) (xy 442.887001 -148.351273) (xy 443.092745 -148.392962)
			(xy 443.296751 -148.442454) (xy 443.498726 -148.499676) (xy 443.698376 -148.564546) (xy 443.895411 -148.63697)
			(xy 444.089547 -148.716843) (xy 444.2805 -148.804049) (xy 444.467996 -148.898461) (xy 444.651761 -148.999943)
			(xy 444.831529 -149.108347) (xy 445.00704 -149.223517) (xy 445.178039 -149.345285) (xy 445.344279 -149.473474)
			(xy 445.505518 -149.6079) (xy 445.661522 -149.748367) (xy 445.812065 -149.894671) (xy 445.956929 -150.0466)
			(xy 446.095904 -150.203934) (xy 446.228789 -150.366445) (xy 446.35539 -150.533898) (xy 446.475525 -150.706048)
			(xy 446.589019 -150.882648) (xy 446.695707 -151.06344) (xy 446.795434 -151.248163) (xy 446.888057 -151.436549)
			(xy 446.973441 -151.628324) (xy 447.051462 -151.823211) (xy 447.122007 -152.020927) (xy 447.184974 -152.221185)
			(xy 447.240271 -152.423695) (xy 447.287818 -152.628164) (xy 447.327546 -152.834295) (xy 447.359398 -153.041788)
			(xy 447.383328 -153.250344) (xy 447.3993 -153.45966) (xy 447.407292 -153.669432) (xy 447.407792 -153.774394)
			(xy 447.407292 -153.879356) (xy 447.3993 -154.089128) (xy 447.383328 -154.298444) (xy 447.359398 -154.507)
			(xy 447.327546 -154.714493) (xy 447.287818 -154.920624) (xy 447.240271 -155.125093) (xy 447.184974 -155.327603)
			(xy 447.122007 -155.527861) (xy 447.051462 -155.725577) (xy 446.973441 -155.920464) (xy 446.888057 -156.112239)
			(xy 446.795434 -156.300625) (xy 446.695707 -156.485348) (xy 446.589019 -156.66614) (xy 446.475525 -156.84274)
			(xy 446.35539 -157.01489) (xy 446.228789 -157.182343) (xy 446.095904 -157.344854) (xy 445.956929 -157.502188)
			(xy 445.812065 -157.654117) (xy 445.661522 -157.800421) (xy 445.505518 -157.940888) (xy 445.344279 -158.075314)
			(xy 445.178039 -158.203503) (xy 445.00704 -158.325271) (xy 444.831529 -158.440441) (xy 444.651761 -158.548845)
			(xy 444.467996 -158.650327) (xy 444.2805 -158.744739) (xy 444.089547 -158.831945) (xy 443.895411 -158.911818)
			(xy 443.698376 -158.984242) (xy 443.498726 -159.049112) (xy 443.296751 -159.106334) (xy 443.092745 -159.155826)
			(xy 442.887001 -159.197515) (xy 442.67982 -159.23134) (xy 442.471502 -159.257254) (xy 442.262348 -159.275219)
			(xy 442.052661 -159.285207) (xy 441.842747 -159.287206) (xy 441.632908 -159.281211) (xy 441.42345 -159.267232)
			(xy 441.214675 -159.245289) (xy 441.006888 -159.215414) (xy 440.800389 -159.177649) (xy 440.595476 -159.132051)
			(xy 440.392449 -159.078684) (xy 440.1916 -159.017627) (xy 439.993222 -158.948968) (xy 439.797601 -158.872805)
			(xy 439.605021 -158.789251) (xy 439.415763 -158.698426) (xy 439.230099 -158.600461) (xy 439.048299 -158.495499)
			(xy 438.870627 -158.383692) (xy 438.697341 -158.265201) (xy 438.528691 -158.1402) (xy 438.364922 -158.008868)
			(xy 438.206272 -157.871397) (xy 438.05297 -157.727986) (xy 437.90524 -157.578842) (xy 437.763294 -157.424182)
			(xy 437.62734 -157.264231) (xy 437.497573 -157.099219) (xy 437.374183 -156.929387) (xy 437.257348 -156.75498)
			(xy 437.147237 -156.576252) (xy 437.04401 -156.393461) (xy 436.947817 -156.206873) (xy 436.858798 -156.016758)
			(xy 436.77708 -155.823392) (xy 436.702784 -155.627055) (xy 436.636016 -155.428032) (xy 436.576874 -155.226611)
			(xy 436.525442 -155.023085) (xy 436.481797 -154.817748) (xy 436.446 -154.610898) (xy 436.418104 -154.402836)
			(xy 436.39815 -154.193862) (xy 436.386165 -153.98428) (xy 436.382169 -153.774394) (xy 427.538896 -153.774394)
			(xy 439.922666 -166.158164) (xy 439.929444 -166.164386) (xy 439.946205 -166.171949) (xy 439.964553 -166.173152)
			(xy 439.973466 -166.170864) (xy 440.009129 -166.1606) (xy 440.081947 -166.146254) (xy 440.155813 -166.139048)
			(xy 440.192922 -166.138606) (xy 440.232857 -166.139094) (xy 440.312289 -166.147445) (xy 440.390413 -166.164053)
			(xy 440.466373 -166.188736) (xy 440.539336 -166.221224) (xy 440.608504 -166.26116) (xy 440.673119 -166.308108)
			(xy 440.732473 -166.361553) (xy 440.785915 -166.420909) (xy 440.832859 -166.485526) (xy 440.872793 -166.554696)
			(xy 440.905277 -166.627661) (xy 440.929957 -166.703622) (xy 440.946561 -166.781747) (xy 440.954908 -166.861179)
			(xy 440.95543 -166.901114) (xy 440.954978 -166.938222) (xy 440.947774 -167.012088) (xy 440.933426 -167.084904)
			(xy 440.923172 -167.12057) (xy 440.920805 -167.129476) (xy 440.921971 -167.147854) (xy 440.929605 -167.164612)
			(xy 440.935872 -167.17137) (xy 442.869828 -169.105326) (xy 442.90615 -169.108628) (xy 442.92139 -169.098214)
			(xy 442.95319 -169.076981) (xy 443.020249 -169.040232) (xy 443.090649 -169.010379) (xy 443.163683 -168.987722)
			(xy 443.238618 -168.972487) (xy 443.314702 -168.964828) (xy 443.352936 -168.964356) (xy 443.392869 -168.964881)
			(xy 443.472298 -168.973232) (xy 443.550419 -168.98984) (xy 443.626377 -169.014522) (xy 443.699338 -169.047009)
			(xy 443.768504 -169.086943) (xy 443.833117 -169.133889) (xy 443.89247 -169.18733) (xy 443.945911 -169.246683)
			(xy 443.992857 -169.311296) (xy 444.032791 -169.380462) (xy 444.065278 -169.453423) (xy 444.08996 -169.529381)
			(xy 444.106568 -169.607502) (xy 444.114919 -169.686931) (xy 444.115444 -169.726864) (xy 444.114956 -169.765078)
			(xy 444.107306 -169.841123) (xy 444.092078 -169.91602) (xy 444.069427 -169.989014) (xy 444.039579 -170.059374)
			(xy 444.002835 -170.12639) (xy 443.981586 -170.158156) (xy 443.975399 -170.168268) (xy 443.972136 -170.191719)
			(xy 443.979712 -170.214151) (xy 443.987682 -170.222926) (xy 456.158854 -182.394352) (xy 456.165659 -182.40178)
			(xy 456.173401 -182.420358) (xy 456.17384 -182.43042) (xy 456.17384 -195.108068) (xy 456.173496 -195.118116)
			(xy 456.165891 -195.136713) (xy 456.159108 -195.144136) (xy 456.036172 -195.266818) (xy 456.029227 -195.274497)
			(xy 456.021562 -195.293705) (xy 456.022115 -195.314378) (xy 456.026012 -195.323968) (xy 456.042163 -195.360657)
			(xy 456.067438 -195.436736) (xy 456.084461 -195.515074) (xy 456.093039 -195.594781) (xy 456.093576 -195.634864)
			(xy 456.093576 -195.635118) (xy 456.093129 -195.674389) (xy 456.084917 -195.752501) (xy 456.068585 -195.829327)
			(xy 456.044312 -195.904024) (xy 456.012364 -195.975775) (xy 455.973091 -196.043794) (xy 455.926923 -196.107334)
			(xy 455.874366 -196.165701) (xy 455.815995 -196.218254) (xy 455.752452 -196.264418) (xy 455.684431 -196.303687)
			(xy 455.612677 -196.33563) (xy 455.537978 -196.359898) (xy 455.461152 -196.376225) (xy 455.383039 -196.384431)
			(xy 455.343768 -196.384926) (xy 455.304393 -196.384472) (xy 455.226077 -196.376212) (xy 455.149059 -196.359787)
			(xy 455.074187 -196.335379) (xy 455.002287 -196.303255) (xy 454.934151 -196.26377) (xy 454.87053 -196.217359)
			(xy 454.812125 -196.164534) (xy 454.75958 -196.105877) (xy 454.713475 -196.042034) (xy 454.674317 -195.97371)
			(xy 454.657968 -195.937886) (xy 454.653624 -195.929078) (xy 454.6395 -195.915449) (xy 454.6213 -195.908103)
			(xy 454.611486 -195.90766) (xy 448.53225 -195.90766) (xy 448.522437 -195.90808) (xy 448.504242 -195.915437)
			(xy 448.490146 -195.929092) (xy 448.485768 -195.937886) (xy 448.469409 -195.973698) (xy 448.430235 -196.041999)
			(xy 448.384117 -196.105817) (xy 448.331565 -196.16445) (xy 448.273157 -196.217252) (xy 448.209536 -196.263641)
			(xy 448.141404 -196.303107) (xy 448.06951 -196.335214) (xy 447.994648 -196.359609) (xy 447.91764 -196.376024)
			(xy 447.839337 -196.384276) (xy 447.760599 -196.384276) (xy 447.682296 -196.376024) (xy 447.605288 -196.359609)
			(xy 447.530426 -196.335214) (xy 447.458532 -196.303107) (xy 447.3904 -196.263641) (xy 447.326779 -196.217252)
			(xy 447.268371 -196.16445) (xy 447.215819 -196.105817) (xy 447.169701 -196.041999) (xy 447.130527 -195.973698)
			(xy 447.114168 -195.937886) (xy 447.109824 -195.929078) (xy 447.0957 -195.915449) (xy 447.0775 -195.908103)
			(xy 447.067686 -195.90766) (xy 446.276222 -195.90766) (xy 446.24752 -195.93306) (xy 446.245234 -195.952364)
			(xy 446.239987 -195.991517) (xy 446.222428 -196.068542) (xy 446.196998 -196.143337) (xy 446.16397 -196.215103)
			(xy 446.123698 -196.283068) (xy 446.076615 -196.346505) (xy 446.023224 -196.404733) (xy 445.964099 -196.457128)
			(xy 445.899873 -196.503129) (xy 445.831234 -196.542241) (xy 445.758919 -196.574047) (xy 445.683702 -196.598204)
			(xy 445.606391 -196.614455) (xy 445.527814 -196.622624) (xy 445.448814 -196.622624) (xy 445.370237 -196.614455)
			(xy 445.292926 -196.598204) (xy 445.217709 -196.574047) (xy 445.145394 -196.542241) (xy 445.076755 -196.503129)
			(xy 445.012529 -196.457128) (xy 444.953404 -196.404733) (xy 444.900013 -196.346505) (xy 444.85293 -196.283068)
			(xy 444.812658 -196.215103) (xy 444.77963 -196.143337) (xy 444.7542 -196.068542) (xy 444.736641 -195.991517)
			(xy 444.731394 -195.952364) (xy 444.729108 -195.93306) (xy 444.700406 -195.90766) (xy 440.988196 -195.90766)
			(xy 440.978386 -195.908113) (xy 440.960193 -195.915454) (xy 440.946094 -195.929097) (xy 440.941714 -195.937886)
			(xy 440.925355 -195.973698) (xy 440.886181 -196.041999) (xy 440.840063 -196.105817) (xy 440.787511 -196.16445)
			(xy 440.729103 -196.217252) (xy 440.665482 -196.263641) (xy 440.59735 -196.303107) (xy 440.525456 -196.335214)
			(xy 440.450594 -196.359609) (xy 440.373586 -196.376024) (xy 440.295283 -196.384276) (xy 440.216545 -196.384276)
			(xy 440.138242 -196.376024) (xy 440.061234 -196.359609) (xy 439.986372 -196.335214) (xy 439.914478 -196.303107)
			(xy 439.846346 -196.263641) (xy 439.782725 -196.217252) (xy 439.724317 -196.16445) (xy 439.671765 -196.105817)
			(xy 439.625647 -196.041999) (xy 439.586473 -195.973698) (xy 439.570114 -195.937886) (xy 439.565737 -195.929097)
			(xy 439.551627 -195.915467) (xy 439.533441 -195.908111) (xy 439.523632 -195.90766) (xy 438.751726 -195.90766)
			(xy 438.742506 -195.908053) (xy 438.72525 -195.914556) (xy 438.711401 -195.926733) (xy 438.702745 -195.943015)
			(xy 438.70118 -195.95211) (xy 438.70118 -195.952364) (xy 438.695876 -195.991458) (xy 438.678218 -196.068355)
			(xy 438.652712 -196.143017) (xy 438.619632 -196.214645) (xy 438.579331 -196.282473) (xy 438.532239 -196.345777)
			(xy 438.478862 -196.403878) (xy 438.419768 -196.456155) (xy 438.355592 -196.502049) (xy 438.287019 -196.54107)
			(xy 438.214782 -196.572799) (xy 438.139654 -196.596898) (xy 438.062439 -196.613109) (xy 437.983963 -196.621258)
			(xy 437.905065 -196.621258) (xy 437.826589 -196.613109) (xy 437.749374 -196.596898) (xy 437.674246 -196.572799)
			(xy 437.602009 -196.54107) (xy 437.533436 -196.502049) (xy 437.46926 -196.456155) (xy 437.410166 -196.403878)
			(xy 437.356789 -196.345777) (xy 437.309697 -196.282473) (xy 437.269396 -196.214645) (xy 437.236316 -196.143017)
			(xy 437.21081 -196.068355) (xy 437.193152 -195.991458) (xy 437.187848 -195.952364) (xy 437.187848 -195.95211)
			(xy 437.186262 -195.943007) (xy 437.177664 -195.926678) (xy 437.163816 -195.914479) (xy 437.146532 -195.90801)
			(xy 437.137302 -195.90766) (xy 433.444142 -195.90766) (xy 433.434328 -195.908073) (xy 433.416133 -195.915434)
			(xy 433.402037 -195.929091) (xy 433.39766 -195.937886) (xy 433.381301 -195.973698) (xy 433.342127 -196.041999)
			(xy 433.296009 -196.105817) (xy 433.243457 -196.16445) (xy 433.185049 -196.217252) (xy 433.121428 -196.263641)
			(xy 433.053296 -196.303107) (xy 432.981402 -196.335214) (xy 432.90654 -196.359609) (xy 432.829532 -196.376024)
			(xy 432.751229 -196.384276) (xy 432.672491 -196.384276) (xy 432.594188 -196.376024) (xy 432.51718 -196.359609)
			(xy 432.442318 -196.335214) (xy 432.370424 -196.303107) (xy 432.302292 -196.263641) (xy 432.238671 -196.217252)
			(xy 432.180263 -196.16445) (xy 432.127711 -196.105817) (xy 432.081593 -196.041999) (xy 432.042419 -195.973698)
			(xy 432.02606 -195.937886) (xy 432.021651 -195.929116) (xy 432.007555 -195.915485) (xy 431.989382 -195.908119)
			(xy 431.979578 -195.90766) (xy 431.206402 -195.90766) (xy 431.197264 -195.908038) (xy 431.180158 -195.914479)
			(xy 431.166397 -195.926508) (xy 431.157726 -195.942599) (xy 431.15611 -195.951602) (xy 431.15611 -195.951856)
			(xy 431.150411 -195.990592) (xy 431.132104 -196.066722) (xy 431.106089 -196.140574) (xy 431.072643 -196.211371)
			(xy 431.032115 -196.278366) (xy 430.984935 -196.340856) (xy 430.931598 -196.39818) (xy 430.872667 -196.449735)
			(xy 430.808761 -196.494979) (xy 430.740555 -196.533434) (xy 430.668767 -196.564696) (xy 430.594152 -196.588435)
			(xy 430.517498 -196.604401) (xy 430.43961 -196.612427) (xy 430.36131 -196.612427) (xy 430.283422 -196.604401)
			(xy 430.206768 -196.588435) (xy 430.132153 -196.564696) (xy 430.060365 -196.533434) (xy 429.992159 -196.494979)
			(xy 429.928253 -196.449735) (xy 429.869322 -196.39818) (xy 429.815985 -196.340856) (xy 429.768805 -196.278366)
			(xy 429.728277 -196.211371) (xy 429.694831 -196.140574) (xy 429.668816 -196.066722) (xy 429.650509 -195.990592)
			(xy 429.64481 -195.951856) (xy 429.64481 -195.951602) (xy 429.643272 -195.942578) (xy 429.634596 -195.926467)
			(xy 429.620807 -195.914439) (xy 429.603668 -195.90803) (xy 429.594518 -195.90766) (xy 426.304456 -195.90766)
			(xy 426.294382 -195.908047) (xy 426.275784 -195.915793) (xy 426.268388 -195.922646) (xy 426.107352 -196.083936)
			(xy 426.103288 -196.094858) (xy 426.096282 -196.113701) (xy 426.077132 -196.149046) (xy 426.065188 -196.165216)
			(xy 426.060361 -196.172047) (xy 426.054909 -196.187849) (xy 426.05452 -196.196204) (xy 426.05452 -266.3825)
			(xy 426.054774 -266.388342) (xy 426.065188 -266.47775) (xy 426.065712 -266.482996) (xy 426.064818 -266.493498)
			(xy 426.06341 -266.498578) (xy 426.051472 -266.537186) (xy 426.051472 -266.544044) (xy 426.866304 -266.544044)
			(xy 426.876934 -266.543615) (xy 426.896397 -266.535078) (xy 426.903896 -266.527534) (xy 426.930499 -266.499313)
			(xy 426.988606 -266.447938) (xy 427.051706 -266.402838) (xy 427.119126 -266.364493) (xy 427.190144 -266.333315)
			(xy 427.264002 -266.309636) (xy 427.339911 -266.293709) (xy 427.417057 -266.285705) (xy 427.455838 -266.285218)
			(xy 427.456346 -266.285218) (xy 427.495126 -266.285715) (xy 427.57227 -266.293725) (xy 427.648176 -266.309656)
			(xy 427.722032 -266.333336) (xy 427.793049 -266.364514) (xy 427.860468 -266.402855) (xy 427.92357 -266.44795)
			(xy 427.98168 -266.499319) (xy 428.008288 -266.527534) (xy 428.015874 -266.534959) (xy 428.035281 -266.543496)
			(xy 428.04588 -266.544044) (xy 434.410358 -266.544044) (xy 434.420991 -266.543645) (xy 434.440454 -266.535087)
			(xy 434.44795 -266.527534) (xy 434.474576 -266.499335) (xy 434.532679 -266.447959) (xy 434.595776 -266.402857)
			(xy 434.663192 -266.36451) (xy 434.734207 -266.333329) (xy 434.808062 -266.309646) (xy 434.883968 -266.293715)
			(xy 434.961112 -266.285707) (xy 434.999892 -266.285218) (xy 435.0004 -266.285218) (xy 435.039181 -266.285678)
			(xy 435.116326 -266.293694) (xy 435.192233 -266.30963) (xy 435.266089 -266.333315) (xy 435.337106 -266.364498)
			(xy 435.404525 -266.402844) (xy 435.467626 -266.447944) (xy 435.525735 -266.499317) (xy 435.552342 -266.527534)
			(xy 435.559908 -266.534983) (xy 435.57933 -266.543506) (xy 435.589934 -266.544044) (xy 439.43397 -266.544044)
			(xy 439.444039 -266.544474) (xy 439.462638 -266.55219) (xy 439.470038 -266.55903) (xy 441.075826 -268.165072)
			(xy 441.08265 -268.172484) (xy 441.090378 -268.191074) (xy 441.090812 -268.20114) (xy 441.090812 -340.463632)
			(xy 441.090558 -340.46414) (xy 441.090558 -346.093542) (xy 441.094368 -346.10294) (xy 441.105069 -346.13061)
			(xy 441.118789 -346.188325) (xy 441.123402 -346.247468) (xy 441.118798 -346.306613) (xy 441.105088 -346.36433)
			(xy 441.094368 -346.391992) (xy 441.090558 -346.40139) (xy 441.090558 -346.728542) (xy 441.094368 -346.73794)
			(xy 441.105069 -346.76561) (xy 441.118789 -346.823325) (xy 441.123402 -346.882468) (xy 441.118798 -346.941613)
			(xy 441.105088 -346.99933) (xy 441.094368 -347.026992) (xy 441.090558 -347.03639) (xy 441.090558 -347.388942)
			(xy 441.094368 -347.39834) (xy 441.105069 -347.42601) (xy 441.118789 -347.483725) (xy 441.123402 -347.542868)
			(xy 441.118798 -347.602013) (xy 441.105088 -347.65973) (xy 441.094368 -347.687392) (xy 441.090558 -347.69679)
			(xy 441.090558 -355.03739) (xy 441.090008 -355.062352) (xy 441.080273 -355.111316) (xy 441.061157 -355.157434)
			(xy 441.033397 -355.198927) (xy 441.016136 -355.216968) (xy 439.853578 -356.379526) (xy 439.835543 -356.39679)
			(xy 439.794039 -356.424529) (xy 439.747921 -356.443636) (xy 439.69896 -356.453377) (xy 439.674 -356.453948)
			(xy 432.09464 -356.453948) (xy 432.085866 -356.454263) (xy 432.069327 -356.460115) (xy 432.055761 -356.47124)
			(xy 432.050952 -356.478586) (xy 432.036064 -356.502377) (xy 432.000406 -356.545715) (xy 431.958782 -356.58336)
			(xy 431.912092 -356.6145) (xy 431.861343 -356.638463) (xy 431.807631 -356.654731) (xy 431.752115 -356.662954)
			(xy 431.695993 -356.662954) (xy 431.640477 -356.654731) (xy 431.586765 -356.638463) (xy 431.536016 -356.6145)
			(xy 431.489326 -356.58336) (xy 431.447702 -356.545715) (xy 431.412044 -356.502377) (xy 431.397156 -356.478586)
			(xy 431.392272 -356.471308) (xy 431.378708 -356.460234) (xy 431.362222 -356.454329) (xy 431.353468 -356.453948)
			(xy 428.489364 -356.453948) (xy 428.481409 -356.454273) (xy 428.466277 -356.459193) (xy 428.459646 -356.4636)
			(xy 428.43777 -356.479008) (xy 428.390568 -356.504207) (xy 428.340309 -356.522568) (xy 428.287978 -356.53373)
			(xy 428.234602 -356.537476) (xy 428.181226 -356.53373) (xy 428.128895 -356.522568) (xy 428.078636 -356.504207)
			(xy 428.031434 -356.479008) (xy 428.009558 -356.4636) (xy 428.002952 -356.459143) (xy 427.987804 -356.45422)
			(xy 427.97984 -356.453948) (xy 423.751248 -356.453948) (xy 423.738987 -356.454639) (xy 423.717216 -356.465912)
			(xy 423.709592 -356.475538) (xy 423.693026 -356.498304) (xy 423.654289 -356.539163) (xy 423.609963 -356.573878)
			(xy 423.561012 -356.601695) (xy 423.508502 -356.622008) (xy 423.453575 -356.634375) (xy 423.397426 -356.638528)
			(xy 423.341277 -356.634375) (xy 423.28635 -356.622008) (xy 423.23384 -356.601695) (xy 423.184889 -356.573878)
			(xy 423.140563 -356.539163) (xy 423.101826 -356.498304) (xy 423.08526 -356.475538) (xy 423.077601 -356.465952)
			(xy 423.055852 -356.454673) (xy 423.043604 -356.453948) (xy 420.672514 -356.453948) (xy 420.659908 -356.454587)
			(xy 420.63766 -356.466448) (xy 420.630096 -356.476554) (xy 420.614873 -356.49863) (xy 420.579222 -356.538685)
			(xy 420.538309 -356.573349) (xy 420.492944 -356.601939) (xy 420.444019 -356.62389) (xy 420.392502 -356.63877)
			(xy 420.339408 -356.646283) (xy 420.285784 -356.646283) (xy 420.23269 -356.63877) (xy 420.181173 -356.62389)
			(xy 420.132248 -356.601939) (xy 420.086883 -356.573349) (xy 420.04597 -356.538685) (xy 420.010319 -356.49863)
			(xy 419.995096 -356.476554) (xy 419.987551 -356.466422) (xy 419.965295 -356.454551) (xy 419.952678 -356.453948)
			(xy 315.03112 -356.453948) (xy 315.023622 -356.454201) (xy 315.009286 -356.458602) (xy 315.002926 -356.462584)
			(xy 314.97153 -356.483033) (xy 314.905452 -356.518364) (xy 314.836228 -356.547045) (xy 314.764525 -356.568802)
			(xy 314.691035 -356.583424) (xy 314.616465 -356.590771) (xy 314.541535 -356.590771) (xy 314.466965 -356.583424)
			(xy 314.393475 -356.568802) (xy 314.321772 -356.547045) (xy 314.252548 -356.518364) (xy 314.18647 -356.483033)
			(xy 314.155074 -356.462584) (xy 314.148695 -356.458647) (xy 314.13437 -356.454256) (xy 314.12688 -356.453948)
			(xy 305.761898 -356.453948) (xy 305.750784 -356.454484) (xy 305.730624 -356.463843) (xy 305.723036 -356.471982)
			(xy 305.704814 -356.4929) (xy 305.663356 -356.529762) (xy 305.616996 -356.56023) (xy 305.566712 -356.583662)
			(xy 305.513564 -356.599563) (xy 305.458674 -356.607599) (xy 305.403198 -356.607599) (xy 305.348308 -356.599563)
			(xy 305.29516 -356.583662) (xy 305.244876 -356.56023) (xy 305.198516 -356.529762) (xy 305.157058 -356.4929)
			(xy 305.138836 -356.471982) (xy 305.131217 -356.463882) (xy 305.111078 -356.454518) (xy 305.099974 -356.453948)
			(xy 303.763934 -356.453948) (xy 303.755743 -356.454282) (xy 303.740197 -356.459448) (xy 303.733454 -356.464108)
			(xy 303.702975 -356.486378) (xy 303.63839 -356.525463) (xy 303.57026 -356.557977) (xy 303.499252 -356.583601)
			(xy 303.426059 -356.602086) (xy 303.351398 -356.613249) (xy 303.276 -356.616983) (xy 303.200602 -356.613249)
			(xy 303.125941 -356.602086) (xy 303.052748 -356.583601) (xy 302.98174 -356.557977) (xy 302.91361 -356.525463)
			(xy 302.849025 -356.486378) (xy 302.818546 -356.464108) (xy 302.811817 -356.459421) (xy 302.796262 -356.454251)
			(xy 302.788066 -356.453948) (xy 289.90671 -356.453948) (xy 289.896529 -356.45446) (xy 289.87779 -356.462435)
			(xy 289.870388 -356.469442) (xy 289.812476 -356.528878) (xy 289.80511 -356.548182) (xy 289.805364 -356.558596)
			(xy 289.805872 -356.584758) (xy 289.805362 -356.625872) (xy 289.797778 -356.707749) (xy 289.782672 -356.788578)
			(xy 289.760173 -356.867667) (xy 289.730472 -356.944344) (xy 289.693822 -357.017952) (xy 289.650537 -357.087865)
			(xy 289.600986 -357.153486) (xy 289.545592 -357.214255) (xy 289.484826 -357.269653) (xy 289.419208 -357.319208)
			(xy 289.349298 -357.362497) (xy 289.275691 -357.399151) (xy 289.199017 -357.428856) (xy 289.119928 -357.45136)
			(xy 289.039101 -357.466471) (xy 288.957224 -357.474059) (xy 288.91611 -357.47452) (xy 288.87782 -357.474114)
			(xy 288.801526 -357.467506) (xy 288.726084 -357.454357) (xy 288.652053 -357.434764) (xy 288.615882 -357.422196)
			(xy 288.607445 -357.419545) (xy 288.589775 -357.419545) (xy 288.581338 -357.422196) (xy 288.54516 -357.434739)
			(xy 288.471127 -357.454312) (xy 288.395688 -357.46746) (xy 288.319398 -357.474084) (xy 288.28111 -357.47452)
			(xy 288.24282 -357.474114) (xy 288.166526 -357.467506) (xy 288.091084 -357.454357) (xy 288.017053 -357.434764)
			(xy 287.980882 -357.422196) (xy 287.972445 -357.419545) (xy 287.954775 -357.419545) (xy 287.946338 -357.422196)
			(xy 287.91016 -357.434739) (xy 287.836127 -357.454312) (xy 287.760688 -357.46746) (xy 287.684398 -357.474084)
			(xy 287.64611 -357.47452) (xy 287.60782 -357.474114) (xy 287.531526 -357.467506) (xy 287.456084 -357.454357)
			(xy 287.382053 -357.434764) (xy 287.345882 -357.422196) (xy 287.337445 -357.419545) (xy 287.319775 -357.419545)
			(xy 287.311338 -357.422196) (xy 287.27516 -357.434739) (xy 287.201127 -357.454312) (xy 287.125688 -357.46746)
			(xy 287.049398 -357.474084) (xy 287.01111 -357.47452) (xy 286.97282 -357.474114) (xy 286.896526 -357.467506)
			(xy 286.821084 -357.454357) (xy 286.747053 -357.434764) (xy 286.710882 -357.422196) (xy 286.702445 -357.419545)
			(xy 286.684775 -357.419545) (xy 286.676338 -357.422196) (xy 286.64016 -357.434739) (xy 286.566127 -357.454312)
			(xy 286.490688 -357.46746) (xy 286.414398 -357.474084) (xy 286.37611 -357.47452) (xy 286.334994 -357.474092)
			(xy 286.253113 -357.466505) (xy 286.172281 -357.451395) (xy 286.093188 -357.428892) (xy 286.016509 -357.399186)
			(xy 285.942899 -357.362532) (xy 285.872984 -357.319241) (xy 285.807362 -357.269685) (xy 285.746593 -357.214284)
			(xy 285.691195 -357.153513) (xy 285.641641 -357.08789) (xy 285.598353 -357.017973) (xy 285.561701 -356.944361)
			(xy 285.531998 -356.867681) (xy 285.509497 -356.788588) (xy 285.49439 -356.707755) (xy 285.486807 -356.625874)
			(xy 285.486348 -356.584758) (xy 285.486856 -356.558596) (xy 285.48711 -356.548182) (xy 285.479744 -356.528878)
			(xy 285.421832 -356.469442) (xy 285.414422 -356.462444) (xy 285.39569 -356.454454) (xy 285.38551 -356.453948)
			(xy 273.05 -356.453948) (xy 273.025038 -356.453407) (xy 272.976073 -356.44367) (xy 272.929955 -356.424551)
			(xy 272.888462 -356.396788) (xy 272.870422 -356.379526) (xy 270.915384 -354.424488) (xy 270.898141 -354.406437)
			(xy 270.870412 -354.364935) (xy 270.851312 -354.318821) (xy 270.841574 -354.269867) (xy 270.840962 -354.24491)
			(xy 270.840962 -335.792318) (xy 270.840565 -335.782293) (xy 270.832894 -335.763769) (xy 270.818714 -335.749595)
			(xy 270.800187 -335.741931) (xy 270.790162 -335.741518) (xy 264.10031 -335.741518) (xy 264.075348 -335.740979)
			(xy 264.026382 -335.731243) (xy 263.980263 -335.712124) (xy 263.938771 -335.684359) (xy 263.920732 -335.667096)
			(xy 263.651238 -335.397602) (xy 263.633979 -335.379563) (xy 263.606241 -335.33806) (xy 263.587133 -335.291942)
			(xy 263.57739 -335.242983) (xy 263.576816 -335.218024) (xy 263.576816 -325.421498) (xy 263.576291 -325.410572)
			(xy 263.567203 -325.390697) (xy 263.55929 -325.383144) (xy 263.528689 -325.356003) (xy 263.47288 -325.296199)
			(xy 263.423794 -325.230763) (xy 263.381996 -325.160449) (xy 263.347966 -325.086064) (xy 263.322095 -325.008464)
			(xy 263.30468 -324.928539) (xy 263.295922 -324.84721) (xy 263.295384 -324.80631) (xy 263.295923 -324.766346)
			(xy 263.304306 -324.686859) (xy 263.320951 -324.608683) (xy 263.345675 -324.532675) (xy 263.378207 -324.459668)
			(xy 263.397746 -324.424802) (xy 263.402005 -324.416656) (xy 263.404999 -324.398531) (xy 263.401468 -324.380504)
			(xy 263.396984 -324.372478) (xy 263.375107 -324.336189) (xy 263.338643 -324.259696) (xy 263.310888 -324.17963)
			(xy 263.292185 -324.09698) (xy 263.282764 -324.012766) (xy 263.282176 -323.970396) (xy 263.282659 -323.933144)
			(xy 263.289937 -323.858996) (xy 263.304413 -323.785911) (xy 263.32595 -323.714587) (xy 263.354341 -323.645705)
			(xy 263.389317 -323.57992) (xy 263.430542 -323.517861) (xy 263.477625 -323.460119) (xy 263.530116 -323.407246)
			(xy 263.558528 -323.383148) (xy 263.566762 -323.375534) (xy 263.57624 -323.355234) (xy 263.576816 -323.344032)
			(xy 263.576816 -318.673226) (xy 263.551416 -318.644524) (xy 263.532112 -318.642238) (xy 263.493028 -318.636874)
			(xy 263.416145 -318.619172) (xy 263.341501 -318.593627) (xy 263.269893 -318.560513) (xy 263.202086 -318.520182)
			(xy 263.138806 -318.473067) (xy 263.080727 -318.419671) (xy 263.028471 -318.360565) (xy 262.982596 -318.296379)
			(xy 262.943593 -318.2278) (xy 262.911879 -318.155561) (xy 262.887791 -318.080434) (xy 262.871588 -318.003222)
			(xy 262.863443 -317.924749) (xy 207.391 -317.924749) (xy 207.391 -326.23252) (xy 207.390423 -326.257481)
			(xy 207.3807 -326.306445) (xy 207.361592 -326.352563) (xy 207.333837 -326.394057) (xy 207.316578 -326.412098)
			(xy 206.704438 -327.024238) (xy 206.68638 -327.041476) (xy 206.644884 -327.069219) (xy 206.598772 -327.088333)
			(xy 206.549818 -327.098083) (xy 206.52486 -327.09866) (xy 196.599048 -327.09866) (xy 196.589035 -327.099158)
			(xy 196.570526 -327.106805) (xy 196.556354 -327.120953) (xy 196.548675 -327.139448) (xy 196.548248 -327.14946)
			(xy 196.548248 -339.82406) (xy 196.547815 -339.834129) (xy 196.540101 -339.852727) (xy 196.533262 -339.860128)
			(xy 194.367404 -342.02624) (xy 194.362679 -342.031188) (xy 194.355857 -342.04304) (xy 194.353942 -342.049608)
			(xy 194.353942 -342.050116) (xy 194.344064 -342.087717) (xy 194.317574 -342.160813) (xy 194.283784 -342.230834)
			(xy 194.243045 -342.297054) (xy 194.195779 -342.358785) (xy 194.142477 -342.415386) (xy 194.083693 -342.46627)
			(xy 194.020036 -342.510909) (xy 193.952168 -342.548838) (xy 193.880793 -342.579665) (xy 193.806651 -342.60307)
			(xy 193.730513 -342.618809) (xy 193.653168 -342.62672) (xy 193.614294 -342.627204) (xy 193.613786 -342.627204)
			(xy 193.576493 -342.626694) (xy 193.502267 -342.619368) (xy 193.42911 -342.604835) (xy 193.357719 -342.583235)
			(xy 193.288777 -342.554772) (xy 193.22294 -342.51972) (xy 193.191638 -342.499442) (xy 193.185252 -342.495547)
			(xy 193.170921 -342.491286) (xy 193.163444 -342.49106) (xy 132.131054 -342.49106) (xy 132.130546 -342.490552)
			(xy 116.090446 -342.490552) (xy 116.080378 -342.490988) (xy 116.061779 -342.4987) (xy 116.054378 -342.505538)
			(xy 111.976916 -346.583) (xy 200.85558 -346.583) (xy 200.856207 -346.536598) (xy 200.865897 -346.444301)
			(xy 200.88515 -346.353515) (xy 200.913758 -346.26523) (xy 200.932034 -346.222574) (xy 200.935843 -346.212632)
			(xy 200.935843 -346.191368) (xy 200.932034 -346.181426) (xy 200.913772 -346.138765) (xy 200.885179 -346.050477)
			(xy 200.865922 -345.959694) (xy 200.856209 -345.867401) (xy 200.85558 -345.821) (xy 200.856064 -345.779859)
			(xy 200.863695 -345.69793) (xy 200.878855 -345.617056) (xy 200.901414 -345.537926) (xy 200.931179 -345.461215)
			(xy 200.967897 -345.38758) (xy 200.989184 -345.35237) (xy 200.993752 -345.344157) (xy 200.997195 -345.3257)
			(xy 200.993752 -345.307243) (xy 200.989184 -345.29903) (xy 200.967885 -345.263826) (xy 200.931155 -345.190194)
			(xy 200.901383 -345.113484) (xy 200.878824 -345.034352) (xy 200.86367 -344.953474) (xy 200.856051 -344.871542)
			(xy 200.85558 -344.8304) (xy 200.856207 -344.783998) (xy 200.865897 -344.691701) (xy 200.88515 -344.600915)
			(xy 200.913758 -344.51263) (xy 200.932034 -344.469974) (xy 200.935843 -344.460032) (xy 200.935843 -344.438768)
			(xy 200.932034 -344.428826) (xy 200.913772 -344.386165) (xy 200.885179 -344.297877) (xy 200.865922 -344.207094)
			(xy 200.856209 -344.114801) (xy 200.85558 -344.0684) (xy 200.856084 -344.026039) (xy 200.864137 -343.941702)
			(xy 200.880171 -343.858512) (xy 200.904039 -343.777222) (xy 200.935527 -343.69857) (xy 200.974349 -343.623267)
			(xy 201.020152 -343.551995) (xy 201.072523 -343.485399) (xy 201.130988 -343.424084) (xy 201.195016 -343.368603)
			(xy 201.264028 -343.31946) (xy 201.337398 -343.2771) (xy 201.414463 -343.241905) (xy 201.494525 -343.214196)
			(xy 201.576858 -343.194222) (xy 201.660717 -343.182165) (xy 201.745342 -343.178134) (xy 201.829967 -343.182165)
			(xy 201.913826 -343.194222) (xy 201.996159 -343.214196) (xy 202.076221 -343.241905) (xy 202.153286 -343.2771)
			(xy 202.226656 -343.31946) (xy 202.295668 -343.368603) (xy 202.359696 -343.424084) (xy 202.418161 -343.485399)
			(xy 202.470532 -343.551995) (xy 202.516335 -343.623267) (xy 202.555157 -343.69857) (xy 202.586645 -343.777222)
			(xy 202.610513 -343.858512) (xy 202.626547 -343.941702) (xy 202.6346 -344.026039) (xy 202.635104 -344.0684)
			(xy 202.634479 -344.114802) (xy 202.624789 -344.2071) (xy 202.605534 -344.297885) (xy 202.576926 -344.38617)
			(xy 202.55865 -344.428826) (xy 202.554842 -344.438768) (xy 202.554842 -344.460032) (xy 202.55865 -344.469974)
			(xy 202.576911 -344.512635) (xy 202.605505 -344.600923) (xy 202.624762 -344.691706) (xy 202.634475 -344.783999)
			(xy 202.635104 -344.8304) (xy 202.634622 -344.871541) (xy 202.626991 -344.95347) (xy 202.611831 -345.034344)
			(xy 202.589272 -345.113474) (xy 202.559506 -345.190185) (xy 202.522787 -345.263821) (xy 202.5015 -345.29903)
			(xy 202.496933 -345.307243) (xy 202.493491 -345.3257) (xy 202.496933 -345.344157) (xy 202.5015 -345.35237)
			(xy 202.522797 -345.387575) (xy 202.559528 -345.461207) (xy 202.5893 -345.537917) (xy 202.61186 -345.617049)
			(xy 202.627014 -345.697926) (xy 202.634633 -345.779858) (xy 202.635104 -345.821) (xy 202.634479 -345.867402)
			(xy 202.624789 -345.9597) (xy 202.605534 -346.050485) (xy 202.576926 -346.13877) (xy 202.55865 -346.181426)
			(xy 202.554842 -346.191368) (xy 202.554842 -346.212632) (xy 202.55865 -346.222574) (xy 202.576911 -346.265235)
			(xy 202.605505 -346.353523) (xy 202.624762 -346.444306) (xy 202.634475 -346.536599) (xy 202.635104 -346.583)
			(xy 202.6346 -346.625361) (xy 202.626547 -346.709698) (xy 202.610513 -346.792888) (xy 202.586645 -346.874178)
			(xy 202.555157 -346.95283) (xy 202.516335 -347.028133) (xy 202.470532 -347.099405) (xy 202.418161 -347.166001)
			(xy 202.359696 -347.227316) (xy 202.295668 -347.282797) (xy 202.226656 -347.33194) (xy 202.153286 -347.3743)
			(xy 202.076221 -347.409495) (xy 201.996159 -347.437204) (xy 201.913826 -347.457178) (xy 201.829967 -347.469235)
			(xy 201.745342 -347.473267) (xy 201.660717 -347.469235) (xy 201.576858 -347.457178) (xy 201.494525 -347.437204)
			(xy 201.414463 -347.409495) (xy 201.337398 -347.3743) (xy 201.264028 -347.33194) (xy 201.195016 -347.282797)
			(xy 201.130988 -347.227316) (xy 201.072523 -347.166001) (xy 201.020152 -347.099405) (xy 200.974349 -347.028133)
			(xy 200.935527 -346.95283) (xy 200.904039 -346.874178) (xy 200.880171 -346.792888) (xy 200.864137 -346.709698)
			(xy 200.856084 -346.625361) (xy 200.85558 -346.583) (xy 111.976916 -346.583) (xy 108.572554 -349.987362)
			(xy 108.554467 -350.004565) (xy 108.512978 -350.032303) (xy 108.466875 -350.051415) (xy 108.417929 -350.061165)
			(xy 108.392976 -350.061784) (xy 103.506778 -350.061784) (xy 103.48087 -350.079564) (xy 103.475282 -350.09455)
			(xy 103.465234 -350.119781) (xy 103.439025 -350.167345) (xy 103.406335 -350.210712) (xy 103.367826 -350.249006)
			(xy 103.324276 -350.281451) (xy 103.276565 -350.307392) (xy 103.225657 -350.326306) (xy 103.172582 -350.337809)
			(xy 103.118412 -350.341669) (xy 103.064242 -350.337809) (xy 103.011167 -350.326306) (xy 102.960259 -350.307392)
			(xy 102.912548 -350.281451) (xy 102.868998 -350.249006) (xy 102.830489 -350.210712) (xy 102.797799 -350.167345)
			(xy 102.77159 -350.119781) (xy 102.761542 -350.09455) (xy 102.757425 -350.08513) (xy 102.7432 -350.07032)
			(xy 102.724311 -350.062262) (xy 102.714044 -350.061784) (xy 87.177372 -350.061784) (xy 87.167298 -350.062173)
			(xy 87.148699 -350.069917) (xy 87.141304 -350.07677) (xy 85.26145 -351.956624) (xy 85.243385 -351.973854)
			(xy 85.201891 -352.001599) (xy 85.155782 -352.020715) (xy 85.106829 -352.030468) (xy 85.081872 -352.031046)
			(xy 81.92516 -352.031046) (xy 81.915087 -352.031439) (xy 81.896489 -352.039181) (xy 81.889092 -352.046032)
			(xy 80.651324 -353.2838) (xy 182.729656 -353.2838) (xy 182.733646 -353.200045) (xy 182.745579 -353.117047)
			(xy 182.765347 -353.035561) (xy 182.792771 -352.956321) (xy 182.827603 -352.880048) (xy 182.869527 -352.807431)
			(xy 182.918163 -352.739127) (xy 182.973072 -352.675756) (xy 183.033756 -352.617891) (xy 183.099666 -352.566056)
			(xy 183.170204 -352.520721) (xy 183.244732 -352.482296) (xy 183.322575 -352.451129) (xy 183.403028 -352.427503)
			(xy 183.485362 -352.411631) (xy 183.568833 -352.403656) (xy 183.610758 -352.403156) (xy 183.611774 -352.403156)
			(xy 183.648831 -352.403571) (xy 183.72268 -352.409833) (xy 183.795742 -352.422272) (xy 183.867502 -352.440802)
			(xy 183.902604 -352.452686) (xy 183.910801 -352.4552) (xy 183.927935 -352.4552) (xy 183.936132 -352.452686)
			(xy 183.964337 -352.443048) (xy 184.021791 -352.42716) (xy 184.05094 -352.420936) (xy 184.060579 -352.41851)
			(xy 184.077071 -352.407448) (xy 184.088123 -352.390948) (xy 184.090564 -352.381312) (xy 184.100088 -352.337416)
			(xy 184.126813 -352.251655) (xy 184.143904 -352.210116) (xy 184.147468 -352.200525) (xy 184.147469 -352.180082)
			(xy 184.143904 -352.170492) (xy 184.126892 -352.12911) (xy 184.100271 -352.043685) (xy 184.082363 -351.956018)
			(xy 184.073351 -351.866996) (xy 184.072784 -351.822258) (xy 184.072784 -351.822004) (xy 184.073288 -351.779656)
			(xy 184.081339 -351.695342) (xy 184.097368 -351.612176) (xy 184.121229 -351.530909) (xy 184.152708 -351.452279)
			(xy 184.191519 -351.376998) (xy 184.237309 -351.305746) (xy 184.289665 -351.23917) (xy 184.348113 -351.177872)
			(xy 184.412123 -351.122407) (xy 184.481115 -351.073278) (xy 184.554465 -351.030929) (xy 184.631508 -350.995745)
			(xy 184.711547 -350.968043) (xy 184.793856 -350.948075) (xy 184.877691 -350.936022) (xy 184.962292 -350.931992)
			(xy 185.046893 -350.936022) (xy 185.130728 -350.948075) (xy 185.213037 -350.968043) (xy 185.293076 -350.995745)
			(xy 185.370119 -351.030929) (xy 185.443469 -351.073278) (xy 185.512461 -351.122407) (xy 185.576471 -351.177872)
			(xy 185.634919 -351.23917) (xy 185.687275 -351.305746) (xy 185.733065 -351.376998) (xy 185.771876 -351.452279)
			(xy 185.803355 -351.530909) (xy 185.827216 -351.612176) (xy 185.843245 -351.695342) (xy 185.851296 -351.779656)
			(xy 185.8518 -351.822004) (xy 185.8518 -351.822258) (xy 185.851234 -351.866996) (xy 185.842218 -351.956018)
			(xy 185.824312 -352.043685) (xy 185.797698 -352.129113) (xy 185.78068 -352.170492) (xy 185.777112 -352.180082)
			(xy 185.777113 -352.200525) (xy 185.78068 -352.210116) (xy 185.797704 -352.251527) (xy 185.824339 -352.337015)
			(xy 185.842246 -352.424746) (xy 185.851245 -352.513834) (xy 185.8518 -352.558604) (xy 185.85116 -352.609084)
			(xy 185.839825 -352.709404) (xy 185.829194 -352.758756) (xy 185.826997 -352.771225) (xy 185.833664 -352.795617)
			(xy 185.841894 -352.805238) (xy 185.882534 -352.847656) (xy 185.889646 -352.846132) (xy 185.898412 -352.843862)
			(xy 185.913646 -352.834103) (xy 185.919364 -352.827082) (xy 185.944527 -352.794419) (xy 185.999939 -352.733355)
			(xy 186.060764 -352.67768) (xy 186.126478 -352.627872) (xy 186.196519 -352.584357) (xy 186.270286 -352.547509)
			(xy 186.347146 -352.517645) (xy 186.426439 -352.49502) (xy 186.507485 -352.479828) (xy 186.589589 -352.472201)
			(xy 186.630818 -352.471736) (xy 186.671925 -352.472195) (xy 186.753788 -352.479781) (xy 186.834603 -352.494887)
			(xy 186.913679 -352.517383) (xy 186.990343 -352.547078) (xy 187.06394 -352.583719) (xy 187.133844 -352.626993)
			(xy 187.199457 -352.676531) (xy 187.260221 -352.73191) (xy 187.315617 -352.792659) (xy 187.365173 -352.85826)
			(xy 187.408465 -352.928152) (xy 187.445126 -353.001739) (xy 187.474841 -353.078395) (xy 187.497359 -353.157466)
			(xy 187.512486 -353.238276) (xy 187.519078 -353.3092) (xy 191.056256 -353.3092) (xy 191.060246 -353.225443)
			(xy 191.07218 -353.142444) (xy 191.091948 -353.060956) (xy 191.119373 -352.981715) (xy 191.154206 -352.90544)
			(xy 191.196132 -352.832822) (xy 191.244771 -352.764518) (xy 191.299682 -352.701146) (xy 191.360368 -352.643281)
			(xy 191.42628 -352.591447) (xy 191.49682 -352.546112) (xy 191.57135 -352.507688) (xy 191.649196 -352.476522)
			(xy 191.729651 -352.452897) (xy 191.811988 -352.437027) (xy 191.89546 -352.429055) (xy 191.937386 -352.428556)
			(xy 191.938402 -352.428556) (xy 191.975459 -352.428963) (xy 192.049308 -352.435227) (xy 192.12237 -352.447669)
			(xy 192.194131 -352.466201) (xy 192.229232 -352.478086) (xy 192.237429 -352.4806) (xy 192.254563 -352.4806)
			(xy 192.26276 -352.478086) (xy 192.290041 -352.468747) (xy 192.345585 -352.453243) (xy 192.373758 -352.447098)
			(xy 192.383527 -352.444576) (xy 192.400163 -352.433196) (xy 192.411142 -352.416293) (xy 192.413382 -352.406458)
			(xy 192.422838 -352.357349) (xy 192.451357 -352.261489) (xy 192.470278 -352.215196) (xy 192.473919 -352.205632)
			(xy 192.474045 -352.185185) (xy 192.470532 -352.175572) (xy 192.453515 -352.134192) (xy 192.426895 -352.048766)
			(xy 192.408989 -351.961099) (xy 192.399978 -351.872077) (xy 192.399412 -351.827338) (xy 192.399412 -351.827084)
			(xy 192.399916 -351.784736) (xy 192.407967 -351.700422) (xy 192.423996 -351.617256) (xy 192.447857 -351.535989)
			(xy 192.479336 -351.457359) (xy 192.518147 -351.382078) (xy 192.563937 -351.310826) (xy 192.616293 -351.24425)
			(xy 192.674741 -351.182952) (xy 192.738751 -351.127487) (xy 192.807743 -351.078358) (xy 192.881093 -351.036009)
			(xy 192.958136 -351.000825) (xy 193.038175 -350.973123) (xy 193.120484 -350.953155) (xy 193.204319 -350.941102)
			(xy 193.28892 -350.937072) (xy 193.373521 -350.941102) (xy 193.457356 -350.953155) (xy 193.539665 -350.973123)
			(xy 193.619704 -351.000825) (xy 193.696747 -351.036009) (xy 193.770097 -351.078358) (xy 193.839089 -351.127487)
			(xy 193.903099 -351.182952) (xy 193.961547 -351.24425) (xy 194.013903 -351.310826) (xy 194.059693 -351.382078)
			(xy 194.098504 -351.457359) (xy 194.129983 -351.535989) (xy 194.153844 -351.617256) (xy 194.169873 -351.700422)
			(xy 194.177924 -351.784736) (xy 194.178428 -351.827084) (xy 194.178428 -351.827338) (xy 194.177853 -351.872076)
			(xy 194.168839 -351.961098) (xy 194.150936 -352.048765) (xy 194.124325 -352.134193) (xy 194.107308 -352.175572)
			(xy 194.10375 -352.185165) (xy 194.103744 -352.205606) (xy 194.107308 -352.215196) (xy 194.12436 -352.256596)
			(xy 194.150986 -352.342088) (xy 194.168886 -352.429823) (xy 194.177877 -352.518913) (xy 194.178428 -352.563684)
			(xy 194.178055 -352.600778) (xy 194.171875 -352.674709) (xy 194.159556 -352.747868) (xy 194.150742 -352.783902)
			(xy 194.149 -352.792252) (xy 194.15051 -352.809229) (xy 194.157543 -352.824754) (xy 194.163188 -352.831146)
			(xy 194.203574 -352.874326) (xy 194.216274 -352.871532) (xy 194.225043 -352.869274) (xy 194.240276 -352.859506)
			(xy 194.245992 -352.852482) (xy 194.271138 -352.819805) (xy 194.326552 -352.758742) (xy 194.387379 -352.703068)
			(xy 194.453095 -352.65326) (xy 194.523138 -352.609746) (xy 194.596907 -352.5729) (xy 194.673768 -352.543037)
			(xy 194.753063 -352.520414) (xy 194.834111 -352.505225) (xy 194.916217 -352.4976) (xy 194.957446 -352.497136)
			(xy 194.998553 -352.497569) (xy 195.080417 -352.505157) (xy 195.161232 -352.520265) (xy 195.240309 -352.542764)
			(xy 195.316973 -352.572461) (xy 195.354442 -352.591116) (xy 205.807056 -352.591116) (xy 205.807462 -352.564732)
			(xy 205.814752 -352.51247) (xy 205.829168 -352.461709) (xy 205.850436 -352.413416) (xy 205.878149 -352.368511)
			(xy 205.911782 -352.327849) (xy 205.950692 -352.292205) (xy 205.994139 -352.262257) (xy 206.041295 -352.238577)
			(xy 206.066136 -352.229674) (xy 206.077432 -352.225019) (xy 206.094294 -352.207398) (xy 206.098394 -352.195892)
			(xy 206.108643 -352.162345) (xy 206.134476 -352.097123) (xy 206.166181 -352.034545) (xy 206.1845 -352.00463)
			(xy 206.19024 -351.994335) (xy 206.192624 -351.970911) (xy 206.189072 -351.959672) (xy 206.169845 -351.928882)
			(xy 206.136611 -351.864342) (xy 206.109656 -351.796937) (xy 206.089223 -351.727278) (xy 206.075496 -351.655993)
			(xy 206.0686 -351.583727) (xy 206.068168 -351.54743) (xy 206.068657 -351.508759) (xy 206.076482 -351.431814)
			(xy 206.092051 -351.356055) (xy 206.115204 -351.28226) (xy 206.145704 -351.211186) (xy 206.183239 -351.143563)
			(xy 206.227422 -351.080083) (xy 206.2778 -351.021399) (xy 206.333857 -350.968113) (xy 206.395017 -350.920772)
			(xy 206.460653 -350.879861) (xy 206.530091 -350.8458) (xy 206.602618 -350.818938) (xy 206.677491 -350.799553)
			(xy 206.753941 -350.787841) (xy 206.831184 -350.783924) (xy 206.908427 -350.787841) (xy 206.984877 -350.799553)
			(xy 207.05975 -350.818938) (xy 207.132277 -350.8458) (xy 207.201715 -350.879861) (xy 207.267351 -350.920772)
			(xy 207.328511 -350.968113) (xy 207.384568 -351.021399) (xy 207.434946 -351.080083) (xy 207.479129 -351.143563)
			(xy 207.516664 -351.211186) (xy 207.547164 -351.28226) (xy 207.570317 -351.356055) (xy 207.585886 -351.431814)
			(xy 207.593711 -351.508759) (xy 207.5942 -351.54743) (xy 207.593778 -351.583728) (xy 207.586882 -351.655995)
			(xy 207.573156 -351.727281) (xy 207.552724 -351.796943) (xy 207.525771 -351.864349) (xy 207.492539 -351.928892)
			(xy 207.473296 -351.959672) (xy 207.469691 -351.970907) (xy 207.472073 -351.994352) (xy 207.477868 -352.00463)
			(xy 207.500205 -352.041221) (xy 207.537401 -352.118464) (xy 207.565714 -352.199386) (xy 207.584789 -352.28297)
			(xy 207.594385 -352.368164) (xy 207.594962 -352.41103) (xy 207.594483 -352.451032) (xy 207.586117 -352.530596)
			(xy 207.569481 -352.60885) (xy 207.544756 -352.684937) (xy 207.512213 -352.758022) (xy 207.472209 -352.827306)
			(xy 207.425182 -352.892028) (xy 207.371648 -352.951481) (xy 207.312193 -353.005011) (xy 207.247467 -353.052034)
			(xy 207.178181 -353.092034) (xy 207.105094 -353.124572) (xy 207.029006 -353.149293) (xy 206.950751 -353.165925)
			(xy 206.871186 -353.174285) (xy 206.831184 -353.174808) (xy 206.790883 -353.174276) (xy 206.710731 -353.165788)
			(xy 206.631919 -353.148898) (xy 206.555327 -353.123794) (xy 206.481808 -353.090756) (xy 206.412182 -353.050153)
			(xy 206.347223 -353.002435) (xy 206.317088 -352.975672) (xy 206.307595 -352.967943) (xy 206.283954 -352.961723)
			(xy 206.271876 -352.963734) (xy 206.251504 -352.96799) (xy 206.210136 -352.972573) (xy 206.189326 -352.972878)
			(xy 206.188818 -352.972878) (xy 206.161548 -352.972382) (xy 206.107563 -352.964623) (xy 206.055232 -352.949259)
			(xy 206.00562 -352.926605) (xy 205.959737 -352.897121) (xy 205.918517 -352.861407) (xy 205.8828 -352.82019)
			(xy 205.853311 -352.77431) (xy 205.830653 -352.7247) (xy 205.815285 -352.67237) (xy 205.807521 -352.618386)
			(xy 205.807056 -352.591116) (xy 195.354442 -352.591116) (xy 195.390571 -352.609104) (xy 195.460474 -352.652379)
			(xy 195.526087 -352.701919) (xy 195.586851 -352.757301) (xy 195.642247 -352.818051) (xy 195.691802 -352.883653)
			(xy 195.735094 -352.953546) (xy 195.771754 -353.027135) (xy 195.80147 -353.103792) (xy 195.823987 -353.182863)
			(xy 195.839114 -353.263674) (xy 195.846722 -353.345537) (xy 195.847208 -353.386644) (xy 195.846646 -353.431414)
			(xy 195.837635 -353.520499) (xy 195.81973 -353.60823) (xy 195.793111 -353.693721) (xy 195.776088 -353.735132)
			(xy 195.772497 -353.744715) (xy 195.772513 -353.765165) (xy 195.776088 -353.774756) (xy 195.793114 -353.816166)
			(xy 195.81975 -353.901654) (xy 195.837657 -353.989386) (xy 195.846654 -354.078474) (xy 195.847208 -354.123244)
			(xy 195.846646 -354.168014) (xy 195.837635 -354.257099) (xy 195.81973 -354.34483) (xy 195.793111 -354.430321)
			(xy 195.776088 -354.471732) (xy 195.772497 -354.481315) (xy 195.772513 -354.501765) (xy 195.776088 -354.511356)
			(xy 195.793114 -354.552766) (xy 195.81975 -354.638254) (xy 195.837657 -354.725986) (xy 195.846654 -354.815074)
			(xy 195.847208 -354.859844) (xy 195.84679 -354.900955) (xy 195.839198 -354.982827) (xy 195.824083 -355.063648)
			(xy 195.801575 -355.14273) (xy 195.771864 -355.219398) (xy 195.735206 -355.292996) (xy 195.691912 -355.362897)
			(xy 195.642352 -355.428505) (xy 195.586949 -355.48926) (xy 195.526176 -355.544642) (xy 195.460551 -355.59418)
			(xy 195.390636 -355.637451) (xy 195.317025 -355.674085) (xy 195.240348 -355.703769) (xy 195.161258 -355.726251)
			(xy 195.080432 -355.741339) (xy 194.998557 -355.748903) (xy 194.957446 -355.749352) (xy 194.915842 -355.74888)
			(xy 194.832994 -355.741147) (xy 194.75123 -355.725716) (xy 194.671262 -355.702722) (xy 194.593789 -355.672366)
			(xy 194.519488 -355.634911) (xy 194.48399 -355.613208) (xy 194.474858 -355.608031) (xy 194.454138 -355.60482)
			(xy 194.433861 -355.61016) (xy 194.425316 -355.616256) (xy 194.391667 -355.642178) (xy 194.320293 -355.688236)
			(xy 194.244854 -355.727283) (xy 194.166037 -355.758962) (xy 194.08456 -355.782986) (xy 194.001164 -355.799135)
			(xy 193.916608 -355.807262) (xy 193.874136 -355.807772) (xy 193.873882 -355.807772) (xy 193.832775 -355.807305)
			(xy 193.750912 -355.799719) (xy 193.670098 -355.784614) (xy 193.591023 -355.762118) (xy 193.514359 -355.732423)
			(xy 193.440762 -355.695782) (xy 193.370859 -355.652509) (xy 193.305245 -355.602971) (xy 193.244482 -355.547592)
			(xy 193.189086 -355.486844) (xy 193.13953 -355.421244) (xy 193.096237 -355.351353) (xy 193.059577 -355.277766)
			(xy 193.029861 -355.201111) (xy 193.007343 -355.122041) (xy 192.992215 -355.041231) (xy 192.984607 -354.959371)
			(xy 192.98412 -354.918264) (xy 192.984683 -354.873494) (xy 192.993693 -354.784409) (xy 193.011598 -354.696678)
			(xy 193.038217 -354.611187) (xy 193.05524 -354.569776) (xy 193.058825 -354.560191) (xy 193.058812 -354.539743)
			(xy 193.05524 -354.530152) (xy 193.03824 -354.4888) (xy 193.011628 -354.403438) (xy 192.99372 -354.315836)
			(xy 192.984697 -354.226879) (xy 192.98412 -354.182172) (xy 192.98412 -354.181156) (xy 192.984374 -354.169726)
			(xy 192.957895 -354.163781) (xy 192.90566 -354.149038) (xy 192.87998 -354.140262) (xy 192.871783 -354.137748)
			(xy 192.854649 -354.137748) (xy 192.846452 -354.140262) (xy 192.811236 -354.152209) (xy 192.739226 -354.170796)
			(xy 192.665903 -354.183236) (xy 192.591792 -354.18944) (xy 192.554606 -354.189792) (xy 192.517422 -354.189422)
			(xy 192.443314 -354.1832) (xy 192.369994 -354.170758) (xy 192.297983 -354.152184) (xy 192.26276 -354.140262)
			(xy 192.254563 -354.137748) (xy 192.237429 -354.137748) (xy 192.229232 -354.140262) (xy 192.19413 -354.15215)
			(xy 192.122374 -354.1707) (xy 192.049311 -354.183146) (xy 191.97546 -354.189399) (xy 191.938402 -354.189792)
			(xy 191.937386 -354.189792) (xy 191.89546 -354.189345) (xy 191.811988 -354.181373) (xy 191.729651 -354.165503)
			(xy 191.649196 -354.141878) (xy 191.57135 -354.110712) (xy 191.49682 -354.072288) (xy 191.42628 -354.026953)
			(xy 191.360368 -353.975119) (xy 191.299682 -353.917254) (xy 191.244771 -353.853882) (xy 191.196132 -353.785578)
			(xy 191.154206 -353.71296) (xy 191.119373 -353.636685) (xy 191.091948 -353.557444) (xy 191.07218 -353.475956)
			(xy 191.060246 -353.392957) (xy 191.056256 -353.3092) (xy 187.519078 -353.3092) (xy 187.520094 -353.320137)
			(xy 187.52058 -353.361244) (xy 187.52002 -353.406014) (xy 187.511009 -353.495099) (xy 187.493104 -353.58283)
			(xy 187.466484 -353.668321) (xy 187.44946 -353.709732) (xy 187.44587 -353.719315) (xy 187.445886 -353.739765)
			(xy 187.44946 -353.749356) (xy 187.466484 -353.790767) (xy 187.493121 -353.876254) (xy 187.511029 -353.963986)
			(xy 187.520026 -354.053074) (xy 187.52058 -354.097844) (xy 187.52002 -354.142614) (xy 187.511009 -354.231699)
			(xy 187.493104 -354.31943) (xy 187.466484 -354.404921) (xy 187.44946 -354.446332) (xy 187.44587 -354.455915)
			(xy 187.445886 -354.476365) (xy 187.44946 -354.485956) (xy 187.466484 -354.527367) (xy 187.493121 -354.612854)
			(xy 187.511029 -354.700586) (xy 187.520026 -354.789674) (xy 187.52058 -354.834444) (xy 187.520189 -354.875556)
			(xy 187.512597 -354.957429) (xy 187.497482 -355.038252) (xy 187.474973 -355.117336) (xy 187.445261 -355.194004)
			(xy 187.408601 -355.267604) (xy 187.365306 -355.337506) (xy 187.315744 -355.403115) (xy 187.260339 -355.46387)
			(xy 187.199564 -355.519252) (xy 187.133937 -355.56879) (xy 187.064019 -355.61206) (xy 186.990406 -355.648693)
			(xy 186.913727 -355.678376) (xy 186.834635 -355.700857) (xy 186.753806 -355.715942) (xy 186.67193 -355.723505)
			(xy 186.630818 -355.723952) (xy 186.589214 -355.723494) (xy 186.506365 -355.715758) (xy 186.424601 -355.700325)
			(xy 186.344633 -355.677328) (xy 186.267161 -355.646969) (xy 186.192859 -355.609513) (xy 186.157362 -355.587808)
			(xy 186.148243 -355.582606) (xy 186.127514 -355.579404) (xy 186.107233 -355.584754) (xy 186.098688 -355.590856)
			(xy 186.065049 -355.616791) (xy 185.993673 -355.662848) (xy 185.918232 -355.701893) (xy 185.839413 -355.73357)
			(xy 185.757935 -355.757592) (xy 185.674537 -355.773739) (xy 185.589981 -355.781864) (xy 185.547508 -355.782372)
			(xy 185.547254 -355.782372) (xy 185.506147 -355.781931) (xy 185.424283 -355.774343) (xy 185.343469 -355.759235)
			(xy 185.264393 -355.736737) (xy 185.187729 -355.70704) (xy 185.114132 -355.670398) (xy 185.044229 -355.627122)
			(xy 184.978615 -355.577583) (xy 184.917852 -355.522202) (xy 184.862456 -355.461452) (xy 184.812901 -355.395851)
			(xy 184.769609 -355.325959) (xy 184.732948 -355.252371) (xy 184.703232 -355.175714) (xy 184.680715 -355.096644)
			(xy 184.665587 -355.015833) (xy 184.657979 -354.933971) (xy 184.657492 -354.892864) (xy 184.658057 -354.848094)
			(xy 184.667066 -354.759009) (xy 184.684971 -354.671278) (xy 184.711589 -354.585787) (xy 184.728612 -354.544376)
			(xy 184.732199 -354.534792) (xy 184.732185 -354.514343) (xy 184.728612 -354.504752) (xy 184.711616 -354.463398)
			(xy 184.685002 -354.378037) (xy 184.667093 -354.290435) (xy 184.658069 -354.201478) (xy 184.657492 -354.156772)
			(xy 184.657492 -354.155756) (xy 184.657746 -354.144326) (xy 184.631266 -354.138384) (xy 184.579032 -354.123639)
			(xy 184.553352 -354.114862) (xy 184.545155 -354.112348) (xy 184.528021 -354.112348) (xy 184.519824 -354.114862)
			(xy 184.484602 -354.126789) (xy 184.412594 -354.145381) (xy 184.339273 -354.157827) (xy 184.265163 -354.164037)
			(xy 184.227978 -354.164392) (xy 184.190794 -354.16403) (xy 184.116686 -354.157806) (xy 184.043366 -354.145361)
			(xy 183.971355 -354.126785) (xy 183.936132 -354.114862) (xy 183.927935 -354.112348) (xy 183.910801 -354.112348)
			(xy 183.902604 -354.114862) (xy 183.867505 -354.126757) (xy 183.795747 -354.145305) (xy 183.722684 -354.157749)
			(xy 183.648832 -354.164001) (xy 183.611774 -354.164392) (xy 183.610758 -354.164392) (xy 183.568833 -354.163944)
			(xy 183.485362 -354.155969) (xy 183.403028 -354.140097) (xy 183.322575 -354.11647) (xy 183.244732 -354.085304)
			(xy 183.170204 -354.046879) (xy 183.099666 -354.001544) (xy 183.033756 -353.949709) (xy 182.973072 -353.891844)
			(xy 182.918163 -353.828473) (xy 182.869527 -353.760169) (xy 182.827603 -353.687552) (xy 182.792771 -353.611278)
			(xy 182.765347 -353.532039) (xy 182.745579 -353.450553) (xy 182.733646 -353.367555) (xy 182.729656 -353.2838)
			(xy 80.651324 -353.2838) (xy 79.196946 -354.738178) (xy 79.178865 -354.755388) (xy 79.137374 -354.783124)
			(xy 79.091269 -354.802233) (xy 79.042322 -354.811982) (xy 79.017368 -354.8126) (xy 27.187652 -354.8126)
			(xy 27.162691 -354.81204) (xy 27.113726 -354.802311) (xy 27.067607 -354.783198) (xy 27.026114 -354.755439)
			(xy 27.008074 -354.738178) (xy 25.037288 -352.767392) (xy 25.030685 -352.761223) (xy 25.014289 -352.753654)
			(xy 24.996282 -352.752289) (xy 24.987504 -352.754438) (xy 24.986996 -352.754438) (xy 24.952747 -352.763874)
			(xy 24.882939 -352.777074) (xy 24.812206 -352.783726) (xy 24.776684 -352.784156) (xy 24.736749 -352.783649)
			(xy 24.657317 -352.775301) (xy 24.579192 -352.758696) (xy 24.503232 -352.734015) (xy 24.430267 -352.701529)
			(xy 24.361097 -352.661594) (xy 24.296481 -352.614648) (xy 24.237126 -352.561205) (xy 24.183683 -352.50185)
			(xy 24.136737 -352.437234) (xy 24.096802 -352.368065) (xy 24.064316 -352.2951) (xy 24.039635 -352.21914)
			(xy 24.023029 -352.141015) (xy 24.014681 -352.061583) (xy 24.014176 -352.021648) (xy 24.014605 -351.986084)
			(xy 24.021246 -351.915265) (xy 24.034456 -351.845374) (xy 24.043894 -351.811082) (xy 24.043894 -351.810828)
			(xy 24.046001 -351.802051) (xy 24.044595 -351.784068) (xy 24.037057 -351.767681) (xy 24.03094 -351.761044)
			(xy 23.696422 -351.426526) (xy 23.679203 -351.408453) (xy 23.651469 -351.366959) (xy 23.632362 -351.320852)
			(xy 23.622616 -351.271903) (xy 23.622 -351.246948) (xy 23.622 -346.293186) (xy 23.621608 -346.283112)
			(xy 23.613867 -346.264513) (xy 23.607014 -346.257118) (xy 22.974808 -345.624912) (xy 22.95758 -345.606847)
			(xy 22.929848 -345.56535) (xy 22.910743 -345.51924) (xy 22.901001 -345.470289) (xy 22.900386 -345.445334)
			(xy 22.900386 -343.306908) (xy 22.899754 -343.295491) (xy 22.889854 -343.274914) (xy 22.881336 -343.267284)
			(xy 22.859903 -343.249489) (xy 22.822053 -343.20862) (xy 22.790708 -343.162572) (xy 22.766567 -343.112371)
			(xy 22.750168 -343.059135) (xy 22.741876 -343.004052) (xy 22.741876 -342.948348) (xy 22.750168 -342.893265)
			(xy 22.766567 -342.840029) (xy 22.790708 -342.789828) (xy 22.822053 -342.74378) (xy 22.859903 -342.702911)
			(xy 22.881336 -342.685116) (xy 22.889855 -342.677487) (xy 22.899754 -342.656909) (xy 22.900386 -342.645492)
			(xy 22.900386 -340.487254) (xy 22.881336 -340.460838) (xy 22.865842 -340.455504) (xy 22.839463 -340.446111)
			(xy 22.789557 -340.42072) (xy 22.743898 -340.388307) (xy 22.703467 -340.349568) (xy 22.669132 -340.305336)
			(xy 22.64163 -340.256561) (xy 22.621553 -340.20429) (xy 22.609332 -340.149646) (xy 22.605228 -340.093803)
			(xy 22.609331 -340.037959) (xy 22.621552 -339.983315) (xy 22.641628 -339.931043) (xy 22.669129 -339.882268)
			(xy 22.703463 -339.838036) (xy 22.743894 -339.799297) (xy 22.789552 -339.766883) (xy 22.839458 -339.741491)
			(xy 22.865842 -339.732112) (xy 22.875698 -339.728252) (xy 22.891334 -339.714022) (xy 22.899863 -339.694678)
			(xy 22.900386 -339.684106) (xy 22.900386 -335.047082) (xy 22.900132 -335.046574) (xy 22.900132 -244.844062)
			(xy 22.899631 -244.833451) (xy 22.891128 -244.814012) (xy 22.875473 -244.799691) (xy 22.865588 -244.795802)
			(xy 22.865334 -244.795802) (xy 22.828623 -244.782881) (xy 22.757856 -244.750488) (xy 22.690824 -244.710938)
			(xy 22.62825 -244.664657) (xy 22.570807 -244.612144) (xy 22.519113 -244.553962) (xy 22.473723 -244.490739)
			(xy 22.435128 -244.423153) (xy 22.40374 -244.351934) (xy 22.3799 -244.277846) (xy 22.363862 -244.201687)
			(xy 22.355799 -244.124276) (xy 22.355799 -244.046447) (xy 22.363861 -243.969036) (xy 22.379899 -243.892877)
			(xy 22.403739 -243.818789) (xy 22.435126 -243.747569) (xy 22.473722 -243.679984) (xy 22.519111 -243.61676)
			(xy 22.570805 -243.558578) (xy 22.628248 -243.506064) (xy 22.690822 -243.459783) (xy 22.757853 -243.420233)
			(xy 22.828621 -243.38784) (xy 22.865334 -243.374926) (xy 22.865588 -243.374926) (xy 22.875455 -243.371022)
			(xy 22.891058 -243.356671) (xy 22.899591 -243.337265) (xy 22.900132 -243.326666) (xy 22.900132 -227.059236)
			(xy 22.900568 -227.049168) (xy 22.90828 -227.030569) (xy 22.915118 -227.023168) (xy 23.51532 -226.422966)
			(xy 23.522715 -226.41612) (xy 23.541318 -226.408405) (xy 23.551388 -226.40798) (xy 28.919932 -226.40798)
			(xy 28.925372 -226.407844) (xy 28.936006 -226.405538) (xy 28.941014 -226.403408) (xy 28.977724 -226.387208)
			(xy 29.053857 -226.36185) (xy 29.132262 -226.344762) (xy 29.212042 -226.336141) (xy 29.252164 -226.33559)
			(xy 29.292287 -226.336138) (xy 29.372069 -226.34475) (xy 29.450474 -226.361838) (xy 29.526604 -226.387206)
			(xy 29.563314 -226.403408) (xy 29.568322 -226.405537) (xy 29.578956 -226.40784) (xy 29.584396 -226.40798)
			(xy 36.463732 -226.40798) (xy 36.469172 -226.407844) (xy 36.479806 -226.405538) (xy 36.484814 -226.403408)
			(xy 36.521524 -226.387208) (xy 36.597657 -226.36185) (xy 36.676062 -226.344762) (xy 36.755842 -226.336141)
			(xy 36.795964 -226.33559) (xy 36.836087 -226.336138) (xy 36.915869 -226.34475) (xy 36.994274 -226.361838)
			(xy 37.070404 -226.387206) (xy 37.107114 -226.403408) (xy 37.112122 -226.405537) (xy 37.122756 -226.40784)
			(xy 37.128196 -226.40798) (xy 40.502332 -226.40798) (xy 40.512344 -226.407538) (xy 40.530841 -226.399864)
			(xy 40.544993 -226.385697) (xy 40.552648 -226.367193) (xy 40.553132 -226.35718) (xy 40.553132 -195.9356)
			(xy 40.552613 -195.925596) (xy 40.544959 -195.907111) (xy 40.530816 -195.892959) (xy 40.512335 -195.885294)
			(xy 40.502332 -195.8848) (xy 38.693852 -195.8848) (xy 38.683784 -195.885262) (xy 38.665217 -195.893065)
			(xy 38.651054 -195.907384) (xy 38.646862 -195.91655) (xy 38.631906 -195.952239) (xy 38.595655 -196.02061)
			(xy 38.552557 -196.084885) (xy 38.503068 -196.144379) (xy 38.447715 -196.198459) (xy 38.387086 -196.246552)
			(xy 38.321828 -196.288145) (xy 38.252632 -196.322796) (xy 38.180236 -196.350137) (xy 38.10541 -196.369876)
			(xy 38.028948 -196.381804) (xy 37.951664 -196.385795) (xy 37.87438 -196.381804) (xy 37.797918 -196.369876)
			(xy 37.723092 -196.350137) (xy 37.650696 -196.322796) (xy 37.5815 -196.288145) (xy 37.516242 -196.246552)
			(xy 37.455613 -196.198459) (xy 37.40026 -196.144379) (xy 37.350771 -196.084885) (xy 37.307673 -196.02061)
			(xy 37.271422 -195.952239) (xy 37.256466 -195.91655) (xy 37.252331 -195.907343) (xy 37.238175 -195.892979)
			(xy 37.219561 -195.885217) (xy 37.209476 -195.8848) (xy 31.150052 -195.8848) (xy 31.139984 -195.885262)
			(xy 31.121417 -195.893065) (xy 31.107254 -195.907384) (xy 31.103062 -195.91655) (xy 31.088106 -195.952239)
			(xy 31.051855 -196.02061) (xy 31.008757 -196.084885) (xy 30.959268 -196.144379) (xy 30.903915 -196.198459)
			(xy 30.843286 -196.246552) (xy 30.778028 -196.288145) (xy 30.708832 -196.322796) (xy 30.636436 -196.350137)
			(xy 30.56161 -196.369876) (xy 30.485148 -196.381804) (xy 30.407864 -196.385795) (xy 30.33058 -196.381804)
			(xy 30.254118 -196.369876) (xy 30.179292 -196.350137) (xy 30.106896 -196.322796) (xy 30.0377 -196.288145)
			(xy 29.972442 -196.246552) (xy 29.911813 -196.198459) (xy 29.85646 -196.144379) (xy 29.806971 -196.084885)
			(xy 29.763873 -196.02061) (xy 29.727622 -195.952239) (xy 29.712666 -195.91655) (xy 29.708531 -195.907343)
			(xy 29.694375 -195.892979) (xy 29.675761 -195.885217) (xy 29.665676 -195.8848) (xy 23.605998 -195.8848)
			(xy 23.595934 -195.885296) (xy 23.577368 -195.893083) (xy 23.563202 -195.907389) (xy 23.559008 -195.91655)
			(xy 23.544052 -195.952239) (xy 23.507801 -196.02061) (xy 23.464703 -196.084885) (xy 23.415214 -196.144379)
			(xy 23.359861 -196.198459) (xy 23.299232 -196.246552) (xy 23.233974 -196.288145) (xy 23.164778 -196.322796)
			(xy 23.092382 -196.350137) (xy 23.017556 -196.369876) (xy 22.941094 -196.381804) (xy 22.86381 -196.385795)
			(xy 22.786526 -196.381804) (xy 22.710064 -196.369876) (xy 22.635238 -196.350137) (xy 22.562842 -196.322796)
			(xy 22.493646 -196.288145) (xy 22.428388 -196.246552) (xy 22.367759 -196.198459) (xy 22.312406 -196.144379)
			(xy 22.262917 -196.084885) (xy 22.219819 -196.02061) (xy 22.183568 -195.952239) (xy 22.168612 -195.91655)
			(xy 22.164443 -195.907362) (xy 22.150301 -195.892997) (xy 22.131702 -195.885225) (xy 22.121622 -195.8848)
			(xy 19.194526 -195.8848) (xy 19.187568 -195.885) (xy 19.174165 -195.888733) (xy 19.16811 -195.892166)
			(xy 19.136077 -195.91109) (xy 19.068969 -195.943229) (xy 18.999007 -195.968559) (xy 18.92688 -195.986833)
			(xy 18.853297 -195.99787) (xy 18.778982 -196.001561) (xy 18.704667 -195.99787) (xy 18.631084 -195.986833)
			(xy 18.558957 -195.968559) (xy 18.488995 -195.943229) (xy 18.421887 -195.91109) (xy 18.389854 -195.892166)
			(xy 18.383787 -195.888763) (xy 18.370391 -195.885035) (xy 18.363438 -195.8848) (xy 16.001492 -195.8848)
			(xy 15.995847 -195.884931) (xy 15.984823 -195.887366) (xy 15.979648 -195.889626) (xy 15.941117 -195.907386)
			(xy 15.860963 -195.935206) (xy 15.778217 -195.953967) (xy 15.693902 -195.963439) (xy 15.65148 -195.964048)
			(xy 15.609056 -195.963471) (xy 15.524735 -195.954015) (xy 15.441988 -195.935246) (xy 15.361841 -195.907395)
			(xy 15.323312 -195.889626) (xy 15.318134 -195.887373) (xy 15.307113 -195.884929) (xy 15.301468 -195.8848)
			(xy 14.588744 -195.8848) (xy 14.578674 -195.884378) (xy 14.560074 -195.876658) (xy 14.552676 -195.869814)
			(xy 13.950442 -195.267834) (xy 13.945108 -195.264532) (xy 13.912921 -195.244801) (xy 13.852225 -195.199899)
			(xy 13.796263 -195.149218) (xy 13.745584 -195.093254) (xy 13.700684 -195.032556) (xy 13.680948 -195.000372)
			(xy 13.677646 -194.995038) (xy 13.300202 -194.617594) (xy 13.293367 -194.61019) (xy 13.285644 -194.591594)
			(xy 13.285216 -194.581526) (xy 3.523996 -194.581526) (xy 3.523996 -358.071674) (xy 14.058646 -358.071674)
			(xy 14.05923 -358.028982) (xy 14.068776 -357.944134) (xy 14.087733 -357.860882) (xy 14.115866 -357.780266)
			(xy 14.152822 -357.703295) (xy 14.174978 -357.666798) (xy 14.179717 -357.658553) (xy 14.18324 -357.639878)
			(xy 14.179701 -357.621205) (xy 14.174978 -357.61295) (xy 14.152819 -357.576453) (xy 14.115833 -357.499493)
			(xy 14.087689 -357.418878) (xy 14.06874 -357.335621) (xy 14.059225 -357.250767) (xy 14.058646 -357.208074)
			(xy 14.059135 -357.169455) (xy 14.066949 -357.092612) (xy 14.082497 -357.016954) (xy 14.10562 -356.943257)
			(xy 14.136079 -356.872278) (xy 14.173564 -356.804744) (xy 14.217688 -356.74135) (xy 14.267999 -356.682744)
			(xy 14.323981 -356.629529) (xy 14.38506 -356.58225) (xy 14.450608 -356.541394) (xy 14.519954 -356.507378)
			(xy 14.592385 -356.480553) (xy 14.667158 -356.461193) (xy 14.743506 -356.449497) (xy 14.820646 -356.445585)
			(xy 14.897786 -356.449497) (xy 14.974134 -356.461193) (xy 15.048907 -356.480553) (xy 15.121338 -356.507378)
			(xy 15.190684 -356.541394) (xy 15.256232 -356.58225) (xy 15.317311 -356.629529) (xy 15.373293 -356.682744)
			(xy 15.423604 -356.74135) (xy 15.467728 -356.804744) (xy 15.505213 -356.872278) (xy 15.535672 -356.943257)
			(xy 15.558795 -357.016954) (xy 15.574343 -357.092612) (xy 15.582157 -357.169455) (xy 15.582646 -357.208074)
			(xy 15.582038 -357.250765) (xy 15.572498 -357.335612) (xy 15.553546 -357.418864) (xy 15.525419 -357.49948)
			(xy 15.488468 -357.576452) (xy 15.466314 -357.61295) (xy 15.461618 -357.621216) (xy 15.458081 -357.639878)
			(xy 15.461602 -357.658543) (xy 15.466314 -357.666798) (xy 15.488492 -357.703284) (xy 15.525474 -357.780247)
			(xy 15.553615 -357.860865) (xy 15.572559 -357.944124) (xy 15.58207 -358.02898) (xy 15.582646 -358.071674)
			(xy 15.582157 -358.110293) (xy 15.574343 -358.187136) (xy 15.558795 -358.262794) (xy 15.535672 -358.336491)
			(xy 15.505213 -358.40747) (xy 15.467728 -358.475004) (xy 15.423604 -358.538398) (xy 15.414336 -358.549194)
			(xy 40.47998 -358.549194) (xy 40.480352 -358.511134) (xy 40.486825 -358.435291) (xy 40.499758 -358.360279)
			(xy 40.519056 -358.286646) (xy 40.544577 -358.214933) (xy 40.55999 -358.180132) (xy 40.563435 -358.171803)
			(xy 40.56487 -358.153848) (xy 40.562784 -358.14508) (xy 40.551663 -358.104882) (xy 40.536092 -358.022938)
			(xy 40.528245 -357.939897) (xy 40.527732 -357.898192) (xy 40.528135 -357.859902) (xy 40.534744 -357.783608)
			(xy 40.547894 -357.708165) (xy 40.567488 -357.634135) (xy 40.580056 -357.597964) (xy 40.58271 -357.589528)
			(xy 40.582708 -357.571857) (xy 40.580056 -357.56342) (xy 40.567506 -357.527245) (xy 40.547935 -357.453211)
			(xy 40.53479 -357.37777) (xy 40.528167 -357.30148) (xy 40.527732 -357.263192) (xy 40.528236 -357.220831)
			(xy 40.536289 -357.136494) (xy 40.552323 -357.053304) (xy 40.576191 -356.972014) (xy 40.607679 -356.893362)
			(xy 40.646501 -356.818059) (xy 40.692304 -356.746787) (xy 40.744675 -356.680191) (xy 40.80314 -356.618876)
			(xy 40.867168 -356.563395) (xy 40.93618 -356.514252) (xy 41.00955 -356.471892) (xy 41.086615 -356.436697)
			(xy 41.166677 -356.408988) (xy 41.24901 -356.389014) (xy 41.332869 -356.376957) (xy 41.417494 -356.372926)
			(xy 41.502119 -356.376957) (xy 41.585978 -356.389014) (xy 41.668311 -356.408988) (xy 41.748373 -356.436697)
			(xy 41.825438 -356.471892) (xy 41.898808 -356.514252) (xy 41.96782 -356.563395) (xy 42.031848 -356.618876)
			(xy 42.090313 -356.680191) (xy 42.142684 -356.746787) (xy 42.188487 -356.818059) (xy 42.227309 -356.893362)
			(xy 42.258797 -356.972014) (xy 42.282665 -357.053304) (xy 42.298699 -357.136494) (xy 42.306752 -357.220831)
			(xy 42.307256 -357.263192) (xy 42.306849 -357.301482) (xy 42.300241 -357.377776) (xy 42.287093 -357.453218)
			(xy 42.2675 -357.527249) (xy 42.254932 -357.56342) (xy 42.252286 -357.571858) (xy 42.252283 -357.589527)
			(xy 42.254932 -357.597964) (xy 42.267477 -357.634141) (xy 42.28705 -357.708174) (xy 42.300196 -357.783614)
			(xy 42.30682 -357.859904) (xy 42.307256 -357.898192) (xy 42.306876 -357.936251) (xy 42.300404 -358.012094)
			(xy 42.287473 -358.087107) (xy 42.268177 -358.160739) (xy 42.242658 -358.232452) (xy 42.227246 -358.267254)
			(xy 42.223809 -358.275586) (xy 42.222368 -358.293538) (xy 42.224452 -358.302306) (xy 42.23557 -358.342505)
			(xy 42.251142 -358.424449) (xy 42.258991 -358.507489) (xy 42.259032 -358.51084) (xy 43.046396 -358.51084)
			(xy 43.046759 -358.47278) (xy 43.053225 -358.396935) (xy 43.066156 -358.321921) (xy 43.085458 -358.248289)
			(xy 43.110988 -358.176577) (xy 43.126406 -358.141778) (xy 43.129746 -358.133421) (xy 43.131033 -358.115482)
			(xy 43.128946 -358.106726) (xy 43.117873 -358.066521) (xy 43.102375 -357.984574) (xy 43.094614 -357.901538)
			(xy 43.094148 -357.859838) (xy 43.094524 -357.821522) (xy 43.101053 -357.745169) (xy 43.114136 -357.669662)
			(xy 43.133673 -357.595562) (xy 43.146218 -357.559356) (xy 43.148787 -357.551035) (xy 43.148799 -357.533636)
			(xy 43.146218 -357.52532) (xy 43.13374 -357.489193) (xy 43.114246 -357.415282) (xy 43.101158 -357.339973)
			(xy 43.094573 -357.263819) (xy 43.094148 -357.2256) (xy 43.094148 -357.224838) (xy 43.094652 -357.18249)
			(xy 43.102703 -357.098176) (xy 43.118732 -357.01501) (xy 43.142593 -356.933743) (xy 43.174072 -356.855113)
			(xy 43.212883 -356.779832) (xy 43.258673 -356.70858) (xy 43.311029 -356.642004) (xy 43.369477 -356.580706)
			(xy 43.433487 -356.525241) (xy 43.502479 -356.476112) (xy 43.575829 -356.433763) (xy 43.652872 -356.398579)
			(xy 43.732911 -356.370877) (xy 43.81522 -356.350909) (xy 43.899055 -356.338856) (xy 43.983656 -356.334826)
			(xy 44.068257 -356.338856) (xy 44.152092 -356.350909) (xy 44.234401 -356.370877) (xy 44.31444 -356.398579)
			(xy 44.391483 -356.433763) (xy 44.464833 -356.476112) (xy 44.533825 -356.525241) (xy 44.597835 -356.580706)
			(xy 44.656283 -356.642004) (xy 44.708639 -356.70858) (xy 44.754429 -356.779832) (xy 44.79324 -356.855113)
			(xy 44.824719 -356.933743) (xy 44.84858 -357.01501) (xy 44.864609 -357.098176) (xy 44.87266 -357.18249)
			(xy 44.873164 -357.224838) (xy 44.873164 -357.2256) (xy 44.87277 -357.263821) (xy 44.866201 -357.339979)
			(xy 44.853113 -357.415292) (xy 44.833602 -357.489202) (xy 44.821094 -357.52532) (xy 44.818487 -357.533631)
			(xy 44.818499 -357.55104) (xy 44.821094 -357.559356) (xy 44.833623 -357.595567) (xy 44.853143 -357.669669)
			(xy 44.866225 -357.745173) (xy 44.872771 -357.821523) (xy 44.873164 -357.859838) (xy 44.872788 -357.897898)
			(xy 44.866324 -357.973742) (xy 44.853395 -358.048756) (xy 44.837736 -358.108504) (xy 46.991016 -358.108504)
			(xy 46.991397 -358.070445) (xy 46.997869 -357.994602) (xy 47.0108 -357.919589) (xy 47.030096 -357.845957)
			(xy 47.055615 -357.774244) (xy 47.071026 -357.739442) (xy 47.074466 -357.731111) (xy 47.075906 -357.713158)
			(xy 47.07382 -357.70439) (xy 47.0627 -357.664192) (xy 47.047129 -357.582247) (xy 47.039281 -357.499207)
			(xy 47.038768 -357.457502) (xy 47.039173 -357.419212) (xy 47.045781 -357.342918) (xy 47.05893 -357.267476)
			(xy 47.078524 -357.193445) (xy 47.091092 -357.157274) (xy 47.09374 -357.148837) (xy 47.093741 -357.131167)
			(xy 47.091092 -357.12273) (xy 47.078546 -357.086553) (xy 47.058974 -357.01252) (xy 47.045827 -356.93708)
			(xy 47.039204 -356.86079) (xy 47.038768 -356.822502) (xy 47.0392 -356.781386) (xy 47.046788 -356.699506)
			(xy 47.061898 -356.618674) (xy 47.084402 -356.539582) (xy 47.114108 -356.462904) (xy 47.150762 -356.389293)
			(xy 47.194052 -356.319379) (xy 47.243609 -356.253758) (xy 47.299008 -356.192989) (xy 47.359779 -356.137591)
			(xy 47.425402 -356.088036) (xy 47.495318 -356.044749) (xy 47.568929 -356.008097) (xy 47.645609 -355.978393)
			(xy 47.724702 -355.955891) (xy 47.805533 -355.940784) (xy 47.887414 -355.933199) (xy 47.92853 -355.93274)
			(xy 47.969637 -355.933252) (xy 48.051499 -355.940877) (xy 48.132307 -355.956023) (xy 48.211373 -355.97856)
			(xy 48.288023 -356.008296) (xy 48.325024 -356.026212) (xy 48.335846 -356.030917) (xy 48.359414 -356.030917)
			(xy 48.370236 -356.026212) (xy 48.407247 -356.008316) (xy 48.483894 -355.978575) (xy 48.562957 -355.956031)
			(xy 48.643763 -355.940876) (xy 48.725623 -355.93324) (xy 48.76673 -355.93274) (xy 48.80502 -355.933136)
			(xy 48.881314 -355.939747) (xy 48.956757 -355.952899) (xy 49.030787 -355.972495) (xy 49.066958 -355.985064)
			(xy 49.075395 -355.987715) (xy 49.093065 -355.987715) (xy 49.101502 -355.985064) (xy 49.137675 -355.972508)
			(xy 49.21171 -355.952938) (xy 49.287151 -355.939795) (xy 49.363442 -355.933174) (xy 49.40173 -355.93274)
			(xy 49.44002 -355.933136) (xy 49.516314 -355.939747) (xy 49.591757 -355.952899) (xy 49.665787 -355.972495)
			(xy 49.701958 -355.985064) (xy 49.710395 -355.987715) (xy 49.728065 -355.987715) (xy 49.736502 -355.985064)
			(xy 49.772675 -355.972508) (xy 49.84671 -355.952938) (xy 49.922151 -355.939795) (xy 49.998442 -355.933174)
			(xy 50.03673 -355.93274) (xy 50.07502 -355.933136) (xy 50.151314 -355.939747) (xy 50.226757 -355.952899)
			(xy 50.300787 -355.972495) (xy 50.336958 -355.985064) (xy 50.345395 -355.987715) (xy 50.363065 -355.987715)
			(xy 50.371502 -355.985064) (xy 50.407675 -355.972508) (xy 50.48171 -355.952938) (xy 50.557151 -355.939795)
			(xy 50.633442 -355.933174) (xy 50.67173 -355.93274) (xy 50.712845 -355.933184) (xy 50.794723 -355.940774)
			(xy 50.875552 -355.955886) (xy 50.954642 -355.978392) (xy 51.031318 -356.008098) (xy 51.104926 -356.044753)
			(xy 51.174838 -356.088043) (xy 51.240458 -356.137599) (xy 51.301225 -356.192997) (xy 51.356622 -356.253767)
			(xy 51.406175 -356.319388) (xy 51.449463 -356.389302) (xy 51.486115 -356.462911) (xy 51.515819 -356.539588)
			(xy 51.538321 -356.618679) (xy 51.55343 -356.699508) (xy 51.561017 -356.781387) (xy 51.561492 -356.822502)
			(xy 51.561091 -356.860792) (xy 51.554482 -356.937086) (xy 51.541332 -357.012529) (xy 51.521737 -357.086559)
			(xy 51.509168 -357.12273) (xy 51.506515 -357.131166) (xy 51.506516 -357.148837) (xy 51.509168 -357.157274)
			(xy 51.521713 -357.193451) (xy 51.541286 -357.267484) (xy 51.554433 -357.342924) (xy 51.561057 -357.419214)
			(xy 51.561492 -357.457502) (xy 51.561112 -357.495561) (xy 51.55464 -357.571404) (xy 51.541708 -357.646417)
			(xy 51.522413 -357.720049) (xy 51.496894 -357.791762) (xy 51.481482 -357.826564) (xy 51.478039 -357.834894)
			(xy 51.476603 -357.852848) (xy 51.478688 -357.861616) (xy 51.48981 -357.901814) (xy 51.50538 -357.983758)
			(xy 51.513227 -358.066799) (xy 51.51374 -358.108504) (xy 51.513251 -358.149614) (xy 51.505664 -358.231482)
			(xy 51.490553 -358.312301) (xy 51.468049 -358.391381) (xy 51.438343 -358.468047) (xy 51.401689 -358.541644)
			(xy 51.3584 -358.611544) (xy 51.308844 -358.677152) (xy 51.253446 -358.737906) (xy 51.192678 -358.793289)
			(xy 51.127058 -358.842827) (xy 51.057146 -358.886099) (xy 50.98354 -358.922734) (xy 50.906867 -358.952421)
			(xy 50.827781 -358.974905) (xy 50.746958 -358.989995) (xy 50.665088 -358.997562) (xy 50.623978 -358.998012)
			(xy 50.585661 -358.99765) (xy 50.509308 -358.991116) (xy 50.433801 -358.97803) (xy 50.359702 -358.958488)
			(xy 50.323496 -358.945942) (xy 50.31518 -358.943356) (xy 50.297776 -358.943356) (xy 50.28946 -358.945942)
			(xy 50.253248 -358.958468) (xy 50.179147 -358.977989) (xy 50.103642 -358.991071) (xy 50.027293 -358.997619)
			(xy 49.988978 -358.998012) (xy 49.950661 -358.99765) (xy 49.874308 -358.991116) (xy 49.798801 -358.97803)
			(xy 49.724702 -358.958488) (xy 49.688496 -358.945942) (xy 49.68018 -358.943356) (xy 49.662776 -358.943356)
			(xy 49.65446 -358.945942) (xy 49.618248 -358.958468) (xy 49.544147 -358.977989) (xy 49.468642 -358.991071)
			(xy 49.392293 -358.997619) (xy 49.353978 -358.998012) (xy 49.315661 -358.99765) (xy 49.239308 -358.991116)
			(xy 49.163801 -358.97803) (xy 49.089702 -358.958488) (xy 49.053496 -358.945942) (xy 49.04518 -358.943356)
			(xy 49.027776 -358.943356) (xy 49.01946 -358.945942) (xy 48.983339 -358.95844) (xy 48.909426 -358.977928)
			(xy 48.834115 -358.99101) (xy 48.757959 -358.99759) (xy 48.71974 -358.998012) (xy 48.718978 -358.998012)
			(xy 48.677876 -358.99753) (xy 48.596022 -358.989953) (xy 48.515216 -358.974857) (xy 48.436148 -358.95237)
			(xy 48.359491 -358.922685) (xy 48.322484 -358.904794) (xy 48.311662 -358.900089) (xy 48.288094 -358.900089)
			(xy 48.277272 -358.904794) (xy 48.240271 -358.922698) (xy 48.163612 -358.952379) (xy 48.084542 -358.974864)
			(xy 48.003735 -358.98996) (xy 47.92188 -358.997539) (xy 47.880778 -358.998012) (xy 47.839669 -358.997608)
			(xy 47.757803 -358.990022) (xy 47.676986 -358.974915) (xy 47.597907 -358.952416) (xy 47.52124 -358.922719)
			(xy 47.447641 -358.886075) (xy 47.377735 -358.842798) (xy 47.312121 -358.793256) (xy 47.251356 -358.737873)
			(xy 47.19596 -358.677119) (xy 47.146405 -358.611515) (xy 47.103114 -358.541618) (xy 47.066455 -358.468026)
			(xy 47.036742 -358.391366) (xy 47.014227 -358.312292) (xy 46.999104 -358.231477) (xy 46.9915 -358.149612)
			(xy 46.991016 -358.108504) (xy 44.837736 -358.108504) (xy 44.834097 -358.122388) (xy 44.808571 -358.1941)
			(xy 44.793154 -358.2289) (xy 44.789778 -358.237249) (xy 44.788481 -358.255202) (xy 44.790614 -358.263952)
			(xy 44.801704 -358.304153) (xy 44.817195 -358.386101) (xy 44.82495 -358.46914) (xy 44.825412 -358.51084)
			(xy 44.824852 -358.556303) (xy 44.815599 -358.646758) (xy 44.797171 -358.735798) (xy 44.78401 -358.779318)
			(xy 44.78146 -358.788893) (xy 44.783017 -358.808626) (xy 44.787058 -358.817672) (xy 44.805431 -358.855048)
			(xy 44.835897 -358.932566) (xy 44.858991 -359.012591) (xy 44.87451 -359.094423) (xy 44.882318 -359.177347)
			(xy 44.882816 -359.218992) (xy 44.882816 -359.219246) (xy 44.882312 -359.261594) (xy 44.874261 -359.345908)
			(xy 44.858232 -359.429074) (xy 44.834371 -359.510341) (xy 44.802892 -359.588971) (xy 44.764081 -359.664252)
			(xy 44.718291 -359.735504) (xy 44.665935 -359.80208) (xy 44.607487 -359.863378) (xy 44.543477 -359.918843)
			(xy 44.474485 -359.967972) (xy 44.401135 -360.010321) (xy 44.324092 -360.045505) (xy 44.244053 -360.073207)
			(xy 44.161744 -360.093175) (xy 44.077909 -360.105228) (xy 43.993308 -360.109259) (xy 43.908707 -360.105228)
			(xy 43.824872 -360.093175) (xy 43.742563 -360.073207) (xy 43.662524 -360.045505) (xy 43.585481 -360.010321)
			(xy 43.512131 -359.967972) (xy 43.443139 -359.918843) (xy 43.379129 -359.863378) (xy 43.320681 -359.80208)
			(xy 43.268325 -359.735504) (xy 43.222535 -359.664252) (xy 43.183724 -359.588971) (xy 43.152245 -359.510341)
			(xy 43.128384 -359.429074) (xy 43.112355 -359.345908) (xy 43.104304 -359.261594) (xy 43.1038 -359.219246)
			(xy 43.104356 -359.173782) (xy 43.113611 -359.083328) (xy 43.13204 -358.994288) (xy 43.145202 -358.950768)
			(xy 43.147759 -358.941194) (xy 43.146197 -358.921461) (xy 43.142154 -358.912414) (xy 43.123767 -358.875016)
			(xy 43.093286 -358.797449) (xy 43.070189 -358.717372) (xy 43.054676 -358.635487) (xy 43.046883 -358.552511)
			(xy 43.046396 -358.51084) (xy 42.259032 -358.51084) (xy 42.259504 -358.549194) (xy 42.258889 -358.594663)
			(xy 42.249552 -358.685121) (xy 42.231047 -358.774157) (xy 42.217848 -358.817672) (xy 42.215273 -358.827242)
			(xy 42.216849 -358.846979) (xy 42.220896 -358.856026) (xy 42.239309 -358.893418) (xy 42.269845 -358.970977)
			(xy 42.292996 -359.051051) (xy 42.308559 -359.132939) (xy 42.316398 -359.215923) (xy 42.316908 -359.2576)
			(xy 42.316404 -359.299961) (xy 42.308351 -359.384298) (xy 42.292317 -359.467488) (xy 42.268449 -359.548778)
			(xy 42.236961 -359.62743) (xy 42.198139 -359.702733) (xy 42.152336 -359.774005) (xy 42.099965 -359.840601)
			(xy 42.0415 -359.901916) (xy 41.977472 -359.957397) (xy 41.90846 -360.00654) (xy 41.83509 -360.0489)
			(xy 41.758025 -360.084095) (xy 41.677963 -360.111804) (xy 41.59563 -360.131778) (xy 41.511771 -360.143835)
			(xy 41.427146 -360.147867) (xy 41.342521 -360.143835) (xy 41.258662 -360.131778) (xy 41.176329 -360.111804)
			(xy 41.096267 -360.084095) (xy 41.019202 -360.0489) (xy 40.945832 -360.00654) (xy 40.87682 -359.957397)
			(xy 40.812792 -359.901916) (xy 40.754327 -359.840601) (xy 40.701956 -359.774005) (xy 40.656153 -359.702733)
			(xy 40.617331 -359.62743) (xy 40.585843 -359.548778) (xy 40.561975 -359.467488) (xy 40.545941 -359.384298)
			(xy 40.537888 -359.299961) (xy 40.537384 -359.2576) (xy 40.537998 -359.212131) (xy 40.547335 -359.121673)
			(xy 40.565841 -359.032637) (xy 40.57904 -358.989122) (xy 40.581619 -358.979553) (xy 40.580041 -358.959815)
			(xy 40.575992 -358.950768) (xy 40.557613 -358.91336) (xy 40.527071 -358.835806) (xy 40.503913 -358.755736)
			(xy 40.488342 -358.673851) (xy 40.480494 -358.59087) (xy 40.47998 -358.549194) (xy 15.414336 -358.549194)
			(xy 15.373293 -358.597004) (xy 15.317311 -358.650219) (xy 15.256232 -358.697498) (xy 15.190684 -358.738354)
			(xy 15.121338 -358.77237) (xy 15.048907 -358.799195) (xy 14.974134 -358.818555) (xy 14.897786 -358.830251)
			(xy 14.820646 -358.834164) (xy 14.743506 -358.830251) (xy 14.667158 -358.818555) (xy 14.592385 -358.799195)
			(xy 14.519954 -358.77237) (xy 14.450608 -358.738354) (xy 14.38506 -358.697498) (xy 14.323981 -358.650219)
			(xy 14.267999 -358.597004) (xy 14.217688 -358.538398) (xy 14.173564 -358.475004) (xy 14.136079 -358.40747)
			(xy 14.10562 -358.336491) (xy 14.082497 -358.262794) (xy 14.066949 -358.187136) (xy 14.059135 -358.110293)
			(xy 14.058646 -358.071674) (xy 3.523996 -358.071674) (xy 3.523996 -361.825848) (xy 5.986007 -361.825848)
			(xy 5.986007 -361.696708) (xy 5.993957 -361.567813) (xy 6.009827 -361.439653) (xy 6.033556 -361.312712)
			(xy 6.065055 -361.187473) (xy 6.104204 -361.06441) (xy 6.150855 -360.943991) (xy 6.20483 -360.826672)
			(xy 6.265925 -360.712898) (xy 6.333908 -360.603101) (xy 6.408522 -360.497698) (xy 6.489483 -360.397088)
			(xy 6.576483 -360.301653) (xy 6.669194 -360.211754) (xy 6.767264 -360.127733) (xy 6.870319 -360.049909)
			(xy 6.97797 -359.978577) (xy 7.089809 -359.914007) (xy 7.20541 -359.856445) (xy 7.324335 -359.806108)
			(xy 7.446134 -359.763188) (xy 7.570344 -359.727847) (xy 7.696493 -359.70022) (xy 7.824105 -359.680411)
			(xy 7.952694 -359.668495) (xy 8.081772 -359.664519) (xy 8.21085 -359.668495) (xy 8.339439 -359.680411)
			(xy 8.467051 -359.70022) (xy 8.5932 -359.727847) (xy 8.71741 -359.763188) (xy 8.839209 -359.806108)
			(xy 8.958134 -359.856445) (xy 9.073735 -359.914007) (xy 9.185574 -359.978577) (xy 9.293225 -360.049909)
			(xy 9.39628 -360.127733) (xy 9.49435 -360.211754) (xy 9.587061 -360.301653) (xy 9.674061 -360.397088)
			(xy 9.689764 -360.416602) (xy 12.16152 -360.416602) (xy 12.162106 -360.37391) (xy 12.17165 -360.289062)
			(xy 12.190606 -360.205809) (xy 12.218739 -360.125194) (xy 12.255695 -360.048223) (xy 12.277852 -360.011726)
			(xy 12.282563 -360.003469) (xy 12.286088 -359.984802) (xy 12.282564 -359.966135) (xy 12.277852 -359.957878)
			(xy 12.25566 -359.9214) (xy 12.218681 -359.844434) (xy 12.190544 -359.763815) (xy 12.171603 -359.680554)
			(xy 12.162095 -359.595696) (xy 12.16152 -359.553002) (xy 12.162009 -359.514383) (xy 12.169823 -359.43754)
			(xy 12.185371 -359.361882) (xy 12.208494 -359.288185) (xy 12.238953 -359.217206) (xy 12.276438 -359.149672)
			(xy 12.320562 -359.086278) (xy 12.370873 -359.027672) (xy 12.426855 -358.974457) (xy 12.487934 -358.927178)
			(xy 12.553482 -358.886322) (xy 12.622828 -358.852306) (xy 12.695259 -358.825481) (xy 12.770032 -358.806121)
			(xy 12.84638 -358.794425) (xy 12.92352 -358.790513) (xy 13.00066 -358.794425) (xy 13.077008 -358.806121)
			(xy 13.151781 -358.825481) (xy 13.224212 -358.852306) (xy 13.293558 -358.886322) (xy 13.359106 -358.927178)
			(xy 13.420185 -358.974457) (xy 13.476167 -359.027672) (xy 13.526478 -359.086278) (xy 13.570602 -359.149672)
			(xy 13.608087 -359.217206) (xy 13.638546 -359.288185) (xy 13.661669 -359.361882) (xy 13.677217 -359.43754)
			(xy 13.685031 -359.514383) (xy 13.68552 -359.553002) (xy 13.68493 -359.595693) (xy 13.675386 -359.680542)
			(xy 13.65643 -359.763794) (xy 13.628299 -359.84441) (xy 13.591344 -359.921381) (xy 13.569188 -359.957878)
			(xy 13.564471 -359.966133) (xy 13.560944 -359.984802) (xy 13.564473 -360.00347) (xy 13.569188 -360.011726)
			(xy 13.591375 -360.048207) (xy 13.628356 -360.125171) (xy 13.656495 -360.20579) (xy 13.675437 -360.289051)
			(xy 13.684946 -360.373908) (xy 13.68552 -360.416602) (xy 13.685031 -360.455221) (xy 13.677217 -360.532064)
			(xy 13.661669 -360.607722) (xy 13.638546 -360.681419) (xy 13.608087 -360.752398) (xy 13.570602 -360.819932)
			(xy 13.526478 -360.883326) (xy 13.476167 -360.941932) (xy 13.420185 -360.995147) (xy 13.408614 -361.004104)
			(xy 165.274244 -361.004104) (xy 165.274705 -360.976833) (xy 165.282467 -360.922846) (xy 165.297833 -360.870512)
			(xy 165.320491 -360.820899) (xy 165.349978 -360.775015) (xy 165.385696 -360.733795) (xy 165.426917 -360.698077)
			(xy 165.472801 -360.66859) (xy 165.522414 -360.645932) (xy 165.574748 -360.630567) (xy 165.628735 -360.622805)
			(xy 165.656006 -360.622342) (xy 165.684126 -360.622865) (xy 165.73976 -360.631099) (xy 165.793585 -360.647402)
			(xy 165.844437 -360.671422) (xy 165.891217 -360.702641) (xy 165.932913 -360.740382) (xy 165.951154 -360.761788)
			(xy 165.958392 -360.769809) (xy 165.977727 -360.779407) (xy 165.988492 -360.78033) (xy 166.02007 -360.775345)
			(xy 166.083779 -360.77) (xy 166.115746 -360.769662) (xy 166.155707 -360.770163) (xy 166.23519 -360.778522)
			(xy 166.313364 -360.795142) (xy 166.389373 -360.819842) (xy 166.462383 -360.852352) (xy 166.531596 -360.892315)
			(xy 166.596253 -360.939293) (xy 166.655645 -360.992772) (xy 166.709122 -361.052166) (xy 166.756098 -361.116824)
			(xy 166.796059 -361.186038) (xy 166.828566 -361.25905) (xy 166.853264 -361.335059) (xy 166.869882 -361.413234)
			(xy 166.878238 -361.492717) (xy 166.878762 -361.532678) (xy 166.87832 -361.568975) (xy 166.871429 -361.641242)
			(xy 166.857707 -361.712528) (xy 166.837279 -361.782189) (xy 166.810328 -361.849596) (xy 166.777099 -361.914139)
			(xy 166.757858 -361.94492) (xy 166.754213 -361.956147) (xy 166.756619 -361.979602) (xy 166.76243 -361.989878)
			(xy 166.784742 -362.026484) (xy 166.821943 -362.103722) (xy 166.850262 -362.184641) (xy 166.861755 -362.234988)
			(xy 185.144664 -362.234988) (xy 185.144664 -362.23448) (xy 185.145268 -362.188148) (xy 185.154941 -362.09599)
			(xy 185.174137 -362.005336) (xy 185.202649 -361.917167) (xy 185.220864 -361.874562) (xy 185.224678 -361.864622)
			(xy 185.224673 -361.843356) (xy 185.220864 -361.833414) (xy 185.202614 -361.790754) (xy 185.174071 -361.702461)
			(xy 185.15488 -361.611675) (xy 185.145248 -361.519384) (xy 185.144664 -361.472988) (xy 185.145245 -361.426592)
			(xy 185.154891 -361.334304) (xy 185.174088 -361.24352) (xy 185.202626 -361.155227) (xy 185.220864 -361.112562)
			(xy 185.224678 -361.102622) (xy 185.224673 -361.081356) (xy 185.220864 -361.071414) (xy 185.202636 -361.028813)
			(xy 185.17412 -360.940645) (xy 185.154929 -360.849989) (xy 185.145271 -360.757828) (xy 185.144664 -360.711496)
			(xy 185.144664 -360.710988) (xy 185.145155 -360.669886) (xy 185.152741 -360.588033) (xy 185.167846 -360.507229)
			(xy 185.190343 -360.428164) (xy 185.220039 -360.351511) (xy 185.25668 -360.277925) (xy 185.299955 -360.208034)
			(xy 185.349493 -360.142434) (xy 185.404873 -360.081684) (xy 185.465622 -360.026303) (xy 185.531221 -359.976764)
			(xy 185.601111 -359.933488) (xy 185.674696 -359.896845) (xy 185.751348 -359.867148) (xy 185.830414 -359.84465)
			(xy 185.911217 -359.829543) (xy 185.99307 -359.821956) (xy 186.034172 -359.82148) (xy 186.03468 -359.82148)
			(xy 186.081011 -359.822097) (xy 186.173169 -359.831765) (xy 186.263823 -359.850958) (xy 186.351992 -359.879466)
			(xy 186.394598 -359.89768) (xy 186.40454 -359.901486) (xy 186.425804 -359.901486) (xy 186.435746 -359.89768)
			(xy 186.478352 -359.879466) (xy 186.566519 -359.850947) (xy 186.657173 -359.831752) (xy 186.749332 -359.822089)
			(xy 186.795664 -359.82148) (xy 186.796172 -359.82148) (xy 186.837274 -359.821979) (xy 186.919129 -359.829561)
			(xy 186.999934 -359.844664) (xy 187.079001 -359.867158) (xy 187.155656 -359.896852) (xy 187.229243 -359.933492)
			(xy 187.299136 -359.976765) (xy 187.364738 -360.026303) (xy 187.425489 -360.081682) (xy 187.480872 -360.142431)
			(xy 187.530412 -360.208031) (xy 187.573689 -360.277922) (xy 187.610332 -360.351508) (xy 187.640029 -360.428161)
			(xy 187.662527 -360.507227) (xy 187.677633 -360.588032) (xy 187.685219 -360.669886) (xy 187.68568 -360.710988)
			(xy 187.68568 -360.711496) (xy 187.685072 -360.757828) (xy 187.675402 -360.849986) (xy 187.673919 -360.856991)
			(xy 209.35746 -360.856991) (xy 209.35746 -360.671157) (xy 209.365455 -360.485494) (xy 209.38143 -360.300348)
			(xy 209.405356 -360.11606) (xy 209.437188 -359.932972) (xy 209.476868 -359.751423) (xy 209.524321 -359.571749)
			(xy 209.579461 -359.394283) (xy 209.642184 -359.219354) (xy 209.712375 -359.047285) (xy 209.789904 -358.878396)
			(xy 209.874627 -358.712998) (xy 209.966388 -358.551398) (xy 210.065016 -358.393896) (xy 210.170329 -358.240782)
			(xy 210.282131 -358.092342) (xy 210.400216 -357.948848) (xy 210.524366 -357.810568) (xy 210.654349 -357.677757)
			(xy 210.789926 -357.550661) (xy 210.930846 -357.429516) (xy 211.076846 -357.314545) (xy 211.227658 -357.205962)
			(xy 211.383002 -357.103969) (xy 211.54259 -357.008752) (xy 211.706127 -356.92049) (xy 211.873309 -356.839345)
			(xy 212.043828 -356.765468) (xy 212.217367 -356.698995) (xy 212.393606 -356.64005) (xy 212.572217 -356.588742)
			(xy 212.75287 -356.545165) (xy 212.935231 -356.509401) (xy 213.118961 -356.481515) (xy 213.303721 -356.46156)
			(xy 213.489168 -356.449572) (xy 213.67496 -356.445574) (xy 213.860752 -356.449572) (xy 214.046199 -356.46156)
			(xy 214.230959 -356.481515) (xy 214.414689 -356.509401) (xy 214.59705 -356.545165) (xy 214.777703 -356.588742)
			(xy 214.956314 -356.64005) (xy 215.132553 -356.698995) (xy 215.306092 -356.765468) (xy 215.476611 -356.839345)
			(xy 215.643793 -356.92049) (xy 215.80733 -357.008752) (xy 215.966918 -357.103969) (xy 216.122262 -357.205962)
			(xy 216.273074 -357.314545) (xy 216.419074 -357.429516) (xy 216.559994 -357.550661) (xy 216.695571 -357.677757)
			(xy 216.825554 -357.810568) (xy 216.949704 -357.948848) (xy 217.067789 -358.092342) (xy 217.179591 -358.240782)
			(xy 217.284904 -358.393896) (xy 217.383532 -358.551398) (xy 217.475293 -358.712998) (xy 217.560016 -358.878396)
			(xy 217.637545 -359.047285) (xy 217.707736 -359.219354) (xy 217.770459 -359.394283) (xy 217.825599 -359.571749)
			(xy 217.873052 -359.751423) (xy 217.912732 -359.932972) (xy 217.944564 -360.11606) (xy 217.96849 -360.300348)
			(xy 217.984465 -360.485494) (xy 217.99246 -360.671157) (xy 217.99296 -360.764074) (xy 217.99246 -360.856991)
			(xy 253.80746 -360.856991) (xy 253.80746 -360.671157) (xy 253.815455 -360.485494) (xy 253.83143 -360.300348)
			(xy 253.855356 -360.11606) (xy 253.887188 -359.932972) (xy 253.926868 -359.751423) (xy 253.974321 -359.571749)
			(xy 254.029461 -359.394283) (xy 254.092184 -359.219354) (xy 254.162375 -359.047285) (xy 254.239904 -358.878396)
			(xy 254.324627 -358.712998) (xy 254.416388 -358.551398) (xy 254.515016 -358.393896) (xy 254.620329 -358.240782)
			(xy 254.732131 -358.092342) (xy 254.850216 -357.948848) (xy 254.974366 -357.810568) (xy 255.104349 -357.677757)
			(xy 255.239926 -357.550661) (xy 255.380846 -357.429516) (xy 255.526846 -357.314545) (xy 255.677658 -357.205962)
			(xy 255.833002 -357.103969) (xy 255.99259 -357.008752) (xy 256.156127 -356.92049) (xy 256.323309 -356.839345)
			(xy 256.493828 -356.765468) (xy 256.667367 -356.698995) (xy 256.843606 -356.64005) (xy 257.022217 -356.588742)
			(xy 257.20287 -356.545165) (xy 257.385231 -356.509401) (xy 257.568961 -356.481515) (xy 257.753721 -356.46156)
			(xy 257.939168 -356.449572) (xy 258.12496 -356.445574) (xy 258.310752 -356.449572) (xy 258.496199 -356.46156)
			(xy 258.680959 -356.481515) (xy 258.864689 -356.509401) (xy 259.04705 -356.545165) (xy 259.227703 -356.588742)
			(xy 259.406314 -356.64005) (xy 259.582553 -356.698995) (xy 259.756092 -356.765468) (xy 259.926611 -356.839345)
			(xy 260.093793 -356.92049) (xy 260.25733 -357.008752) (xy 260.416918 -357.103969) (xy 260.572262 -357.205962)
			(xy 260.723074 -357.314545) (xy 260.869074 -357.429516) (xy 261.009994 -357.550661) (xy 261.145571 -357.677757)
			(xy 261.275554 -357.810568) (xy 261.399704 -357.948848) (xy 261.517789 -358.092342) (xy 261.629591 -358.240782)
			(xy 261.734904 -358.393896) (xy 261.833532 -358.551398) (xy 261.925293 -358.712998) (xy 261.95432 -358.769666)
			(xy 294.901627 -358.769666) (xy 294.905632 -358.663917) (xy 294.917622 -358.558774) (xy 294.937531 -358.454839)
			(xy 294.965242 -358.352707) (xy 295.000599 -358.252963) (xy 295.043397 -358.156179) (xy 295.093393 -358.062909)
			(xy 295.1503 -357.973688) (xy 295.213791 -357.889025) (xy 295.283503 -357.809407) (xy 295.359037 -357.735289)
			(xy 295.43996 -357.667096) (xy 295.525809 -357.605218) (xy 295.616092 -357.550011) (xy 295.710291 -357.501789)
			(xy 295.807868 -357.460829) (xy 295.908263 -357.427367) (xy 296.010901 -357.401593) (xy 296.115194 -357.383655)
			(xy 296.220545 -357.373656) (xy 296.326351 -357.371653) (xy 296.432005 -357.377658) (xy 296.536902 -357.391637)
			(xy 296.640442 -357.413508) (xy 296.742031 -357.443148) (xy 296.841088 -357.480386) (xy 296.937045 -357.525008)
			(xy 297.029352 -357.57676) (xy 297.117481 -357.635345) (xy 297.200927 -357.700427) (xy 297.279211 -357.771633)
			(xy 297.351886 -357.848556) (xy 297.418536 -357.930756) (xy 297.478778 -358.01776) (xy 297.532267 -358.109071)
			(xy 297.578698 -358.204166) (xy 297.617803 -358.3025) (xy 297.64936 -358.403511) (xy 297.673187 -358.506618)
			(xy 297.689148 -358.611232) (xy 297.697152 -358.716754) (xy 297.697652 -358.769666) (xy 297.697152 -358.822578)
			(xy 297.689148 -358.9281) (xy 297.673187 -359.032714) (xy 297.64936 -359.135821) (xy 297.617803 -359.236832)
			(xy 297.578698 -359.335166) (xy 297.532267 -359.430261) (xy 297.478778 -359.521572) (xy 297.418536 -359.608576)
			(xy 297.351886 -359.690776) (xy 297.279211 -359.767699) (xy 297.200927 -359.838905) (xy 297.117481 -359.903987)
			(xy 297.029352 -359.962572) (xy 296.937045 -360.014324) (xy 296.841088 -360.058946) (xy 296.742031 -360.096184)
			(xy 296.640442 -360.125824) (xy 296.536902 -360.147695) (xy 296.432005 -360.161674) (xy 296.326351 -360.167679)
			(xy 296.220545 -360.165676) (xy 296.115194 -360.155677) (xy 296.010901 -360.137739) (xy 295.908263 -360.111965)
			(xy 295.807868 -360.078503) (xy 295.710291 -360.037543) (xy 295.616092 -359.989321) (xy 295.525809 -359.934114)
			(xy 295.43996 -359.872236) (xy 295.359037 -359.804043) (xy 295.283503 -359.729925) (xy 295.213791 -359.650307)
			(xy 295.1503 -359.565644) (xy 295.093393 -359.476423) (xy 295.043397 -359.383153) (xy 295.000599 -359.286369)
			(xy 294.965242 -359.186625) (xy 294.937531 -359.084493) (xy 294.917622 -358.980558) (xy 294.905632 -358.875415)
			(xy 294.901627 -358.769666) (xy 261.95432 -358.769666) (xy 262.010016 -358.878396) (xy 262.087545 -359.047285)
			(xy 262.157736 -359.219354) (xy 262.220459 -359.394283) (xy 262.275599 -359.571749) (xy 262.323052 -359.751423)
			(xy 262.362732 -359.932972) (xy 262.394564 -360.11606) (xy 262.41849 -360.300348) (xy 262.434465 -360.485494)
			(xy 262.44246 -360.671157) (xy 262.44296 -360.764074) (xy 262.44246 -360.856991) (xy 262.434465 -361.042654)
			(xy 262.41849 -361.2278) (xy 262.394564 -361.412088) (xy 262.362732 -361.595176) (xy 262.323052 -361.776725)
			(xy 262.309556 -361.827826) (xy 430.615097 -361.827826) (xy 430.619102 -361.722077) (xy 430.631092 -361.616934)
			(xy 430.651001 -361.512999) (xy 430.678712 -361.410867) (xy 430.714069 -361.311123) (xy 430.756867 -361.214339)
			(xy 430.806863 -361.121069) (xy 430.86377 -361.031848) (xy 430.927261 -360.947185) (xy 430.996973 -360.867567)
			(xy 431.072507 -360.793449) (xy 431.15343 -360.725256) (xy 431.239279 -360.663378) (xy 431.329562 -360.608171)
			(xy 431.423761 -360.559949) (xy 431.521338 -360.518989) (xy 431.621733 -360.485527) (xy 431.724371 -360.459753)
			(xy 431.828664 -360.441815) (xy 431.934015 -360.431816) (xy 432.039821 -360.429813) (xy 432.145475 -360.435818)
			(xy 432.250372 -360.449797) (xy 432.353912 -360.471668) (xy 432.455501 -360.501308) (xy 432.554558 -360.538546)
			(xy 432.650515 -360.583168) (xy 432.742822 -360.63492) (xy 432.830951 -360.693505) (xy 432.914397 -360.758587)
			(xy 432.992681 -360.829793) (xy 433.065356 -360.906716) (xy 433.132006 -360.988916) (xy 433.192248 -361.07592)
			(xy 433.245737 -361.167231) (xy 433.292168 -361.262326) (xy 433.331273 -361.36066) (xy 433.36283 -361.461671)
			(xy 433.370787 -361.496102) (xy 434.579776 -361.496102) (xy 434.580404 -361.4497) (xy 434.590093 -361.357403)
			(xy 434.609347 -361.266617) (xy 434.637954 -361.178332) (xy 434.65623 -361.135676) (xy 434.660038 -361.125734)
			(xy 434.660039 -361.10447) (xy 434.65623 -361.094528) (xy 434.637968 -361.051867) (xy 434.609375 -360.963579)
			(xy 434.590118 -360.872796) (xy 434.580405 -360.780503) (xy 434.579776 -360.734102) (xy 434.580404 -360.6877)
			(xy 434.590093 -360.595403) (xy 434.609347 -360.504617) (xy 434.637954 -360.416332) (xy 434.65623 -360.373676)
			(xy 434.660038 -360.363734) (xy 434.660039 -360.34247) (xy 434.65623 -360.332528) (xy 434.637968 -360.289867)
			(xy 434.609375 -360.201579) (xy 434.590118 -360.110796) (xy 434.580405 -360.018503) (xy 434.579776 -359.972102)
			(xy 434.5802 -359.930986) (xy 434.587788 -359.849105) (xy 434.602898 -359.768273) (xy 434.625402 -359.68918)
			(xy 434.655109 -359.612502) (xy 434.691763 -359.538891) (xy 434.735054 -359.468977) (xy 434.784611 -359.403355)
			(xy 434.840011 -359.342586) (xy 434.900783 -359.287188) (xy 434.966406 -359.237634) (xy 435.036323 -359.194346)
			(xy 435.109935 -359.157694) (xy 435.186615 -359.127991) (xy 435.265708 -359.10549) (xy 435.346541 -359.090383)
			(xy 435.428422 -359.082799) (xy 435.469538 -359.08234) (xy 435.51594 -359.082957) (xy 435.608238 -359.09265)
			(xy 435.699023 -359.111907) (xy 435.787308 -359.140517) (xy 435.829964 -359.158794) (xy 435.839906 -359.1626)
			(xy 435.86117 -359.1626) (xy 435.871112 -359.158794) (xy 435.913767 -359.140517) (xy 436.002057 -359.111928)
			(xy 436.092842 -359.092675) (xy 436.185137 -359.082967) (xy 436.231538 -359.08234) (xy 436.272653 -359.082777)
			(xy 436.354532 -359.090367) (xy 436.435361 -359.10548) (xy 436.514451 -359.127986) (xy 436.591127 -359.157693)
			(xy 436.664735 -359.194349) (xy 436.734647 -359.237639) (xy 436.800266 -359.287195) (xy 436.861034 -359.342595)
			(xy 436.91643 -359.403364) (xy 436.965984 -359.468986) (xy 437.009271 -359.5389) (xy 437.045923 -359.61251)
			(xy 437.075627 -359.689187) (xy 437.098129 -359.768278) (xy 437.113238 -359.849108) (xy 437.120825 -359.930987)
			(xy 437.1213 -359.972102) (xy 437.120676 -360.018504) (xy 437.110985 -360.110802) (xy 437.091731 -360.201587)
			(xy 437.063122 -360.289872) (xy 437.044846 -360.332528) (xy 437.041037 -360.34247) (xy 437.041038 -360.363734)
			(xy 437.044846 -360.373676) (xy 437.063108 -360.416337) (xy 437.091701 -360.504625) (xy 437.110959 -360.595408)
			(xy 437.120671 -360.687701) (xy 437.1213 -360.734102) (xy 437.120676 -360.780504) (xy 437.110985 -360.872802)
			(xy 437.091731 -360.963587) (xy 437.063122 -361.051872) (xy 437.044846 -361.094528) (xy 437.041037 -361.10447)
			(xy 437.041038 -361.125734) (xy 437.044846 -361.135676) (xy 437.063108 -361.178337) (xy 437.091701 -361.266625)
			(xy 437.110959 -361.357408) (xy 437.120671 -361.449701) (xy 437.1213 -361.496102) (xy 437.120789 -361.537215)
			(xy 437.113202 -361.619091) (xy 437.098093 -361.699917) (xy 437.075592 -361.779004) (xy 437.045889 -361.855678)
			(xy 437.009238 -361.929285) (xy 436.965952 -361.999196) (xy 436.916401 -362.064814) (xy 436.861007 -362.125581)
			(xy 436.800242 -362.180978) (xy 436.734625 -362.230532) (xy 436.664716 -362.273821) (xy 436.591111 -362.310474)
			(xy 436.514439 -362.34018) (xy 436.435352 -362.362685) (xy 436.354526 -362.377797) (xy 436.272651 -362.385387)
			(xy 436.231538 -362.385864) (xy 436.185135 -362.385256) (xy 436.092838 -362.37556) (xy 436.002052 -362.356301)
			(xy 435.913768 -362.327688) (xy 435.871112 -362.30941) (xy 435.86117 -362.305604) (xy 435.839906 -362.305604)
			(xy 435.829964 -362.30941) (xy 435.787299 -362.327662) (xy 435.699012 -362.356257) (xy 435.608231 -362.375517)
			(xy 435.515939 -362.385233) (xy 435.469538 -362.385864) (xy 435.428424 -362.385365) (xy 435.346546 -362.377782)
			(xy 435.265717 -362.362675) (xy 435.186627 -362.340175) (xy 435.10995 -362.310473) (xy 435.036341 -362.273823)
			(xy 434.966428 -362.230538) (xy 434.900807 -362.180986) (xy 434.840038 -362.12559) (xy 434.78464 -362.064824)
			(xy 434.735085 -361.999205) (xy 434.691796 -361.929294) (xy 434.655143 -361.855686) (xy 434.625438 -361.779011)
			(xy 434.602934 -361.699922) (xy 434.587824 -361.619094) (xy 434.580237 -361.537216) (xy 434.579776 -361.496102)
			(xy 433.370787 -361.496102) (xy 433.386657 -361.564778) (xy 433.402618 -361.669392) (xy 433.410622 -361.774914)
			(xy 433.411122 -361.827826) (xy 433.410622 -361.880738) (xy 433.402618 -361.98626) (xy 433.386657 -362.090874)
			(xy 433.36283 -362.193981) (xy 433.331273 -362.294992) (xy 433.292168 -362.393326) (xy 433.245737 -362.488421)
			(xy 433.192248 -362.579732) (xy 433.132006 -362.666736) (xy 433.065356 -362.748936) (xy 432.992681 -362.825859)
			(xy 432.914397 -362.897065) (xy 432.830951 -362.962147) (xy 432.742822 -363.020732) (xy 432.650515 -363.072484)
			(xy 432.554558 -363.117106) (xy 432.455501 -363.154344) (xy 432.353912 -363.183984) (xy 432.250372 -363.205855)
			(xy 432.145475 -363.219834) (xy 432.039821 -363.225839) (xy 431.934015 -363.223836) (xy 431.828664 -363.213837)
			(xy 431.724371 -363.195899) (xy 431.621733 -363.170125) (xy 431.521338 -363.136663) (xy 431.423761 -363.095703)
			(xy 431.329562 -363.047481) (xy 431.239279 -362.992274) (xy 431.15343 -362.930396) (xy 431.072507 -362.862203)
			(xy 430.996973 -362.788085) (xy 430.927261 -362.708467) (xy 430.86377 -362.623804) (xy 430.806863 -362.534583)
			(xy 430.756867 -362.441313) (xy 430.714069 -362.344529) (xy 430.678712 -362.244785) (xy 430.651001 -362.142653)
			(xy 430.631092 -362.038718) (xy 430.619102 -361.933575) (xy 430.615097 -361.827826) (xy 262.309556 -361.827826)
			(xy 262.275599 -361.956399) (xy 262.220459 -362.133865) (xy 262.157736 -362.308794) (xy 262.087545 -362.480863)
			(xy 262.010016 -362.649752) (xy 261.925293 -362.81515) (xy 261.833532 -362.97675) (xy 261.734904 -363.134252)
			(xy 261.629591 -363.287366) (xy 261.517789 -363.435806) (xy 261.399704 -363.5793) (xy 261.275554 -363.71758)
			(xy 261.145571 -363.850391) (xy 261.009994 -363.977487) (xy 260.869074 -364.098632) (xy 260.723074 -364.213603)
			(xy 260.572262 -364.322186) (xy 260.416918 -364.424179) (xy 260.25733 -364.519396) (xy 260.093793 -364.607658)
			(xy 259.926611 -364.688803) (xy 259.756092 -364.76268) (xy 259.582553 -364.829153) (xy 259.406314 -364.888098)
			(xy 259.227703 -364.939406) (xy 259.04705 -364.982983) (xy 258.864689 -365.018747) (xy 258.680959 -365.046633)
			(xy 258.496199 -365.066588) (xy 258.310752 -365.078576) (xy 258.12496 -365.082574) (xy 257.939168 -365.078576)
			(xy 257.753721 -365.066588) (xy 257.568961 -365.046633) (xy 257.385231 -365.018747) (xy 257.20287 -364.982983)
			(xy 257.022217 -364.939406) (xy 256.843606 -364.888098) (xy 256.667367 -364.829153) (xy 256.493828 -364.76268)
			(xy 256.323309 -364.688803) (xy 256.156127 -364.607658) (xy 255.99259 -364.519396) (xy 255.833002 -364.424179)
			(xy 255.677658 -364.322186) (xy 255.526846 -364.213603) (xy 255.380846 -364.098632) (xy 255.239926 -363.977487)
			(xy 255.104349 -363.850391) (xy 254.974366 -363.71758) (xy 254.850216 -363.5793) (xy 254.732131 -363.435806)
			(xy 254.620329 -363.287366) (xy 254.515016 -363.134252) (xy 254.416388 -362.97675) (xy 254.324627 -362.81515)
			(xy 254.239904 -362.649752) (xy 254.162375 -362.480863) (xy 254.092184 -362.308794) (xy 254.029461 -362.133865)
			(xy 253.974321 -361.956399) (xy 253.926868 -361.776725) (xy 253.887188 -361.595176) (xy 253.855356 -361.412088)
			(xy 253.83143 -361.2278) (xy 253.815455 -361.042654) (xy 253.80746 -360.856991) (xy 217.99246 -360.856991)
			(xy 217.984465 -361.042654) (xy 217.96849 -361.2278) (xy 217.944564 -361.412088) (xy 217.912732 -361.595176)
			(xy 217.873052 -361.776725) (xy 217.825599 -361.956399) (xy 217.770459 -362.133865) (xy 217.707736 -362.308794)
			(xy 217.637545 -362.480863) (xy 217.560016 -362.649752) (xy 217.475293 -362.81515) (xy 217.383532 -362.97675)
			(xy 217.284904 -363.134252) (xy 217.179591 -363.287366) (xy 217.067789 -363.435806) (xy 216.949704 -363.5793)
			(xy 216.825554 -363.71758) (xy 216.695571 -363.850391) (xy 216.559994 -363.977487) (xy 216.419074 -364.098632)
			(xy 216.273074 -364.213603) (xy 216.122262 -364.322186) (xy 215.966918 -364.424179) (xy 215.80733 -364.519396)
			(xy 215.643793 -364.607658) (xy 215.476611 -364.688803) (xy 215.306092 -364.76268) (xy 215.132553 -364.829153)
			(xy 214.956314 -364.888098) (xy 214.777703 -364.939406) (xy 214.59705 -364.982983) (xy 214.414689 -365.018747)
			(xy 214.230959 -365.046633) (xy 214.046199 -365.066588) (xy 213.860752 -365.078576) (xy 213.67496 -365.082574)
			(xy 213.489168 -365.078576) (xy 213.303721 -365.066588) (xy 213.118961 -365.046633) (xy 212.935231 -365.018747)
			(xy 212.75287 -364.982983) (xy 212.572217 -364.939406) (xy 212.393606 -364.888098) (xy 212.217367 -364.829153)
			(xy 212.043828 -364.76268) (xy 211.873309 -364.688803) (xy 211.706127 -364.607658) (xy 211.54259 -364.519396)
			(xy 211.383002 -364.424179) (xy 211.227658 -364.322186) (xy 211.076846 -364.213603) (xy 210.930846 -364.098632)
			(xy 210.789926 -363.977487) (xy 210.654349 -363.850391) (xy 210.524366 -363.71758) (xy 210.400216 -363.5793)
			(xy 210.282131 -363.435806) (xy 210.170329 -363.287366) (xy 210.065016 -363.134252) (xy 209.966388 -362.97675)
			(xy 209.874627 -362.81515) (xy 209.789904 -362.649752) (xy 209.712375 -362.480863) (xy 209.642184 -362.308794)
			(xy 209.579461 -362.133865) (xy 209.524321 -361.956399) (xy 209.476868 -361.776725) (xy 209.437188 -361.595176)
			(xy 209.405356 -361.412088) (xy 209.38143 -361.2278) (xy 209.365455 -361.042654) (xy 209.35746 -360.856991)
			(xy 187.673919 -360.856991) (xy 187.656207 -360.94064) (xy 187.627695 -361.028809) (xy 187.60948 -361.071414)
			(xy 187.605683 -361.081359) (xy 187.605679 -361.10262) (xy 187.60948 -361.112562) (xy 187.627719 -361.155227)
			(xy 187.656265 -361.243518) (xy 187.67546 -361.334302) (xy 187.685094 -361.426592) (xy 187.68568 -361.472988)
			(xy 187.685095 -361.519384) (xy 187.675451 -361.611672) (xy 187.656256 -361.702456) (xy 187.627718 -361.790749)
			(xy 187.60948 -361.833414) (xy 187.605683 -361.843359) (xy 187.605679 -361.86462) (xy 187.60948 -361.874562)
			(xy 187.627696 -361.917167) (xy 187.656216 -362.005334) (xy 187.67541 -362.095988) (xy 187.685071 -362.188148)
			(xy 187.68568 -362.23448) (xy 187.68568 -362.234988) (xy 187.685236 -362.276092) (xy 187.677652 -362.357949)
			(xy 187.664078 -362.430568) (xy 190.281567 -362.430568) (xy 190.285572 -362.324819) (xy 190.297562 -362.219676)
			(xy 190.317471 -362.115741) (xy 190.345182 -362.013609) (xy 190.380539 -361.913865) (xy 190.423337 -361.817081)
			(xy 190.473333 -361.723811) (xy 190.53024 -361.63459) (xy 190.593731 -361.549927) (xy 190.663443 -361.470309)
			(xy 190.738977 -361.396191) (xy 190.8199 -361.327998) (xy 190.905749 -361.26612) (xy 190.996032 -361.210913)
			(xy 191.090231 -361.162691) (xy 191.187808 -361.121731) (xy 191.288203 -361.088269) (xy 191.390841 -361.062495)
			(xy 191.495134 -361.044557) (xy 191.600485 -361.034558) (xy 191.706291 -361.032555) (xy 191.811945 -361.03856)
			(xy 191.916842 -361.052539) (xy 192.020382 -361.07441) (xy 192.121971 -361.10405) (xy 192.221028 -361.141288)
			(xy 192.316985 -361.18591) (xy 192.409292 -361.237662) (xy 192.497421 -361.296247) (xy 192.580867 -361.361329)
			(xy 192.659151 -361.432535) (xy 192.731826 -361.509458) (xy 192.798476 -361.591658) (xy 192.858718 -361.678662)
			(xy 192.912207 -361.769973) (xy 192.958638 -361.865068) (xy 192.997743 -361.963402) (xy 193.0293 -362.064413)
			(xy 193.053127 -362.16752) (xy 193.069088 -362.272134) (xy 193.077092 -362.377656) (xy 193.077592 -362.430568)
			(xy 193.077092 -362.48348) (xy 193.069088 -362.589002) (xy 193.053127 -362.693616) (xy 193.0293 -362.796723)
			(xy 192.997743 -362.897734) (xy 192.958638 -362.996068) (xy 192.912207 -363.091163) (xy 192.858718 -363.182474)
			(xy 192.798476 -363.269478) (xy 192.731826 -363.351678) (xy 192.659151 -363.428601) (xy 192.580867 -363.499807)
			(xy 192.497421 -363.564889) (xy 192.409292 -363.623474) (xy 192.316985 -363.675226) (xy 192.221028 -363.719848)
			(xy 192.121971 -363.757086) (xy 192.020382 -363.786726) (xy 191.916842 -363.808597) (xy 191.811945 -363.822576)
			(xy 191.706291 -363.828581) (xy 191.600485 -363.826578) (xy 191.495134 -363.816579) (xy 191.390841 -363.798641)
			(xy 191.288203 -363.772867) (xy 191.187808 -363.739405) (xy 191.090231 -363.698445) (xy 190.996032 -363.650223)
			(xy 190.905749 -363.595016) (xy 190.8199 -363.533138) (xy 190.738977 -363.464945) (xy 190.663443 -363.390827)
			(xy 190.593731 -363.311209) (xy 190.53024 -363.226546) (xy 190.473333 -363.137325) (xy 190.423337 -363.044055)
			(xy 190.380539 -362.947271) (xy 190.345182 -362.847527) (xy 190.317471 -362.745395) (xy 190.297562 -362.64146)
			(xy 190.285572 -362.536317) (xy 190.281567 -362.430568) (xy 187.664078 -362.430568) (xy 187.662547 -362.438757)
			(xy 187.64005 -362.517826) (xy 187.610354 -362.594483) (xy 187.573711 -362.668072) (xy 187.530434 -362.737966)
			(xy 187.480892 -362.803569) (xy 187.425509 -362.86432) (xy 187.364756 -362.919703) (xy 187.299153 -362.969243)
			(xy 187.229258 -363.012519) (xy 187.155668 -363.04916) (xy 187.079011 -363.078856) (xy 186.999941 -363.101351)
			(xy 186.919133 -363.116454) (xy 186.837276 -363.124037) (xy 186.796172 -363.124496) (xy 186.795664 -363.124496)
			(xy 186.749333 -363.123866) (xy 186.657176 -363.114202) (xy 186.566521 -363.095013) (xy 186.478352 -363.066508)
			(xy 186.435746 -363.048296) (xy 186.425804 -363.04449) (xy 186.40454 -363.04449) (xy 186.394598 -363.048296)
			(xy 186.351999 -363.066527) (xy 186.26383 -363.095042) (xy 186.173173 -363.114232) (xy 186.081013 -363.123889)
			(xy 186.03468 -363.124496) (xy 186.034172 -363.124496) (xy 185.993069 -363.12406) (xy 185.911213 -363.116473)
			(xy 185.830407 -363.101365) (xy 185.751339 -363.078866) (xy 185.674684 -363.049167) (xy 185.601097 -363.012522)
			(xy 185.531204 -362.969244) (xy 185.465603 -362.919702) (xy 185.404853 -362.864319) (xy 185.349472 -362.803566)
			(xy 185.299933 -362.737963) (xy 185.256658 -362.668068) (xy 185.220017 -362.594479) (xy 185.190322 -362.517823)
			(xy 185.167826 -362.438755) (xy 185.152722 -362.357947) (xy 185.145138 -362.276091) (xy 185.144664 -362.234988)
			(xy 166.861755 -362.234988) (xy 166.869342 -362.268221) (xy 166.878944 -362.353413) (xy 166.879524 -362.396278)
			(xy 166.879524 -362.396532) (xy 166.879105 -362.432139) (xy 166.87247 -362.503043) (xy 166.859253 -362.573019)
			(xy 166.849806 -362.607352) (xy 166.84764 -362.616108) (xy 166.848933 -362.634087) (xy 166.856407 -362.650491)
			(xy 166.862506 -362.657136) (xy 166.883163 -362.678752) (xy 166.918174 -362.727215) (xy 166.945209 -362.780541)
			(xy 166.963608 -362.837426) (xy 166.972924 -362.896483) (xy 166.973504 -362.926376) (xy 166.972953 -362.953643)
			(xy 166.965196 -363.007622) (xy 166.949836 -363.059948) (xy 166.927186 -363.109555) (xy 166.897706 -363.155434)
			(xy 166.861998 -363.196651) (xy 166.820787 -363.232366) (xy 166.774913 -363.261854) (xy 166.72531 -363.284513)
			(xy 166.672987 -363.299882) (xy 166.619009 -363.307649) (xy 166.591742 -363.308138) (xy 166.563429 -363.307673)
			(xy 166.507424 -363.2993) (xy 166.453275 -363.282732) (xy 166.402174 -363.258333) (xy 166.355246 -363.226642)
			(xy 166.313525 -363.188354) (xy 166.295324 -363.16666) (xy 166.289383 -363.159834) (xy 166.273827 -363.150609)
			(xy 166.25603 -363.147392) (xy 166.247064 -363.148626) (xy 166.214498 -363.153977) (xy 166.148746 -363.159698)
			(xy 166.115746 -363.160056) (xy 166.075745 -363.159529) (xy 165.99618 -363.151171) (xy 165.917925 -363.134541)
			(xy 165.841837 -363.109822) (xy 165.76875 -363.077285) (xy 165.699464 -363.037286) (xy 165.63474 -362.990263)
			(xy 165.575285 -362.936732) (xy 165.521752 -362.877279) (xy 165.474727 -362.812556) (xy 165.434726 -362.743272)
			(xy 165.402187 -362.670186) (xy 165.377465 -362.594098) (xy 165.360833 -362.515844) (xy 165.352472 -362.436279)
			(xy 165.351968 -362.396278) (xy 165.352527 -362.353412) (xy 165.36213 -362.268219) (xy 165.381213 -362.184637)
			(xy 165.409535 -362.103718) (xy 165.446741 -362.026479) (xy 165.469062 -361.989878) (xy 165.474834 -361.979597)
			(xy 165.477199 -361.95616) (xy 165.473634 -361.94492) (xy 165.45438 -361.914147) (xy 165.421151 -361.849602)
			(xy 165.3942 -361.782194) (xy 165.373772 -361.712532) (xy 165.36005 -361.641244) (xy 165.353159 -361.568976)
			(xy 165.35273 -361.532678) (xy 165.353223 -361.493666) (xy 165.361175 -361.416048) (xy 165.376995 -361.339644)
			(xy 165.38829 -361.3023) (xy 165.388907 -361.291485) (xy 165.382069 -361.270953) (xy 165.375082 -361.262676)
			(xy 165.356243 -361.241395) (xy 165.324384 -361.19433) (xy 165.299852 -361.143063) (xy 165.28319 -361.088727)
			(xy 165.274766 -361.032521) (xy 165.274244 -361.004104) (xy 13.408614 -361.004104) (xy 13.359106 -361.042426)
			(xy 13.293558 -361.083282) (xy 13.224212 -361.117298) (xy 13.151781 -361.144123) (xy 13.077008 -361.163483)
			(xy 13.00066 -361.175179) (xy 12.92352 -361.179092) (xy 12.84638 -361.175179) (xy 12.770032 -361.163483)
			(xy 12.695259 -361.144123) (xy 12.622828 -361.117298) (xy 12.553482 -361.083282) (xy 12.487934 -361.042426)
			(xy 12.426855 -360.995147) (xy 12.370873 -360.941932) (xy 12.320562 -360.883326) (xy 12.276438 -360.819932)
			(xy 12.238953 -360.752398) (xy 12.208494 -360.681419) (xy 12.185371 -360.607722) (xy 12.169823 -360.532064)
			(xy 12.162009 -360.455221) (xy 12.16152 -360.416602) (xy 9.689764 -360.416602) (xy 9.755022 -360.497698)
			(xy 9.829636 -360.603101) (xy 9.897619 -360.712898) (xy 9.958714 -360.826672) (xy 10.012689 -360.943991)
			(xy 10.05934 -361.06441) (xy 10.098489 -361.187473) (xy 10.129988 -361.312712) (xy 10.153717 -361.439653)
			(xy 10.169587 -361.567813) (xy 10.177537 -361.696708) (xy 10.178034 -361.761278) (xy 10.177537 -361.825848)
			(xy 10.169587 -361.954743) (xy 10.153717 -362.082903) (xy 10.129988 -362.209844) (xy 10.098489 -362.335083)
			(xy 10.05934 -362.458146) (xy 10.012689 -362.578565) (xy 9.958714 -362.695884) (xy 9.897619 -362.809658)
			(xy 9.829636 -362.919455) (xy 9.755022 -363.024858) (xy 9.674061 -363.125468) (xy 9.587061 -363.220903)
			(xy 9.49435 -363.310802) (xy 9.39628 -363.394823) (xy 9.293225 -363.472647) (xy 9.185574 -363.543979)
			(xy 9.073735 -363.608549) (xy 8.958134 -363.666111) (xy 8.839209 -363.716448) (xy 8.71741 -363.759368)
			(xy 8.5932 -363.794709) (xy 8.467051 -363.822336) (xy 8.339439 -363.842145) (xy 8.21085 -363.854061)
			(xy 8.081772 -363.858038) (xy 7.952694 -363.854061) (xy 7.824105 -363.842145) (xy 7.696493 -363.822336)
			(xy 7.570344 -363.794709) (xy 7.446134 -363.759368) (xy 7.324335 -363.716448) (xy 7.20541 -363.666111)
			(xy 7.089809 -363.608549) (xy 6.97797 -363.543979) (xy 6.870319 -363.472647) (xy 6.767264 -363.394823)
			(xy 6.669194 -363.310802) (xy 6.576483 -363.220903) (xy 6.489483 -363.125468) (xy 6.408522 -363.024858)
			(xy 6.333908 -362.919455) (xy 6.265925 -362.809658) (xy 6.20483 -362.695884) (xy 6.150855 -362.578565)
			(xy 6.104204 -362.458146) (xy 6.065055 -362.335083) (xy 6.033556 -362.209844) (xy 6.009827 -362.082903)
			(xy 5.993957 -361.954743) (xy 5.986007 -361.825848) (xy 3.523996 -361.825848) (xy 3.523996 -369.035302)
			(xy 43.674419 -369.035302) (xy 43.678313 -368.980888) (xy 43.689914 -368.927582) (xy 43.708986 -368.876471)
			(xy 43.735142 -368.828596) (xy 43.767847 -368.784933) (xy 43.806436 -368.746371) (xy 43.850122 -368.713696)
			(xy 43.898016 -368.687575) (xy 43.94914 -368.668538) (xy 44.002454 -368.656974) (xy 44.02963 -368.654584)
			(xy 44.041631 -368.653099) (xy 44.062306 -368.640609) (xy 44.069254 -368.630708) (xy 44.089152 -368.599589)
			(xy 44.134063 -368.54094) (xy 44.158916 -368.513614) (xy 44.164471 -368.507276) (xy 44.171361 -368.491905)
			(xy 44.172845 -368.475125) (xy 44.171108 -368.466878) (xy 44.165861 -368.444255) (xy 44.160259 -368.398151)
			(xy 44.159932 -368.37493) (xy 44.160429 -368.34766) (xy 44.168187 -368.293675) (xy 44.183549 -368.241343)
			(xy 44.206203 -368.19173) (xy 44.235687 -368.145847) (xy 44.271401 -368.104626) (xy 44.312618 -368.068909)
			(xy 44.358499 -368.03942) (xy 44.408109 -368.016762) (xy 44.460439 -368.001395) (xy 44.514424 -367.993632)
			(xy 44.541694 -367.993168) (xy 44.569174 -367.993593) (xy 44.623562 -368.001499) (xy 44.676256 -368.01712)
			(xy 44.726166 -368.040133) (xy 44.772262 -368.070063) (xy 44.813591 -368.106292) (xy 44.8493 -368.148071)
			(xy 44.878651 -368.194538) (xy 44.901038 -368.244732) (xy 44.908978 -368.271044) (xy 44.911606 -368.279121)
			(xy 44.921273 -368.29307) (xy 44.934988 -368.303067) (xy 44.943014 -368.305842) (xy 44.974313 -368.31594)
			(xy 45.035215 -368.340776) (xy 45.093763 -368.370743) (xy 45.12183 -368.387884) (xy 45.130091 -368.39258)
			(xy 45.148754 -368.396088) (xy 45.167417 -368.39258) (xy 45.175678 -368.387884) (xy 45.203735 -368.370723)
			(xy 45.262276 -368.340739) (xy 45.323185 -368.315914) (xy 45.354494 -368.305842) (xy 45.362508 -368.303037)
			(xy 45.37622 -368.293044) (xy 45.385917 -368.279121) (xy 45.38853 -368.271044) (xy 45.396474 -368.244733)
			(xy 45.418848 -368.194533) (xy 45.448192 -368.148062) (xy 45.483898 -368.106281) (xy 45.525229 -368.070055)
			(xy 45.571328 -368.040131) (xy 45.621244 -368.01713) (xy 45.673942 -368.001528) (xy 45.728334 -367.993646)
			(xy 45.755814 -367.993168) (xy 45.783087 -367.993589) (xy 45.837077 -368.001353) (xy 45.889412 -368.016723)
			(xy 45.939027 -368.039384) (xy 45.984912 -368.068876) (xy 46.026133 -368.104598) (xy 46.06185 -368.145823)
			(xy 46.091337 -368.191711) (xy 46.113992 -368.241329) (xy 46.129356 -368.293666) (xy 46.137115 -368.347657)
			(xy 46.137576 -368.37493) (xy 46.137244 -368.398151) (xy 46.131643 -368.444254) (xy 46.1264 -368.466878)
			(xy 46.124068 -368.47935) (xy 46.130464 -368.503871) (xy 46.138592 -368.513614) (xy 46.163456 -368.540931)
			(xy 46.208369 -368.59958) (xy 46.228254 -368.630708) (xy 46.235214 -368.640596) (xy 46.255883 -368.653071)
			(xy 46.267878 -368.654584) (xy 46.295067 -368.656909) (xy 46.348399 -368.668465) (xy 46.399543 -368.687497)
			(xy 46.447455 -368.713618) (xy 46.491159 -368.746296) (xy 46.529764 -368.784865) (xy 46.562484 -368.828537)
			(xy 46.588651 -368.876424) (xy 46.607732 -368.92755) (xy 46.619339 -368.980871) (xy 46.623234 -369.035302)
			(xy 50.481619 -369.035302) (xy 50.485513 -368.980888) (xy 50.497114 -368.927582) (xy 50.516186 -368.876471)
			(xy 50.542342 -368.828596) (xy 50.575047 -368.784933) (xy 50.613636 -368.746371) (xy 50.657322 -368.713696)
			(xy 50.705216 -368.687575) (xy 50.75634 -368.668538) (xy 50.809654 -368.656974) (xy 50.83683 -368.654584)
			(xy 50.848831 -368.653099) (xy 50.869506 -368.640609) (xy 50.876454 -368.630708) (xy 50.896352 -368.599589)
			(xy 50.941263 -368.54094) (xy 50.966116 -368.513614) (xy 50.971671 -368.507276) (xy 50.978561 -368.491905)
			(xy 50.980045 -368.475125) (xy 50.978308 -368.466878) (xy 50.973061 -368.444255) (xy 50.967459 -368.398151)
			(xy 50.967132 -368.37493) (xy 50.967629 -368.34766) (xy 50.975387 -368.293675) (xy 50.990749 -368.241343)
			(xy 51.013403 -368.19173) (xy 51.042887 -368.145847) (xy 51.078601 -368.104626) (xy 51.119818 -368.068909)
			(xy 51.165699 -368.03942) (xy 51.215309 -368.016762) (xy 51.267639 -368.001395) (xy 51.321624 -367.993632)
			(xy 51.348894 -367.993168) (xy 51.376374 -367.993593) (xy 51.430762 -368.001499) (xy 51.483456 -368.01712)
			(xy 51.533366 -368.040133) (xy 51.579462 -368.070063) (xy 51.620791 -368.106292) (xy 51.6565 -368.148071)
			(xy 51.685851 -368.194538) (xy 51.708238 -368.244732) (xy 51.716178 -368.271044) (xy 51.718806 -368.279121)
			(xy 51.728473 -368.29307) (xy 51.742188 -368.303067) (xy 51.750214 -368.305842) (xy 51.781513 -368.31594)
			(xy 51.842415 -368.340776) (xy 51.900963 -368.370743) (xy 51.92903 -368.387884) (xy 51.937291 -368.39258)
			(xy 51.955954 -368.396088) (xy 51.974617 -368.39258) (xy 51.982878 -368.387884) (xy 52.010935 -368.370723)
			(xy 52.069476 -368.340739) (xy 52.130385 -368.315914) (xy 52.161694 -368.305842) (xy 52.169708 -368.303037)
			(xy 52.18342 -368.293044) (xy 52.193117 -368.279121) (xy 52.19573 -368.271044) (xy 52.203674 -368.244733)
			(xy 52.226048 -368.194533) (xy 52.255392 -368.148062) (xy 52.291098 -368.106281) (xy 52.332429 -368.070055)
			(xy 52.378528 -368.040131) (xy 52.428444 -368.01713) (xy 52.481142 -368.001528) (xy 52.535534 -367.993646)
			(xy 52.563014 -367.993168) (xy 52.590287 -367.993589) (xy 52.644277 -368.001353) (xy 52.696612 -368.016723)
			(xy 52.746227 -368.039384) (xy 52.792112 -368.068876) (xy 52.833333 -368.104598) (xy 52.86905 -368.145823)
			(xy 52.898537 -368.191711) (xy 52.921192 -368.241329) (xy 52.936556 -368.293666) (xy 52.944315 -368.347657)
			(xy 52.944776 -368.37493) (xy 52.944444 -368.398151) (xy 52.938843 -368.444254) (xy 52.9336 -368.466878)
			(xy 52.931268 -368.47935) (xy 52.937664 -368.503871) (xy 52.945792 -368.513614) (xy 52.970656 -368.540931)
			(xy 53.015569 -368.59958) (xy 53.035454 -368.630708) (xy 53.042414 -368.640596) (xy 53.063083 -368.653071)
			(xy 53.075078 -368.654584) (xy 53.102267 -368.656909) (xy 53.155599 -368.668465) (xy 53.206743 -368.687497)
			(xy 53.254655 -368.713618) (xy 53.298359 -368.746296) (xy 53.336964 -368.784865) (xy 53.369684 -368.828537)
			(xy 53.395851 -368.876424) (xy 53.414932 -368.92755) (xy 53.426539 -368.980871) (xy 53.430434 -369.035302)
			(xy 57.288819 -369.035302) (xy 57.292713 -368.980888) (xy 57.304314 -368.927582) (xy 57.323386 -368.876471)
			(xy 57.349542 -368.828596) (xy 57.382247 -368.784933) (xy 57.420836 -368.746371) (xy 57.464522 -368.713696)
			(xy 57.512416 -368.687575) (xy 57.56354 -368.668538) (xy 57.616854 -368.656974) (xy 57.64403 -368.654584)
			(xy 57.656031 -368.653099) (xy 57.676706 -368.640609) (xy 57.683654 -368.630708) (xy 57.703552 -368.599589)
			(xy 57.748463 -368.54094) (xy 57.773316 -368.513614) (xy 57.778871 -368.507276) (xy 57.785761 -368.491905)
			(xy 57.787245 -368.475125) (xy 57.785508 -368.466878) (xy 57.780261 -368.444255) (xy 57.774659 -368.398151)
			(xy 57.774332 -368.37493) (xy 57.774829 -368.34766) (xy 57.782587 -368.293675) (xy 57.797949 -368.241343)
			(xy 57.820603 -368.19173) (xy 57.850087 -368.145847) (xy 57.885801 -368.104626) (xy 57.927018 -368.068909)
			(xy 57.972899 -368.03942) (xy 58.022509 -368.016762) (xy 58.074839 -368.001395) (xy 58.128824 -367.993632)
			(xy 58.156094 -367.993168) (xy 58.183574 -367.993593) (xy 58.237962 -368.001499) (xy 58.290656 -368.01712)
			(xy 58.340566 -368.040133) (xy 58.386662 -368.070063) (xy 58.427991 -368.106292) (xy 58.4637 -368.148071)
			(xy 58.493051 -368.194538) (xy 58.515438 -368.244732) (xy 58.523378 -368.271044) (xy 58.526006 -368.279121)
			(xy 58.535673 -368.29307) (xy 58.549388 -368.303067) (xy 58.557414 -368.305842) (xy 58.588713 -368.31594)
			(xy 58.649615 -368.340776) (xy 58.708163 -368.370743) (xy 58.73623 -368.387884) (xy 58.744491 -368.39258)
			(xy 58.763154 -368.396088) (xy 58.781817 -368.39258) (xy 58.790078 -368.387884) (xy 58.818135 -368.370723)
			(xy 58.876676 -368.340739) (xy 58.937585 -368.315914) (xy 58.968894 -368.305842) (xy 58.976908 -368.303037)
			(xy 58.99062 -368.293044) (xy 59.000317 -368.279121) (xy 59.00293 -368.271044) (xy 59.010874 -368.244733)
			(xy 59.033248 -368.194533) (xy 59.062592 -368.148062) (xy 59.098298 -368.106281) (xy 59.139629 -368.070055)
			(xy 59.185728 -368.040131) (xy 59.235644 -368.01713) (xy 59.288342 -368.001528) (xy 59.342734 -367.993646)
			(xy 59.370214 -367.993168) (xy 59.397487 -367.993589) (xy 59.451477 -368.001353) (xy 59.503812 -368.016723)
			(xy 59.553427 -368.039384) (xy 59.599312 -368.068876) (xy 59.640533 -368.104598) (xy 59.67625 -368.145823)
			(xy 59.705737 -368.191711) (xy 59.728392 -368.241329) (xy 59.743756 -368.293666) (xy 59.751515 -368.347657)
			(xy 59.751976 -368.37493) (xy 59.751644 -368.398151) (xy 59.746043 -368.444254) (xy 59.7408 -368.466878)
			(xy 59.738468 -368.47935) (xy 59.744864 -368.503871) (xy 59.752992 -368.513614) (xy 59.777856 -368.540931)
			(xy 59.822769 -368.59958) (xy 59.842654 -368.630708) (xy 59.849614 -368.640596) (xy 59.870283 -368.653071)
			(xy 59.882278 -368.654584) (xy 59.909467 -368.656909) (xy 59.962799 -368.668465) (xy 60.013943 -368.687497)
			(xy 60.061855 -368.713618) (xy 60.105559 -368.746296) (xy 60.144164 -368.784865) (xy 60.176884 -368.828537)
			(xy 60.203051 -368.876424) (xy 60.222132 -368.92755) (xy 60.233739 -368.980871) (xy 60.237634 -369.035302)
			(xy 64.096019 -369.035302) (xy 64.099913 -368.980888) (xy 64.111514 -368.927582) (xy 64.130586 -368.876471)
			(xy 64.156742 -368.828596) (xy 64.189447 -368.784933) (xy 64.228036 -368.746371) (xy 64.271722 -368.713696)
			(xy 64.319616 -368.687575) (xy 64.37074 -368.668538) (xy 64.424054 -368.656974) (xy 64.45123 -368.654584)
			(xy 64.463231 -368.653099) (xy 64.483906 -368.640609) (xy 64.490854 -368.630708) (xy 64.510752 -368.599589)
			(xy 64.555663 -368.54094) (xy 64.580516 -368.513614) (xy 64.586071 -368.507276) (xy 64.592961 -368.491905)
			(xy 64.594445 -368.475125) (xy 64.592708 -368.466878) (xy 64.587461 -368.444255) (xy 64.581859 -368.398151)
			(xy 64.581532 -368.37493) (xy 64.582029 -368.34766) (xy 64.589787 -368.293675) (xy 64.605149 -368.241343)
			(xy 64.627803 -368.19173) (xy 64.657287 -368.145847) (xy 64.693001 -368.104626) (xy 64.734218 -368.068909)
			(xy 64.780099 -368.03942) (xy 64.829709 -368.016762) (xy 64.882039 -368.001395) (xy 64.936024 -367.993632)
			(xy 64.963294 -367.993168) (xy 64.990774 -367.993593) (xy 65.045162 -368.001499) (xy 65.097856 -368.01712)
			(xy 65.147766 -368.040133) (xy 65.193862 -368.070063) (xy 65.235191 -368.106292) (xy 65.2709 -368.148071)
			(xy 65.300251 -368.194538) (xy 65.322638 -368.244732) (xy 65.330578 -368.271044) (xy 65.333206 -368.279121)
			(xy 65.342873 -368.29307) (xy 65.356588 -368.303067) (xy 65.364614 -368.305842) (xy 65.395913 -368.31594)
			(xy 65.456815 -368.340776) (xy 65.515363 -368.370743) (xy 65.54343 -368.387884) (xy 65.551691 -368.39258)
			(xy 65.570354 -368.396088) (xy 65.589017 -368.39258) (xy 65.597278 -368.387884) (xy 65.625335 -368.370723)
			(xy 65.683876 -368.340739) (xy 65.744785 -368.315914) (xy 65.776094 -368.305842) (xy 65.784108 -368.303037)
			(xy 65.79782 -368.293044) (xy 65.807517 -368.279121) (xy 65.81013 -368.271044) (xy 65.818074 -368.244733)
			(xy 65.840448 -368.194533) (xy 65.869792 -368.148062) (xy 65.905498 -368.106281) (xy 65.946829 -368.070055)
			(xy 65.992928 -368.040131) (xy 66.042844 -368.01713) (xy 66.095542 -368.001528) (xy 66.149934 -367.993646)
			(xy 66.177414 -367.993168) (xy 66.204687 -367.993589) (xy 66.258677 -368.001353) (xy 66.311012 -368.016723)
			(xy 66.360627 -368.039384) (xy 66.406512 -368.068876) (xy 66.447733 -368.104598) (xy 66.48345 -368.145823)
			(xy 66.512937 -368.191711) (xy 66.535592 -368.241329) (xy 66.550956 -368.293666) (xy 66.558715 -368.347657)
			(xy 66.559176 -368.37493) (xy 66.558844 -368.398151) (xy 66.553243 -368.444254) (xy 66.548 -368.466878)
			(xy 66.545668 -368.47935) (xy 66.552064 -368.503871) (xy 66.560192 -368.513614) (xy 66.585056 -368.540931)
			(xy 66.629969 -368.59958) (xy 66.649854 -368.630708) (xy 66.656814 -368.640596) (xy 66.677483 -368.653071)
			(xy 66.689478 -368.654584) (xy 66.716667 -368.656909) (xy 66.769999 -368.668465) (xy 66.821143 -368.687497)
			(xy 66.869055 -368.713618) (xy 66.912759 -368.746296) (xy 66.951364 -368.784865) (xy 66.984084 -368.828537)
			(xy 67.010251 -368.876424) (xy 67.029332 -368.92755) (xy 67.040939 -368.980871) (xy 67.044834 -369.035302)
			(xy 67.040938 -369.089733) (xy 67.029331 -369.143054) (xy 67.010249 -369.194179) (xy 66.984082 -369.242066)
			(xy 66.951362 -369.285739) (xy 66.912756 -369.324307) (xy 66.869051 -369.356984) (xy 66.821139 -369.383105)
			(xy 66.769995 -369.402137) (xy 66.716663 -369.413691) (xy 66.689478 -369.416076) (xy 66.677482 -369.417582)
			(xy 66.656806 -369.430058) (xy 66.649854 -369.439952) (xy 66.629951 -369.471069) (xy 66.585043 -369.529719)
			(xy 66.560192 -369.557046) (xy 66.554664 -369.563404) (xy 66.547766 -369.578765) (xy 66.54627 -369.595537)
			(xy 66.548 -369.603782) (xy 66.55324 -369.626407) (xy 66.558846 -369.672509) (xy 66.559176 -369.69573)
			(xy 66.558703 -369.722999) (xy 66.550938 -369.776983) (xy 66.53557 -369.829312) (xy 66.512911 -369.878921)
			(xy 66.483423 -369.924801) (xy 66.447707 -369.966018) (xy 66.406488 -370.001733) (xy 66.360607 -370.031219)
			(xy 66.310997 -370.053875) (xy 66.258667 -370.069242) (xy 66.204683 -370.077005) (xy 66.177414 -370.077492)
			(xy 66.149936 -370.077017) (xy 66.095552 -370.069113) (xy 66.042862 -370.053496) (xy 65.992954 -370.030488)
			(xy 65.94686 -370.000564) (xy 65.905531 -369.964342) (xy 65.86982 -369.922571) (xy 65.840466 -369.876112)
			(xy 65.818073 -369.825925) (xy 65.81013 -369.799616) (xy 65.807575 -369.791511) (xy 65.797878 -369.777563)
			(xy 65.784133 -369.76758) (xy 65.776094 -369.764818) (xy 65.744797 -369.754713) (xy 65.683895 -369.72988)
			(xy 65.625346 -369.699916) (xy 65.597278 -369.682776) (xy 65.589017 -369.67808) (xy 65.570354 -369.674572)
			(xy 65.551691 -369.67808) (xy 65.54343 -369.682776) (xy 65.515371 -369.699933) (xy 65.45683 -369.729919)
			(xy 65.395922 -369.754746) (xy 65.364614 -369.764818) (xy 65.356587 -369.767592) (xy 65.342874 -369.777596)
			(xy 65.333184 -369.791533) (xy 65.330578 -369.799616) (xy 65.322691 -369.825947) (xy 65.300315 -369.876152)
			(xy 65.270967 -369.922627) (xy 65.235254 -369.96441) (xy 65.193916 -370.000637) (xy 65.147808 -370.030558)
			(xy 65.097884 -370.053554) (xy 65.045176 -370.069149) (xy 64.990777 -370.07702) (xy 64.963294 -370.077492)
			(xy 64.936026 -370.076981) (xy 64.882045 -370.06922) (xy 64.829717 -370.053855) (xy 64.780109 -370.0312)
			(xy 64.73423 -370.001717) (xy 64.693013 -369.966004) (xy 64.657298 -369.924789) (xy 64.627811 -369.878912)
			(xy 64.605153 -369.829305) (xy 64.589786 -369.776979) (xy 64.58202 -369.722998) (xy 64.581532 -369.69573)
			(xy 64.581857 -369.672509) (xy 64.587463 -369.626406) (xy 64.592708 -369.603782) (xy 64.595065 -369.591312)
			(xy 64.588652 -369.566788) (xy 64.580516 -369.557046) (xy 64.555643 -369.529738) (xy 64.510736 -369.471083)
			(xy 64.490854 -369.439952) (xy 64.4839 -369.43006) (xy 64.463226 -369.417589) (xy 64.45123 -369.416076)
			(xy 64.424058 -369.413626) (xy 64.370744 -369.402063) (xy 64.319619 -369.383027) (xy 64.271726 -369.356906)
			(xy 64.228039 -369.324232) (xy 64.18945 -369.285671) (xy 64.156744 -369.242008) (xy 64.130588 -369.194133)
			(xy 64.111515 -369.143022) (xy 64.099913 -369.089717) (xy 64.096019 -369.035302) (xy 60.237634 -369.035302)
			(xy 60.233738 -369.089733) (xy 60.222131 -369.143054) (xy 60.203049 -369.194179) (xy 60.176882 -369.242066)
			(xy 60.144162 -369.285739) (xy 60.105556 -369.324307) (xy 60.061851 -369.356984) (xy 60.013939 -369.383105)
			(xy 59.962795 -369.402137) (xy 59.909463 -369.413691) (xy 59.882278 -369.416076) (xy 59.870282 -369.417582)
			(xy 59.849606 -369.430058) (xy 59.842654 -369.439952) (xy 59.822751 -369.471069) (xy 59.777843 -369.529719)
			(xy 59.752992 -369.557046) (xy 59.747464 -369.563404) (xy 59.740566 -369.578765) (xy 59.73907 -369.595537)
			(xy 59.7408 -369.603782) (xy 59.74604 -369.626407) (xy 59.751646 -369.672509) (xy 59.751976 -369.69573)
			(xy 59.751503 -369.722999) (xy 59.743738 -369.776983) (xy 59.72837 -369.829312) (xy 59.705711 -369.878921)
			(xy 59.676223 -369.924801) (xy 59.640507 -369.966018) (xy 59.599288 -370.001733) (xy 59.553407 -370.031219)
			(xy 59.503797 -370.053875) (xy 59.451467 -370.069242) (xy 59.397483 -370.077005) (xy 59.370214 -370.077492)
			(xy 59.342736 -370.077017) (xy 59.288352 -370.069113) (xy 59.235662 -370.053496) (xy 59.185754 -370.030488)
			(xy 59.13966 -370.000564) (xy 59.098331 -369.964342) (xy 59.06262 -369.922571) (xy 59.033266 -369.876112)
			(xy 59.010873 -369.825925) (xy 59.00293 -369.799616) (xy 59.000375 -369.791511) (xy 58.990678 -369.777563)
			(xy 58.976933 -369.76758) (xy 58.968894 -369.764818) (xy 58.937597 -369.754713) (xy 58.876695 -369.72988)
			(xy 58.818146 -369.699916) (xy 58.790078 -369.682776) (xy 58.781817 -369.67808) (xy 58.763154 -369.674572)
			(xy 58.744491 -369.67808) (xy 58.73623 -369.682776) (xy 58.708171 -369.699933) (xy 58.64963 -369.729919)
			(xy 58.588722 -369.754746) (xy 58.557414 -369.764818) (xy 58.549387 -369.767592) (xy 58.535674 -369.777596)
			(xy 58.525984 -369.791533) (xy 58.523378 -369.799616) (xy 58.515491 -369.825947) (xy 58.493115 -369.876152)
			(xy 58.463767 -369.922627) (xy 58.428054 -369.96441) (xy 58.386716 -370.000637) (xy 58.340608 -370.030558)
			(xy 58.290684 -370.053554) (xy 58.237976 -370.069149) (xy 58.183577 -370.07702) (xy 58.156094 -370.077492)
			(xy 58.128826 -370.076981) (xy 58.074845 -370.06922) (xy 58.022517 -370.053855) (xy 57.972909 -370.0312)
			(xy 57.92703 -370.001717) (xy 57.885813 -369.966004) (xy 57.850098 -369.924789) (xy 57.820611 -369.878912)
			(xy 57.797953 -369.829305) (xy 57.782586 -369.776979) (xy 57.77482 -369.722998) (xy 57.774332 -369.69573)
			(xy 57.774657 -369.672509) (xy 57.780263 -369.626406) (xy 57.785508 -369.603782) (xy 57.787865 -369.591312)
			(xy 57.781452 -369.566788) (xy 57.773316 -369.557046) (xy 57.748443 -369.529738) (xy 57.703536 -369.471083)
			(xy 57.683654 -369.439952) (xy 57.6767 -369.43006) (xy 57.656026 -369.417589) (xy 57.64403 -369.416076)
			(xy 57.616858 -369.413626) (xy 57.563544 -369.402063) (xy 57.512419 -369.383027) (xy 57.464526 -369.356906)
			(xy 57.420839 -369.324232) (xy 57.38225 -369.285671) (xy 57.349544 -369.242008) (xy 57.323388 -369.194133)
			(xy 57.304315 -369.143022) (xy 57.292713 -369.089717) (xy 57.288819 -369.035302) (xy 53.430434 -369.035302)
			(xy 53.426538 -369.089733) (xy 53.414931 -369.143054) (xy 53.395849 -369.194179) (xy 53.369682 -369.242066)
			(xy 53.336962 -369.285739) (xy 53.298356 -369.324307) (xy 53.254651 -369.356984) (xy 53.206739 -369.383105)
			(xy 53.155595 -369.402137) (xy 53.102263 -369.413691) (xy 53.075078 -369.416076) (xy 53.063082 -369.417582)
			(xy 53.042406 -369.430058) (xy 53.035454 -369.439952) (xy 53.015551 -369.471069) (xy 52.970643 -369.529719)
			(xy 52.945792 -369.557046) (xy 52.940264 -369.563404) (xy 52.933366 -369.578765) (xy 52.93187 -369.595537)
			(xy 52.9336 -369.603782) (xy 52.93884 -369.626407) (xy 52.944446 -369.672509) (xy 52.944776 -369.69573)
			(xy 52.944303 -369.722999) (xy 52.936538 -369.776983) (xy 52.92117 -369.829312) (xy 52.898511 -369.878921)
			(xy 52.869023 -369.924801) (xy 52.833307 -369.966018) (xy 52.792088 -370.001733) (xy 52.746207 -370.031219)
			(xy 52.696597 -370.053875) (xy 52.644267 -370.069242) (xy 52.590283 -370.077005) (xy 52.563014 -370.077492)
			(xy 52.535536 -370.077017) (xy 52.481152 -370.069113) (xy 52.428462 -370.053496) (xy 52.378554 -370.030488)
			(xy 52.33246 -370.000564) (xy 52.291131 -369.964342) (xy 52.25542 -369.922571) (xy 52.226066 -369.876112)
			(xy 52.203673 -369.825925) (xy 52.19573 -369.799616) (xy 52.193175 -369.791511) (xy 52.183478 -369.777563)
			(xy 52.169733 -369.76758) (xy 52.161694 -369.764818) (xy 52.130397 -369.754713) (xy 52.069495 -369.72988)
			(xy 52.010946 -369.699916) (xy 51.982878 -369.682776) (xy 51.974617 -369.67808) (xy 51.955954 -369.674572)
			(xy 51.937291 -369.67808) (xy 51.92903 -369.682776) (xy 51.900971 -369.699933) (xy 51.84243 -369.729919)
			(xy 51.781522 -369.754746) (xy 51.750214 -369.764818) (xy 51.742187 -369.767592) (xy 51.728474 -369.777596)
			(xy 51.718784 -369.791533) (xy 51.716178 -369.799616) (xy 51.708291 -369.825947) (xy 51.685915 -369.876152)
			(xy 51.656567 -369.922627) (xy 51.620854 -369.96441) (xy 51.579516 -370.000637) (xy 51.533408 -370.030558)
			(xy 51.483484 -370.053554) (xy 51.430776 -370.069149) (xy 51.376377 -370.07702) (xy 51.348894 -370.077492)
			(xy 51.321626 -370.076981) (xy 51.267645 -370.06922) (xy 51.215317 -370.053855) (xy 51.165709 -370.0312)
			(xy 51.11983 -370.001717) (xy 51.078613 -369.966004) (xy 51.042898 -369.924789) (xy 51.013411 -369.878912)
			(xy 50.990753 -369.829305) (xy 50.975386 -369.776979) (xy 50.96762 -369.722998) (xy 50.967132 -369.69573)
			(xy 50.967457 -369.672509) (xy 50.973063 -369.626406) (xy 50.978308 -369.603782) (xy 50.980665 -369.591312)
			(xy 50.974252 -369.566788) (xy 50.966116 -369.557046) (xy 50.941243 -369.529738) (xy 50.896336 -369.471083)
			(xy 50.876454 -369.439952) (xy 50.8695 -369.43006) (xy 50.848826 -369.417589) (xy 50.83683 -369.416076)
			(xy 50.809658 -369.413626) (xy 50.756344 -369.402063) (xy 50.705219 -369.383027) (xy 50.657326 -369.356906)
			(xy 50.613639 -369.324232) (xy 50.57505 -369.285671) (xy 50.542344 -369.242008) (xy 50.516188 -369.194133)
			(xy 50.497115 -369.143022) (xy 50.485513 -369.089717) (xy 50.481619 -369.035302) (xy 46.623234 -369.035302)
			(xy 46.619338 -369.089733) (xy 46.607731 -369.143054) (xy 46.588649 -369.194179) (xy 46.562482 -369.242066)
			(xy 46.529762 -369.285739) (xy 46.491156 -369.324307) (xy 46.447451 -369.356984) (xy 46.399539 -369.383105)
			(xy 46.348395 -369.402137) (xy 46.295063 -369.413691) (xy 46.267878 -369.416076) (xy 46.255882 -369.417582)
			(xy 46.235206 -369.430058) (xy 46.228254 -369.439952) (xy 46.208351 -369.471069) (xy 46.163443 -369.529719)
			(xy 46.138592 -369.557046) (xy 46.133064 -369.563404) (xy 46.126166 -369.578765) (xy 46.12467 -369.595537)
			(xy 46.1264 -369.603782) (xy 46.13164 -369.626407) (xy 46.137246 -369.672509) (xy 46.137576 -369.69573)
			(xy 46.137103 -369.722999) (xy 46.129338 -369.776983) (xy 46.11397 -369.829312) (xy 46.091311 -369.878921)
			(xy 46.061823 -369.924801) (xy 46.026107 -369.966018) (xy 45.984888 -370.001733) (xy 45.939007 -370.031219)
			(xy 45.889397 -370.053875) (xy 45.837067 -370.069242) (xy 45.783083 -370.077005) (xy 45.755814 -370.077492)
			(xy 45.728336 -370.077017) (xy 45.673952 -370.069113) (xy 45.621262 -370.053496) (xy 45.571354 -370.030488)
			(xy 45.52526 -370.000564) (xy 45.483931 -369.964342) (xy 45.44822 -369.922571) (xy 45.418866 -369.876112)
			(xy 45.396473 -369.825925) (xy 45.38853 -369.799616) (xy 45.385975 -369.791511) (xy 45.376278 -369.777563)
			(xy 45.362533 -369.76758) (xy 45.354494 -369.764818) (xy 45.323197 -369.754713) (xy 45.262295 -369.72988)
			(xy 45.203746 -369.699916) (xy 45.175678 -369.682776) (xy 45.167417 -369.67808) (xy 45.148754 -369.674572)
			(xy 45.130091 -369.67808) (xy 45.12183 -369.682776) (xy 45.093771 -369.699933) (xy 45.03523 -369.729919)
			(xy 44.974322 -369.754746) (xy 44.943014 -369.764818) (xy 44.934987 -369.767592) (xy 44.921274 -369.777596)
			(xy 44.911584 -369.791533) (xy 44.908978 -369.799616) (xy 44.901091 -369.825947) (xy 44.878715 -369.876152)
			(xy 44.849367 -369.922627) (xy 44.813654 -369.96441) (xy 44.772316 -370.000637) (xy 44.726208 -370.030558)
			(xy 44.676284 -370.053554) (xy 44.623576 -370.069149) (xy 44.569177 -370.07702) (xy 44.541694 -370.077492)
			(xy 44.514426 -370.076981) (xy 44.460445 -370.06922) (xy 44.408117 -370.053855) (xy 44.358509 -370.0312)
			(xy 44.31263 -370.001717) (xy 44.271413 -369.966004) (xy 44.235698 -369.924789) (xy 44.206211 -369.878912)
			(xy 44.183553 -369.829305) (xy 44.168186 -369.776979) (xy 44.16042 -369.722998) (xy 44.159932 -369.69573)
			(xy 44.160257 -369.672509) (xy 44.165863 -369.626406) (xy 44.171108 -369.603782) (xy 44.173465 -369.591312)
			(xy 44.167052 -369.566788) (xy 44.158916 -369.557046) (xy 44.134043 -369.529738) (xy 44.089136 -369.471083)
			(xy 44.069254 -369.439952) (xy 44.0623 -369.43006) (xy 44.041626 -369.417589) (xy 44.02963 -369.416076)
			(xy 44.002458 -369.413626) (xy 43.949144 -369.402063) (xy 43.898019 -369.383027) (xy 43.850126 -369.356906)
			(xy 43.806439 -369.324232) (xy 43.76785 -369.285671) (xy 43.735144 -369.242008) (xy 43.708988 -369.194133)
			(xy 43.689915 -369.143022) (xy 43.678313 -369.089717) (xy 43.674419 -369.035302) (xy 3.523996 -369.035302)
			(xy 3.523996 -371.499102) (xy 41.972619 -371.499102) (xy 41.976513 -371.444688) (xy 41.988114 -371.391382)
			(xy 42.007186 -371.340271) (xy 42.033342 -371.292396) (xy 42.066047 -371.248733) (xy 42.104636 -371.210171)
			(xy 42.148322 -371.177496) (xy 42.196216 -371.151375) (xy 42.24734 -371.132338) (xy 42.300654 -371.120774)
			(xy 42.32783 -371.118384) (xy 42.339831 -371.116899) (xy 42.360506 -371.104409) (xy 42.367454 -371.094508)
			(xy 42.387352 -371.063389) (xy 42.432263 -371.00474) (xy 42.457116 -370.977414) (xy 42.462671 -370.971076)
			(xy 42.469561 -370.955705) (xy 42.471045 -370.938925) (xy 42.469308 -370.930678) (xy 42.464061 -370.908055)
			(xy 42.458459 -370.861951) (xy 42.458132 -370.83873) (xy 42.458629 -370.81146) (xy 42.466387 -370.757475)
			(xy 42.481749 -370.705143) (xy 42.504403 -370.65553) (xy 42.533887 -370.609647) (xy 42.569601 -370.568426)
			(xy 42.610818 -370.532709) (xy 42.656699 -370.50322) (xy 42.706309 -370.480562) (xy 42.758639 -370.465195)
			(xy 42.812624 -370.457432) (xy 42.839894 -370.456968) (xy 42.867374 -370.457393) (xy 42.921762 -370.465299)
			(xy 42.974456 -370.48092) (xy 43.024366 -370.503933) (xy 43.070462 -370.533863) (xy 43.111791 -370.570092)
			(xy 43.1475 -370.611871) (xy 43.176851 -370.658338) (xy 43.199238 -370.708532) (xy 43.207178 -370.734844)
			(xy 43.209806 -370.742921) (xy 43.219473 -370.75687) (xy 43.233188 -370.766867) (xy 43.241214 -370.769642)
			(xy 43.272513 -370.77974) (xy 43.333415 -370.804576) (xy 43.391963 -370.834543) (xy 43.42003 -370.851684)
			(xy 43.428291 -370.85638) (xy 43.446954 -370.859888) (xy 43.465617 -370.85638) (xy 43.473878 -370.851684)
			(xy 43.501935 -370.834523) (xy 43.560476 -370.804539) (xy 43.621385 -370.779714) (xy 43.652694 -370.769642)
			(xy 43.660708 -370.766837) (xy 43.67442 -370.756844) (xy 43.684117 -370.742921) (xy 43.68673 -370.734844)
			(xy 43.694674 -370.708533) (xy 43.717048 -370.658333) (xy 43.746392 -370.611862) (xy 43.782098 -370.570081)
			(xy 43.823429 -370.533855) (xy 43.869528 -370.503931) (xy 43.919444 -370.48093) (xy 43.972142 -370.465328)
			(xy 44.026534 -370.457446) (xy 44.054014 -370.456968) (xy 44.081287 -370.457389) (xy 44.135277 -370.465153)
			(xy 44.187612 -370.480523) (xy 44.237227 -370.503184) (xy 44.283112 -370.532676) (xy 44.324333 -370.568398)
			(xy 44.36005 -370.609623) (xy 44.389537 -370.655511) (xy 44.412192 -370.705129) (xy 44.427556 -370.757466)
			(xy 44.435315 -370.811457) (xy 44.435776 -370.83873) (xy 44.435444 -370.861951) (xy 44.429843 -370.908054)
			(xy 44.4246 -370.930678) (xy 44.422268 -370.94315) (xy 44.428664 -370.967671) (xy 44.436792 -370.977414)
			(xy 44.461656 -371.004731) (xy 44.506569 -371.06338) (xy 44.526454 -371.094508) (xy 44.533414 -371.104396)
			(xy 44.554083 -371.116871) (xy 44.566078 -371.118384) (xy 44.593267 -371.120709) (xy 44.646599 -371.132265)
			(xy 44.697743 -371.151297) (xy 44.745655 -371.177418) (xy 44.789359 -371.210096) (xy 44.827964 -371.248665)
			(xy 44.860684 -371.292337) (xy 44.886851 -371.340224) (xy 44.905932 -371.39135) (xy 44.917539 -371.444671)
			(xy 44.921434 -371.499102) (xy 48.779819 -371.499102) (xy 48.783713 -371.444688) (xy 48.795314 -371.391382)
			(xy 48.814386 -371.340271) (xy 48.840542 -371.292396) (xy 48.873247 -371.248733) (xy 48.911836 -371.210171)
			(xy 48.955522 -371.177496) (xy 49.003416 -371.151375) (xy 49.05454 -371.132338) (xy 49.107854 -371.120774)
			(xy 49.13503 -371.118384) (xy 49.147031 -371.116899) (xy 49.167706 -371.104409) (xy 49.174654 -371.094508)
			(xy 49.194552 -371.063389) (xy 49.239463 -371.00474) (xy 49.264316 -370.977414) (xy 49.269871 -370.971076)
			(xy 49.276761 -370.955705) (xy 49.278245 -370.938925) (xy 49.276508 -370.930678) (xy 49.271261 -370.908055)
			(xy 49.265659 -370.861951) (xy 49.265332 -370.83873) (xy 49.265829 -370.81146) (xy 49.273587 -370.757475)
			(xy 49.288949 -370.705143) (xy 49.311603 -370.65553) (xy 49.341087 -370.609647) (xy 49.376801 -370.568426)
			(xy 49.418018 -370.532709) (xy 49.463899 -370.50322) (xy 49.513509 -370.480562) (xy 49.565839 -370.465195)
			(xy 49.619824 -370.457432) (xy 49.647094 -370.456968) (xy 49.674574 -370.457393) (xy 49.728962 -370.465299)
			(xy 49.781656 -370.48092) (xy 49.831566 -370.503933) (xy 49.877662 -370.533863) (xy 49.918991 -370.570092)
			(xy 49.9547 -370.611871) (xy 49.984051 -370.658338) (xy 50.006438 -370.708532) (xy 50.014378 -370.734844)
			(xy 50.017006 -370.742921) (xy 50.026673 -370.75687) (xy 50.040388 -370.766867) (xy 50.048414 -370.769642)
			(xy 50.079713 -370.77974) (xy 50.140615 -370.804576) (xy 50.199163 -370.834543) (xy 50.22723 -370.851684)
			(xy 50.235491 -370.85638) (xy 50.254154 -370.859888) (xy 50.272817 -370.85638) (xy 50.281078 -370.851684)
			(xy 50.309135 -370.834523) (xy 50.367676 -370.804539) (xy 50.428585 -370.779714) (xy 50.459894 -370.769642)
			(xy 50.467908 -370.766837) (xy 50.48162 -370.756844) (xy 50.491317 -370.742921) (xy 50.49393 -370.734844)
			(xy 50.501874 -370.708533) (xy 50.524248 -370.658333) (xy 50.553592 -370.611862) (xy 50.589298 -370.570081)
			(xy 50.630629 -370.533855) (xy 50.676728 -370.503931) (xy 50.726644 -370.48093) (xy 50.779342 -370.465328)
			(xy 50.833734 -370.457446) (xy 50.861214 -370.456968) (xy 50.888487 -370.457389) (xy 50.942477 -370.465153)
			(xy 50.994812 -370.480523) (xy 51.044427 -370.503184) (xy 51.090312 -370.532676) (xy 51.131533 -370.568398)
			(xy 51.16725 -370.609623) (xy 51.196737 -370.655511) (xy 51.219392 -370.705129) (xy 51.234756 -370.757466)
			(xy 51.242515 -370.811457) (xy 51.242976 -370.83873) (xy 51.242644 -370.861951) (xy 51.237043 -370.908054)
			(xy 51.2318 -370.930678) (xy 51.229468 -370.94315) (xy 51.235864 -370.967671) (xy 51.243992 -370.977414)
			(xy 51.268856 -371.004731) (xy 51.313769 -371.06338) (xy 51.333654 -371.094508) (xy 51.340614 -371.104396)
			(xy 51.361283 -371.116871) (xy 51.373278 -371.118384) (xy 51.400467 -371.120709) (xy 51.453799 -371.132265)
			(xy 51.504943 -371.151297) (xy 51.552855 -371.177418) (xy 51.596559 -371.210096) (xy 51.635164 -371.248665)
			(xy 51.667884 -371.292337) (xy 51.694051 -371.340224) (xy 51.713132 -371.39135) (xy 51.724739 -371.444671)
			(xy 51.728634 -371.499102) (xy 55.587019 -371.499102) (xy 55.590913 -371.444688) (xy 55.602514 -371.391382)
			(xy 55.621586 -371.340271) (xy 55.647742 -371.292396) (xy 55.680447 -371.248733) (xy 55.719036 -371.210171)
			(xy 55.762722 -371.177496) (xy 55.810616 -371.151375) (xy 55.86174 -371.132338) (xy 55.915054 -371.120774)
			(xy 55.94223 -371.118384) (xy 55.954231 -371.116899) (xy 55.974906 -371.104409) (xy 55.981854 -371.094508)
			(xy 56.001752 -371.063389) (xy 56.046663 -371.00474) (xy 56.071516 -370.977414) (xy 56.077071 -370.971076)
			(xy 56.083961 -370.955705) (xy 56.085445 -370.938925) (xy 56.083708 -370.930678) (xy 56.078461 -370.908055)
			(xy 56.072859 -370.861951) (xy 56.072532 -370.83873) (xy 56.073029 -370.81146) (xy 56.080787 -370.757475)
			(xy 56.096149 -370.705143) (xy 56.118803 -370.65553) (xy 56.148287 -370.609647) (xy 56.184001 -370.568426)
			(xy 56.225218 -370.532709) (xy 56.271099 -370.50322) (xy 56.320709 -370.480562) (xy 56.373039 -370.465195)
			(xy 56.427024 -370.457432) (xy 56.454294 -370.456968) (xy 56.481774 -370.457393) (xy 56.536162 -370.465299)
			(xy 56.588856 -370.48092) (xy 56.638766 -370.503933) (xy 56.684862 -370.533863) (xy 56.726191 -370.570092)
			(xy 56.7619 -370.611871) (xy 56.791251 -370.658338) (xy 56.813638 -370.708532) (xy 56.821578 -370.734844)
			(xy 56.824206 -370.742921) (xy 56.833873 -370.75687) (xy 56.847588 -370.766867) (xy 56.855614 -370.769642)
			(xy 56.886913 -370.77974) (xy 56.947815 -370.804576) (xy 57.006363 -370.834543) (xy 57.03443 -370.851684)
			(xy 57.042691 -370.85638) (xy 57.061354 -370.859888) (xy 57.080017 -370.85638) (xy 57.088278 -370.851684)
			(xy 57.116335 -370.834523) (xy 57.174876 -370.804539) (xy 57.235785 -370.779714) (xy 57.267094 -370.769642)
			(xy 57.275108 -370.766837) (xy 57.28882 -370.756844) (xy 57.298517 -370.742921) (xy 57.30113 -370.734844)
			(xy 57.309074 -370.708533) (xy 57.331448 -370.658333) (xy 57.360792 -370.611862) (xy 57.396498 -370.570081)
			(xy 57.437829 -370.533855) (xy 57.483928 -370.503931) (xy 57.533844 -370.48093) (xy 57.586542 -370.465328)
			(xy 57.640934 -370.457446) (xy 57.668414 -370.456968) (xy 57.695687 -370.457389) (xy 57.749677 -370.465153)
			(xy 57.802012 -370.480523) (xy 57.851627 -370.503184) (xy 57.897512 -370.532676) (xy 57.938733 -370.568398)
			(xy 57.97445 -370.609623) (xy 58.003937 -370.655511) (xy 58.026592 -370.705129) (xy 58.041956 -370.757466)
			(xy 58.049715 -370.811457) (xy 58.050176 -370.83873) (xy 58.049844 -370.861951) (xy 58.044243 -370.908054)
			(xy 58.039 -370.930678) (xy 58.036668 -370.94315) (xy 58.043064 -370.967671) (xy 58.051192 -370.977414)
			(xy 58.076056 -371.004731) (xy 58.120969 -371.06338) (xy 58.140854 -371.094508) (xy 58.147814 -371.104396)
			(xy 58.168483 -371.116871) (xy 58.180478 -371.118384) (xy 58.207667 -371.120709) (xy 58.260999 -371.132265)
			(xy 58.312143 -371.151297) (xy 58.360055 -371.177418) (xy 58.403759 -371.210096) (xy 58.442364 -371.248665)
			(xy 58.475084 -371.292337) (xy 58.501251 -371.340224) (xy 58.520332 -371.39135) (xy 58.531939 -371.444671)
			(xy 58.535834 -371.499102) (xy 62.394219 -371.499102) (xy 62.398113 -371.444688) (xy 62.409714 -371.391382)
			(xy 62.428786 -371.340271) (xy 62.454942 -371.292396) (xy 62.487647 -371.248733) (xy 62.526236 -371.210171)
			(xy 62.569922 -371.177496) (xy 62.617816 -371.151375) (xy 62.66894 -371.132338) (xy 62.722254 -371.120774)
			(xy 62.74943 -371.118384) (xy 62.761431 -371.116899) (xy 62.782106 -371.104409) (xy 62.789054 -371.094508)
			(xy 62.808952 -371.063389) (xy 62.853863 -371.00474) (xy 62.878716 -370.977414) (xy 62.884271 -370.971076)
			(xy 62.891161 -370.955705) (xy 62.892645 -370.938925) (xy 62.890908 -370.930678) (xy 62.885661 -370.908055)
			(xy 62.880059 -370.861951) (xy 62.879732 -370.83873) (xy 62.880229 -370.81146) (xy 62.887987 -370.757475)
			(xy 62.903349 -370.705143) (xy 62.926003 -370.65553) (xy 62.955487 -370.609647) (xy 62.991201 -370.568426)
			(xy 63.032418 -370.532709) (xy 63.078299 -370.50322) (xy 63.127909 -370.480562) (xy 63.180239 -370.465195)
			(xy 63.234224 -370.457432) (xy 63.261494 -370.456968) (xy 63.288974 -370.457393) (xy 63.343362 -370.465299)
			(xy 63.396056 -370.48092) (xy 63.445966 -370.503933) (xy 63.492062 -370.533863) (xy 63.533391 -370.570092)
			(xy 63.5691 -370.611871) (xy 63.598451 -370.658338) (xy 63.620838 -370.708532) (xy 63.628778 -370.734844)
			(xy 63.631406 -370.742921) (xy 63.641073 -370.75687) (xy 63.654788 -370.766867) (xy 63.662814 -370.769642)
			(xy 63.694113 -370.77974) (xy 63.755015 -370.804576) (xy 63.813563 -370.834543) (xy 63.84163 -370.851684)
			(xy 63.849891 -370.85638) (xy 63.868554 -370.859888) (xy 63.887217 -370.85638) (xy 63.895478 -370.851684)
			(xy 63.923535 -370.834523) (xy 63.982076 -370.804539) (xy 64.042985 -370.779714) (xy 64.074294 -370.769642)
			(xy 64.082308 -370.766837) (xy 64.09602 -370.756844) (xy 64.105717 -370.742921) (xy 64.10833 -370.734844)
			(xy 64.116274 -370.708533) (xy 64.138648 -370.658333) (xy 64.167992 -370.611862) (xy 64.203698 -370.570081)
			(xy 64.245029 -370.533855) (xy 64.291128 -370.503931) (xy 64.341044 -370.48093) (xy 64.393742 -370.465328)
			(xy 64.448134 -370.457446) (xy 64.475614 -370.456968) (xy 64.502887 -370.457389) (xy 64.556877 -370.465153)
			(xy 64.609212 -370.480523) (xy 64.658827 -370.503184) (xy 64.704712 -370.532676) (xy 64.745933 -370.568398)
			(xy 64.78165 -370.609623) (xy 64.811137 -370.655511) (xy 64.833792 -370.705129) (xy 64.849156 -370.757466)
			(xy 64.856915 -370.811457) (xy 64.857376 -370.83873) (xy 64.857044 -370.861951) (xy 64.851443 -370.908054)
			(xy 64.8462 -370.930678) (xy 64.843868 -370.94315) (xy 64.850264 -370.967671) (xy 64.858392 -370.977414)
			(xy 64.883256 -371.004731) (xy 64.928169 -371.06338) (xy 64.948054 -371.094508) (xy 64.955014 -371.104396)
			(xy 64.975683 -371.116871) (xy 64.987678 -371.118384) (xy 65.014867 -371.120709) (xy 65.068199 -371.132265)
			(xy 65.119343 -371.151297) (xy 65.167255 -371.177418) (xy 65.210959 -371.210096) (xy 65.249564 -371.248665)
			(xy 65.282284 -371.292337) (xy 65.308451 -371.340224) (xy 65.327532 -371.39135) (xy 65.339139 -371.444671)
			(xy 65.343034 -371.499102) (xy 65.339138 -371.553533) (xy 65.327531 -371.606854) (xy 65.308449 -371.657979)
			(xy 65.282282 -371.705866) (xy 65.249562 -371.749539) (xy 65.210956 -371.788107) (xy 65.167251 -371.820784)
			(xy 65.119339 -371.846905) (xy 65.068195 -371.865937) (xy 65.014863 -371.877491) (xy 64.987678 -371.879876)
			(xy 64.975682 -371.881382) (xy 64.955006 -371.893858) (xy 64.948054 -371.903752) (xy 64.928151 -371.934869)
			(xy 64.883243 -371.993519) (xy 64.858392 -372.020846) (xy 64.852864 -372.027204) (xy 64.845966 -372.042565)
			(xy 64.84447 -372.059337) (xy 64.8462 -372.067582) (xy 64.85144 -372.090207) (xy 64.857046 -372.136309)
			(xy 64.857376 -372.15953) (xy 64.856903 -372.186799) (xy 64.849138 -372.240783) (xy 64.83377 -372.293112)
			(xy 64.811111 -372.342721) (xy 64.781623 -372.388601) (xy 64.745907 -372.429818) (xy 64.704688 -372.465533)
			(xy 64.658807 -372.495019) (xy 64.609197 -372.517675) (xy 64.556867 -372.533042) (xy 64.502883 -372.540805)
			(xy 64.475614 -372.541292) (xy 64.448136 -372.540817) (xy 64.393752 -372.532913) (xy 64.341062 -372.517296)
			(xy 64.291154 -372.494288) (xy 64.24506 -372.464364) (xy 64.203731 -372.428142) (xy 64.16802 -372.386371)
			(xy 64.138666 -372.339912) (xy 64.116273 -372.289725) (xy 64.10833 -372.263416) (xy 64.105775 -372.255311)
			(xy 64.096078 -372.241363) (xy 64.082333 -372.23138) (xy 64.074294 -372.228618) (xy 64.042997 -372.218513)
			(xy 63.982095 -372.19368) (xy 63.923546 -372.163716) (xy 63.895478 -372.146576) (xy 63.887217 -372.14188)
			(xy 63.868554 -372.138372) (xy 63.849891 -372.14188) (xy 63.84163 -372.146576) (xy 63.813571 -372.163733)
			(xy 63.75503 -372.193719) (xy 63.694122 -372.218546) (xy 63.662814 -372.228618) (xy 63.654787 -372.231392)
			(xy 63.641074 -372.241396) (xy 63.631384 -372.255333) (xy 63.628778 -372.263416) (xy 63.620891 -372.289747)
			(xy 63.598515 -372.339952) (xy 63.569167 -372.386427) (xy 63.533454 -372.42821) (xy 63.492116 -372.464437)
			(xy 63.446008 -372.494358) (xy 63.396084 -372.517354) (xy 63.343376 -372.532949) (xy 63.288977 -372.54082)
			(xy 63.261494 -372.541292) (xy 63.234226 -372.540781) (xy 63.180245 -372.53302) (xy 63.127917 -372.517655)
			(xy 63.078309 -372.495) (xy 63.03243 -372.465517) (xy 62.991213 -372.429804) (xy 62.955498 -372.388589)
			(xy 62.926011 -372.342712) (xy 62.903353 -372.293105) (xy 62.887986 -372.240779) (xy 62.88022 -372.186798)
			(xy 62.879732 -372.15953) (xy 62.880057 -372.136309) (xy 62.885663 -372.090206) (xy 62.890908 -372.067582)
			(xy 62.893265 -372.055112) (xy 62.886852 -372.030588) (xy 62.878716 -372.020846) (xy 62.853843 -371.993538)
			(xy 62.808936 -371.934883) (xy 62.789054 -371.903752) (xy 62.7821 -371.89386) (xy 62.761426 -371.881389)
			(xy 62.74943 -371.879876) (xy 62.722258 -371.877426) (xy 62.668944 -371.865863) (xy 62.617819 -371.846827)
			(xy 62.569926 -371.820706) (xy 62.526239 -371.788032) (xy 62.48765 -371.749471) (xy 62.454944 -371.705808)
			(xy 62.428788 -371.657933) (xy 62.409715 -371.606822) (xy 62.398113 -371.553517) (xy 62.394219 -371.499102)
			(xy 58.535834 -371.499102) (xy 58.531938 -371.553533) (xy 58.520331 -371.606854) (xy 58.501249 -371.657979)
			(xy 58.475082 -371.705866) (xy 58.442362 -371.749539) (xy 58.403756 -371.788107) (xy 58.360051 -371.820784)
			(xy 58.312139 -371.846905) (xy 58.260995 -371.865937) (xy 58.207663 -371.877491) (xy 58.180478 -371.879876)
			(xy 58.168482 -371.881382) (xy 58.147806 -371.893858) (xy 58.140854 -371.903752) (xy 58.120951 -371.934869)
			(xy 58.076043 -371.993519) (xy 58.051192 -372.020846) (xy 58.045664 -372.027204) (xy 58.038766 -372.042565)
			(xy 58.03727 -372.059337) (xy 58.039 -372.067582) (xy 58.04424 -372.090207) (xy 58.049846 -372.136309)
			(xy 58.050176 -372.15953) (xy 58.049703 -372.186799) (xy 58.041938 -372.240783) (xy 58.02657 -372.293112)
			(xy 58.003911 -372.342721) (xy 57.974423 -372.388601) (xy 57.938707 -372.429818) (xy 57.897488 -372.465533)
			(xy 57.851607 -372.495019) (xy 57.801997 -372.517675) (xy 57.749667 -372.533042) (xy 57.695683 -372.540805)
			(xy 57.668414 -372.541292) (xy 57.640936 -372.540817) (xy 57.586552 -372.532913) (xy 57.533862 -372.517296)
			(xy 57.483954 -372.494288) (xy 57.43786 -372.464364) (xy 57.396531 -372.428142) (xy 57.36082 -372.386371)
			(xy 57.331466 -372.339912) (xy 57.309073 -372.289725) (xy 57.30113 -372.263416) (xy 57.298575 -372.255311)
			(xy 57.288878 -372.241363) (xy 57.275133 -372.23138) (xy 57.267094 -372.228618) (xy 57.235797 -372.218513)
			(xy 57.174895 -372.19368) (xy 57.116346 -372.163716) (xy 57.088278 -372.146576) (xy 57.080017 -372.14188)
			(xy 57.061354 -372.138372) (xy 57.042691 -372.14188) (xy 57.03443 -372.146576) (xy 57.006371 -372.163733)
			(xy 56.94783 -372.193719) (xy 56.886922 -372.218546) (xy 56.855614 -372.228618) (xy 56.847587 -372.231392)
			(xy 56.833874 -372.241396) (xy 56.824184 -372.255333) (xy 56.821578 -372.263416) (xy 56.813691 -372.289747)
			(xy 56.791315 -372.339952) (xy 56.761967 -372.386427) (xy 56.726254 -372.42821) (xy 56.684916 -372.464437)
			(xy 56.638808 -372.494358) (xy 56.588884 -372.517354) (xy 56.536176 -372.532949) (xy 56.481777 -372.54082)
			(xy 56.454294 -372.541292) (xy 56.427026 -372.540781) (xy 56.373045 -372.53302) (xy 56.320717 -372.517655)
			(xy 56.271109 -372.495) (xy 56.22523 -372.465517) (xy 56.184013 -372.429804) (xy 56.148298 -372.388589)
			(xy 56.118811 -372.342712) (xy 56.096153 -372.293105) (xy 56.080786 -372.240779) (xy 56.07302 -372.186798)
			(xy 56.072532 -372.15953) (xy 56.072857 -372.136309) (xy 56.078463 -372.090206) (xy 56.083708 -372.067582)
			(xy 56.086065 -372.055112) (xy 56.079652 -372.030588) (xy 56.071516 -372.020846) (xy 56.046643 -371.993538)
			(xy 56.001736 -371.934883) (xy 55.981854 -371.903752) (xy 55.9749 -371.89386) (xy 55.954226 -371.881389)
			(xy 55.94223 -371.879876) (xy 55.915058 -371.877426) (xy 55.861744 -371.865863) (xy 55.810619 -371.846827)
			(xy 55.762726 -371.820706) (xy 55.719039 -371.788032) (xy 55.68045 -371.749471) (xy 55.647744 -371.705808)
			(xy 55.621588 -371.657933) (xy 55.602515 -371.606822) (xy 55.590913 -371.553517) (xy 55.587019 -371.499102)
			(xy 51.728634 -371.499102) (xy 51.724738 -371.553533) (xy 51.713131 -371.606854) (xy 51.694049 -371.657979)
			(xy 51.667882 -371.705866) (xy 51.635162 -371.749539) (xy 51.596556 -371.788107) (xy 51.552851 -371.820784)
			(xy 51.504939 -371.846905) (xy 51.453795 -371.865937) (xy 51.400463 -371.877491) (xy 51.373278 -371.879876)
			(xy 51.361282 -371.881382) (xy 51.340606 -371.893858) (xy 51.333654 -371.903752) (xy 51.313751 -371.934869)
			(xy 51.268843 -371.993519) (xy 51.243992 -372.020846) (xy 51.238464 -372.027204) (xy 51.231566 -372.042565)
			(xy 51.23007 -372.059337) (xy 51.2318 -372.067582) (xy 51.23704 -372.090207) (xy 51.242646 -372.136309)
			(xy 51.242976 -372.15953) (xy 51.242503 -372.186799) (xy 51.234738 -372.240783) (xy 51.21937 -372.293112)
			(xy 51.196711 -372.342721) (xy 51.167223 -372.388601) (xy 51.131507 -372.429818) (xy 51.090288 -372.465533)
			(xy 51.044407 -372.495019) (xy 50.994797 -372.517675) (xy 50.942467 -372.533042) (xy 50.888483 -372.540805)
			(xy 50.861214 -372.541292) (xy 50.833736 -372.540817) (xy 50.779352 -372.532913) (xy 50.726662 -372.517296)
			(xy 50.676754 -372.494288) (xy 50.63066 -372.464364) (xy 50.589331 -372.428142) (xy 50.55362 -372.386371)
			(xy 50.524266 -372.339912) (xy 50.501873 -372.289725) (xy 50.49393 -372.263416) (xy 50.491375 -372.255311)
			(xy 50.481678 -372.241363) (xy 50.467933 -372.23138) (xy 50.459894 -372.228618) (xy 50.428597 -372.218513)
			(xy 50.367695 -372.19368) (xy 50.309146 -372.163716) (xy 50.281078 -372.146576) (xy 50.272817 -372.14188)
			(xy 50.254154 -372.138372) (xy 50.235491 -372.14188) (xy 50.22723 -372.146576) (xy 50.199171 -372.163733)
			(xy 50.14063 -372.193719) (xy 50.079722 -372.218546) (xy 50.048414 -372.228618) (xy 50.040387 -372.231392)
			(xy 50.026674 -372.241396) (xy 50.016984 -372.255333) (xy 50.014378 -372.263416) (xy 50.006491 -372.289747)
			(xy 49.984115 -372.339952) (xy 49.954767 -372.386427) (xy 49.919054 -372.42821) (xy 49.877716 -372.464437)
			(xy 49.831608 -372.494358) (xy 49.781684 -372.517354) (xy 49.728976 -372.532949) (xy 49.674577 -372.54082)
			(xy 49.647094 -372.541292) (xy 49.619826 -372.540781) (xy 49.565845 -372.53302) (xy 49.513517 -372.517655)
			(xy 49.463909 -372.495) (xy 49.41803 -372.465517) (xy 49.376813 -372.429804) (xy 49.341098 -372.388589)
			(xy 49.311611 -372.342712) (xy 49.288953 -372.293105) (xy 49.273586 -372.240779) (xy 49.26582 -372.186798)
			(xy 49.265332 -372.15953) (xy 49.265657 -372.136309) (xy 49.271263 -372.090206) (xy 49.276508 -372.067582)
			(xy 49.278865 -372.055112) (xy 49.272452 -372.030588) (xy 49.264316 -372.020846) (xy 49.239443 -371.993538)
			(xy 49.194536 -371.934883) (xy 49.174654 -371.903752) (xy 49.1677 -371.89386) (xy 49.147026 -371.881389)
			(xy 49.13503 -371.879876) (xy 49.107858 -371.877426) (xy 49.054544 -371.865863) (xy 49.003419 -371.846827)
			(xy 48.955526 -371.820706) (xy 48.911839 -371.788032) (xy 48.87325 -371.749471) (xy 48.840544 -371.705808)
			(xy 48.814388 -371.657933) (xy 48.795315 -371.606822) (xy 48.783713 -371.553517) (xy 48.779819 -371.499102)
			(xy 44.921434 -371.499102) (xy 44.917538 -371.553533) (xy 44.905931 -371.606854) (xy 44.886849 -371.657979)
			(xy 44.860682 -371.705866) (xy 44.827962 -371.749539) (xy 44.789356 -371.788107) (xy 44.745651 -371.820784)
			(xy 44.697739 -371.846905) (xy 44.646595 -371.865937) (xy 44.593263 -371.877491) (xy 44.566078 -371.879876)
			(xy 44.554082 -371.881382) (xy 44.533406 -371.893858) (xy 44.526454 -371.903752) (xy 44.506551 -371.934869)
			(xy 44.461643 -371.993519) (xy 44.436792 -372.020846) (xy 44.431264 -372.027204) (xy 44.424366 -372.042565)
			(xy 44.42287 -372.059337) (xy 44.4246 -372.067582) (xy 44.42984 -372.090207) (xy 44.435446 -372.136309)
			(xy 44.435776 -372.15953) (xy 44.435303 -372.186799) (xy 44.427538 -372.240783) (xy 44.41217 -372.293112)
			(xy 44.389511 -372.342721) (xy 44.360023 -372.388601) (xy 44.324307 -372.429818) (xy 44.283088 -372.465533)
			(xy 44.237207 -372.495019) (xy 44.187597 -372.517675) (xy 44.135267 -372.533042) (xy 44.081283 -372.540805)
			(xy 44.054014 -372.541292) (xy 44.026536 -372.540817) (xy 43.972152 -372.532913) (xy 43.919462 -372.517296)
			(xy 43.869554 -372.494288) (xy 43.82346 -372.464364) (xy 43.782131 -372.428142) (xy 43.74642 -372.386371)
			(xy 43.717066 -372.339912) (xy 43.694673 -372.289725) (xy 43.68673 -372.263416) (xy 43.684175 -372.255311)
			(xy 43.674478 -372.241363) (xy 43.660733 -372.23138) (xy 43.652694 -372.228618) (xy 43.621397 -372.218513)
			(xy 43.560495 -372.19368) (xy 43.501946 -372.163716) (xy 43.473878 -372.146576) (xy 43.465617 -372.14188)
			(xy 43.446954 -372.138372) (xy 43.428291 -372.14188) (xy 43.42003 -372.146576) (xy 43.391971 -372.163733)
			(xy 43.33343 -372.193719) (xy 43.272522 -372.218546) (xy 43.241214 -372.228618) (xy 43.233187 -372.231392)
			(xy 43.219474 -372.241396) (xy 43.209784 -372.255333) (xy 43.207178 -372.263416) (xy 43.199291 -372.289747)
			(xy 43.176915 -372.339952) (xy 43.147567 -372.386427) (xy 43.111854 -372.42821) (xy 43.070516 -372.464437)
			(xy 43.024408 -372.494358) (xy 42.974484 -372.517354) (xy 42.921776 -372.532949) (xy 42.867377 -372.54082)
			(xy 42.839894 -372.541292) (xy 42.812626 -372.540781) (xy 42.758645 -372.53302) (xy 42.706317 -372.517655)
			(xy 42.656709 -372.495) (xy 42.61083 -372.465517) (xy 42.569613 -372.429804) (xy 42.533898 -372.388589)
			(xy 42.504411 -372.342712) (xy 42.481753 -372.293105) (xy 42.466386 -372.240779) (xy 42.45862 -372.186798)
			(xy 42.458132 -372.15953) (xy 42.458457 -372.136309) (xy 42.464063 -372.090206) (xy 42.469308 -372.067582)
			(xy 42.471665 -372.055112) (xy 42.465252 -372.030588) (xy 42.457116 -372.020846) (xy 42.432243 -371.993538)
			(xy 42.387336 -371.934883) (xy 42.367454 -371.903752) (xy 42.3605 -371.89386) (xy 42.339826 -371.881389)
			(xy 42.32783 -371.879876) (xy 42.300658 -371.877426) (xy 42.247344 -371.865863) (xy 42.196219 -371.846827)
			(xy 42.148326 -371.820706) (xy 42.104639 -371.788032) (xy 42.06605 -371.749471) (xy 42.033344 -371.705808)
			(xy 42.007188 -371.657933) (xy 41.988115 -371.606822) (xy 41.976513 -371.553517) (xy 41.972619 -371.499102)
			(xy 3.523996 -371.499102) (xy 3.523996 -379.448822) (xy 6.884924 -379.448822) (xy 6.884924 -374.65)
			(xy 6.885343 -374.63993) (xy 6.893068 -374.621332) (xy 6.89991 -374.613932) (xy 8.250428 -373.263414)
			(xy 8.257826 -373.256571) (xy 8.276427 -373.248852) (xy 8.286496 -373.248428) (xy 32.203898 -373.248428)
			(xy 32.213 -373.248047) (xy 32.230051 -373.241665) (xy 32.237172 -373.235982) (xy 32.308143 -373.175037)
			(xy 32.454602 -373.058616) (xy 32.605967 -372.948649) (xy 32.761952 -372.845341) (xy 32.922267 -372.748888)
			(xy 33.086609 -372.659469) (xy 33.25467 -372.577253) (xy 33.426135 -372.502395) (xy 33.600681 -372.435033)
			(xy 33.777982 -372.375296) (xy 33.957703 -372.323295) (xy 34.139509 -372.279128) (xy 34.323057 -372.242878)
			(xy 34.508003 -372.214613) (xy 34.694 -372.194385) (xy 34.880698 -372.182233) (xy 35.067748 -372.17818)
			(xy 35.254798 -372.182233) (xy 35.441496 -372.194385) (xy 35.627493 -372.214613) (xy 35.812439 -372.242878)
			(xy 35.995987 -372.279128) (xy 36.177793 -372.323295) (xy 36.357514 -372.375296) (xy 36.534815 -372.435033)
			(xy 36.709361 -372.502395) (xy 36.880826 -372.577253) (xy 37.048887 -372.659469) (xy 37.213229 -372.748888)
			(xy 37.373544 -372.845341) (xy 37.529529 -372.948649) (xy 37.680894 -373.058616) (xy 37.827353 -373.175037)
			(xy 37.898324 -373.235982) (xy 37.905448 -373.241662) (xy 37.922496 -373.248048) (xy 37.931598 -373.248428)
			(xy 47.52594 -373.248428) (xy 47.537205 -373.247864) (xy 47.557581 -373.238254) (xy 47.57189 -373.220853)
			(xy 47.575216 -373.210074) (xy 47.575216 -373.20982) (xy 47.582562 -373.182688) (xy 47.604069 -373.130759)
			(xy 47.632962 -373.082547) (xy 47.668618 -373.039097) (xy 47.710263 -373.00135) (xy 47.756996 -372.970121)
			(xy 47.807806 -372.946088) (xy 47.861592 -372.929771) (xy 47.917191 -372.921523) (xy 47.945294 -372.921022)
			(xy 47.972834 -372.921509) (xy 48.027345 -372.929403) (xy 48.080153 -372.945057) (xy 48.13016 -372.968146)
			(xy 48.176325 -372.998188) (xy 48.217689 -373.034559) (xy 48.253389 -373.076502) (xy 48.282684 -373.123145)
			(xy 48.304964 -373.173517) (xy 48.312832 -373.199914) (xy 48.315347 -373.208) (xy 48.324954 -373.221936)
			(xy 48.338614 -373.231932) (xy 48.346614 -373.234712) (xy 48.378364 -373.24538) (xy 48.391318 -373.247666)
			(xy 48.400208 -373.248428) (xy 48.717962 -373.248428) (xy 48.726344 -373.24538) (xy 48.758094 -373.234712)
			(xy 48.770032 -373.230247) (xy 48.787756 -373.211976) (xy 48.791876 -373.199914) (xy 48.799798 -373.173538)
			(xy 48.822095 -373.123184) (xy 48.851397 -373.076557) (xy 48.887096 -373.034626) (xy 48.92845 -372.99826)
			(xy 48.974601 -372.968214) (xy 49.024592 -372.945114) (xy 49.077383 -372.929438) (xy 49.131879 -372.921511)
			(xy 49.159414 -372.921022) (xy 49.18752 -372.921481) (xy 49.243124 -372.929731) (xy 49.296915 -372.946051)
			(xy 49.347729 -372.970087) (xy 49.394467 -373.001319) (xy 49.436116 -373.039071) (xy 49.471774 -373.082526)
			(xy 49.50067 -373.130743) (xy 49.522179 -373.182677) (xy 49.529492 -373.20982) (xy 49.529492 -373.210074)
			(xy 49.532858 -373.220832) (xy 49.547162 -373.238212) (xy 49.567514 -373.247829) (xy 49.578768 -373.248428)
			(xy 52.17414 -373.248428) (xy 52.184213 -373.248825) (xy 52.202811 -373.256565) (xy 52.210208 -373.263414)
			(xy 52.909696 -373.962902) (xy 53.885219 -373.962902) (xy 53.889113 -373.908488) (xy 53.900714 -373.855182)
			(xy 53.919786 -373.804071) (xy 53.945942 -373.756196) (xy 53.978647 -373.712533) (xy 54.017236 -373.673971)
			(xy 54.060922 -373.641296) (xy 54.108816 -373.615175) (xy 54.15994 -373.596138) (xy 54.213254 -373.584574)
			(xy 54.24043 -373.582184) (xy 54.252431 -373.580699) (xy 54.273106 -373.568209) (xy 54.280054 -373.558308)
			(xy 54.299952 -373.527189) (xy 54.344863 -373.46854) (xy 54.369716 -373.441214) (xy 54.375271 -373.434876)
			(xy 54.382161 -373.419505) (xy 54.383645 -373.402725) (xy 54.381908 -373.394478) (xy 54.376661 -373.371855)
			(xy 54.371059 -373.325751) (xy 54.370732 -373.30253) (xy 54.371229 -373.27526) (xy 54.378987 -373.221275)
			(xy 54.394349 -373.168943) (xy 54.417003 -373.11933) (xy 54.446487 -373.073447) (xy 54.482201 -373.032226)
			(xy 54.523418 -372.996509) (xy 54.569299 -372.96702) (xy 54.618909 -372.944362) (xy 54.671239 -372.928995)
			(xy 54.725224 -372.921232) (xy 54.752494 -372.920768) (xy 54.779974 -372.921193) (xy 54.834362 -372.929099)
			(xy 54.887056 -372.94472) (xy 54.936966 -372.967733) (xy 54.983062 -372.997663) (xy 55.024391 -373.033892)
			(xy 55.0601 -373.075671) (xy 55.089451 -373.122138) (xy 55.111838 -373.172332) (xy 55.119778 -373.198644)
			(xy 55.122406 -373.206721) (xy 55.132073 -373.22067) (xy 55.145788 -373.230667) (xy 55.153814 -373.233442)
			(xy 55.185113 -373.24354) (xy 55.246015 -373.268376) (xy 55.304563 -373.298343) (xy 55.33263 -373.315484)
			(xy 55.340891 -373.32018) (xy 55.359554 -373.323688) (xy 55.378217 -373.32018) (xy 55.386478 -373.315484)
			(xy 55.414535 -373.298323) (xy 55.473076 -373.268339) (xy 55.533985 -373.243514) (xy 55.565294 -373.233442)
			(xy 55.573308 -373.230637) (xy 55.58702 -373.220644) (xy 55.596717 -373.206721) (xy 55.59933 -373.198644)
			(xy 55.607274 -373.172333) (xy 55.629648 -373.122133) (xy 55.658992 -373.075662) (xy 55.694698 -373.033881)
			(xy 55.736029 -372.997655) (xy 55.782128 -372.967731) (xy 55.832044 -372.94473) (xy 55.884742 -372.929128)
			(xy 55.939134 -372.921246) (xy 55.966614 -372.920768) (xy 55.993887 -372.921189) (xy 56.047877 -372.928953)
			(xy 56.100212 -372.944323) (xy 56.149827 -372.966984) (xy 56.195712 -372.996476) (xy 56.236933 -373.032198)
			(xy 56.27265 -373.073423) (xy 56.302137 -373.119311) (xy 56.324792 -373.168929) (xy 56.340156 -373.221266)
			(xy 56.347915 -373.275257) (xy 56.348376 -373.30253) (xy 56.348044 -373.325751) (xy 56.342443 -373.371854)
			(xy 56.3372 -373.394478) (xy 56.334868 -373.40695) (xy 56.341264 -373.431471) (xy 56.349392 -373.441214)
			(xy 56.374256 -373.468531) (xy 56.419169 -373.52718) (xy 56.439054 -373.558308) (xy 56.446014 -373.568196)
			(xy 56.466683 -373.580671) (xy 56.478678 -373.582184) (xy 56.505867 -373.584509) (xy 56.559199 -373.596065)
			(xy 56.610343 -373.615097) (xy 56.658255 -373.641218) (xy 56.701959 -373.673896) (xy 56.740564 -373.712465)
			(xy 56.773284 -373.756137) (xy 56.799451 -373.804024) (xy 56.818532 -373.85515) (xy 56.830139 -373.908471)
			(xy 56.834034 -373.962902) (xy 60.692419 -373.962902) (xy 60.696313 -373.908488) (xy 60.707914 -373.855182)
			(xy 60.726986 -373.804071) (xy 60.753142 -373.756196) (xy 60.785847 -373.712533) (xy 60.824436 -373.673971)
			(xy 60.868122 -373.641296) (xy 60.916016 -373.615175) (xy 60.96714 -373.596138) (xy 61.020454 -373.584574)
			(xy 61.04763 -373.582184) (xy 61.059631 -373.580699) (xy 61.080306 -373.568209) (xy 61.087254 -373.558308)
			(xy 61.107152 -373.527189) (xy 61.152063 -373.46854) (xy 61.176916 -373.441214) (xy 61.182471 -373.434876)
			(xy 61.189361 -373.419505) (xy 61.190845 -373.402725) (xy 61.189108 -373.394478) (xy 61.183861 -373.371855)
			(xy 61.178259 -373.325751) (xy 61.177932 -373.30253) (xy 61.178429 -373.27526) (xy 61.186187 -373.221275)
			(xy 61.201549 -373.168943) (xy 61.224203 -373.11933) (xy 61.253687 -373.073447) (xy 61.289401 -373.032226)
			(xy 61.330618 -372.996509) (xy 61.376499 -372.96702) (xy 61.426109 -372.944362) (xy 61.478439 -372.928995)
			(xy 61.532424 -372.921232) (xy 61.559694 -372.920768) (xy 61.587174 -372.921193) (xy 61.641562 -372.929099)
			(xy 61.694256 -372.94472) (xy 61.744166 -372.967733) (xy 61.790262 -372.997663) (xy 61.831591 -373.033892)
			(xy 61.8673 -373.075671) (xy 61.896651 -373.122138) (xy 61.919038 -373.172332) (xy 61.926978 -373.198644)
			(xy 61.929606 -373.206721) (xy 61.939273 -373.22067) (xy 61.952988 -373.230667) (xy 61.961014 -373.233442)
			(xy 61.992313 -373.24354) (xy 62.053215 -373.268376) (xy 62.111763 -373.298343) (xy 62.13983 -373.315484)
			(xy 62.148091 -373.32018) (xy 62.166754 -373.323688) (xy 62.185417 -373.32018) (xy 62.193678 -373.315484)
			(xy 62.221735 -373.298323) (xy 62.280276 -373.268339) (xy 62.341185 -373.243514) (xy 62.372494 -373.233442)
			(xy 62.380508 -373.230637) (xy 62.39422 -373.220644) (xy 62.403917 -373.206721) (xy 62.40653 -373.198644)
			(xy 62.414474 -373.172333) (xy 62.436848 -373.122133) (xy 62.466192 -373.075662) (xy 62.501898 -373.033881)
			(xy 62.543229 -372.997655) (xy 62.589328 -372.967731) (xy 62.639244 -372.94473) (xy 62.691942 -372.929128)
			(xy 62.746334 -372.921246) (xy 62.773814 -372.920768) (xy 62.801087 -372.921189) (xy 62.855077 -372.928953)
			(xy 62.907412 -372.944323) (xy 62.957027 -372.966984) (xy 63.002912 -372.996476) (xy 63.044133 -373.032198)
			(xy 63.07985 -373.073423) (xy 63.109337 -373.119311) (xy 63.131992 -373.168929) (xy 63.147356 -373.221266)
			(xy 63.155115 -373.275257) (xy 63.155576 -373.30253) (xy 63.155244 -373.325751) (xy 63.149643 -373.371854)
			(xy 63.1444 -373.394478) (xy 63.142068 -373.40695) (xy 63.148464 -373.431471) (xy 63.156592 -373.441214)
			(xy 63.181456 -373.468531) (xy 63.226369 -373.52718) (xy 63.246254 -373.558308) (xy 63.253214 -373.568196)
			(xy 63.273883 -373.580671) (xy 63.285878 -373.582184) (xy 63.313067 -373.584509) (xy 63.366399 -373.596065)
			(xy 63.417543 -373.615097) (xy 63.465455 -373.641218) (xy 63.509159 -373.673896) (xy 63.547764 -373.712465)
			(xy 63.580484 -373.756137) (xy 63.606651 -373.804024) (xy 63.625732 -373.85515) (xy 63.637339 -373.908471)
			(xy 63.641234 -373.962902) (xy 63.637338 -374.017333) (xy 63.625731 -374.070654) (xy 63.606649 -374.121779)
			(xy 63.580482 -374.169666) (xy 63.547762 -374.213339) (xy 63.509156 -374.251907) (xy 63.465451 -374.284584)
			(xy 63.417539 -374.310705) (xy 63.366395 -374.329737) (xy 63.313063 -374.341291) (xy 63.285878 -374.343676)
			(xy 63.273882 -374.345182) (xy 63.253206 -374.357658) (xy 63.246254 -374.367552) (xy 63.226351 -374.398669)
			(xy 63.181443 -374.457319) (xy 63.156592 -374.484646) (xy 63.151064 -374.491004) (xy 63.144166 -374.506365)
			(xy 63.14267 -374.523137) (xy 63.1444 -374.531382) (xy 63.14964 -374.554007) (xy 63.155246 -374.600109)
			(xy 63.155576 -374.62333) (xy 63.155103 -374.650599) (xy 63.147338 -374.704583) (xy 63.13197 -374.756912)
			(xy 63.109311 -374.806521) (xy 63.079823 -374.852401) (xy 63.044107 -374.893618) (xy 63.002888 -374.929333)
			(xy 62.957007 -374.958819) (xy 62.907397 -374.981475) (xy 62.855067 -374.996842) (xy 62.801083 -375.004605)
			(xy 62.773814 -375.005092) (xy 62.746336 -375.004617) (xy 62.691952 -374.996713) (xy 62.639262 -374.981096)
			(xy 62.589354 -374.958088) (xy 62.54326 -374.928164) (xy 62.501931 -374.891942) (xy 62.46622 -374.850171)
			(xy 62.436866 -374.803712) (xy 62.414473 -374.753525) (xy 62.40653 -374.727216) (xy 62.403975 -374.719111)
			(xy 62.394278 -374.705163) (xy 62.380533 -374.69518) (xy 62.372494 -374.692418) (xy 62.341197 -374.682313)
			(xy 62.280295 -374.65748) (xy 62.221746 -374.627516) (xy 62.193678 -374.610376) (xy 62.185417 -374.60568)
			(xy 62.166754 -374.602172) (xy 62.148091 -374.60568) (xy 62.13983 -374.610376) (xy 62.111771 -374.627533)
			(xy 62.05323 -374.657519) (xy 61.992322 -374.682346) (xy 61.961014 -374.692418) (xy 61.952987 -374.695192)
			(xy 61.939274 -374.705196) (xy 61.929584 -374.719133) (xy 61.926978 -374.727216) (xy 61.919091 -374.753547)
			(xy 61.896715 -374.803752) (xy 61.867367 -374.850227) (xy 61.831654 -374.89201) (xy 61.790316 -374.928237)
			(xy 61.744208 -374.958158) (xy 61.694284 -374.981154) (xy 61.641576 -374.996749) (xy 61.587177 -375.00462)
			(xy 61.559694 -375.005092) (xy 61.532426 -375.004581) (xy 61.478445 -374.99682) (xy 61.426117 -374.981455)
			(xy 61.376509 -374.9588) (xy 61.33063 -374.929317) (xy 61.289413 -374.893604) (xy 61.253698 -374.852389)
			(xy 61.224211 -374.806512) (xy 61.201553 -374.756905) (xy 61.186186 -374.704579) (xy 61.17842 -374.650598)
			(xy 61.177932 -374.62333) (xy 61.178257 -374.600109) (xy 61.183863 -374.554006) (xy 61.189108 -374.531382)
			(xy 61.191465 -374.518912) (xy 61.185052 -374.494388) (xy 61.176916 -374.484646) (xy 61.152043 -374.457338)
			(xy 61.107136 -374.398683) (xy 61.087254 -374.367552) (xy 61.0803 -374.35766) (xy 61.059626 -374.345189)
			(xy 61.04763 -374.343676) (xy 61.020458 -374.341226) (xy 60.967144 -374.329663) (xy 60.916019 -374.310627)
			(xy 60.868126 -374.284506) (xy 60.824439 -374.251832) (xy 60.78585 -374.213271) (xy 60.753144 -374.169608)
			(xy 60.726988 -374.121733) (xy 60.707915 -374.070622) (xy 60.696313 -374.017317) (xy 60.692419 -373.962902)
			(xy 56.834034 -373.962902) (xy 56.830138 -374.017333) (xy 56.818531 -374.070654) (xy 56.799449 -374.121779)
			(xy 56.773282 -374.169666) (xy 56.740562 -374.213339) (xy 56.701956 -374.251907) (xy 56.658251 -374.284584)
			(xy 56.610339 -374.310705) (xy 56.559195 -374.329737) (xy 56.505863 -374.341291) (xy 56.478678 -374.343676)
			(xy 56.466682 -374.345182) (xy 56.446006 -374.357658) (xy 56.439054 -374.367552) (xy 56.419151 -374.398669)
			(xy 56.374243 -374.457319) (xy 56.349392 -374.484646) (xy 56.343864 -374.491004) (xy 56.336966 -374.506365)
			(xy 56.33547 -374.523137) (xy 56.3372 -374.531382) (xy 56.34244 -374.554007) (xy 56.348046 -374.600109)
			(xy 56.348376 -374.62333) (xy 56.347903 -374.650599) (xy 56.340138 -374.704583) (xy 56.32477 -374.756912)
			(xy 56.302111 -374.806521) (xy 56.272623 -374.852401) (xy 56.236907 -374.893618) (xy 56.195688 -374.929333)
			(xy 56.149807 -374.958819) (xy 56.100197 -374.981475) (xy 56.047867 -374.996842) (xy 55.993883 -375.004605)
			(xy 55.966614 -375.005092) (xy 55.939136 -375.004617) (xy 55.884752 -374.996713) (xy 55.832062 -374.981096)
			(xy 55.782154 -374.958088) (xy 55.73606 -374.928164) (xy 55.694731 -374.891942) (xy 55.65902 -374.850171)
			(xy 55.629666 -374.803712) (xy 55.607273 -374.753525) (xy 55.59933 -374.727216) (xy 55.596775 -374.719111)
			(xy 55.587078 -374.705163) (xy 55.573333 -374.69518) (xy 55.565294 -374.692418) (xy 55.533997 -374.682313)
			(xy 55.473095 -374.65748) (xy 55.414546 -374.627516) (xy 55.386478 -374.610376) (xy 55.378217 -374.60568)
			(xy 55.359554 -374.602172) (xy 55.340891 -374.60568) (xy 55.33263 -374.610376) (xy 55.304571 -374.627533)
			(xy 55.24603 -374.657519) (xy 55.185122 -374.682346) (xy 55.153814 -374.692418) (xy 55.145787 -374.695192)
			(xy 55.132074 -374.705196) (xy 55.122384 -374.719133) (xy 55.119778 -374.727216) (xy 55.111891 -374.753547)
			(xy 55.089515 -374.803752) (xy 55.060167 -374.850227) (xy 55.024454 -374.89201) (xy 54.983116 -374.928237)
			(xy 54.937008 -374.958158) (xy 54.887084 -374.981154) (xy 54.834376 -374.996749) (xy 54.779977 -375.00462)
			(xy 54.752494 -375.005092) (xy 54.725226 -375.004581) (xy 54.671245 -374.99682) (xy 54.618917 -374.981455)
			(xy 54.569309 -374.9588) (xy 54.52343 -374.929317) (xy 54.482213 -374.893604) (xy 54.446498 -374.852389)
			(xy 54.417011 -374.806512) (xy 54.394353 -374.756905) (xy 54.378986 -374.704579) (xy 54.37122 -374.650598)
			(xy 54.370732 -374.62333) (xy 54.371057 -374.600109) (xy 54.376663 -374.554006) (xy 54.381908 -374.531382)
			(xy 54.384265 -374.518912) (xy 54.377852 -374.494388) (xy 54.369716 -374.484646) (xy 54.344843 -374.457338)
			(xy 54.299936 -374.398683) (xy 54.280054 -374.367552) (xy 54.2731 -374.35766) (xy 54.252426 -374.345189)
			(xy 54.24043 -374.343676) (xy 54.213258 -374.341226) (xy 54.159944 -374.329663) (xy 54.108819 -374.310627)
			(xy 54.060926 -374.284506) (xy 54.017239 -374.251832) (xy 53.97865 -374.213271) (xy 53.945944 -374.169608)
			(xy 53.919788 -374.121733) (xy 53.900715 -374.070622) (xy 53.889113 -374.017317) (xy 53.885219 -373.962902)
			(xy 52.909696 -373.962902) (xy 54.678834 -375.73204) (xy 54.685689 -375.739428) (xy 54.693399 -375.758037)
			(xy 54.69382 -375.768108) (xy 54.69382 -383.172208) (xy 54.694214 -383.182232) (xy 54.70189 -383.200753)
			(xy 54.71607 -383.214926) (xy 54.734595 -383.222592) (xy 54.74462 -383.223008) (xy 69.284088 -383.223008)
			(xy 69.294108 -383.222571) (xy 69.312623 -383.214906) (xy 69.326795 -383.20074) (xy 69.334467 -383.182227)
			(xy 69.334888 -383.172208) (xy 69.334888 -370.009928) (xy 69.334393 -369.99956) (xy 69.326121 -369.980543)
			(xy 69.318886 -369.973098) (xy 69.30042 -369.955027) (xy 69.268013 -369.914786) (xy 69.241324 -369.870545)
			(xy 69.22084 -369.823112) (xy 69.213476 -369.798346) (xy 69.210926 -369.790273) (xy 69.201336 -369.776334)
			(xy 69.187689 -369.766332) (xy 69.179694 -369.763548) (xy 69.148486 -369.753477) (xy 69.087756 -369.728723)
			(xy 69.029374 -369.698849) (xy 69.001386 -369.68176) (xy 68.993122 -369.677055) (xy 68.974428 -369.673625)
			(xy 68.955772 -369.677253) (xy 68.947538 -369.682014) (xy 68.919442 -369.699185) (xy 68.860816 -369.729176)
			(xy 68.79982 -369.753994) (xy 68.768468 -369.764056) (xy 68.760428 -369.766809) (xy 68.746689 -369.776797)
			(xy 68.737013 -369.790756) (xy 68.734432 -369.798854) (xy 68.726523 -369.825223) (xy 68.704199 -369.875544)
			(xy 68.674878 -369.922136) (xy 68.639168 -369.964033) (xy 68.597809 -370.000365) (xy 68.55166 -370.030378)
			(xy 68.501677 -370.05345) (xy 68.448899 -370.069103) (xy 68.394419 -370.07701) (xy 68.366894 -370.077492)
			(xy 68.339626 -370.076981) (xy 68.285645 -370.06922) (xy 68.233317 -370.053855) (xy 68.183709 -370.0312)
			(xy 68.13783 -370.001717) (xy 68.096613 -369.966004) (xy 68.060898 -369.924789) (xy 68.031411 -369.878912)
			(xy 68.008753 -369.829305) (xy 67.993386 -369.776979) (xy 67.98562 -369.722998) (xy 67.985132 -369.69573)
			(xy 67.985132 -369.695222) (xy 67.985499 -369.671866) (xy 67.991231 -369.625508) (xy 67.996562 -369.602766)
			(xy 67.998873 -369.590291) (xy 67.992493 -369.565773) (xy 67.98437 -369.55603) (xy 67.959679 -369.528936)
			(xy 67.915022 -369.470798) (xy 67.895216 -369.439952) (xy 67.88828 -369.430044) (xy 67.867593 -369.417582)
			(xy 67.855592 -369.416076) (xy 67.828383 -369.413676) (xy 67.774985 -369.402195) (xy 67.723769 -369.383219)
			(xy 67.675782 -369.357135) (xy 67.632003 -369.324476) (xy 67.593328 -369.28591) (xy 67.560546 -369.242223)
			(xy 67.534327 -369.194309) (xy 67.515207 -369.143147) (xy 67.503576 -369.089781) (xy 67.499673 -369.035302)
			(xy 67.503576 -368.980823) (xy 67.515206 -368.927457) (xy 67.534325 -368.876295) (xy 67.560543 -368.828381)
			(xy 67.593325 -368.784694) (xy 67.632 -368.746126) (xy 67.675778 -368.713467) (xy 67.723765 -368.687383)
			(xy 67.774981 -368.668406) (xy 67.828379 -368.656925) (xy 67.855592 -368.654584) (xy 67.867589 -368.653078)
			(xy 67.888265 -368.640603) (xy 67.895216 -368.630708) (xy 67.915021 -368.599862) (xy 67.959675 -368.541721)
			(xy 67.98437 -368.51463) (xy 67.989921 -368.50829) (xy 67.996807 -368.492919) (xy 67.998295 -368.476141)
			(xy 67.996562 -368.467894) (xy 67.99123 -368.445152) (xy 67.985499 -368.398794) (xy 67.985132 -368.375438)
			(xy 67.985132 -368.37493) (xy 67.985629 -368.34766) (xy 67.993387 -368.293675) (xy 68.008749 -368.241343)
			(xy 68.031403 -368.19173) (xy 68.060887 -368.145847) (xy 68.096601 -368.104626) (xy 68.137818 -368.068909)
			(xy 68.183699 -368.03942) (xy 68.233309 -368.016762) (xy 68.285639 -368.001395) (xy 68.339624 -367.993632)
			(xy 68.366894 -367.993168) (xy 68.394418 -367.993648) (xy 68.448895 -368.001566) (xy 68.501669 -368.017225)
			(xy 68.551648 -368.040301) (xy 68.597796 -368.070314) (xy 68.639155 -368.106643) (xy 68.674868 -368.148535)
			(xy 68.704196 -368.195121) (xy 68.72653 -368.245436) (xy 68.734432 -368.271806) (xy 68.737072 -368.279866)
			(xy 68.746788 -368.293758) (xy 68.760476 -368.303759) (xy 68.768468 -368.306604) (xy 68.79982 -368.316667)
			(xy 68.86081 -368.341497) (xy 68.919439 -368.371481) (xy 68.947538 -368.388646) (xy 68.955793 -368.393347)
			(xy 68.974428 -368.396946) (xy 68.993101 -368.393544) (xy 69.001386 -368.3889) (xy 69.029368 -368.371799)
			(xy 69.087746 -368.341915) (xy 69.148478 -368.31716) (xy 69.179694 -368.307112) (xy 69.191632 -368.302647)
			(xy 69.209356 -368.284376) (xy 69.213476 -368.272314) (xy 69.220822 -368.247541) (xy 69.241289 -368.200095)
			(xy 69.267978 -368.15585) (xy 69.300401 -368.115617) (xy 69.318886 -368.097562) (xy 69.326077 -368.090088)
			(xy 69.334342 -368.071088) (xy 69.334888 -368.060732) (xy 69.334888 -367.864898) (xy 69.335289 -367.854826)
			(xy 69.343024 -367.836227) (xy 69.349874 -367.82883) (xy 70.42404 -366.754918) (xy 70.431434 -366.74807)
			(xy 70.450038 -366.740354) (xy 70.460108 -366.739932) (xy 182.040276 -366.739932) (xy 182.050345 -366.740362)
			(xy 182.068943 -366.748079) (xy 182.076344 -366.754918) (xy 184.63133 -369.30965) (xy 184.638145 -369.31707)
			(xy 184.645878 -369.335654) (xy 184.646316 -369.345718) (xy 184.646316 -373.956834) (xy 282.471114 -373.956834)
			(xy 282.471739 -373.914145) (xy 282.481298 -373.829303) (xy 282.500255 -373.746055) (xy 282.528374 -373.66544)
			(xy 282.565305 -373.588462) (xy 282.587446 -373.551958) (xy 282.592117 -373.543684) (xy 282.595637 -373.525029)
			(xy 282.592138 -373.50637) (xy 282.587446 -373.49811) (xy 282.565303 -373.461607) (xy 282.528357 -373.384633)
			(xy 282.500229 -373.304019) (xy 282.481271 -373.220769) (xy 282.471719 -373.135924) (xy 282.471114 -373.093234)
			(xy 282.47166 -373.053233) (xy 282.480019 -372.97367) (xy 282.496649 -372.895417) (xy 282.521368 -372.81933)
			(xy 282.553904 -372.746245) (xy 282.593902 -372.676961) (xy 282.640924 -372.612237) (xy 282.694453 -372.552783)
			(xy 282.753904 -372.49925) (xy 282.818625 -372.452225) (xy 282.887907 -372.412223) (xy 282.960991 -372.379683)
			(xy 283.037076 -372.35496) (xy 283.115329 -372.338325) (xy 283.194892 -372.329962) (xy 283.234892 -372.329456)
			(xy 283.275327 -372.329955) (xy 283.355745 -372.338503) (xy 283.43481 -372.355493) (xy 283.51164 -372.380736)
			(xy 283.585376 -372.413949) (xy 283.655193 -372.454761) (xy 283.720311 -372.502716) (xy 283.750512 -372.529608)
			(xy 283.758153 -372.536152) (xy 283.777034 -372.543063) (xy 283.797118 -372.542149) (xy 283.806392 -372.538244)
			(xy 283.830255 -372.527496) (xy 283.880344 -372.512327) (xy 283.932116 -372.504666) (xy 283.958284 -372.504208)
			(xy 283.986285 -372.504802) (xy 284.041598 -372.51356) (xy 284.094861 -372.530863) (xy 284.14476 -372.556284)
			(xy 284.190069 -372.589199) (xy 284.229671 -372.628796) (xy 284.262592 -372.6741) (xy 284.28802 -372.723997)
			(xy 284.305329 -372.777257) (xy 284.314095 -372.832569) (xy 284.314646 -372.86057) (xy 284.314081 -372.88807)
			(xy 284.305629 -372.942415) (xy 284.288921 -372.994816) (xy 284.264356 -373.044024) (xy 284.232516 -373.08887)
			(xy 284.19416 -373.128287) (xy 284.1502 -373.161338) (xy 284.10168 -373.187237) (xy 284.049755 -373.205367)
			(xy 284.0228 -373.210836) (xy 284.012957 -373.21306) (xy 283.996044 -373.224043) (xy 283.984646 -373.240679)
			(xy 283.98216 -373.25046) (xy 283.972326 -373.294116) (xy 283.94378 -373.378932) (xy 283.905521 -373.459833)
			(xy 283.882338 -373.49811) (xy 283.877613 -373.506358) (xy 283.874112 -373.525029) (xy 283.877634 -373.543697)
			(xy 283.882338 -373.551958) (xy 283.904004 -373.587611) (xy 283.940308 -373.662731) (xy 283.968217 -373.741357)
			(xy 283.97835 -373.781828) (xy 283.98087 -373.790807) (xy 283.991268 -373.806266) (xy 284.006504 -373.816988)
			(xy 284.015434 -373.819674) (xy 284.04073 -373.826572) (xy 284.089147 -373.846691) (xy 284.134091 -373.873689)
			(xy 284.174594 -373.906983) (xy 284.209779 -373.945853) (xy 284.238888 -373.98946) (xy 284.261292 -374.036863)
			(xy 284.276506 -374.087037) (xy 284.284203 -374.138899) (xy 284.284674 -374.165114) (xy 284.284126 -374.193117)
			(xy 284.275363 -374.248433) (xy 284.258055 -374.301697) (xy 284.232628 -374.351598) (xy 284.199708 -374.396907)
			(xy 284.160106 -374.436509) (xy 284.114796 -374.469429) (xy 284.064895 -374.494855) (xy 284.011631 -374.512163)
			(xy 283.956315 -374.520926) (xy 283.928312 -374.521476) (xy 283.928058 -374.521476) (xy 283.898074 -374.520826)
			(xy 283.838958 -374.510742) (xy 283.810456 -374.50141) (xy 283.801553 -374.498768) (xy 283.78301 -374.499329)
			(xy 283.765892 -374.506484) (xy 283.758894 -374.512586) (xy 283.728487 -374.540473) (xy 283.662696 -374.590269)
			(xy 283.591922 -374.632684) (xy 283.51699 -374.667224) (xy 283.438771 -374.693487) (xy 283.358177 -374.711168)
			(xy 283.276147 -374.720059) (xy 283.234892 -374.720612) (xy 283.194893 -374.720062) (xy 283.115332 -374.711699)
			(xy 283.037081 -374.695067) (xy 282.960997 -374.670346) (xy 282.887915 -374.637807) (xy 282.818633 -374.597808)
			(xy 282.753912 -374.550787) (xy 282.69446 -374.497258) (xy 282.64093 -374.437808) (xy 282.593906 -374.373089)
			(xy 282.553905 -374.303809) (xy 282.521364 -374.230727) (xy 282.49664 -374.154644) (xy 282.480005 -374.076394)
			(xy 282.471639 -373.996833) (xy 282.471114 -373.956834) (xy 184.646316 -373.956834) (xy 184.646316 -377.678385)
			(xy 193.900548 -377.678385) (xy 193.900548 -377.593663) (xy 193.908601 -377.509326) (xy 193.924635 -377.426136)
			(xy 193.948503 -377.344846) (xy 193.979991 -377.266194) (xy 194.018813 -377.190891) (xy 194.064616 -377.119619)
			(xy 194.116987 -377.053023) (xy 194.175452 -376.991708) (xy 194.23948 -376.936227) (xy 194.308492 -376.887084)
			(xy 194.381862 -376.844724) (xy 194.458927 -376.809529) (xy 194.538989 -376.78182) (xy 194.621322 -376.761846)
			(xy 194.705181 -376.749789) (xy 194.789806 -376.745758) (xy 194.874431 -376.749789) (xy 194.95829 -376.761846)
			(xy 195.040623 -376.78182) (xy 195.120685 -376.809529) (xy 195.19775 -376.844724) (xy 195.27112 -376.887084)
			(xy 195.340132 -376.936227) (xy 195.40416 -376.991708) (xy 195.462625 -377.053023) (xy 195.514996 -377.119619)
			(xy 195.560799 -377.190891) (xy 195.599621 -377.266194) (xy 195.631109 -377.344846) (xy 195.654977 -377.426136)
			(xy 195.671011 -377.509326) (xy 195.679064 -377.593663) (xy 195.679568 -377.636024) (xy 195.679064 -377.678385)
			(xy 195.671011 -377.762722) (xy 195.654977 -377.845912) (xy 195.631109 -377.927202) (xy 195.599621 -378.005854)
			(xy 195.560799 -378.081157) (xy 195.514996 -378.152429) (xy 195.47531 -378.202895) (xy 199.443082 -378.202895)
			(xy 199.443082 -378.118173) (xy 199.451135 -378.033836) (xy 199.467169 -377.950646) (xy 199.491037 -377.869356)
			(xy 199.522525 -377.790704) (xy 199.561347 -377.715401) (xy 199.60715 -377.644129) (xy 199.659521 -377.577533)
			(xy 199.717986 -377.516218) (xy 199.782014 -377.460737) (xy 199.851026 -377.411594) (xy 199.924396 -377.369234)
			(xy 200.001461 -377.334039) (xy 200.081523 -377.30633) (xy 200.163856 -377.286356) (xy 200.247715 -377.274299)
			(xy 200.33234 -377.270268) (xy 200.416965 -377.274299) (xy 200.500824 -377.286356) (xy 200.583157 -377.30633)
			(xy 200.663219 -377.334039) (xy 200.740284 -377.369234) (xy 200.813654 -377.411594) (xy 200.882666 -377.460737)
			(xy 200.946694 -377.516218) (xy 201.005159 -377.577533) (xy 201.05753 -377.644129) (xy 201.103333 -377.715401)
			(xy 201.142155 -377.790704) (xy 201.173643 -377.869356) (xy 201.197511 -377.950646) (xy 201.213545 -378.033836)
			(xy 201.221598 -378.118173) (xy 201.222102 -378.160534) (xy 201.221598 -378.202895) (xy 201.213545 -378.287232)
			(xy 201.197511 -378.370422) (xy 201.173643 -378.451712) (xy 201.142155 -378.530364) (xy 201.103333 -378.605667)
			(xy 201.05753 -378.676939) (xy 201.005159 -378.743535) (xy 200.946694 -378.80485) (xy 200.882666 -378.860331)
			(xy 200.813654 -378.909474) (xy 200.740284 -378.951834) (xy 200.663219 -378.987029) (xy 200.583157 -379.014738)
			(xy 200.500824 -379.034712) (xy 200.416965 -379.046769) (xy 200.33234 -379.050801) (xy 200.247715 -379.046769)
			(xy 200.163856 -379.034712) (xy 200.081523 -379.014738) (xy 200.001461 -378.987029) (xy 199.924396 -378.951834)
			(xy 199.851026 -378.909474) (xy 199.782014 -378.860331) (xy 199.717986 -378.80485) (xy 199.659521 -378.743535)
			(xy 199.60715 -378.676939) (xy 199.561347 -378.605667) (xy 199.522525 -378.530364) (xy 199.491037 -378.451712)
			(xy 199.467169 -378.370422) (xy 199.451135 -378.287232) (xy 199.443082 -378.202895) (xy 195.47531 -378.202895)
			(xy 195.462625 -378.219025) (xy 195.40416 -378.28034) (xy 195.340132 -378.335821) (xy 195.27112 -378.384964)
			(xy 195.19775 -378.427324) (xy 195.120685 -378.462519) (xy 195.040623 -378.490228) (xy 194.95829 -378.510202)
			(xy 194.874431 -378.522259) (xy 194.789806 -378.526291) (xy 194.705181 -378.522259) (xy 194.621322 -378.510202)
			(xy 194.538989 -378.490228) (xy 194.458927 -378.462519) (xy 194.381862 -378.427324) (xy 194.308492 -378.384964)
			(xy 194.23948 -378.335821) (xy 194.175452 -378.28034) (xy 194.116987 -378.219025) (xy 194.064616 -378.152429)
			(xy 194.018813 -378.081157) (xy 193.979991 -378.005854) (xy 193.948503 -377.927202) (xy 193.924635 -377.845912)
			(xy 193.908601 -377.762722) (xy 193.900548 -377.678385) (xy 184.646316 -377.678385) (xy 184.646316 -386.496052)
			(xy 184.645888 -386.506121) (xy 184.638171 -386.52472) (xy 184.63133 -386.53212) (xy 182.435816 -388.727385)
			(xy 193.900548 -388.727385) (xy 193.900548 -388.642663) (xy 193.908601 -388.558326) (xy 193.924635 -388.475136)
			(xy 193.948503 -388.393846) (xy 193.979991 -388.315194) (xy 194.018813 -388.239891) (xy 194.064616 -388.168619)
			(xy 194.116987 -388.102023) (xy 194.175452 -388.040708) (xy 194.23948 -387.985227) (xy 194.308492 -387.936084)
			(xy 194.381862 -387.893724) (xy 194.458927 -387.858529) (xy 194.538989 -387.83082) (xy 194.621322 -387.810846)
			(xy 194.705181 -387.798789) (xy 194.789806 -387.794758) (xy 194.874431 -387.798789) (xy 194.95829 -387.810846)
			(xy 195.040623 -387.83082) (xy 195.120685 -387.858529) (xy 195.19775 -387.893724) (xy 195.27112 -387.936084)
			(xy 195.340132 -387.985227) (xy 195.40416 -388.040708) (xy 195.462625 -388.102023) (xy 195.514996 -388.168619)
			(xy 195.560799 -388.239891) (xy 195.599621 -388.315194) (xy 195.631109 -388.393846) (xy 195.654977 -388.475136)
			(xy 195.671011 -388.558326) (xy 195.679064 -388.642663) (xy 195.679568 -388.685024) (xy 195.679064 -388.727385)
			(xy 195.671011 -388.811722) (xy 195.654977 -388.894912) (xy 195.631109 -388.976202) (xy 195.599621 -389.054854)
			(xy 195.560799 -389.130157) (xy 195.514996 -389.201429) (xy 195.462625 -389.268025) (xy 195.40416 -389.32934)
			(xy 195.340132 -389.384821) (xy 195.27112 -389.433964) (xy 195.19775 -389.476324) (xy 195.120685 -389.511519)
			(xy 195.040623 -389.539228) (xy 194.95829 -389.559202) (xy 194.874431 -389.571259) (xy 194.789806 -389.575291)
			(xy 194.705181 -389.571259) (xy 194.621322 -389.559202) (xy 194.538989 -389.539228) (xy 194.458927 -389.511519)
			(xy 194.381862 -389.476324) (xy 194.308492 -389.433964) (xy 194.23948 -389.384821) (xy 194.175452 -389.32934)
			(xy 194.116987 -389.268025) (xy 194.064616 -389.201429) (xy 194.018813 -389.130157) (xy 193.979991 -389.054854)
			(xy 193.948503 -388.976202) (xy 193.924635 -388.894912) (xy 193.908601 -388.811722) (xy 193.900548 -388.727385)
			(xy 182.435816 -388.727385) (xy 182.395622 -388.767574) (xy 182.390796 -388.80034) (xy 182.398416 -388.815072)
			(xy 182.411846 -388.842316) (xy 182.430869 -388.899996) (xy 182.4405 -388.959964) (xy 182.441088 -388.990332)
			(xy 182.441088 -388.990586) (xy 182.440613 -389.018022) (xy 182.43278 -389.07233) (xy 182.417244 -389.124955)
			(xy 182.394328 -389.174811) (xy 182.364502 -389.220868) (xy 182.328384 -389.262175) (xy 182.286719 -389.29788)
			(xy 182.240368 -389.327244) (xy 182.190286 -389.349663) (xy 182.137509 -389.364674) (xy 182.11038 -389.368792)
			(xy 182.101236 -389.370062) (xy 182.08498 -389.378952) (xy 182.028338 -389.44423) (xy 182.022242 -389.461756)
			(xy 182.022496 -389.471154) (xy 182.022496 -389.478012) (xy 182.022033 -389.505264) (xy 182.014275 -389.559213)
			(xy 181.998918 -389.611509) (xy 181.976274 -389.661087) (xy 181.946806 -389.706938) (xy 181.911112 -389.748129)
			(xy 181.869919 -389.78382) (xy 181.824066 -389.813286) (xy 181.774487 -389.835926) (xy 181.72219 -389.85128)
			(xy 181.66824 -389.859035) (xy 181.640988 -389.85952) (xy 181.612444 -389.858973) (xy 181.555994 -389.850464)
			(xy 181.501441 -389.833639) (xy 181.450005 -389.808873) (xy 181.402834 -389.776718) (xy 181.36098 -389.737894)
			(xy 181.325379 -389.693266) (xy 181.296826 -389.643832) (xy 181.285896 -389.617458) (xy 181.280308 -389.60298)
			(xy 181.2544 -389.5852) (xy 180.156866 -389.5852) (xy 180.147008 -389.585579) (xy 180.128711 -389.592904)
			(xy 180.121306 -389.599424) (xy 180.094678 -389.624638) (xy 180.037347 -389.670374) (xy 179.975891 -389.710395)
			(xy 179.910877 -389.744331) (xy 179.842905 -389.77187) (xy 179.772603 -389.792755) (xy 179.700621 -389.806795)
			(xy 179.627623 -389.81386) (xy 179.590954 -389.814308) (xy 179.590446 -389.814308) (xy 179.553776 -389.813898)
			(xy 179.480777 -389.806832) (xy 179.408793 -389.792788) (xy 179.338491 -389.771897) (xy 179.27052 -389.744352)
			(xy 179.205508 -389.710407) (xy 179.144056 -389.670377) (xy 179.086731 -389.62463) (xy 179.060094 -389.599424)
			(xy 179.052659 -389.59295) (xy 179.034382 -389.585618) (xy 179.024534 -389.5852) (xy 170.472608 -389.5852)
			(xy 170.462536 -389.584797) (xy 170.443936 -389.577064) (xy 170.43654 -389.570214) (xy 169.67327 -388.806944)
			(xy 169.665858 -388.80026) (xy 169.647425 -388.792663) (xy 169.627487 -388.792663) (xy 169.609054 -388.80026)
			(xy 169.601642 -388.806944) (xy 169.429684 -388.978902) (xy 169.427144 -388.982712) (xy 169.413777 -389.00151)
			(xy 169.383186 -389.036035) (xy 169.348655 -389.06662) (xy 169.329862 -389.079994) (xy 169.326052 -389.082788)
			(xy 168.884854 -389.523986) (xy 168.877428 -389.530793) (xy 168.858849 -389.538533) (xy 168.848786 -389.538972)
			(xy 167.995854 -389.538972) (xy 167.986393 -389.539399) (xy 167.968773 -389.546294) (xy 167.961564 -389.552434)
			(xy 167.933335 -389.577968) (xy 167.872341 -389.623514) (xy 167.806835 -389.662292) (xy 167.737567 -389.69386)
			(xy 167.665325 -389.717856) (xy 167.590936 -389.734007) (xy 167.515247 -389.742129) (xy 167.439125 -389.742129)
			(xy 167.363436 -389.734007) (xy 167.289047 -389.717856) (xy 167.216805 -389.69386) (xy 167.147537 -389.662292)
			(xy 167.082031 -389.623514) (xy 167.021037 -389.577968) (xy 166.992808 -389.552434) (xy 166.985565 -389.54635)
			(xy 166.967966 -389.539456) (xy 166.958518 -389.538972) (xy 166.137336 -389.538972) (xy 166.111428 -389.557006)
			(xy 166.10584 -389.572246) (xy 166.097401 -389.593961) (xy 166.074924 -389.634766) (xy 166.046512 -389.671685)
			(xy 166.012823 -389.703861) (xy 165.974639 -389.730548) (xy 165.932845 -389.751128) (xy 165.888411 -389.765123)
			(xy 165.842367 -389.772208) (xy 165.819074 -389.772652) (xy 165.795665 -389.772204) (xy 165.749396 -389.765054)
			(xy 165.704761 -389.750924) (xy 165.662806 -389.730146) (xy 165.624515 -389.703208) (xy 165.590784 -389.670739)
			(xy 165.562405 -389.633503) (xy 165.55085 -389.61314) (xy 165.549834 -389.611108) (xy 165.549326 -389.610346)
			(xy 165.151562 -388.922006) (xy 165.139686 -388.899329) (xy 165.122835 -388.850996) (xy 165.114262 -388.800533)
			(xy 165.113716 -388.77494) (xy 165.113716 -388.774432) (xy 165.113819 -388.763151) (xy 165.115471 -388.740649)
			(xy 165.117018 -388.729474) (xy 165.117901 -388.720759) (xy 165.1144 -388.703611) (xy 165.11016 -388.695946)
			(xy 165.071298 -388.631938) (xy 165.057582 -388.620762) (xy 165.048946 -388.617968) (xy 165.025655 -388.60965)
			(xy 164.981925 -388.586551) (xy 164.942485 -388.556713) (xy 164.908365 -388.520913) (xy 164.880455 -388.480086)
			(xy 164.859483 -388.435298) (xy 164.845996 -388.387717) (xy 164.842698 -388.363206) (xy 164.840633 -388.350912)
			(xy 164.826526 -388.330396) (xy 164.815774 -388.32409) (xy 164.776047 -388.302446) (xy 164.701904 -388.250604)
			(xy 164.667946 -388.220712) (xy 164.661088 -388.214362) (xy 164.643308 -388.207504) (xy 164.449252 -388.207504)
			(xy 164.431472 -388.214362) (xy 164.424614 -388.220712) (xy 164.390491 -388.250711) (xy 164.315964 -388.302685)
			(xy 164.276024 -388.324344) (xy 164.267346 -388.32932) (xy 164.254516 -388.344648) (xy 164.251132 -388.354062)
			(xy 164.247068 -388.384796) (xy 164.249862 -388.400036) (xy 164.288978 -388.463282) (xy 164.293902 -388.470694)
			(xy 164.307821 -388.481757) (xy 164.316156 -388.484872) (xy 164.338391 -388.492825) (xy 164.380288 -388.514606)
			(xy 164.418348 -388.542558) (xy 164.451669 -388.576017) (xy 164.479462 -388.614192) (xy 164.490654 -388.634986)
			(xy 164.491162 -388.636256) (xy 164.883592 -389.314944) (xy 164.896306 -389.338272) (xy 164.914407 -389.388215)
			(xy 164.923631 -389.44053) (xy 164.924232 -389.46709) (xy 164.924232 -389.467344) (xy 164.923778 -389.491335)
			(xy 164.916266 -389.538726) (xy 164.901434 -389.584359) (xy 164.879647 -389.62711) (xy 164.851442 -389.665927)
			(xy 164.817512 -389.699855) (xy 164.778693 -389.728058) (xy 164.73594 -389.749842) (xy 164.690307 -389.764671)
			(xy 164.642915 -389.77218) (xy 164.618924 -389.772652) (xy 164.595515 -389.772222) (xy 164.549248 -389.765064)
			(xy 164.504615 -389.750928) (xy 164.462663 -389.730146) (xy 164.424375 -389.703203) (xy 164.390648 -389.670732)
			(xy 164.362273 -389.633493) (xy 164.3507 -389.61314) (xy 164.349684 -389.611108) (xy 164.349176 -389.610346)
			(xy 163.951412 -388.922006) (xy 163.939498 -388.899337) (xy 163.92256 -388.851012) (xy 163.9139 -388.800542)
			(xy 163.913312 -388.77494) (xy 163.913312 -388.774432) (xy 163.913453 -388.763019) (xy 163.915235 -388.740262)
			(xy 163.916868 -388.728966) (xy 163.916868 -388.728712) (xy 163.917775 -388.719998) (xy 163.914256 -388.702848)
			(xy 163.91001 -388.695184) (xy 163.871148 -388.63143) (xy 163.859464 -388.621778) (xy 163.834569 -388.613852)
			(xy 163.787731 -388.590714) (xy 163.745506 -388.559952) (xy 163.709124 -388.522461) (xy 163.679644 -388.479332)
			(xy 163.657922 -388.43182) (xy 163.644592 -388.381307) (xy 163.641786 -388.355332) (xy 163.638448 -388.345535)
			(xy 163.625335 -388.329545) (xy 163.616386 -388.324344) (xy 163.57651 -388.302677) (xy 163.502116 -388.250697)
			(xy 163.46805 -388.220712) (xy 163.461192 -388.214362) (xy 163.443412 -388.207504) (xy 163.249102 -388.207504)
			(xy 163.231322 -388.214362) (xy 163.224464 -388.220712) (xy 163.190555 -388.250525) (xy 163.116541 -388.302239)
			(xy 163.07689 -388.323836) (xy 163.066115 -388.330117) (xy 163.052001 -388.350646) (xy 163.049966 -388.362952)
			(xy 163.048442 -388.374636) (xy 163.047357 -388.383603) (xy 163.050875 -388.401306) (xy 163.0553 -388.40918)
			(xy 163.088828 -388.463282) (xy 163.093734 -388.470707) (xy 163.107666 -388.481764) (xy 163.116006 -388.484872)
			(xy 163.138275 -388.492796) (xy 163.180241 -388.514544) (xy 163.218363 -388.542487) (xy 163.251734 -388.575962)
			(xy 163.279558 -388.61417) (xy 163.290758 -388.634986) (xy 163.291266 -388.636256) (xy 163.683696 -389.314944)
			(xy 163.69641 -389.338271) (xy 163.714511 -389.388215) (xy 163.723735 -389.44053) (xy 163.724336 -389.46709)
			(xy 163.724336 -389.467344) (xy 163.723878 -389.491335) (xy 163.716366 -389.538726) (xy 163.701535 -389.584358)
			(xy 163.679748 -389.627109) (xy 163.651543 -389.665926) (xy 163.617613 -389.699853) (xy 163.578795 -389.728056)
			(xy 163.536043 -389.749841) (xy 163.49041 -389.76467) (xy 163.443019 -389.772179) (xy 163.419028 -389.772652)
			(xy 163.395619 -389.772219) (xy 163.349352 -389.765062) (xy 163.30472 -389.750926) (xy 163.262768 -389.730144)
			(xy 163.22448 -389.703202) (xy 163.190753 -389.670731) (xy 163.162377 -389.633493) (xy 163.150804 -389.61314)
			(xy 163.149788 -389.611108) (xy 163.14928 -389.610346) (xy 162.751516 -388.922006) (xy 162.739602 -388.899337)
			(xy 162.722664 -388.851012) (xy 162.714004 -388.800542) (xy 162.713416 -388.77494) (xy 162.713416 -388.774432)
			(xy 162.713496 -388.763023) (xy 162.715153 -388.740267) (xy 162.716718 -388.728966) (xy 162.717636 -388.720126)
			(xy 162.71414 -388.702718) (xy 162.70986 -388.69493) (xy 162.677094 -388.640828) (xy 162.672135 -388.63333)
			(xy 162.658078 -388.622143) (xy 162.649662 -388.618984) (xy 162.62621 -388.610675) (xy 162.582158 -388.587556)
			(xy 162.542428 -388.557612) (xy 162.508067 -388.521634) (xy 162.479982 -388.480569) (xy 162.458912 -388.4355)
			(xy 162.445414 -388.387616) (xy 162.442144 -388.362952) (xy 162.440132 -388.350643) (xy 162.425989 -388.330132)
			(xy 162.41522 -388.323836) (xy 162.375631 -388.302235) (xy 162.301746 -388.250517) (xy 162.2679 -388.220712)
			(xy 162.261042 -388.214362) (xy 162.243262 -388.207504) (xy 162.049206 -388.207504) (xy 162.031426 -388.214362)
			(xy 162.024568 -388.220712) (xy 161.990439 -388.250705) (xy 161.915917 -388.302682) (xy 161.875978 -388.324344)
			(xy 161.86731 -388.329335) (xy 161.854473 -388.344652) (xy 161.851086 -388.354062) (xy 161.847022 -388.384796)
			(xy 161.849816 -388.400036) (xy 161.888932 -388.463282) (xy 161.893871 -388.470682) (xy 161.90778 -388.481752)
			(xy 161.91611 -388.484872) (xy 161.938337 -388.492846) (xy 161.980235 -388.514622) (xy 162.018297 -388.542568)
			(xy 162.05162 -388.576022) (xy 162.079415 -388.614194) (xy 162.090608 -388.634986) (xy 162.091116 -388.636256)
			(xy 162.483546 -389.314944) (xy 162.496353 -389.338286) (xy 162.51458 -389.388304) (xy 162.523847 -389.440727)
			(xy 162.52444 -389.467344) (xy 162.523979 -389.491322) (xy 162.516475 -389.538688) (xy 162.501659 -389.584298)
			(xy 162.479895 -389.627032) (xy 162.451718 -389.665837) (xy 162.417822 -389.699761) (xy 162.379038 -389.727969)
			(xy 162.336322 -389.749767) (xy 162.290724 -389.764619) (xy 162.243364 -389.77216) (xy 162.219386 -389.772652)
			(xy 162.218878 -389.772652) (xy 162.195469 -389.772201) (xy 162.1492 -389.765051) (xy 162.104566 -389.750922)
			(xy 162.062611 -389.730145) (xy 162.024319 -389.703207) (xy 161.990588 -389.670739) (xy 161.962209 -389.633503)
			(xy 161.950654 -389.61314) (xy 161.949638 -389.611108) (xy 161.94913 -389.610346) (xy 161.551366 -388.922006)
			(xy 161.539491 -388.899329) (xy 161.522639 -388.850996) (xy 161.514066 -388.800533) (xy 161.51352 -388.77494)
			(xy 161.51352 -388.774432) (xy 161.513601 -388.76296) (xy 161.515252 -388.740076) (xy 161.516822 -388.728712)
			(xy 161.518092 -388.719822) (xy 161.51479 -388.702296) (xy 161.471102 -388.63143) (xy 161.459418 -388.621778)
			(xy 161.434514 -388.613879) (xy 161.387677 -388.590734) (xy 161.345454 -388.559967) (xy 161.309074 -388.522471)
			(xy 161.279595 -388.479338) (xy 161.257875 -388.431823) (xy 161.244545 -388.381308) (xy 161.24174 -388.355332)
			(xy 161.238464 -388.345555) (xy 161.22549 -388.329556) (xy 161.216594 -388.324344) (xy 161.202439 -388.316827)
			(xy 161.174742 -388.300693) (xy 161.161222 -388.292086) (xy 161.153378 -388.287464) (xy 161.13561 -388.283553)
			(xy 161.117591 -388.286066) (xy 161.109406 -388.290054) (xy 161.03092 -388.33298) (xy 161.023114 -388.337631)
			(xy 161.0112 -388.351334) (xy 161.004861 -388.36835) (xy 161.004504 -388.37743) (xy 161.004504 -388.818374)
			(xy 161.004738 -388.825035) (xy 161.008216 -388.837897) (xy 161.011362 -388.843774) (xy 161.28365 -389.314944)
			(xy 161.296457 -389.338285) (xy 161.314684 -389.388304) (xy 161.323951 -389.440726) (xy 161.324544 -389.467344)
			(xy 161.324107 -389.492284) (xy 161.316008 -389.5415) (xy 161.300016 -389.588746) (xy 161.276557 -389.632764)
			(xy 161.246255 -389.672383) (xy 161.209915 -389.706549) (xy 161.168505 -389.734354) (xy 161.123126 -389.755057)
			(xy 161.074985 -389.768109) (xy 161.050224 -389.771128) (xy 161.04997 -389.771128) (xy 161.040726 -389.772505)
			(xy 161.024099 -389.781009) (xy 161.011614 -389.794899) (xy 161.004924 -389.812336) (xy 161.004504 -389.821674)
			(xy 161.004504 -392.303) (xy 161.007044 -392.310874) (xy 161.01579 -392.339616) (xy 161.025228 -392.398946)
			(xy 161.02584 -392.428984) (xy 161.02584 -393.292838) (xy 161.46272 -393.292838) (xy 161.46272 -392.429238)
			(xy 161.463206 -392.401987) (xy 161.470962 -392.348039) (xy 161.486317 -392.295744) (xy 161.508959 -392.246167)
			(xy 161.538425 -392.200317) (xy 161.574116 -392.159126) (xy 161.615307 -392.123435) (xy 161.661157 -392.093969)
			(xy 161.710734 -392.071327) (xy 161.763029 -392.055972) (xy 161.816977 -392.048216) (xy 161.871479 -392.048216)
			(xy 161.925427 -392.055972) (xy 161.977722 -392.071327) (xy 162.027299 -392.093969) (xy 162.073149 -392.123435)
			(xy 162.11434 -392.159126) (xy 162.150031 -392.200317) (xy 162.179497 -392.246167) (xy 162.202139 -392.295744)
			(xy 162.217494 -392.348039) (xy 162.22525 -392.401987) (xy 162.225736 -392.429238) (xy 162.225736 -393.292838)
			(xy 162.662616 -393.292838) (xy 162.662616 -392.429238) (xy 162.663102 -392.401987) (xy 162.670858 -392.348039)
			(xy 162.686213 -392.295744) (xy 162.708855 -392.246167) (xy 162.738321 -392.200317) (xy 162.774012 -392.159126)
			(xy 162.815203 -392.123435) (xy 162.861053 -392.093969) (xy 162.91063 -392.071327) (xy 162.962925 -392.055972)
			(xy 163.016873 -392.048216) (xy 163.071375 -392.048216) (xy 163.125323 -392.055972) (xy 163.177618 -392.071327)
			(xy 163.227195 -392.093969) (xy 163.273045 -392.123435) (xy 163.314236 -392.159126) (xy 163.349927 -392.200317)
			(xy 163.379393 -392.246167) (xy 163.402035 -392.295744) (xy 163.41739 -392.348039) (xy 163.425146 -392.401987)
			(xy 163.425632 -392.429238) (xy 163.425632 -393.292838) (xy 163.862512 -393.292838) (xy 163.862512 -392.429238)
			(xy 163.862998 -392.401969) (xy 163.87076 -392.347985) (xy 163.886125 -392.295655) (xy 163.908782 -392.246045)
			(xy 163.938268 -392.200164) (xy 163.973983 -392.158947) (xy 164.0152 -392.123232) (xy 164.061081 -392.093746)
			(xy 164.110691 -392.071089) (xy 164.163021 -392.055724) (xy 164.217005 -392.047962) (xy 164.271543 -392.047962)
			(xy 164.325527 -392.055724) (xy 164.377857 -392.071089) (xy 164.427467 -392.093746) (xy 164.473348 -392.123232)
			(xy 164.514565 -392.158947) (xy 164.55028 -392.200164) (xy 164.579766 -392.246045) (xy 164.602423 -392.295655)
			(xy 164.617788 -392.347985) (xy 164.62555 -392.401969) (xy 164.626036 -392.429238) (xy 164.626036 -393.292838)
			(xy 165.062408 -393.292838) (xy 165.062408 -392.429238) (xy 165.062894 -392.401969) (xy 165.070656 -392.347985)
			(xy 165.086021 -392.295655) (xy 165.108678 -392.246045) (xy 165.138164 -392.200164) (xy 165.173879 -392.158947)
			(xy 165.215096 -392.123232) (xy 165.260977 -392.093746) (xy 165.310587 -392.071089) (xy 165.362917 -392.055724)
			(xy 165.416901 -392.047962) (xy 165.471439 -392.047962) (xy 165.525423 -392.055724) (xy 165.577753 -392.071089)
			(xy 165.627363 -392.093746) (xy 165.673244 -392.123232) (xy 165.714461 -392.158947) (xy 165.750176 -392.200164)
			(xy 165.779662 -392.246045) (xy 165.802319 -392.295655) (xy 165.817684 -392.347985) (xy 165.825446 -392.401969)
			(xy 165.825932 -392.429238) (xy 165.825932 -393.292838) (xy 165.825446 -393.320107) (xy 165.817684 -393.374091)
			(xy 165.802319 -393.426421) (xy 165.779662 -393.476031) (xy 165.750176 -393.521912) (xy 165.714461 -393.563129)
			(xy 165.673244 -393.598844) (xy 165.627363 -393.62833) (xy 165.577753 -393.650987) (xy 165.525423 -393.666352)
			(xy 165.471439 -393.674114) (xy 165.416901 -393.674114) (xy 165.362917 -393.666352) (xy 165.310587 -393.650987)
			(xy 165.260977 -393.62833) (xy 165.215096 -393.598844) (xy 165.173879 -393.563129) (xy 165.138164 -393.521912)
			(xy 165.108678 -393.476031) (xy 165.086021 -393.426421) (xy 165.070656 -393.374091) (xy 165.062894 -393.320107)
			(xy 165.062408 -393.292838) (xy 164.626036 -393.292838) (xy 164.62555 -393.320107) (xy 164.617788 -393.374091)
			(xy 164.602423 -393.426421) (xy 164.579766 -393.476031) (xy 164.55028 -393.521912) (xy 164.514565 -393.563129)
			(xy 164.473348 -393.598844) (xy 164.427467 -393.62833) (xy 164.377857 -393.650987) (xy 164.325527 -393.666352)
			(xy 164.271543 -393.674114) (xy 164.217005 -393.674114) (xy 164.163021 -393.666352) (xy 164.110691 -393.650987)
			(xy 164.061081 -393.62833) (xy 164.0152 -393.598844) (xy 163.973983 -393.563129) (xy 163.938268 -393.521912)
			(xy 163.908782 -393.476031) (xy 163.886125 -393.426421) (xy 163.87076 -393.374091) (xy 163.862998 -393.320107)
			(xy 163.862512 -393.292838) (xy 163.425632 -393.292838) (xy 163.425146 -393.320089) (xy 163.41739 -393.374037)
			(xy 163.402035 -393.426332) (xy 163.379393 -393.475909) (xy 163.349927 -393.521759) (xy 163.314236 -393.56295)
			(xy 163.273045 -393.598641) (xy 163.227195 -393.628107) (xy 163.177618 -393.650749) (xy 163.125323 -393.666104)
			(xy 163.071375 -393.67386) (xy 163.016873 -393.67386) (xy 162.962925 -393.666104) (xy 162.91063 -393.650749)
			(xy 162.861053 -393.628107) (xy 162.815203 -393.598641) (xy 162.774012 -393.56295) (xy 162.738321 -393.521759)
			(xy 162.708855 -393.475909) (xy 162.686213 -393.426332) (xy 162.670858 -393.374037) (xy 162.663102 -393.320089)
			(xy 162.662616 -393.292838) (xy 162.225736 -393.292838) (xy 162.22525 -393.320089) (xy 162.217494 -393.374037)
			(xy 162.202139 -393.426332) (xy 162.179497 -393.475909) (xy 162.150031 -393.521759) (xy 162.11434 -393.56295)
			(xy 162.073149 -393.598641) (xy 162.027299 -393.628107) (xy 161.977722 -393.650749) (xy 161.925427 -393.666104)
			(xy 161.871479 -393.67386) (xy 161.816977 -393.67386) (xy 161.763029 -393.666104) (xy 161.710734 -393.650749)
			(xy 161.661157 -393.628107) (xy 161.615307 -393.598641) (xy 161.574116 -393.56295) (xy 161.538425 -393.521759)
			(xy 161.508959 -393.475909) (xy 161.486317 -393.426332) (xy 161.470962 -393.374037) (xy 161.463206 -393.320089)
			(xy 161.46272 -393.292838) (xy 161.02584 -393.292838) (xy 161.02584 -393.293092) (xy 161.025273 -393.323133)
			(xy 161.015831 -393.382469) (xy 161.007044 -393.411202) (xy 161.004504 -393.419076) (xy 161.004504 -397.747236)
			(xy 161.004883 -397.757311) (xy 161.012633 -397.77591) (xy 161.01949 -397.783304) (xy 161.736278 -398.499838)
			(xy 161.744744 -398.507519) (xy 161.766262 -398.515154) (xy 161.77768 -398.51457) (xy 161.868104 -398.504664)
			(xy 161.887662 -398.492726) (xy 161.893758 -398.48282) (xy 161.914719 -398.450841) (xy 161.962093 -398.390818)
			(xy 162.015238 -398.335839) (xy 162.073621 -398.286458) (xy 162.136655 -398.24317) (xy 162.203706 -398.206411)
			(xy 162.2741 -398.17655) (xy 162.347131 -398.153887) (xy 162.422063 -398.13865) (xy 162.498145 -398.130992)
			(xy 162.536378 -398.130522) (xy 162.576287 -398.131025) (xy 162.655667 -398.139367) (xy 162.73374 -398.15596)
			(xy 162.809651 -398.180623) (xy 162.882568 -398.213087) (xy 162.951692 -398.252995) (xy 163.016266 -398.29991)
			(xy 163.075582 -398.353318) (xy 163.12899 -398.412634) (xy 163.175905 -398.477208) (xy 163.215813 -398.546332)
			(xy 163.248277 -398.619249) (xy 163.27294 -398.69516) (xy 163.289533 -398.773233) (xy 163.297875 -398.852613)
			(xy 163.298378 -398.892522) (xy 163.297844 -398.932367) (xy 163.289537 -399.011624) (xy 163.273005 -399.089581)
			(xy 163.248429 -399.165387) (xy 163.216078 -399.238215) (xy 163.176303 -399.30727) (xy 163.12954 -399.371798)
			(xy 163.103306 -399.401792) (xy 163.095912 -399.410721) (xy 163.089434 -399.432958) (xy 163.09086 -399.444464)
			(xy 163.096084 -399.476658) (xy 163.101681 -399.541645) (xy 163.102036 -399.574258) (xy 163.101566 -399.611548)
			(xy 163.094226 -399.685768) (xy 163.07966 -399.758913) (xy 163.06927 -399.79473) (xy 163.06927 -399.795238)
			(xy 163.067031 -399.804067) (xy 163.068306 -399.822227) (xy 163.075823 -399.838807) (xy 163.08197 -399.84553)
			(xy 165.362382 -402.126196) (xy 165.36921 -402.133605) (xy 165.376938 -402.152197) (xy 165.377368 -402.162264)
			(xy 165.377368 -404.885605) (xy 166.678094 -404.885605) (xy 166.678094 -404.699771) (xy 166.686089 -404.514108)
			(xy 166.702064 -404.328962) (xy 166.72599 -404.144674) (xy 166.757822 -403.961586) (xy 166.797502 -403.780037)
			(xy 166.844955 -403.600363) (xy 166.900095 -403.422897) (xy 166.962818 -403.247968) (xy 167.033009 -403.075899)
			(xy 167.110538 -402.90701) (xy 167.195261 -402.741612) (xy 167.287022 -402.580012) (xy 167.38565 -402.42251)
			(xy 167.490963 -402.269396) (xy 167.602765 -402.120956) (xy 167.72085 -401.977462) (xy 167.845 -401.839182)
			(xy 167.974983 -401.706371) (xy 168.11056 -401.579275) (xy 168.25148 -401.45813) (xy 168.39748 -401.343159)
			(xy 168.548292 -401.234576) (xy 168.703636 -401.132583) (xy 168.863224 -401.037366) (xy 169.026761 -400.949104)
			(xy 169.193943 -400.867959) (xy 169.364462 -400.794082) (xy 169.538001 -400.727609) (xy 169.71424 -400.668664)
			(xy 169.892851 -400.617356) (xy 170.073504 -400.573779) (xy 170.255865 -400.538015) (xy 170.439595 -400.510129)
			(xy 170.624355 -400.490174) (xy 170.809802 -400.478186) (xy 170.995594 -400.474188) (xy 171.181386 -400.478186)
			(xy 171.366833 -400.490174) (xy 171.551593 -400.510129) (xy 171.735323 -400.538015) (xy 171.917684 -400.573779)
			(xy 172.098337 -400.617356) (xy 172.276948 -400.668664) (xy 172.453187 -400.727609) (xy 172.626726 -400.794082)
			(xy 172.797245 -400.867959) (xy 172.964427 -400.949104) (xy 173.127964 -401.037366) (xy 173.287552 -401.132583)
			(xy 173.442896 -401.234576) (xy 173.593708 -401.343159) (xy 173.739708 -401.45813) (xy 173.880628 -401.579275)
			(xy 174.016205 -401.706371) (xy 174.146188 -401.839182) (xy 174.270338 -401.977462) (xy 174.388423 -402.120956)
			(xy 174.500225 -402.269396) (xy 174.605538 -402.42251) (xy 174.704166 -402.580012) (xy 174.795927 -402.741612)
			(xy 174.88065 -402.90701) (xy 174.958179 -403.075899) (xy 175.02837 -403.247968) (xy 175.091093 -403.422897)
			(xy 175.146233 -403.600363) (xy 175.193686 -403.780037) (xy 175.233366 -403.961586) (xy 175.265198 -404.144674)
			(xy 175.289124 -404.328962) (xy 175.305099 -404.514108) (xy 175.313094 -404.699771) (xy 175.313594 -404.792688)
			(xy 175.313094 -404.885605) (xy 175.305099 -405.071268) (xy 175.289124 -405.256414) (xy 175.265198 -405.440702)
			(xy 175.233366 -405.62379) (xy 175.193686 -405.805339) (xy 175.146233 -405.985013) (xy 175.091093 -406.162479)
			(xy 175.02837 -406.337408) (xy 174.958179 -406.509477) (xy 174.88065 -406.678366) (xy 174.795927 -406.843764)
			(xy 174.704166 -407.005364) (xy 174.605538 -407.162866) (xy 174.500225 -407.31598) (xy 174.388423 -407.46442)
			(xy 174.270338 -407.607914) (xy 174.146188 -407.746194) (xy 174.016205 -407.879005) (xy 173.880628 -408.006101)
			(xy 173.739708 -408.127246) (xy 173.593708 -408.242217) (xy 173.442896 -408.3508) (xy 173.287552 -408.452793)
			(xy 173.127964 -408.54801) (xy 172.964427 -408.636272) (xy 172.797245 -408.717417) (xy 172.626726 -408.791294)
			(xy 172.453187 -408.857767) (xy 172.276948 -408.916712) (xy 172.098337 -408.96802) (xy 171.917684 -409.011597)
			(xy 171.735323 -409.047361) (xy 171.551593 -409.075247) (xy 171.366833 -409.095202) (xy 171.181386 -409.10719)
			(xy 170.995594 -409.111188) (xy 170.809802 -409.10719) (xy 170.624355 -409.095202) (xy 170.439595 -409.075247)
			(xy 170.255865 -409.047361) (xy 170.073504 -409.011597) (xy 169.892851 -408.96802) (xy 169.71424 -408.916712)
			(xy 169.538001 -408.857767) (xy 169.364462 -408.791294) (xy 169.193943 -408.717417) (xy 169.026761 -408.636272)
			(xy 168.863224 -408.54801) (xy 168.703636 -408.452793) (xy 168.548292 -408.3508) (xy 168.39748 -408.242217)
			(xy 168.25148 -408.127246) (xy 168.11056 -408.006101) (xy 167.974983 -407.879005) (xy 167.845 -407.746194)
			(xy 167.72085 -407.607914) (xy 167.602765 -407.46442) (xy 167.490963 -407.31598) (xy 167.38565 -407.162866)
			(xy 167.287022 -407.005364) (xy 167.195261 -406.843764) (xy 167.110538 -406.678366) (xy 167.033009 -406.509477)
			(xy 166.962818 -406.337408) (xy 166.900095 -406.162479) (xy 166.844955 -405.985013) (xy 166.797502 -405.805339)
			(xy 166.757822 -405.62379) (xy 166.72599 -405.440702) (xy 166.702064 -405.256414) (xy 166.686089 -405.071268)
			(xy 166.678094 -404.885605) (xy 165.377368 -404.885605) (xy 165.377368 -409.640024) (xy 165.377739 -409.648939)
			(xy 165.383856 -409.665688) (xy 165.395342 -409.679327) (xy 165.410806 -409.688205) (xy 165.419532 -409.690062)
			(xy 165.419786 -409.690062) (xy 165.45734 -409.696926) (xy 165.530933 -409.717249) (xy 165.602127 -409.744825)
			(xy 165.670208 -409.779379) (xy 165.734495 -409.820563) (xy 165.794343 -409.867967) (xy 165.849155 -409.921114)
			(xy 165.898381 -409.979473) (xy 165.941527 -410.04246) (xy 165.978163 -410.109444) (xy 166.00792 -410.179753)
			(xy 166.030502 -410.252685) (xy 166.045681 -410.327508) (xy 166.053307 -410.403474) (xy 166.05377 -410.441648)
			(xy 166.05377 -410.441902) (xy 166.053256 -410.482152) (xy 166.044743 -410.562202) (xy 166.027844 -410.64091)
			(xy 166.005717 -410.708348) (xy 183.940958 -410.708348) (xy 183.940958 -400.09572) (xy 183.941483 -400.070772)
			(xy 183.94929 -400.021491) (xy 183.964701 -399.974034) (xy 183.987336 -399.929568) (xy 184.01664 -399.889183)
			(xy 184.033922 -399.871184) (xy 184.239408 -399.665698) (xy 184.257395 -399.648399) (xy 184.297773 -399.619076)
			(xy 184.342241 -399.59643) (xy 184.389704 -399.581018) (xy 184.438993 -399.57322) (xy 184.463944 -399.572734)
			(xy 188.119004 -399.572734) (xy 188.143952 -399.57325) (xy 188.193234 -399.581061) (xy 188.24069 -399.596474)
			(xy 188.285156 -399.619111) (xy 188.32554 -399.648416) (xy 188.34354 -399.665698) (xy 188.362082 -399.684494)
			(xy 188.369495 -399.691318) (xy 188.388084 -399.699047) (xy 188.39815 -399.69948) (xy 188.444124 -399.69948)
			(xy 188.454131 -399.699968) (xy 188.472619 -399.707632) (xy 188.486771 -399.721784) (xy 188.494433 -399.740273)
			(xy 188.494924 -399.75028) (xy 188.494924 -399.796) (xy 188.495459 -399.805899) (xy 188.503018 -399.8242)
			(xy 188.509656 -399.83156) (xy 188.528452 -399.85061) (xy 188.545762 -399.868588) (xy 188.575091 -399.908966)
			(xy 188.597741 -399.953436) (xy 188.613156 -400.000901) (xy 188.620956 -400.050193) (xy 188.621416 -400.075146)
			(xy 188.621416 -402.753322) (xy 188.621826 -402.763393) (xy 188.629557 -402.781991) (xy 188.636402 -402.78939)
			(xy 191.190372 -405.34336) (xy 191.197792 -405.350175) (xy 191.216376 -405.35791) (xy 191.22644 -405.358346)
			(xy 195.26631 -405.358346) (xy 195.276382 -405.35794) (xy 195.29498 -405.350207) (xy 195.302378 -405.34336)
			(xy 197.179184 -403.466554) (xy 197.185991 -403.459128) (xy 197.193731 -403.440549) (xy 197.19417 -403.430486)
			(xy 197.19417 -400.104356) (xy 197.194651 -400.079406) (xy 197.202469 -400.030123) (xy 197.217889 -399.982665)
			(xy 197.240534 -399.9382) (xy 197.269848 -399.897818) (xy 197.287134 -399.87982) (xy 197.53961 -399.627344)
			(xy 197.557604 -399.610052) (xy 197.597979 -399.580727) (xy 197.642445 -399.558078) (xy 197.689907 -399.542665)
			(xy 197.739195 -399.534866) (xy 197.764146 -399.53438) (xy 201.33818 -399.53438) (xy 201.363128 -399.534898)
			(xy 201.41241 -399.542706) (xy 201.459867 -399.558118) (xy 201.504334 -399.580755) (xy 201.544717 -399.610061)
			(xy 201.562716 -399.627344) (xy 201.823066 -399.887694) (xy 201.840352 -399.905693) (xy 201.869678 -399.946068)
			(xy 201.892327 -399.990532) (xy 201.907742 -400.037992) (xy 201.915543 -400.08728) (xy 201.91603 -400.11223)
			(xy 201.91603 -403.422612) (xy 201.916441 -403.432683) (xy 201.924171 -403.451281) (xy 201.931016 -403.45868)
			(xy 202.036172 -403.563836) (xy 202.053479 -403.581816) (xy 202.082802 -403.622195) (xy 202.105447 -403.666665)
			(xy 202.120857 -403.714129) (xy 202.128652 -403.76342) (xy 202.129136 -403.788372) (xy 202.129136 -406.516078)
			(xy 202.129564 -406.526147) (xy 202.137282 -406.544745) (xy 202.144122 -406.552146) (xy 203.1365 -407.544524)
			(xy 203.14386 -407.551203) (xy 203.162204 -407.558804) (xy 203.18206 -407.55887) (xy 203.200455 -407.551392)
			(xy 203.207874 -407.544778) (xy 203.208128 -407.544524) (xy 203.234897 -407.518495) (xy 203.292695 -407.47122)
			(xy 203.354838 -407.429822) (xy 203.420731 -407.3947) (xy 203.489743 -407.366189) (xy 203.561212 -407.344564)
			(xy 203.634454 -407.33003) (xy 203.708765 -407.322729) (xy 203.7461 -407.322274) (xy 203.784342 -407.322756)
			(xy 203.860439 -407.330431) (xy 203.935385 -407.345686) (xy 204.008428 -407.368366) (xy 204.078834 -407.398244)
			(xy 204.145896 -407.435019) (xy 204.20894 -407.478323) (xy 204.267332 -407.527719) (xy 204.320487 -407.582713)
			(xy 204.367869 -407.642751) (xy 204.409004 -407.70723) (xy 204.443479 -407.775504) (xy 204.470945 -407.846885)
			(xy 204.491129 -407.920657) (xy 204.49794 -407.95829) (xy 204.499688 -407.967077) (xy 204.508531 -407.982651)
			(xy 204.522201 -407.994222) (xy 204.539023 -408.000371) (xy 204.547978 -408.000708) (xy 205.795372 -408.000708)
			(xy 205.805443 -408.000292) (xy 205.824042 -407.992567) (xy 205.83144 -407.985722) (xy 207.658716 -406.158446)
			(xy 207.66553 -406.151026) (xy 207.673264 -406.132442) (xy 207.673702 -406.122378) (xy 207.673702 -403.722586)
			(xy 207.674193 -403.697637) (xy 207.682006 -403.648353) (xy 207.697424 -403.600896) (xy 207.720068 -403.55643)
			(xy 207.74938 -403.516048) (xy 207.766666 -403.49805) (xy 207.847184 -403.417532) (xy 207.854 -403.410113)
			(xy 207.861735 -403.391528) (xy 207.86217 -403.381464) (xy 207.86217 -400.079464) (xy 207.862656 -400.054515)
			(xy 207.870472 -400.005231) (xy 207.885892 -399.957774) (xy 207.908536 -399.913308) (xy 207.937848 -399.872926)
			(xy 207.955134 -399.854928) (xy 208.201514 -399.608548) (xy 208.21949 -399.591236) (xy 208.259869 -399.561908)
			(xy 208.304339 -399.539258) (xy 208.351805 -399.523843) (xy 208.401097 -399.516044) (xy 208.42605 -399.515584)
			(xy 211.971128 -399.515584) (xy 211.996077 -399.516071) (xy 212.045361 -399.523886) (xy 212.092818 -399.539306)
			(xy 212.137284 -399.561949) (xy 212.177666 -399.591262) (xy 212.195664 -399.608548) (xy 212.507576 -399.92046)
			(xy 212.524847 -399.938473) (xy 212.554175 -399.978843) (xy 212.576826 -400.023305) (xy 212.592245 -400.070762)
			(xy 212.600051 -400.120047) (xy 212.60054 -400.144996) (xy 212.60054 -403.480016) (xy 212.600947 -403.490088)
			(xy 212.608679 -403.508686) (xy 212.615526 -403.516084) (xy 212.638894 -403.539452) (xy 212.656213 -403.557421)
			(xy 212.685533 -403.597804) (xy 212.708176 -403.642276) (xy 212.723583 -403.689743) (xy 212.731376 -403.739036)
			(xy 212.731858 -403.763988) (xy 212.731858 -406.258014) (xy 212.732261 -406.268086) (xy 212.739995 -406.286685)
			(xy 212.746844 -406.294082) (xy 213.909148 -407.456386) (xy 213.918075 -407.464228) (xy 213.940643 -407.471552)
			(xy 213.964107 -407.468029) (xy 213.974172 -407.46172) (xy 214.00639 -407.439635) (xy 214.074493 -407.401378)
			(xy 214.146148 -407.370278) (xy 214.220606 -407.346659) (xy 214.297086 -407.330769) (xy 214.374789 -407.322775)
			(xy 214.413846 -407.322274) (xy 214.4141 -407.322274) (xy 214.453201 -407.322745) (xy 214.530992 -407.330766)
			(xy 214.607553 -407.346704) (xy 214.682083 -407.370392) (xy 214.753797 -407.40158) (xy 214.821945 -407.439942)
			(xy 214.88581 -407.485074) (xy 214.944722 -407.536504) (xy 214.998064 -407.593691) (xy 215.045275 -407.656036)
			(xy 215.085859 -407.722884) (xy 215.119392 -407.793533) (xy 215.14552 -407.867242) (xy 215.16397 -407.943237)
			(xy 215.16975 -407.981912) (xy 215.17229 -408.000962) (xy 215.200738 -408.025854) (xy 216.38895 -408.025854)
			(xy 216.399018 -408.025415) (xy 216.417617 -408.017705) (xy 216.425018 -408.010868) (xy 218.335098 -406.100788)
			(xy 218.341936 -406.093386) (xy 218.349657 -406.074788) (xy 218.350084 -406.06472) (xy 218.350084 -403.755606)
			(xy 218.350592 -403.730657) (xy 218.358403 -403.681375) (xy 218.373817 -403.633918) (xy 218.396456 -403.589452)
			(xy 218.425764 -403.549069) (xy 218.443048 -403.53107) (xy 218.50731 -403.466808) (xy 218.51414 -403.4594)
			(xy 218.521865 -403.440807) (xy 218.522296 -403.43074) (xy 218.522296 -400.095974) (xy 218.522781 -400.071024)
			(xy 218.530596 -400.021741) (xy 218.546016 -399.974283) (xy 218.56866 -399.929817) (xy 218.597974 -399.889436)
			(xy 218.61526 -399.871438) (xy 218.820746 -399.665952) (xy 218.838709 -399.648625) (xy 218.879091 -399.619299)
			(xy 218.923564 -399.596652) (xy 218.971033 -399.581241) (xy 219.020328 -399.573446) (xy 219.045282 -399.572988)
			(xy 222.709232 -399.572988) (xy 222.734182 -399.573471) (xy 222.783465 -399.581288) (xy 222.830923 -399.596707)
			(xy 222.875388 -399.619352) (xy 222.91577 -399.648666) (xy 222.933768 -399.665952) (xy 223.130618 -399.862802)
			(xy 223.147917 -399.880789) (xy 223.177239 -399.921168) (xy 223.199885 -399.965636) (xy 223.215297 -400.013098)
			(xy 223.223096 -400.062387) (xy 223.223582 -400.087338) (xy 223.223582 -403.455124) (xy 223.223973 -403.465198)
			(xy 223.231716 -403.483796) (xy 223.238568 -403.491192) (xy 223.323658 -403.576282) (xy 223.340937 -403.594288)
			(xy 223.370264 -403.63466) (xy 223.392915 -403.679123) (xy 223.408331 -403.726582) (xy 223.416134 -403.775868)
			(xy 223.416622 -403.800818) (xy 223.416622 -406.262078) (xy 223.417053 -406.272147) (xy 223.424769 -406.290745)
			(xy 223.431608 -406.298146) (xy 224.597722 -407.46426) (xy 224.634044 -407.467308) (xy 224.649284 -407.456894)
			(xy 224.681129 -407.435538) (xy 224.748312 -407.398577) (xy 224.818867 -407.368551) (xy 224.892082 -407.345763)
			(xy 224.967215 -407.330443) (xy 225.043506 -407.322747) (xy 225.081846 -407.322274) (xy 225.0821 -407.322274)
			(xy 225.119934 -407.322682) (xy 225.19523 -407.330193) (xy 225.269411 -407.345122) (xy 225.34175 -407.367321)
			(xy 225.411536 -407.396574) (xy 225.478083 -407.432592) (xy 225.540737 -407.475021) (xy 225.598883 -407.523445)
			(xy 225.651949 -407.577387) (xy 225.699414 -407.636318) (xy 225.740811 -407.699659) (xy 225.775734 -407.766787)
			(xy 225.803839 -407.837043) (xy 225.824851 -407.909736) (xy 225.832162 -407.94686) (xy 225.835464 -407.965148)
			(xy 225.863658 -407.988516) (xy 227.066094 -407.988516) (xy 227.076166 -407.98811) (xy 227.094765 -407.980378)
			(xy 227.102162 -407.97353) (xy 228.999288 -406.076404) (xy 229.006117 -406.068995) (xy 229.013844 -406.050403)
			(xy 229.014274 -406.040336) (xy 229.014274 -403.768052) (xy 229.014751 -403.743102) (xy 229.02257 -403.693818)
			(xy 229.037991 -403.646361) (xy 229.060637 -403.601896) (xy 229.089951 -403.561514) (xy 229.107238 -403.543516)
			(xy 229.183692 -403.467062) (xy 229.19054 -403.459668) (xy 229.198255 -403.441064) (xy 229.198678 -403.430994)
			(xy 229.198678 -400.11223) (xy 229.199203 -400.087282) (xy 229.20701 -400.038) (xy 229.22242 -399.990544)
			(xy 229.245055 -399.946077) (xy 229.27436 -399.905693) (xy 229.291642 -399.887694) (xy 229.521766 -399.65757)
			(xy 229.539767 -399.640284) (xy 229.580139 -399.610952) (xy 229.624602 -399.588297) (xy 229.672062 -399.572876)
			(xy 229.721351 -399.56507) (xy 229.746302 -399.564606) (xy 233.352594 -399.564606) (xy 233.377543 -399.565108)
			(xy 233.426826 -399.572919) (xy 233.474284 -399.588334) (xy 233.51875 -399.610975) (xy 233.559132 -399.640285)
			(xy 233.57713 -399.65757) (xy 233.798872 -399.879312) (xy 233.816168 -399.897302) (xy 233.845492 -399.937679)
			(xy 233.868139 -399.982146) (xy 233.883552 -400.029608) (xy 233.89135 -400.078897) (xy 233.891836 -400.103848)
			(xy 233.891836 -403.52091) (xy 233.892247 -403.530981) (xy 233.899977 -403.549579) (xy 233.906822 -403.556978)
			(xy 234.044998 -403.695154) (xy 234.062318 -403.713122) (xy 234.091638 -403.753505) (xy 234.114281 -403.797978)
			(xy 234.129687 -403.845445) (xy 234.13748 -403.894737) (xy 234.137962 -403.91969) (xy 234.137962 -404.702518)
			(xy 234.138361 -404.712591) (xy 234.146098 -404.731189) (xy 234.152948 -404.738586) (xy 234.63885 -405.224488)
			(xy 234.646275 -405.231297) (xy 234.664855 -405.239035) (xy 234.674918 -405.239474) (xy 238.514382 -405.239474)
			(xy 238.524405 -405.239065) (xy 238.542927 -405.231396) (xy 238.557101 -405.21722) (xy 238.564767 -405.198697)
			(xy 238.565182 -405.188674) (xy 238.565182 -394.210794) (xy 238.565684 -394.185845) (xy 238.57349 -394.136563)
			(xy 238.588909 -394.089108) (xy 238.611562 -394.044649) (xy 238.64089 -394.004281) (xy 238.676172 -393.968998)
			(xy 238.716539 -393.939668) (xy 238.760997 -393.917014) (xy 238.808451 -393.901593) (xy 238.857733 -393.893785)
			(xy 238.882682 -393.893294) (xy 238.88319 -393.893294) (xy 238.893211 -393.892872) (xy 238.911729 -393.885204)
			(xy 238.925902 -393.871033) (xy 238.933571 -393.852515) (xy 238.93399 -393.842494) (xy 238.93399 -393.82954)
			(xy 238.921798 -393.807188) (xy 238.91113 -393.800076) (xy 238.882225 -393.780498) (xy 238.828145 -393.736342)
			(xy 238.80318 -393.711938) (xy 238.579914 -393.488672) (xy 238.553014 -393.461125) (xy 238.504928 -393.400988)
			(xy 238.463885 -393.33584) (xy 238.430403 -393.266502) (xy 238.404904 -393.193848) (xy 238.387709 -393.118794)
			(xy 238.379036 -393.042285) (xy 238.378492 -393.003786) (xy 238.378492 -384.337306) (xy 238.379215 -384.306679)
			(xy 238.390978 -384.246564) (xy 238.40186 -384.217926) (xy 238.457994 -384.079496) (xy 238.466633 -384.059188)
			(xy 238.488684 -384.020961) (xy 238.515818 -383.986157) (xy 238.5314 -383.97053) (xy 238.583216 -383.920746)
			(xy 238.583724 -383.920238) (xy 239.05718 -383.446782) (xy 239.084743 -383.419899) (xy 239.144878 -383.371812)
			(xy 239.210023 -383.330768) (xy 239.279359 -383.297284) (xy 239.35201 -383.271782) (xy 239.427061 -383.254584)
			(xy 239.503568 -383.245906) (xy 239.542066 -383.24536) (xy 273.481546 -383.24536) (xy 273.512174 -383.24607)
			(xy 273.572289 -383.257841) (xy 273.600926 -383.268728) (xy 273.739356 -383.324862) (xy 273.759667 -383.333494)
			(xy 273.797892 -383.355549) (xy 273.832695 -383.382685) (xy 273.848322 -383.398268) (xy 273.898106 -383.450084)
			(xy 273.898614 -383.450592) (xy 274.11807 -383.670048) (xy 274.141946 -383.69494) (xy 274.148804 -383.70256)
			(xy 274.167854 -383.71145) (xy 274.251674 -383.713482) (xy 274.262067 -383.713236) (xy 274.281342 -383.705512)
			(xy 274.289012 -383.698496) (xy 274.649184 -383.338324) (xy 274.667186 -383.321041) (xy 274.70756 -383.291715)
			(xy 274.752024 -383.269066) (xy 274.799483 -383.25365) (xy 274.84877 -383.245848) (xy 274.87372 -383.24536)
			(xy 280.202132 -383.24536) (xy 280.227081 -383.245851) (xy 280.276364 -383.253667) (xy 280.323821 -383.269085)
			(xy 280.368287 -383.291728) (xy 280.40867 -383.321039) (xy 280.426668 -383.338324) (xy 281.135836 -384.047492)
			(xy 281.153135 -384.065481) (xy 281.182465 -384.105856) (xy 281.205118 -384.150322) (xy 281.220536 -384.197785)
			(xy 281.228338 -384.247076) (xy 281.2288 -384.272028) (xy 281.2288 -384.878585) (xy 286.749043 -384.878585)
			(xy 286.75295 -384.694958) (xy 286.764661 -384.511664) (xy 286.784157 -384.329034) (xy 286.811401 -384.147398)
			(xy 286.846345 -383.967085) (xy 286.888924 -383.788421) (xy 286.939063 -383.611729) (xy 286.99667 -383.437329)
			(xy 287.061641 -383.265536) (xy 287.133858 -383.096662) (xy 287.213192 -382.931012) (xy 287.299498 -382.768885)
			(xy 287.39262 -382.610574) (xy 287.49239 -382.456367) (xy 287.598627 -382.306542) (xy 287.711139 -382.16137)
			(xy 287.770062 -382.09093) (xy 287.775496 -382.083846) (xy 287.781604 -382.067084) (xy 287.782 -382.058164)
			(xy 287.782 -377.650756) (xy 287.781617 -377.64116) (xy 287.774628 -377.623291) (xy 287.761538 -377.609261)
			(xy 287.753044 -377.604782) (xy 287.718141 -377.587458) (xy 287.651661 -377.546806) (xy 287.589675 -377.499584)
			(xy 287.532829 -377.446285) (xy 287.481716 -377.387466) (xy 287.43687 -377.323741) (xy 287.398758 -377.255772)
			(xy 287.367778 -377.184271) (xy 287.344253 -377.109983) (xy 287.328428 -377.033683) (xy 287.320469 -376.956166)
			(xy 287.319974 -376.917204) (xy 287.320518 -376.877271) (xy 287.328866 -376.797842) (xy 287.345471 -376.71972)
			(xy 287.37015 -376.643762) (xy 287.402634 -376.5708) (xy 287.442567 -376.501633) (xy 287.48951 -376.437019)
			(xy 287.542951 -376.377666) (xy 287.602302 -376.324224) (xy 287.666915 -376.277279) (xy 287.736081 -376.237344)
			(xy 287.809042 -376.204858) (xy 287.884999 -376.180177) (xy 287.96312 -376.16357) (xy 288.042549 -376.15522)
			(xy 288.082482 -376.154696) (xy 288.11708 -376.155097) (xy 288.185987 -376.161407) (xy 288.254038 -376.17394)
			(xy 288.28746 -376.18289) (xy 288.287714 -376.18289) (xy 288.296419 -376.184877) (xy 288.314202 -376.183425)
			(xy 288.330412 -376.175971) (xy 288.33699 -376.169936) (xy 289.570922 -374.93575) (xy 289.578326 -374.928915)
			(xy 289.596922 -374.921191) (xy 289.60699 -374.920764) (xy 392.42111 -374.920764) (xy 392.430968 -374.920382)
			(xy 392.449266 -374.91306) (xy 392.45667 -374.90654) (xy 392.483305 -374.8813) (xy 392.540649 -374.835509)
			(xy 392.602127 -374.795439) (xy 392.66717 -374.761461) (xy 392.735177 -374.733889) (xy 392.805518 -374.712978)
			(xy 392.877542 -374.698922) (xy 392.950584 -374.69185) (xy 392.987276 -374.691402) (xy 392.987784 -374.691402)
			(xy 393.024476 -374.691824) (xy 393.097518 -374.698901) (xy 393.169542 -374.712963) (xy 393.239882 -374.733879)
			(xy 393.307888 -374.761456) (xy 393.372929 -374.795439) (xy 393.434405 -374.835513) (xy 393.491747 -374.881308)
			(xy 393.51839 -374.90654) (xy 393.525791 -374.913059) (xy 393.544094 -374.920362) (xy 393.55395 -374.920764)
			(xy 426.282104 -374.920764) (xy 426.292176 -374.921171) (xy 426.310774 -374.928903) (xy 426.318172 -374.93575)
			(xy 432.13401 -380.751588) (xy 432.140841 -380.757895) (xy 432.157799 -380.76548) (xy 432.17635 -380.766489)
			(xy 432.185318 -380.764034) (xy 432.27603 -380.735716) (xy 432.459492 -380.68609) (xy 432.64496 -380.644583)
			(xy 432.832074 -380.611275) (xy 433.020472 -380.58623) (xy 433.20979 -380.569498) (xy 433.39966 -380.56111)
			(xy 433.494688 -380.56058) (xy 433.49545 -380.56058) (xy 433.594886 -380.561146) (xy 433.793547 -380.570306)
			(xy 433.991576 -380.588604) (xy 434.188552 -380.616001) (xy 434.384058 -380.65244) (xy 434.577678 -380.697842)
			(xy 434.769002 -380.752113) (xy 434.863494 -380.783084) (xy 434.871368 -380.785624) (xy 435.902354 -380.785624)
			(xy 435.902354 -380.785116) (xy 464.46948 -380.785116) (xy 464.479549 -380.785548) (xy 464.498147 -380.793263)
			(xy 464.505548 -380.800102) (xy 465.018374 -381.313182) (xy 465.025195 -381.320597) (xy 465.032926 -381.339185)
			(xy 465.03336 -381.34925) (xy 465.03336 -392.832336) (xy 465.032964 -392.842409) (xy 465.025224 -392.861007)
			(xy 465.018374 -392.868404) (xy 458.197458 -399.689574) (xy 458.191314 -399.696175) (xy 458.183797 -399.712559)
			(xy 458.18242 -399.730532) (xy 458.187352 -399.74787) (xy 458.192378 -399.75536) (xy 458.215489 -399.787951)
			(xy 458.255468 -399.857132) (xy 458.28799 -399.930115) (xy 458.312698 -400.006101) (xy 458.329319 -400.084255)
			(xy 458.337672 -400.163719) (xy 458.338174 -400.20367) (xy 458.337675 -400.243605) (xy 458.329329 -400.323039)
			(xy 458.312725 -400.401165) (xy 458.288045 -400.477127) (xy 458.25556 -400.550094) (xy 458.215625 -400.619264)
			(xy 458.168679 -400.683882) (xy 458.115234 -400.743237) (xy 458.055879 -400.796681) (xy 457.991261 -400.843627)
			(xy 457.92209 -400.883562) (xy 457.849124 -400.916046) (xy 457.773161 -400.940726) (xy 457.695035 -400.957329)
			(xy 457.615601 -400.965675) (xy 457.575666 -400.966178) (xy 457.538489 -400.965719) (xy 457.464488 -400.958473)
			(xy 457.391546 -400.944054) (xy 457.320355 -400.922598) (xy 457.251592 -400.894309) (xy 457.218542 -400.877278)
			(xy 457.207186 -400.871969) (xy 457.182146 -400.871969) (xy 457.17079 -400.877278) (xy 457.135292 -400.89555)
			(xy 457.06124 -400.925405) (xy 456.984472 -400.947352) (xy 456.945238 -400.954748) (xy 456.937595 -400.956376)
			(xy 456.92376 -400.963626) (xy 456.91806 -400.968972) (xy 449.886832 -407.999946) (xy 449.878958 -408.020012)
			(xy 449.879466 -408.03068) (xy 449.880228 -408.063446) (xy 449.879729 -408.10338) (xy 449.871376 -408.18281)
			(xy 449.854767 -408.260933) (xy 449.830083 -408.336891) (xy 449.797595 -408.409853) (xy 449.757658 -408.47902)
			(xy 449.710711 -408.543633) (xy 449.657268 -408.602986) (xy 449.597913 -408.656428) (xy 449.533298 -408.703373)
			(xy 449.46413 -408.743306) (xy 449.391167 -408.775792) (xy 449.315208 -408.800473) (xy 449.237085 -408.81708)
			(xy 449.157654 -408.82543) (xy 449.11772 -408.825954) (xy 449.084954 -408.825192) (xy 449.074286 -408.824684)
			(xy 449.05422 -408.832558) (xy 447.757042 -410.12999) (xy 447.749583 -410.138369) (xy 447.742064 -410.159475)
			(xy 447.744214 -410.181777) (xy 447.749422 -410.191712) (xy 447.769526 -410.226967) (xy 447.803042 -410.300884)
			(xy 447.828518 -410.377943) (xy 447.845666 -410.457272) (xy 447.854291 -410.537974) (xy 447.854832 -410.578554)
			(xy 447.85426 -410.618487) (xy 447.845916 -410.697917) (xy 447.829315 -410.776039) (xy 447.804639 -410.851998)
			(xy 447.772159 -410.924961) (xy 447.732229 -410.994129) (xy 447.685288 -411.058745) (xy 447.631849 -411.1181)
			(xy 447.572499 -411.171544) (xy 447.507888 -411.218491) (xy 447.438723 -411.258427) (xy 447.365763 -411.290914)
			(xy 447.289806 -411.315597) (xy 447.211686 -411.332205) (xy 447.132257 -411.340556) (xy 447.092324 -411.341062)
			(xy 447.051743 -411.340522) (xy 446.971039 -411.331904) (xy 446.891708 -411.314761) (xy 446.814646 -411.289289)
			(xy 446.740726 -411.255776) (xy 446.705482 -411.235652) (xy 446.695533 -411.230464) (xy 446.673233 -411.228283)
			(xy 446.652124 -411.235796) (xy 446.64376 -411.243272) (xy 444.98514 -412.901892) (xy 444.978969 -412.908575)
			(xy 444.971334 -412.925068) (xy 444.969939 -412.943189) (xy 444.974958 -412.960657) (xy 444.98006 -412.968186)
			(xy 444.997584 -412.992916) (xy 445.025382 -413.046774) (xy 445.044313 -413.10435) (xy 445.053899 -413.164196)
			(xy 445.054482 -413.1945) (xy 445.054045 -413.221754) (xy 445.046287 -413.275707) (xy 445.03093 -413.328007)
			(xy 445.008285 -413.377589) (xy 444.978815 -413.423443) (xy 444.943118 -413.464637) (xy 444.901923 -413.50033)
			(xy 444.856066 -413.529798) (xy 444.806483 -413.552439) (xy 444.754182 -413.567792) (xy 444.700228 -413.575546)
			(xy 444.672974 -413.576008) (xy 444.64267 -413.575426) (xy 444.582823 -413.565845) (xy 444.525247 -413.546912)
			(xy 444.471394 -413.519105) (xy 444.44666 -413.501586) (xy 444.439156 -413.49644) (xy 444.421672 -413.491431)
			(xy 444.403539 -413.492833) (xy 444.387033 -413.500471) (xy 444.380366 -413.506666) (xy 439.235342 -418.65169)
			(xy 439.229246 -418.66185) (xy 439.227214 -418.667438) (xy 439.227214 -418.667946) (xy 439.214448 -418.706263)
			(xy 439.181866 -418.780169) (xy 439.141659 -418.85022) (xy 439.094275 -418.91563) (xy 439.040246 -418.975668)
			(xy 438.980175 -419.029661) (xy 438.914737 -419.077006) (xy 438.844663 -419.117172) (xy 438.770737 -419.149709)
			(xy 438.732422 -419.162484) (xy 438.726722 -419.164447) (xy 438.716451 -419.170754) (xy 438.712102 -419.17493)
			(xy 435.525164 -422.361614) (xy 435.517772 -422.368464) (xy 435.499167 -422.376177) (xy 435.489096 -422.3766)
			(xy 420.618666 -422.3766) (xy 420.609816 -422.376887) (xy 420.593165 -422.382875) (xy 420.586154 -422.388284)
			(xy 420.556797 -422.412154) (xy 420.494163 -422.454608) (xy 420.42763 -422.490648) (xy 420.357855 -422.51992)
			(xy 420.285523 -422.542135) (xy 420.211346 -422.557075) (xy 420.136053 -422.564593) (xy 420.09822 -422.565068)
			(xy 420.060387 -422.564581) (xy 419.985097 -422.557059) (xy 419.910921 -422.542117) (xy 419.838591 -422.519903)
			(xy 419.768816 -422.490634) (xy 419.702282 -422.454598) (xy 419.639645 -422.412149) (xy 419.610286 -422.388284)
			(xy 419.603234 -422.382951) (xy 419.586607 -422.376978) (xy 419.577774 -422.3766) (xy 370.363496 -422.3766)
			(xy 370.353488 -422.377085) (xy 370.334996 -422.384746) (xy 370.320844 -422.3989) (xy 370.313184 -422.417392)
			(xy 370.312696 -422.4274) (xy 370.312696 -422.692576) (xy 370.312264 -422.702697) (xy 370.304523 -422.721401)
			(xy 370.290211 -422.735717) (xy 370.271509 -422.743462) (xy 370.261388 -422.743884) (xy 365.362744 -422.743884)
			(xy 365.352622 -422.743447) (xy 365.333917 -422.735711) (xy 365.3196 -422.7214) (xy 365.311856 -422.702697)
			(xy 365.311436 -422.692576) (xy 365.311436 -422.4274) (xy 365.310913 -422.417397) (xy 365.30326 -422.398912)
			(xy 365.289118 -422.38476) (xy 365.270639 -422.377094) (xy 365.260636 -422.3766) (xy 303.062386 -422.3766)
			(xy 303.053086 -422.377017) (xy 303.035689 -422.383588) (xy 303.021806 -422.395959) (xy 303.017174 -422.404032)
			(xy 302.998483 -422.439092) (xy 302.954867 -422.505506) (xy 302.904581 -422.567025) (xy 302.848171 -422.62298)
			(xy 302.786247 -422.672766) (xy 302.719482 -422.715843) (xy 302.648599 -422.751743) (xy 302.574367 -422.780077)
			(xy 302.497591 -422.800538) (xy 302.419104 -422.812904) (xy 302.339756 -422.817041) (xy 302.260408 -422.812904)
			(xy 302.181921 -422.800538) (xy 302.105145 -422.780077) (xy 302.030913 -422.751743) (xy 301.96003 -422.715843)
			(xy 301.893265 -422.672766) (xy 301.831341 -422.62298) (xy 301.774931 -422.567025) (xy 301.724645 -422.505506)
			(xy 301.681029 -422.439092) (xy 301.662338 -422.404032) (xy 301.657645 -422.396004) (xy 301.643768 -422.383653)
			(xy 301.626414 -422.377024) (xy 301.617126 -422.3766) (xy 299.341794 -422.3766) (xy 299.331721 -422.376204)
			(xy 299.313122 -422.368466) (xy 299.305726 -422.361614) (xy 295.79443 -418.850318) (xy 295.78761 -418.842902)
			(xy 295.779878 -418.824315) (xy 295.779444 -418.81425) (xy 295.779444 -417.137342) (xy 295.778962 -417.127707)
			(xy 295.771787 -417.109817) (xy 295.75854 -417.095815) (xy 295.74998 -417.091368) (xy 295.666202 -417.05197)
			(xy 295.501746 -416.966901) (xy 295.341088 -416.87486) (xy 295.184523 -416.776016) (xy 295.032339 -416.670553)
			(xy 294.884815 -416.558662) (xy 294.742223 -416.440551) (xy 294.604826 -416.316436) (xy 294.472875 -416.186545)
			(xy 294.346613 -416.051118) (xy 294.226273 -415.910403) (xy 294.112075 -415.764658) (xy 294.004229 -415.614152)
			(xy 293.902935 -415.459162) (xy 293.808377 -415.299972) (xy 293.72073 -415.136875) (xy 293.640155 -414.97017)
			(xy 293.5668 -414.800165) (xy 293.5008 -414.627172) (xy 293.442276 -414.451509) (xy 293.391336 -414.273498)
			(xy 293.348074 -414.093468) (xy 293.312568 -413.911748) (xy 293.284885 -413.728674) (xy 293.265075 -413.544581)
			(xy 293.253174 -413.359808) (xy 293.249205 -413.174695) (xy 293.253174 -412.989582) (xy 293.265075 -412.804809)
			(xy 293.284886 -412.620716) (xy 293.31257 -412.437642) (xy 293.348076 -412.255922) (xy 293.391339 -412.075892)
			(xy 293.442279 -411.897881) (xy 293.500804 -411.722218) (xy 293.566804 -411.549225) (xy 293.640159 -411.37922)
			(xy 293.720735 -411.212516) (xy 293.808382 -411.04942) (xy 293.90294 -410.89023) (xy 294.004235 -410.73524)
			(xy 294.112081 -410.584734) (xy 294.226279 -410.43899) (xy 294.34662 -410.298275) (xy 294.472882 -410.162847)
			(xy 294.604833 -410.032957) (xy 294.742231 -409.908842) (xy 294.884823 -409.790731) (xy 295.032347 -409.678841)
			(xy 295.184531 -409.573378) (xy 295.341097 -409.474535) (xy 295.501755 -409.382495) (xy 295.666211 -409.297425)
			(xy 295.74998 -409.258008) (xy 295.758565 -409.25358) (xy 295.771873 -409.239606) (xy 295.779028 -409.221683)
			(xy 295.779444 -409.212034) (xy 295.779444 -400.138392) (xy 295.778919 -400.128389) (xy 295.771265 -400.109906)
			(xy 295.757124 -400.095755) (xy 295.738646 -400.088088) (xy 295.728644 -400.087592) (xy 289.122866 -400.087592)
			(xy 289.112795 -400.087186) (xy 289.094197 -400.079452) (xy 289.086798 -400.072606) (xy 288.254948 -399.240756)
			(xy 288.227008 -399.234152) (xy 288.213546 -399.23847) (xy 288.175164 -399.250488) (xy 288.096513 -399.267328)
			(xy 288.016527 -399.275796) (xy 287.97631 -399.276316) (xy 287.936376 -399.275794) (xy 287.856944 -399.267446)
			(xy 287.77882 -399.250842) (xy 287.70286 -399.226162) (xy 287.629896 -399.193677) (xy 287.560727 -399.153743)
			(xy 287.496111 -399.106798) (xy 287.436756 -399.053356) (xy 287.383313 -398.994003) (xy 287.336366 -398.929388)
			(xy 287.296431 -398.86022) (xy 287.263945 -398.787257) (xy 287.239263 -398.711297) (xy 287.222657 -398.633174)
			(xy 287.214307 -398.553742) (xy 287.213802 -398.513808) (xy 287.214348 -398.473606) (xy 287.222788 -398.393648)
			(xy 287.239596 -398.315021) (xy 287.264587 -398.2386) (xy 287.297481 -398.165234) (xy 287.337914 -398.095737)
			(xy 287.385437 -398.030882) (xy 287.439521 -397.971388) (xy 287.499566 -397.917916) (xy 287.564906 -397.871062)
			(xy 287.634814 -397.831343) (xy 287.708514 -397.799203) (xy 287.746694 -397.786606) (xy 287.762442 -397.781526)
			(xy 287.782 -397.754856) (xy 287.782 -395.835378) (xy 287.781518 -395.825193) (xy 287.773524 -395.806454)
			(xy 287.766506 -395.799056) (xy 287.739572 -395.77211) (xy 287.690535 -395.713796) (xy 287.647557 -395.650884)
			(xy 287.611066 -395.584) (xy 287.581426 -395.51381) (xy 287.558933 -395.441015) (xy 287.543811 -395.36634)
			(xy 287.53621 -395.290529) (xy 287.536207 -395.214338) (xy 287.543801 -395.138526) (xy 287.558917 -395.06385)
			(xy 287.581403 -394.991053) (xy 287.611037 -394.92086) (xy 287.647522 -394.853973) (xy 287.690494 -394.791057)
			(xy 287.739526 -394.73274) (xy 287.766506 -394.70584) (xy 287.773493 -394.698421) (xy 287.781491 -394.679696)
			(xy 287.782 -394.669518) (xy 287.782 -387.698996) (xy 287.781685 -387.690062) (xy 287.775561 -387.673278)
			(xy 287.770062 -387.66623) (xy 287.71112 -387.595806) (xy 287.598609 -387.450633) (xy 287.492373 -387.300808)
			(xy 287.392604 -387.1466) (xy 287.299483 -386.988289) (xy 287.213178 -386.826161) (xy 287.133846 -386.66051)
			(xy 287.061629 -386.491635) (xy 286.996659 -386.319842) (xy 286.939054 -386.145442) (xy 286.888916 -385.96875)
			(xy 286.846338 -385.790085) (xy 286.811396 -385.609772) (xy 286.784153 -385.428136) (xy 286.764659 -385.245505)
			(xy 286.752948 -385.062211) (xy 286.749043 -384.878585) (xy 281.2288 -384.878585) (xy 281.2288 -386.978652)
			(xy 281.250898 -387.006084) (xy 281.268424 -387.010148) (xy 281.306983 -387.019259) (xy 281.382098 -387.044474)
			(xy 281.454194 -387.077345) (xy 281.522491 -387.117516) (xy 281.586253 -387.164555) (xy 281.644791 -387.217953)
			(xy 281.697476 -387.277135) (xy 281.743737 -387.341463) (xy 281.783077 -387.410243) (xy 281.81507 -387.482731)
			(xy 281.839372 -387.558148) (xy 281.85572 -387.635678) (xy 281.863939 -387.714486) (xy 281.863938 -387.793721)
			(xy 281.855719 -387.872528) (xy 281.839371 -387.950058) (xy 281.815068 -388.025474) (xy 281.783074 -388.097963)
			(xy 281.743734 -388.166742) (xy 281.697472 -388.231069) (xy 281.644787 -388.290251) (xy 281.586248 -388.343649)
			(xy 281.522486 -388.390687) (xy 281.454188 -388.430858) (xy 281.382093 -388.463728) (xy 281.306977 -388.488942)
			(xy 281.268424 -388.49808) (xy 281.250898 -388.502144) (xy 281.2288 -388.529576) (xy 281.2288 -393.283694)
			(xy 281.228296 -393.308643) (xy 281.220486 -393.357926) (xy 281.205071 -393.405383) (xy 281.18243 -393.449849)
			(xy 281.153121 -393.490232) (xy 281.135836 -393.50823) (xy 280.360882 -394.283184) (xy 280.354195 -394.290595)
			(xy 280.34659 -394.309028) (xy 280.346589 -394.328969) (xy 280.354193 -394.347403) (xy 280.360882 -394.354812)
			(xy 280.483818 -394.478002) (xy 280.510712 -394.505555) (xy 280.558798 -394.565692) (xy 280.599841 -394.630839)
			(xy 280.633323 -394.700176) (xy 280.658823 -394.772829) (xy 280.67602 -394.847882) (xy 280.684696 -394.924389)
			(xy 280.68524 -394.962888) (xy 280.68524 -402.161756) (xy 289.53714 -402.161756) (xy 289.537635 -402.121005)
			(xy 289.546327 -402.039968) (xy 289.563597 -401.960317) (xy 289.589248 -401.882958) (xy 289.62299 -401.808769)
			(xy 289.664438 -401.738593) (xy 289.713122 -401.67323) (xy 289.768488 -401.61342) (xy 289.829906 -401.559845)
			(xy 289.89668 -401.513113) (xy 289.93211 -401.492974) (xy 289.94059 -401.487733) (xy 289.953086 -401.472227)
			(xy 289.958781 -401.453145) (xy 289.958272 -401.44319) (xy 289.95624 -401.405344) (xy 289.95624 -401.404836)
			(xy 289.956726 -401.377567) (xy 289.964488 -401.323583) (xy 289.979853 -401.271253) (xy 290.00251 -401.221643)
			(xy 290.031996 -401.175762) (xy 290.067711 -401.134545) (xy 290.108928 -401.09883) (xy 290.154809 -401.069344)
			(xy 290.204419 -401.046687) (xy 290.256749 -401.031322) (xy 290.310733 -401.02356) (xy 290.365271 -401.02356)
			(xy 290.419255 -401.031322) (xy 290.471585 -401.046687) (xy 290.521195 -401.069344) (xy 290.567076 -401.09883)
			(xy 290.608293 -401.134545) (xy 290.644008 -401.175762) (xy 290.673494 -401.221643) (xy 290.696151 -401.271253)
			(xy 290.711516 -401.323583) (xy 290.719278 -401.377567) (xy 290.719764 -401.404836) (xy 290.719505 -401.423826)
			(xy 290.715691 -401.461616) (xy 290.712144 -401.480274) (xy 290.71068 -401.490086) (xy 290.714439 -401.509542)
			(xy 290.725314 -401.526107) (xy 290.733226 -401.53209) (xy 290.766806 -401.555851) (xy 290.829228 -401.609432)
			(xy 290.885531 -401.66941) (xy 290.935062 -401.735092) (xy 290.977248 -401.805716) (xy 291.011599 -401.880465)
			(xy 291.037717 -401.958473) (xy 291.055301 -402.038836) (xy 291.064147 -402.120624) (xy 291.064696 -402.161756)
			(xy 291.064111 -402.204622) (xy 291.054515 -402.289814) (xy 291.035439 -402.373396) (xy 291.007122 -402.454315)
			(xy 290.96992 -402.531554) (xy 290.947602 -402.568156) (xy 290.941871 -402.578455) (xy 290.939482 -402.601875)
			(xy 290.94303 -402.613114) (xy 290.962251 -402.643907) (xy 290.995486 -402.708447) (xy 291.022442 -402.775851)
			(xy 291.042876 -402.845509) (xy 291.056604 -402.916793) (xy 291.063501 -402.989059) (xy 291.063934 -403.025356)
			(xy 291.063445 -403.064027) (xy 291.05562 -403.140972) (xy 291.040051 -403.216731) (xy 291.016898 -403.290526)
			(xy 290.986398 -403.3616) (xy 290.948863 -403.429223) (xy 290.90468 -403.492703) (xy 290.854302 -403.551387)
			(xy 290.798245 -403.604673) (xy 290.737085 -403.652014) (xy 290.671449 -403.692925) (xy 290.602011 -403.726986)
			(xy 290.529484 -403.753848) (xy 290.454611 -403.773233) (xy 290.378161 -403.784945) (xy 290.300918 -403.788863)
			(xy 290.223675 -403.784945) (xy 290.147225 -403.773233) (xy 290.072352 -403.753848) (xy 289.999825 -403.726986)
			(xy 289.930387 -403.692925) (xy 289.864751 -403.652014) (xy 289.803591 -403.604673) (xy 289.747534 -403.551387)
			(xy 289.697156 -403.492703) (xy 289.652973 -403.429223) (xy 289.615438 -403.3616) (xy 289.584938 -403.290526)
			(xy 289.561785 -403.216731) (xy 289.546216 -403.140972) (xy 289.538391 -403.064027) (xy 289.537902 -403.025356)
			(xy 289.538317 -402.989058) (xy 289.545214 -402.91679) (xy 289.558941 -402.845504) (xy 289.579374 -402.775843)
			(xy 289.606329 -402.708437) (xy 289.639562 -402.643894) (xy 289.658806 -402.613114) (xy 289.662419 -402.601881)
			(xy 289.660032 -402.578434) (xy 289.654234 -402.568156) (xy 289.631952 -402.531534) (xy 289.594751 -402.454299)
			(xy 289.566431 -402.373384) (xy 289.547348 -402.289807) (xy 289.537744 -402.20462) (xy 289.53714 -402.161756)
			(xy 280.68524 -402.161756) (xy 280.68524 -404.215092) (xy 283.243782 -404.215092) (xy 283.244369 -404.1724)
			(xy 283.253913 -404.087552) (xy 283.27287 -404.0043) (xy 283.301002 -403.923684) (xy 283.337958 -403.846713)
			(xy 283.360114 -403.810216) (xy 283.364836 -403.801963) (xy 283.368362 -403.783293) (xy 283.364831 -403.764624)
			(xy 283.360114 -403.756368) (xy 283.337925 -403.719888) (xy 283.300944 -403.642924) (xy 283.272806 -403.562305)
			(xy 283.253864 -403.479044) (xy 283.244356 -403.394186) (xy 283.243782 -403.351492) (xy 283.244271 -403.312873)
			(xy 283.252085 -403.23603) (xy 283.267633 -403.160372) (xy 283.290756 -403.086675) (xy 283.321215 -403.015696)
			(xy 283.3587 -402.948162) (xy 283.402824 -402.884768) (xy 283.453135 -402.826162) (xy 283.509117 -402.772947)
			(xy 283.570196 -402.725668) (xy 283.635744 -402.684812) (xy 283.70509 -402.650796) (xy 283.777521 -402.623971)
			(xy 283.852294 -402.604611) (xy 283.928642 -402.592915) (xy 284.005782 -402.589003) (xy 284.082922 -402.592915)
			(xy 284.15927 -402.604611) (xy 284.234043 -402.623971) (xy 284.306474 -402.650796) (xy 284.37582 -402.684812)
			(xy 284.441368 -402.725668) (xy 284.502447 -402.772947) (xy 284.558429 -402.826162) (xy 284.60874 -402.884768)
			(xy 284.652864 -402.948162) (xy 284.690349 -403.015696) (xy 284.720808 -403.086675) (xy 284.743931 -403.160372)
			(xy 284.759479 -403.23603) (xy 284.767293 -403.312873) (xy 284.767782 -403.351492) (xy 284.767193 -403.394184)
			(xy 284.75765 -403.479032) (xy 284.738694 -403.562284) (xy 284.710562 -403.6429) (xy 284.673606 -403.719871)
			(xy 284.65145 -403.756368) (xy 284.646744 -403.764628) (xy 284.643216 -403.783293) (xy 284.646739 -403.801959)
			(xy 284.65145 -403.810216) (xy 284.673639 -403.846695) (xy 284.710619 -403.923661) (xy 284.738756 -404.00428)
			(xy 284.757698 -404.08754) (xy 284.767207 -404.172398) (xy 284.767782 -404.215092) (xy 284.767251 -404.254852)
			(xy 284.758988 -404.333943) (xy 284.742531 -404.411742) (xy 284.718059 -404.487403) (xy 284.685837 -404.560103)
			(xy 284.646217 -404.629051) (xy 284.59963 -404.693496) (xy 284.546582 -404.752737) (xy 284.487652 -404.806129)
			(xy 284.45587 -404.830026) (xy 284.449103 -404.835398) (xy 284.439368 -404.84966) (xy 284.434943 -404.866351)
			(xy 284.435296 -404.874984) (xy 284.436566 -404.905464) (xy 284.436566 -404.905972) (xy 284.43608 -404.933241)
			(xy 284.428318 -404.987225) (xy 284.412953 -405.039555) (xy 284.390296 -405.089165) (xy 284.36081 -405.135046)
			(xy 284.325095 -405.176263) (xy 284.283878 -405.211978) (xy 284.237997 -405.241464) (xy 284.188387 -405.264121)
			(xy 284.136057 -405.279486) (xy 284.082073 -405.287248) (xy 284.027535 -405.287248) (xy 283.973551 -405.279486)
			(xy 283.921221 -405.264121) (xy 283.871611 -405.241464) (xy 283.82573 -405.211978) (xy 283.784513 -405.176263)
			(xy 283.748798 -405.135046) (xy 283.719312 -405.089165) (xy 283.696655 -405.039555) (xy 283.68129 -404.987225)
			(xy 283.673528 -404.933241) (xy 283.673042 -404.905972) (xy 283.673042 -404.900638) (xy 283.63836 -404.883314)
			(xy 283.572413 -404.842543) (xy 283.510947 -404.795287) (xy 283.454597 -404.742035) (xy 283.403945 -404.683336)
			(xy 283.359514 -404.619798) (xy 283.321764 -404.552077) (xy 283.291085 -404.480873) (xy 283.267795 -404.406923)
			(xy 283.252133 -404.330989) (xy 283.244262 -404.253858) (xy 283.243782 -404.215092) (xy 280.68524 -404.215092)
			(xy 280.68524 -406.550622) (xy 286.72028 -406.550622) (xy 286.720799 -406.511177) (xy 286.728937 -406.432708)
			(xy 286.745129 -406.355498) (xy 286.769201 -406.280371) (xy 286.800897 -406.208128) (xy 286.839877 -406.139542)
			(xy 286.885727 -406.075344) (xy 286.937957 -406.01622) (xy 286.996008 -405.962801) (xy 287.059262 -405.915657)
			(xy 287.092898 -405.895048) (xy 287.092898 -405.887936) (xy 287.093458 -405.860669) (xy 287.101213 -405.80669)
			(xy 287.116572 -405.754365) (xy 287.139221 -405.704757) (xy 287.1687 -405.658878) (xy 287.204407 -405.617661)
			(xy 287.245617 -405.581945) (xy 287.291491 -405.552458) (xy 287.341093 -405.529799) (xy 287.393416 -405.51443)
			(xy 287.447393 -405.506663) (xy 287.47466 -405.506174) (xy 287.503262 -405.50668) (xy 287.559825 -405.515209)
			(xy 287.614483 -405.532084) (xy 287.666011 -405.556925) (xy 287.713256 -405.589176) (xy 287.755159 -405.628117)
			(xy 287.790783 -405.672873) (xy 287.819329 -405.722445) (xy 287.840159 -405.775721) (xy 287.852807 -405.831508)
			(xy 287.855406 -405.859996) (xy 287.856475 -405.869547) (xy 287.864689 -405.886907) (xy 287.871408 -405.893778)
			(xy 287.905205 -405.914371) (xy 287.968819 -405.961461) (xy 288.027216 -406.014884) (xy 288.079767 -406.074066)
			(xy 288.12591 -406.138371) (xy 288.165146 -406.207107) (xy 288.197055 -406.279536) (xy 288.221295 -406.35488)
			(xy 288.237603 -406.432328) (xy 288.245805 -406.511049) (xy 288.246312 -406.550622) (xy 288.245911 -406.587018)
			(xy 288.239012 -406.659483) (xy 288.22524 -406.730961) (xy 288.204721 -406.800801) (xy 288.177641 -406.868369)
			(xy 288.144247 -406.933049) (xy 288.1249 -406.96388) (xy 288.121134 -406.975188) (xy 288.123239 -406.998894)
			(xy 288.128964 -407.009346) (xy 288.151103 -407.045826) (xy 288.188074 -407.122736) (xy 288.216214 -407.203297)
			(xy 288.23517 -407.2865) (xy 288.244704 -407.371301) (xy 288.245296 -407.413968) (xy 288.245296 -407.414222)
			(xy 288.244807 -407.452841) (xy 288.236993 -407.529684) (xy 288.221445 -407.605342) (xy 288.198322 -407.679039)
			(xy 288.167863 -407.750018) (xy 288.130378 -407.817552) (xy 288.086254 -407.880946) (xy 288.035943 -407.939552)
			(xy 287.979961 -407.992767) (xy 287.918882 -408.040046) (xy 287.853334 -408.080902) (xy 287.783988 -408.114918)
			(xy 287.711557 -408.141743) (xy 287.636784 -408.161103) (xy 287.560436 -408.172799) (xy 287.483296 -408.176712)
			(xy 287.406156 -408.172799) (xy 287.329808 -408.161103) (xy 287.255035 -408.141743) (xy 287.182604 -408.114918)
			(xy 287.113258 -408.080902) (xy 287.04771 -408.040046) (xy 286.986631 -407.992767) (xy 286.930649 -407.939552)
			(xy 286.880338 -407.880946) (xy 286.836214 -407.817552) (xy 286.798729 -407.750018) (xy 286.76827 -407.679039)
			(xy 286.745147 -407.605342) (xy 286.729599 -407.529684) (xy 286.721785 -407.452841) (xy 286.721296 -407.414222)
			(xy 286.721296 -407.413968) (xy 286.721908 -407.371302) (xy 286.731466 -407.286508) (xy 286.750425 -407.203309)
			(xy 286.778548 -407.122744) (xy 286.815485 -407.045821) (xy 286.837628 -407.009346) (xy 286.843386 -406.9989)
			(xy 286.845515 -406.975178) (xy 286.841692 -406.96388) (xy 286.822364 -406.933038) (xy 286.78898 -406.868356)
			(xy 286.761905 -406.800789) (xy 286.741384 -406.730951) (xy 286.727606 -406.659478) (xy 286.720693 -406.587017)
			(xy 286.72028 -406.550622) (xy 280.68524 -406.550622) (xy 280.68524 -407.5567) (xy 282.15461 -407.5567)
			(xy 282.158522 -407.479558) (xy 282.170219 -407.403207) (xy 282.189581 -407.328432) (xy 282.216408 -407.255999)
			(xy 282.250425 -407.186651) (xy 282.291284 -407.121102) (xy 282.338566 -407.060022) (xy 282.391784 -407.004039)
			(xy 282.450393 -406.953728) (xy 282.513791 -406.909604) (xy 282.581328 -406.872121) (xy 282.652311 -406.841663)
			(xy 282.726011 -406.818543) (xy 282.801672 -406.802998) (xy 282.878517 -406.795187) (xy 282.917138 -406.794716)
			(xy 282.959829 -406.795331) (xy 283.044676 -406.804868) (xy 283.127928 -406.823818) (xy 283.208544 -406.851944)
			(xy 283.285516 -406.888894) (xy 283.322014 -406.911048) (xy 283.33027 -406.915762) (xy 283.348938 -406.919289)
			(xy 283.367606 -406.915762) (xy 283.375862 -406.911048) (xy 283.412355 -406.888881) (xy 283.489316 -406.851897)
			(xy 283.569932 -406.823755) (xy 283.65319 -406.804808) (xy 283.738044 -406.795294) (xy 283.780738 -406.794716)
			(xy 283.819357 -406.795175) (xy 283.896198 -406.802993) (xy 283.971855 -406.818544) (xy 284.04555 -406.841669)
			(xy 284.116527 -406.872131) (xy 284.184059 -406.909617) (xy 284.247452 -406.953743) (xy 284.306055 -407.004055)
			(xy 284.359268 -407.060038) (xy 284.406545 -407.121117) (xy 284.4474 -407.186665) (xy 284.481414 -407.256011)
			(xy 284.508239 -407.328441) (xy 284.527598 -407.403214) (xy 284.539294 -407.479561) (xy 284.543206 -407.5567)
			(xy 284.539294 -407.633839) (xy 284.527598 -407.710186) (xy 284.508239 -407.784959) (xy 284.481414 -407.857389)
			(xy 284.4474 -407.926735) (xy 284.406545 -407.992283) (xy 284.359268 -408.053362) (xy 284.306055 -408.109345)
			(xy 284.247452 -408.159657) (xy 284.184059 -408.203783) (xy 284.116527 -408.241269) (xy 284.04555 -408.271731)
			(xy 283.971855 -408.294856) (xy 283.896198 -408.310407) (xy 283.819357 -408.318225) (xy 283.780738 -408.318716)
			(xy 283.738047 -408.318107) (xy 283.6532 -408.308568) (xy 283.569947 -408.289617) (xy 283.489332 -408.261489)
			(xy 283.41236 -408.224538) (xy 283.375862 -408.202384) (xy 283.367606 -408.19767) (xy 283.348938 -408.194143)
			(xy 283.33027 -408.19767) (xy 283.322014 -408.202384) (xy 283.285523 -408.224554) (xy 283.208562 -408.261538)
			(xy 283.127945 -408.289681) (xy 283.044687 -408.308627) (xy 282.959832 -408.318139) (xy 282.917138 -408.318716)
			(xy 282.878517 -408.318213) (xy 282.801672 -408.310402) (xy 282.726011 -408.294857) (xy 282.652311 -408.271737)
			(xy 282.581328 -408.241279) (xy 282.513791 -408.203796) (xy 282.450393 -408.159672) (xy 282.391784 -408.109361)
			(xy 282.338566 -408.053378) (xy 282.291284 -407.992298) (xy 282.250425 -407.926749) (xy 282.216408 -407.857401)
			(xy 282.189581 -407.784968) (xy 282.170219 -407.710193) (xy 282.158522 -407.633842) (xy 282.15461 -407.5567)
			(xy 280.68524 -407.5567) (xy 280.68524 -409.10256) (xy 280.684766 -409.12751) (xy 280.676946 -409.176794)
			(xy 280.661524 -409.224251) (xy 280.638877 -409.268716) (xy 280.609563 -409.309098) (xy 280.592276 -409.327096)
			(xy 272.414746 -417.504626) (xy 272.396783 -417.521953) (xy 272.356401 -417.55128) (xy 272.311928 -417.573928)
			(xy 272.264459 -417.589339) (xy 272.215164 -417.597133) (xy 272.19021 -417.59759) (xy 235.05033 -417.59759)
			(xy 235.040259 -417.598007) (xy 235.02166 -417.605731) (xy 235.014262 -417.612576) (xy 233.545126 -419.081712)
			(xy 276.341332 -419.081712) (xy 276.341921 -419.03902) (xy 276.351464 -418.954172) (xy 276.370419 -418.87092)
			(xy 276.398551 -418.790304) (xy 276.435508 -418.713333) (xy 276.457664 -418.676836) (xy 276.462366 -418.668574)
			(xy 276.465893 -418.64991) (xy 276.462373 -418.631245) (xy 276.457664 -418.622988) (xy 276.435478 -418.586507)
			(xy 276.398497 -418.509542) (xy 276.370359 -418.428923) (xy 276.351416 -418.345663) (xy 276.341907 -418.260806)
			(xy 276.341332 -418.218112) (xy 276.341821 -418.179493) (xy 276.349635 -418.10265) (xy 276.365183 -418.026992)
			(xy 276.388306 -417.953295) (xy 276.418765 -417.882316) (xy 276.45625 -417.814782) (xy 276.500374 -417.751388)
			(xy 276.550685 -417.692782) (xy 276.606667 -417.639567) (xy 276.667746 -417.592288) (xy 276.733294 -417.551432)
			(xy 276.80264 -417.517416) (xy 276.875071 -417.490591) (xy 276.949844 -417.471231) (xy 277.026192 -417.459535)
			(xy 277.103332 -417.455623) (xy 277.180472 -417.459535) (xy 277.25682 -417.471231) (xy 277.331593 -417.490591)
			(xy 277.404024 -417.517416) (xy 277.47337 -417.551432) (xy 277.538918 -417.592288) (xy 277.599997 -417.639567)
			(xy 277.655979 -417.692782) (xy 277.70629 -417.751388) (xy 277.750414 -417.814782) (xy 277.787899 -417.882316)
			(xy 277.818358 -417.953295) (xy 277.841481 -418.026992) (xy 277.857029 -418.10265) (xy 277.864843 -418.179493)
			(xy 277.865332 -418.218112) (xy 277.864828 -418.254688) (xy 289.073336 -418.254688) (xy 289.073913 -418.211996)
			(xy 289.083458 -418.127147) (xy 289.102417 -418.043895) (xy 289.130551 -417.963279) (xy 289.16751 -417.886308)
			(xy 289.189668 -417.849812) (xy 289.194389 -417.84156) (xy 289.19791 -417.82289) (xy 289.194382 -417.804221)
			(xy 289.189668 -417.795964) (xy 289.167472 -417.759488) (xy 289.130493 -417.682522) (xy 289.102357 -417.601902)
			(xy 289.083417 -417.518641) (xy 289.07391 -417.433783) (xy 289.073336 -417.391088) (xy 289.073825 -417.352469)
			(xy 289.081639 -417.275626) (xy 289.097187 -417.199968) (xy 289.12031 -417.126271) (xy 289.150769 -417.055292)
			(xy 289.188254 -416.987758) (xy 289.232378 -416.924364) (xy 289.282689 -416.865758) (xy 289.338671 -416.812543)
			(xy 289.39975 -416.765264) (xy 289.465298 -416.724408) (xy 289.534644 -416.690392) (xy 289.607075 -416.663567)
			(xy 289.681848 -416.644207) (xy 289.758196 -416.632511) (xy 289.835336 -416.628599) (xy 289.912476 -416.632511)
			(xy 289.988824 -416.644207) (xy 290.063597 -416.663567) (xy 290.136028 -416.690392) (xy 290.205374 -416.724408)
			(xy 290.270922 -416.765264) (xy 290.332001 -416.812543) (xy 290.387983 -416.865758) (xy 290.438294 -416.924364)
			(xy 290.482418 -416.987758) (xy 290.519903 -417.055292) (xy 290.550362 -417.126271) (xy 290.573485 -417.199968)
			(xy 290.589033 -417.275626) (xy 290.596847 -417.352469) (xy 290.597336 -417.391088) (xy 290.596736 -417.433779)
			(xy 290.587195 -417.518627) (xy 290.568241 -417.601879) (xy 290.540112 -417.682495) (xy 290.503159 -417.759467)
			(xy 290.481004 -417.795964) (xy 290.476297 -417.804224) (xy 290.472765 -417.82289) (xy 290.47629 -417.841557)
			(xy 290.481004 -417.849812) (xy 290.503187 -417.886295) (xy 290.540169 -417.963259) (xy 290.568308 -418.043877)
			(xy 290.587251 -418.127137) (xy 290.596761 -418.211994) (xy 290.597336 -418.254688) (xy 290.596847 -418.293307)
			(xy 290.589033 -418.37015) (xy 290.573485 -418.445808) (xy 290.550362 -418.519505) (xy 290.519903 -418.590484)
			(xy 290.482418 -418.658018) (xy 290.438294 -418.721412) (xy 290.387983 -418.780018) (xy 290.332001 -418.833233)
			(xy 290.270922 -418.880512) (xy 290.205374 -418.921368) (xy 290.136028 -418.955384) (xy 290.063597 -418.982209)
			(xy 289.988824 -419.001569) (xy 289.912476 -419.013265) (xy 289.835336 -419.017178) (xy 289.758196 -419.013265)
			(xy 289.681848 -419.001569) (xy 289.607075 -418.982209) (xy 289.534644 -418.955384) (xy 289.465298 -418.921368)
			(xy 289.39975 -418.880512) (xy 289.338671 -418.833233) (xy 289.282689 -418.780018) (xy 289.232378 -418.721412)
			(xy 289.188254 -418.658018) (xy 289.150769 -418.590484) (xy 289.12031 -418.519505) (xy 289.097187 -418.445808)
			(xy 289.081639 -418.37015) (xy 289.073825 -418.293307) (xy 289.073336 -418.254688) (xy 277.864828 -418.254688)
			(xy 277.864744 -418.260804) (xy 277.8552 -418.345652) (xy 277.836244 -418.428904) (xy 277.808112 -418.50952)
			(xy 277.771156 -418.586491) (xy 277.749 -418.622988) (xy 277.744274 -418.631239) (xy 277.740749 -418.64991)
			(xy 277.744282 -418.66858) (xy 277.749 -418.676836) (xy 277.771192 -418.713314) (xy 277.808173 -418.790279)
			(xy 277.83631 -418.870899) (xy 277.855251 -418.95416) (xy 277.864758 -419.039017) (xy 277.865332 -419.081712)
			(xy 277.864843 -419.120331) (xy 277.857029 -419.197174) (xy 277.841481 -419.272832) (xy 277.818358 -419.346529)
			(xy 277.787899 -419.417508) (xy 277.750414 -419.485042) (xy 277.70629 -419.548436) (xy 277.655979 -419.607042)
			(xy 277.599997 -419.660257) (xy 277.599254 -419.660832) (xy 290.447476 -419.660832) (xy 290.44798 -419.620714)
			(xy 290.456404 -419.540922) (xy 290.47315 -419.462453) (xy 290.498035 -419.386174) (xy 290.530783 -419.312926)
			(xy 290.571034 -419.243517) (xy 290.618344 -419.178713) (xy 290.67219 -419.119229) (xy 290.731978 -419.065721)
			(xy 290.764214 -419.041834) (xy 290.771273 -419.036255) (xy 290.781256 -419.021298) (xy 290.785472 -419.003816)
			(xy 290.784788 -418.994844) (xy 290.783712 -418.984464) (xy 290.78257 -418.963624) (xy 290.782502 -418.953188)
			(xy 290.782988 -418.925919) (xy 290.79075 -418.871935) (xy 290.806115 -418.819605) (xy 290.828772 -418.769995)
			(xy 290.858258 -418.724114) (xy 290.893973 -418.682897) (xy 290.93519 -418.647182) (xy 290.981071 -418.617696)
			(xy 291.030681 -418.595039) (xy 291.083011 -418.579674) (xy 291.136995 -418.571912) (xy 291.191533 -418.571912)
			(xy 291.245517 -418.579674) (xy 291.297847 -418.595039) (xy 291.347457 -418.617696) (xy 291.393338 -418.647182)
			(xy 291.434555 -418.682897) (xy 291.47027 -418.724114) (xy 291.499756 -418.769995) (xy 291.522413 -418.819605)
			(xy 291.537778 -418.871935) (xy 291.54554 -418.925919) (xy 291.546026 -418.953188) (xy 291.545518 -418.974016)
			(xy 291.580194 -418.99147) (xy 291.646189 -419.032359) (xy 291.707697 -419.07973) (xy 291.764083 -419.133096)
			(xy 291.814765 -419.191905) (xy 291.859221 -419.255552) (xy 291.896992 -419.32338) (xy 291.927688 -419.394689)
			(xy 291.950994 -419.468744) (xy 291.966668 -419.54478) (xy 291.974549 -419.622014) (xy 291.975032 -419.660832)
			(xy 291.974478 -419.703698) (xy 291.964874 -419.788892) (xy 291.94579 -419.872474) (xy 291.917466 -419.953393)
			(xy 291.880259 -420.030631) (xy 291.857938 -420.067232) (xy 291.852222 -420.077538) (xy 291.849822 -420.100953)
			(xy 291.853366 -420.11219) (xy 291.872624 -420.142961) (xy 291.905853 -420.207506) (xy 291.932803 -420.274915)
			(xy 291.953231 -420.344577) (xy 291.966951 -420.415865) (xy 291.973841 -420.488134) (xy 291.97427 -420.524432)
			(xy 291.973792 -420.563822) (xy 291.965665 -420.642181) (xy 291.949511 -420.719287) (xy 291.925502 -420.794319)
			(xy 291.893893 -420.86648) (xy 291.855021 -420.935001) (xy 291.809298 -420.999155) (xy 291.757211 -421.058258)
			(xy 291.699314 -421.111683) (xy 291.636223 -421.158861) (xy 291.602668 -421.179498) (xy 291.594677 -421.187636)
			(xy 291.586098 -421.208734) (xy 291.586158 -421.220138) (xy 291.58692 -421.244014) (xy 291.586434 -421.271283)
			(xy 291.578672 -421.325267) (xy 291.563307 -421.377597) (xy 291.54065 -421.427207) (xy 291.511164 -421.473088)
			(xy 291.475449 -421.514305) (xy 291.434232 -421.55002) (xy 291.388351 -421.579506) (xy 291.338741 -421.602163)
			(xy 291.286411 -421.617528) (xy 291.232427 -421.62529) (xy 291.177889 -421.62529) (xy 291.123905 -421.617528)
			(xy 291.071575 -421.602163) (xy 291.021965 -421.579506) (xy 290.976084 -421.55002) (xy 290.934867 -421.514305)
			(xy 290.899152 -421.473088) (xy 290.869666 -421.427207) (xy 290.847009 -421.377597) (xy 290.831644 -421.325267)
			(xy 290.823882 -421.271283) (xy 290.823396 -421.244014) (xy 290.823396 -421.243506) (xy 290.824666 -421.213788)
			(xy 290.824895 -421.2024) (xy 290.816743 -421.181168) (xy 290.808918 -421.172894) (xy 290.776263 -421.152023)
			(xy 290.714898 -421.104683) (xy 290.658646 -421.051368) (xy 290.608088 -420.992626) (xy 290.563742 -420.929063)
			(xy 290.526067 -420.861333) (xy 290.49545 -420.790134) (xy 290.472206 -420.716198) (xy 290.456575 -420.640288)
			(xy 290.448717 -420.563184) (xy 290.448238 -420.524432) (xy 290.448685 -420.488135) (xy 290.455575 -420.415868)
			(xy 290.469296 -420.344582) (xy 290.489723 -420.274921) (xy 290.516673 -420.207514) (xy 290.549901 -420.142971)
			(xy 290.569142 -420.11219) (xy 290.57278 -420.100962) (xy 290.570379 -420.077508) (xy 290.56457 -420.067232)
			(xy 290.542263 -420.030624) (xy 290.50506 -419.953386) (xy 290.476741 -419.872468) (xy 290.457659 -419.788888)
			(xy 290.448057 -419.703697) (xy 290.447476 -419.660832) (xy 277.599254 -419.660832) (xy 277.538918 -419.707536)
			(xy 277.47337 -419.748392) (xy 277.404024 -419.782408) (xy 277.331593 -419.809233) (xy 277.25682 -419.828593)
			(xy 277.180472 -419.840289) (xy 277.103332 -419.844202) (xy 277.026192 -419.840289) (xy 276.949844 -419.828593)
			(xy 276.875071 -419.809233) (xy 276.80264 -419.782408) (xy 276.733294 -419.748392) (xy 276.667746 -419.707536)
			(xy 276.606667 -419.660257) (xy 276.550685 -419.607042) (xy 276.500374 -419.548436) (xy 276.45625 -419.485042)
			(xy 276.418765 -419.417508) (xy 276.388306 -419.346529) (xy 276.365183 -419.272832) (xy 276.349635 -419.197174)
			(xy 276.341821 -419.120331) (xy 276.341332 -419.081712) (xy 233.545126 -419.081712) (xy 230.329486 -422.297352)
			(xy 230.322673 -422.304773) (xy 230.314938 -422.323356) (xy 230.314775 -422.3271) (xy 285.186564 -422.3271)
			(xy 285.190477 -422.249953) (xy 285.202174 -422.173598) (xy 285.221537 -422.098818) (xy 285.248365 -422.026381)
			(xy 285.282385 -421.95703) (xy 285.323246 -421.891476) (xy 285.37053 -421.830393) (xy 285.423751 -421.774407)
			(xy 285.482364 -421.724092) (xy 285.545766 -421.679966) (xy 285.613307 -421.64248) (xy 285.684293 -421.612021)
			(xy 285.757998 -421.588899) (xy 285.833663 -421.573352) (xy 285.910513 -421.565541) (xy 285.949136 -421.56507)
			(xy 285.991827 -421.565693) (xy 286.076673 -421.575229) (xy 286.159925 -421.594178) (xy 286.240541 -421.622302)
			(xy 286.317514 -421.65925) (xy 286.354012 -421.681402) (xy 286.362268 -421.686116) (xy 286.380936 -421.689643)
			(xy 286.399604 -421.686116) (xy 286.40786 -421.681402) (xy 286.444356 -421.659242) (xy 286.521316 -421.622256)
			(xy 286.601931 -421.594112) (xy 286.685188 -421.575163) (xy 286.770043 -421.565648) (xy 286.812736 -421.56507)
			(xy 286.851353 -421.565621) (xy 286.92819 -421.573438) (xy 287.003842 -421.588988) (xy 287.077532 -421.612112)
			(xy 287.148506 -421.642572) (xy 287.216033 -421.680055) (xy 287.279423 -421.724178) (xy 287.338023 -421.774488)
			(xy 287.391233 -421.830467) (xy 287.438507 -421.891543) (xy 287.47936 -421.957087) (xy 287.513372 -422.026428)
			(xy 287.540195 -422.098854) (xy 287.559553 -422.173623) (xy 287.571248 -422.249966) (xy 287.57516 -422.3271)
			(xy 287.571248 -422.404234) (xy 287.559553 -422.480577) (xy 287.540195 -422.555346) (xy 287.513372 -422.627772)
			(xy 287.47936 -422.697113) (xy 287.438507 -422.762657) (xy 287.391233 -422.823733) (xy 287.338023 -422.879712)
			(xy 287.279423 -422.930022) (xy 287.216033 -422.974145) (xy 287.148506 -423.011628) (xy 287.077532 -423.042088)
			(xy 287.003842 -423.065212) (xy 286.92819 -423.080762) (xy 286.851353 -423.088579) (xy 286.812736 -423.08907)
			(xy 286.770045 -423.088469) (xy 286.685197 -423.078929) (xy 286.601944 -423.059976) (xy 286.521329 -423.031847)
			(xy 286.444357 -422.994893) (xy 286.40786 -422.972738) (xy 286.399604 -422.968024) (xy 286.380936 -422.964497)
			(xy 286.362268 -422.968024) (xy 286.354012 -422.972738) (xy 286.317525 -422.994914) (xy 286.240562 -423.031897)
			(xy 286.159945 -423.060037) (xy 286.076686 -423.078982) (xy 285.99183 -423.088494) (xy 285.949136 -423.08907)
			(xy 285.910513 -423.088659) (xy 285.833663 -423.080848) (xy 285.757998 -423.065301) (xy 285.684293 -423.042179)
			(xy 285.613307 -423.01172) (xy 285.545766 -422.974234) (xy 285.482364 -422.930108) (xy 285.423751 -422.879793)
			(xy 285.37053 -422.823807) (xy 285.323246 -422.762724) (xy 285.282385 -422.69717) (xy 285.248365 -422.627819)
			(xy 285.221537 -422.555382) (xy 285.202174 -422.480602) (xy 285.190477 -422.404247) (xy 285.186564 -422.3271)
			(xy 230.314775 -422.3271) (xy 230.3145 -422.33342) (xy 230.3145 -424.74007) (xy 357.551238 -424.74007)
			(xy 357.555218 -424.60708) (xy 357.567145 -424.474566) (xy 357.586975 -424.343002) (xy 357.614637 -424.21286)
			(xy 357.650033 -424.084605) (xy 357.693036 -423.958697) (xy 357.743492 -423.835585) (xy 357.80122 -423.715712)
			(xy 357.866014 -423.599505) (xy 357.937641 -423.487381) (xy 358.015846 -423.379742) (xy 358.100348 -423.276972)
			(xy 358.190845 -423.17944) (xy 358.287012 -423.087494) (xy 358.388506 -423.001464) (xy 358.494964 -422.921658)
			(xy 358.606003 -422.848362) (xy 358.721228 -422.781837) (xy 358.840224 -422.722322) (xy 358.962567 -422.67003)
			(xy 359.087818 -422.625149) (xy 359.215529 -422.587838) (xy 359.345243 -422.558231) (xy 359.476495 -422.536436)
			(xy 359.608816 -422.522528) (xy 359.741732 -422.516559) (xy 359.874767 -422.518549) (xy 360.007444 -422.528492)
			(xy 360.13929 -422.546352) (xy 360.269831 -422.572064) (xy 360.398601 -422.605538) (xy 360.525139 -422.646652)
			(xy 360.648991 -422.695261) (xy 360.769715 -422.751189) (xy 360.886878 -422.814237) (xy 361.000061 -422.884179)
			(xy 361.108858 -422.960765) (xy 361.21288 -423.04372) (xy 361.311755 -423.132748) (xy 361.405129 -423.227529)
			(xy 361.492668 -423.327725) (xy 361.574058 -423.432977) (xy 361.649007 -423.542907) (xy 361.657271 -423.556738)
			(xy 456.285335 -423.556738) (xy 456.285335 -423.427598) (xy 456.293285 -423.298703) (xy 456.309155 -423.170543)
			(xy 456.332884 -423.043602) (xy 456.364383 -422.918363) (xy 456.403532 -422.7953) (xy 456.450183 -422.674881)
			(xy 456.504158 -422.557562) (xy 456.565253 -422.443788) (xy 456.633236 -422.333991) (xy 456.70785 -422.228588)
			(xy 456.788811 -422.127978) (xy 456.875811 -422.032543) (xy 456.968522 -421.942644) (xy 457.066592 -421.858623)
			(xy 457.169647 -421.780799) (xy 457.277298 -421.709467) (xy 457.389137 -421.644897) (xy 457.504738 -421.587335)
			(xy 457.623663 -421.536998) (xy 457.745462 -421.494078) (xy 457.869672 -421.458737) (xy 457.995821 -421.43111)
			(xy 458.123433 -421.411301) (xy 458.252022 -421.399385) (xy 458.3811 -421.395409) (xy 458.510178 -421.399385)
			(xy 458.638767 -421.411301) (xy 458.766379 -421.43111) (xy 458.892528 -421.458737) (xy 459.016738 -421.494078)
			(xy 459.138537 -421.536998) (xy 459.257462 -421.587335) (xy 459.373063 -421.644897) (xy 459.484902 -421.709467)
			(xy 459.592553 -421.780799) (xy 459.695608 -421.858623) (xy 459.793678 -421.942644) (xy 459.886389 -422.032543)
			(xy 459.973389 -422.127978) (xy 460.05435 -422.228588) (xy 460.128964 -422.333991) (xy 460.196947 -422.443788)
			(xy 460.258042 -422.557562) (xy 460.312017 -422.674881) (xy 460.358668 -422.7953) (xy 460.397817 -422.918363)
			(xy 460.429316 -423.043602) (xy 460.453045 -423.170543) (xy 460.468915 -423.298703) (xy 460.476865 -423.427598)
			(xy 460.477362 -423.492168) (xy 460.476865 -423.556738) (xy 460.468915 -423.685633) (xy 460.453045 -423.813793)
			(xy 460.429316 -423.940734) (xy 460.397817 -424.065973) (xy 460.358668 -424.189036) (xy 460.312017 -424.309455)
			(xy 460.258042 -424.426774) (xy 460.196947 -424.540548) (xy 460.128964 -424.650345) (xy 460.05435 -424.755748)
			(xy 459.973389 -424.856358) (xy 459.886389 -424.951793) (xy 459.793678 -425.041692) (xy 459.695608 -425.125713)
			(xy 459.592553 -425.203537) (xy 459.484902 -425.274869) (xy 459.373063 -425.339439) (xy 459.257462 -425.397001)
			(xy 459.138537 -425.447338) (xy 459.016738 -425.490258) (xy 458.892528 -425.525599) (xy 458.766379 -425.553226)
			(xy 458.638767 -425.573035) (xy 458.510178 -425.584951) (xy 458.3811 -425.588928) (xy 458.252022 -425.584951)
			(xy 458.123433 -425.573035) (xy 457.995821 -425.553226) (xy 457.869672 -425.525599) (xy 457.745462 -425.490258)
			(xy 457.623663 -425.447338) (xy 457.504738 -425.397001) (xy 457.389137 -425.339439) (xy 457.277298 -425.274869)
			(xy 457.169647 -425.203537) (xy 457.066592 -425.125713) (xy 456.968522 -425.041692) (xy 456.875811 -424.951793)
			(xy 456.788811 -424.856358) (xy 456.70785 -424.755748) (xy 456.633236 -424.650345) (xy 456.565253 -424.540548)
			(xy 456.504158 -424.426774) (xy 456.450183 -424.309455) (xy 456.403532 -424.189036) (xy 456.364383 -424.065973)
			(xy 456.332884 -423.940734) (xy 456.309155 -423.813793) (xy 456.293285 -423.685633) (xy 456.285335 -423.556738)
			(xy 361.657271 -423.556738) (xy 361.717248 -423.657124) (xy 361.778537 -423.775217) (xy 361.832653 -423.896764)
			(xy 361.879403 -424.021329) (xy 361.91862 -424.148468) (xy 361.950164 -424.277724) (xy 361.97392 -424.408636)
			(xy 361.989806 -424.540734) (xy 361.997763 -424.673545) (xy 361.99826 -424.74007) (xy 361.997763 -424.806595)
			(xy 361.989806 -424.939406) (xy 361.97392 -425.071504) (xy 361.950164 -425.202416) (xy 361.91862 -425.331672)
			(xy 361.879403 -425.458811) (xy 361.832653 -425.583376) (xy 361.778537 -425.704923) (xy 361.717248 -425.823016)
			(xy 361.649007 -425.937233) (xy 361.574058 -426.047163) (xy 361.492668 -426.152415) (xy 361.405129 -426.252611)
			(xy 361.311755 -426.347392) (xy 361.21288 -426.43642) (xy 361.108858 -426.519375) (xy 361.000061 -426.595961)
			(xy 360.886878 -426.665903) (xy 360.769715 -426.728951) (xy 360.648991 -426.784879) (xy 360.525139 -426.833488)
			(xy 360.398601 -426.874602) (xy 360.269831 -426.908076) (xy 360.13929 -426.933788) (xy 360.007444 -426.951648)
			(xy 359.874767 -426.961591) (xy 359.741732 -426.963581) (xy 359.608816 -426.957612) (xy 359.476495 -426.943704)
			(xy 359.345243 -426.921909) (xy 359.215529 -426.892302) (xy 359.087818 -426.854991) (xy 358.962567 -426.81011)
			(xy 358.840224 -426.757818) (xy 358.721228 -426.698303) (xy 358.606003 -426.631778) (xy 358.494964 -426.558482)
			(xy 358.388506 -426.478676) (xy 358.287012 -426.392646) (xy 358.190845 -426.3007) (xy 358.100348 -426.203168)
			(xy 358.015846 -426.100398) (xy 357.937641 -425.992759) (xy 357.866014 -425.880635) (xy 357.80122 -425.764428)
			(xy 357.743492 -425.644555) (xy 357.693036 -425.521443) (xy 357.650033 -425.395535) (xy 357.614637 -425.26728)
			(xy 357.586975 -425.137138) (xy 357.567145 -425.005574) (xy 357.555218 -424.87306) (xy 357.551238 -424.74007)
			(xy 230.3145 -424.74007) (xy 230.3145 -427.960536) (xy 314.141104 -427.960536) (xy 314.141104 -425.419012)
			(xy 314.14157 -425.406962) (xy 314.149 -425.384036) (xy 314.163139 -425.36452) (xy 314.182609 -425.350316)
			(xy 314.20551 -425.342811) (xy 314.217558 -425.342304) (xy 315.157866 -425.342304) (xy 315.16995 -425.342836)
			(xy 315.192944 -425.350279) (xy 315.212521 -425.36445) (xy 315.226774 -425.383968) (xy 315.234313 -425.40693)
			(xy 315.234828 -425.419012) (xy 315.234828 -427.960536) (xy 315.234371 -427.972585) (xy 315.226932 -427.995507)
			(xy 315.21279 -428.01502) (xy 315.193321 -428.029223) (xy 315.170422 -428.036734) (xy 315.158374 -428.037244)
			(xy 314.218066 -428.037244) (xy 314.205973 -428.036821) (xy 314.182969 -428.029353) (xy 314.163388 -428.015156)
			(xy 314.149139 -427.995612) (xy 314.141611 -427.972628) (xy 314.141104 -427.960536) (xy 230.3145 -427.960536)
			(xy 230.3145 -433.134051) (xy 266.619222 -433.134051) (xy 266.619222 -432.950069) (xy 266.627247 -432.766261)
			(xy 266.643282 -432.582979) (xy 266.667296 -432.400571) (xy 266.699245 -432.219383) (xy 266.739066 -432.039762)
			(xy 266.786684 -431.862048) (xy 266.842008 -431.686581) (xy 266.904934 -431.513694) (xy 266.975341 -431.343717)
			(xy 267.053096 -431.176972) (xy 267.138049 -431.013777) (xy 267.23004 -430.854444) (xy 267.328894 -430.699275)
			(xy 267.434422 -430.548565) (xy 267.546424 -430.402602) (xy 267.664685 -430.261663) (xy 267.788982 -430.126017)
			(xy 267.919077 -429.995922) (xy 268.054723 -429.871625) (xy 268.195662 -429.753364) (xy 268.341625 -429.641362)
			(xy 268.492335 -429.535834) (xy 268.647504 -429.43698) (xy 268.806837 -429.344989) (xy 268.970032 -429.260036)
			(xy 269.136777 -429.182281) (xy 269.306754 -429.111874) (xy 269.479641 -429.048948) (xy 269.655108 -428.993624)
			(xy 269.832822 -428.946006) (xy 270.012443 -428.906185) (xy 270.193631 -428.874236) (xy 270.376039 -428.850222)
			(xy 270.559321 -428.834187) (xy 270.743129 -428.826162) (xy 270.927111 -428.826162) (xy 271.110919 -428.834187)
			(xy 271.294201 -428.850222) (xy 271.476609 -428.874236) (xy 271.657797 -428.906185) (xy 271.837418 -428.946006)
			(xy 272.015132 -428.993624) (xy 272.190599 -429.048948) (xy 272.363486 -429.111874) (xy 272.533463 -429.182281)
			(xy 272.700208 -429.260036) (xy 272.863403 -429.344989) (xy 273.022736 -429.43698) (xy 273.177905 -429.535834)
			(xy 273.328615 -429.641362) (xy 273.474578 -429.753364) (xy 273.615517 -429.871625) (xy 273.751163 -429.995922)
			(xy 273.881258 -430.126017) (xy 274.005555 -430.261663) (xy 274.123816 -430.402602) (xy 274.235818 -430.548565)
			(xy 274.341346 -430.699275) (xy 274.4402 -430.854444) (xy 274.532191 -431.013777) (xy 274.617144 -431.176972)
			(xy 274.694899 -431.343717) (xy 274.765306 -431.513694) (xy 274.828232 -431.686581) (xy 274.883556 -431.862048)
			(xy 274.931174 -432.039762) (xy 274.970995 -432.219383) (xy 275.002944 -432.400571) (xy 275.026958 -432.582979)
			(xy 275.042993 -432.766261) (xy 275.051018 -432.950069) (xy 275.05152 -433.04206) (xy 275.051018 -433.134051)
			(xy 275.042993 -433.317859) (xy 275.026958 -433.501141) (xy 275.002944 -433.683549) (xy 274.970995 -433.864737)
			(xy 274.931174 -434.044358) (xy 274.883556 -434.222072) (xy 274.828232 -434.397539) (xy 274.765306 -434.570426)
			(xy 274.694899 -434.740403) (xy 274.617144 -434.907148) (xy 274.532191 -435.070343) (xy 274.4402 -435.229676)
			(xy 274.341346 -435.384845) (xy 274.235818 -435.535555) (xy 274.123816 -435.681518) (xy 274.005555 -435.822457)
			(xy 273.881258 -435.958103) (xy 273.751163 -436.088198) (xy 273.615517 -436.212495) (xy 273.474578 -436.330756)
			(xy 273.328615 -436.442758) (xy 273.177905 -436.548286) (xy 273.022736 -436.64714) (xy 272.863403 -436.739131)
			(xy 272.700208 -436.824084) (xy 272.533463 -436.901839) (xy 272.363486 -436.972246) (xy 272.190599 -437.035172)
			(xy 272.015132 -437.090496) (xy 271.837418 -437.138114) (xy 271.657797 -437.177935) (xy 271.476609 -437.209884)
			(xy 271.294201 -437.233898) (xy 271.110919 -437.249933) (xy 270.927111 -437.257958) (xy 270.743129 -437.257958)
			(xy 270.559321 -437.249933) (xy 270.376039 -437.233898) (xy 270.193631 -437.209884) (xy 270.012443 -437.177935)
			(xy 269.832822 -437.138114) (xy 269.655108 -437.090496) (xy 269.479641 -437.035172) (xy 269.306754 -436.972246)
			(xy 269.136777 -436.901839) (xy 268.970032 -436.824084) (xy 268.806837 -436.739131) (xy 268.647504 -436.64714)
			(xy 268.492335 -436.548286) (xy 268.341625 -436.442758) (xy 268.195662 -436.330756) (xy 268.054723 -436.212495)
			(xy 267.919077 -436.088198) (xy 267.788982 -435.958103) (xy 267.664685 -435.822457) (xy 267.546424 -435.681518)
			(xy 267.434422 -435.535555) (xy 267.328894 -435.384845) (xy 267.23004 -435.229676) (xy 267.138049 -435.070343)
			(xy 267.053096 -434.907148) (xy 266.975341 -434.740403) (xy 266.904934 -434.570426) (xy 266.842008 -434.397539)
			(xy 266.786684 -434.222072) (xy 266.739066 -434.044358) (xy 266.699245 -433.864737) (xy 266.667296 -433.683549)
			(xy 266.643282 -433.501141) (xy 266.627247 -433.317859) (xy 266.619222 -433.134051) (xy 230.3145 -433.134051)
			(xy 230.3145 -435.873652) (xy 230.314033 -435.898602) (xy 230.306213 -435.947887) (xy 230.29079 -435.995345)
			(xy 230.268141 -436.03981) (xy 230.238824 -436.080191) (xy 230.221536 -436.098188) (xy 229.299008 -437.020716)
			(xy 229.281016 -437.03801) (xy 229.240639 -437.067332) (xy 229.196172 -437.089979) (xy 229.148711 -437.105393)
			(xy 229.099423 -437.113193) (xy 229.074472 -437.11368) (xy 207.302608 -437.11368) (xy 207.27766 -437.113152)
			(xy 207.22838 -437.105344) (xy 207.180923 -437.089933) (xy 207.136457 -437.067299) (xy 207.096072 -437.037997)
			(xy 207.078072 -437.020716) (xy 205.512924 -435.455568) (xy 205.495618 -435.437587) (xy 205.466295 -435.397208)
			(xy 205.44365 -435.352738) (xy 205.42824 -435.305274) (xy 205.420444 -435.255984) (xy 205.41996 -435.231032)
			(xy 205.41996 -431.16881) (xy 205.41954 -431.15874) (xy 205.411817 -431.140141) (xy 205.404974 -431.132742)
			(xy 196.207888 -421.935656) (xy 196.19057 -421.917686) (xy 196.16125 -421.877303) (xy 196.138608 -421.832831)
			(xy 196.1232 -421.785364) (xy 196.115407 -421.736072) (xy 196.114924 -421.71112) (xy 196.114924 -413.329374)
			(xy 196.114532 -413.319301) (xy 196.10679 -413.300702) (xy 196.099938 -413.293306) (xy 195.154296 -412.347664)
			(xy 195.146896 -412.340825) (xy 195.128296 -412.333106) (xy 195.118228 -412.332678) (xy 188.720222 -412.332678)
			(xy 188.695275 -412.332142) (xy 188.645994 -412.324336) (xy 188.598538 -412.308927) (xy 188.554072 -412.286295)
			(xy 188.513686 -412.256994) (xy 188.495686 -412.239714) (xy 187.848748 -411.592776) (xy 187.841328 -411.585961)
			(xy 187.822744 -411.578227) (xy 187.81268 -411.57779) (xy 184.8104 -411.57779) (xy 184.785451 -411.577293)
			(xy 184.736167 -411.569481) (xy 184.68871 -411.554065) (xy 184.644244 -411.531423) (xy 184.603862 -411.502111)
			(xy 184.585864 -411.484826) (xy 184.033922 -410.932884) (xy 184.016624 -410.914896) (xy 183.9873 -410.874519)
			(xy 183.964653 -410.830051) (xy 183.949241 -410.782588) (xy 183.941443 -410.733299) (xy 183.940958 -410.708348)
			(xy 166.005717 -410.708348) (xy 166.002747 -410.717399) (xy 165.986714 -410.754322) (xy 165.982115 -410.766115)
			(xy 165.984005 -410.791327) (xy 165.99027 -410.802328) (xy 166.012694 -410.838944) (xy 166.050052 -410.916258)
			(xy 166.07849 -410.997278) (xy 166.09765 -411.080979) (xy 166.107289 -411.166303) (xy 166.107872 -411.209236)
			(xy 166.107389 -411.248809) (xy 166.09919 -411.32753) (xy 166.082884 -411.404978) (xy 166.058646 -411.480321)
			(xy 166.026736 -411.55275) (xy 165.987498 -411.621485) (xy 165.941354 -411.685788) (xy 165.888799 -411.744966)
			(xy 165.830399 -411.798385) (xy 165.766781 -411.84547) (xy 165.69863 -411.885713) (xy 165.662864 -411.902656)
			(xy 165.65372 -411.90672) (xy 165.640258 -411.920944) (xy 165.621716 -411.967934) (xy 165.62197 -411.987746)
			(xy 165.62578 -411.996636) (xy 165.639748 -412.031452) (xy 165.661538 -412.103238) (xy 165.676173 -412.176818)
			(xy 165.683512 -412.251479) (xy 165.683946 -412.28899) (xy 165.683946 -412.289244) (xy 165.683539 -412.324647)
			(xy 165.676948 -412.395147) (xy 165.663855 -412.464733) (xy 165.644373 -412.532808) (xy 165.618668 -412.598784)
			(xy 165.603174 -412.63062) (xy 165.598942 -412.640112) (xy 165.597765 -412.660839) (xy 165.600888 -412.670752)
			(xy 165.615779 -412.71305) (xy 165.63668 -412.800257) (xy 165.647218 -412.889312) (xy 165.647878 -412.93415)
			(xy 165.647878 -412.934404) (xy 165.647415 -412.974367) (xy 165.63906 -413.053855) (xy 165.622441 -413.132034)
			(xy 165.597742 -413.208047) (xy 165.565232 -413.281062) (xy 165.525268 -413.350279) (xy 165.478287 -413.414939)
			(xy 165.424805 -413.474334) (xy 165.365407 -413.527813) (xy 165.300744 -413.57479) (xy 165.231525 -413.614751)
			(xy 165.158508 -413.647257) (xy 165.082493 -413.671952) (xy 165.004313 -413.688566) (xy 164.924825 -413.696917)
			(xy 164.884862 -413.69742) (xy 164.847804 -413.697014) (xy 164.774038 -413.689816) (xy 164.701318 -413.6755)
			(xy 164.630328 -413.654202) (xy 164.561737 -413.626122) (xy 164.496191 -413.591525) (xy 164.434308 -413.550736)
			(xy 164.376671 -413.50414) (xy 164.349938 -413.478472) (xy 164.34252 -413.471801) (xy 164.324089 -413.46422)
			(xy 164.314124 -413.46374) (xy 164.242496 -413.464248) (xy 164.232596 -413.464775) (xy 164.214295 -413.472339)
			(xy 164.206936 -413.47898) (xy 163.666678 -414.019238) (xy 163.659284 -414.026086) (xy 163.64068 -414.0338)
			(xy 163.63061 -414.034224) (xy 116.511832 -414.034224) (xy 116.487194 -414.049464) (xy 116.480844 -414.062418)
			(xy 116.467834 -414.087519) (xy 116.435532 -414.133917) (xy 116.396737 -414.17504) (xy 116.352299 -414.209989)
			(xy 116.30319 -414.237999) (xy 116.250486 -414.258455) (xy 116.19534 -414.270911) (xy 116.13896 -414.275094)
			(xy 116.08258 -414.270911) (xy 116.027434 -414.258455) (xy 115.97473 -414.237999) (xy 115.925621 -414.209989)
			(xy 115.881183 -414.17504) (xy 115.842388 -414.133917) (xy 115.810086 -414.087519) (xy 115.797076 -414.062418)
			(xy 115.790726 -414.049464) (xy 115.766088 -414.034224) (xy 107.362752 -414.034224) (xy 107.354556 -414.034507)
			(xy 107.33901 -414.039707) (xy 107.332272 -414.044384) (xy 107.3194 -414.053884) (xy 107.292975 -414.071924)
			(xy 107.27944 -414.080452) (xy 107.271948 -414.085582) (xy 107.26092 -414.099991) (xy 107.255632 -414.117348)
			(xy 107.255818 -414.126426) (xy 107.256326 -414.14573) (xy 107.255839 -414.173018) (xy 107.248073 -414.227037)
			(xy 107.232697 -414.279401) (xy 107.210026 -414.329045) (xy 107.18052 -414.374956) (xy 107.144781 -414.416201)
			(xy 107.103536 -414.45194) (xy 107.057625 -414.481446) (xy 107.007981 -414.504117) (xy 106.955617 -414.519493)
			(xy 106.901598 -414.527259) (xy 106.847022 -414.527259) (xy 106.793003 -414.519493) (xy 106.740639 -414.504117)
			(xy 106.690995 -414.481446) (xy 106.645084 -414.45194) (xy 106.603839 -414.416201) (xy 106.5681 -414.374956)
			(xy 106.538594 -414.329045) (xy 106.515923 -414.279401) (xy 106.500547 -414.227037) (xy 106.492781 -414.173018)
			(xy 106.492294 -414.14573) (xy 106.492366 -414.134592) (xy 106.493635 -414.112353) (xy 106.494834 -414.10128)
			(xy 106.495088 -414.096708) (xy 106.469434 -414.080706) (xy 106.461178 -414.075992) (xy 106.44251 -414.072465)
			(xy 106.423842 -414.075992) (xy 106.415586 -414.080706) (xy 106.389932 -414.096708) (xy 106.390186 -414.10128)
			(xy 106.39139 -414.112353) (xy 106.392661 -414.134592) (xy 106.392726 -414.14573) (xy 106.392239 -414.173018)
			(xy 106.384473 -414.227037) (xy 106.369097 -414.279401) (xy 106.346426 -414.329045) (xy 106.31692 -414.374956)
			(xy 106.281181 -414.416201) (xy 106.239936 -414.45194) (xy 106.194025 -414.481446) (xy 106.144381 -414.504117)
			(xy 106.092017 -414.519493) (xy 106.037998 -414.527259) (xy 105.983422 -414.527259) (xy 105.929403 -414.519493)
			(xy 105.877039 -414.504117) (xy 105.827395 -414.481446) (xy 105.781484 -414.45194) (xy 105.740239 -414.416201)
			(xy 105.7045 -414.374956) (xy 105.674994 -414.329045) (xy 105.652323 -414.279401) (xy 105.636947 -414.227037)
			(xy 105.629181 -414.173018) (xy 105.628694 -414.14573) (xy 105.629202 -414.126426) (xy 105.629365 -414.117356)
			(xy 105.624038 -414.100027) (xy 105.613041 -414.085614) (xy 105.60558 -414.080452) (xy 105.592045 -414.071924)
			(xy 105.56562 -414.053884) (xy 105.552748 -414.044384) (xy 105.546014 -414.039705) (xy 105.530463 -414.034529)
			(xy 105.522268 -414.034224) (xy 103.654606 -414.034224) (xy 103.645886 -414.034602) (xy 103.629476 -414.040521)
			(xy 103.615984 -414.051579) (xy 103.611172 -414.058862) (xy 103.59054 -414.092351) (xy 103.543387 -414.155315)
			(xy 103.490004 -414.213091) (xy 103.430957 -414.265066) (xy 103.366875 -414.310687) (xy 103.298436 -414.349469)
			(xy 103.22637 -414.381001) (xy 103.151441 -414.404948) (xy 103.074445 -414.421056) (xy 102.996199 -414.429152)
			(xy 102.917537 -414.429152) (xy 102.839291 -414.421056) (xy 102.762295 -414.404948) (xy 102.687366 -414.381001)
			(xy 102.6153 -414.349469) (xy 102.546861 -414.310687) (xy 102.482779 -414.265066) (xy 102.423732 -414.213091)
			(xy 102.370349 -414.155315) (xy 102.323196 -414.092351) (xy 102.302564 -414.058862) (xy 102.29778 -414.051551)
			(xy 102.284299 -414.040458) (xy 102.26786 -414.034577) (xy 102.25913 -414.034224) (xy 102.172516 -414.034224)
			(xy 102.16168 -414.034807) (xy 102.14195 -414.043784) (xy 102.127649 -414.060074) (xy 102.124002 -414.070292)
			(xy 102.124002 -414.070546) (xy 102.119273 -414.085943) (xy 102.107577 -414.115957) (xy 102.100634 -414.13049)
			(xy 102.100634 -414.130744) (xy 102.097121 -414.138565) (xy 102.095024 -414.15557) (xy 102.098696 -414.172305)
			(xy 102.10292 -414.179766) (xy 102.143052 -414.244282) (xy 102.146568 -414.250384) (xy 102.150444 -414.263914)
			(xy 102.150672 -414.270952) (xy 102.150672 -414.27654) (xy 102.15118 -414.27654) (xy 102.15118 -421.173656)
			(xy 97.149412 -421.173656) (xy 97.149412 -414.434528) (xy 97.148382 -414.42788) (xy 97.143358 -414.415405)
			(xy 97.139506 -414.40989) (xy 97.117514 -414.38043) (xy 97.07866 -414.318016) (xy 97.045998 -414.252149)
			(xy 97.01983 -414.183443) (xy 97.0004 -414.112537) (xy 96.99371 -414.076388) (xy 96.991887 -414.067648)
			(xy 96.983009 -414.052169) (xy 96.969359 -414.040675) (xy 96.952594 -414.034562) (xy 96.943672 -414.034224)
			(xy 42.362882 -414.034224) (xy 42.35431 -414.034572) (xy 42.338137 -414.040264) (xy 42.324768 -414.050997)
			(xy 42.319956 -414.0581) (xy 42.267378 -414.142936) (xy 42.266108 -414.169098) (xy 42.272204 -414.181036)
			(xy 42.291182 -414.220667) (xy 42.320937 -414.303348) (xy 42.340995 -414.3889) (xy 42.351089 -414.47619)
			(xy 42.351706 -414.520126) (xy 42.351131 -414.562727) (xy 42.341628 -414.647397) (xy 42.322754 -414.730482)
			(xy 42.294744 -414.810948) (xy 42.257947 -414.887794) (xy 42.235882 -414.92424) (xy 42.231196 -414.93251)
			(xy 42.227659 -414.951169) (xy 42.231174 -414.969832) (xy 42.235882 -414.978088) (xy 42.258115 -415.014607)
			(xy 42.295158 -415.091667) (xy 42.32335 -415.172387) (xy 42.342337 -415.255754) (xy 42.35188 -415.340721)
			(xy 42.352468 -415.383472) (xy 42.352468 -415.383726) (xy 42.351979 -415.423727) (xy 42.343614 -415.503291)
			(xy 42.326978 -415.581545) (xy 42.302254 -415.657631) (xy 42.269712 -415.730717) (xy 42.229708 -415.8)
			(xy 42.182682 -415.864722) (xy 42.129149 -415.924174) (xy 42.069694 -415.977705) (xy 42.00497 -416.024728)
			(xy 41.935684 -416.064728) (xy 41.862598 -416.097267) (xy 41.78651 -416.121987) (xy 41.708256 -416.13862)
			(xy 41.628691 -416.146981) (xy 41.58869 -416.147504) (xy 41.547848 -416.14698) (xy 41.46663 -416.138265)
			(xy 41.386807 -416.120925) (xy 41.309294 -416.095158) (xy 41.234975 -416.06126) (xy 41.164703 -416.019617)
			(xy 41.099281 -415.970707) (xy 41.069006 -415.943288) (xy 41.059662 -415.935672) (xy 41.03649 -415.929163)
			(xy 41.024556 -415.930842) (xy 41.007398 -415.934034) (xy 40.972665 -415.937473) (xy 40.955214 -415.9377)
			(xy 40.954706 -415.9377) (xy 40.926705 -415.937107) (xy 40.871392 -415.928348) (xy 40.818131 -415.911044)
			(xy 40.768231 -415.885622) (xy 40.722923 -415.852707) (xy 40.683321 -415.813111) (xy 40.650401 -415.767806)
			(xy 40.624972 -415.71791) (xy 40.607662 -415.664651) (xy 40.598896 -415.609339) (xy 40.598344 -415.581338)
			(xy 40.598844 -415.55542) (xy 40.606362 -415.504132) (xy 40.621229 -415.454473) (xy 40.643134 -415.407493)
			(xy 40.671612 -415.36418) (xy 40.706065 -415.32545) (xy 40.745764 -415.292119) (xy 40.789873 -415.26489)
			(xy 40.813482 -415.254186) (xy 40.824266 -415.248777) (xy 40.83964 -415.230228) (xy 40.842946 -415.218626)
			(xy 40.852954 -415.176239) (xy 40.881331 -415.093895) (xy 40.918893 -415.015315) (xy 40.941498 -414.978088)
			(xy 40.946244 -414.969847) (xy 40.949763 -414.951169) (xy 40.946221 -414.932496) (xy 40.941498 -414.92424)
			(xy 40.919094 -414.887273) (xy 40.881857 -414.809262) (xy 40.853676 -414.727541) (xy 40.843708 -414.68548)
			(xy 40.840423 -414.673861) (xy 40.825056 -414.65529) (xy 40.814244 -414.64992) (xy 40.790553 -414.639275)
			(xy 40.746293 -414.612097) (xy 40.70645 -414.57878) (xy 40.671866 -414.54003) (xy 40.643276 -414.49667)
			(xy 40.621284 -414.449617) (xy 40.606359 -414.39987) (xy 40.598815 -414.348483) (xy 40.598344 -414.322514)
			(xy 40.598899 -414.294524) (xy 40.607651 -414.239231) (xy 40.62494 -414.185988) (xy 40.650343 -414.136103)
			(xy 40.683234 -414.090803) (xy 40.722804 -414.051205) (xy 40.768079 -414.01828) (xy 40.817945 -413.992841)
			(xy 40.871176 -413.975512) (xy 40.926462 -413.96672) (xy 40.954452 -413.966152) (xy 40.954706 -413.966152)
			(xy 40.972482 -413.96637) (xy 41.007855 -413.969937) (xy 41.025318 -413.973264) (xy 41.037263 -413.974994)
			(xy 41.060471 -413.968511) (xy 41.069768 -413.960818) (xy 41.087926 -413.944258) (xy 41.126057 -413.913247)
			(xy 41.145968 -413.898842) (xy 41.15476 -413.891948) (xy 41.165837 -413.872579) (xy 41.167304 -413.861504)
			(xy 41.173654 -413.784288) (xy 41.173981 -413.773199) (xy 41.166353 -413.752393) (xy 41.158922 -413.744156)
			(xy 40.235886 -412.82112) (xy 40.229712 -412.815342) (xy 40.214512 -412.807949) (xy 40.197731 -412.805926)
			(xy 40.189404 -412.807404) (xy 40.105838 -412.82493) (xy 40.093527 -412.828346) (xy 40.074201 -412.845007)
			(xy 40.069008 -412.85668) (xy 40.055409 -412.891106) (xy 40.022462 -412.957393) (xy 40.003222 -412.989014)
			(xy 39.998473 -412.997254) (xy 39.994954 -413.015933) (xy 39.998497 -413.034607) (xy 40.003222 -413.042862)
			(xy 40.025438 -413.079391) (xy 40.062485 -413.156448) (xy 40.090681 -413.237166) (xy 40.109672 -413.32053)
			(xy 40.119219 -413.405496) (xy 40.119808 -413.448246) (xy 40.119808 -413.4485) (xy 40.119255 -413.488499)
			(xy 40.110893 -413.56806) (xy 40.09426 -413.646311) (xy 40.06954 -413.722395) (xy 40.037002 -413.795478)
			(xy 39.997004 -413.864759) (xy 39.949982 -413.929481) (xy 39.896454 -413.988933) (xy 39.837004 -414.042464)
			(xy 39.772285 -414.089487) (xy 39.703005 -414.129489) (xy 39.629923 -414.162029) (xy 39.55384 -414.186753)
			(xy 39.47559 -414.203388) (xy 39.396029 -414.211753) (xy 39.35603 -414.212278) (xy 39.315189 -414.21171)
			(xy 39.233974 -414.203) (xy 39.154153 -414.185665) (xy 39.07664 -414.159905) (xy 39.002321 -414.126014)
			(xy 38.932047 -414.084379) (xy 38.866622 -414.035477) (xy 38.836346 -414.008062) (xy 38.827027 -414.00041)
			(xy 38.803835 -413.993923) (xy 38.791896 -413.995616) (xy 38.774739 -413.998817) (xy 38.740005 -414.00225)
			(xy 38.722554 -414.002474) (xy 38.722046 -414.002474) (xy 38.694043 -414.001899) (xy 38.638724 -413.993144)
			(xy 38.585457 -413.975843) (xy 38.535552 -413.950421) (xy 38.490238 -413.917505) (xy 38.450632 -413.877906)
			(xy 38.417709 -413.832598) (xy 38.392279 -413.782697) (xy 38.37497 -413.729432) (xy 38.366206 -413.674115)
			(xy 38.365684 -413.646112) (xy 38.366138 -413.620192) (xy 38.37366 -413.568901) (xy 38.388534 -413.51924)
			(xy 38.410444 -413.472258) (xy 38.438929 -413.428945) (xy 38.473388 -413.390216) (xy 38.513094 -413.356887)
			(xy 38.55721 -413.329662) (xy 38.580822 -413.31896) (xy 38.591591 -413.313528) (xy 38.60697 -413.294994)
			(xy 38.610286 -413.2834) (xy 38.620308 -413.241017) (xy 38.64868 -413.158672) (xy 38.686236 -413.08009)
			(xy 38.708838 -413.042862) (xy 38.71352 -413.03459) (xy 38.717057 -413.015932) (xy 38.713544 -412.99727)
			(xy 38.708838 -412.989014) (xy 38.686431 -412.952049) (xy 38.649195 -412.874037) (xy 38.621015 -412.792315)
			(xy 38.611048 -412.750254) (xy 38.607804 -412.73862) (xy 38.592409 -412.720054) (xy 38.581584 -412.714694)
			(xy 38.557908 -412.704019) (xy 38.513652 -412.676841) (xy 38.473812 -412.643527) (xy 38.439229 -412.604781)
			(xy 38.410638 -412.561426) (xy 38.388644 -412.514379) (xy 38.373712 -412.464637) (xy 38.36616 -412.413255)
			(xy 38.365684 -412.387288) (xy 38.366175 -412.359295) (xy 38.374932 -412.303998) (xy 38.392228 -412.25075)
			(xy 38.417637 -412.200863) (xy 38.450535 -412.155562) (xy 38.490113 -412.115963) (xy 38.535395 -412.08304)
			(xy 38.585269 -412.057603) (xy 38.638507 -412.040278) (xy 38.693799 -412.031491) (xy 38.721792 -412.030926)
			(xy 38.722046 -412.030926) (xy 38.739822 -412.031153) (xy 38.775194 -412.034714) (xy 38.792658 -412.038038)
			(xy 38.804601 -412.039801) (xy 38.827814 -412.033297) (xy 38.837108 -412.025592) (xy 38.86427 -412.001003)
			(xy 38.922522 -411.956556) (xy 38.984764 -411.917893) (xy 39.050422 -411.885369) (xy 39.084504 -411.871922)
			(xy 39.092286 -411.868625) (xy 39.10523 -411.857767) (xy 39.113937 -411.843289) (xy 39.116 -411.835092)
			(xy 39.13378 -411.751526) (xy 39.135253 -411.743202) (xy 39.133213 -411.72643) (xy 39.125816 -411.711239)
			(xy 39.120064 -411.705044) (xy 28.41371 -400.998944) (xy 28.404765 -400.990934) (xy 28.381967 -400.983507)
			(xy 28.370022 -400.98472) (xy 28.288742 -400.997166) (xy 28.276975 -400.999656) (xy 28.257497 -401.013718)
			(xy 28.251404 -401.02409) (xy 28.251404 -401.024344) (xy 28.233593 -401.057923) (xy 28.192279 -401.121729)
			(xy 28.144824 -401.18111) (xy 28.091699 -401.235477) (xy 28.033431 -401.284293) (xy 27.970598 -401.327071)
			(xy 27.903822 -401.36339) (xy 27.833765 -401.392888) (xy 27.761122 -401.415273) (xy 27.686613 -401.430323)
			(xy 27.610977 -401.437889) (xy 27.57297 -401.438364) (xy 27.533008 -401.437861) (xy 27.453523 -401.429507)
			(xy 27.375346 -401.41289) (xy 27.299335 -401.388192) (xy 27.226322 -401.355684) (xy 27.157106 -401.315723)
			(xy 27.092447 -401.268745) (xy 27.033053 -401.215266) (xy 26.979574 -401.155871) (xy 26.932596 -401.091212)
			(xy 26.892635 -401.021997) (xy 26.860127 -400.948983) (xy 26.83543 -400.872972) (xy 26.818813 -400.794795)
			(xy 26.810459 -400.71531) (xy 26.809954 -400.675348) (xy 26.809954 -400.675094) (xy 26.810579 -400.631828)
			(xy 26.820372 -400.545853) (xy 26.839842 -400.461541) (xy 26.868739 -400.379978) (xy 26.88717 -400.34083)
			(xy 26.89183 -400.330144) (xy 26.89197 -400.30686) (xy 26.887424 -400.296126) (xy 26.869087 -400.257082)
			(xy 26.840301 -400.175763) (xy 26.820885 -400.091714) (xy 26.811087 -400.006009) (xy 26.810462 -399.962878)
			(xy 26.810462 -399.962624) (xy 26.81103 -399.920618) (xy 26.820281 -399.837117) (xy 26.83865 -399.755138)
			(xy 26.865915 -399.675674) (xy 26.901747 -399.599687) (xy 26.923238 -399.56359) (xy 26.932636 -399.548604)
			(xy 26.928572 -399.513806) (xy 22.46757 -395.052804) (xy 22.450552 -395.045184) (xy 22.441154 -395.044676)
			(xy 22.402504 -395.04209) (xy 22.325964 -395.030148) (xy 22.251029 -395.010508) (xy 22.178472 -394.98337)
			(xy 22.109041 -394.949016) (xy 22.043451 -394.907798) (xy 21.982378 -394.860143) (xy 21.926452 -394.80654)
			(xy 21.876249 -394.747543) (xy 21.832287 -394.68376) (xy 21.795019 -394.615848) (xy 21.779484 -394.580364)
			(xy 21.747734 -394.581634) (xy 21.720483 -394.581113) (xy 21.666536 -394.573361) (xy 21.61424 -394.558011)
			(xy 21.564662 -394.535374) (xy 21.51881 -394.505912) (xy 21.477618 -394.470225) (xy 21.441924 -394.429038)
			(xy 21.412454 -394.383191) (xy 21.38981 -394.333616) (xy 21.374451 -394.281323) (xy 21.366691 -394.227377)
			(xy 21.366226 -394.200126) (xy 21.366776 -394.171928) (xy 21.375148 -394.116157) (xy 21.391641 -394.062226)
			(xy 21.40331 -394.03655) (xy 21.40331 -394.036042) (xy 21.407282 -394.026435) (xy 21.407967 -394.00568)
			(xy 21.40037 -393.986353) (xy 21.393404 -393.978638) (xy 19.967194 -392.552428) (xy 19.958686 -392.544702)
			(xy 19.937003 -392.537159) (xy 19.925538 -392.53795) (xy 19.92503 -392.53795) (xy 19.902951 -392.540416)
			(xy 19.8586 -392.543087) (xy 19.836384 -392.543284) (xy 19.83613 -392.543284) (xy 19.800898 -392.542839)
			(xy 19.730737 -392.536319) (xy 19.661475 -392.523358) (xy 19.593703 -392.504068) (xy 19.527998 -392.478613)
			(xy 19.496278 -392.463274) (xy 19.486138 -392.458785) (xy 19.463998 -392.458133) (xy 19.453606 -392.462004)
			(xy 19.417719 -392.477014) (xy 19.343547 -392.500475) (xy 19.267374 -392.516269) (xy 19.189989 -392.524232)
			(xy 19.151092 -392.524742) (xy 19.150584 -392.524742) (xy 19.110624 -392.524208) (xy 19.031142 -392.515853)
			(xy 18.952969 -392.499236) (xy 18.87696 -392.474538) (xy 18.80395 -392.442031) (xy 18.734737 -392.402071)
			(xy 18.670081 -392.355095) (xy 18.610688 -392.301619) (xy 18.557211 -392.242227) (xy 18.510234 -392.177571)
			(xy 18.470273 -392.108359) (xy 18.437765 -392.035349) (xy 18.413067 -391.959341) (xy 18.396449 -391.881168)
			(xy 18.388092 -391.801686) (xy 18.387568 -391.761726) (xy 18.387568 -391.760964) (xy 18.387653 -391.745516)
			(xy 18.388924 -391.714645) (xy 18.390108 -391.699242) (xy 18.390448 -391.689678) (xy 18.384848 -391.671396)
			(xy 18.379186 -391.663682) (xy 18.36039 -391.639806) (xy 18.354123 -391.632571) (xy 18.337538 -391.623042)
			(xy 18.328132 -391.621264) (xy 18.281967 -391.613663) (xy 18.191905 -391.588316) (xy 18.148554 -391.570718)
			(xy 18.138963 -391.567153) (xy 18.118521 -391.567153) (xy 18.10893 -391.570718) (xy 18.074528 -391.584887)
			(xy 18.003498 -391.607043) (xy 17.9306 -391.621942) (xy 17.856573 -391.629434) (xy 17.81937 -391.6299)
			(xy 17.819116 -391.6299) (xy 17.782015 -391.629431) (xy 17.70819 -391.621961) (xy 17.635487 -391.607126)
			(xy 17.564637 -391.585074) (xy 17.530318 -391.570972) (xy 17.520727 -391.567407) (xy 17.500285 -391.567407)
			(xy 17.490694 -391.570972) (xy 17.456459 -391.585013) (xy 17.385792 -391.606971) (xy 17.313282 -391.621743)
			(xy 17.239658 -391.629179) (xy 17.202658 -391.629646) (xy 17.20215 -391.629646) (xy 17.163533 -391.629133)
			(xy 17.086723 -391.62106) (xy 17.011177 -391.605002) (xy 16.937723 -391.581135) (xy 16.867167 -391.549722)
			(xy 16.80028 -391.511105) (xy 16.737797 -391.465708) (xy 16.680401 -391.414029) (xy 16.628722 -391.356633)
			(xy 16.583325 -391.29415) (xy 16.544708 -391.227263) (xy 16.513295 -391.156707) (xy 16.489428 -391.083253)
			(xy 16.47337 -391.007707) (xy 16.465297 -390.930897) (xy 16.465297 -390.853663) (xy 16.47337 -390.776853)
			(xy 16.489428 -390.701307) (xy 16.513295 -390.627853) (xy 16.544708 -390.557297) (xy 16.583325 -390.49041)
			(xy 16.628722 -390.427927) (xy 16.680401 -390.370531) (xy 16.737797 -390.318852) (xy 16.80028 -390.273455)
			(xy 16.867167 -390.234838) (xy 16.937723 -390.203425) (xy 17.011177 -390.179558) (xy 17.086723 -390.1635)
			(xy 17.163533 -390.155427) (xy 17.20215 -390.154922) (xy 17.231553 -390.155222) (xy 17.29017 -390.159925)
			(xy 17.319244 -390.16432) (xy 17.3355 -390.16686) (xy 17.36471 -390.152128) (xy 17.416526 -390.05129)
			(xy 17.420985 -390.041507) (xy 17.422133 -390.020059) (xy 17.414409 -390.000017) (xy 17.407128 -389.992108)
			(xy 16.211042 -388.796022) (xy 16.20436 -388.789783) (xy 16.187729 -388.782215) (xy 16.169499 -388.780975)
			(xy 16.151997 -388.786223) (xy 16.144494 -388.79145) (xy 16.120149 -388.808953) (xy 16.067024 -388.836749)
			(xy 16.010137 -388.855686) (xy 15.950952 -388.865276) (xy 15.920974 -388.865872) (xy 15.894353 -388.86549)
			(xy 15.841655 -388.857909) (xy 15.790571 -388.842905) (xy 15.742143 -388.820784) (xy 15.697357 -388.791995)
			(xy 15.657123 -388.757126) (xy 15.622261 -388.716886) (xy 15.593482 -388.672093) (xy 15.57137 -388.623661)
			(xy 15.556376 -388.572575) (xy 15.548805 -388.519875) (xy 15.548356 -388.493254) (xy 15.548925 -388.463275)
			(xy 15.558527 -388.404091) (xy 15.577475 -388.347206) (xy 15.605283 -388.294086) (xy 15.622778 -388.269734)
			(xy 15.627936 -388.262209) (xy 15.633102 -388.244727) (xy 15.631856 -388.22654) (xy 15.624353 -388.209926)
			(xy 15.618206 -388.203186) (xy 15.440406 -388.025386) (xy 15.406878 -388.020814) (xy 15.391892 -388.029196)
			(xy 15.363894 -388.044148) (xy 15.304061 -388.065319) (xy 15.241508 -388.076058) (xy 15.209774 -388.076694)
			(xy 15.183156 -388.076267) (xy 15.130462 -388.068688) (xy 15.079384 -388.053686) (xy 15.03096 -388.031567)
			(xy 14.986177 -388.002783) (xy 14.945947 -387.967918) (xy 14.911087 -387.927683) (xy 14.882309 -387.882896)
			(xy 14.860197 -387.834469) (xy 14.845202 -387.783389) (xy 14.837629 -387.730694) (xy 14.837156 -387.704076)
			(xy 14.837779 -387.672342) (xy 14.848527 -387.60979) (xy 14.869709 -387.54996) (xy 14.884654 -387.521958)
			(xy 14.893036 -387.506972) (xy 14.888464 -387.473444) (xy 14.701012 -387.286246) (xy 14.694401 -387.280088)
			(xy 14.678008 -387.27252) (xy 14.660005 -387.271149) (xy 14.651228 -387.273292) (xy 14.626291 -387.279943)
			(xy 14.575179 -387.28708) (xy 14.549374 -387.287516) (xy 14.522757 -387.287068) (xy 14.470065 -387.279488)
			(xy 14.418989 -387.264487) (xy 14.370566 -387.242371) (xy 14.325785 -387.213588) (xy 14.285554 -387.178726)
			(xy 14.250695 -387.138493) (xy 14.221916 -387.093709) (xy 14.199803 -387.045285) (xy 14.184806 -386.994207)
			(xy 14.17723 -386.941515) (xy 14.176756 -386.914898) (xy 14.177221 -386.889096) (xy 14.184353 -386.837985)
			(xy 14.19098 -386.813044) (xy 14.193078 -386.804266) (xy 14.191677 -386.786284) (xy 14.184142 -386.769897)
			(xy 14.178026 -386.76326) (xy 12.572238 -385.157472) (xy 12.55395 -385.149598) (xy 12.544044 -385.149598)
			(xy 12.517235 -385.148841) (xy 12.464231 -385.140656) (xy 12.412895 -385.125128) (xy 12.364239 -385.102565)
			(xy 12.319222 -385.073411) (xy 12.278731 -385.03824) (xy 12.243565 -384.997746) (xy 12.214415 -384.952726)
			(xy 12.191857 -384.904068) (xy 12.176335 -384.85273) (xy 12.168155 -384.799725) (xy 12.167362 -384.772916)
			(xy 12.167362 -384.76301) (xy 12.159488 -384.744722) (xy 12.107926 -384.69316) (xy 12.082018 -384.686302)
			(xy 12.069064 -384.689604) (xy 12.04566 -384.695277) (xy 11.997892 -384.701394) (xy 11.973814 -384.701796)
			(xy 11.973052 -384.701796) (xy 11.945799 -384.701367) (xy 11.891849 -384.693603) (xy 11.839552 -384.678242)
			(xy 11.789974 -384.655594) (xy 11.744123 -384.626122) (xy 11.702933 -384.590424) (xy 11.667242 -384.549229)
			(xy 11.637777 -384.503373) (xy 11.615137 -384.453792) (xy 11.599784 -384.401493) (xy 11.592029 -384.347541)
			(xy 11.591544 -384.320288) (xy 11.591544 -384.319526) (xy 11.591931 -384.295446) (xy 11.598046 -384.247677)
			(xy 11.603736 -384.224276) (xy 11.607038 -384.211322) (xy 11.60018 -384.185414) (xy 6.89991 -379.48489)
			(xy 6.893074 -379.477486) (xy 6.885352 -379.45889) (xy 6.884924 -379.448822) (xy 3.523996 -379.448822)
			(xy 3.523996 -403.371812) (xy 3.524481 -403.402978) (xy 3.532614 -403.464777) (xy 3.548748 -403.524985)
			(xy 3.572608 -403.58257) (xy 3.603784 -403.636545) (xy 3.641742 -403.685987) (xy 3.663442 -403.708362)
			(xy 6.991604 -407.036524) (xy 7.052397 -407.098056) (xy 7.168585 -407.226226) (xy 7.278345 -407.359941)
			(xy 7.381412 -407.49888) (xy 7.477539 -407.642708) (xy 7.566493 -407.79108) (xy 7.648061 -407.943637)
			(xy 7.722046 -408.100012) (xy 7.78827 -408.259829) (xy 7.846574 -408.422702) (xy 7.896816 -408.588239)
			(xy 7.938876 -408.756043) (xy 7.972653 -408.925707) (xy 7.998065 -409.096825) (xy 8.015052 -409.268983)
			(xy 8.023571 -409.441767) (xy 8.024114 -409.528264) (xy 8.024114 -416.06089) (xy 35.400488 -416.06089)
			(xy 35.40095 -416.032882) (xy 35.409715 -415.977556) (xy 35.427027 -415.924282) (xy 35.452461 -415.874373)
			(xy 35.48539 -415.829057) (xy 35.525003 -415.789451) (xy 35.570324 -415.75653) (xy 35.620238 -415.731104)
			(xy 35.673514 -415.713801) (xy 35.728842 -415.705045) (xy 35.75685 -415.704528) (xy 35.782851 -415.70503)
			(xy 35.8343 -415.712593) (xy 35.884104 -415.727553) (xy 35.931206 -415.74959) (xy 35.974605 -415.778238)
			(xy 36.013381 -415.812888) (xy 36.030408 -415.832544) (xy 36.036446 -415.839144) (xy 36.051945 -415.848048)
			(xy 36.06956 -415.85108) (xy 36.078414 -415.849816) (xy 36.112097 -415.844111) (xy 36.180144 -415.838004)
			(xy 36.214304 -415.837624) (xy 36.254305 -415.838142) (xy 36.333868 -415.846504) (xy 36.41212 -415.863138)
			(xy 36.488206 -415.88786) (xy 36.561291 -415.9204) (xy 36.630574 -415.960401) (xy 36.695296 -416.007425)
			(xy 36.754748 -416.060956) (xy 36.808279 -416.120409) (xy 36.855302 -416.185131) (xy 36.895303 -416.254415)
			(xy 36.927842 -416.3275) (xy 36.952564 -416.403585) (xy 36.969196 -416.481838) (xy 36.977559 -416.561401)
			(xy 36.977713 -416.573208) (xy 48.430688 -416.573208) (xy 48.431253 -416.533209) (xy 48.439614 -416.453649)
			(xy 48.456245 -416.375398) (xy 48.480965 -416.299315) (xy 48.513502 -416.226232) (xy 48.5535 -416.15695)
			(xy 48.60052 -416.092229) (xy 48.654048 -416.032777) (xy 48.713497 -415.979246) (xy 48.778215 -415.932222)
			(xy 48.847494 -415.892221) (xy 48.920575 -415.85968) (xy 48.996657 -415.834956) (xy 49.074907 -415.818321)
			(xy 49.154467 -415.809955) (xy 49.194466 -415.80943) (xy 49.234412 -415.809963) (xy 49.313868 -415.818288)
			(xy 49.392022 -415.83486) (xy 49.468019 -415.8595) (xy 49.541029 -415.891937) (xy 49.610254 -415.931817)
			(xy 49.674939 -415.978705) (xy 49.705006 -416.00501) (xy 49.713821 -416.01207) (xy 49.735423 -416.018545)
			(xy 49.746662 -416.017456) (xy 49.761048 -416.015347) (xy 49.790035 -416.013059) (xy 49.804574 -416.012884)
			(xy 49.831846 -416.013326) (xy 49.885837 -416.021086) (xy 49.938172 -416.036451) (xy 49.987789 -416.059109)
			(xy 50.033675 -416.088598) (xy 50.074896 -416.124318) (xy 50.110614 -416.165541) (xy 50.140101 -416.211429)
			(xy 50.162756 -416.261046) (xy 50.178119 -416.313383) (xy 50.185876 -416.367374) (xy 50.186336 -416.394646)
			(xy 50.185862 -416.422206) (xy 50.177922 -416.476751) (xy 50.162228 -416.52959) (xy 50.139105 -416.579626)
			(xy 50.109034 -416.625821) (xy 50.072638 -416.667216) (xy 50.030673 -416.702953) (xy 49.984008 -416.73229)
			(xy 49.959006 -416.743896) (xy 49.948984 -416.748983) (xy 49.934342 -416.765992) (xy 49.930812 -416.776662)
			(xy 49.92048 -416.812315) (xy 49.893815 -416.881596) (xy 49.860551 -416.947961) (xy 49.84115 -416.979608)
			(xy 49.835387 -416.989893) (xy 49.833015 -417.013326) (xy 49.836578 -417.024566) (xy 49.855827 -417.055342)
			(xy 49.889057 -417.119886) (xy 49.916008 -417.187294) (xy 49.936438 -417.256955) (xy 49.95016 -417.328242)
			(xy 49.957052 -417.40051) (xy 49.957482 -417.436808) (xy 49.957121 -417.469866) (xy 49.951385 -417.535732)
			(xy 49.939982 -417.600857) (xy 49.931828 -417.632896) (xy 49.931839 -417.642681) (xy 49.93837 -417.661106)
			(xy 49.944528 -417.66871) (xy 49.962373 -417.68976) (xy 49.99249 -417.735999) (xy 50.015644 -417.786088)
			(xy 50.031354 -417.838987) (xy 50.039292 -417.893595) (xy 50.039778 -417.921186) (xy 50.039263 -417.948454)
			(xy 50.031503 -418.002436) (xy 50.016141 -418.054764) (xy 49.993487 -418.104373) (xy 49.964004 -418.150253)
			(xy 49.928292 -418.191471) (xy 49.887077 -418.227186) (xy 49.841199 -418.256673) (xy 49.791592 -418.27933)
			(xy 49.739265 -418.294697) (xy 49.733111 -418.295582) (xy 51.383438 -418.295582) (xy 51.383438 -418.295328)
			(xy 51.383928 -418.268058) (xy 51.391686 -418.214072) (xy 51.407049 -418.16174) (xy 51.429703 -418.112126)
			(xy 51.459188 -418.066243) (xy 51.494902 -418.025022) (xy 51.53612 -417.989304) (xy 51.582002 -417.959816)
			(xy 51.631613 -417.937158) (xy 51.683944 -417.921792) (xy 51.73793 -417.91403) (xy 51.7652 -417.913566)
			(xy 51.793253 -417.91404) (xy 51.848752 -417.922275) (xy 51.902445 -417.938552) (xy 51.953174 -417.962521)
			(xy 51.999843 -417.993664) (xy 52.020978 -418.012118) (xy 52.029919 -418.019497) (xy 52.052146 -418.025986)
			(xy 52.06365 -418.024564) (xy 52.09541 -418.019477) (xy 52.159503 -418.014008) (xy 52.191666 -418.013642)
			(xy 52.231667 -418.01416) (xy 52.311232 -418.022519) (xy 52.389488 -418.03915) (xy 52.465576 -418.06387)
			(xy 52.538663 -418.096408) (xy 52.607948 -418.136408) (xy 52.672673 -418.183432) (xy 52.732127 -418.236963)
			(xy 52.78566 -418.296417) (xy 52.832684 -418.36114) (xy 52.872686 -418.430425) (xy 52.905225 -418.503511)
			(xy 52.929946 -418.579599) (xy 52.946579 -418.657854) (xy 52.95494 -418.737419) (xy 52.955444 -418.77742)
			(xy 52.954883 -418.820286) (xy 52.94528 -418.905479) (xy 52.926198 -418.989061) (xy 52.897876 -419.06998)
			(xy 52.86067 -419.147219) (xy 52.83835 -419.18382) (xy 52.832579 -419.194102) (xy 52.830212 -419.217538)
			(xy 52.833778 -419.228778) (xy 52.854216 -419.261522) (xy 52.889154 -419.330354) (xy 52.916973 -419.402358)
			(xy 52.937389 -419.476801) (xy 52.944268 -419.514782) (xy 52.948396 -419.524058) (xy 52.962537 -419.538604)
			(xy 52.9717 -419.542976) (xy 52.997318 -419.554307) (xy 53.045233 -419.583321) (xy 53.088397 -419.619023)
			(xy 53.125883 -419.660646) (xy 53.156887 -419.707298) (xy 53.180744 -419.757979) (xy 53.196943 -419.8116)
			(xy 53.205137 -419.867013) (xy 53.205634 -419.89502) (xy 53.205217 -419.922293) (xy 53.197451 -419.976283)
			(xy 53.182081 -420.028618) (xy 53.159419 -420.078233) (xy 53.129927 -420.124118) (xy 53.094205 -420.165339)
			(xy 53.05298 -420.201056) (xy 53.007091 -420.230542) (xy 52.957473 -420.253198) (xy 52.905136 -420.268562)
			(xy 52.851145 -420.27632) (xy 52.823872 -420.276782) (xy 52.80057 -420.276404) (xy 52.754317 -420.270693)
			(xy 52.7091 -420.259406) (xy 52.68722 -420.251382) (xy 52.677575 -420.248178) (xy 52.657275 -420.248845)
			(xy 52.64785 -420.252652) (xy 52.614874 -420.276613) (xy 52.544705 -420.318102) (xy 52.470513 -420.351875)
			(xy 52.393143 -420.377546) (xy 52.313478 -420.394823) (xy 52.232425 -420.40351) (xy 52.191666 -420.404036)
			(xy 52.151705 -420.403525) (xy 52.072223 -420.395168) (xy 51.994048 -420.378549) (xy 51.91804 -420.35385)
			(xy 51.845029 -420.321341) (xy 51.775816 -420.281379) (xy 51.711159 -420.234401) (xy 51.651767 -420.180923)
			(xy 51.59829 -420.12153) (xy 51.551313 -420.056872) (xy 51.511353 -419.987659) (xy 51.478845 -419.914647)
			(xy 51.454147 -419.838638) (xy 51.43753 -419.760464) (xy 51.429174 -419.680981) (xy 51.42865 -419.64102)
			(xy 51.42909 -419.604723) (xy 51.435981 -419.532456) (xy 51.449703 -419.461169) (xy 51.470132 -419.391508)
			(xy 51.497083 -419.324102) (xy 51.530312 -419.259559) (xy 51.549554 -419.228778) (xy 51.553199 -419.217551)
			(xy 51.550793 -419.194096) (xy 51.544982 -419.18382) (xy 51.522671 -419.147214) (xy 51.485469 -419.069976)
			(xy 51.45715 -418.989057) (xy 51.43807 -418.905477) (xy 51.428468 -418.820285) (xy 51.427888 -418.77742)
			(xy 51.428339 -418.740446) (xy 51.435503 -418.666846) (xy 51.449735 -418.59428) (xy 51.459892 -418.558726)
			(xy 51.462623 -418.547522) (xy 51.45894 -418.524784) (xy 51.45278 -418.515038) (xy 51.436446 -418.490783)
			(xy 51.410539 -418.438363) (xy 51.39292 -418.382607) (xy 51.384 -418.324818) (xy 51.383438 -418.295582)
			(xy 49.733111 -418.295582) (xy 49.685284 -418.30246) (xy 49.658016 -418.302948) (xy 49.628757 -418.302359)
			(xy 49.570927 -418.29342) (xy 49.515137 -418.275764) (xy 49.462693 -418.249804) (xy 49.414823 -418.216148)
			(xy 49.393348 -418.196268) (xy 49.385811 -418.18975) (xy 49.367242 -418.18257) (xy 49.35728 -418.182298)
			(xy 49.317078 -418.190506) (xy 49.235494 -418.199293) (xy 49.194466 -418.199824) (xy 49.154505 -418.199325)
			(xy 49.075021 -418.190968) (xy 48.996847 -418.174348) (xy 48.920837 -418.149649) (xy 48.847826 -418.117139)
			(xy 48.778612 -418.077176) (xy 48.713955 -418.030198) (xy 48.654563 -417.976719) (xy 48.601086 -417.917324)
			(xy 48.554109 -417.852666) (xy 48.514149 -417.783451) (xy 48.481642 -417.710439) (xy 48.456945 -417.634428)
			(xy 48.440328 -417.556253) (xy 48.431973 -417.476769) (xy 48.43145 -417.436808) (xy 48.431884 -417.40051)
			(xy 48.438776 -417.328243) (xy 48.452499 -417.256957) (xy 48.472929 -417.187296) (xy 48.499881 -417.119889)
			(xy 48.533112 -417.055346) (xy 48.552354 -417.024566) (xy 48.55594 -417.013326) (xy 48.553573 -416.989885)
			(xy 48.547782 -416.979608) (xy 48.525466 -416.943005) (xy 48.488265 -416.865766) (xy 48.459947 -416.784846)
			(xy 48.440868 -416.701265) (xy 48.431267 -416.616074) (xy 48.430688 -416.573208) (xy 36.977713 -416.573208)
			(xy 36.978082 -416.601402) (xy 36.977506 -416.644268) (xy 36.967906 -416.72946) (xy 36.948827 -416.813041)
			(xy 36.920508 -416.893961) (xy 36.883306 -416.9712) (xy 36.860988 -417.007802) (xy 36.855229 -417.018088)
			(xy 36.852857 -417.04152) (xy 36.856416 -417.05276) (xy 36.875655 -417.083542) (xy 36.908887 -417.148084)
			(xy 36.935841 -417.21549) (xy 36.956272 -417.285151) (xy 36.969996 -417.356437) (xy 36.976889 -417.428704)
			(xy 36.97732 -417.465002) (xy 36.976831 -417.503673) (xy 36.969006 -417.580618) (xy 36.953437 -417.656377)
			(xy 36.930284 -417.730172) (xy 36.899784 -417.801246) (xy 36.862249 -417.868869) (xy 36.818066 -417.932349)
			(xy 36.767688 -417.991033) (xy 36.711631 -418.044319) (xy 36.650471 -418.09166) (xy 36.584835 -418.132571)
			(xy 36.515397 -418.166632) (xy 36.44287 -418.193494) (xy 36.367997 -418.212879) (xy 36.291547 -418.224591)
			(xy 36.214304 -418.228509) (xy 36.137061 -418.224591) (xy 36.060611 -418.212879) (xy 35.985738 -418.193494)
			(xy 35.913211 -418.166632) (xy 35.843773 -418.132571) (xy 35.778137 -418.09166) (xy 35.716977 -418.044319)
			(xy 35.66092 -417.991033) (xy 35.610542 -417.932349) (xy 35.566359 -417.868869) (xy 35.528824 -417.801246)
			(xy 35.498324 -417.730172) (xy 35.475171 -417.656377) (xy 35.459602 -417.580618) (xy 35.451777 -417.503673)
			(xy 35.451288 -417.465002) (xy 35.451728 -417.428705) (xy 35.45862 -417.356438) (xy 35.472343 -417.285152)
			(xy 35.492772 -417.215491) (xy 35.519722 -417.148084) (xy 35.552951 -417.083541) (xy 35.572192 -417.05276)
			(xy 35.575777 -417.04152) (xy 35.573409 -417.01808) (xy 35.56762 -417.007802) (xy 35.545305 -416.971198)
			(xy 35.508104 -416.893959) (xy 35.479785 -416.81304) (xy 35.460705 -416.729459) (xy 35.451105 -416.644268)
			(xy 35.450526 -416.601402) (xy 35.450526 -416.600894) (xy 35.451159 -416.557049) (xy 35.461255 -416.46994)
			(xy 35.481245 -416.384558) (xy 35.495484 -416.343084) (xy 35.49823 -416.334547) (xy 35.498153 -416.316624)
			(xy 35.491903 -416.299827) (xy 35.48634 -416.292792) (xy 35.470221 -416.273331) (xy 35.443068 -416.230716)
			(xy 35.422211 -416.184691) (xy 35.40807 -416.136179) (xy 35.400929 -416.086155) (xy 35.400488 -416.06089)
			(xy 8.024114 -416.06089) (xy 8.024114 -421.400986) (xy 9.378442 -421.400986) (xy 9.378963 -421.372228)
			(xy 9.387572 -421.315362) (xy 9.404624 -421.260433) (xy 9.42973 -421.208688) (xy 9.462323 -421.161299)
			(xy 9.501662 -421.119343) (xy 9.546856 -421.08377) (xy 9.59688 -421.055387) (xy 9.623552 -421.044624)
			(xy 9.634657 -421.039609) (xy 9.650835 -421.021434) (xy 9.65454 -421.009826) (xy 9.66475 -420.972143)
			(xy 9.691826 -420.898912) (xy 9.726223 -420.82882) (xy 9.746488 -420.79545) (xy 9.751184 -420.787184)
			(xy 9.754721 -420.768522) (xy 9.7512 -420.749857) (xy 9.746488 -420.741602) (xy 9.726214 -420.708236)
			(xy 9.691806 -420.638149) (xy 9.664739 -420.564913) (xy 9.65454 -420.527226) (xy 9.65085 -420.515611)
			(xy 9.63466 -420.497442) (xy 9.623552 -420.492428) (xy 9.596899 -420.481626) (xy 9.546893 -420.453229)
			(xy 9.501713 -420.417652) (xy 9.462382 -420.375699) (xy 9.42979 -420.32832) (xy 9.404675 -420.276588)
			(xy 9.387606 -420.221673) (xy 9.378969 -420.164819) (xy 9.378442 -420.136066) (xy 9.378893 -420.108796)
			(xy 9.386659 -420.054811) (xy 9.402029 -420.00248) (xy 9.42469 -419.95287) (xy 9.454179 -419.906989)
			(xy 9.489898 -419.865771) (xy 9.531119 -419.830057) (xy 9.577003 -419.800571) (xy 9.626616 -419.777916)
			(xy 9.678948 -419.762551) (xy 9.732934 -419.75479) (xy 9.760204 -419.754304) (xy 9.783751 -419.754628)
			(xy 9.830495 -419.760356) (xy 9.853422 -419.765734) (xy 9.865391 -419.768069) (xy 9.889128 -419.762631)
			(xy 9.898888 -419.75532) (xy 9.928501 -419.730736) (xy 9.991813 -419.686968) (xy 10.059207 -419.649789)
			(xy 10.129998 -419.619578) (xy 10.203469 -419.59664) (xy 10.278875 -419.581208) (xy 10.35545 -419.57344)
			(xy 10.393934 -419.572948) (xy 10.394188 -419.572948) (xy 10.43419 -419.573449) (xy 10.513754 -419.581812)
			(xy 10.592009 -419.598445) (xy 10.668097 -419.623168) (xy 10.741183 -419.655708) (xy 10.810468 -419.695709)
			(xy 10.875192 -419.742734) (xy 10.934646 -419.796267) (xy 10.988178 -419.855721) (xy 11.035203 -419.920445)
			(xy 11.075204 -419.98973) (xy 11.107744 -420.062817) (xy 11.132466 -420.138904) (xy 11.149099 -420.217159)
			(xy 11.157461 -420.296724) (xy 11.157966 -420.336726) (xy 11.157373 -420.379416) (xy 11.147807 -420.464259)
			(xy 11.128843 -420.547507) (xy 11.100716 -420.628122) (xy 11.063778 -420.705099) (xy 11.041634 -420.741602)
			(xy 11.036916 -420.749853) (xy 11.033413 -420.768522) (xy 11.036932 -420.787189) (xy 11.041634 -420.79545)
			(xy 11.0638 -420.83194) (xy 11.100743 -420.908917) (xy 11.128866 -420.989535) (xy 11.147818 -421.072788)
			(xy 11.157364 -421.157635) (xy 11.157966 -421.200326) (xy 11.157479 -421.240327) (xy 11.149114 -421.319892)
			(xy 11.132478 -421.398146) (xy 11.10894 -421.470582) (xy 20.786598 -421.470582) (xy 20.787144 -421.441826)
			(xy 20.795753 -421.384962) (xy 20.812802 -421.330035) (xy 20.837906 -421.278291) (xy 20.870495 -421.230903)
			(xy 20.90983 -421.188946) (xy 20.955019 -421.153371) (xy 21.005038 -421.124985) (xy 21.031708 -421.11422)
			(xy 21.042805 -421.109191) (xy 21.058988 -421.091027) (xy 21.062696 -421.079422) (xy 21.072899 -421.041737)
			(xy 21.099978 -420.968506) (xy 21.134378 -420.898416) (xy 21.154644 -420.865046) (xy 21.159339 -420.856781)
			(xy 21.162871 -420.838119) (xy 21.159353 -420.819454) (xy 21.154644 -420.811198) (xy 21.134374 -420.77783)
			(xy 21.099964 -420.707744) (xy 21.072895 -420.634508) (xy 21.062696 -420.596822) (xy 21.058981 -420.585218)
			(xy 21.042808 -420.567045) (xy 21.031708 -420.562024) (xy 21.005044 -420.551249) (xy 20.955039 -420.522846)
			(xy 20.909861 -420.487264) (xy 20.870531 -420.445307) (xy 20.837941 -420.397924) (xy 20.812828 -420.346189)
			(xy 20.79576 -420.291272) (xy 20.787124 -420.234416) (xy 20.786598 -420.205662) (xy 20.787089 -420.178394)
			(xy 20.794855 -420.124412) (xy 20.810223 -420.072085) (xy 20.832881 -420.022478) (xy 20.862367 -419.976599)
			(xy 20.898081 -419.935383) (xy 20.939297 -419.899668) (xy 20.985176 -419.870182) (xy 21.034783 -419.847524)
			(xy 21.08711 -419.832155) (xy 21.141092 -419.824389) (xy 21.16836 -419.8239) (xy 21.191908 -419.824211)
			(xy 21.238651 -419.829948) (xy 21.261578 -419.83533) (xy 21.273551 -419.837637) (xy 21.297283 -419.832218)
			(xy 21.307044 -419.824916) (xy 21.336635 -419.800305) (xy 21.399951 -419.756539) (xy 21.467349 -419.719364)
			(xy 21.538144 -419.689156) (xy 21.611618 -419.666223) (xy 21.687027 -419.650796) (xy 21.763605 -419.643033)
			(xy 21.80209 -419.642544) (xy 21.802344 -419.642544) (xy 21.842346 -419.643004) (xy 21.921911 -419.651371)
			(xy 22.000166 -419.668009) (xy 22.076253 -419.692735) (xy 22.149339 -419.72528) (xy 22.218623 -419.765285)
			(xy 22.283345 -419.812313) (xy 22.342798 -419.865849) (xy 22.396328 -419.925306) (xy 22.443351 -419.990033)
			(xy 22.48335 -420.05932) (xy 22.515888 -420.132408) (xy 22.540608 -420.208498) (xy 22.557239 -420.286754)
			(xy 22.5656 -420.36632) (xy 22.566122 -420.406322) (xy 22.565518 -420.449012) (xy 22.555954 -420.533854)
			(xy 22.536991 -420.617102) (xy 22.508867 -420.697717) (xy 22.471932 -420.774695) (xy 22.44979 -420.811198)
			(xy 22.445078 -420.819451) (xy 22.441578 -420.838119) (xy 22.445092 -420.856784) (xy 22.44979 -420.865046)
			(xy 22.47195 -420.90154) (xy 22.508894 -420.978515) (xy 22.537019 -421.059132) (xy 22.555973 -421.142384)
			(xy 22.56552 -421.227231) (xy 22.566122 -421.269922) (xy 22.565575 -421.309921) (xy 22.557211 -421.389482)
			(xy 22.540577 -421.467732) (xy 22.515856 -421.543815) (xy 22.483317 -421.616898) (xy 22.443317 -421.686179)
			(xy 22.396295 -421.7509) (xy 22.342766 -421.810351) (xy 22.283317 -421.863882) (xy 22.218597 -421.910905)
			(xy 22.149317 -421.950907) (xy 22.076236 -421.983448) (xy 22.000154 -422.008172) (xy 21.921904 -422.024808)
			(xy 21.842343 -422.033174) (xy 21.802344 -422.0337) (xy 21.80209 -422.0337) (xy 21.763607 -422.033176)
			(xy 21.687032 -422.025413) (xy 21.611626 -422.009988) (xy 21.538154 -421.987057) (xy 21.467361 -421.956852)
			(xy 21.399966 -421.91968) (xy 21.336651 -421.875918) (xy 21.307044 -421.851328) (xy 21.297306 -421.843971)
			(xy 21.27355 -421.838537) (xy 21.261578 -421.840914) (xy 21.238652 -421.8463) (xy 21.191908 -421.852028)
			(xy 21.16836 -421.852344) (xy 21.141089 -421.851913) (xy 21.087102 -421.844145) (xy 21.034771 -421.828774)
			(xy 20.985159 -421.806112) (xy 20.939278 -421.77662) (xy 20.89806 -421.740899) (xy 20.862345 -421.699676)
			(xy 20.832861 -421.65379) (xy 20.810206 -421.604175) (xy 20.794843 -421.551841) (xy 20.787083 -421.497853)
			(xy 20.786598 -421.470582) (xy 11.10894 -421.470582) (xy 11.107754 -421.474232) (xy 11.075211 -421.547317)
			(xy 11.035208 -421.6166) (xy 10.988182 -421.681323) (xy 10.934648 -421.740775) (xy 10.875193 -421.794306)
			(xy 10.810468 -421.841329) (xy 10.741183 -421.881329) (xy 10.668096 -421.913867) (xy 10.592009 -421.938588)
			(xy 10.513754 -421.95522) (xy 10.434189 -421.963581) (xy 10.394188 -421.964104) (xy 10.393934 -421.964104)
			(xy 10.35545 -421.963612) (xy 10.278874 -421.955844) (xy 10.203468 -421.940414) (xy 10.129996 -421.917477)
			(xy 10.059203 -421.887268) (xy 9.991808 -421.850091) (xy 9.928494 -421.806324) (xy 9.898888 -421.781732)
			(xy 9.889133 -421.774402) (xy 9.865391 -421.768952) (xy 9.853422 -421.771318) (xy 9.830495 -421.776696)
			(xy 9.783751 -421.78243) (xy 9.760204 -421.782748) (xy 9.732932 -421.782295) (xy 9.678944 -421.774533)
			(xy 9.626611 -421.759166) (xy 9.576997 -421.736508) (xy 9.531112 -421.70702) (xy 9.489892 -421.671301)
			(xy 9.454174 -421.63008) (xy 9.424687 -421.584195) (xy 9.40203 -421.53458) (xy 9.386665 -421.482246)
			(xy 9.378905 -421.428258) (xy 9.378442 -421.400986) (xy 8.024114 -421.400986) (xy 8.024114 -422.130474)
			(xy 24.494744 -422.130474) (xy 24.495304 -422.087608) (xy 24.504908 -422.002415) (xy 24.52399 -421.918833)
			(xy 24.552312 -421.837914) (xy 24.589518 -421.760675) (xy 24.611838 -421.724074) (xy 24.617612 -421.713794)
			(xy 24.619977 -421.690356) (xy 24.61641 -421.679116) (xy 24.597152 -421.648345) (xy 24.563923 -421.5838)
			(xy 24.536974 -421.516391) (xy 24.516546 -421.446728) (xy 24.502825 -421.375441) (xy 24.495935 -421.303172)
			(xy 24.495506 -421.266874) (xy 24.495982 -421.226912) (xy 24.504339 -421.147427) (xy 24.520959 -421.06925)
			(xy 24.545659 -420.993239) (xy 24.578169 -420.920226) (xy 24.618133 -420.851012) (xy 24.665113 -420.786354)
			(xy 24.718595 -420.726961) (xy 24.777991 -420.673483) (xy 24.842652 -420.626507) (xy 24.911869 -420.586548)
			(xy 24.984884 -420.554042) (xy 25.060897 -420.529346) (xy 25.139074 -420.512732) (xy 25.21856 -420.50438)
			(xy 25.258522 -420.503858) (xy 25.297603 -420.504357) (xy 25.375356 -420.512337) (xy 25.451886 -420.528221)
			(xy 25.526393 -420.551842) (xy 25.598095 -420.582954) (xy 25.666243 -420.62123) (xy 25.730123 -420.66627)
			(xy 25.759918 -420.691564) (xy 25.768627 -420.69597) (xy 25.787949 -420.698598) (xy 25.79751 -420.696644)
			(xy 25.820737 -420.691085) (xy 25.868119 -420.685094) (xy 25.891998 -420.684706) (xy 25.892506 -420.684706)
			(xy 25.919774 -420.685219) (xy 25.973755 -420.69298) (xy 26.026082 -420.708345) (xy 26.07569 -420.730999)
			(xy 26.121438 -420.760398) (xy 58.141108 -420.760398) (xy 58.141108 -418.218874) (xy 58.141589 -418.206761)
			(xy 58.14908 -418.183722) (xy 58.16332 -418.164123) (xy 58.182918 -418.149882) (xy 58.205957 -418.14239)
			(xy 58.21807 -418.141912) (xy 59.15787 -418.141912) (xy 59.169989 -418.142385) (xy 59.193042 -418.149866)
			(xy 59.212655 -418.164105) (xy 59.226908 -418.183708) (xy 59.234406 -418.206756) (xy 59.234832 -418.218874)
			(xy 59.234832 -420.760398) (xy 59.234438 -420.772524) (xy 59.226942 -420.795587) (xy 59.212685 -420.815205)
			(xy 59.193062 -420.829455) (xy 59.169996 -420.836942) (xy 59.15787 -420.83736) (xy 58.21807 -420.83736)
			(xy 58.205954 -420.836914) (xy 58.182909 -420.829418) (xy 58.163308 -420.81517) (xy 58.149067 -420.795562)
			(xy 58.141581 -420.772515) (xy 58.141108 -420.760398) (xy 26.121438 -420.760398) (xy 26.12157 -420.760483)
			(xy 26.162786 -420.796195) (xy 26.198501 -420.83741) (xy 26.227988 -420.883287) (xy 26.250646 -420.932893)
			(xy 26.266014 -420.98522) (xy 26.273779 -421.0392) (xy 26.274268 -421.066468) (xy 26.273775 -421.095347)
			(xy 26.265065 -421.152444) (xy 26.247855 -421.207578) (xy 26.222537 -421.259491) (xy 26.189688 -421.306998)
			(xy 26.150059 -421.349015) (xy 26.104554 -421.384585) (xy 26.05421 -421.412894) (xy 26.02738 -421.423592)
			(xy 26.018391 -421.427514) (xy 26.004016 -421.440827) (xy 25.99944 -421.4495) (xy 25.988848 -421.490002)
			(xy 25.960015 -421.568602) (xy 25.922767 -421.643581) (xy 25.900634 -421.679116) (xy 25.896995 -421.690344)
			(xy 25.899397 -421.713797) (xy 25.905206 -421.724074) (xy 25.907079 -421.727138) (xy 26.688369 -421.727138)
			(xy 26.688369 -421.67226) (xy 26.69623 -421.617948) (xy 26.71179 -421.565322) (xy 26.734728 -421.515468)
			(xy 26.76457 -421.469414) (xy 26.800702 -421.42811) (xy 26.842378 -421.392407) (xy 26.888738 -421.363042)
			(xy 26.938827 -421.340621) (xy 26.99161 -421.325605) (xy 27.018742 -421.321484) (xy 27.029854 -421.319379)
			(xy 27.04883 -421.307125) (xy 27.055318 -421.297862) (xy 27.076126 -421.265078) (xy 27.123449 -421.203511)
			(xy 27.17678 -421.147067) (xy 27.235567 -421.096331) (xy 27.299202 -421.051826) (xy 27.367028 -421.014015)
			(xy 27.438343 -420.983286) (xy 27.51241 -420.959958) (xy 27.588463 -420.944272) (xy 27.665715 -420.936391)
			(xy 27.704542 -420.935912) (xy 27.747231 -420.936549) (xy 27.832072 -420.946105) (xy 27.91532 -420.965059)
			(xy 27.995935 -420.993176) (xy 28.072914 -421.030105) (xy 28.109418 -421.052244) (xy 28.117679 -421.05694)
			(xy 28.136342 -421.060448) (xy 28.155005 -421.05694) (xy 28.163266 -421.052244) (xy 28.199751 -421.030069)
			(xy 28.276729 -420.993129) (xy 28.357349 -420.965007) (xy 28.440602 -420.946057) (xy 28.525451 -420.936513)
			(xy 28.568142 -420.935912) (xy 28.606968 -420.936389) (xy 28.684218 -420.944277) (xy 28.760268 -420.959968)
			(xy 28.834332 -420.9833) (xy 28.905644 -421.014031) (xy 28.973467 -421.051844) (xy 29.037101 -421.096348)
			(xy 29.095887 -421.147083) (xy 29.149218 -421.203525) (xy 29.196542 -421.265089) (xy 29.217366 -421.297862)
			(xy 29.223827 -421.307157) (xy 29.242811 -421.319429) (xy 29.253942 -421.321484) (xy 29.281066 -421.32563)
			(xy 29.333837 -421.340653) (xy 29.383913 -421.363079) (xy 29.43026 -421.392446) (xy 29.471924 -421.428148)
			(xy 29.508045 -421.469449) (xy 29.537879 -421.515498) (xy 29.560809 -421.565345) (xy 29.576364 -421.617962)
			(xy 29.584222 -421.672265) (xy 29.584223 -421.727133) (xy 29.576364 -421.781435) (xy 29.56081 -421.834053)
			(xy 29.53788 -421.8839) (xy 29.508047 -421.929949) (xy 29.471926 -421.97125) (xy 29.430263 -422.006953)
			(xy 29.383915 -422.03632) (xy 29.33384 -422.058746) (xy 29.281068 -422.073769) (xy 29.253942 -422.077896)
			(xy 29.24283 -422.080001) (xy 29.223855 -422.092256) (xy 29.217366 -422.101518) (xy 29.196562 -422.134304)
			(xy 29.149239 -422.195873) (xy 29.095908 -422.252317) (xy 29.037121 -422.303054) (xy 28.973485 -422.347558)
			(xy 28.905659 -422.38537) (xy 28.834343 -422.416098) (xy 28.760276 -422.439425) (xy 28.684222 -422.45511)
			(xy 28.606969 -422.46299) (xy 28.568142 -422.463468) (xy 28.525453 -422.462842) (xy 28.440611 -422.453284)
			(xy 28.357363 -422.434327) (xy 28.276748 -422.406208) (xy 28.19977 -422.369277) (xy 28.163266 -422.347136)
			(xy 28.155005 -422.34244) (xy 28.136342 -422.338932) (xy 28.117679 -422.34244) (xy 28.109418 -422.347136)
			(xy 28.072911 -422.369274) (xy 27.995939 -422.406222) (xy 27.915325 -422.43435) (xy 27.832076 -422.45331)
			(xy 27.747232 -422.462862) (xy 27.704542 -422.463468) (xy 27.665717 -422.462966) (xy 27.588469 -422.455077)
			(xy 27.512421 -422.439386) (xy 27.438358 -422.416056) (xy 27.367048 -422.385327) (xy 27.299225 -422.347516)
			(xy 27.235591 -422.303016) (xy 27.176804 -422.252285) (xy 27.123471 -422.195848) (xy 27.076144 -422.134288)
			(xy 27.055318 -422.101518) (xy 27.048869 -422.092213) (xy 27.029876 -422.079948) (xy 27.018742 -422.077896)
			(xy 26.991608 -422.073794) (xy 26.938824 -422.058779) (xy 26.888736 -422.036357) (xy 26.842376 -422.006992)
			(xy 26.8007 -421.971289) (xy 26.764569 -421.929984) (xy 26.734727 -421.883929) (xy 26.711789 -421.834075)
			(xy 26.69623 -421.781449) (xy 26.688369 -421.727138) (xy 25.907079 -421.727138) (xy 25.925889 -421.757909)
			(xy 25.960911 -421.829061) (xy 25.98838 -421.903457) (xy 25.998678 -421.941752) (xy 26.002309 -421.953334)
			(xy 26.018376 -421.97149) (xy 26.029412 -421.97655) (xy 26.056064 -421.987324) (xy 26.106029 -422.015754)
			(xy 26.151166 -422.051355) (xy 26.190455 -422.09332) (xy 26.223008 -422.140702) (xy 26.248089 -422.192429)
			(xy 26.265131 -422.247331) (xy 26.273748 -422.304169) (xy 26.274268 -422.332912) (xy 26.273787 -422.360181)
			(xy 26.266024 -422.414165) (xy 26.250657 -422.466494) (xy 26.228 -422.516104) (xy 26.198513 -422.561984)
			(xy 26.162798 -422.603202) (xy 26.12158 -422.638917) (xy 26.078761 -422.666435) (xy 38.128055 -422.666435)
			(xy 38.128055 -422.61156) (xy 38.135915 -422.557251) (xy 38.151473 -422.504628) (xy 38.174408 -422.454775)
			(xy 38.204247 -422.408722) (xy 38.240374 -422.367417) (xy 38.282045 -422.331713) (xy 38.328401 -422.302346)
			(xy 38.378485 -422.279921) (xy 38.431264 -422.2649) (xy 38.458394 -422.260776) (xy 38.4695 -422.25865)
			(xy 38.488479 -422.246411) (xy 38.49497 -422.237154) (xy 38.515808 -422.20439) (xy 38.563128 -422.142823)
			(xy 38.616456 -422.086379) (xy 38.675239 -422.035642) (xy 38.738871 -421.991137) (xy 38.806693 -421.953323)
			(xy 38.878005 -421.922592) (xy 38.952068 -421.899261) (xy 39.028118 -421.883571) (xy 39.105368 -421.875685)
			(xy 39.144194 -421.875204) (xy 39.186883 -421.875817) (xy 39.271726 -421.885379) (xy 39.354974 -421.904339)
			(xy 39.435589 -421.932461) (xy 39.512566 -421.969394) (xy 39.54907 -421.991536) (xy 39.557331 -421.996232)
			(xy 39.575994 -421.99974) (xy 39.594657 -421.996232) (xy 39.602918 -421.991536) (xy 39.63942 -421.969391)
			(xy 39.716393 -421.932443) (xy 39.797008 -421.904315) (xy 39.880258 -421.885358) (xy 39.965104 -421.875808)
			(xy 40.007794 -421.875204) (xy 40.046621 -421.875643) (xy 40.123872 -421.883536) (xy 40.199923 -421.899233)
			(xy 40.273987 -421.922569) (xy 40.345299 -421.953305) (xy 40.410676 -421.989758) (xy 41.018968 -421.989758)
			(xy 41.019385 -421.962486) (xy 41.027154 -421.908499) (xy 41.042526 -421.856166) (xy 41.065189 -421.806554)
			(xy 41.094682 -421.760672) (xy 41.130405 -421.719454) (xy 41.171629 -421.683739) (xy 41.217517 -421.654255)
			(xy 41.267134 -421.631601) (xy 41.319469 -421.616238) (xy 41.373458 -421.60848) (xy 41.40073 -421.607996)
			(xy 41.425071 -421.608402) (xy 41.473352 -421.614642) (xy 41.496996 -421.620442) (xy 41.508967 -421.622758)
			(xy 41.532701 -421.617333) (xy 41.542462 -421.610028) (xy 41.571991 -421.5858) (xy 41.635035 -421.542669)
			(xy 41.70207 -421.506047) (xy 41.772426 -421.476299) (xy 41.8454 -421.453724) (xy 41.920263 -421.438545)
			(xy 41.996267 -421.430916) (xy 42.03446 -421.43045) (xy 42.034714 -421.43045) (xy 42.074717 -421.430914)
			(xy 42.154283 -421.439279) (xy 42.23254 -421.455914) (xy 42.308629 -421.480639) (xy 42.381717 -421.513182)
			(xy 42.451002 -421.553186) (xy 42.515727 -421.600214) (xy 42.575181 -421.653749) (xy 42.628713 -421.713206)
			(xy 42.675737 -421.777933) (xy 42.715737 -421.847221) (xy 42.748276 -421.92031) (xy 42.772997 -421.996401)
			(xy 42.789628 -422.074658) (xy 42.797988 -422.154225) (xy 42.798492 -422.194228) (xy 42.797896 -422.236918)
			(xy 42.78833 -422.321761) (xy 42.769366 -422.405009) (xy 42.741241 -422.485624) (xy 42.704303 -422.562601)
			(xy 42.68216 -422.599104) (xy 42.677438 -422.607353) (xy 42.673934 -422.626024) (xy 42.677456 -422.644691)
			(xy 42.68216 -422.652952) (xy 42.704319 -422.689446) (xy 42.741264 -422.766422) (xy 42.76939 -422.847038)
			(xy 42.788344 -422.93029) (xy 42.79789 -423.015137) (xy 42.798492 -423.057828) (xy 42.797981 -423.097829)
			(xy 42.789616 -423.177391) (xy 42.772981 -423.255643) (xy 42.748257 -423.331728) (xy 42.715716 -423.404812)
			(xy 42.675714 -423.474095) (xy 42.62869 -423.538816) (xy 42.575158 -423.598268) (xy 42.515705 -423.651799)
			(xy 42.450983 -423.698822) (xy 42.3817 -423.738822) (xy 42.308615 -423.771362) (xy 42.23253 -423.796084)
			(xy 42.154277 -423.812718) (xy 42.074715 -423.821082) (xy 42.034714 -423.821606) (xy 41.998052 -423.821162)
			(xy 41.925065 -423.814143) (xy 41.853086 -423.800168) (xy 41.782775 -423.779366) (xy 41.714779 -423.751927)
			(xy 41.649722 -423.718104) (xy 41.588203 -423.678207) (xy 41.559226 -423.655744) (xy 41.549213 -423.648507)
			(xy 41.52498 -423.643844) (xy 41.512998 -423.646854) (xy 41.486074 -423.65445) (xy 41.430732 -423.662617)
			(xy 41.402762 -423.66311) (xy 41.375494 -423.662611) (xy 41.321513 -423.654845) (xy 41.269187 -423.639478)
			(xy 41.21958 -423.616821) (xy 41.173701 -423.587335) (xy 41.132485 -423.551622) (xy 41.096771 -423.510407)
			(xy 41.067284 -423.464529) (xy 41.044626 -423.414922) (xy 41.029257 -423.362597) (xy 41.02149 -423.308616)
			(xy 41.021 -423.281348) (xy 41.021529 -423.253075) (xy 41.029879 -423.197147) (xy 41.046374 -423.143059)
			(xy 41.070655 -423.09199) (xy 41.102192 -423.045054) (xy 41.140297 -423.003273) (xy 41.18414 -422.96756)
			(xy 41.232764 -422.938693) (xy 41.258744 -422.927526) (xy 41.269839 -422.922217) (xy 41.285757 -422.903513)
			(xy 41.289224 -422.891712) (xy 41.299209 -422.849656) (xy 41.327398 -422.767941) (xy 41.364626 -422.689927)
			(xy 41.387014 -422.652952) (xy 41.391706 -422.644685) (xy 41.395242 -422.626024) (xy 41.391724 -422.60736)
			(xy 41.387014 -422.599104) (xy 41.366403 -422.565173) (xy 41.331531 -422.493846) (xy 41.304245 -422.419287)
			(xy 41.29405 -422.380918) (xy 41.290432 -422.369218) (xy 41.274225 -422.350907) (xy 41.263062 -422.345866)
			(xy 41.236502 -422.334999) (xy 41.186681 -422.306526) (xy 41.141682 -422.270917) (xy 41.102519 -422.228977)
			(xy 41.070072 -422.181648) (xy 41.045072 -422.129996) (xy 41.028084 -422.075185) (xy 41.019488 -422.01845)
			(xy 41.018968 -421.989758) (xy 40.410676 -421.989758) (xy 40.413122 -421.991122) (xy 40.476755 -422.035629)
			(xy 40.535541 -422.086368) (xy 40.588871 -422.142812) (xy 40.636195 -422.20438) (xy 40.657018 -422.237154)
			(xy 40.663458 -422.246467) (xy 40.682457 -422.25873) (xy 40.693594 -422.260776) (xy 40.720717 -422.264935)
			(xy 40.773493 -422.279952) (xy 40.823574 -422.302374) (xy 40.869926 -422.331738) (xy 40.911595 -422.367439)
			(xy 40.94772 -422.40874) (xy 40.977557 -422.454789) (xy 41.000491 -422.504638) (xy 41.016048 -422.557257)
			(xy 41.023908 -422.611562) (xy 41.023908 -422.666433) (xy 41.016049 -422.720738) (xy 41.000493 -422.773358)
			(xy 40.97756 -422.823206) (xy 40.947723 -422.869256) (xy 40.911598 -422.910558) (xy 40.86993 -422.946259)
			(xy 40.823578 -422.975624) (xy 40.773498 -422.998046) (xy 40.720722 -423.013064) (xy 40.693594 -423.017188)
			(xy 40.68249 -423.019322) (xy 40.663511 -423.031556) (xy 40.657018 -423.04081) (xy 40.636175 -423.073571)
			(xy 40.588857 -423.13514) (xy 40.535531 -423.191585) (xy 40.476748 -423.242322) (xy 40.413117 -423.286829)
			(xy 40.345295 -423.324643) (xy 40.273983 -423.355374) (xy 40.19992 -423.378705) (xy 40.12387 -423.394394)
			(xy 40.04662 -423.402279) (xy 40.007794 -423.40276) (xy 39.965104 -423.402158) (xy 39.880261 -423.392595)
			(xy 39.797013 -423.373632) (xy 39.716398 -423.345508) (xy 39.639421 -423.308571) (xy 39.602918 -423.286428)
			(xy 39.594657 -423.281732) (xy 39.575994 -423.278224) (xy 39.557331 -423.281732) (xy 39.54907 -423.286428)
			(xy 39.512575 -423.308585) (xy 39.435599 -423.345529) (xy 39.354983 -423.373654) (xy 39.271731 -423.392609)
			(xy 39.186885 -423.402157) (xy 39.144194 -423.40276) (xy 39.105368 -423.402301) (xy 39.028118 -423.394407)
			(xy 38.952069 -423.378711) (xy 38.878006 -423.355376) (xy 38.806695 -423.324642) (xy 38.738872 -423.286827)
			(xy 38.675239 -423.242322) (xy 38.616452 -423.191587) (xy 38.563121 -423.135146) (xy 38.515794 -423.073583)
			(xy 38.49497 -423.04081) (xy 38.488544 -423.031486) (xy 38.469534 -423.01923) (xy 38.458394 -423.017188)
			(xy 38.431259 -423.013099) (xy 38.37848 -422.998078) (xy 38.328397 -422.975652) (xy 38.282042 -422.946284)
			(xy 38.240371 -422.91058) (xy 38.204244 -422.869274) (xy 38.174406 -422.823221) (xy 38.151471 -422.773368)
			(xy 38.135914 -422.720744) (xy 38.128055 -422.666435) (xy 26.078761 -422.666435) (xy 26.075699 -422.668403)
			(xy 26.026088 -422.691059) (xy 25.973759 -422.706425) (xy 25.919775 -422.714187) (xy 25.892506 -422.714674)
			(xy 25.868562 -422.714312) (xy 25.821051 -422.708319) (xy 25.797764 -422.702736) (xy 25.785797 -422.700376)
			(xy 25.762055 -422.705828) (xy 25.752298 -422.71315) (xy 25.722753 -422.737622) (xy 25.659542 -422.781107)
			(xy 25.592289 -422.818034) (xy 25.521673 -422.848031) (xy 25.448404 -422.870795) (xy 25.373222 -422.886097)
			(xy 25.296884 -422.893783) (xy 25.258522 -422.894252) (xy 25.21852 -422.893752) (xy 25.138954 -422.885391)
			(xy 25.060699 -422.868759) (xy 24.98461 -422.844038) (xy 24.911523 -422.811498) (xy 24.842237 -422.771497)
			(xy 24.777513 -422.724472) (xy 24.718058 -422.670939) (xy 24.664526 -422.611484) (xy 24.617501 -422.546759)
			(xy 24.5775 -422.477474) (xy 24.544961 -422.404386) (xy 24.52024 -422.328297) (xy 24.503608 -422.250042)
			(xy 24.495248 -422.170476) (xy 24.494744 -422.130474) (xy 8.024114 -422.130474) (xy 8.024114 -425.887642)
			(xy 9.824466 -425.887642) (xy 9.825079 -425.844951) (xy 9.834618 -425.760104) (xy 9.853568 -425.676852)
			(xy 9.881695 -425.596236) (xy 9.918645 -425.519264) (xy 9.940798 -425.482766) (xy 9.94548 -425.474494)
			(xy 9.949021 -425.455836) (xy 9.945507 -425.437173) (xy 9.940798 -425.428918) (xy 9.918628 -425.392427)
			(xy 9.881644 -425.315466) (xy 9.853502 -425.234849) (xy 9.834556 -425.151591) (xy 9.825043 -425.066736)
			(xy 9.824466 -425.024042) (xy 9.824955 -424.985423) (xy 9.832769 -424.90858) (xy 9.848317 -424.832922)
			(xy 9.87144 -424.759225) (xy 9.901899 -424.688246) (xy 9.939384 -424.620712) (xy 9.983508 -424.557318)
			(xy 10.033819 -424.498712) (xy 10.089801 -424.445497) (xy 10.15088 -424.398218) (xy 10.216428 -424.357362)
			(xy 10.285774 -424.323346) (xy 10.358205 -424.296521) (xy 10.432978 -424.277161) (xy 10.509326 -424.265465)
			(xy 10.586466 -424.261553) (xy 10.663606 -424.265465) (xy 10.739954 -424.277161) (xy 10.814727 -424.296521)
			(xy 10.887158 -424.323346) (xy 10.956504 -424.357362) (xy 11.022052 -424.398218) (xy 11.083131 -424.445497)
			(xy 11.139113 -424.498712) (xy 11.189424 -424.557318) (xy 11.233548 -424.620712) (xy 11.271033 -424.688246)
			(xy 11.301492 -424.759225) (xy 11.324615 -424.832922) (xy 11.340163 -424.90858) (xy 11.347977 -424.985423)
			(xy 11.348466 -425.024042) (xy 11.347855 -425.066733) (xy 11.338318 -425.151581) (xy 11.319367 -425.234833)
			(xy 11.29124 -425.315449) (xy 11.254288 -425.392421) (xy 11.232134 -425.428918) (xy 11.227388 -425.437158)
			(xy 11.223876 -425.455836) (xy 11.227415 -425.474509) (xy 11.232134 -425.482766) (xy 11.254301 -425.519259)
			(xy 11.258979 -425.528994) (xy 21.308568 -425.528994) (xy 21.309143 -425.500239) (xy 21.317749 -425.443377)
			(xy 21.334796 -425.388452) (xy 21.359896 -425.336709) (xy 21.392481 -425.289322) (xy 21.431811 -425.247364)
			(xy 21.476996 -425.211788) (xy 21.52701 -425.183399) (xy 21.553678 -425.172632) (xy 21.564786 -425.167622)
			(xy 21.580961 -425.149443) (xy 21.584666 -425.137834) (xy 21.594875 -425.100151) (xy 21.621952 -425.02692)
			(xy 21.656349 -424.956828) (xy 21.676614 -424.923458) (xy 21.681302 -424.915189) (xy 21.684839 -424.896529)
			(xy 21.681323 -424.877866) (xy 21.676614 -424.86961) (xy 21.656344 -424.836242) (xy 21.621934 -424.766156)
			(xy 21.594865 -424.69292) (xy 21.584666 -424.655234) (xy 21.58096 -424.643626) (xy 21.564781 -424.625454)
			(xy 21.553678 -424.620436) (xy 21.527012 -424.609666) (xy 21.477008 -424.581262) (xy 21.431831 -424.545677)
			(xy 21.392503 -424.503719) (xy 21.359914 -424.456336) (xy 21.334801 -424.404601) (xy 21.317732 -424.349684)
			(xy 21.309095 -424.292828) (xy 21.308568 -424.264074) (xy 21.308977 -424.236801) (xy 21.316744 -424.182811)
			(xy 21.332115 -424.130475) (xy 21.354778 -424.08086) (xy 21.384271 -424.034975) (xy 21.419994 -423.993754)
			(xy 21.46122 -423.958037) (xy 21.507109 -423.928551) (xy 21.556728 -423.905895) (xy 21.609065 -423.890532)
			(xy 21.663057 -423.882773) (xy 21.69033 -423.882312) (xy 21.713877 -423.882631) (xy 21.760621 -423.888363)
			(xy 21.783548 -423.893742) (xy 21.795515 -423.896092) (xy 21.819254 -423.890644) (xy 21.829014 -423.883328)
			(xy 21.858618 -423.858733) (xy 21.921932 -423.814965) (xy 21.989327 -423.777788) (xy 22.06012 -423.747578)
			(xy 22.133592 -423.724642) (xy 22.208999 -423.709213) (xy 22.285576 -423.701447) (xy 22.32406 -423.700956)
			(xy 22.324314 -423.700956) (xy 22.364317 -423.701414) (xy 22.443884 -423.709779) (xy 22.522141 -423.726415)
			(xy 22.59823 -423.751139) (xy 22.671318 -423.783683) (xy 22.740604 -423.823687) (xy 22.805329 -423.870715)
			(xy 22.864783 -423.924251) (xy 22.918315 -423.983709) (xy 22.965339 -424.048436) (xy 23.005339 -424.117725)
			(xy 23.037878 -424.190815) (xy 23.062598 -424.266905) (xy 23.079229 -424.345163) (xy 23.08085 -424.360594)
			(xy 58.141108 -424.360594) (xy 58.141108 -421.81907) (xy 58.141586 -421.806957) (xy 58.149077 -421.783918)
			(xy 58.163319 -421.764319) (xy 58.182918 -421.750077) (xy 58.205957 -421.742586) (xy 58.21807 -421.742108)
			(xy 59.15787 -421.742108) (xy 59.16998 -421.742637) (xy 59.193017 -421.750112) (xy 59.207184 -421.760396)
			(xy 60.141104 -421.760396) (xy 60.141104 -419.218872) (xy 60.141536 -419.20682) (xy 60.148977 -419.183893)
			(xy 60.163125 -419.164377) (xy 60.182601 -419.150175) (xy 60.205507 -419.14267) (xy 60.217558 -419.142164)
			(xy 61.157866 -419.142164) (xy 61.169956 -419.142637) (xy 61.19296 -419.150087) (xy 61.212542 -419.164271)
			(xy 61.226793 -419.183805) (xy 61.234322 -419.206783) (xy 61.234828 -419.218872) (xy 61.234828 -421.760396)
			(xy 61.234337 -421.772443) (xy 61.226909 -421.795364) (xy 61.212775 -421.814877) (xy 61.193313 -421.829082)
			(xy 61.170419 -421.836593) (xy 61.158374 -421.837104) (xy 60.218066 -421.837104) (xy 60.205979 -421.836623)
			(xy 60.182985 -421.829162) (xy 60.163409 -421.814977) (xy 60.149158 -421.79545) (xy 60.141619 -421.772481)
			(xy 60.141104 -421.760396) (xy 59.207184 -421.760396) (xy 59.212617 -421.76434) (xy 59.22686 -421.783929)
			(xy 59.234354 -421.80696) (xy 59.234832 -421.81907) (xy 59.234832 -424.360594) (xy 62.1411 -424.360594)
			(xy 62.1411 -421.81907) (xy 62.141585 -421.806958) (xy 62.149076 -421.78392) (xy 62.163316 -421.764322)
			(xy 62.182913 -421.75008) (xy 62.20595 -421.742587) (xy 62.218062 -421.742108) (xy 63.157862 -421.742108)
			(xy 63.16998 -421.742592) (xy 63.193032 -421.75007) (xy 63.207258 -421.760396) (xy 68.141088 -421.760396)
			(xy 68.141088 -419.218872) (xy 68.141536 -419.206822) (xy 68.148975 -419.183897) (xy 68.163119 -419.164383)
			(xy 68.182591 -419.15018) (xy 68.205493 -419.142672) (xy 68.217542 -419.142164) (xy 69.15785 -419.142164)
			(xy 69.169939 -419.14265) (xy 69.192942 -419.150096) (xy 69.212525 -419.164277) (xy 69.226777 -419.183808)
			(xy 69.234306 -419.206784) (xy 69.234812 -419.218872) (xy 69.234812 -420.760398) (xy 70.141084 -420.760398)
			(xy 70.141084 -418.218874) (xy 70.141438 -418.206745) (xy 70.148943 -418.183678) (xy 70.16321 -418.164059)
			(xy 70.182842 -418.14981) (xy 70.205917 -418.142327) (xy 70.218046 -418.141912) (xy 71.157846 -418.141912)
			(xy 71.16996 -418.142372) (xy 71.193001 -418.149869) (xy 71.212599 -418.164115) (xy 71.22684 -418.183717)
			(xy 71.234331 -418.20676) (xy 71.234808 -418.218874) (xy 71.234808 -418.3761) (xy 77.278992 -418.3761)
			(xy 77.279604 -418.333411) (xy 77.289166 -418.248568) (xy 77.308127 -418.165321) (xy 77.336249 -418.084705)
			(xy 77.373182 -418.007728) (xy 77.395324 -417.971224) (xy 77.400017 -417.962962) (xy 77.403523 -417.9443)
			(xy 77.400017 -417.925638) (xy 77.395324 -417.917376) (xy 77.373175 -417.880876) (xy 77.336228 -417.803902)
			(xy 77.308101 -417.723287) (xy 77.289144 -417.640036) (xy 77.279595 -417.555191) (xy 77.278992 -417.5125)
			(xy 77.279467 -417.473829) (xy 77.287277 -417.396883) (xy 77.302828 -417.321121) (xy 77.32596 -417.247319)
			(xy 77.356435 -417.176235) (xy 77.393942 -417.108596) (xy 77.438096 -417.045097) (xy 77.488445 -416.986388)
			(xy 77.544472 -416.933071) (xy 77.605603 -416.885692) (xy 77.638148 -416.8648) (xy 77.648062 -416.857872)
			(xy 77.660522 -416.837179) (xy 77.662024 -416.825176) (xy 77.664412 -416.797996) (xy 77.675971 -416.744672)
			(xy 77.695005 -416.693538) (xy 77.721126 -416.645635) (xy 77.753802 -416.60194) (xy 77.792367 -416.563343)
			(xy 77.836035 -416.53063) (xy 77.883916 -416.504469) (xy 77.935034 -416.485391) (xy 77.988347 -416.473787)
			(xy 78.04277 -416.469893) (xy 78.097193 -416.473787) (xy 78.150506 -416.485391) (xy 78.201624 -416.504469)
			(xy 78.249505 -416.53063) (xy 78.293173 -416.563343) (xy 78.331738 -416.60194) (xy 78.364414 -416.645635)
			(xy 78.390535 -416.693538) (xy 78.409569 -416.744672) (xy 78.421128 -416.797996) (xy 78.423516 -416.825176)
			(xy 78.425031 -416.837171) (xy 78.437499 -416.857848) (xy 78.447392 -416.8648) (xy 78.479943 -416.885682)
			(xy 78.541064 -416.933069) (xy 78.597083 -416.986393) (xy 78.647425 -417.045106) (xy 78.691574 -417.108606)
			(xy 78.729078 -417.176245) (xy 78.759553 -417.247327) (xy 78.782686 -417.321127) (xy 78.798242 -417.396886)
			(xy 78.806059 -417.47383) (xy 78.806548 -417.5125) (xy 78.805945 -417.55519) (xy 78.796382 -417.640033)
			(xy 78.77742 -417.723281) (xy 78.749296 -417.803896) (xy 78.712359 -417.880873) (xy 78.690216 -417.917376)
			(xy 78.68552 -417.925637) (xy 78.682012 -417.9443) (xy 78.68552 -417.962963) (xy 78.690216 -417.971224)
			(xy 78.712369 -418.007722) (xy 78.749315 -418.084696) (xy 78.77744 -418.165312) (xy 78.796396 -418.248563)
			(xy 78.805945 -418.333409) (xy 78.806548 -418.3761) (xy 78.806054 -418.41477) (xy 78.798244 -418.491715)
			(xy 78.782695 -418.567476) (xy 78.759564 -418.641277) (xy 78.72909 -418.712361) (xy 78.691585 -418.779999)
			(xy 78.647434 -418.843498) (xy 78.597088 -418.902208) (xy 78.541064 -418.955526) (xy 78.479936 -419.002907)
			(xy 78.447392 -419.0238) (xy 78.437485 -419.030738) (xy 78.425021 -419.051424) (xy 78.423516 -419.063424)
			(xy 78.421128 -419.090604) (xy 78.409569 -419.143928) (xy 78.390535 -419.195062) (xy 78.364414 -419.242965)
			(xy 78.331738 -419.28666) (xy 78.293173 -419.325257) (xy 78.249505 -419.35797) (xy 78.201624 -419.384131)
			(xy 78.150506 -419.403209) (xy 78.097193 -419.414813) (xy 78.04277 -419.418707) (xy 77.988347 -419.414813)
			(xy 77.935034 -419.403209) (xy 77.883916 -419.384131) (xy 77.836035 -419.35797) (xy 77.792367 -419.325257)
			(xy 77.753802 -419.28666) (xy 77.721126 -419.242965) (xy 77.695005 -419.195062) (xy 77.675971 -419.143928)
			(xy 77.664412 -419.090604) (xy 77.662024 -419.063424) (xy 77.660493 -419.051433) (xy 77.648035 -419.030756)
			(xy 77.638148 -419.0238) (xy 77.605583 -419.00294) (xy 77.544464 -418.955548) (xy 77.488447 -418.902221)
			(xy 77.438107 -418.843505) (xy 77.39396 -418.780001) (xy 77.356458 -418.712361) (xy 77.325985 -418.641277)
			(xy 77.302852 -418.567476) (xy 77.287298 -418.491715) (xy 77.279481 -418.414771) (xy 77.278992 -418.3761)
			(xy 71.234808 -418.3761) (xy 71.234808 -420.760398) (xy 71.234287 -420.772508) (xy 71.226806 -420.795543)
			(xy 71.212575 -420.815141) (xy 71.192986 -420.829384) (xy 71.169956 -420.83688) (xy 71.157846 -420.83736)
			(xy 70.218046 -420.83736) (xy 70.205925 -420.836901) (xy 70.182868 -420.829421) (xy 70.163252 -420.81518)
			(xy 70.148999 -420.795572) (xy 70.141506 -420.772518) (xy 70.141084 -420.760398) (xy 69.234812 -420.760398)
			(xy 69.234812 -421.760396) (xy 69.234337 -421.772445) (xy 69.226907 -421.795368) (xy 69.212769 -421.814883)
			(xy 69.193303 -421.829087) (xy 69.170405 -421.836595) (xy 69.158358 -421.837104) (xy 68.21805 -421.837104)
			(xy 68.205967 -421.836551) (xy 68.182976 -421.829113) (xy 68.163399 -421.814947) (xy 68.149145 -421.795434)
			(xy 68.141604 -421.772476) (xy 68.141088 -421.760396) (xy 63.207258 -421.760396) (xy 63.212645 -421.764306)
			(xy 63.226899 -421.783907) (xy 63.234398 -421.806953) (xy 63.234824 -421.81907) (xy 63.234824 -424.360594)
			(xy 63.234434 -424.37272) (xy 63.226939 -424.395785) (xy 63.212681 -424.415404) (xy 63.193057 -424.429654)
			(xy 63.169988 -424.437139) (xy 63.157862 -424.437556) (xy 62.218062 -424.437556) (xy 62.205945 -424.437121)
			(xy 62.182899 -424.429622) (xy 62.163298 -424.415371) (xy 62.149058 -424.395761) (xy 62.141572 -424.372711)
			(xy 62.1411 -424.360594) (xy 59.234832 -424.360594) (xy 59.234434 -424.372719) (xy 59.22694 -424.395783)
			(xy 59.212684 -424.415401) (xy 59.193062 -424.429651) (xy 59.169996 -424.437138) (xy 59.15787 -424.437556)
			(xy 58.21807 -424.437556) (xy 58.205953 -424.437114) (xy 58.182908 -424.429618) (xy 58.163306 -424.415368)
			(xy 58.149066 -424.39576) (xy 58.14158 -424.372711) (xy 58.141108 -424.360594) (xy 23.08085 -424.360594)
			(xy 23.087588 -424.424731) (xy 23.088092 -424.464734) (xy 23.087498 -424.507424) (xy 23.077932 -424.592267)
			(xy 23.058968 -424.675515) (xy 23.030841 -424.75613) (xy 22.993904 -424.833107) (xy 22.97176 -424.86961)
			(xy 22.967034 -424.877857) (xy 22.963531 -424.896529) (xy 22.967055 -424.915197) (xy 22.97176 -424.923458)
			(xy 22.993922 -424.959951) (xy 23.030866 -425.036926) (xy 23.058991 -425.117544) (xy 23.077945 -425.200796)
			(xy 23.087491 -425.285643) (xy 23.088092 -425.328334) (xy 23.087587 -425.368335) (xy 23.079221 -425.447897)
			(xy 23.062585 -425.52615) (xy 23.037861 -425.602235) (xy 23.005319 -425.675319) (xy 22.965317 -425.744601)
			(xy 22.918292 -425.809322) (xy 22.86476 -425.868774) (xy 22.805307 -425.922305) (xy 22.784478 -425.937438)
			(xy 38.102373 -425.937438) (xy 38.102373 -425.882561) (xy 38.110234 -425.82825) (xy 38.125793 -425.775625)
			(xy 38.148731 -425.725771) (xy 38.178573 -425.679717) (xy 38.214704 -425.638413) (xy 38.256379 -425.602711)
			(xy 38.302738 -425.573346) (xy 38.352826 -425.550925) (xy 38.405609 -425.535909) (xy 38.43274 -425.531788)
			(xy 38.443851 -425.52968) (xy 38.462827 -425.517428) (xy 38.469316 -425.508166) (xy 38.490126 -425.475384)
			(xy 38.537449 -425.413816) (xy 38.59078 -425.357372) (xy 38.649566 -425.306636) (xy 38.713201 -425.262132)
			(xy 38.781027 -425.22432) (xy 38.852342 -425.193591) (xy 38.926408 -425.170263) (xy 39.002461 -425.154577)
			(xy 39.079713 -425.146695) (xy 39.11854 -425.146216) (xy 39.16123 -425.146805) (xy 39.246073 -425.156372)
			(xy 39.329321 -425.175338) (xy 39.409936 -425.203465) (xy 39.486913 -425.240404) (xy 39.523416 -425.262548)
			(xy 39.531677 -425.267244) (xy 39.55034 -425.270752) (xy 39.569003 -425.267244) (xy 39.577264 -425.262548)
			(xy 39.61375 -425.240374) (xy 39.690728 -425.203433) (xy 39.771347 -425.175312) (xy 39.854601 -425.156361)
			(xy 39.939449 -425.146817) (xy 39.98214 -425.146216) (xy 40.020966 -425.146692) (xy 40.098216 -425.154581)
			(xy 40.174266 -425.170272) (xy 40.24833 -425.193604) (xy 40.319642 -425.224335) (xy 40.387466 -425.262148)
			(xy 40.39167 -425.265088) (xy 40.979598 -425.265088) (xy 40.980113 -425.23782) (xy 40.987875 -425.18384)
			(xy 41.00324 -425.131513) (xy 41.025895 -425.081906) (xy 41.055378 -425.036027) (xy 41.09109 -424.99481)
			(xy 41.132304 -424.959095) (xy 41.178181 -424.929608) (xy 41.227787 -424.90695) (xy 41.280112 -424.891581)
			(xy 41.334092 -424.883815) (xy 41.36136 -424.883326) (xy 41.385701 -424.883728) (xy 41.433983 -424.889971)
			(xy 41.457626 -424.895772) (xy 41.469594 -424.898123) (xy 41.493334 -424.892677) (xy 41.503092 -424.885358)
			(xy 41.532614 -424.861121) (xy 41.595659 -424.81799) (xy 41.662695 -424.781369) (xy 41.733052 -424.751622)
			(xy 41.806027 -424.729048) (xy 41.880891 -424.713872) (xy 41.956897 -424.706245) (xy 41.99509 -424.70578)
			(xy 41.995344 -424.70578) (xy 42.035344 -424.706304) (xy 42.114905 -424.71467) (xy 42.193156 -424.731306)
			(xy 42.269239 -424.75603) (xy 42.342322 -424.788571) (xy 42.411603 -424.828572) (xy 42.476324 -424.875596)
			(xy 42.535775 -424.929126) (xy 42.589305 -424.988578) (xy 42.636329 -425.053299) (xy 42.67633 -425.12258)
			(xy 42.708871 -425.195662) (xy 42.733594 -425.271746) (xy 42.75023 -425.349997) (xy 42.758596 -425.429558)
			(xy 42.759122 -425.469558) (xy 42.758488 -425.512247) (xy 42.748931 -425.597088) (xy 42.729975 -425.680336)
			(xy 42.701858 -425.760951) (xy 42.664929 -425.83793) (xy 42.64279 -425.874434) (xy 42.63813 -425.882713)
			(xy 42.634612 -425.901364) (xy 42.638104 -425.92002) (xy 42.64279 -425.928282) (xy 42.664923 -425.964791)
			(xy 42.701872 -426.041763) (xy 42.730003 -426.122376) (xy 42.748963 -426.205624) (xy 42.758516 -426.290468)
			(xy 42.759122 -426.333158) (xy 42.758515 -426.373156) (xy 42.750157 -426.452715) (xy 42.733529 -426.530964)
			(xy 42.708813 -426.607047) (xy 42.67628 -426.680129) (xy 42.636286 -426.74941) (xy 42.589269 -426.814131)
			(xy 42.535744 -426.873583) (xy 42.476298 -426.927114) (xy 42.411582 -426.974139) (xy 42.342305 -427.014141)
			(xy 42.269227 -427.046683) (xy 42.193147 -427.071407) (xy 42.1149 -427.088044) (xy 42.035342 -427.09641)
			(xy 41.995344 -427.096936) (xy 41.958683 -427.096468) (xy 41.885697 -427.089452) (xy 41.813718 -427.075481)
			(xy 41.743407 -427.054682) (xy 41.675411 -427.027247) (xy 41.610354 -426.993428) (xy 41.548834 -426.953535)
			(xy 41.519856 -426.931074) (xy 41.50983 -426.923858) (xy 41.485608 -426.919181) (xy 41.473628 -426.922184)
			(xy 41.446708 -426.929795) (xy 41.391363 -426.937952) (xy 41.363392 -426.93844) (xy 41.33612 -426.938006)
			(xy 41.282131 -426.930242) (xy 41.229796 -426.914874) (xy 41.180182 -426.892214) (xy 41.134297 -426.862723)
			(xy 41.093076 -426.827003) (xy 41.057359 -426.785779) (xy 41.027872 -426.739892) (xy 41.005216 -426.690276)
			(xy 40.989852 -426.63794) (xy 40.982092 -426.58395) (xy 40.98163 -426.556678) (xy 40.982166 -426.528404)
			(xy 40.990513 -426.472476) (xy 41.007005 -426.418388) (xy 41.031284 -426.367318) (xy 41.06282 -426.320381)
			(xy 41.100926 -426.2786) (xy 41.144769 -426.242888) (xy 41.193394 -426.214022) (xy 41.219374 -426.202856)
			(xy 41.230466 -426.197542) (xy 41.246384 -426.178841) (xy 41.249854 -426.167042) (xy 41.259843 -426.124987)
			(xy 41.288031 -426.043271) (xy 41.325256 -425.965257) (xy 41.347644 -425.928282) (xy 41.352391 -425.920042)
			(xy 41.355905 -425.901364) (xy 41.352365 -425.882691) (xy 41.347644 -425.874434) (xy 41.327042 -425.840498)
			(xy 41.292166 -425.769173) (xy 41.264877 -425.694617) (xy 41.25468 -425.656248) (xy 41.251034 -425.64456)
			(xy 41.234847 -425.626243) (xy 41.223692 -425.621196) (xy 41.197113 -425.610371) (xy 41.147289 -425.581895)
			(xy 41.102288 -425.546282) (xy 41.063124 -425.504335) (xy 41.030678 -425.457) (xy 41.005683 -425.405341)
			(xy 40.9887 -425.350524) (xy 40.980113 -425.293782) (xy 40.979598 -425.265088) (xy 40.39167 -425.265088)
			(xy 40.451099 -425.306652) (xy 40.509885 -425.357387) (xy 40.563216 -425.413828) (xy 40.61054 -425.475393)
			(xy 40.631364 -425.508166) (xy 40.637825 -425.517461) (xy 40.656809 -425.529733) (xy 40.66794 -425.531788)
			(xy 40.695065 -425.535926) (xy 40.747837 -425.550949) (xy 40.797914 -425.573375) (xy 40.844262 -425.602742)
			(xy 40.885927 -425.638445) (xy 40.922048 -425.679747) (xy 40.951882 -425.725796) (xy 40.974812 -425.775644)
			(xy 40.990368 -425.828262) (xy 40.998226 -425.882565) (xy 40.998226 -425.937434) (xy 40.990368 -425.991737)
			(xy 40.974813 -426.044355) (xy 40.951882 -426.094202) (xy 40.922049 -426.140252) (xy 40.885928 -426.181554)
			(xy 40.844263 -426.217257) (xy 40.797915 -426.246624) (xy 40.747839 -426.26905) (xy 40.695067 -426.284074)
			(xy 40.66794 -426.2882) (xy 40.656828 -426.290303) (xy 40.637852 -426.302559) (xy 40.631364 -426.311822)
			(xy 40.610563 -426.34461) (xy 40.563239 -426.406178) (xy 40.509908 -426.462623) (xy 40.451121 -426.513359)
			(xy 40.387484 -426.557863) (xy 40.319658 -426.595675) (xy 40.248342 -426.626403) (xy 40.174274 -426.649729)
			(xy 40.09822 -426.665414) (xy 40.020967 -426.673294) (xy 39.98214 -426.673772) (xy 39.939451 -426.673146)
			(xy 39.854609 -426.663588) (xy 39.771361 -426.644631) (xy 39.690746 -426.616512) (xy 39.613768 -426.579581)
			(xy 39.577264 -426.55744) (xy 39.569003 -426.552744) (xy 39.55034 -426.549236) (xy 39.531677 -426.552744)
			(xy 39.523416 -426.55744) (xy 39.48691 -426.579579) (xy 39.409938 -426.616526) (xy 39.329324 -426.644655)
			(xy 39.246075 -426.663614) (xy 39.16123 -426.673167) (xy 39.11854 -426.673772) (xy 39.079715 -426.67327)
			(xy 39.002467 -426.665381) (xy 38.926419 -426.64969) (xy 38.852357 -426.626359) (xy 38.781046 -426.59563)
			(xy 38.713223 -426.55782) (xy 38.64959 -426.51332) (xy 38.590802 -426.462589) (xy 38.537469 -426.406152)
			(xy 38.490142 -426.344592) (xy 38.469316 -426.311822) (xy 38.462867 -426.302517) (xy 38.443874 -426.290251)
			(xy 38.43274 -426.2882) (xy 38.405607 -426.28409) (xy 38.352824 -426.269075) (xy 38.302737 -426.246653)
			(xy 38.256377 -426.217288) (xy 38.214703 -426.181586) (xy 38.178572 -426.140281) (xy 38.14873 -426.094227)
			(xy 38.125793 -426.044374) (xy 38.110233 -425.991749) (xy 38.102373 -425.937438) (xy 22.784478 -425.937438)
			(xy 22.740584 -425.969328) (xy 22.671301 -426.009329) (xy 22.598216 -426.041868) (xy 22.522131 -426.06659)
			(xy 22.443878 -426.083224) (xy 22.364315 -426.091588) (xy 22.324314 -426.092112) (xy 22.32406 -426.092112)
			(xy 22.285576 -426.091603) (xy 22.209001 -426.083838) (xy 22.133595 -426.06841) (xy 22.060123 -426.045476)
			(xy 21.989331 -426.015269) (xy 21.921935 -425.978095) (xy 21.85862 -425.934331) (xy 21.829014 -425.90974)
			(xy 21.819249 -425.902426) (xy 21.795515 -425.896966) (xy 21.783548 -425.899326) (xy 21.76062 -425.9047)
			(xy 21.713877 -425.910436) (xy 21.69033 -425.910756) (xy 21.663059 -425.910271) (xy 21.609073 -425.902512)
			(xy 21.55674 -425.88715) (xy 21.507127 -425.864495) (xy 21.461243 -425.83501) (xy 21.420022 -425.799295)
			(xy 21.384304 -425.758076) (xy 21.354816 -425.712194) (xy 21.332159 -425.662582) (xy 21.316793 -425.61025)
			(xy 21.309031 -425.556265) (xy 21.308568 -425.528994) (xy 11.258979 -425.528994) (xy 11.291285 -425.59622)
			(xy 11.319427 -425.676836) (xy 11.338374 -425.760094) (xy 11.347888 -425.844948) (xy 11.348466 -425.887642)
			(xy 11.347977 -425.926261) (xy 11.340163 -426.003104) (xy 11.324615 -426.078762) (xy 11.301492 -426.152459)
			(xy 11.271033 -426.223438) (xy 11.233548 -426.290972) (xy 11.189424 -426.354366) (xy 11.139113 -426.412972)
			(xy 11.083131 -426.466187) (xy 11.022052 -426.513466) (xy 10.956504 -426.554322) (xy 10.887158 -426.588338)
			(xy 10.814727 -426.615163) (xy 10.739954 -426.634523) (xy 10.663606 -426.646219) (xy 10.586466 -426.650132)
			(xy 10.509326 -426.646219) (xy 10.432978 -426.634523) (xy 10.358205 -426.615163) (xy 10.285774 -426.588338)
			(xy 10.216428 -426.554322) (xy 10.15088 -426.513466) (xy 10.089801 -426.466187) (xy 10.033819 -426.412972)
			(xy 9.983508 -426.354366) (xy 9.939384 -426.290972) (xy 9.901899 -426.223438) (xy 9.87144 -426.152459)
			(xy 9.848317 -426.078762) (xy 9.832769 -426.003104) (xy 9.824955 -425.926261) (xy 9.824466 -425.887642)
			(xy 8.024114 -425.887642) (xy 8.024114 -428.615602) (xy 24.748744 -428.615602) (xy 24.749349 -428.572912)
			(xy 24.758912 -428.488069) (xy 24.777873 -428.404821) (xy 24.805997 -428.324206) (xy 24.842933 -428.247229)
			(xy 24.865076 -428.210726) (xy 24.869771 -428.202464) (xy 24.87328 -428.183802) (xy 24.869772 -428.165139)
			(xy 24.865076 -428.156878) (xy 24.842922 -428.12038) (xy 24.805978 -428.043406) (xy 24.777852 -427.96279)
			(xy 24.758896 -427.879539) (xy 24.749347 -427.794693) (xy 24.748744 -427.752002) (xy 24.749229 -427.712)
			(xy 24.757592 -427.632434) (xy 24.774226 -427.554178) (xy 24.798949 -427.47809) (xy 24.83149 -427.405002)
			(xy 24.871493 -427.335717) (xy 24.918519 -427.270993) (xy 24.972053 -427.211538) (xy 25.031508 -427.158006)
			(xy 25.096234 -427.110982) (xy 25.16552 -427.070981) (xy 25.238608 -427.038442) (xy 25.314697 -427.013721)
			(xy 25.392954 -426.997089) (xy 25.47252 -426.988728) (xy 25.512522 -426.988224) (xy 25.556227 -426.988868)
			(xy 25.643056 -426.998922) (xy 25.68575 -427.00829) (xy 25.697261 -427.010415) (xy 25.720035 -427.005104)
			(xy 25.729438 -426.99813) (xy 25.749907 -426.982092) (xy 25.794389 -426.955159) (xy 25.842115 -426.934511)
			(xy 25.892201 -426.920531) (xy 25.943722 -426.913478) (xy 25.969722 -426.91304) (xy 25.996992 -426.913504)
			(xy 26.050977 -426.921269) (xy 26.103307 -426.936637) (xy 26.152917 -426.959296) (xy 26.198798 -426.988784)
			(xy 26.240015 -427.024502) (xy 26.27573 -427.065721) (xy 26.305216 -427.111604) (xy 26.327871 -427.161216)
			(xy 26.343236 -427.213547) (xy 26.350998 -427.267532) (xy 26.351484 -427.294802) (xy 26.351074 -427.320803)
			(xy 26.344014 -427.372323) (xy 26.330025 -427.422408) (xy 26.309366 -427.470131) (xy 26.28242 -427.514606)
			(xy 26.266394 -427.535086) (xy 26.259441 -427.544493) (xy 26.254165 -427.567259) (xy 26.256234 -427.578774)
			(xy 26.265599 -427.621468) (xy 26.275654 -427.708298) (xy 26.2763 -427.752002) (xy 26.27569 -427.794692)
			(xy 26.266128 -427.879534) (xy 26.247167 -427.962782) (xy 26.219044 -428.043397) (xy 26.18211 -428.120375)
			(xy 26.159968 -428.156878) (xy 26.155267 -428.165138) (xy 26.151755 -428.183802) (xy 26.155268 -428.202466)
			(xy 26.159968 -428.210726) (xy 26.160279 -428.211238) (xy 26.306379 -428.211238) (xy 26.306379 -428.156363)
			(xy 26.314239 -428.102054) (xy 26.329797 -428.049431) (xy 26.352733 -427.999579) (xy 26.382573 -427.953527)
			(xy 26.418702 -427.912224) (xy 26.460374 -427.876522) (xy 26.506731 -427.847157) (xy 26.556816 -427.824735)
			(xy 26.609596 -427.809718) (xy 26.636726 -427.805596) (xy 26.647834 -427.803478) (xy 26.666811 -427.791233)
			(xy 26.673302 -427.781974) (xy 26.694125 -427.7492) (xy 26.741446 -427.687632) (xy 26.794775 -427.631188)
			(xy 26.85356 -427.580451) (xy 26.917194 -427.535946) (xy 26.985018 -427.498133) (xy 27.056331 -427.467403)
			(xy 27.130397 -427.444074) (xy 27.206448 -427.428387) (xy 27.2837 -427.420504) (xy 27.322526 -427.420024)
			(xy 27.365216 -427.420619) (xy 27.450059 -427.430184) (xy 27.533307 -427.449148) (xy 27.613922 -427.477275)
			(xy 27.690899 -427.514212) (xy 27.727402 -427.536356) (xy 27.735663 -427.541052) (xy 27.754326 -427.54456)
			(xy 27.772989 -427.541052) (xy 27.78125 -427.536356) (xy 27.817739 -427.514189) (xy 27.894717 -427.477247)
			(xy 27.975335 -427.449124) (xy 28.058587 -427.430171) (xy 28.143435 -427.420626) (xy 28.186126 -427.420024)
			(xy 28.22495 -427.420555) (xy 28.302197 -427.428441) (xy 28.378245 -427.444128) (xy 28.452306 -427.467456)
			(xy 28.523617 -427.498182) (xy 28.59144 -427.535989) (xy 28.655074 -427.580486) (xy 28.713861 -427.631214)
			(xy 28.767195 -427.687648) (xy 28.814524 -427.749205) (xy 28.83535 -427.781974) (xy 28.841816 -427.791265)
			(xy 28.860796 -427.803538) (xy 28.871926 -427.805596) (xy 28.899054 -427.809718) (xy 28.951829 -427.82474)
			(xy 29.001908 -427.847165) (xy 29.048259 -427.876533) (xy 29.089926 -427.912236) (xy 29.12605 -427.953539)
			(xy 29.130583 -427.960536) (xy 58.141108 -427.960536) (xy 58.141108 -425.419012) (xy 58.14157 -425.406962)
			(xy 58.149001 -425.384035) (xy 58.163141 -425.364518) (xy 58.182611 -425.350315) (xy 58.205513 -425.34281)
			(xy 58.217562 -425.342304) (xy 59.15787 -425.342304) (xy 59.169954 -425.342832) (xy 59.192948 -425.350276)
			(xy 59.212525 -425.364448) (xy 59.226778 -425.383967) (xy 59.234317 -425.40693) (xy 59.234832 -425.419012)
			(xy 59.234832 -427.960536) (xy 59.234372 -427.972585) (xy 59.226933 -427.995506) (xy 59.212791 -428.015019)
			(xy 59.193323 -428.029222) (xy 59.170425 -428.036733) (xy 59.158378 -428.037244) (xy 58.21807 -428.037244)
			(xy 58.205977 -428.036818) (xy 58.182973 -428.029351) (xy 58.163392 -428.015154) (xy 58.149143 -427.995612)
			(xy 58.141615 -427.972627) (xy 58.141108 -427.960536) (xy 29.130583 -427.960536) (xy 29.155885 -427.99959)
			(xy 29.178817 -428.049439) (xy 29.194373 -428.102059) (xy 29.202232 -428.156365) (xy 29.202232 -428.211236)
			(xy 29.194373 -428.265541) (xy 29.178817 -428.318161) (xy 29.155885 -428.368011) (xy 29.126049 -428.414061)
			(xy 29.089926 -428.455364) (xy 29.048259 -428.491068) (xy 29.001908 -428.520435) (xy 28.951829 -428.542861)
			(xy 28.899054 -428.557882) (xy 28.871926 -428.562008) (xy 28.860811 -428.564101) (xy 28.841837 -428.576364)
			(xy 28.83535 -428.58563) (xy 28.814493 -428.618381) (xy 28.767175 -428.679949) (xy 28.71385 -428.736394)
			(xy 28.655069 -428.787131) (xy 28.591439 -428.831638) (xy 28.523619 -428.869453) (xy 28.45231 -428.900186)
			(xy 28.378248 -428.923519) (xy 28.3022 -428.93921) (xy 28.224951 -428.947098) (xy 28.186126 -428.94758)
			(xy 28.143437 -428.94696) (xy 28.058595 -428.9374) (xy 27.975347 -428.918442) (xy 27.894732 -428.890321)
			(xy 27.817754 -428.853389) (xy 27.78125 -428.831248) (xy 27.772989 -428.826552) (xy 27.754326 -428.823044)
			(xy 27.735663 -428.826552) (xy 27.727402 -428.831248) (xy 27.6909 -428.853394) (xy 27.613926 -428.89034)
			(xy 27.533311 -428.918467) (xy 27.450062 -428.937424) (xy 27.365216 -428.946975) (xy 27.322526 -428.94758)
			(xy 27.283699 -428.947133) (xy 27.206448 -428.939241) (xy 27.130397 -428.923546) (xy 27.056333 -428.900211)
			(xy 26.98502 -428.869477) (xy 26.917197 -428.831661) (xy 26.853564 -428.787154) (xy 26.794779 -428.736416)
			(xy 26.741449 -428.679971) (xy 26.694125 -428.618404) (xy 26.673302 -428.58563) (xy 26.666857 -428.576321)
			(xy 26.647861 -428.564057) (xy 26.636726 -428.562008) (xy 26.609596 -428.557882) (xy 26.556816 -428.542865)
			(xy 26.506731 -428.520443) (xy 26.460375 -428.491079) (xy 26.418702 -428.455377) (xy 26.382573 -428.414073)
			(xy 26.352733 -428.368021) (xy 26.329798 -428.318169) (xy 26.314239 -428.265547) (xy 26.306379 -428.211238)
			(xy 26.160279 -428.211238) (xy 26.182117 -428.247226) (xy 26.219064 -428.3242) (xy 26.247191 -428.404815)
			(xy 26.266148 -428.488066) (xy 26.275697 -428.572911) (xy 26.2763 -428.615602) (xy 26.275669 -428.659307)
			(xy 26.265606 -428.746137) (xy 26.256234 -428.78883) (xy 26.254138 -428.800343) (xy 26.259432 -428.823111)
			(xy 26.266394 -428.832518) (xy 26.282426 -428.852991) (xy 26.30936 -428.897473) (xy 26.330008 -428.945197)
			(xy 26.343989 -428.995283) (xy 26.351045 -429.046802) (xy 26.351484 -429.072802) (xy 26.350978 -429.10007)
			(xy 26.343216 -429.154052) (xy 26.327852 -429.20638) (xy 26.305197 -429.255989) (xy 26.275713 -429.301869)
			(xy 26.24 -429.343086) (xy 26.198785 -429.378801) (xy 26.152906 -429.408287) (xy 26.103299 -429.430945)
			(xy 26.050972 -429.446312) (xy 25.99699 -429.454076) (xy 25.969722 -429.454564) (xy 25.943721 -429.454145)
			(xy 25.892201 -429.447088) (xy 25.842116 -429.433101) (xy 25.794394 -429.412444) (xy 25.749918 -429.385499)
			(xy 25.729438 -429.369474) (xy 25.720024 -429.362533) (xy 25.697263 -429.357251) (xy 25.68575 -429.359314)
			(xy 25.643055 -429.368675) (xy 25.556226 -429.378732) (xy 25.512522 -429.37938) (xy 25.472521 -429.378852)
			(xy 25.392957 -429.370491) (xy 25.314703 -429.35386) (xy 25.238616 -429.32914) (xy 25.16553 -429.296602)
			(xy 25.096246 -429.256602) (xy 25.031522 -429.20958) (xy 24.972068 -429.156049) (xy 24.918536 -429.096597)
			(xy 24.871511 -429.031874) (xy 24.831509 -428.962591) (xy 24.798969 -428.889506) (xy 24.774246 -428.81342)
			(xy 24.757612 -428.735167) (xy 24.74925 -428.655603) (xy 24.748744 -428.615602) (xy 8.024114 -428.615602)
			(xy 8.024114 -433.340256) (xy 8.024594 -433.351758) (xy 8.034479 -433.372524) (xy 8.052399 -433.38694)
			(xy 8.063484 -433.39004) (xy 8.063992 -433.39004) (xy 8.160766 -433.411376) (xy 8.172159 -433.413322)
			(xy 8.194622 -433.40798) (xy 8.212535 -433.39341) (xy 8.217916 -433.383182) (xy 8.217916 -433.382928)
			(xy 8.261881 -433.289319) (xy 8.356187 -433.105234) (xy 8.457641 -432.924989) (xy 8.566088 -432.748863)
			(xy 8.68136 -432.577127) (xy 8.80328 -432.410045) (xy 8.931661 -432.247874) (xy 9.066304 -432.090863)
			(xy 9.207002 -431.939256) (xy 9.35354 -431.793284) (xy 9.505691 -431.653172) (xy 9.663221 -431.519138)
			(xy 9.825887 -431.391385) (xy 9.99344 -431.270112) (xy 10.165621 -431.155506) (xy 10.342165 -431.047741)
			(xy 10.522801 -430.946985) (xy 10.70725 -430.853392) (xy 10.895228 -430.767107) (xy 11.086447 -430.688262)
			(xy 11.280611 -430.616978) (xy 11.477422 -430.553366) (xy 11.676577 -430.497524) (xy 11.877769 -430.449537)
			(xy 12.080688 -430.409478) (xy 12.285023 -430.377411) (xy 12.490459 -430.353384) (xy 12.696678 -430.337434)
			(xy 12.903365 -430.329586) (xy 13.110201 -430.329852) (xy 13.316867 -430.338231) (xy 13.523045 -430.35471)
			(xy 13.728418 -430.379265) (xy 13.93267 -430.411857) (xy 14.135486 -430.452436) (xy 14.336554 -430.50094)
			(xy 14.535565 -430.557294) (xy 14.732212 -430.621411) (xy 14.926192 -430.693193) (xy 15.117208 -430.772529)
			(xy 15.304964 -430.859297) (xy 15.489172 -430.953363) (xy 15.669548 -431.054583) (xy 15.845815 -431.162801)
			(xy 16.017701 -431.277849) (xy 16.184941 -431.399552) (xy 16.347279 -431.527722) (xy 16.385577 -431.560478)
			(xy 58.141108 -431.560478) (xy 58.141108 -429.018954) (xy 58.141572 -429.00684) (xy 58.149068 -428.9838)
			(xy 58.163313 -428.964202) (xy 58.182915 -428.949961) (xy 58.205956 -428.94247) (xy 58.21807 -428.941992)
			(xy 59.15787 -428.941992) (xy 59.169978 -428.942537) (xy 59.193013 -428.95001) (xy 59.207512 -428.960534)
			(xy 60.141104 -428.960534) (xy 60.141104 -426.41901) (xy 60.14162 -426.406899) (xy 60.1491 -426.383862)
			(xy 60.163332 -426.364263) (xy 60.182923 -426.35002) (xy 60.205956 -426.342527) (xy 60.218066 -426.342048)
			(xy 61.157866 -426.342048) (xy 61.169988 -426.342489) (xy 61.193047 -426.349973) (xy 61.212664 -426.364219)
			(xy 61.226916 -426.383831) (xy 61.234407 -426.406888) (xy 61.234828 -426.41901) (xy 61.234828 -427.960536)
			(xy 62.1411 -427.960536) (xy 62.1411 -425.419012) (xy 62.14157 -425.406962) (xy 62.149 -425.384037)
			(xy 62.163138 -425.364521) (xy 62.182606 -425.350318) (xy 62.205506 -425.342811) (xy 62.217554 -425.342304)
			(xy 63.157862 -425.342304) (xy 63.169946 -425.342839) (xy 63.192939 -425.350281) (xy 63.207185 -425.360592)
			(xy 64.141096 -425.360592) (xy 64.141096 -422.819068) (xy 64.141532 -422.807017) (xy 64.148973 -422.784091)
			(xy 64.16312 -422.764576) (xy 64.182595 -422.750373) (xy 64.2055 -422.742867) (xy 64.21755 -422.74236)
			(xy 65.157858 -422.74236) (xy 65.169947 -422.742843) (xy 65.19295 -422.750291) (xy 65.212532 -422.764473)
			(xy 65.226784 -422.784004) (xy 65.234313 -422.80698) (xy 65.23482 -422.819068) (xy 65.23482 -425.360592)
			(xy 65.234334 -425.37264) (xy 65.226905 -425.395562) (xy 65.212771 -425.415076) (xy 65.193307 -425.42928)
			(xy 65.170412 -425.43679) (xy 65.158366 -425.4373) (xy 64.218058 -425.4373) (xy 64.20597 -425.436829)
			(xy 64.182975 -425.429366) (xy 64.163399 -425.415179) (xy 64.149149 -425.395649) (xy 64.141611 -425.372678)
			(xy 64.141096 -425.360592) (xy 63.207185 -425.360592) (xy 63.212517 -425.364451) (xy 63.22677 -425.383968)
			(xy 63.234309 -425.40693) (xy 63.234824 -425.419012) (xy 63.234824 -427.960536) (xy 63.234371 -427.972586)
			(xy 63.226932 -427.995508) (xy 63.212788 -428.015022) (xy 63.193318 -428.029225) (xy 63.170418 -428.036734)
			(xy 63.15837 -428.037244) (xy 62.218062 -428.037244) (xy 62.205969 -428.036825) (xy 62.182964 -428.029356)
			(xy 62.163384 -428.015157) (xy 62.149135 -427.995613) (xy 62.141607 -427.972628) (xy 62.1411 -427.960536)
			(xy 61.234828 -427.960536) (xy 61.234828 -428.960534) (xy 61.234417 -428.972654) (xy 61.226916 -428.995704)
			(xy 61.21266 -429.015308) (xy 61.193043 -429.029547) (xy 61.169986 -429.037027) (xy 61.157866 -429.037496)
			(xy 60.218066 -429.037496) (xy 60.205953 -429.037018) (xy 60.182914 -429.029525) (xy 60.163316 -429.015284)
			(xy 60.149075 -428.995686) (xy 60.141582 -428.972647) (xy 60.141104 -428.960534) (xy 59.207512 -428.960534)
			(xy 59.212611 -428.964235) (xy 59.226855 -428.983819) (xy 59.234351 -429.006846) (xy 59.234832 -429.018954)
			(xy 59.234832 -431.560478) (xy 59.234421 -431.572603) (xy 59.226931 -431.595666) (xy 59.212678 -431.615284)
			(xy 59.193059 -431.629535) (xy 59.169995 -431.637022) (xy 59.15787 -431.63744) (xy 58.21807 -431.63744)
			(xy 58.205952 -431.637014) (xy 58.182904 -431.629515) (xy 58.163301 -431.615262) (xy 58.149061 -431.59565)
			(xy 58.141578 -431.572597) (xy 58.141108 -431.560478) (xy 16.385577 -431.560478) (xy 16.504464 -431.662161)
			(xy 16.656255 -431.802662) (xy 16.802417 -431.94901) (xy 16.942726 -432.100979) (xy 17.076965 -432.258334)
			(xy 17.204929 -432.420835) (xy 17.326419 -432.58823) (xy 17.44125 -432.760262) (xy 17.549244 -432.936666)
			(xy 17.650235 -433.11717) (xy 17.744067 -433.301497) (xy 17.830597 -433.489363) (xy 17.90969 -433.680479)
			(xy 17.981226 -433.874551) (xy 18.045093 -434.071279) (xy 18.101195 -434.270361) (xy 18.149444 -434.47149)
			(xy 18.189765 -434.674358) (xy 18.222098 -434.878651) (xy 18.246392 -435.084055) (xy 18.252398 -435.16042)
			(xy 58.141108 -435.16042) (xy 58.141108 -432.618896) (xy 58.141557 -432.606845) (xy 58.148992 -432.583918)
			(xy 58.163135 -432.564401) (xy 58.182608 -432.550199) (xy 58.205512 -432.542694) (xy 58.217562 -432.542188)
			(xy 59.15787 -432.542188) (xy 59.169963 -432.542634) (xy 59.19297 -432.550088) (xy 59.207307 -432.560476)
			(xy 60.141104 -432.560476) (xy 60.141104 -430.018952) (xy 60.141519 -430.006899) (xy 60.148965 -429.983971)
			(xy 60.163118 -429.964456) (xy 60.182597 -429.950254) (xy 60.205506 -429.94275) (xy 60.217558 -429.942244)
			(xy 61.157866 -429.942244) (xy 61.169954 -429.942736) (xy 61.192954 -429.950184) (xy 61.212535 -429.964364)
			(xy 61.226787 -429.983893) (xy 61.234319 -430.006866) (xy 61.234828 -430.018952) (xy 61.234828 -431.560478)
			(xy 62.1411 -431.560478) (xy 62.1411 -429.018954) (xy 62.141572 -429.006841) (xy 62.149067 -428.983803)
			(xy 62.163311 -428.964205) (xy 62.18291 -428.949964) (xy 62.205949 -428.942471) (xy 62.218062 -428.941992)
			(xy 63.157862 -428.941992) (xy 63.16997 -428.942543) (xy 63.193004 -428.950015) (xy 63.207499 -428.960534)
			(xy 64.141096 -428.960534) (xy 64.141096 -426.41901) (xy 64.14162 -426.4069) (xy 64.149099 -426.383864)
			(xy 64.163329 -426.364266) (xy 64.182918 -426.350023) (xy 64.205948 -426.342528) (xy 64.218058 -426.342048)
			(xy 65.157858 -426.342048) (xy 65.16998 -426.342496) (xy 65.193039 -426.349978) (xy 65.212655 -426.364222)
			(xy 65.226908 -426.383833) (xy 65.234399 -426.406889) (xy 65.23482 -426.41901) (xy 65.23482 -427.960536)
			(xy 66.141092 -427.960536) (xy 66.141092 -425.419012) (xy 66.14157 -425.406963) (xy 66.148998 -425.384039)
			(xy 66.163135 -425.364524) (xy 66.182601 -425.35032) (xy 66.205499 -425.342812) (xy 66.217546 -425.342304)
			(xy 67.157854 -425.342304) (xy 67.169938 -425.342846) (xy 67.192931 -425.350286) (xy 67.207172 -425.360592)
			(xy 68.141088 -425.360592) (xy 68.141088 -422.819068) (xy 68.141532 -422.807017) (xy 68.148972 -422.784093)
			(xy 68.163118 -422.764578) (xy 68.18259 -422.750376) (xy 68.205493 -422.742868) (xy 68.217542 -422.74236)
			(xy 69.15785 -422.74236) (xy 69.169939 -422.74285) (xy 69.192941 -422.750296) (xy 69.212524 -422.764475)
			(xy 69.226775 -422.784006) (xy 69.234305 -422.806981) (xy 69.234812 -422.819068) (xy 69.234812 -424.360594)
			(xy 70.141084 -424.360594) (xy 70.141084 -421.81907) (xy 70.141435 -421.806941) (xy 70.148941 -421.783873)
			(xy 70.163209 -421.764255) (xy 70.182842 -421.750006) (xy 70.205917 -421.742523) (xy 70.218046 -421.742108)
			(xy 71.157846 -421.742108) (xy 71.16996 -421.742572) (xy 71.193 -421.750068) (xy 71.207209 -421.760396)
			(xy 72.14108 -421.760396) (xy 72.14108 -419.218872) (xy 72.141535 -419.206822) (xy 72.148973 -419.183899)
			(xy 72.163116 -419.164386) (xy 72.182586 -419.150182) (xy 72.205486 -419.142673) (xy 72.217534 -419.142164)
			(xy 73.157842 -419.142164) (xy 73.169936 -419.142572) (xy 73.192942 -419.150043) (xy 73.212524 -419.164244)
			(xy 73.226772 -419.183791) (xy 73.234298 -419.206779) (xy 73.234804 -419.218872) (xy 73.234804 -420.921688)
			(xy 74.756264 -420.921688) (xy 74.75686 -420.878998) (xy 74.766424 -420.794155) (xy 74.785387 -420.710907)
			(xy 74.813514 -420.630292) (xy 74.850452 -420.553315) (xy 74.872596 -420.516812) (xy 74.8773 -420.508555)
			(xy 74.880805 -420.48989) (xy 74.877293 -420.471226) (xy 74.872596 -420.462964) (xy 74.850439 -420.426469)
			(xy 74.813494 -420.349493) (xy 74.785369 -420.268877) (xy 74.766414 -420.185625) (xy 74.756867 -420.100779)
			(xy 74.756264 -420.058088) (xy 74.756742 -420.019417) (xy 74.764554 -419.942472) (xy 74.780105 -419.86671)
			(xy 74.803237 -419.792909) (xy 74.833712 -419.721825) (xy 74.871219 -419.654187) (xy 74.915372 -419.590688)
			(xy 74.96572 -419.531978) (xy 75.021746 -419.47866) (xy 75.082875 -419.431281) (xy 75.11542 -419.410388)
			(xy 75.125334 -419.403459) (xy 75.137795 -419.382767) (xy 75.139296 -419.370764) (xy 75.141684 -419.343584)
			(xy 75.153243 -419.29026) (xy 75.172277 -419.239126) (xy 75.198398 -419.191223) (xy 75.231074 -419.147528)
			(xy 75.269639 -419.108931) (xy 75.313307 -419.076218) (xy 75.361188 -419.050057) (xy 75.412306 -419.030979)
			(xy 75.465619 -419.019375) (xy 75.520042 -419.015481) (xy 75.574465 -419.019375) (xy 75.627778 -419.030979)
			(xy 75.678896 -419.050057) (xy 75.726777 -419.076218) (xy 75.770445 -419.108931) (xy 75.80901 -419.147528)
			(xy 75.841686 -419.191223) (xy 75.867807 -419.239126) (xy 75.886841 -419.29026) (xy 75.8984 -419.343584)
			(xy 75.900788 -419.370764) (xy 75.902321 -419.382755) (xy 75.914778 -419.403432) (xy 75.924664 -419.410388)
			(xy 75.957226 -419.431252) (xy 76.018345 -419.478644) (xy 76.074362 -419.531971) (xy 76.124701 -419.590686)
			(xy 76.168848 -419.654189) (xy 76.20635 -419.721829) (xy 76.236824 -419.792913) (xy 76.259957 -419.866713)
			(xy 76.275513 -419.942473) (xy 76.283331 -420.019418) (xy 76.28382 -420.058088) (xy 76.2832 -420.100777)
			(xy 76.27364 -420.185619) (xy 76.254681 -420.268867) (xy 76.226561 -420.349482) (xy 76.189629 -420.42646)
			(xy 76.167488 -420.462964) (xy 76.162804 -420.471231) (xy 76.159294 -420.48989) (xy 76.162797 -420.50855)
			(xy 76.167488 -420.516812) (xy 76.189634 -420.553314) (xy 76.226581 -420.630287) (xy 76.254708 -420.710902)
			(xy 76.273666 -420.794152) (xy 76.283216 -420.878998) (xy 76.28382 -420.921688) (xy 76.28333 -420.960358)
			(xy 76.275521 -421.037304) (xy 76.259972 -421.113066) (xy 76.236841 -421.186867) (xy 76.206367 -421.257951)
			(xy 76.168862 -421.325589) (xy 76.12471 -421.389089) (xy 76.074363 -421.447798) (xy 76.018338 -421.501116)
			(xy 75.957208 -421.548495) (xy 75.924664 -421.569388) (xy 75.914757 -421.576325) (xy 75.902294 -421.597012)
			(xy 75.900788 -421.609012) (xy 75.8984 -421.636192) (xy 75.886841 -421.689516) (xy 75.867807 -421.74065)
			(xy 75.841686 -421.788553) (xy 75.80901 -421.832248) (xy 75.770445 -421.870845) (xy 75.726777 -421.903558)
			(xy 75.678896 -421.929719) (xy 75.627778 -421.948797) (xy 75.574465 -421.960401) (xy 75.520042 -421.964295)
			(xy 75.465619 -421.960401) (xy 75.412306 -421.948797) (xy 75.361188 -421.929719) (xy 75.313307 -421.903558)
			(xy 75.269639 -421.870845) (xy 75.231074 -421.832248) (xy 75.198398 -421.788553) (xy 75.172277 -421.74065)
			(xy 75.153243 -421.689516) (xy 75.141684 -421.636192) (xy 75.139296 -421.609012) (xy 75.137783 -421.597017)
			(xy 75.125313 -421.57634) (xy 75.11542 -421.569388) (xy 75.082912 -421.548442) (xy 75.02179 -421.501062)
			(xy 74.96577 -421.447746) (xy 74.915426 -421.389041) (xy 74.871274 -421.325547) (xy 74.833766 -421.257917)
			(xy 74.803285 -421.186841) (xy 74.780145 -421.113048) (xy 74.764583 -421.037294) (xy 74.756757 -420.960356)
			(xy 74.756264 -420.921688) (xy 73.234804 -420.921688) (xy 73.234804 -421.760396) (xy 73.234337 -421.772446)
			(xy 73.226906 -421.79537) (xy 73.212766 -421.814886) (xy 73.193298 -421.829089) (xy 73.170398 -421.836596)
			(xy 73.15835 -421.837104) (xy 72.218042 -421.837104) (xy 72.205959 -421.836558) (xy 72.182967 -421.829118)
			(xy 72.16339 -421.81495) (xy 72.149137 -421.795436) (xy 72.141596 -421.772477) (xy 72.14108 -421.760396)
			(xy 71.207209 -421.760396) (xy 71.212598 -421.764313) (xy 71.226839 -421.783915) (xy 71.23433 -421.806956)
			(xy 71.234808 -421.81907) (xy 71.234808 -424.360594) (xy 71.234284 -424.372704) (xy 71.226804 -424.395739)
			(xy 71.212574 -424.415337) (xy 71.192985 -424.42958) (xy 71.169955 -424.437076) (xy 71.157846 -424.437556)
			(xy 70.218046 -424.437556) (xy 70.205925 -424.437101) (xy 70.182867 -424.429621) (xy 70.16325 -424.415378)
			(xy 70.148998 -424.395769) (xy 70.141505 -424.372715) (xy 70.141084 -424.360594) (xy 69.234812 -424.360594)
			(xy 69.234812 -425.360592) (xy 69.234333 -425.372641) (xy 69.226904 -425.395564) (xy 69.212768 -425.415079)
			(xy 69.193302 -425.429283) (xy 69.170405 -425.436791) (xy 69.158358 -425.4373) (xy 68.21805 -425.4373)
			(xy 68.205967 -425.436751) (xy 68.182975 -425.429313) (xy 68.163397 -425.415146) (xy 68.149144 -425.395632)
			(xy 68.141603 -425.372673) (xy 68.141088 -425.360592) (xy 67.207172 -425.360592) (xy 67.212508 -425.364454)
			(xy 67.226762 -425.38397) (xy 67.234301 -425.40693) (xy 67.234816 -425.419012) (xy 67.234816 -427.960536)
			(xy 67.234371 -427.972587) (xy 67.226931 -427.995511) (xy 67.212785 -428.015024) (xy 67.193313 -428.029227)
			(xy 67.170411 -428.036735) (xy 67.158362 -428.037244) (xy 66.218054 -428.037244) (xy 66.20596 -428.036832)
			(xy 66.182956 -428.02936) (xy 66.163375 -428.01516) (xy 66.149127 -427.995615) (xy 66.141599 -427.972628)
			(xy 66.141092 -427.960536) (xy 65.23482 -427.960536) (xy 65.23482 -428.960534) (xy 65.234469 -428.972663)
			(xy 65.226962 -428.99573) (xy 65.212694 -429.015348) (xy 65.193062 -429.029597) (xy 65.169987 -429.03708)
			(xy 65.157858 -429.037496) (xy 64.218058 -429.037496) (xy 64.205945 -429.037025) (xy 64.182906 -429.02953)
			(xy 64.163308 -429.015287) (xy 64.149066 -428.995687) (xy 64.141574 -428.972647) (xy 64.141096 -428.960534)
			(xy 63.207499 -428.960534) (xy 63.212603 -428.964238) (xy 63.226847 -428.98382) (xy 63.234343 -429.006847)
			(xy 63.234824 -429.018954) (xy 63.234824 -431.560478) (xy 63.234421 -431.572603) (xy 63.22693 -431.595668)
			(xy 63.212675 -431.615287) (xy 63.193054 -431.629537) (xy 63.169987 -431.637023) (xy 63.157862 -431.63744)
			(xy 62.218062 -431.63744) (xy 62.205943 -431.63702) (xy 62.182895 -431.62952) (xy 62.163292 -431.615265)
			(xy 62.149053 -431.595651) (xy 62.14157 -431.572597) (xy 62.1411 -431.560478) (xy 61.234828 -431.560478)
			(xy 61.234828 -432.560476) (xy 61.23432 -432.572522) (xy 61.226897 -432.595442) (xy 61.212768 -432.614956)
			(xy 61.193309 -432.629161) (xy 61.170418 -432.636673) (xy 61.158374 -432.637184) (xy 60.218066 -432.637184)
			(xy 60.205977 -432.636722) (xy 60.182979 -432.629259) (xy 60.163402 -432.61507) (xy 60.149152 -432.595538)
			(xy 60.141616 -432.572563) (xy 60.141104 -432.560476) (xy 59.207307 -432.560476) (xy 59.212555 -432.564278)
			(xy 59.226805 -432.58382) (xy 59.234329 -432.606805) (xy 59.234832 -432.618896) (xy 59.234832 -435.16042)
			(xy 59.234358 -435.172468) (xy 59.226923 -435.195389) (xy 59.212785 -435.214901) (xy 59.19332 -435.229105)
			(xy 59.170424 -435.236616) (xy 59.158378 -435.237128) (xy 58.21807 -435.237128) (xy 58.205976 -435.236718)
			(xy 58.182969 -435.229249) (xy 58.163386 -435.215049) (xy 58.149138 -435.195502) (xy 58.141612 -435.172513)
			(xy 58.141108 -435.16042) (xy 18.252398 -435.16042) (xy 18.26261 -435.290254) (xy 18.270727 -435.49693)
			(xy 18.271236 -435.600348) (xy 18.27074 -435.702965) (xy 18.262751 -435.908044) (xy 18.246786 -436.112657)
			(xy 18.222869 -436.316493) (xy 18.191035 -436.519244) (xy 18.151333 -436.720602) (xy 18.103823 -436.920261)
			(xy 18.048576 -437.11792) (xy 17.985678 -437.313279) (xy 17.915223 -437.506041) (xy 17.837318 -437.695915)
			(xy 17.752081 -437.882612) (xy 17.659641 -438.06585) (xy 17.560138 -438.24535) (xy 17.453724 -438.420842)
			(xy 17.340559 -438.592058) (xy 17.220815 -438.758739) (xy 17.219352 -438.760616) (xy 58.141108 -438.760616)
			(xy 58.141108 -436.219092) (xy 58.141553 -436.207041) (xy 58.148989 -436.184113) (xy 58.163134 -436.164597)
			(xy 58.182607 -436.150394) (xy 58.205512 -436.14289) (xy 58.217562 -436.142384) (xy 59.15787 -436.142384)
			(xy 59.169962 -436.142834) (xy 59.192969 -436.150288) (xy 59.206951 -436.160418) (xy 60.141104 -436.160418)
			(xy 60.141104 -433.618894) (xy 60.141606 -433.606783) (xy 60.149091 -433.583745) (xy 60.163326 -433.564146)
			(xy 60.18292 -433.549904) (xy 60.205955 -433.542411) (xy 60.218066 -433.541932) (xy 61.157866 -433.541932)
			(xy 61.169986 -433.542389) (xy 61.193043 -433.549871) (xy 61.212658 -433.564113) (xy 61.226911 -433.583721)
			(xy 61.234405 -433.606774) (xy 61.234828 -433.618894) (xy 61.234828 -435.16042) (xy 62.1411 -435.16042)
			(xy 62.1411 -432.618896) (xy 62.141557 -432.606846) (xy 62.14899 -432.58392) (xy 62.163132 -432.564404)
			(xy 62.182603 -432.550201) (xy 62.205505 -432.542695) (xy 62.217554 -432.542188) (xy 63.157862 -432.542188)
			(xy 63.169954 -432.542641) (xy 63.192962 -432.550093) (xy 63.207295 -432.560476) (xy 64.141096 -432.560476)
			(xy 64.141096 -430.018952) (xy 64.141519 -430.0069) (xy 64.148964 -429.983973) (xy 64.163115 -429.964459)
			(xy 64.182592 -429.950257) (xy 64.205499 -429.942751) (xy 64.21755 -429.942244) (xy 65.157858 -429.942244)
			(xy 65.169946 -429.942743) (xy 65.192946 -429.950189) (xy 65.212527 -429.964367) (xy 65.226779 -429.983894)
			(xy 65.234311 -430.006866) (xy 65.23482 -430.018952) (xy 65.23482 -431.560478) (xy 66.141092 -431.560478)
			(xy 66.141092 -429.018954) (xy 66.141572 -429.006842) (xy 66.149066 -428.983805) (xy 66.163308 -428.964208)
			(xy 66.182905 -428.949966) (xy 66.205942 -428.942472) (xy 66.218054 -428.941992) (xy 67.157854 -428.941992)
			(xy 67.169962 -428.94255) (xy 67.192996 -428.950019) (xy 67.207487 -428.960534) (xy 68.141088 -428.960534)
			(xy 68.141088 -426.41901) (xy 68.14162 -426.406901) (xy 68.149098 -426.383867) (xy 68.163326 -426.364269)
			(xy 68.182913 -426.350025) (xy 68.205941 -426.342529) (xy 68.21805 -426.342048) (xy 69.15785 -426.342048)
			(xy 69.169968 -426.342469) (xy 69.193015 -426.349972) (xy 69.212616 -426.364226) (xy 69.226856 -426.383839)
			(xy 69.23434 -426.406891) (xy 69.234812 -426.41901) (xy 69.234812 -427.960536) (xy 70.141084 -427.960536)
			(xy 70.141084 -425.419012) (xy 70.14157 -425.406964) (xy 70.148997 -425.384042) (xy 70.163132 -425.364527)
			(xy 70.182596 -425.350323) (xy 70.205492 -425.342813) (xy 70.217538 -425.342304) (xy 71.157846 -425.342304)
			(xy 71.169934 -425.342767) (xy 71.19293 -425.350232) (xy 71.207224 -425.360592) (xy 72.14108 -425.360592)
			(xy 72.14108 -422.819068) (xy 72.141532 -422.807018) (xy 72.148971 -422.784095) (xy 72.163115 -422.764581)
			(xy 72.182585 -422.750378) (xy 72.205486 -422.742869) (xy 72.217534 -422.74236) (xy 73.157842 -422.74236)
			(xy 73.169936 -422.742772) (xy 73.192941 -422.750243) (xy 73.212522 -422.764443) (xy 73.226771 -422.783989)
			(xy 73.234298 -422.806975) (xy 73.234804 -422.819068) (xy 73.234804 -424.74007) (xy 109.801162 -424.74007)
			(xy 109.805142 -424.60708) (xy 109.817069 -424.474566) (xy 109.836899 -424.343002) (xy 109.864561 -424.21286)
			(xy 109.899957 -424.084605) (xy 109.94296 -423.958697) (xy 109.993416 -423.835585) (xy 110.051144 -423.715712)
			(xy 110.115938 -423.599505) (xy 110.187565 -423.487381) (xy 110.26577 -423.379742) (xy 110.350272 -423.276972)
			(xy 110.440769 -423.17944) (xy 110.536936 -423.087494) (xy 110.63843 -423.001464) (xy 110.744888 -422.921658)
			(xy 110.855927 -422.848362) (xy 110.971152 -422.781837) (xy 111.090148 -422.722322) (xy 111.212491 -422.67003)
			(xy 111.337742 -422.625149) (xy 111.465453 -422.587838) (xy 111.595167 -422.558231) (xy 111.726419 -422.536436)
			(xy 111.85874 -422.522528) (xy 111.991656 -422.516559) (xy 112.124691 -422.518549) (xy 112.257368 -422.528492)
			(xy 112.389214 -422.546352) (xy 112.519755 -422.572064) (xy 112.648525 -422.605538) (xy 112.775063 -422.646652)
			(xy 112.898915 -422.695261) (xy 113.019639 -422.751189) (xy 113.136802 -422.814237) (xy 113.249985 -422.884179)
			(xy 113.358782 -422.960765) (xy 113.462804 -423.04372) (xy 113.561679 -423.132748) (xy 113.655053 -423.227529)
			(xy 113.742592 -423.327725) (xy 113.823982 -423.432977) (xy 113.898931 -423.542907) (xy 113.967172 -423.657124)
			(xy 114.028461 -423.775217) (xy 114.082577 -423.896764) (xy 114.129327 -424.021329) (xy 114.168544 -424.148468)
			(xy 114.200088 -424.277724) (xy 114.223844 -424.408636) (xy 114.23973 -424.540734) (xy 114.247687 -424.673545)
			(xy 114.248184 -424.74007) (xy 114.247687 -424.806595) (xy 114.23973 -424.939406) (xy 114.223844 -425.071504)
			(xy 114.200088 -425.202416) (xy 114.168544 -425.331672) (xy 114.129327 -425.458811) (xy 114.082577 -425.583376)
			(xy 114.028461 -425.704923) (xy 113.967172 -425.823016) (xy 113.898931 -425.937233) (xy 113.823982 -426.047163)
			(xy 113.742592 -426.152415) (xy 113.655053 -426.252611) (xy 113.561679 -426.347392) (xy 113.462804 -426.43642)
			(xy 113.358782 -426.519375) (xy 113.249985 -426.595961) (xy 113.136802 -426.665903) (xy 113.019639 -426.728951)
			(xy 112.898915 -426.784879) (xy 112.775063 -426.833488) (xy 112.648525 -426.874602) (xy 112.519755 -426.908076)
			(xy 112.389214 -426.933788) (xy 112.257368 -426.951648) (xy 112.124691 -426.961591) (xy 111.991656 -426.963581)
			(xy 111.85874 -426.957612) (xy 111.726419 -426.943704) (xy 111.595167 -426.921909) (xy 111.465453 -426.892302)
			(xy 111.337742 -426.854991) (xy 111.212491 -426.81011) (xy 111.090148 -426.757818) (xy 110.971152 -426.698303)
			(xy 110.855927 -426.631778) (xy 110.744888 -426.558482) (xy 110.63843 -426.478676) (xy 110.536936 -426.392646)
			(xy 110.440769 -426.3007) (xy 110.350272 -426.203168) (xy 110.26577 -426.100398) (xy 110.187565 -425.992759)
			(xy 110.115938 -425.880635) (xy 110.051144 -425.764428) (xy 109.993416 -425.644555) (xy 109.94296 -425.521443)
			(xy 109.899957 -425.395535) (xy 109.864561 -425.26728) (xy 109.836899 -425.137138) (xy 109.817069 -425.005574)
			(xy 109.805142 -424.87306) (xy 109.801162 -424.74007) (xy 73.234804 -424.74007) (xy 73.234804 -425.360592)
			(xy 73.234333 -425.372641) (xy 73.226903 -425.395566) (xy 73.212765 -425.415082) (xy 73.193297 -425.429285)
			(xy 73.170398 -425.436792) (xy 73.15835 -425.4373) (xy 72.218042 -425.4373) (xy 72.205959 -425.436758)
			(xy 72.182966 -425.429317) (xy 72.163389 -425.415149) (xy 72.149135 -425.395633) (xy 72.141595 -425.372673)
			(xy 72.14108 -425.360592) (xy 71.207224 -425.360592) (xy 71.212507 -425.364421) (xy 71.226757 -425.383953)
			(xy 71.234294 -425.406925) (xy 71.234808 -425.419012) (xy 71.234808 -427.960536) (xy 71.234371 -427.972587)
			(xy 71.226929 -427.995513) (xy 71.212782 -428.015027) (xy 71.193308 -428.02923) (xy 71.170404 -428.036736)
			(xy 71.158354 -428.037244) (xy 70.218046 -428.037244) (xy 70.205957 -428.036753) (xy 70.182955 -428.029307)
			(xy 70.163373 -428.015127) (xy 70.149122 -427.995597) (xy 70.141591 -427.972623) (xy 70.141084 -427.960536)
			(xy 69.234812 -427.960536) (xy 69.234812 -428.960534) (xy 69.234318 -428.972645) (xy 69.226828 -428.995681)
			(xy 69.21259 -429.015278) (xy 69.192996 -429.02952) (xy 69.169961 -429.037016) (xy 69.15785 -429.037496)
			(xy 68.21805 -429.037496) (xy 68.205936 -429.037031) (xy 68.182897 -429.029535) (xy 68.163299 -429.015289)
			(xy 68.149058 -428.995689) (xy 68.141566 -428.972648) (xy 68.141088 -428.960534) (xy 67.207487 -428.960534)
			(xy 67.212594 -428.96424) (xy 67.226839 -428.983822) (xy 67.234335 -429.006847) (xy 67.234816 -429.018954)
			(xy 67.234816 -431.560478) (xy 67.234421 -431.572604) (xy 67.226929 -431.59567) (xy 67.212672 -431.61529)
			(xy 67.193049 -431.62954) (xy 67.16998 -431.637024) (xy 67.157854 -431.63744) (xy 66.218054 -431.63744)
			(xy 66.205935 -431.637027) (xy 66.182886 -431.629525) (xy 66.163284 -431.615268) (xy 66.149044 -431.595653)
			(xy 66.141562 -431.572598) (xy 66.141092 -431.560478) (xy 65.23482 -431.560478) (xy 65.23482 -432.560476)
			(xy 65.23432 -432.572523) (xy 65.226896 -432.595444) (xy 65.212765 -432.614959) (xy 65.193304 -432.629164)
			(xy 65.170411 -432.636674) (xy 65.158366 -432.637184) (xy 64.218058 -432.637184) (xy 64.205969 -432.636729)
			(xy 64.182971 -432.629264) (xy 64.163393 -432.615073) (xy 64.149143 -432.595539) (xy 64.141608 -432.572564)
			(xy 64.141096 -432.560476) (xy 63.207295 -432.560476) (xy 63.212547 -432.564281) (xy 63.226797 -432.583821)
			(xy 63.234321 -432.606805) (xy 63.234824 -432.618896) (xy 63.234824 -435.16042) (xy 63.234357 -435.172469)
			(xy 63.226922 -435.195391) (xy 63.212782 -435.214904) (xy 63.193315 -435.229108) (xy 63.170417 -435.236618)
			(xy 63.15837 -435.237128) (xy 62.218062 -435.237128) (xy 62.205967 -435.236724) (xy 62.18296 -435.229253)
			(xy 62.163378 -435.215052) (xy 62.14913 -435.195503) (xy 62.141604 -435.172514) (xy 62.1411 -435.16042)
			(xy 61.234828 -435.16042) (xy 61.234828 -436.160418) (xy 61.234455 -436.172545) (xy 61.226953 -436.19561)
			(xy 61.212691 -436.215228) (xy 61.193064 -436.229477) (xy 61.169993 -436.236963) (xy 61.157866 -436.23738)
			(xy 60.218066 -436.23738) (xy 60.205951 -436.236918) (xy 60.18291 -436.229423) (xy 60.16331 -436.215178)
			(xy 60.149069 -436.195576) (xy 60.14158 -436.172533) (xy 60.141104 -436.160418) (xy 59.206951 -436.160418)
			(xy 59.212554 -436.164477) (xy 59.226804 -436.184017) (xy 59.234329 -436.207001) (xy 59.234832 -436.219092)
			(xy 59.234832 -438.760616) (xy 59.234354 -438.772664) (xy 59.226921 -438.795584) (xy 59.212784 -438.815097)
			(xy 59.193319 -438.829301) (xy 59.170424 -438.836812) (xy 59.158378 -438.837324) (xy 58.21807 -438.837324)
			(xy 58.205975 -438.836918) (xy 58.182968 -438.829448) (xy 58.163385 -438.815247) (xy 58.149137 -438.795699)
			(xy 58.141612 -438.77271) (xy 58.141108 -438.760616) (xy 17.219352 -438.760616) (xy 17.094673 -438.920632)
			(xy 16.962326 -439.077493) (xy 16.823972 -439.229083) (xy 16.679823 -439.375173) (xy 16.530096 -439.515541)
			(xy 16.375019 -439.649974) (xy 16.236871 -439.760614) (xy 60.141104 -439.760614) (xy 60.141104 -437.21909)
			(xy 60.141603 -437.206978) (xy 60.149089 -437.183941) (xy 60.163325 -437.164342) (xy 60.182919 -437.1501)
			(xy 60.205954 -437.142607) (xy 60.218066 -437.142128) (xy 61.157866 -437.142128) (xy 61.169986 -437.142589)
			(xy 61.193042 -437.15007) (xy 61.212657 -437.164312) (xy 61.22691 -437.183918) (xy 61.234404 -437.20697)
			(xy 61.234828 -437.21909) (xy 61.234828 -438.760616) (xy 62.1411 -438.760616) (xy 62.1411 -436.219092)
			(xy 62.141553 -436.207041) (xy 62.148988 -436.184116) (xy 62.163131 -436.1646) (xy 62.182602 -436.150397)
			(xy 62.205505 -436.142891) (xy 62.217554 -436.142384) (xy 63.157862 -436.142384) (xy 63.169954 -436.142841)
			(xy 63.192961 -436.150292) (xy 63.206938 -436.160418) (xy 64.141096 -436.160418) (xy 64.141096 -433.618894)
			(xy 64.141606 -433.606783) (xy 64.14909 -433.583747) (xy 64.163324 -433.564149) (xy 64.182915 -433.549906)
			(xy 64.205948 -433.542412) (xy 64.218058 -433.541932) (xy 65.157858 -433.541932) (xy 65.169978 -433.542396)
			(xy 65.193034 -433.549876) (xy 65.21265 -433.564116) (xy 65.226903 -433.583722) (xy 65.234397 -433.606774)
			(xy 65.23482 -433.618894) (xy 65.23482 -435.16042) (xy 66.141092 -435.16042) (xy 66.141092 -432.618896)
			(xy 66.141556 -432.606846) (xy 66.148989 -432.583922) (xy 66.163129 -432.564407) (xy 66.182598 -432.550204)
			(xy 66.205498 -432.542696) (xy 66.217546 -432.542188) (xy 67.157854 -432.542188) (xy 67.169946 -432.542647)
			(xy 67.192953 -432.550097) (xy 67.207281 -432.560476) (xy 68.141088 -432.560476) (xy 68.141088 -430.018952)
			(xy 68.141519 -430.0069) (xy 68.148963 -429.983975) (xy 68.163112 -429.964461) (xy 68.182587 -429.950259)
			(xy 68.205492 -429.942752) (xy 68.217542 -429.942244) (xy 69.15785 -429.942244) (xy 69.169937 -429.94275)
			(xy 69.192937 -429.950193) (xy 69.212518 -429.96437) (xy 69.22677 -429.983896) (xy 69.234303 -430.006866)
			(xy 69.234812 -430.018952) (xy 69.234812 -431.560478) (xy 70.141084 -431.560478) (xy 70.141084 -429.018954)
			(xy 70.141473 -429.006832) (xy 70.148979 -428.98378) (xy 70.16324 -428.964175) (xy 70.182862 -428.949937)
			(xy 70.205924 -428.942459) (xy 70.218046 -428.941992) (xy 71.157846 -428.941992) (xy 71.169958 -428.942472)
			(xy 71.192995 -428.949966) (xy 71.207537 -428.960534) (xy 72.14108 -428.960534) (xy 72.14108 -426.41901)
			(xy 72.141469 -426.406884) (xy 72.148964 -426.383818) (xy 72.163222 -426.364199) (xy 72.182847 -426.349949)
			(xy 72.205915 -426.342464) (xy 72.218042 -426.342048) (xy 73.157842 -426.342048) (xy 73.16996 -426.342476)
			(xy 73.193006 -426.349976) (xy 73.212608 -426.364229) (xy 73.226848 -426.383841) (xy 73.234332 -426.406892)
			(xy 73.234804 -426.41901) (xy 73.234804 -427.960536) (xy 75.141328 -427.960536) (xy 75.141328 -425.419012)
			(xy 75.141724 -425.406926) (xy 75.149192 -425.383938) (xy 75.163402 -425.364384) (xy 75.18296 -425.350181)
			(xy 75.20595 -425.34272) (xy 75.218036 -425.342304) (xy 76.157836 -425.342304) (xy 76.169914 -425.342734)
			(xy 76.192884 -425.350207) (xy 76.212422 -425.364413) (xy 76.226615 -425.383959) (xy 76.234074 -425.406934)
			(xy 76.234544 -425.419012) (xy 76.234544 -427.960536) (xy 76.234067 -427.972609) (xy 76.226599 -427.995571)
			(xy 76.212405 -428.015105) (xy 76.192871 -428.029299) (xy 76.169909 -428.036767) (xy 76.157836 -428.037244)
			(xy 75.218036 -428.037244) (xy 75.205967 -428.036706) (xy 75.183007 -428.029258) (xy 75.163472 -428.015079)
			(xy 75.149275 -427.995558) (xy 75.141806 -427.972605) (xy 75.141328 -427.960536) (xy 73.234804 -427.960536)
			(xy 73.234804 -428.960534) (xy 73.234318 -428.972646) (xy 73.226827 -428.995683) (xy 73.212587 -429.015281)
			(xy 73.192991 -429.029523) (xy 73.169954 -429.037017) (xy 73.157842 -429.037496) (xy 72.218042 -429.037496)
			(xy 72.205925 -429.037005) (xy 72.182873 -429.029528) (xy 72.16326 -429.015294) (xy 72.149006 -428.995695)
			(xy 72.141507 -428.972651) (xy 72.14108 -428.960534) (xy 71.207537 -428.960534) (xy 71.212592 -428.964208)
			(xy 71.226834 -428.983805) (xy 71.234328 -429.006842) (xy 71.234808 -429.018954) (xy 71.234808 -431.560478)
			(xy 71.23427 -431.572587) (xy 71.226795 -431.595622) (xy 71.212568 -431.61522) (xy 71.192983 -431.629464)
			(xy 71.169954 -431.636959) (xy 71.157846 -431.63744) (xy 70.218046 -431.63744) (xy 70.205923 -431.637001)
			(xy 70.182862 -431.629518) (xy 70.163245 -431.615273) (xy 70.148993 -431.595659) (xy 70.141503 -431.5726)
			(xy 70.141084 -431.560478) (xy 69.234812 -431.560478) (xy 69.234812 -432.560476) (xy 69.23432 -432.572524)
			(xy 69.226895 -432.595447) (xy 69.212762 -432.614962) (xy 69.193299 -432.629166) (xy 69.170404 -432.636675)
			(xy 69.158358 -432.637184) (xy 68.21805 -432.637184) (xy 68.205965 -432.636651) (xy 68.18297 -432.62921)
			(xy 68.163392 -432.61504) (xy 68.149139 -432.595522) (xy 68.141601 -432.572559) (xy 68.141088 -432.560476)
			(xy 67.207281 -432.560476) (xy 67.212538 -432.564284) (xy 67.226788 -432.583823) (xy 67.234313 -432.606806)
			(xy 67.234816 -432.618896) (xy 67.234816 -435.16042) (xy 67.234357 -435.17247) (xy 67.226921 -435.195393)
			(xy 67.212779 -435.214907) (xy 67.19331 -435.22911) (xy 67.17041 -435.236619) (xy 67.158362 -435.237128)
			(xy 66.218054 -435.237128) (xy 66.205959 -435.236731) (xy 66.182951 -435.229258) (xy 66.163369 -435.215054)
			(xy 66.149122 -435.195505) (xy 66.141596 -435.172514) (xy 66.141092 -435.16042) (xy 65.23482 -435.16042)
			(xy 65.23482 -436.160418) (xy 65.234454 -436.172546) (xy 65.226952 -436.195612) (xy 65.212688 -436.215231)
			(xy 65.193058 -436.22948) (xy 65.169986 -436.236964) (xy 65.157858 -436.23738) (xy 64.218058 -436.23738)
			(xy 64.205943 -436.236924) (xy 64.182901 -436.229428) (xy 64.163302 -436.215181) (xy 64.149061 -436.195577)
			(xy 64.141572 -436.172533) (xy 64.141096 -436.160418) (xy 63.206938 -436.160418) (xy 63.212545 -436.16448)
			(xy 63.226795 -436.184019) (xy 63.234321 -436.207002) (xy 63.234824 -436.219092) (xy 63.234824 -438.760616)
			(xy 63.234354 -438.772665) (xy 63.22692 -438.795587) (xy 63.212781 -438.8151) (xy 63.193314 -438.829304)
			(xy 63.170417 -438.836814) (xy 63.15837 -438.837324) (xy 62.218062 -438.837324) (xy 62.205967 -438.836924)
			(xy 62.182959 -438.829453) (xy 62.163377 -438.81525) (xy 62.149129 -438.795701) (xy 62.141604 -438.77271)
			(xy 62.1411 -438.760616) (xy 61.234828 -438.760616) (xy 61.234828 -439.760614) (xy 64.141096 -439.760614)
			(xy 64.141096 -437.21909) (xy 64.141603 -437.206979) (xy 64.149088 -437.183943) (xy 64.163322 -437.164345)
			(xy 64.182914 -437.150102) (xy 64.205947 -437.142608) (xy 64.218058 -437.142128) (xy 65.157858 -437.142128)
			(xy 65.169978 -437.142595) (xy 65.193033 -437.150075) (xy 65.212648 -437.164315) (xy 65.226901 -437.18392)
			(xy 65.234396 -437.206971) (xy 65.23482 -437.21909) (xy 65.23482 -438.760616) (xy 66.141092 -438.760616)
			(xy 66.141092 -436.219092) (xy 66.141553 -436.207042) (xy 66.148987 -436.184118) (xy 66.163128 -436.164603)
			(xy 66.182597 -436.1504) (xy 66.205498 -436.142892) (xy 66.217546 -436.142384) (xy 67.157854 -436.142384)
			(xy 67.169946 -436.142847) (xy 67.192952 -436.150297) (xy 67.206925 -436.160418) (xy 68.141088 -436.160418)
			(xy 68.141088 -433.618894) (xy 68.141606 -433.606784) (xy 68.149089 -433.583749) (xy 68.163321 -433.564152)
			(xy 68.18291 -433.549909) (xy 68.20594 -433.542413) (xy 68.21805 -433.541932) (xy 69.15785 -433.541932)
			(xy 69.169967 -433.542369) (xy 69.19301 -433.549869) (xy 69.212611 -433.564121) (xy 69.226851 -433.583729)
			(xy 69.234338 -433.606777) (xy 69.234812 -433.618894) (xy 69.234812 -435.16042) (xy 70.141084 -435.16042)
			(xy 70.141084 -432.618896) (xy 70.141556 -432.606847) (xy 70.148988 -432.583924) (xy 70.163126 -432.56441)
			(xy 70.182593 -432.550206) (xy 70.205491 -432.542697) (xy 70.217538 -432.542188) (xy 71.157846 -432.542188)
			(xy 71.169943 -432.542569) (xy 71.192953 -432.550044) (xy 71.207333 -432.560476) (xy 72.14108 -432.560476)
			(xy 72.14108 -430.018952) (xy 72.141519 -430.006901) (xy 72.148962 -429.983977) (xy 72.163109 -429.964464)
			(xy 72.182582 -429.950262) (xy 72.205485 -429.942753) (xy 72.217534 -429.942244) (xy 73.157842 -429.942244)
			(xy 73.169934 -429.942672) (xy 73.192937 -429.95014) (xy 73.212516 -429.964337) (xy 73.226765 -429.983879)
			(xy 73.234296 -430.006861) (xy 73.234804 -430.018952) (xy 73.234804 -431.560478) (xy 75.141328 -431.560478)
			(xy 75.141328 -429.018954) (xy 75.141768 -429.006863) (xy 75.149236 -428.983863) (xy 75.16343 -428.964285)
			(xy 75.182968 -428.950036) (xy 75.205947 -428.942503) (xy 75.218036 -428.941992) (xy 76.157836 -428.941992)
			(xy 76.169946 -428.942386) (xy 76.192973 -428.949894) (xy 76.207568 -428.960534) (xy 77.141324 -428.960534)
			(xy 77.141324 -426.41901) (xy 77.141816 -426.406923) (xy 77.149268 -426.383925) (xy 77.163449 -426.364346)
			(xy 77.182976 -426.350095) (xy 77.205946 -426.34256) (xy 77.218032 -426.342048) (xy 78.157832 -426.342048)
			(xy 78.169937 -426.342488) (xy 78.192957 -426.34999) (xy 78.212525 -426.364248) (xy 78.22672 -426.38386)
			(xy 78.234149 -426.406903) (xy 78.23454 -426.41901) (xy 78.23454 -427.960536) (xy 79.14132 -427.960536)
			(xy 79.14132 -425.419012) (xy 79.141724 -425.406927) (xy 79.149191 -425.38394) (xy 79.163399 -425.364387)
			(xy 79.182954 -425.350184) (xy 79.205943 -425.342721) (xy 79.218028 -425.342304) (xy 80.157828 -425.342304)
			(xy 80.169905 -425.34274) (xy 80.192875 -425.350212) (xy 80.212413 -425.364415) (xy 80.226606 -425.38396)
			(xy 80.234066 -425.406935) (xy 80.234536 -425.419012) (xy 80.234536 -427.960536) (xy 80.234067 -427.97261)
			(xy 80.226598 -427.995573) (xy 80.212402 -428.015107) (xy 80.192866 -428.029302) (xy 80.169902 -428.036768)
			(xy 80.157828 -428.037244) (xy 79.218028 -428.037244) (xy 79.205958 -428.036713) (xy 79.182998 -428.029262)
			(xy 79.163464 -428.015082) (xy 79.149267 -427.995559) (xy 79.141797 -427.972605) (xy 79.14132 -427.960536)
			(xy 78.23454 -427.960536) (xy 78.23454 -428.960534) (xy 78.234121 -428.972627) (xy 78.226653 -428.995632)
			(xy 78.212454 -429.015214) (xy 78.19291 -429.029462) (xy 78.169924 -429.03699) (xy 78.157832 -429.037496)
			(xy 77.218032 -429.037496) (xy 77.205924 -429.037056) (xy 77.182898 -429.029565) (xy 77.163324 -429.01531)
			(xy 77.149128 -428.995692) (xy 77.141707 -428.972643) (xy 77.141324 -428.960534) (xy 76.207568 -428.960534)
			(xy 76.212545 -428.964162) (xy 76.226738 -428.983787) (xy 76.23416 -429.006843) (xy 76.234544 -429.018954)
			(xy 76.234544 -431.560478) (xy 76.234074 -431.572568) (xy 76.226621 -431.595571) (xy 76.212436 -431.615152)
			(xy 76.192902 -431.629403) (xy 76.169924 -431.636933) (xy 76.157836 -431.63744) (xy 75.218036 -431.63744)
			(xy 75.205933 -431.636953) (xy 75.182914 -431.629469) (xy 75.163344 -431.615224) (xy 75.149146 -431.595619)
			(xy 75.141718 -431.572582) (xy 75.141328 -431.560478) (xy 73.234804 -431.560478) (xy 73.234804 -432.560476)
			(xy 73.23432 -432.572525) (xy 73.226894 -432.595449) (xy 73.212759 -432.614964) (xy 73.193294 -432.629169)
			(xy 73.170397 -432.636676) (xy 73.15835 -432.637184) (xy 72.218042 -432.637184) (xy 72.205957 -432.636657)
			(xy 72.182962 -432.629215) (xy 72.163383 -432.615043) (xy 72.14913 -432.595523) (xy 72.141593 -432.572559)
			(xy 72.14108 -432.560476) (xy 71.207333 -432.560476) (xy 71.212536 -432.564251) (xy 71.226784 -432.583805)
			(xy 71.234306 -432.6068) (xy 71.234808 -432.618896) (xy 71.234808 -435.16042) (xy 71.234357 -435.17247)
			(xy 71.22692 -435.195395) (xy 71.212776 -435.21491) (xy 71.193305 -435.229113) (xy 71.170403 -435.23662)
			(xy 71.158354 -435.237128) (xy 70.218046 -435.237128) (xy 70.205956 -435.236653) (xy 70.182951 -435.229205)
			(xy 70.163368 -435.215022) (xy 70.149117 -435.195487) (xy 70.141589 -435.172509) (xy 70.141084 -435.16042)
			(xy 69.234812 -435.16042) (xy 69.234812 -436.160418) (xy 69.234305 -436.172529) (xy 69.226818 -436.195564)
			(xy 69.212584 -436.215161) (xy 69.192993 -436.229404) (xy 69.16996 -436.2369) (xy 69.15785 -436.23738)
			(xy 68.21805 -436.23738) (xy 68.205935 -436.236931) (xy 68.182893 -436.229432) (xy 68.163293 -436.215184)
			(xy 68.149053 -436.195578) (xy 68.141564 -436.172534) (xy 68.141088 -436.160418) (xy 67.206925 -436.160418)
			(xy 67.212537 -436.164483) (xy 67.226787 -436.18402) (xy 67.234312 -436.207002) (xy 67.234816 -436.219092)
			(xy 67.234816 -438.760616) (xy 67.234354 -438.772665) (xy 67.226919 -438.795589) (xy 67.212778 -438.815103)
			(xy 67.193309 -438.829306) (xy 67.17041 -438.836815) (xy 67.158362 -438.837324) (xy 66.218054 -438.837324)
			(xy 66.205958 -438.836931) (xy 66.18295 -438.829457) (xy 66.163368 -438.815253) (xy 66.14912 -438.795702)
			(xy 66.141596 -438.77271) (xy 66.141092 -438.760616) (xy 65.23482 -438.760616) (xy 65.23482 -439.760614)
			(xy 68.141088 -439.760614) (xy 68.141088 -437.21909) (xy 68.141603 -437.20698) (xy 68.149087 -437.183945)
			(xy 68.163319 -437.164348) (xy 68.182909 -437.150105) (xy 68.20594 -437.142609) (xy 68.21805 -437.142128)
			(xy 69.15785 -437.142128) (xy 69.169966 -437.142569) (xy 69.193009 -437.150069) (xy 69.212609 -437.164319)
			(xy 69.22685 -437.183927) (xy 69.234337 -437.206974) (xy 69.234812 -437.21909) (xy 69.234812 -438.760616)
			(xy 70.141084 -438.760616) (xy 70.141084 -436.219092) (xy 70.141553 -436.207043) (xy 70.148986 -436.18412)
			(xy 70.163125 -436.164606) (xy 70.182592 -436.150402) (xy 70.205491 -436.142893) (xy 70.217538 -436.142384)
			(xy 71.157846 -436.142384) (xy 71.169942 -436.142769) (xy 71.192952 -436.150244) (xy 71.206977 -436.160418)
			(xy 72.14108 -436.160418) (xy 72.14108 -433.618894) (xy 72.141456 -433.606767) (xy 72.148955 -433.583701)
			(xy 72.163216 -433.564082) (xy 72.182844 -433.549833) (xy 72.205915 -433.542348) (xy 72.218042 -433.541932)
			(xy 73.157842 -433.541932) (xy 73.169958 -433.542376) (xy 73.193002 -433.549874) (xy 73.212602 -433.564123)
			(xy 73.226843 -433.583731) (xy 73.23433 -433.606778) (xy 73.234804 -433.618894) (xy 73.234804 -435.16042)
			(xy 75.141328 -435.16042) (xy 75.141328 -432.618896) (xy 75.14171 -432.606809) (xy 75.149183 -432.58382)
			(xy 75.163396 -432.564267) (xy 75.182956 -432.550064) (xy 75.205949 -432.542603) (xy 75.218036 -432.542188)
			(xy 76.157836 -432.542188) (xy 76.169912 -432.542633) (xy 76.19288 -432.550105) (xy 76.207146 -432.560476)
			(xy 77.141324 -432.560476) (xy 77.141324 -430.018952) (xy 77.141724 -430.006872) (xy 77.149203 -429.983898)
			(xy 77.163415 -429.964358) (xy 77.182969 -429.950167) (xy 77.205951 -429.942711) (xy 77.218032 -429.942244)
			(xy 78.157832 -429.942244) (xy 78.169903 -429.942736) (xy 78.192864 -429.950201) (xy 78.212396 -429.964393)
			(xy 78.226591 -429.983922) (xy 78.234062 -430.006881) (xy 78.23454 -430.018952) (xy 78.23454 -431.560478)
			(xy 79.14132 -431.560478) (xy 79.14132 -429.018954) (xy 79.141768 -429.006864) (xy 79.149235 -428.983865)
			(xy 79.163427 -428.964288) (xy 79.182963 -428.950038) (xy 79.205939 -428.942504) (xy 79.218028 -428.941992)
			(xy 80.157828 -428.941992) (xy 80.169938 -428.942392) (xy 80.192964 -428.949899) (xy 80.207555 -428.960534)
			(xy 81.141316 -428.960534) (xy 81.141316 -426.41901) (xy 81.141816 -426.406923) (xy 81.149267 -426.383927)
			(xy 81.163446 -426.364349) (xy 81.182971 -426.350097) (xy 81.205939 -426.342561) (xy 81.218024 -426.342048)
			(xy 82.157824 -426.342048) (xy 82.169929 -426.342495) (xy 82.192948 -426.349995) (xy 82.212516 -426.36425)
			(xy 82.226712 -426.383862) (xy 82.234141 -426.406904) (xy 82.234532 -426.41901) (xy 82.234532 -427.960536)
			(xy 83.141312 -427.960536) (xy 83.141312 -425.419012) (xy 83.141723 -425.406928) (xy 83.14919 -425.383942)
			(xy 83.163396 -425.36439) (xy 83.182949 -425.350186) (xy 83.205936 -425.342722) (xy 83.21802 -425.342304)
			(xy 84.15782 -425.342304) (xy 84.169897 -425.342748) (xy 84.192867 -425.350217) (xy 84.212404 -425.364419)
			(xy 84.226598 -425.383962) (xy 84.234057 -425.406935) (xy 84.234528 -425.419012) (xy 84.234528 -427.960536)
			(xy 84.234067 -427.97261) (xy 84.226597 -427.995576) (xy 84.212399 -428.01511) (xy 84.192861 -428.029304)
			(xy 84.169895 -428.036769) (xy 84.15782 -428.037244) (xy 83.21802 -428.037244) (xy 83.20595 -428.036719)
			(xy 83.18299 -428.029267) (xy 83.163455 -428.015085) (xy 83.149259 -427.995561) (xy 83.141789 -427.972606)
			(xy 83.141312 -427.960536) (xy 82.234532 -427.960536) (xy 82.234532 -428.960534) (xy 82.234121 -428.972628)
			(xy 82.226652 -428.995635) (xy 82.212452 -429.015216) (xy 82.192905 -429.029465) (xy 82.169917 -429.036991)
			(xy 82.157824 -429.037496) (xy 81.218024 -429.037496) (xy 81.205916 -429.037063) (xy 81.182889 -429.02957)
			(xy 81.163315 -429.015313) (xy 81.14912 -428.995694) (xy 81.141699 -428.972643) (xy 81.141316 -428.960534)
			(xy 80.207555 -428.960534) (xy 80.212536 -428.964165) (xy 80.22673 -428.983789) (xy 80.234152 -429.006843)
			(xy 80.234536 -429.018954) (xy 80.234536 -431.560478) (xy 80.234073 -431.572569) (xy 80.22662 -431.595573)
			(xy 80.212433 -431.615155) (xy 80.192897 -431.629405) (xy 80.169917 -431.636934) (xy 80.157828 -431.63744)
			(xy 79.218028 -431.63744) (xy 79.205925 -431.63696) (xy 79.182905 -431.629473) (xy 79.163335 -431.615227)
			(xy 79.149138 -431.595621) (xy 79.141709 -431.572582) (xy 79.14132 -431.560478) (xy 78.23454 -431.560478)
			(xy 78.23454 -432.560476) (xy 78.234016 -432.572546) (xy 78.226564 -432.595507) (xy 78.212382 -432.615042)
			(xy 78.192857 -432.629238) (xy 78.169902 -432.636707) (xy 78.157832 -432.637184) (xy 77.218032 -432.637184)
			(xy 77.205949 -432.63676) (xy 77.182963 -432.629298) (xy 77.16341 -432.615096) (xy 77.149206 -432.595544)
			(xy 77.141742 -432.572559) (xy 77.141324 -432.560476) (xy 76.207146 -432.560476) (xy 76.212416 -432.564307)
			(xy 76.226609 -432.583849) (xy 76.234072 -432.60682) (xy 76.234544 -432.618896) (xy 76.234544 -435.16042)
			(xy 76.234053 -435.172492) (xy 76.22659 -435.195454) (xy 76.212399 -435.214987) (xy 76.192868 -435.229182)
			(xy 76.169908 -435.236651) (xy 76.157836 -435.237128) (xy 75.218036 -435.237128) (xy 75.205957 -435.236657)
			(xy 75.182979 -435.229202) (xy 75.16343 -435.21501) (xy 75.149224 -435.195471) (xy 75.141752 -435.172499)
			(xy 75.141328 -435.16042) (xy 73.234804 -435.16042) (xy 73.234804 -436.160418) (xy 73.234304 -436.172529)
			(xy 73.226817 -436.195566) (xy 73.212581 -436.215164) (xy 73.192988 -436.229406) (xy 73.169953 -436.236901)
			(xy 73.157842 -436.23738) (xy 72.218042 -436.23738) (xy 72.205923 -436.236905) (xy 72.182869 -436.229426)
			(xy 72.163255 -436.215188) (xy 72.149001 -436.195585) (xy 72.141505 -436.172536) (xy 72.14108 -436.160418)
			(xy 71.206977 -436.160418) (xy 71.212535 -436.16445) (xy 71.226782 -436.184003) (xy 71.234305 -436.206997)
			(xy 71.234808 -436.219092) (xy 71.234808 -438.760616) (xy 71.234354 -438.772666) (xy 71.226918 -438.795591)
			(xy 71.212775 -438.815106) (xy 71.193304 -438.829309) (xy 71.170403 -438.836816) (xy 71.158354 -438.837324)
			(xy 70.218046 -438.837324) (xy 70.205955 -438.836853) (xy 70.18295 -438.829404) (xy 70.163366 -438.81522)
			(xy 70.149115 -438.795685) (xy 70.141589 -438.772705) (xy 70.141084 -438.760616) (xy 69.234812 -438.760616)
			(xy 69.234812 -439.760614) (xy 72.14108 -439.760614) (xy 72.14108 -437.21909) (xy 72.141452 -437.206963)
			(xy 72.148952 -437.183896) (xy 72.163215 -437.164278) (xy 72.182843 -437.150029) (xy 72.205914 -437.142544)
			(xy 72.218042 -437.142128) (xy 73.157842 -437.142128) (xy 73.169958 -437.142576) (xy 73.193001 -437.150073)
			(xy 73.212601 -437.164322) (xy 73.226841 -437.183928) (xy 73.234329 -437.206974) (xy 73.234804 -437.21909)
			(xy 73.234804 -438.760616) (xy 75.141328 -438.760616) (xy 75.141328 -436.219092) (xy 75.141706 -436.207005)
			(xy 75.14918 -436.184016) (xy 75.163394 -436.164463) (xy 75.182956 -436.15026) (xy 75.205949 -436.142799)
			(xy 75.218036 -436.142384) (xy 76.157836 -436.142384) (xy 76.169912 -436.142833) (xy 76.192879 -436.150305)
			(xy 76.206792 -436.160418) (xy 77.141324 -436.160418) (xy 77.141324 -433.618894) (xy 77.141802 -433.606806)
			(xy 77.149259 -433.583808) (xy 77.163443 -433.564229) (xy 77.182973 -433.549978) (xy 77.205945 -433.542444)
			(xy 77.218032 -433.541932) (xy 78.157832 -433.541932) (xy 78.169946 -433.542289) (xy 78.19298 -433.549802)
			(xy 78.212555 -433.564077) (xy 78.226747 -433.583713) (xy 78.234161 -433.606779) (xy 78.23454 -433.618894)
			(xy 78.23454 -435.16042) (xy 79.14132 -435.16042) (xy 79.14132 -432.618896) (xy 79.141709 -432.60681)
			(xy 79.149182 -432.583823) (xy 79.163393 -432.56427) (xy 79.182951 -432.550067) (xy 79.205942 -432.542604)
			(xy 79.218028 -432.542188) (xy 80.157828 -432.542188) (xy 80.169904 -432.54264) (xy 80.192871 -432.55011)
			(xy 80.207132 -432.560476) (xy 81.141316 -432.560476) (xy 81.141316 -430.018952) (xy 81.141724 -430.006873)
			(xy 81.149202 -429.9839) (xy 81.163413 -429.964361) (xy 81.182964 -429.950169) (xy 81.205944 -429.942712)
			(xy 81.218024 -429.942244) (xy 82.157824 -429.942244) (xy 82.169895 -429.942743) (xy 82.192855 -429.950206)
			(xy 82.212387 -429.964396) (xy 82.226583 -429.983924) (xy 82.234053 -430.006881) (xy 82.234532 -430.018952)
			(xy 82.234532 -431.560478) (xy 83.141312 -431.560478) (xy 83.141312 -429.018954) (xy 83.141768 -429.006865)
			(xy 83.149234 -428.983867) (xy 83.163424 -428.964291) (xy 83.182958 -428.950041) (xy 83.205932 -428.942505)
			(xy 83.21802 -428.941992) (xy 84.15782 -428.941992) (xy 84.169929 -428.942399) (xy 84.192956 -428.949903)
			(xy 84.207543 -428.960534) (xy 85.141308 -428.960534) (xy 85.141308 -426.41901) (xy 85.141815 -426.406924)
			(xy 85.149265 -426.383929) (xy 85.163443 -426.364352) (xy 85.182966 -426.3501) (xy 85.205932 -426.342562)
			(xy 85.218016 -426.342048) (xy 86.157816 -426.342048) (xy 86.169921 -426.342502) (xy 86.192939 -426.349999)
			(xy 86.212508 -426.364253) (xy 86.226704 -426.383863) (xy 86.234133 -426.406904) (xy 86.234524 -426.41901)
			(xy 86.234524 -427.960536) (xy 87.141304 -427.960536) (xy 87.141304 -425.419012) (xy 87.141723 -425.406929)
			(xy 87.149189 -425.383944) (xy 87.163393 -425.364393) (xy 87.182944 -425.350189) (xy 87.205929 -425.342723)
			(xy 87.218012 -425.342304) (xy 88.157812 -425.342304) (xy 88.169888 -425.342754) (xy 88.192858 -425.350222)
			(xy 88.212396 -425.364421) (xy 88.226589 -425.383964) (xy 88.234049 -425.406935) (xy 88.23452 -425.419012)
			(xy 88.23452 -427.960536) (xy 88.234067 -427.972611) (xy 88.226596 -427.995578) (xy 88.212396 -428.015113)
			(xy 88.192856 -428.029307) (xy 88.169887 -428.036771) (xy 88.157812 -428.037244) (xy 87.218012 -428.037244)
			(xy 87.205942 -428.036726) (xy 87.182981 -428.029271) (xy 87.163447 -428.015087) (xy 87.149251 -427.995562)
			(xy 87.141781 -427.972606) (xy 87.141304 -427.960536) (xy 86.234524 -427.960536) (xy 86.234524 -428.960534)
			(xy 86.234121 -428.972629) (xy 86.226651 -428.995637) (xy 86.212449 -429.015219) (xy 86.1929 -429.029467)
			(xy 86.16991 -429.036992) (xy 86.157816 -429.037496) (xy 85.218016 -429.037496) (xy 85.205908 -429.03707)
			(xy 85.18288 -429.029574) (xy 85.163307 -429.015315) (xy 85.149112 -428.995695) (xy 85.141691 -428.972644)
			(xy 85.141308 -428.960534) (xy 84.207543 -428.960534) (xy 84.212528 -428.964167) (xy 84.226722 -428.98379)
			(xy 84.234144 -429.006843) (xy 84.234528 -429.018954) (xy 84.234528 -431.560478) (xy 84.234073 -431.57257)
			(xy 84.226619 -431.595575) (xy 84.21243 -431.615158) (xy 84.192892 -431.629408) (xy 84.16991 -431.636935)
			(xy 84.15782 -431.63744) (xy 83.21802 -431.63744) (xy 83.205916 -431.636967) (xy 83.182896 -431.629478)
			(xy 83.163327 -431.61523) (xy 83.14913 -431.595622) (xy 83.141701 -431.572583) (xy 83.141312 -431.560478)
			(xy 82.234532 -431.560478) (xy 82.234532 -432.560476) (xy 82.234016 -432.572547) (xy 82.226563 -432.595509)
			(xy 82.212379 -432.615045) (xy 82.192852 -432.629241) (xy 82.169895 -432.636708) (xy 82.157824 -432.637184)
			(xy 81.218024 -432.637184) (xy 81.20594 -432.636766) (xy 81.182954 -432.629303) (xy 81.163401 -432.615099)
			(xy 81.149197 -432.595546) (xy 81.141734 -432.57256) (xy 81.141316 -432.560476) (xy 80.207132 -432.560476)
			(xy 80.212407 -432.56431) (xy 80.226601 -432.58385) (xy 80.234064 -432.60682) (xy 80.234536 -432.618896)
			(xy 80.234536 -435.16042) (xy 80.234053 -435.172493) (xy 80.226588 -435.195456) (xy 80.212396 -435.21499)
			(xy 80.192863 -435.229185) (xy 80.169901 -435.236652) (xy 80.157828 -435.237128) (xy 79.218028 -435.237128)
			(xy 79.205949 -435.236664) (xy 79.18297 -435.229206) (xy 79.163421 -435.215013) (xy 79.149216 -435.195473)
			(xy 79.141744 -435.172499) (xy 79.14132 -435.16042) (xy 78.23454 -435.16042) (xy 78.23454 -436.160418)
			(xy 78.234108 -436.172511) (xy 78.226644 -436.195515) (xy 78.212449 -436.215097) (xy 78.192907 -436.229346)
			(xy 78.169923 -436.236874) (xy 78.157832 -436.23738) (xy 77.218032 -436.23738) (xy 77.205923 -436.236956)
			(xy 77.182893 -436.229463) (xy 77.163318 -436.215204) (xy 77.149123 -436.195582) (xy 77.141705 -436.172528)
			(xy 77.141324 -436.160418) (xy 76.206792 -436.160418) (xy 76.212415 -436.164505) (xy 76.226608 -436.184046)
			(xy 76.234071 -436.207016) (xy 76.234544 -436.219092) (xy 76.234544 -438.760616) (xy 76.23405 -438.772688)
			(xy 76.226587 -438.795649) (xy 76.212397 -438.815183) (xy 76.192867 -438.829378) (xy 76.169908 -438.836847)
			(xy 76.157836 -438.837324) (xy 75.218036 -438.837324) (xy 75.205957 -438.836857) (xy 75.182978 -438.829401)
			(xy 75.163428 -438.815209) (xy 75.149223 -438.795669) (xy 75.141751 -438.772695) (xy 75.141328 -438.760616)
			(xy 73.234804 -438.760616) (xy 73.234804 -439.760614) (xy 77.141324 -439.760614) (xy 77.141324 -437.21909)
			(xy 77.141799 -437.207002) (xy 77.149256 -437.184003) (xy 77.163441 -437.164425) (xy 77.182972 -437.150174)
			(xy 77.205945 -437.14264) (xy 77.218032 -437.142128) (xy 78.157832 -437.142128) (xy 78.169945 -437.142489)
			(xy 78.192978 -437.150001) (xy 78.212553 -437.164276) (xy 78.226746 -437.183911) (xy 78.234161 -437.206975)
			(xy 78.23454 -437.21909) (xy 78.23454 -438.760616) (xy 79.14132 -438.760616) (xy 79.14132 -436.219092)
			(xy 79.141706 -436.207006) (xy 79.149179 -436.184018) (xy 79.163391 -436.164466) (xy 79.182951 -436.150263)
			(xy 79.205942 -436.1428) (xy 79.218028 -436.142384) (xy 80.157828 -436.142384) (xy 80.169903 -436.14284)
			(xy 80.19287 -436.150309) (xy 80.206779 -436.160418) (xy 81.141316 -436.160418) (xy 81.141316 -433.618894)
			(xy 81.141802 -433.606807) (xy 81.149257 -433.58381) (xy 81.16344 -433.564232) (xy 81.182968 -433.549981)
			(xy 81.205938 -433.542445) (xy 81.218024 -433.541932) (xy 82.157824 -433.541932) (xy 82.169937 -433.542296)
			(xy 82.192971 -433.549806) (xy 82.212546 -433.56408) (xy 82.226739 -433.583715) (xy 82.234153 -433.606779)
			(xy 82.234532 -433.618894) (xy 82.234532 -435.16042) (xy 83.141312 -435.16042) (xy 83.141312 -432.618896)
			(xy 83.141709 -432.606811) (xy 83.14918 -432.583825) (xy 83.16339 -432.564273) (xy 83.182946 -432.550069)
			(xy 83.205935 -432.542606) (xy 83.21802 -432.542188) (xy 84.15782 -432.542188) (xy 84.169895 -432.542647)
			(xy 84.192862 -432.550115) (xy 84.207119 -432.560476) (xy 85.141308 -432.560476) (xy 85.141308 -430.018952)
			(xy 85.141723 -430.006873) (xy 85.149201 -429.983902) (xy 85.16341 -429.964364) (xy 85.182959 -429.950172)
			(xy 85.205937 -429.942713) (xy 85.218016 -429.942244) (xy 86.157816 -429.942244) (xy 86.169887 -429.94275)
			(xy 86.192846 -429.950211) (xy 86.212379 -429.964399) (xy 86.226574 -429.983925) (xy 86.234045 -430.006882)
			(xy 86.234524 -430.018952) (xy 86.234524 -431.560478) (xy 87.141304 -431.560478) (xy 87.141304 -429.018954)
			(xy 87.141767 -429.006866) (xy 87.149232 -428.98387) (xy 87.163421 -428.964293) (xy 87.182953 -428.950043)
			(xy 87.205925 -428.942506) (xy 87.218012 -428.941992) (xy 88.157812 -428.941992) (xy 88.169921 -428.942406)
			(xy 88.192947 -428.949908) (xy 88.207529 -428.960534) (xy 89.1413 -428.960534) (xy 89.1413 -426.41901)
			(xy 89.141815 -426.406925) (xy 89.149264 -426.383931) (xy 89.16344 -426.364355) (xy 89.182961 -426.350103)
			(xy 89.205925 -426.342563) (xy 89.218008 -426.342048) (xy 90.157808 -426.342048) (xy 90.169912 -426.342509)
			(xy 90.192931 -426.350004) (xy 90.212499 -426.364256) (xy 90.226696 -426.383865) (xy 90.234125 -426.406905)
			(xy 90.234516 -426.41901) (xy 90.234516 -428.960534) (xy 90.234121 -428.97263) (xy 90.226649 -428.995639)
			(xy 90.212446 -429.015222) (xy 90.192895 -429.02947) (xy 90.169903 -429.036993) (xy 90.157808 -429.037496)
			(xy 89.218008 -429.037496) (xy 89.205899 -429.037077) (xy 89.182871 -429.029579) (xy 89.163298 -429.015319)
			(xy 89.149103 -428.995697) (xy 89.141683 -428.972644) (xy 89.1413 -428.960534) (xy 88.207529 -428.960534)
			(xy 88.212519 -428.96417) (xy 88.226714 -428.983792) (xy 88.234136 -429.006844) (xy 88.23452 -429.018954)
			(xy 88.23452 -431.560478) (xy 88.234073 -431.57257) (xy 88.226618 -431.595577) (xy 88.212427 -431.615161)
			(xy 88.192887 -431.629411) (xy 88.169903 -431.636936) (xy 88.157812 -431.63744) (xy 87.218012 -431.63744)
			(xy 87.205908 -431.636974) (xy 87.182888 -431.629483) (xy 87.163318 -431.615232) (xy 87.149122 -431.595624)
			(xy 87.141693 -431.572583) (xy 87.141304 -431.560478) (xy 86.234524 -431.560478) (xy 86.234524 -432.560476)
			(xy 86.234067 -432.572556) (xy 86.226608 -432.595535) (xy 86.212413 -432.615084) (xy 86.192871 -432.62929)
			(xy 86.169896 -432.636761) (xy 86.157816 -432.637184) (xy 85.218016 -432.637184) (xy 85.205932 -432.636773)
			(xy 85.182946 -432.629307) (xy 85.163393 -432.615101) (xy 85.149189 -432.595547) (xy 85.141726 -432.57256)
			(xy 85.141308 -432.560476) (xy 84.207119 -432.560476) (xy 84.212399 -432.564313) (xy 84.226593 -432.583852)
			(xy 84.234055 -432.606821) (xy 84.234528 -432.618896) (xy 84.234528 -435.16042) (xy 84.234053 -435.172494)
			(xy 84.226587 -435.195458) (xy 84.212393 -435.214993) (xy 84.192858 -435.229187) (xy 84.169894 -435.236653)
			(xy 84.15782 -435.237128) (xy 83.21802 -435.237128) (xy 83.205948 -435.236619) (xy 83.182985 -435.229165)
			(xy 83.16345 -435.214979) (xy 83.149254 -435.195451) (xy 83.141787 -435.172491) (xy 83.141312 -435.16042)
			(xy 82.234532 -435.16042) (xy 82.234532 -436.160418) (xy 82.234108 -436.172511) (xy 82.226643 -436.195517)
			(xy 82.212446 -436.215099) (xy 82.192902 -436.229348) (xy 82.169916 -436.236875) (xy 82.157824 -436.23738)
			(xy 81.218024 -436.23738) (xy 81.205914 -436.236963) (xy 81.182885 -436.229468) (xy 81.163309 -436.215207)
			(xy 81.149115 -436.195584) (xy 81.141697 -436.172529) (xy 81.141316 -436.160418) (xy 80.206779 -436.160418)
			(xy 80.212406 -436.164508) (xy 80.2266 -436.184048) (xy 80.234063 -436.207017) (xy 80.234536 -436.219092)
			(xy 80.234536 -438.760616) (xy 80.23405 -438.772689) (xy 80.226586 -438.795651) (xy 80.212394 -438.815186)
			(xy 80.192862 -438.829381) (xy 80.169901 -438.836848) (xy 80.157828 -438.837324) (xy 79.218028 -438.837324)
			(xy 79.205948 -438.836864) (xy 79.182969 -438.829406) (xy 79.16342 -438.815211) (xy 79.149214 -438.79567)
			(xy 79.141743 -438.772695) (xy 79.14132 -438.760616) (xy 78.23454 -438.760616) (xy 78.23454 -439.760614)
			(xy 81.141316 -439.760614) (xy 81.141316 -437.21909) (xy 81.141799 -437.207002) (xy 81.149255 -437.184006)
			(xy 81.163439 -437.164428) (xy 81.182967 -437.150177) (xy 81.205938 -437.142641) (xy 81.218024 -437.142128)
			(xy 82.157824 -437.142128) (xy 82.169937 -437.142496) (xy 82.19297 -437.150006) (xy 82.212545 -437.164279)
			(xy 82.226738 -437.183912) (xy 82.234153 -437.206975) (xy 82.234532 -437.21909) (xy 82.234532 -438.760616)
			(xy 83.141312 -438.760616) (xy 83.141312 -436.219092) (xy 83.141706 -436.207007) (xy 83.149178 -436.18402)
			(xy 83.163388 -436.164469) (xy 83.182946 -436.150265) (xy 83.205935 -436.142802) (xy 83.21802 -436.142384)
			(xy 84.15782 -436.142384) (xy 84.169895 -436.142847) (xy 84.192861 -436.150314) (xy 84.206765 -436.160418)
			(xy 85.141308 -436.160418) (xy 85.141308 -433.618894) (xy 85.141802 -433.606807) (xy 85.149256 -433.583812)
			(xy 85.163437 -433.564235) (xy 85.182963 -433.549984) (xy 85.205931 -433.542446) (xy 85.218016 -433.541932)
			(xy 86.157816 -433.541932) (xy 86.169929 -433.542303) (xy 86.192962 -433.549811) (xy 86.212538 -433.564083)
			(xy 86.226731 -433.583716) (xy 86.234145 -433.606779) (xy 86.234524 -433.618894) (xy 86.234524 -435.16042)
			(xy 87.141304 -435.16042) (xy 87.141304 -432.618896) (xy 87.141709 -432.606812) (xy 87.149179 -432.583827)
			(xy 87.163387 -432.564276) (xy 87.182941 -432.550072) (xy 87.205928 -432.542607) (xy 87.218012 -432.542188)
			(xy 88.157812 -432.542188) (xy 88.169887 -432.542654) (xy 88.192854 -432.550119) (xy 88.207106 -432.560476)
			(xy 89.1413 -432.560476) (xy 89.1413 -430.018952) (xy 89.141723 -430.006874) (xy 89.1492 -429.983904)
			(xy 89.163407 -429.964367) (xy 89.182954 -429.950174) (xy 89.20593 -429.942714) (xy 89.218008 -429.942244)
			(xy 90.157808 -429.942244) (xy 90.169878 -429.942757) (xy 90.192837 -429.950216) (xy 90.21237 -429.964401)
			(xy 90.226566 -429.983927) (xy 90.234037 -430.006882) (xy 90.234516 -430.018952) (xy 90.234516 -432.560476)
			(xy 90.234067 -432.572557) (xy 90.226607 -432.595537) (xy 90.21241 -432.615087) (xy 90.192866 -432.629292)
			(xy 90.169888 -432.636762) (xy 90.157808 -432.637184) (xy 89.218008 -432.637184) (xy 89.205923 -432.63678)
			(xy 89.182937 -432.629312) (xy 89.163384 -432.615105) (xy 89.149181 -432.595549) (xy 89.141717 -432.572561)
			(xy 89.1413 -432.560476) (xy 88.207106 -432.560476) (xy 88.21239 -432.564316) (xy 88.226584 -432.583854)
			(xy 88.234047 -432.606821) (xy 88.23452 -432.618896) (xy 88.23452 -435.16042) (xy 88.234053 -435.172494)
			(xy 88.226586 -435.19546) (xy 88.21239 -435.214996) (xy 88.192853 -435.22919) (xy 88.169886 -435.236654)
			(xy 88.157812 -435.237128) (xy 87.218012 -435.237128) (xy 87.20594 -435.236626) (xy 87.182977 -435.229169)
			(xy 87.163441 -435.214982) (xy 87.149246 -435.195452) (xy 87.141779 -435.172492) (xy 87.141304 -435.16042)
			(xy 86.234524 -435.16042) (xy 86.234524 -436.160418) (xy 86.234107 -436.172512) (xy 86.226641 -436.195519)
			(xy 86.212443 -436.215102) (xy 86.192897 -436.229351) (xy 86.169909 -436.236876) (xy 86.157816 -436.23738)
			(xy 85.218016 -436.23738) (xy 85.205906 -436.23697) (xy 85.182876 -436.229472) (xy 85.163301 -436.21521)
			(xy 85.149106 -436.195585) (xy 85.141689 -436.172529) (xy 85.141308 -436.160418) (xy 84.206765 -436.160418)
			(xy 84.212397 -436.164511) (xy 84.226591 -436.18405) (xy 84.234055 -436.207017) (xy 84.234528 -436.219092)
			(xy 84.234528 -438.760616) (xy 84.23405 -438.772689) (xy 84.226585 -438.795654) (xy 84.212391 -438.815189)
			(xy 84.192857 -438.829383) (xy 84.169893 -438.836849) (xy 84.15782 -438.837324) (xy 83.21802 -438.837324)
			(xy 83.20594 -438.83687) (xy 83.182961 -438.82941) (xy 83.163411 -438.815214) (xy 83.149206 -438.795672)
			(xy 83.141735 -438.772696) (xy 83.141312 -438.760616) (xy 82.234532 -438.760616) (xy 82.234532 -439.760614)
			(xy 85.141308 -439.760614) (xy 85.141308 -437.21909) (xy 85.141798 -437.207003) (xy 85.149254 -437.184008)
			(xy 85.163436 -437.164431) (xy 85.182962 -437.150179) (xy 85.205931 -437.142642) (xy 85.218016 -437.142128)
			(xy 86.157816 -437.142128) (xy 86.169929 -437.142503) (xy 86.192961 -437.15001) (xy 86.212536 -437.164281)
			(xy 86.226729 -437.183914) (xy 86.234145 -437.206976) (xy 86.234524 -437.21909) (xy 86.234524 -438.760616)
			(xy 87.141304 -438.760616) (xy 87.141304 -436.219092) (xy 87.141706 -436.207008) (xy 87.149177 -436.184023)
			(xy 87.163386 -436.164471) (xy 87.182941 -436.150268) (xy 87.205928 -436.142803) (xy 87.218012 -436.142384)
			(xy 88.157812 -436.142384) (xy 88.169886 -436.142854) (xy 88.192853 -436.150319) (xy 88.206752 -436.160418)
			(xy 89.1413 -436.160418) (xy 89.1413 -433.618894) (xy 89.141802 -433.606808) (xy 89.149255 -433.583814)
			(xy 89.163434 -433.564238) (xy 89.182958 -433.549986) (xy 89.205924 -433.542447) (xy 89.218008 -433.541932)
			(xy 90.157808 -433.541932) (xy 90.169921 -433.54231) (xy 90.192954 -433.549815) (xy 90.212529 -433.564086)
			(xy 90.226723 -433.583717) (xy 90.234137 -433.60678) (xy 90.234516 -433.618894) (xy 90.234516 -436.160418)
			(xy 90.234107 -436.172513) (xy 90.22664 -436.195522) (xy 90.21244 -436.215105) (xy 90.192892 -436.229353)
			(xy 90.169902 -436.236877) (xy 90.157808 -436.23738) (xy 89.218008 -436.23738) (xy 89.205898 -436.236977)
			(xy 89.182867 -436.229477) (xy 89.163292 -436.215213) (xy 89.149098 -436.195587) (xy 89.14168 -436.17253)
			(xy 89.1413 -436.160418) (xy 88.206752 -436.160418) (xy 88.212389 -436.164514) (xy 88.226583 -436.184051)
			(xy 88.234047 -436.207018) (xy 88.23452 -436.219092) (xy 88.23452 -438.760616) (xy 88.234049 -438.77269)
			(xy 88.226584 -438.795656) (xy 88.212389 -438.815191) (xy 88.192852 -438.829386) (xy 88.169886 -438.83685)
			(xy 88.157812 -438.837324) (xy 87.218012 -438.837324) (xy 87.20594 -438.836826) (xy 87.182976 -438.829369)
			(xy 87.16344 -438.81518) (xy 87.149244 -438.79565) (xy 87.141779 -438.772688) (xy 87.141304 -438.760616)
			(xy 86.234524 -438.760616) (xy 86.234524 -439.760614) (xy 89.1413 -439.760614) (xy 89.1413 -437.21909)
			(xy 89.141798 -437.207004) (xy 89.149253 -437.18401) (xy 89.163433 -437.164434) (xy 89.182957 -437.150182)
			(xy 89.205924 -437.142643) (xy 89.218008 -437.142128) (xy 90.157808 -437.142128) (xy 90.16992 -437.14251)
			(xy 90.192952 -437.150015) (xy 90.212528 -437.164284) (xy 90.226721 -437.183915) (xy 90.234137 -437.206976)
			(xy 90.234516 -437.21909) (xy 90.234516 -439.760614) (xy 90.234104 -439.772709) (xy 90.226638 -439.795717)
			(xy 90.212439 -439.815301) (xy 90.192891 -439.829549) (xy 90.169901 -439.837073) (xy 90.157808 -439.837576)
			(xy 89.218008 -439.837576) (xy 89.205897 -439.837177) (xy 89.182866 -439.829677) (xy 89.163291 -439.815412)
			(xy 89.149096 -439.795785) (xy 89.14168 -439.772726) (xy 89.1413 -439.760614) (xy 86.234524 -439.760614)
			(xy 86.234104 -439.772708) (xy 86.226639 -439.795715) (xy 86.212442 -439.815298) (xy 86.192896 -439.829547)
			(xy 86.169909 -439.837072) (xy 86.157816 -439.837576) (xy 85.218016 -439.837576) (xy 85.205906 -439.83717)
			(xy 85.182875 -439.829672) (xy 85.163299 -439.815408) (xy 85.149105 -439.795783) (xy 85.141688 -439.772726)
			(xy 85.141308 -439.760614) (xy 82.234532 -439.760614) (xy 82.234104 -439.772707) (xy 82.22664 -439.795713)
			(xy 82.212445 -439.815295) (xy 82.192901 -439.829544) (xy 82.169916 -439.837071) (xy 82.157824 -439.837576)
			(xy 81.218024 -439.837576) (xy 81.205914 -439.837163) (xy 81.182883 -439.829667) (xy 81.163308 -439.815406)
			(xy 81.149113 -439.795781) (xy 81.141696 -439.772725) (xy 81.141316 -439.760614) (xy 78.23454 -439.760614)
			(xy 78.234104 -439.772706) (xy 78.226641 -439.795711) (xy 78.212447 -439.815292) (xy 78.192906 -439.829542)
			(xy 78.169923 -439.83707) (xy 78.157832 -439.837576) (xy 77.218032 -439.837576) (xy 77.205922 -439.837156)
			(xy 77.182892 -439.829663) (xy 77.163316 -439.815403) (xy 77.149122 -439.79578) (xy 77.141704 -439.772725)
			(xy 77.141324 -439.760614) (xy 73.234804 -439.760614) (xy 73.234301 -439.772725) (xy 73.226815 -439.795762)
			(xy 73.21258 -439.81536) (xy 73.192987 -439.829602) (xy 73.169953 -439.837097) (xy 73.157842 -439.837576)
			(xy 72.218042 -439.837576) (xy 72.205923 -439.837105) (xy 72.182868 -439.829626) (xy 72.163253 -439.815387)
			(xy 72.149 -439.795783) (xy 72.141504 -439.772733) (xy 72.14108 -439.760614) (xy 69.234812 -439.760614)
			(xy 69.234301 -439.772724) (xy 69.226816 -439.79576) (xy 69.212582 -439.815357) (xy 69.192992 -439.8296)
			(xy 69.16996 -439.837096) (xy 69.15785 -439.837576) (xy 68.21805 -439.837576) (xy 68.205934 -439.837131)
			(xy 68.182892 -439.829632) (xy 68.163292 -439.815382) (xy 68.149052 -439.795776) (xy 68.141563 -439.77273)
			(xy 68.141088 -439.760614) (xy 65.23482 -439.760614) (xy 65.234451 -439.772742) (xy 65.22695 -439.795808)
			(xy 65.212686 -439.815426) (xy 65.193058 -439.829675) (xy 65.169986 -439.83716) (xy 65.157858 -439.837576)
			(xy 64.218058 -439.837576) (xy 64.205943 -439.837124) (xy 64.1829 -439.829627) (xy 64.163301 -439.815379)
			(xy 64.14906 -439.795774) (xy 64.141571 -439.77273) (xy 64.141096 -439.760614) (xy 61.234828 -439.760614)
			(xy 61.234451 -439.772741) (xy 61.226951 -439.795806) (xy 61.212689 -439.815424) (xy 61.193063 -439.829673)
			(xy 61.169993 -439.837159) (xy 61.157866 -439.837576) (xy 60.218066 -439.837576) (xy 60.205951 -439.837118)
			(xy 60.182909 -439.829623) (xy 60.163309 -439.815377) (xy 60.149068 -439.795773) (xy 60.141579 -439.772729)
			(xy 60.141104 -439.760614) (xy 16.236871 -439.760614) (xy 16.214826 -439.778269) (xy 16.049761 -439.900231)
			(xy 15.880073 -440.015675) (xy 15.706021 -440.124426) (xy 15.527867 -440.22632) (xy 15.437104 -440.274202)
			(xy 15.43685 -440.274202) (xy 15.42709 -440.280024) (xy 15.413491 -440.298196) (xy 15.409027 -440.32045)
			(xy 15.411196 -440.331606) (xy 15.434818 -440.427364) (xy 15.438119 -440.438178) (xy 15.45241 -440.455664)
			(xy 15.472804 -440.465361) (xy 15.484094 -440.465972) (xy 58.119264 -440.465972)
		)
		(stroke
			(width 0)
			(type solid)
		)
		(fill yes)
		(layer "In8.Cu")
		(net "P12V_AUX")
	)
	(gr_line
		(start 1.414272 -79.914242)
		(end 0.585724 -79.085694)
		(stroke
			(width 3.048)
			(type default)
		)
		(layer "In8.Cu")
	)
	(gr_line
		(start 1.999996 -403.371558)
		(end 1.999996 -81.328514)
		(stroke
			(width 3.048)
			(type default)
		)
		(layer "In8.Cu")
	)
	(gr_arc
		(start 1.999996 -403.371558)
		(mid 2.152159 -404.136965)
		(end 2.58572 -404.78583)
		(stroke
			(width 3.048)
			(type default)
		)
		(layer "In8.Cu")
	)
	(gr_arc
		(start 1.999996 -81.328514)
		(mid 1.847755 -80.563149)
		(end 1.414272 -79.914242)
		(stroke
			(width 3.048)
			(type default)
		)
		(layer "In8.Cu")
	)
	(gr_arc
		(start 1.999996 -11.780012)
		(mid 0.585785 -12.365797)
		(end 0 -13.780008)
		(stroke
			(width 3.048)
			(type default)
		)
		(layer "In8.Cu")
	)
	(gr_line
		(start 1.999996 -11.780012)
		(end 11.102086 -11.780012)
		(stroke
			(width 3.048)
			(type default)
		)
		(layer "In8.Cu")
	)
	(gr_line
		(start 5.914136 -408.114246)
		(end 2.58572 -404.78583)
		(stroke
			(width 3.048)
			(type default)
		)
		(layer "In8.Cu")
	)
	(gr_line
		(start 6.500114 -439.989976)
		(end 6.500114 -409.528518)
		(stroke
			(width 3.048)
			(type default)
		)
		(layer "In8.Cu")
	)
	(gr_arc
		(start 6.500114 -439.989976)
		(mid 7.085891 -441.404199)
		(end 8.50011 -441.989972)
		(stroke
			(width 3.048)
			(type default)
		)
		(layer "In8.Cu")
	)
	(gr_arc
		(start 6.500114 -409.528518)
		(mid 6.347771 -408.763109)
		(end 5.914136 -408.114246)
		(stroke
			(width 3.048)
			(type default)
		)
		(layer "In8.Cu")
	)
	(gr_line
		(start 7.139178 -379.364494)
		(end 41.5544 -413.779716)
		(stroke
			(width 0.508)
			(type default)
		)
		(layer "In8.Cu")
	)
	(gr_line
		(start 7.139178 -374.734328)
		(end 7.139178 -379.364494)
		(stroke
			(width 0.508)
			(type default)
		)
		(layer "In8.Cu")
	)
	(gr_line
		(start 8.370824 -373.502682)
		(end 7.139178 -374.734328)
		(stroke
			(width 0.508)
			(type default)
		)
		(layer "In8.Cu")
	)
	(gr_arc
		(start 11.102086 -11.780012)
		(mid 12.516297 -11.194227)
		(end 13.102082 -9.780016)
		(stroke
			(width 3.048)
			(type default)
		)
		(layer "In8.Cu")
	)
	(gr_line
		(start 13.102082 -9.780016)
		(end 13.102082 -0.500126)
		(stroke
			(width 3.048)
			(type default)
		)
		(layer "In8.Cu")
	)
	(gr_line
		(start 13.539724 -194.497198)
		(end 13.539724 -185.935874)
		(stroke
			(width 0.508)
			(type default)
		)
		(layer "In8.Cu")
	)
	(gr_line
		(start 13.539724 -185.935874)
		(end 15.639034 -183.836564)
		(stroke
			(width 0.508)
			(type default)
		)
		(layer "In8.Cu")
	)
	(gr_arc
		(start 13.601954 0)
		(mid 13.24848 -0.146572)
		(end 13.102082 -0.500126)
		(stroke
			(width 3.048)
			(type default)
		)
		(layer "In8.Cu")
	)
	(gr_line
		(start 13.601954 0)
		(end 81.202022 0)
		(stroke
			(width 3.048)
			(type default)
		)
		(layer "In8.Cu")
	)
	(gr_line
		(start 14.673072 -195.630546)
		(end 13.539724 -194.497198)
		(stroke
			(width 0.508)
			(type default)
		)
		(layer "In8.Cu")
	)
	(gr_line
		(start 15.639034 -183.836564)
		(end 24.454104 -183.836564)
		(stroke
			(width 0.508)
			(type default)
		)
		(layer "In8.Cu")
	)
	(gr_line
		(start 23.154386 -345.445334)
		(end 23.876 -346.166948)
		(stroke
			(width 0.508)
			(type default)
		)
		(layer "In8.Cu")
	)
	(gr_line
		(start 23.154386 -334.941164)
		(end 23.154386 -345.445334)
		(stroke
			(width 0.508)
			(type default)
		)
		(layer "In8.Cu")
	)
	(gr_line
		(start 23.154386 -334.941164)
		(end 23.700486 -335.487264)
		(stroke
			(width 0.508)
			(type default)
		)
		(layer "In8.Cu")
	)
	(gr_line
		(start 23.154386 -227.143564)
		(end 23.154386 -334.941164)
		(stroke
			(width 0.508)
			(type default)
		)
		(layer "In8.Cu")
	)
	(gr_line
		(start 23.154386 -227.143564)
		(end 23.635716 -226.662234)
		(stroke
			(width 0.508)
			(type default)
		)
		(layer "In8.Cu")
	)
	(gr_line
		(start 23.635716 -226.662234)
		(end 79.817976 -226.662234)
		(stroke
			(width 0.508)
			(type default)
		)
		(layer "In8.Cu")
	)
	(gr_line
		(start 23.700486 -335.487264)
		(end 64.444626 -335.487264)
		(stroke
			(width 0.508)
			(type default)
		)
		(layer "In8.Cu")
	)
	(gr_line
		(start 23.876 -351.246948)
		(end 27.187652 -354.5586)
		(stroke
			(width 0.508)
			(type default)
		)
		(layer "In8.Cu")
	)
	(gr_line
		(start 23.876 -346.166948)
		(end 23.876 -351.246948)
		(stroke
			(width 0.508)
			(type default)
		)
		(layer "In8.Cu")
	)
	(gr_line
		(start 24.454104 -183.836564)
		(end 24.538178 -183.920638)
		(stroke
			(width 0.508)
			(type default)
		)
		(layer "In8.Cu")
	)
	(gr_line
		(start 24.538178 -183.920638)
		(end 35.28441 -173.174406)
		(stroke
			(width 0.508)
			(type default)
		)
		(layer "In8.Cu")
	)
	(gr_circle
		(center 25.82545 -40.816276)
		(end 26.71445 -40.816276)
		(stroke
			(width 0.2)
			(type default)
		)
		(fill no)
		(layer "In8.Cu")
	)
	(gr_line
		(start 27.187652 -354.5586)
		(end 79.017368 -354.5586)
		(stroke
			(width 0.508)
			(type default)
		)
		(layer "In8.Cu")
	)
	(gr_circle
		(center 29.291534 -348.709488)
		(end 30.171644 -348.709488)
		(stroke
			(width 0.2)
			(type default)
		)
		(fill no)
		(layer "In8.Cu")
	)
	(gr_circle
		(center 29.908754 -348.709488)
		(end 30.788864 -348.709488)
		(stroke
			(width 0.2)
			(type default)
		)
		(fill no)
		(layer "In8.Cu")
	)
	(gr_circle
		(center 30.525974 -348.709488)
		(end 31.406084 -348.709488)
		(stroke
			(width 0.2)
			(type default)
		)
		(fill no)
		(layer "In8.Cu")
	)
	(gr_circle
		(center 30.795214 -347.966538)
		(end 31.684214 -347.966538)
		(stroke
			(width 0.2)
			(type default)
		)
		(fill no)
		(layer "In8.Cu")
	)
	(gr_circle
		(center 30.795214 -347.229938)
		(end 31.684214 -347.229938)
		(stroke
			(width 0.2)
			(type default)
		)
		(fill no)
		(layer "In8.Cu")
	)
	(gr_circle
		(center 31.22803 -350.318578)
		(end 32.11703 -350.318578)
		(stroke
			(width 0.2)
			(type default)
		)
		(fill no)
		(layer "In8.Cu")
	)
	(gr_circle
		(center 31.22803 -349.581978)
		(end 32.11703 -349.581978)
		(stroke
			(width 0.2)
			(type default)
		)
		(fill no)
		(layer "In8.Cu")
	)
	(gr_circle
		(center 31.752794 -349.142558)
		(end 32.641794 -349.142558)
		(stroke
			(width 0.2)
			(type default)
		)
		(fill no)
		(layer "In8.Cu")
	)
	(gr_circle
		(center 31.778194 -349.904558)
		(end 32.667194 -349.904558)
		(stroke
			(width 0.2)
			(type default)
		)
		(fill no)
		(layer "In8.Cu")
	)
	(gr_circle
		(center 32.311594 -350.260158)
		(end 33.200594 -350.260158)
		(stroke
			(width 0.2)
			(type default)
		)
		(fill no)
		(layer "In8.Cu")
	)
	(gr_circle
		(center 32.311594 -349.523558)
		(end 33.200594 -349.523558)
		(stroke
			(width 0.2)
			(type default)
		)
		(fill no)
		(layer "In8.Cu")
	)
	(gr_circle
		(center 32.311594 -348.786958)
		(end 33.200594 -348.786958)
		(stroke
			(width 0.2)
			(type default)
		)
		(fill no)
		(layer "In8.Cu")
	)
	(gr_circle
		(center 35.067748 -376.49658)
		(end 37.226748 -376.49658)
		(stroke
			(width 4.318)
			(type default)
		)
		(fill no)
		(layer "In8.Cu")
	)
	(gr_line
		(start 35.28441 -173.174406)
		(end 35.28441 -153.193242)
		(stroke
			(width 0.508)
			(type default)
		)
		(layer "In8.Cu")
	)
	(gr_line
		(start 35.28441 -153.193242)
		(end 42.401236 -146.076416)
		(stroke
			(width 0.508)
			(type default)
		)
		(layer "In8.Cu")
	)
	(gr_circle
		(center 37.571934 -348.709488)
		(end 38.452044 -348.709488)
		(stroke
			(width 0.2)
			(type default)
		)
		(fill no)
		(layer "In8.Cu")
	)
	(gr_circle
		(center 38.189154 -348.709488)
		(end 39.069264 -348.709488)
		(stroke
			(width 0.2)
			(type default)
		)
		(fill no)
		(layer "In8.Cu")
	)
	(gr_circle
		(center 38.806374 -348.709488)
		(end 39.686484 -348.709488)
		(stroke
			(width 0.2)
			(type default)
		)
		(fill no)
		(layer "In8.Cu")
	)
	(gr_circle
		(center 39.050214 -347.974158)
		(end 39.939214 -347.974158)
		(stroke
			(width 0.2)
			(type default)
		)
		(fill no)
		(layer "In8.Cu")
	)
	(gr_circle
		(center 39.050214 -347.237558)
		(end 39.939214 -347.237558)
		(stroke
			(width 0.2)
			(type default)
		)
		(fill no)
		(layer "In8.Cu")
	)
	(gr_circle
		(center 39.50843 -350.318578)
		(end 40.39743 -350.318578)
		(stroke
			(width 0.2)
			(type default)
		)
		(fill no)
		(layer "In8.Cu")
	)
	(gr_circle
		(center 39.50843 -349.581978)
		(end 40.39743 -349.581978)
		(stroke
			(width 0.2)
			(type default)
		)
		(fill no)
		(layer "In8.Cu")
	)
	(gr_circle
		(center 40.033194 -349.142558)
		(end 40.922194 -349.142558)
		(stroke
			(width 0.2)
			(type default)
		)
		(fill no)
		(layer "In8.Cu")
	)
	(gr_circle
		(center 40.058594 -349.904558)
		(end 40.947594 -349.904558)
		(stroke
			(width 0.2)
			(type default)
		)
		(fill no)
		(layer "In8.Cu")
	)
	(gr_circle
		(center 40.591994 -350.260158)
		(end 41.480994 -350.260158)
		(stroke
			(width 0.2)
			(type default)
		)
		(fill no)
		(layer "In8.Cu")
	)
	(gr_circle
		(center 40.591994 -349.523558)
		(end 41.480994 -349.523558)
		(stroke
			(width 0.2)
			(type default)
		)
		(fill no)
		(layer "In8.Cu")
	)
	(gr_circle
		(center 40.591994 -348.786958)
		(end 41.480994 -348.786958)
		(stroke
			(width 0.2)
			(type default)
		)
		(fill no)
		(layer "In8.Cu")
	)
	(gr_line
		(start 40.740838 -195.630546)
		(end 14.673072 -195.630546)
		(stroke
			(width 0.508)
			(type default)
		)
		(layer "In8.Cu")
	)
	(gr_line
		(start 40.807386 -226.662234)
		(end 40.807386 -180.71592)
		(stroke
			(width 0.508)
			(type default)
		)
		(layer "In8.Cu")
	)
	(gr_line
		(start 40.807386 -180.71592)
		(end 45.202094 -176.321212)
		(stroke
			(width 0.508)
			(type default)
		)
		(layer "In8.Cu")
	)
	(gr_circle
		(center 41.369742 -358.549194)
		(end 42.258742 -358.549194)
		(stroke
			(width 0.2)
			(type default)
		)
		(fill no)
		(layer "In8.Cu")
	)
	(gr_circle
		(center 41.417494 -357.898192)
		(end 42.306494 -357.898192)
		(stroke
			(width 0.2)
			(type default)
		)
		(fill no)
		(layer "In8.Cu")
	)
	(gr_circle
		(center 41.417494 -357.263192)
		(end 42.306494 -357.263192)
		(stroke
			(width 0.2)
			(type default)
		)
		(fill no)
		(layer "In8.Cu")
	)
	(gr_circle
		(center 41.427146 -359.2576)
		(end 42.316146 -359.2576)
		(stroke
			(width 0.2)
			(type default)
		)
		(fill no)
		(layer "In8.Cu")
	)
	(gr_line
		(start 41.5544 -413.779716)
		(end 163.546282 -413.779716)
		(stroke
			(width 0.508)
			(type default)
		)
		(layer "In8.Cu")
	)
	(gr_circle
		(center 41.567862 -404.792688)
		(end 43.726862 -404.792688)
		(stroke
			(width 4.318)
			(type default)
		)
		(fill no)
		(layer "In8.Cu")
	)
	(gr_line
		(start 42.401236 -146.076416)
		(end 59.946032 -146.076416)
		(stroke
			(width 0.508)
			(type default)
		)
		(layer "In8.Cu")
	)
	(gr_circle
		(center 43.935904 -358.51084)
		(end 44.824904 -358.51084)
		(stroke
			(width 0.2)
			(type default)
		)
		(fill no)
		(layer "In8.Cu")
	)
	(gr_circle
		(center 43.983656 -357.859838)
		(end 44.872656 -357.859838)
		(stroke
			(width 0.2)
			(type default)
		)
		(fill no)
		(layer "In8.Cu")
	)
	(gr_circle
		(center 43.983656 -357.224838)
		(end 44.872656 -357.224838)
		(stroke
			(width 0.2)
			(type default)
		)
		(fill no)
		(layer "In8.Cu")
	)
	(gr_circle
		(center 43.993308 -359.219246)
		(end 44.882308 -359.219246)
		(stroke
			(width 0.2)
			(type default)
		)
		(fill no)
		(layer "In8.Cu")
	)
	(gr_line
		(start 44.264834 -172.488352)
		(end 44.264834 -156.714952)
		(stroke
			(width 0.508)
			(type default)
		)
		(layer "In8.Cu")
	)
	(gr_line
		(start 44.264834 -156.714952)
		(end 47.569374 -153.410412)
		(stroke
			(width 0.508)
			(type default)
		)
		(layer "In8.Cu")
	)
	(gr_line
		(start 45.202094 -176.321212)
		(end 45.202094 -173.425612)
		(stroke
			(width 0.508)
			(type default)
		)
		(layer "In8.Cu")
	)
	(gr_line
		(start 45.202094 -173.425612)
		(end 44.264834 -172.488352)
		(stroke
			(width 0.508)
			(type default)
		)
		(layer "In8.Cu")
	)
	(gr_circle
		(center 45.877734 -348.709488)
		(end 46.757844 -348.709488)
		(stroke
			(width 0.2)
			(type default)
		)
		(fill no)
		(layer "In8.Cu")
	)
	(gr_circle
		(center 46.494954 -348.709488)
		(end 47.375064 -348.709488)
		(stroke
			(width 0.2)
			(type default)
		)
		(fill no)
		(layer "In8.Cu")
	)
	(gr_circle
		(center 47.112174 -348.709488)
		(end 47.992284 -348.709488)
		(stroke
			(width 0.2)
			(type default)
		)
		(fill no)
		(layer "In8.Cu")
	)
	(gr_circle
		(center 47.366174 -348.017338)
		(end 48.255174 -348.017338)
		(stroke
			(width 0.2)
			(type default)
		)
		(fill no)
		(layer "In8.Cu")
	)
	(gr_circle
		(center 47.366174 -347.280738)
		(end 48.255174 -347.280738)
		(stroke
			(width 0.2)
			(type default)
		)
		(fill no)
		(layer "In8.Cu")
	)
	(gr_line
		(start 47.569374 -153.410412)
		(end 58.044334 -153.410412)
		(stroke
			(width 0.508)
			(type default)
		)
		(layer "In8.Cu")
	)
	(gr_circle
		(center 47.81423 -350.318578)
		(end 48.70323 -350.318578)
		(stroke
			(width 0.2)
			(type default)
		)
		(fill no)
		(layer "In8.Cu")
	)
	(gr_circle
		(center 47.81423 -349.581978)
		(end 48.70323 -349.581978)
		(stroke
			(width 0.2)
			(type default)
		)
		(fill no)
		(layer "In8.Cu")
	)
	(gr_circle
		(center 47.880778 -358.108504)
		(end 48.769778 -358.108504)
		(stroke
			(width 0.2)
			(type default)
		)
		(fill no)
		(layer "In8.Cu")
	)
	(gr_circle
		(center 47.92853 -357.457502)
		(end 48.81753 -357.457502)
		(stroke
			(width 0.2)
			(type default)
		)
		(fill no)
		(layer "In8.Cu")
	)
	(gr_circle
		(center 47.92853 -356.822502)
		(end 48.81753 -356.822502)
		(stroke
			(width 0.2)
			(type default)
		)
		(fill no)
		(layer "In8.Cu")
	)
	(gr_circle
		(center 48.338994 -349.142558)
		(end 49.227994 -349.142558)
		(stroke
			(width 0.2)
			(type default)
		)
		(fill no)
		(layer "In8.Cu")
	)
	(gr_circle
		(center 48.364394 -349.904558)
		(end 49.253394 -349.904558)
		(stroke
			(width 0.2)
			(type default)
		)
		(fill no)
		(layer "In8.Cu")
	)
	(gr_circle
		(center 48.718978 -358.108504)
		(end 49.607978 -358.108504)
		(stroke
			(width 0.2)
			(type default)
		)
		(fill no)
		(layer "In8.Cu")
	)
	(gr_circle
		(center 48.76673 -357.457502)
		(end 49.65573 -357.457502)
		(stroke
			(width 0.2)
			(type default)
		)
		(fill no)
		(layer "In8.Cu")
	)
	(gr_circle
		(center 48.76673 -356.822502)
		(end 49.65573 -356.822502)
		(stroke
			(width 0.2)
			(type default)
		)
		(fill no)
		(layer "In8.Cu")
	)
	(gr_circle
		(center 48.897794 -350.260158)
		(end 49.786794 -350.260158)
		(stroke
			(width 0.2)
			(type default)
		)
		(fill no)
		(layer "In8.Cu")
	)
	(gr_circle
		(center 48.897794 -349.523558)
		(end 49.786794 -349.523558)
		(stroke
			(width 0.2)
			(type default)
		)
		(fill no)
		(layer "In8.Cu")
	)
	(gr_circle
		(center 48.897794 -348.786958)
		(end 49.786794 -348.786958)
		(stroke
			(width 0.2)
			(type default)
		)
		(fill no)
		(layer "In8.Cu")
	)
	(gr_circle
		(center 49.353978 -358.108504)
		(end 50.242978 -358.108504)
		(stroke
			(width 0.2)
			(type default)
		)
		(fill no)
		(layer "In8.Cu")
	)
	(gr_circle
		(center 49.40173 -357.457502)
		(end 50.29073 -357.457502)
		(stroke
			(width 0.2)
			(type default)
		)
		(fill no)
		(layer "In8.Cu")
	)
	(gr_circle
		(center 49.40173 -356.822502)
		(end 50.29073 -356.822502)
		(stroke
			(width 0.2)
			(type default)
		)
		(fill no)
		(layer "In8.Cu")
	)
	(gr_circle
		(center 49.988978 -358.108504)
		(end 50.877978 -358.108504)
		(stroke
			(width 0.2)
			(type default)
		)
		(fill no)
		(layer "In8.Cu")
	)
	(gr_circle
		(center 50.03673 -357.457502)
		(end 50.92573 -357.457502)
		(stroke
			(width 0.2)
			(type default)
		)
		(fill no)
		(layer "In8.Cu")
	)
	(gr_circle
		(center 50.03673 -356.822502)
		(end 50.92573 -356.822502)
		(stroke
			(width 0.2)
			(type default)
		)
		(fill no)
		(layer "In8.Cu")
	)
	(gr_circle
		(center 50.623978 -358.108504)
		(end 51.512978 -358.108504)
		(stroke
			(width 0.2)
			(type default)
		)
		(fill no)
		(layer "In8.Cu")
	)
	(gr_circle
		(center 50.67173 -357.457502)
		(end 51.56073 -357.457502)
		(stroke
			(width 0.2)
			(type default)
		)
		(fill no)
		(layer "In8.Cu")
	)
	(gr_circle
		(center 50.67173 -356.822502)
		(end 51.56073 -356.822502)
		(stroke
			(width 0.2)
			(type default)
		)
		(fill no)
		(layer "In8.Cu")
	)
	(gr_line
		(start 52.089812 -373.502682)
		(end 8.370824 -373.502682)
		(stroke
			(width 0.508)
			(type default)
		)
		(layer "In8.Cu")
	)
	(gr_line
		(start 54.101238 -387.902196)
		(end 54.101238 -384.033776)
		(stroke
			(width 0.508)
			(type default)
		)
		(layer "In8.Cu")
	)
	(gr_line
		(start 54.101238 -384.033776)
		(end 54.439566 -383.695448)
		(stroke
			(width 0.508)
			(type default)
		)
		(layer "In8.Cu")
	)
	(gr_circle
		(center 54.234334 -348.709488)
		(end 55.114444 -348.709488)
		(stroke
			(width 0.2)
			(type default)
		)
		(fill no)
		(layer "In8.Cu")
	)
	(gr_line
		(start 54.439566 -383.695448)
		(end 54.439566 -375.852436)
		(stroke
			(width 0.508)
			(type default)
		)
		(layer "In8.Cu")
	)
	(gr_line
		(start 54.439566 -375.852436)
		(end 52.089812 -373.502682)
		(stroke
			(width 0.508)
			(type default)
		)
		(layer "In8.Cu")
	)
	(gr_line
		(start 54.548024 -383.649728)
		(end 54.720236 -383.477516)
		(stroke
			(width 0.508)
			(type default)
		)
		(layer "In8.Cu")
	)
	(gr_line
		(start 54.548278 -388.349236)
		(end 54.101238 -387.902196)
		(stroke
			(width 0.508)
			(type default)
		)
		(layer "In8.Cu")
	)
	(gr_line
		(start 54.720236 -383.477516)
		(end 69.589396 -383.477516)
		(stroke
			(width 0.508)
			(type default)
		)
		(layer "In8.Cu")
	)
	(gr_circle
		(center 54.851554 -348.709488)
		(end 55.731664 -348.709488)
		(stroke
			(width 0.2)
			(type default)
		)
		(fill no)
		(layer "In8.Cu")
	)
	(gr_circle
		(center 55.468774 -348.709488)
		(end 56.348884 -348.709488)
		(stroke
			(width 0.2)
			(type default)
		)
		(fill no)
		(layer "In8.Cu")
	)
	(gr_circle
		(center 55.727854 -347.997018)
		(end 56.616854 -347.997018)
		(stroke
			(width 0.2)
			(type default)
		)
		(fill no)
		(layer "In8.Cu")
	)
	(gr_circle
		(center 55.727854 -347.260418)
		(end 56.616854 -347.260418)
		(stroke
			(width 0.2)
			(type default)
		)
		(fill no)
		(layer "In8.Cu")
	)
	(gr_circle
		(center 56.17083 -350.318578)
		(end 57.05983 -350.318578)
		(stroke
			(width 0.2)
			(type default)
		)
		(fill no)
		(layer "In8.Cu")
	)
	(gr_circle
		(center 56.17083 -349.581978)
		(end 57.05983 -349.581978)
		(stroke
			(width 0.2)
			(type default)
		)
		(fill no)
		(layer "In8.Cu")
	)
	(gr_line
		(start 56.230266 -335.487264)
		(end 56.809386 -334.908144)
		(stroke
			(width 0.508)
			(type default)
		)
		(layer "In8.Cu")
	)
	(gr_line
		(start 56.593486 -335.487264)
		(end 56.499506 -335.487264)
		(stroke
			(width 0.508)
			(type default)
		)
		(layer "In8.Cu")
	)
	(gr_circle
		(center 56.695594 -349.142558)
		(end 57.584594 -349.142558)
		(stroke
			(width 0.2)
			(type default)
		)
		(fill no)
		(layer "In8.Cu")
	)
	(gr_circle
		(center 56.720994 -349.904558)
		(end 57.609994 -349.904558)
		(stroke
			(width 0.2)
			(type default)
		)
		(fill no)
		(layer "In8.Cu")
	)
	(gr_line
		(start 56.809386 -334.908144)
		(end 56.809386 -308.169564)
		(stroke
			(width 0.508)
			(type default)
		)
		(layer "In8.Cu")
	)
	(gr_line
		(start 56.809386 -308.169564)
		(end 69.02069 -295.95826)
		(stroke
			(width 0.508)
			(type default)
		)
		(layer "In8.Cu")
	)
	(gr_line
		(start 57.237122 -388.349236)
		(end 54.548278 -388.349236)
		(stroke
			(width 0.508)
			(type default)
		)
		(layer "In8.Cu")
	)
	(gr_circle
		(center 57.254394 -350.260158)
		(end 58.143394 -350.260158)
		(stroke
			(width 0.2)
			(type default)
		)
		(fill no)
		(layer "In8.Cu")
	)
	(gr_circle
		(center 57.254394 -349.523558)
		(end 58.143394 -349.523558)
		(stroke
			(width 0.2)
			(type default)
		)
		(fill no)
		(layer "In8.Cu")
	)
	(gr_circle
		(center 57.254394 -348.786958)
		(end 58.143394 -348.786958)
		(stroke
			(width 0.2)
			(type default)
		)
		(fill no)
		(layer "In8.Cu")
	)
	(gr_line
		(start 57.388506 -335.487264)
		(end 56.809386 -334.908144)
		(stroke
			(width 0.508)
			(type default)
		)
		(layer "In8.Cu")
	)
	(gr_line
		(start 57.404 -90.769948)
		(end 57.404 -30.190948)
		(stroke
			(width 0.508)
			(type default)
		)
		(layer "In8.Cu")
	)
	(gr_line
		(start 57.404 -30.190948)
		(end 59.944 -27.650948)
		(stroke
			(width 0.508)
			(type default)
		)
		(layer "In8.Cu")
	)
	(gr_line
		(start 58.044334 -153.410412)
		(end 58.051954 -153.402792)
		(stroke
			(width 0.508)
			(type default)
		)
		(layer "In8.Cu")
	)
	(gr_line
		(start 58.051954 -153.402792)
		(end 58.940954 -153.402792)
		(stroke
			(width 0.508)
			(type default)
		)
		(layer "In8.Cu")
	)
	(gr_line
		(start 58.940954 -153.402792)
		(end 60.12688 -154.588718)
		(stroke
			(width 0.508)
			(type default)
		)
		(layer "In8.Cu")
	)
	(gr_line
		(start 59.064144 -386.522214)
		(end 57.237122 -388.349236)
		(stroke
			(width 0.508)
			(type default)
		)
		(layer "In8.Cu")
	)
	(gr_line
		(start 59.76493 -386.522214)
		(end 59.064144 -386.522214)
		(stroke
			(width 0.508)
			(type default)
		)
		(layer "In8.Cu")
	)
	(gr_line
		(start 59.944 -27.650948)
		(end 64.135 -27.650948)
		(stroke
			(width 0.508)
			(type default)
		)
		(layer "In8.Cu")
	)
	(gr_line
		(start 59.946032 -146.076416)
		(end 66.872104 -153.002488)
		(stroke
			(width 0.508)
			(type default)
		)
		(layer "In8.Cu")
	)
	(gr_line
		(start 60.12688 -154.588718)
		(end 60.12688 -202.648058)
		(stroke
			(width 0.508)
			(type default)
		)
		(layer "In8.Cu")
	)
	(gr_line
		(start 60.134246 -179.541424)
		(end 60.492386 -179.899564)
		(stroke
			(width 0.508)
			(type default)
		)
		(layer "In8.Cu")
	)
	(gr_line
		(start 60.492386 -179.899564)
		(end 60.129166 -180.262784)
		(stroke
			(width 0.508)
			(type default)
		)
		(layer "In8.Cu")
	)
	(gr_line
		(start 60.617354 -162.19551)
		(end 60.197492 -162.615372)
		(stroke
			(width 0.508)
			(type default)
		)
		(layer "In8.Cu")
	)
	(gr_line
		(start 60.617354 -162.19551)
		(end 60.617354 -162.11169)
		(stroke
			(width 0.508)
			(type default)
		)
		(layer "In8.Cu")
	)
	(gr_line
		(start 60.617354 -162.11169)
		(end 60.155582 -161.649918)
		(stroke
			(width 0.508)
			(type default)
		)
		(layer "In8.Cu")
	)
	(gr_line
		(start 61.12129 -387.878574)
		(end 59.76493 -386.522214)
		(stroke
			(width 0.508)
			(type default)
		)
		(layer "In8.Cu")
	)
	(gr_circle
		(center 61.93663 -166.86276)
		(end 62.82563 -166.86276)
		(stroke
			(width 0.2)
			(type default)
		)
		(fill no)
		(layer "In8.Cu")
	)
	(gr_circle
		(center 61.93663 -166.12616)
		(end 62.82563 -166.12616)
		(stroke
			(width 0.2)
			(type default)
		)
		(fill no)
		(layer "In8.Cu")
	)
	(gr_circle
		(center 61.93663 -165.38956)
		(end 62.82563 -165.38956)
		(stroke
			(width 0.2)
			(type default)
		)
		(fill no)
		(layer "In8.Cu")
	)
	(gr_circle
		(center 62.47003 -165.74516)
		(end 63.35903 -165.74516)
		(stroke
			(width 0.2)
			(type default)
		)
		(fill no)
		(layer "In8.Cu")
	)
	(gr_circle
		(center 62.49543 -166.50716)
		(end 63.38443 -166.50716)
		(stroke
			(width 0.2)
			(type default)
		)
		(fill no)
		(layer "In8.Cu")
	)
	(gr_circle
		(center 62.565534 -348.709488)
		(end 63.445644 -348.709488)
		(stroke
			(width 0.2)
			(type default)
		)
		(fill no)
		(layer "In8.Cu")
	)
	(gr_line
		(start 62.738 -96.103948)
		(end 57.404 -90.769948)
		(stroke
			(width 0.508)
			(type default)
		)
		(layer "In8.Cu")
	)
	(gr_circle
		(center 63.020194 -166.06774)
		(end 63.909194 -166.06774)
		(stroke
			(width 0.2)
			(type default)
		)
		(fill no)
		(layer "In8.Cu")
	)
	(gr_circle
		(center 63.020194 -165.33114)
		(end 63.909194 -165.33114)
		(stroke
			(width 0.2)
			(type default)
		)
		(fill no)
		(layer "In8.Cu")
	)
	(gr_circle
		(center 63.182754 -348.709488)
		(end 64.062864 -348.709488)
		(stroke
			(width 0.2)
			(type default)
		)
		(fill no)
		(layer "In8.Cu")
	)
	(gr_circle
		(center 63.199264 -12.43711)
		(end 64.088264 -12.43711)
		(stroke
			(width 0.2)
			(type default)
		)
		(fill no)
		(layer "In8.Cu")
	)
	(gr_circle
		(center 63.579248 -168.42232)
		(end 64.468248 -168.42232)
		(stroke
			(width 0.2)
			(type default)
		)
		(fill no)
		(layer "In8.Cu")
	)
	(gr_circle
		(center 63.579248 -167.68572)
		(end 64.468248 -167.68572)
		(stroke
			(width 0.2)
			(type default)
		)
		(fill no)
		(layer "In8.Cu")
	)
	(gr_circle
		(center 63.631064 -13.09751)
		(end 64.520064 -13.09751)
		(stroke
			(width 0.2)
			(type default)
		)
		(fill no)
		(layer "In8.Cu")
	)
	(gr_circle
		(center 63.72225 -166.94023)
		(end 64.60236 -166.94023)
		(stroke
			(width 0.2)
			(type default)
		)
		(fill no)
		(layer "In8.Cu")
	)
	(gr_circle
		(center 63.799974 -348.709488)
		(end 64.680084 -348.709488)
		(stroke
			(width 0.2)
			(type default)
		)
		(fill no)
		(layer "In8.Cu")
	)
	(gr_circle
		(center 64.061594 -348.038928)
		(end 64.941704 -348.038928)
		(stroke
			(width 0.2)
			(type default)
		)
		(fill no)
		(layer "In8.Cu")
	)
	(gr_circle
		(center 64.061594 -347.302328)
		(end 64.941704 -347.302328)
		(stroke
			(width 0.2)
			(type default)
		)
		(fill no)
		(layer "In8.Cu")
	)
	(gr_circle
		(center 64.088264 -12.43711)
		(end 64.977264 -12.43711)
		(stroke
			(width 0.2)
			(type default)
		)
		(fill no)
		(layer "In8.Cu")
	)
	(gr_line
		(start 64.135 -27.650948)
		(end 66.421 -29.936948)
		(stroke
			(width 0.508)
			(type default)
		)
		(layer "In8.Cu")
	)
	(gr_circle
		(center 64.33947 -166.94023)
		(end 65.21958 -166.94023)
		(stroke
			(width 0.2)
			(type default)
		)
		(fill no)
		(layer "In8.Cu")
	)
	(gr_line
		(start 64.444626 -335.487264)
		(end 64.9478 -334.98409)
		(stroke
			(width 0.508)
			(type default)
		)
		(layer "In8.Cu")
	)
	(gr_circle
		(center 64.50203 -350.318578)
		(end 65.39103 -350.318578)
		(stroke
			(width 0.2)
			(type default)
		)
		(fill no)
		(layer "In8.Cu")
	)
	(gr_circle
		(center 64.50203 -349.581978)
		(end 65.39103 -349.581978)
		(stroke
			(width 0.2)
			(type default)
		)
		(fill no)
		(layer "In8.Cu")
	)
	(gr_circle
		(center 64.520064 -13.09751)
		(end 65.409064 -13.09751)
		(stroke
			(width 0.2)
			(type default)
		)
		(fill no)
		(layer "In8.Cu")
	)
	(gr_line
		(start 64.9478 -330.38415)
		(end 64.9478 -334.98409)
		(stroke
			(width 0.508)
			(type default)
		)
		(layer "In8.Cu")
	)
	(gr_line
		(start 64.9478 -330.38415)
		(end 65.699386 -329.632564)
		(stroke
			(width 0.508)
			(type default)
		)
		(layer "In8.Cu")
	)
	(gr_circle
		(center 64.95669 -166.94023)
		(end 65.8368 -166.94023)
		(stroke
			(width 0.2)
			(type default)
		)
		(fill no)
		(layer "In8.Cu")
	)
	(gr_circle
		(center 64.977264 -12.43711)
		(end 65.866264 -12.43711)
		(stroke
			(width 0.2)
			(type default)
		)
		(fill no)
		(layer "In8.Cu")
	)
	(gr_circle
		(center 65.026794 -349.142558)
		(end 65.915794 -349.142558)
		(stroke
			(width 0.2)
			(type default)
		)
		(fill no)
		(layer "In8.Cu")
	)
	(gr_circle
		(center 65.052194 -349.904558)
		(end 65.941194 -349.904558)
		(stroke
			(width 0.2)
			(type default)
		)
		(fill no)
		(layer "In8.Cu")
	)
	(gr_circle
		(center 65.409064 -13.09751)
		(end 66.298064 -13.09751)
		(stroke
			(width 0.2)
			(type default)
		)
		(fill no)
		(layer "In8.Cu")
	)
	(gr_circle
		(center 65.585594 -350.260158)
		(end 66.474594 -350.260158)
		(stroke
			(width 0.2)
			(type default)
		)
		(fill no)
		(layer "In8.Cu")
	)
	(gr_circle
		(center 65.585594 -349.523558)
		(end 66.474594 -349.523558)
		(stroke
			(width 0.2)
			(type default)
		)
		(fill no)
		(layer "In8.Cu")
	)
	(gr_circle
		(center 65.585594 -348.786958)
		(end 66.474594 -348.786958)
		(stroke
			(width 0.2)
			(type default)
		)
		(fill no)
		(layer "In8.Cu")
	)
	(gr_line
		(start 65.699386 -329.632564)
		(end 70.779386 -329.632564)
		(stroke
			(width 0.508)
			(type default)
		)
		(layer "In8.Cu")
	)
	(gr_circle
		(center 65.866264 -12.43711)
		(end 66.755264 -12.43711)
		(stroke
			(width 0.2)
			(type default)
		)
		(fill no)
		(layer "In8.Cu")
	)
	(gr_circle
		(center 66.298064 -13.09751)
		(end 67.187064 -13.09751)
		(stroke
			(width 0.2)
			(type default)
		)
		(fill no)
		(layer "In8.Cu")
	)
	(gr_circle
		(center 66.399664 -25.56891)
		(end 67.288664 -25.56891)
		(stroke
			(width 0.2)
			(type default)
		)
		(fill no)
		(layer "In8.Cu")
	)
	(gr_line
		(start 66.421 -29.936948)
		(end 177.165 -29.936948)
		(stroke
			(width 0.508)
			(type default)
		)
		(layer "In8.Cu")
	)
	(gr_circle
		(center 66.501264 -12.43711)
		(end 67.390264 -12.43711)
		(stroke
			(width 0.2)
			(type default)
		)
		(fill no)
		(layer "In8.Cu")
	)
	(gr_circle
		(center 66.774822 -20.327366)
		(end 67.663822 -20.327366)
		(stroke
			(width 0.2)
			(type default)
		)
		(fill no)
		(layer "In8.Cu")
	)
	(gr_circle
		(center 66.774822 -19.692366)
		(end 67.663822 -19.692366)
		(stroke
			(width 0.2)
			(type default)
		)
		(fill no)
		(layer "In8.Cu")
	)
	(gr_circle
		(center 66.780664 -24.88311)
		(end 67.669664 -24.88311)
		(stroke
			(width 0.2)
			(type default)
		)
		(fill no)
		(layer "In8.Cu")
	)
	(gr_circle
		(center 66.848228 -18.642584)
		(end 67.737228 -18.642584)
		(stroke
			(width 0.2)
			(type default)
		)
		(fill no)
		(layer "In8.Cu")
	)
	(gr_line
		(start 66.872104 -153.002488)
		(end 76.484988 -153.002488)
		(stroke
			(width 0.508)
			(type default)
		)
		(layer "In8.Cu")
	)
	(gr_circle
		(center 66.882264 -22.26691)
		(end 67.771264 -22.26691)
		(stroke
			(width 0.2)
			(type default)
		)
		(fill no)
		(layer "In8.Cu")
	)
	(gr_circle
		(center 66.933064 -13.09751)
		(end 67.822064 -13.09751)
		(stroke
			(width 0.2)
			(type default)
		)
		(fill no)
		(layer "In8.Cu")
	)
	(gr_circle
		(center 67.288664 -25.56891)
		(end 68.177664 -25.56891)
		(stroke
			(width 0.2)
			(type default)
		)
		(fill no)
		(layer "In8.Cu")
	)
	(gr_circle
		(center 67.40271 -12.489434)
		(end 68.29171 -12.489434)
		(stroke
			(width 0.2)
			(type default)
		)
		(fill no)
		(layer "In8.Cu")
	)
	(gr_circle
		(center 67.669664 -24.88311)
		(end 68.558664 -24.88311)
		(stroke
			(width 0.2)
			(type default)
		)
		(fill no)
		(layer "In8.Cu")
	)
	(gr_line
		(start 67.985386 -179.899564)
		(end 60.492386 -179.899564)
		(stroke
			(width 0.508)
			(type default)
		)
		(layer "In8.Cu")
	)
	(gr_circle
		(center 68.177664 -25.56891)
		(end 69.066664 -25.56891)
		(stroke
			(width 0.2)
			(type default)
		)
		(fill no)
		(layer "In8.Cu")
	)
	(gr_circle
		(center 68.54444 -18.476214)
		(end 69.43344 -18.476214)
		(stroke
			(width 0.2)
			(type default)
		)
		(fill no)
		(layer "In8.Cu")
	)
	(gr_circle
		(center 68.558664 -24.88311)
		(end 69.447664 -24.88311)
		(stroke
			(width 0.2)
			(type default)
		)
		(fill no)
		(layer "In8.Cu")
	)
	(gr_line
		(start 69.02069 -295.95826)
		(end 79.177896 -295.95826)
		(stroke
			(width 0.508)
			(type default)
		)
		(layer "In8.Cu")
	)
	(gr_line
		(start 69.158358 -387.878574)
		(end 61.12129 -387.878574)
		(stroke
			(width 0.508)
			(type default)
		)
		(layer "In8.Cu")
	)
	(gr_circle
		(center 69.498464 -24.55291)
		(end 70.387464 -24.55291)
		(stroke
			(width 0.2)
			(type default)
		)
		(fill no)
		(layer "In8.Cu")
	)
	(gr_line
		(start 69.589396 -383.477516)
		(end 69.589396 -367.949226)
		(stroke
			(width 0.508)
			(type default)
		)
		(layer "In8.Cu")
	)
	(gr_line
		(start 69.589396 -383.477516)
		(end 69.93382 -383.82194)
		(stroke
			(width 0.508)
			(type default)
		)
		(layer "In8.Cu")
	)
	(gr_line
		(start 69.589396 -367.949226)
		(end 70.544436 -366.994186)
		(stroke
			(width 0.508)
			(type default)
		)
		(layer "In8.Cu")
	)
	(gr_line
		(start 69.636386 -183.985408)
		(end 69.636386 -181.550564)
		(stroke
			(width 0.508)
			(type default)
		)
		(layer "In8.Cu")
	)
	(gr_line
		(start 69.636386 -181.550564)
		(end 67.985386 -179.899564)
		(stroke
			(width 0.508)
			(type default)
		)
		(layer "In8.Cu")
	)
	(gr_line
		(start 69.75602 -387.280912)
		(end 69.158358 -387.878574)
		(stroke
			(width 0.508)
			(type default)
		)
		(layer "In8.Cu")
	)
	(gr_line
		(start 69.75602 -386.689346)
		(end 69.75602 -387.280912)
		(stroke
			(width 0.508)
			(type default)
		)
		(layer "In8.Cu")
	)
	(gr_line
		(start 69.75602 -386.320538)
		(end 69.75602 -386.689346)
		(stroke
			(width 0.254)
			(type default)
		)
		(layer "In8.Cu")
	)
	(gr_line
		(start 69.93382 -386.142738)
		(end 69.75602 -386.320538)
		(stroke
			(width 0.254)
			(type default)
		)
		(layer "In8.Cu")
	)
	(gr_line
		(start 69.93382 -384.62077)
		(end 69.93382 -386.142738)
		(stroke
			(width 0.254)
			(type default)
		)
		(layer "In8.Cu")
	)
	(gr_line
		(start 69.93382 -383.82194)
		(end 69.93382 -384.62077)
		(stroke
			(width 0.508)
			(type default)
		)
		(layer "In8.Cu")
	)
	(gr_circle
		(center 70.25005 -175.559974)
		(end 71.13905 -175.559974)
		(stroke
			(width 0.2)
			(type default)
		)
		(fill no)
		(layer "In8.Cu")
	)
	(gr_circle
		(center 70.25005 -174.823374)
		(end 71.13905 -174.823374)
		(stroke
			(width 0.2)
			(type default)
		)
		(fill no)
		(layer "In8.Cu")
	)
	(gr_circle
		(center 70.25005 -174.086774)
		(end 71.13905 -174.086774)
		(stroke
			(width 0.2)
			(type default)
		)
		(fill no)
		(layer "In8.Cu")
	)
	(gr_line
		(start 70.544436 -366.994186)
		(end 181.955948 -366.994186)
		(stroke
			(width 0.508)
			(type default)
		)
		(layer "In8.Cu")
	)
	(gr_line
		(start 70.779386 -329.632564)
		(end 74.462386 -325.949564)
		(stroke
			(width 0.508)
			(type default)
		)
		(layer "In8.Cu")
	)
	(gr_circle
		(center 70.78345 -174.442374)
		(end 71.67245 -174.442374)
		(stroke
			(width 0.2)
			(type default)
		)
		(fill no)
		(layer "In8.Cu")
	)
	(gr_circle
		(center 70.80885 -175.204374)
		(end 71.69785 -175.204374)
		(stroke
			(width 0.2)
			(type default)
		)
		(fill no)
		(layer "In8.Cu")
	)
	(gr_circle
		(center 71.099934 -336.988404)
		(end 71.980044 -336.988404)
		(stroke
			(width 0.2)
			(type default)
		)
		(fill no)
		(layer "In8.Cu")
	)
	(gr_circle
		(center 71.333614 -174.764954)
		(end 72.222614 -174.764954)
		(stroke
			(width 0.2)
			(type default)
		)
		(fill no)
		(layer "In8.Cu")
	)
	(gr_circle
		(center 71.333614 -174.028354)
		(end 72.222614 -174.028354)
		(stroke
			(width 0.2)
			(type default)
		)
		(fill no)
		(layer "In8.Cu")
	)
	(gr_line
		(start 71.70293 -387.280912)
		(end 69.75602 -387.280912)
		(stroke
			(width 0.508)
			(type default)
		)
		(layer "In8.Cu")
	)
	(gr_circle
		(center 71.717154 -336.988404)
		(end 72.597264 -336.988404)
		(stroke
			(width 0.2)
			(type default)
		)
		(fill no)
		(layer "In8.Cu")
	)
	(gr_line
		(start 71.830692 -186.179714)
		(end 69.636386 -183.985408)
		(stroke
			(width 0.508)
			(type default)
		)
		(layer "In8.Cu")
	)
	(gr_circle
		(center 71.892668 -177.10912)
		(end 72.781668 -177.10912)
		(stroke
			(width 0.2)
			(type default)
		)
		(fill no)
		(layer "In8.Cu")
	)
	(gr_circle
		(center 71.892668 -176.37252)
		(end 72.781668 -176.37252)
		(stroke
			(width 0.2)
			(type default)
		)
		(fill no)
		(layer "In8.Cu")
	)
	(gr_circle
		(center 72.03567 -175.639222)
		(end 72.91578 -175.639222)
		(stroke
			(width 0.2)
			(type default)
		)
		(fill no)
		(layer "In8.Cu")
	)
	(gr_circle
		(center 72.334374 -336.988404)
		(end 73.214484 -336.988404)
		(stroke
			(width 0.2)
			(type default)
		)
		(fill no)
		(layer "In8.Cu")
	)
	(gr_circle
		(center 72.616314 -336.255868)
		(end 73.496424 -336.255868)
		(stroke
			(width 0.2)
			(type default)
		)
		(fill no)
		(layer "In8.Cu")
	)
	(gr_circle
		(center 72.616314 -335.519268)
		(end 73.496424 -335.519268)
		(stroke
			(width 0.2)
			(type default)
		)
		(fill no)
		(layer "In8.Cu")
	)
	(gr_circle
		(center 72.65289 -175.639222)
		(end 73.533 -175.639222)
		(stroke
			(width 0.2)
			(type default)
		)
		(fill no)
		(layer "In8.Cu")
	)
	(gr_circle
		(center 73.03643 -338.597494)
		(end 73.92543 -338.597494)
		(stroke
			(width 0.2)
			(type default)
		)
		(fill no)
		(layer "In8.Cu")
	)
	(gr_circle
		(center 73.03643 -337.860894)
		(end 73.92543 -337.860894)
		(stroke
			(width 0.2)
			(type default)
		)
		(fill no)
		(layer "In8.Cu")
	)
	(gr_circle
		(center 73.27011 -175.639222)
		(end 74.15022 -175.639222)
		(stroke
			(width 0.2)
			(type default)
		)
		(fill no)
		(layer "In8.Cu")
	)
	(gr_line
		(start 73.278746 -385.705096)
		(end 71.70293 -387.280912)
		(stroke
			(width 0.508)
			(type default)
		)
		(layer "In8.Cu")
	)
	(gr_line
		(start 73.278746 -384.41249)
		(end 73.278746 -385.705096)
		(stroke
			(width 0.508)
			(type default)
		)
		(layer "In8.Cu")
	)
	(gr_circle
		(center 73.561194 -337.421474)
		(end 74.450194 -337.421474)
		(stroke
			(width 0.2)
			(type default)
		)
		(fill no)
		(layer "In8.Cu")
	)
	(gr_circle
		(center 73.586594 -338.183474)
		(end 74.475594 -338.183474)
		(stroke
			(width 0.2)
			(type default)
		)
		(fill no)
		(layer "In8.Cu")
	)
	(gr_line
		(start 73.753726 -186.179714)
		(end 71.830692 -186.179714)
		(stroke
			(width 0.508)
			(type default)
		)
		(layer "In8.Cu")
	)
	(gr_line
		(start 73.979278 -383.711958)
		(end 73.278746 -384.41249)
		(stroke
			(width 0.508)
			(type default)
		)
		(layer "In8.Cu")
	)
	(gr_circle
		(center 74.119994 -338.539074)
		(end 75.008994 -338.539074)
		(stroke
			(width 0.2)
			(type default)
		)
		(fill no)
		(layer "In8.Cu")
	)
	(gr_circle
		(center 74.119994 -337.802474)
		(end 75.008994 -337.802474)
		(stroke
			(width 0.2)
			(type default)
		)
		(fill no)
		(layer "In8.Cu")
	)
	(gr_circle
		(center 74.119994 -337.065874)
		(end 75.008994 -337.065874)
		(stroke
			(width 0.2)
			(type default)
		)
		(fill no)
		(layer "In8.Cu")
	)
	(gr_circle
		(center 74.811382 -351.637854)
		(end 75.700382 -351.637854)
		(stroke
			(width 0.2)
			(type default)
		)
		(fill no)
		(layer "In8.Cu")
	)
	(gr_circle
		(center 74.849482 -353.131374)
		(end 75.738482 -353.131374)
		(stroke
			(width 0.2)
			(type default)
		)
		(fill no)
		(layer "In8.Cu")
	)
	(gr_circle
		(center 74.849736 -352.30816)
		(end 75.738736 -352.30816)
		(stroke
			(width 0.2)
			(type default)
		)
		(fill no)
		(layer "In8.Cu")
	)
	(gr_circle
		(center 74.86015 -350.929448)
		(end 75.74915 -350.929448)
		(stroke
			(width 0.2)
			(type default)
		)
		(fill no)
		(layer "In8.Cu")
	)
	(gr_line
		(start 76.484988 -153.002488)
		(end 81.438496 -157.955996)
		(stroke
			(width 0.508)
			(type default)
		)
		(layer "In8.Cu")
	)
	(gr_line
		(start 76.748386 -219.269564)
		(end 60.12688 -202.648058)
		(stroke
			(width 0.508)
			(type default)
		)
		(layer "In8.Cu")
	)
	(gr_circle
		(center 77.178408 -16.520668)
		(end 78.067408 -16.520668)
		(stroke
			(width 0.2)
			(type default)
		)
		(fill no)
		(layer "In8.Cu")
	)
	(gr_circle
		(center 77.473048 -351.5995)
		(end 78.362048 -351.5995)
		(stroke
			(width 0.2)
			(type default)
		)
		(fill no)
		(layer "In8.Cu")
	)
	(gr_circle
		(center 77.511402 -352.978212)
		(end 78.400402 -352.978212)
		(stroke
			(width 0.2)
			(type default)
		)
		(fill no)
		(layer "In8.Cu")
	)
	(gr_circle
		(center 77.511402 -352.269806)
		(end 78.400402 -352.269806)
		(stroke
			(width 0.2)
			(type default)
		)
		(fill no)
		(layer "In8.Cu")
	)
	(gr_circle
		(center 77.521816 -350.891094)
		(end 78.410816 -350.891094)
		(stroke
			(width 0.2)
			(type default)
		)
		(fill no)
		(layer "In8.Cu")
	)
	(gr_circle
		(center 77.84338 -16.55064)
		(end 78.73238 -16.55064)
		(stroke
			(width 0.2)
			(type default)
		)
		(fill no)
		(layer "In8.Cu")
	)
	(gr_line
		(start 78.573884 -190.999872)
		(end 73.753726 -186.179714)
		(stroke
			(width 0.508)
			(type default)
		)
		(layer "In8.Cu")
	)
	(gr_circle
		(center 78.85303 -178.798474)
		(end 79.74203 -178.798474)
		(stroke
			(width 0.2)
			(type default)
		)
		(fill no)
		(layer "In8.Cu")
	)
	(gr_circle
		(center 78.85303 -178.036474)
		(end 79.74203 -178.036474)
		(stroke
			(width 0.2)
			(type default)
		)
		(fill no)
		(layer "In8.Cu")
	)
	(gr_line
		(start 79.017368 -354.5586)
		(end 81.798922 -351.777046)
		(stroke
			(width 0.508)
			(type default)
		)
		(layer "In8.Cu")
	)
	(gr_circle
		(center 79.10703 -179.560474)
		(end 79.99603 -179.560474)
		(stroke
			(width 0.2)
			(type default)
		)
		(fill no)
		(layer "In8.Cu")
	)
	(gr_circle
		(center 79.13243 -180.322474)
		(end 80.02143 -180.322474)
		(stroke
			(width 0.2)
			(type default)
		)
		(fill no)
		(layer "In8.Cu")
	)
	(gr_line
		(start 79.177896 -295.95826)
		(end 92.33789 -295.95826)
		(stroke
			(width 0.254)
			(type default)
		)
		(layer "In8.Cu")
	)
	(gr_circle
		(center 79.403194 -178.384454)
		(end 80.292194 -178.384454)
		(stroke
			(width 0.2)
			(type default)
		)
		(fill no)
		(layer "In8.Cu")
	)
	(gr_circle
		(center 79.455518 -336.981292)
		(end 80.335628 -336.981292)
		(stroke
			(width 0.2)
			(type default)
		)
		(fill no)
		(layer "In8.Cu")
	)
	(gr_circle
		(center 79.657194 -179.883054)
		(end 80.546194 -179.883054)
		(stroke
			(width 0.2)
			(type default)
		)
		(fill no)
		(layer "In8.Cu")
	)
	(gr_circle
		(center 79.657194 -179.146454)
		(end 80.546194 -179.146454)
		(stroke
			(width 0.2)
			(type default)
		)
		(fill no)
		(layer "In8.Cu")
	)
	(gr_line
		(start 79.817976 -226.662234)
		(end 86.946486 -226.662234)
		(stroke
			(width 0.254)
			(type default)
		)
		(layer "In8.Cu")
	)
	(gr_circle
		(center 79.921862 -18.238724)
		(end 80.810862 -18.238724)
		(stroke
			(width 0.2)
			(type default)
		)
		(fill no)
		(layer "In8.Cu")
	)
	(gr_circle
		(center 79.921862 -17.502124)
		(end 80.810862 -17.502124)
		(stroke
			(width 0.2)
			(type default)
		)
		(fill no)
		(layer "In8.Cu")
	)
	(gr_circle
		(center 80.072738 -336.981292)
		(end 80.952848 -336.981292)
		(stroke
			(width 0.2)
			(type default)
		)
		(fill no)
		(layer "In8.Cu")
	)
	(gr_circle
		(center 80.241648 -182.2196)
		(end 81.130648 -182.2196)
		(stroke
			(width 0.2)
			(type default)
		)
		(fill no)
		(layer "In8.Cu")
	)
	(gr_circle
		(center 80.241648 -181.483)
		(end 81.130648 -181.483)
		(stroke
			(width 0.2)
			(type default)
		)
		(fill no)
		(layer "In8.Cu")
	)
	(gr_circle
		(center 80.35925 -180.755544)
		(end 81.23936 -180.755544)
		(stroke
			(width 0.2)
			(type default)
		)
		(fill no)
		(layer "In8.Cu")
	)
	(gr_circle
		(center 80.689958 -336.981292)
		(end 81.570068 -336.981292)
		(stroke
			(width 0.2)
			(type default)
		)
		(fill no)
		(layer "In8.Cu")
	)
	(gr_circle
		(center 80.97647 -180.755544)
		(end 81.85658 -180.755544)
		(stroke
			(width 0.2)
			(type default)
		)
		(fill no)
		(layer "In8.Cu")
	)
	(gr_circle
		(center 80.977994 -336.245708)
		(end 81.858104 -336.245708)
		(stroke
			(width 0.2)
			(type default)
		)
		(fill no)
		(layer "In8.Cu")
	)
	(gr_circle
		(center 80.977994 -335.509108)
		(end 81.858104 -335.509108)
		(stroke
			(width 0.2)
			(type default)
		)
		(fill no)
		(layer "In8.Cu")
	)
	(gr_circle
		(center 81.392014 -338.590382)
		(end 82.281014 -338.590382)
		(stroke
			(width 0.2)
			(type default)
		)
		(fill no)
		(layer "In8.Cu")
	)
	(gr_circle
		(center 81.392014 -337.853782)
		(end 82.281014 -337.853782)
		(stroke
			(width 0.2)
			(type default)
		)
		(fill no)
		(layer "In8.Cu")
	)
	(gr_line
		(start 81.438496 -157.955996)
		(end 91.976702 -157.955996)
		(stroke
			(width 0.508)
			(type default)
		)
		(layer "In8.Cu")
	)
	(gr_circle
		(center 81.59369 -180.755544)
		(end 82.4738 -180.755544)
		(stroke
			(width 0.2)
			(type default)
		)
		(fill no)
		(layer "In8.Cu")
	)
	(gr_arc
		(start 81.701894 -9.780016)
		(mid 82.287679 -11.194227)
		(end 83.70189 -11.780012)
		(stroke
			(width 3.048)
			(type default)
		)
		(layer "In8.Cu")
	)
	(gr_arc
		(start 81.701894 -0.500126)
		(mid 81.555625 -0.146451)
		(end 81.202022 0)
		(stroke
			(width 3.048)
			(type default)
		)
		(layer "In8.Cu")
	)
	(gr_line
		(start 81.701894 -0.500126)
		(end 81.701894 -9.780016)
		(stroke
			(width 3.048)
			(type default)
		)
		(layer "In8.Cu")
	)
	(gr_line
		(start 81.798922 -351.777046)
		(end 85.081872 -351.777046)
		(stroke
			(width 0.508)
			(type default)
		)
		(layer "In8.Cu")
	)
	(gr_circle
		(center 81.916778 -337.414362)
		(end 82.805778 -337.414362)
		(stroke
			(width 0.2)
			(type default)
		)
		(fill no)
		(layer "In8.Cu")
	)
	(gr_circle
		(center 81.942178 -338.176362)
		(end 82.831178 -338.176362)
		(stroke
			(width 0.2)
			(type default)
		)
		(fill no)
		(layer "In8.Cu")
	)
	(gr_circle
		(center 82.183986 -348.89948)
		(end 83.072986 -348.89948)
		(stroke
			(width 0.2)
			(type default)
		)
		(fill no)
		(layer "In8.Cu")
	)
	(gr_circle
		(center 82.222086 -350.393)
		(end 83.111086 -350.393)
		(stroke
			(width 0.2)
			(type default)
		)
		(fill no)
		(layer "In8.Cu")
	)
	(gr_circle
		(center 82.22234 -349.569786)
		(end 83.11134 -349.569786)
		(stroke
			(width 0.2)
			(type default)
		)
		(fill no)
		(layer "In8.Cu")
	)
	(gr_circle
		(center 82.232754 -348.191074)
		(end 83.121754 -348.191074)
		(stroke
			(width 0.2)
			(type default)
		)
		(fill no)
		(layer "In8.Cu")
	)
	(gr_circle
		(center 82.475578 -338.531962)
		(end 83.364578 -338.531962)
		(stroke
			(width 0.2)
			(type default)
		)
		(fill no)
		(layer "In8.Cu")
	)
	(gr_circle
		(center 82.475578 -337.795362)
		(end 83.364578 -337.795362)
		(stroke
			(width 0.2)
			(type default)
		)
		(fill no)
		(layer "In8.Cu")
	)
	(gr_circle
		(center 82.475578 -337.058762)
		(end 83.364578 -337.058762)
		(stroke
			(width 0.2)
			(type default)
		)
		(fill no)
		(layer "In8.Cu")
	)
	(gr_circle
		(center 82.989674 -165.962076)
		(end 84.386674 -165.962076)
		(stroke
			(width 0.2)
			(type default)
		)
		(fill no)
		(layer "In8.Cu")
	)
	(gr_line
		(start 83.70189 -11.780012)
		(end 124.102114 -11.780012)
		(stroke
			(width 3.048)
			(type default)
		)
		(layer "In8.Cu")
	)
	(gr_line
		(start 84.622386 -219.269564)
		(end 76.748386 -219.269564)
		(stroke
			(width 0.508)
			(type default)
		)
		(layer "In8.Cu")
	)
	(gr_circle
		(center 84.845652 -348.861126)
		(end 85.734652 -348.861126)
		(stroke
			(width 0.2)
			(type default)
		)
		(fill no)
		(layer "In8.Cu")
	)
	(gr_circle
		(center 84.884006 -350.239838)
		(end 85.773006 -350.239838)
		(stroke
			(width 0.2)
			(type default)
		)
		(fill no)
		(layer "In8.Cu")
	)
	(gr_circle
		(center 84.884006 -349.531432)
		(end 85.773006 -349.531432)
		(stroke
			(width 0.2)
			(type default)
		)
		(fill no)
		(layer "In8.Cu")
	)
	(gr_circle
		(center 84.89442 -348.15272)
		(end 85.78342 -348.15272)
		(stroke
			(width 0.2)
			(type default)
		)
		(fill no)
		(layer "In8.Cu")
	)
	(gr_line
		(start 85.081872 -351.777046)
		(end 87.051134 -349.807784)
		(stroke
			(width 0.508)
			(type default)
		)
		(layer "In8.Cu")
	)
	(gr_line
		(start 86.228682 -383.711958)
		(end 73.979278 -383.711958)
		(stroke
			(width 0.508)
			(type default)
		)
		(layer "In8.Cu")
	)
	(gr_line
		(start 86.606126 -387.797802)
		(end 86.606126 -384.089402)
		(stroke
			(width 0.508)
			(type default)
		)
		(layer "In8.Cu")
	)
	(gr_line
		(start 86.606126 -384.089402)
		(end 86.228682 -383.711958)
		(stroke
			(width 0.508)
			(type default)
		)
		(layer "In8.Cu")
	)
	(gr_line
		(start 86.606126 -384.089402)
		(end 86.606126 -383.99466)
		(stroke
			(width 0.508)
			(type default)
		)
		(layer "In8.Cu")
	)
	(gr_line
		(start 86.606126 -383.99466)
		(end 87.065866 -383.53492)
		(stroke
			(width 0.508)
			(type default)
		)
		(layer "In8.Cu")
	)
	(gr_line
		(start 86.946486 -226.662234)
		(end 87.503762 -227.21951)
		(stroke
			(width 0.254)
			(type default)
		)
		(layer "In8.Cu")
	)
	(gr_circle
		(center 86.97087 -180.610002)
		(end 87.85987 -180.610002)
		(stroke
			(width 0.2)
			(type default)
		)
		(fill no)
		(layer "In8.Cu")
	)
	(gr_circle
		(center 86.97087 -179.873402)
		(end 87.85987 -179.873402)
		(stroke
			(width 0.2)
			(type default)
		)
		(fill no)
		(layer "In8.Cu")
	)
	(gr_circle
		(center 86.97087 -179.136802)
		(end 87.85987 -179.136802)
		(stroke
			(width 0.2)
			(type default)
		)
		(fill no)
		(layer "In8.Cu")
	)
	(gr_circle
		(center 87.01913 -164.097716)
		(end 87.90813 -164.097716)
		(stroke
			(width 0.2)
			(type default)
		)
		(fill no)
		(layer "In8.Cu")
	)
	(gr_circle
		(center 87.03945 -163.447476)
		(end 87.92845 -163.447476)
		(stroke
			(width 0.2)
			(type default)
		)
		(fill no)
		(layer "In8.Cu")
	)
	(gr_circle
		(center 87.03945 -162.812476)
		(end 87.92845 -162.812476)
		(stroke
			(width 0.2)
			(type default)
		)
		(fill no)
		(layer "In8.Cu")
	)
	(gr_line
		(start 87.042752 -388.234428)
		(end 86.606126 -387.797802)
		(stroke
			(width 0.508)
			(type default)
		)
		(layer "In8.Cu")
	)
	(gr_line
		(start 87.051134 -349.807784)
		(end 108.392976 -349.807784)
		(stroke
			(width 0.508)
			(type default)
		)
		(layer "In8.Cu")
	)
	(gr_line
		(start 87.065866 -383.53492)
		(end 102.181406 -383.53492)
		(stroke
			(width 0.508)
			(type default)
		)
		(layer "In8.Cu")
	)
	(gr_line
		(start 87.503762 -255.164082)
		(end 88.974422 -256.634742)
		(stroke
			(width 0.254)
			(type default)
		)
		(layer "In8.Cu")
	)
	(gr_line
		(start 87.503762 -227.21951)
		(end 87.503762 -255.164082)
		(stroke
			(width 0.254)
			(type default)
		)
		(layer "In8.Cu")
	)
	(gr_circle
		(center 87.50427 -179.492402)
		(end 88.39327 -179.492402)
		(stroke
			(width 0.2)
			(type default)
		)
		(fill no)
		(layer "In8.Cu")
	)
	(gr_circle
		(center 87.52967 -180.254402)
		(end 88.41867 -180.254402)
		(stroke
			(width 0.2)
			(type default)
		)
		(fill no)
		(layer "In8.Cu")
	)
	(gr_circle
		(center 87.65413 -164.097716)
		(end 88.54313 -164.097716)
		(stroke
			(width 0.2)
			(type default)
		)
		(fill no)
		(layer "In8.Cu")
	)
	(gr_circle
		(center 87.67445 -163.447476)
		(end 88.56345 -163.447476)
		(stroke
			(width 0.2)
			(type default)
		)
		(fill no)
		(layer "In8.Cu")
	)
	(gr_circle
		(center 87.67445 -162.812476)
		(end 88.56345 -162.812476)
		(stroke
			(width 0.2)
			(type default)
		)
		(fill no)
		(layer "In8.Cu")
	)
	(gr_circle
		(center 87.813134 -336.966814)
		(end 88.693244 -336.966814)
		(stroke
			(width 0.2)
			(type default)
		)
		(fill no)
		(layer "In8.Cu")
	)
	(gr_circle
		(center 88.054434 -179.814982)
		(end 88.943434 -179.814982)
		(stroke
			(width 0.2)
			(type default)
		)
		(fill no)
		(layer "In8.Cu")
	)
	(gr_circle
		(center 88.054434 -179.078382)
		(end 88.943434 -179.078382)
		(stroke
			(width 0.2)
			(type default)
		)
		(fill no)
		(layer "In8.Cu")
	)
	(gr_circle
		(center 88.28913 -164.097716)
		(end 89.17813 -164.097716)
		(stroke
			(width 0.2)
			(type default)
		)
		(fill no)
		(layer "In8.Cu")
	)
	(gr_circle
		(center 88.30945 -163.447476)
		(end 89.19845 -163.447476)
		(stroke
			(width 0.2)
			(type default)
		)
		(fill no)
		(layer "In8.Cu")
	)
	(gr_circle
		(center 88.30945 -162.812476)
		(end 89.19845 -162.812476)
		(stroke
			(width 0.2)
			(type default)
		)
		(fill no)
		(layer "In8.Cu")
	)
	(gr_circle
		(center 88.430354 -336.966814)
		(end 89.310464 -336.966814)
		(stroke
			(width 0.2)
			(type default)
		)
		(fill no)
		(layer "In8.Cu")
	)
	(gr_circle
		(center 88.49233 -182.13324)
		(end 89.38133 -182.13324)
		(stroke
			(width 0.2)
			(type default)
		)
		(fill no)
		(layer "In8.Cu")
	)
	(gr_circle
		(center 88.49233 -181.39664)
		(end 89.38133 -181.39664)
		(stroke
			(width 0.2)
			(type default)
		)
		(fill no)
		(layer "In8.Cu")
	)
	(gr_circle
		(center 88.75649 -180.687472)
		(end 89.6366 -180.687472)
		(stroke
			(width 0.2)
			(type default)
		)
		(fill no)
		(layer "In8.Cu")
	)
	(gr_circle
		(center 88.92413 -164.097716)
		(end 89.81313 -164.097716)
		(stroke
			(width 0.2)
			(type default)
		)
		(fill no)
		(layer "In8.Cu")
	)
	(gr_circle
		(center 88.94445 -163.447476)
		(end 89.83345 -163.447476)
		(stroke
			(width 0.2)
			(type default)
		)
		(fill no)
		(layer "In8.Cu")
	)
	(gr_circle
		(center 88.94445 -162.812476)
		(end 89.83345 -162.812476)
		(stroke
			(width 0.2)
			(type default)
		)
		(fill no)
		(layer "In8.Cu")
	)
	(gr_line
		(start 88.974422 -256.634742)
		(end 95.331026 -256.634488)
		(stroke
			(width 0.254)
			(type default)
		)
		(layer "In8.Cu")
	)
	(gr_circle
		(center 89.047574 -336.966814)
		(end 89.927684 -336.966814)
		(stroke
			(width 0.2)
			(type default)
		)
		(fill no)
		(layer "In8.Cu")
	)
	(gr_circle
		(center 89.314528 -345.237562)
		(end 90.203528 -345.237562)
		(stroke
			(width 0.2)
			(type default)
		)
		(fill no)
		(layer "In8.Cu")
	)
	(gr_circle
		(center 89.319354 -336.255868)
		(end 90.199464 -336.255868)
		(stroke
			(width 0.2)
			(type default)
		)
		(fill no)
		(layer "In8.Cu")
	)
	(gr_circle
		(center 89.319354 -335.519268)
		(end 90.199464 -335.519268)
		(stroke
			(width 0.2)
			(type default)
		)
		(fill no)
		(layer "In8.Cu")
	)
	(gr_circle
		(center 89.350088 -345.96959)
		(end 90.239088 -345.96959)
		(stroke
			(width 0.2)
			(type default)
		)
		(fill no)
		(layer "In8.Cu")
	)
	(gr_circle
		(center 89.37371 -180.687472)
		(end 90.25382 -180.687472)
		(stroke
			(width 0.2)
			(type default)
		)
		(fill no)
		(layer "In8.Cu")
	)
	(gr_circle
		(center 89.388442 -346.639896)
		(end 90.277442 -346.639896)
		(stroke
			(width 0.2)
			(type default)
		)
		(fill no)
		(layer "In8.Cu")
	)
	(gr_circle
		(center 89.55913 -164.097716)
		(end 90.44813 -164.097716)
		(stroke
			(width 0.2)
			(type default)
		)
		(fill no)
		(layer "In8.Cu")
	)
	(gr_circle
		(center 89.57945 -163.447476)
		(end 90.46845 -163.447476)
		(stroke
			(width 0.2)
			(type default)
		)
		(fill no)
		(layer "In8.Cu")
	)
	(gr_circle
		(center 89.57945 -162.812476)
		(end 90.46845 -162.812476)
		(stroke
			(width 0.2)
			(type default)
		)
		(fill no)
		(layer "In8.Cu")
	)
	(gr_circle
		(center 89.74963 -338.575904)
		(end 90.63863 -338.575904)
		(stroke
			(width 0.2)
			(type default)
		)
		(fill no)
		(layer "In8.Cu")
	)
	(gr_circle
		(center 89.74963 -337.839304)
		(end 90.63863 -337.839304)
		(stroke
			(width 0.2)
			(type default)
		)
		(fill no)
		(layer "In8.Cu")
	)
	(gr_circle
		(center 89.983056 -345.261184)
		(end 90.872056 -345.261184)
		(stroke
			(width 0.2)
			(type default)
		)
		(fill no)
		(layer "In8.Cu")
	)
	(gr_circle
		(center 89.985088 -345.96959)
		(end 90.874088 -345.96959)
		(stroke
			(width 0.2)
			(type default)
		)
		(fill no)
		(layer "In8.Cu")
	)
	(gr_circle
		(center 89.99093 -180.687472)
		(end 90.87104 -180.687472)
		(stroke
			(width 0.2)
			(type default)
		)
		(fill no)
		(layer "In8.Cu")
	)
	(gr_circle
		(center 90.023442 -346.639896)
		(end 90.912442 -346.639896)
		(stroke
			(width 0.2)
			(type default)
		)
		(fill no)
		(layer "In8.Cu")
	)
	(gr_line
		(start 90.030554 -388.234428)
		(end 87.042752 -388.234428)
		(stroke
			(width 0.508)
			(type default)
		)
		(layer "In8.Cu")
	)
	(gr_circle
		(center 90.21953 -164.107876)
		(end 91.10853 -164.107876)
		(stroke
			(width 0.2)
			(type default)
		)
		(fill no)
		(layer "In8.Cu")
	)
	(gr_circle
		(center 90.23985 -163.457636)
		(end 91.12885 -163.457636)
		(stroke
			(width 0.2)
			(type default)
		)
		(fill no)
		(layer "In8.Cu")
	)
	(gr_circle
		(center 90.23985 -162.822636)
		(end 91.12885 -162.822636)
		(stroke
			(width 0.2)
			(type default)
		)
		(fill no)
		(layer "In8.Cu")
	)
	(gr_circle
		(center 90.274394 -337.399884)
		(end 91.163394 -337.399884)
		(stroke
			(width 0.2)
			(type default)
		)
		(fill no)
		(layer "In8.Cu")
	)
	(gr_circle
		(center 90.299794 -338.161884)
		(end 91.188794 -338.161884)
		(stroke
			(width 0.2)
			(type default)
		)
		(fill no)
		(layer "In8.Cu")
	)
	(gr_circle
		(center 90.618056 -345.261184)
		(end 91.507056 -345.261184)
		(stroke
			(width 0.2)
			(type default)
		)
		(fill no)
		(layer "In8.Cu")
	)
	(gr_circle
		(center 90.620088 -345.96959)
		(end 91.509088 -345.96959)
		(stroke
			(width 0.2)
			(type default)
		)
		(fill no)
		(layer "In8.Cu")
	)
	(gr_circle
		(center 90.658442 -346.639896)
		(end 91.547442 -346.639896)
		(stroke
			(width 0.2)
			(type default)
		)
		(fill no)
		(layer "In8.Cu")
	)
	(gr_circle
		(center 90.833194 -338.517484)
		(end 91.722194 -338.517484)
		(stroke
			(width 0.2)
			(type default)
		)
		(fill no)
		(layer "In8.Cu")
	)
	(gr_circle
		(center 90.833194 -337.780884)
		(end 91.722194 -337.780884)
		(stroke
			(width 0.2)
			(type default)
		)
		(fill no)
		(layer "In8.Cu")
	)
	(gr_circle
		(center 90.833194 -337.044284)
		(end 91.722194 -337.044284)
		(stroke
			(width 0.2)
			(type default)
		)
		(fill no)
		(layer "In8.Cu")
	)
	(gr_circle
		(center 91.255088 -345.96959)
		(end 92.144088 -345.96959)
		(stroke
			(width 0.2)
			(type default)
		)
		(fill no)
		(layer "In8.Cu")
	)
	(gr_circle
		(center 91.293442 -346.639896)
		(end 92.182442 -346.639896)
		(stroke
			(width 0.2)
			(type default)
		)
		(fill no)
		(layer "In8.Cu")
	)
	(gr_circle
		(center 91.380056 -345.261184)
		(end 92.269056 -345.261184)
		(stroke
			(width 0.2)
			(type default)
		)
		(fill no)
		(layer "In8.Cu")
	)
	(gr_line
		(start 91.731084 -386.533898)
		(end 90.030554 -388.234428)
		(stroke
			(width 0.508)
			(type default)
		)
		(layer "In8.Cu")
	)
	(gr_circle
		(center 91.966288 -345.96959)
		(end 92.855288 -345.96959)
		(stroke
			(width 0.2)
			(type default)
		)
		(fill no)
		(layer "In8.Cu")
	)
	(gr_line
		(start 91.976702 -157.955996)
		(end 106.856022 -143.076676)
		(stroke
			(width 0.508)
			(type default)
		)
		(layer "In8.Cu")
	)
	(gr_circle
		(center 92.004642 -346.639896)
		(end 92.893642 -346.639896)
		(stroke
			(width 0.2)
			(type default)
		)
		(fill no)
		(layer "In8.Cu")
	)
	(gr_circle
		(center 92.015056 -345.261184)
		(end 92.904056 -345.261184)
		(stroke
			(width 0.2)
			(type default)
		)
		(fill no)
		(layer "In8.Cu")
	)
	(gr_line
		(start 92.33789 -295.95826)
		(end 92.808044 -295.148254)
		(stroke
			(width 0.254)
			(type default)
		)
		(layer "In8.Cu")
	)
	(gr_circle
		(center 92.387674 -165.962076)
		(end 93.784674 -165.962076)
		(stroke
			(width 0.2)
			(type default)
		)
		(fill no)
		(layer "In8.Cu")
	)
	(gr_line
		(start 92.420694 -386.533898)
		(end 91.731084 -386.533898)
		(stroke
			(width 0.508)
			(type default)
		)
		(layer "In8.Cu")
	)
	(gr_line
		(start 92.496386 -219.269564)
		(end 84.622386 -219.269564)
		(stroke
			(width 0.254)
			(type default)
		)
		(layer "In8.Cu")
	)
	(gr_circle
		(center 92.601288 -345.96959)
		(end 93.490288 -345.96959)
		(stroke
			(width 0.2)
			(type default)
		)
		(fill no)
		(layer "In8.Cu")
	)
	(gr_circle
		(center 92.639642 -346.639896)
		(end 93.528642 -346.639896)
		(stroke
			(width 0.2)
			(type default)
		)
		(fill no)
		(layer "In8.Cu")
	)
	(gr_circle
		(center 92.650056 -345.261184)
		(end 93.539056 -345.261184)
		(stroke
			(width 0.2)
			(type default)
		)
		(fill no)
		(layer "In8.Cu")
	)
	(gr_line
		(start 93.004386 -223.752156)
		(end 93.004386 -222.317564)
		(stroke
			(width 0.254)
			(type default)
		)
		(layer "In8.Cu")
	)
	(gr_line
		(start 93.004386 -222.317564)
		(end 93.131386 -222.190564)
		(stroke
			(width 0.254)
			(type default)
		)
		(layer "In8.Cu")
	)
	(gr_line
		(start 93.110812 -223.858582)
		(end 93.004386 -223.752156)
		(stroke
			(width 0.254)
			(type default)
		)
		(layer "In8.Cu")
	)
	(gr_line
		(start 93.131386 -222.190564)
		(end 93.131386 -219.904564)
		(stroke
			(width 0.254)
			(type default)
		)
		(layer "In8.Cu")
	)
	(gr_line
		(start 93.131386 -219.904564)
		(end 92.496386 -219.269564)
		(stroke
			(width 0.254)
			(type default)
		)
		(layer "In8.Cu")
	)
	(gr_line
		(start 93.747844 -293.528242)
		(end 92.808044 -295.148254)
		(stroke
			(width 0.254)
			(type default)
		)
		(layer "In8.Cu")
	)
	(gr_line
		(start 93.805248 -387.918452)
		(end 92.420694 -386.533898)
		(stroke
			(width 0.508)
			(type default)
		)
		(layer "In8.Cu")
	)
	(gr_line
		(start 94.687898 -293.528242)
		(end 93.747844 -293.528242)
		(stroke
			(width 0.254)
			(type default)
		)
		(layer "In8.Cu")
	)
	(gr_line
		(start 94.873826 -162.19551)
		(end 60.617354 -162.19551)
		(stroke
			(width 0.508)
			(type default)
		)
		(layer "In8.Cu")
	)
	(gr_line
		(start 95.157798 -292.718236)
		(end 94.687898 -293.528242)
		(stroke
			(width 0.254)
			(type default)
		)
		(layer "In8.Cu")
	)
	(gr_line
		(start 95.331026 -256.634488)
		(end 95.800926 -255.824482)
		(stroke
			(width 0.254)
			(type default)
		)
		(layer "In8.Cu")
	)
	(gr_circle
		(center 95.36303 -180.627274)
		(end 96.25203 -180.627274)
		(stroke
			(width 0.2)
			(type default)
		)
		(fill no)
		(layer "In8.Cu")
	)
	(gr_circle
		(center 95.36303 -179.890674)
		(end 96.25203 -179.890674)
		(stroke
			(width 0.2)
			(type default)
		)
		(fill no)
		(layer "In8.Cu")
	)
	(gr_circle
		(center 95.36303 -179.154074)
		(end 96.25203 -179.154074)
		(stroke
			(width 0.2)
			(type default)
		)
		(fill no)
		(layer "In8.Cu")
	)
	(gr_line
		(start 95.627952 -291.90823)
		(end 95.157798 -292.718236)
		(stroke
			(width 0.254)
			(type default)
		)
		(layer "In8.Cu")
	)
	(gr_line
		(start 95.800926 -255.824482)
		(end 97.211134 -256.634488)
		(stroke
			(width 0.254)
			(type default)
		)
		(layer "In8.Cu")
	)
	(gr_circle
		(center 95.89643 -179.509674)
		(end 96.78543 -179.509674)
		(stroke
			(width 0.2)
			(type default)
		)
		(fill no)
		(layer "In8.Cu")
	)
	(gr_circle
		(center 95.92183 -180.271674)
		(end 96.81083 -180.271674)
		(stroke
			(width 0.2)
			(type default)
		)
		(fill no)
		(layer "In8.Cu")
	)
	(gr_line
		(start 96.097852 -291.098224)
		(end 95.627952 -291.90823)
		(stroke
			(width 0.254)
			(type default)
		)
		(layer "In8.Cu")
	)
	(gr_circle
		(center 96.144334 -337.017614)
		(end 97.024444 -337.017614)
		(stroke
			(width 0.2)
			(type default)
		)
		(fill no)
		(layer "In8.Cu")
	)
	(gr_line
		(start 96.267778 -248.532396)
		(end 97.207832 -246.912384)
		(stroke
			(width 0.254)
			(type default)
		)
		(layer "In8.Cu")
	)
	(gr_line
		(start 96.267778 -245.292372)
		(end 97.207832 -243.67236)
		(stroke
			(width 0.254)
			(type default)
		)
		(layer "In8.Cu")
	)
	(gr_line
		(start 96.267778 -242.052348)
		(end 97.207832 -240.432336)
		(stroke
			(width 0.254)
			(type default)
		)
		(layer "In8.Cu")
	)
	(gr_line
		(start 96.267778 -238.812324)
		(end 97.677986 -238.002318)
		(stroke
			(width 0.254)
			(type default)
		)
		(layer "In8.Cu")
	)
	(gr_line
		(start 96.267778 -233.952288)
		(end 97.207832 -232.332276)
		(stroke
			(width 0.254)
			(type default)
		)
		(layer "In8.Cu")
	)
	(gr_line
		(start 96.306386 -325.949564)
		(end 74.462386 -325.949564)
		(stroke
			(width 0.508)
			(type default)
		)
		(layer "In8.Cu")
	)
	(gr_circle
		(center 96.446594 -179.832254)
		(end 97.335594 -179.832254)
		(stroke
			(width 0.2)
			(type default)
		)
		(fill no)
		(layer "In8.Cu")
	)
	(gr_circle
		(center 96.446594 -179.095654)
		(end 97.335594 -179.095654)
		(stroke
			(width 0.2)
			(type default)
		)
		(fill no)
		(layer "In8.Cu")
	)
	(gr_line
		(start 96.568006 -290.288472)
		(end 96.097852 -291.098224)
		(stroke
			(width 0.254)
			(type default)
		)
		(layer "In8.Cu")
	)
	(gr_line
		(start 96.568006 -287.048448)
		(end 97.507806 -288.66846)
		(stroke
			(width 0.254)
			(type default)
		)
		(layer "In8.Cu")
	)
	(gr_line
		(start 96.568006 -283.808424)
		(end 97.507806 -285.428436)
		(stroke
			(width 0.254)
			(type default)
		)
		(layer "In8.Cu")
	)
	(gr_line
		(start 96.568006 -278.948388)
		(end 97.97796 -279.758394)
		(stroke
			(width 0.254)
			(type default)
		)
		(layer "In8.Cu")
	)
	(gr_line
		(start 96.568006 -275.708364)
		(end 97.507806 -277.328376)
		(stroke
			(width 0.254)
			(type default)
		)
		(layer "In8.Cu")
	)
	(gr_line
		(start 96.568006 -272.46834)
		(end 97.507806 -274.088352)
		(stroke
			(width 0.254)
			(type default)
		)
		(layer "In8.Cu")
	)
	(gr_line
		(start 96.568006 -269.228316)
		(end 97.507806 -270.848328)
		(stroke
			(width 0.254)
			(type default)
		)
		(layer "In8.Cu")
	)
	(gr_line
		(start 96.737932 -236.382306)
		(end 97.207832 -235.5723)
		(stroke
			(width 0.254)
			(type default)
		)
		(layer "In8.Cu")
	)
	(gr_line
		(start 96.737932 -231.52227)
		(end 97.207832 -230.712264)
		(stroke
			(width 0.254)
			(type default)
		)
		(layer "In8.Cu")
	)
	(gr_line
		(start 96.737932 -229.902258)
		(end 97.207832 -229.092252)
		(stroke
			(width 0.254)
			(type default)
		)
		(layer "In8.Cu")
	)
	(gr_line
		(start 96.737932 -228.282246)
		(end 93.110812 -223.858582)
		(stroke
			(width 0.254)
			(type default)
		)
		(layer "In8.Cu")
	)
	(gr_circle
		(center 96.761554 -337.017614)
		(end 97.641664 -337.017614)
		(stroke
			(width 0.2)
			(type default)
		)
		(fill no)
		(layer "In8.Cu")
	)
	(gr_circle
		(center 96.980248 -182.13324)
		(end 97.869248 -182.13324)
		(stroke
			(width 0.2)
			(type default)
		)
		(fill no)
		(layer "In8.Cu")
	)
	(gr_circle
		(center 96.980248 -181.39664)
		(end 97.869248 -181.39664)
		(stroke
			(width 0.2)
			(type default)
		)
		(fill no)
		(layer "In8.Cu")
	)
	(gr_line
		(start 97.037906 -281.378406)
		(end 97.507806 -282.188412)
		(stroke
			(width 0.254)
			(type default)
		)
		(layer "In8.Cu")
	)
	(gr_circle
		(center 97.14865 -180.704744)
		(end 98.02876 -180.704744)
		(stroke
			(width 0.2)
			(type default)
		)
		(fill no)
		(layer "In8.Cu")
	)
	(gr_line
		(start 97.207832 -246.912384)
		(end 96.267778 -245.292372)
		(stroke
			(width 0.254)
			(type default)
		)
		(layer "In8.Cu")
	)
	(gr_line
		(start 97.207832 -243.67236)
		(end 96.267778 -242.052348)
		(stroke
			(width 0.254)
			(type default)
		)
		(layer "In8.Cu")
	)
	(gr_line
		(start 97.207832 -240.432336)
		(end 96.267778 -238.812324)
		(stroke
			(width 0.254)
			(type default)
		)
		(layer "In8.Cu")
	)
	(gr_line
		(start 97.207832 -235.5723)
		(end 96.267778 -233.952288)
		(stroke
			(width 0.254)
			(type default)
		)
		(layer "In8.Cu")
	)
	(gr_line
		(start 97.207832 -232.332276)
		(end 96.737932 -231.52227)
		(stroke
			(width 0.254)
			(type default)
		)
		(layer "In8.Cu")
	)
	(gr_line
		(start 97.207832 -230.712264)
		(end 96.737932 -229.902258)
		(stroke
			(width 0.254)
			(type default)
		)
		(layer "In8.Cu")
	)
	(gr_line
		(start 97.207832 -229.092252)
		(end 96.737932 -228.282246)
		(stroke
			(width 0.254)
			(type default)
		)
		(layer "In8.Cu")
	)
	(gr_line
		(start 97.211134 -256.634488)
		(end 97.681034 -255.824482)
		(stroke
			(width 0.254)
			(type default)
		)
		(layer "In8.Cu")
	)
	(gr_circle
		(center 97.378774 -337.017614)
		(end 98.258884 -337.017614)
		(stroke
			(width 0.2)
			(type default)
		)
		(fill no)
		(layer "In8.Cu")
	)
	(gr_line
		(start 97.507806 -288.66846)
		(end 96.568006 -290.288472)
		(stroke
			(width 0.254)
			(type default)
		)
		(layer "In8.Cu")
	)
	(gr_line
		(start 97.507806 -285.428436)
		(end 96.568006 -287.048448)
		(stroke
			(width 0.254)
			(type default)
		)
		(layer "In8.Cu")
	)
	(gr_line
		(start 97.507806 -282.188412)
		(end 96.568006 -283.808424)
		(stroke
			(width 0.254)
			(type default)
		)
		(layer "In8.Cu")
	)
	(gr_line
		(start 97.507806 -280.5684)
		(end 97.037906 -281.378406)
		(stroke
			(width 0.254)
			(type default)
		)
		(layer "In8.Cu")
	)
	(gr_line
		(start 97.507806 -277.328376)
		(end 96.568006 -278.948388)
		(stroke
			(width 0.254)
			(type default)
		)
		(layer "In8.Cu")
	)
	(gr_line
		(start 97.507806 -274.088352)
		(end 96.568006 -275.708364)
		(stroke
			(width 0.254)
			(type default)
		)
		(layer "In8.Cu")
	)
	(gr_line
		(start 97.507806 -270.848328)
		(end 96.568006 -272.46834)
		(stroke
			(width 0.254)
			(type default)
		)
		(layer "In8.Cu")
	)
	(gr_line
		(start 97.507806 -267.608304)
		(end 96.568006 -269.228316)
		(stroke
			(width 0.254)
			(type default)
		)
		(layer "In8.Cu")
	)
	(gr_circle
		(center 97.658174 -336.319368)
		(end 98.538284 -336.319368)
		(stroke
			(width 0.2)
			(type default)
		)
		(fill no)
		(layer "In8.Cu")
	)
	(gr_circle
		(center 97.658174 -335.582768)
		(end 98.538284 -335.582768)
		(stroke
			(width 0.2)
			(type default)
		)
		(fill no)
		(layer "In8.Cu")
	)
	(gr_line
		(start 97.677986 -249.342402)
		(end 96.267778 -248.532396)
		(stroke
			(width 0.254)
			(type default)
		)
		(layer "In8.Cu")
	)
	(gr_line
		(start 97.677986 -238.002318)
		(end 96.737932 -236.382306)
		(stroke
			(width 0.254)
			(type default)
		)
		(layer "In8.Cu")
	)
	(gr_line
		(start 97.681034 -255.824482)
		(end 99.090988 -256.634488)
		(stroke
			(width 0.254)
			(type default)
		)
		(layer "In8.Cu")
	)
	(gr_circle
		(center 97.76587 -180.704744)
		(end 98.64598 -180.704744)
		(stroke
			(width 0.2)
			(type default)
		)
		(fill no)
		(layer "In8.Cu")
	)
	(gr_line
		(start 97.97796 -279.758394)
		(end 97.507806 -280.5684)
		(stroke
			(width 0.254)
			(type default)
		)
		(layer "In8.Cu")
	)
	(gr_line
		(start 97.981008 -291.096192)
		(end 98.921062 -291.096192)
		(stroke
			(width 0.6096)
			(type default)
		)
		(layer "In8.Cu")
	)
	(gr_line
		(start 97.981008 -289.47618)
		(end 98.921062 -289.47618)
		(stroke
			(width 0.6096)
			(type default)
		)
		(layer "In8.Cu")
	)
	(gr_line
		(start 97.981008 -287.856422)
		(end 98.921062 -287.856422)
		(stroke
			(width 0.6096)
			(type default)
		)
		(layer "In8.Cu")
	)
	(gr_line
		(start 97.981008 -286.23641)
		(end 98.921062 -286.23641)
		(stroke
			(width 0.6096)
			(type default)
		)
		(layer "In8.Cu")
	)
	(gr_circle
		(center 98.08083 -338.626704)
		(end 98.96983 -338.626704)
		(stroke
			(width 0.2)
			(type default)
		)
		(fill no)
		(layer "In8.Cu")
	)
	(gr_circle
		(center 98.08083 -337.890104)
		(end 98.96983 -337.890104)
		(stroke
			(width 0.2)
			(type default)
		)
		(fill no)
		(layer "In8.Cu")
	)
	(gr_circle
		(center 98.199194 -339.358224)
		(end 99.088194 -339.358224)
		(stroke
			(width 0.2)
			(type default)
		)
		(fill no)
		(layer "In8.Cu")
	)
	(gr_circle
		(center 98.38309 -180.704744)
		(end 99.2632 -180.704744)
		(stroke
			(width 0.2)
			(type default)
		)
		(fill no)
		(layer "In8.Cu")
	)
	(gr_circle
		(center 98.605594 -337.450684)
		(end 99.494594 -337.450684)
		(stroke
			(width 0.2)
			(type default)
		)
		(fill no)
		(layer "In8.Cu")
	)
	(gr_line
		(start 98.621088 -247.724422)
		(end 97.681034 -247.724422)
		(stroke
			(width 0.6096)
			(type default)
		)
		(layer "In8.Cu")
	)
	(gr_line
		(start 98.621088 -246.10441)
		(end 97.681034 -246.10441)
		(stroke
			(width 0.6096)
			(type default)
		)
		(layer "In8.Cu")
	)
	(gr_line
		(start 98.621088 -244.484398)
		(end 97.681034 -244.484398)
		(stroke
			(width 0.6096)
			(type default)
		)
		(layer "In8.Cu")
	)
	(gr_circle
		(center 98.630994 -338.212684)
		(end 99.519994 -338.212684)
		(stroke
			(width 0.2)
			(type default)
		)
		(fill no)
		(layer "In8.Cu")
	)
	(gr_circle
		(center 98.747834 -339.736684)
		(end 99.636834 -339.736684)
		(stroke
			(width 0.2)
			(type default)
		)
		(fill no)
		(layer "In8.Cu")
	)
	(gr_circle
		(center 98.747834 -338.974684)
		(end 99.636834 -338.974684)
		(stroke
			(width 0.2)
			(type default)
		)
		(fill no)
		(layer "In8.Cu")
	)
	(gr_line
		(start 98.775774 -328.418952)
		(end 96.306386 -325.949564)
		(stroke
			(width 0.508)
			(type default)
		)
		(layer "In8.Cu")
	)
	(gr_line
		(start 98.921062 -284.616398)
		(end 97.981008 -284.616398)
		(stroke
			(width 0.6096)
			(type default)
		)
		(layer "In8.Cu")
	)
	(gr_line
		(start 98.921062 -282.996386)
		(end 97.981008 -282.996386)
		(stroke
			(width 0.6096)
			(type default)
		)
		(layer "In8.Cu")
	)
	(gr_line
		(start 98.921062 -281.376374)
		(end 97.981008 -281.376374)
		(stroke
			(width 0.6096)
			(type default)
		)
		(layer "In8.Cu")
	)
	(gr_line
		(start 99.08794 -248.532396)
		(end 97.677986 -249.342402)
		(stroke
			(width 0.254)
			(type default)
		)
		(layer "In8.Cu")
	)
	(gr_line
		(start 99.090988 -256.634488)
		(end 99.561142 -255.824482)
		(stroke
			(width 0.254)
			(type default)
		)
		(layer "In8.Cu")
	)
	(gr_line
		(start 99.387914 -267.608304)
		(end 97.507806 -267.608304)
		(stroke
			(width 0.254)
			(type default)
		)
		(layer "In8.Cu")
	)
	(gr_line
		(start 99.561142 -255.824482)
		(end 100.500942 -255.824482)
		(stroke
			(width 0.254)
			(type default)
		)
		(layer "In8.Cu")
	)
	(gr_line
		(start 99.857814 -266.798298)
		(end 99.387914 -267.608304)
		(stroke
			(width 0.254)
			(type default)
		)
		(layer "In8.Cu")
	)
	(gr_line
		(start 100.027994 -255.012444)
		(end 101.437948 -254.202438)
		(stroke
			(width 0.254)
			(type default)
		)
		(layer "In8.Cu")
	)
	(gr_line
		(start 100.027994 -253.392432)
		(end 101.437948 -252.582426)
		(stroke
			(width 0.254)
			(type default)
		)
		(layer "In8.Cu")
	)
	(gr_line
		(start 100.027994 -250.152408)
		(end 99.08794 -248.532396)
		(stroke
			(width 0.254)
			(type default)
		)
		(layer "In8.Cu")
	)
	(gr_line
		(start 100.327968 -265.988292)
		(end 99.857814 -266.798298)
		(stroke
			(width 0.254)
			(type default)
		)
		(layer "In8.Cu")
	)
	(gr_line
		(start 100.327968 -264.36828)
		(end 101.737922 -265.178286)
		(stroke
			(width 0.254)
			(type default)
		)
		(layer "In8.Cu")
	)
	(gr_line
		(start 100.47478 -190.999872)
		(end 78.573884 -190.999872)
		(stroke
			(width 0.508)
			(type default)
		)
		(layer "In8.Cu")
	)
	(gr_line
		(start 100.80117 -291.096192)
		(end 101.741224 -291.096192)
		(stroke
			(width 0.6096)
			(type default)
		)
		(layer "In8.Cu")
	)
	(gr_line
		(start 100.80117 -289.47618)
		(end 101.741224 -289.47618)
		(stroke
			(width 0.6096)
			(type default)
		)
		(layer "In8.Cu")
	)
	(gr_line
		(start 100.80117 -287.856422)
		(end 101.741224 -287.856422)
		(stroke
			(width 0.6096)
			(type default)
		)
		(layer "In8.Cu")
	)
	(gr_line
		(start 100.967794 -256.632456)
		(end 100.027994 -255.012444)
		(stroke
			(width 0.254)
			(type default)
		)
		(layer "In8.Cu")
	)
	(gr_line
		(start 100.967794 -256.632456)
		(end 102.855014 -257.930396)
		(stroke
			(width 0.254)
			(type default)
		)
		(layer "In8.Cu")
	)
	(gr_line
		(start 101.268022 -262.748268)
		(end 101.737922 -263.558274)
		(stroke
			(width 0.254)
			(type default)
		)
		(layer "In8.Cu")
	)
	(gr_line
		(start 101.268022 -261.128256)
		(end 101.737922 -261.938262)
		(stroke
			(width 0.254)
			(type default)
		)
		(layer "In8.Cu")
	)
	(gr_line
		(start 101.437948 -254.202438)
		(end 100.027994 -253.392432)
		(stroke
			(width 0.254)
			(type default)
		)
		(layer "In8.Cu")
	)
	(gr_line
		(start 101.437948 -252.582426)
		(end 101.907848 -251.77242)
		(stroke
			(width 0.254)
			(type default)
		)
		(layer "In8.Cu")
	)
	(gr_line
		(start 101.437948 -250.962414)
		(end 100.027994 -250.152408)
		(stroke
			(width 0.254)
			(type default)
		)
		(layer "In8.Cu")
	)
	(gr_line
		(start 101.440996 -247.724422)
		(end 100.500942 -247.724422)
		(stroke
			(width 0.6096)
			(type default)
		)
		(layer "In8.Cu")
	)
	(gr_line
		(start 101.440996 -246.10441)
		(end 100.500942 -246.10441)
		(stroke
			(width 0.6096)
			(type default)
		)
		(layer "In8.Cu")
	)
	(gr_line
		(start 101.440996 -244.484398)
		(end 100.500942 -244.484398)
		(stroke
			(width 0.6096)
			(type default)
		)
		(layer "In8.Cu")
	)
	(gr_line
		(start 101.737922 -266.798298)
		(end 100.327968 -265.988292)
		(stroke
			(width 0.254)
			(type default)
		)
		(layer "In8.Cu")
	)
	(gr_line
		(start 101.737922 -265.178286)
		(end 100.327968 -265.988292)
		(stroke
			(width 0.254)
			(type default)
		)
		(layer "In8.Cu")
	)
	(gr_line
		(start 101.737922 -263.558274)
		(end 100.327968 -264.36828)
		(stroke
			(width 0.254)
			(type default)
		)
		(layer "In8.Cu")
	)
	(gr_line
		(start 101.737922 -261.938262)
		(end 101.268022 -262.748268)
		(stroke
			(width 0.254)
			(type default)
		)
		(layer "In8.Cu")
	)
	(gr_line
		(start 101.741224 -286.23641)
		(end 100.80117 -286.23641)
		(stroke
			(width 0.6096)
			(type default)
		)
		(layer "In8.Cu")
	)
	(gr_line
		(start 101.741224 -284.616398)
		(end 100.80117 -284.616398)
		(stroke
			(width 0.6096)
			(type default)
		)
		(layer "In8.Cu")
	)
	(gr_line
		(start 101.741224 -282.996386)
		(end 100.80117 -282.996386)
		(stroke
			(width 0.6096)
			(type default)
		)
		(layer "In8.Cu")
	)
	(gr_line
		(start 101.741224 -281.376374)
		(end 100.80117 -281.376374)
		(stroke
			(width 0.6096)
			(type default)
		)
		(layer "In8.Cu")
	)
	(gr_line
		(start 101.907848 -251.77242)
		(end 101.437948 -250.962414)
		(stroke
			(width 0.254)
			(type default)
		)
		(layer "In8.Cu")
	)
	(gr_line
		(start 102.060756 -387.918452)
		(end 93.805248 -387.918452)
		(stroke
			(width 0.508)
			(type default)
		)
		(layer "In8.Cu")
	)
	(gr_line
		(start 102.181406 -383.53492)
		(end 102.461568 -383.815082)
		(stroke
			(width 0.508)
			(type default)
		)
		(layer "In8.Cu")
	)
	(gr_line
		(start 102.207822 -264.36828)
		(end 101.737922 -263.558274)
		(stroke
			(width 0.254)
			(type default)
		)
		(layer "In8.Cu")
	)
	(gr_line
		(start 102.279958 -267.340334)
		(end 101.737922 -266.798298)
		(stroke
			(width 0.254)
			(type default)
		)
		(layer "In8.Cu")
	)
	(gr_line
		(start 102.283768 -387.325108)
		(end 102.468934 -387.510274)
		(stroke
			(width 0.508)
			(type default)
		)
		(layer "In8.Cu")
	)
	(gr_line
		(start 102.283768 -386.689346)
		(end 102.283768 -387.325108)
		(stroke
			(width 0.508)
			(type default)
		)
		(layer "In8.Cu")
	)
	(gr_line
		(start 102.283768 -386.689346)
		(end 102.283768 -386.320538)
		(stroke
			(width 0.254)
			(type default)
		)
		(layer "In8.Cu")
	)
	(gr_line
		(start 102.283768 -386.320538)
		(end 102.461568 -386.142738)
		(stroke
			(width 0.254)
			(type default)
		)
		(layer "In8.Cu")
	)
	(gr_line
		(start 102.461568 -386.142738)
		(end 102.461568 -384.62077)
		(stroke
			(width 0.254)
			(type default)
		)
		(layer "In8.Cu")
	)
	(gr_line
		(start 102.461568 -383.815082)
		(end 102.461568 -384.62077)
		(stroke
			(width 0.508)
			(type default)
		)
		(layer "In8.Cu")
	)
	(gr_line
		(start 102.468934 -387.510274)
		(end 102.060756 -387.918452)
		(stroke
			(width 0.508)
			(type default)
		)
		(layer "In8.Cu")
	)
	(gr_line
		(start 102.677976 -267.340334)
		(end 102.279958 -267.340334)
		(stroke
			(width 0.254)
			(type default)
		)
		(layer "In8.Cu")
	)
	(gr_line
		(start 102.855014 -259.73024)
		(end 101.268022 -261.128256)
		(stroke
			(width 0.254)
			(type default)
		)
		(layer "In8.Cu")
	)
	(gr_line
		(start 102.855014 -257.930396)
		(end 102.855014 -259.73024)
		(stroke
			(width 0.254)
			(type default)
		)
		(layer "In8.Cu")
	)
	(gr_line
		(start 103.317802 -250.962414)
		(end 101.907848 -251.77242)
		(stroke
			(width 0.254)
			(type default)
		)
		(layer "In8.Cu")
	)
	(gr_line
		(start 103.61803 -266.798298)
		(end 102.677976 -267.340334)
		(stroke
			(width 0.254)
			(type default)
		)
		(layer "In8.Cu")
	)
	(gr_line
		(start 103.61803 -263.558274)
		(end 102.207822 -264.36828)
		(stroke
			(width 0.254)
			(type default)
		)
		(layer "In8.Cu")
	)
	(gr_line
		(start 103.621078 -291.096192)
		(end 104.561132 -291.096192)
		(stroke
			(width 0.6096)
			(type default)
		)
		(layer "In8.Cu")
	)
	(gr_line
		(start 103.621078 -289.47618)
		(end 104.561132 -289.47618)
		(stroke
			(width 0.6096)
			(type default)
		)
		(layer "In8.Cu")
	)
	(gr_line
		(start 103.621078 -287.856422)
		(end 104.561132 -287.856422)
		(stroke
			(width 0.6096)
			(type default)
		)
		(layer "In8.Cu")
	)
	(gr_circle
		(center 103.74503 -176.106074)
		(end 104.63403 -176.106074)
		(stroke
			(width 0.2)
			(type default)
		)
		(fill no)
		(layer "In8.Cu")
	)
	(gr_circle
		(center 103.74503 -175.369474)
		(end 104.63403 -175.369474)
		(stroke
			(width 0.2)
			(type default)
		)
		(fill no)
		(layer "In8.Cu")
	)
	(gr_circle
		(center 103.74503 -174.632874)
		(end 104.63403 -174.632874)
		(stroke
			(width 0.2)
			(type default)
		)
		(fill no)
		(layer "In8.Cu")
	)
	(gr_line
		(start 103.787956 -251.77242)
		(end 103.317802 -250.962414)
		(stroke
			(width 0.254)
			(type default)
		)
		(layer "In8.Cu")
	)
	(gr_line
		(start 103.886 -96.103948)
		(end 62.738 -96.103948)
		(stroke
			(width 0.508)
			(type default)
		)
		(layer "In8.Cu")
	)
	(gr_line
		(start 104.08793 -265.988292)
		(end 103.61803 -266.798298)
		(stroke
			(width 0.254)
			(type default)
		)
		(layer "In8.Cu")
	)
	(gr_line
		(start 104.23271 -152.836626)
		(end 94.873826 -162.19551)
		(stroke
			(width 0.508)
			(type default)
		)
		(layer "In8.Cu")
	)
	(gr_line
		(start 104.261158 -247.724422)
		(end 103.321104 -247.724422)
		(stroke
			(width 0.6096)
			(type default)
		)
		(layer "In8.Cu")
	)
	(gr_line
		(start 104.261158 -246.10441)
		(end 103.321104 -246.10441)
		(stroke
			(width 0.6096)
			(type default)
		)
		(layer "In8.Cu")
	)
	(gr_line
		(start 104.261158 -244.484398)
		(end 103.321104 -244.484398)
		(stroke
			(width 0.6096)
			(type default)
		)
		(layer "In8.Cu")
	)
	(gr_circle
		(center 104.27843 -174.988474)
		(end 105.16743 -174.988474)
		(stroke
			(width 0.2)
			(type default)
		)
		(fill no)
		(layer "In8.Cu")
	)
	(gr_circle
		(center 104.30383 -175.750474)
		(end 105.19283 -175.750474)
		(stroke
			(width 0.2)
			(type default)
		)
		(fill no)
		(layer "In8.Cu")
	)
	(gr_circle
		(center 104.420162 -341.927688)
		(end 105.300272 -341.927688)
		(stroke
			(width 0.2)
			(type default)
		)
		(fill no)
		(layer "In8.Cu")
	)
	(gr_line
		(start 104.421178 -187.053474)
		(end 100.47478 -190.999872)
		(stroke
			(width 0.508)
			(type default)
		)
		(layer "In8.Cu")
	)
	(gr_line
		(start 104.561132 -286.23641)
		(end 103.621078 -286.23641)
		(stroke
			(width 0.6096)
			(type default)
		)
		(layer "In8.Cu")
	)
	(gr_line
		(start 104.561132 -284.616398)
		(end 103.621078 -284.616398)
		(stroke
			(width 0.6096)
			(type default)
		)
		(layer "In8.Cu")
	)
	(gr_line
		(start 104.561132 -282.996386)
		(end 103.621078 -282.996386)
		(stroke
			(width 0.6096)
			(type default)
		)
		(layer "In8.Cu")
	)
	(gr_line
		(start 104.589834 -328.418952)
		(end 98.775774 -328.418952)
		(stroke
			(width 0.508)
			(type default)
		)
		(layer "In8.Cu")
	)
	(gr_circle
		(center 104.828594 -175.311054)
		(end 105.717594 -175.311054)
		(stroke
			(width 0.2)
			(type default)
		)
		(fill no)
		(layer "In8.Cu")
	)
	(gr_circle
		(center 104.828594 -174.574454)
		(end 105.717594 -174.574454)
		(stroke
			(width 0.2)
			(type default)
		)
		(fill no)
		(layer "In8.Cu")
	)
	(gr_circle
		(center 105.037382 -341.927688)
		(end 105.917492 -341.927688)
		(stroke
			(width 0.2)
			(type default)
		)
		(fill no)
		(layer "In8.Cu")
	)
	(gr_line
		(start 105.19791 -250.962414)
		(end 103.787956 -251.77242)
		(stroke
			(width 0.254)
			(type default)
		)
		(layer "In8.Cu")
	)
	(gr_circle
		(center 105.336848 -177.65776)
		(end 106.225848 -177.65776)
		(stroke
			(width 0.2)
			(type default)
		)
		(fill no)
		(layer "In8.Cu")
	)
	(gr_circle
		(center 105.336848 -176.92116)
		(end 106.225848 -176.92116)
		(stroke
			(width 0.2)
			(type default)
		)
		(fill no)
		(layer "In8.Cu")
	)
	(gr_line
		(start 105.408222 -327.600564)
		(end 104.589834 -328.418952)
		(stroke
			(width 0.508)
			(type default)
		)
		(layer "In8.Cu")
	)
	(gr_line
		(start 105.490772 -262.180324)
		(end 103.61803 -263.558274)
		(stroke
			(width 0.254)
			(type default)
		)
		(layer "In8.Cu")
	)
	(gr_line
		(start 105.497884 -266.798298)
		(end 104.08793 -265.988292)
		(stroke
			(width 0.254)
			(type default)
		)
		(layer "In8.Cu")
	)
	(gr_circle
		(center 105.53065 -176.183544)
		(end 106.41076 -176.183544)
		(stroke
			(width 0.2)
			(type default)
		)
		(fill no)
		(layer "In8.Cu")
	)
	(gr_line
		(start 105.605834 -327.600564)
		(end 131.818126 -327.600564)
		(stroke
			(width 0.508)
			(type default)
		)
		(layer "In8.Cu")
	)
	(gr_circle
		(center 105.654602 -341.927688)
		(end 106.534712 -341.927688)
		(stroke
			(width 0.2)
			(type default)
		)
		(fill no)
		(layer "In8.Cu")
	)
	(gr_line
		(start 105.66781 -251.77242)
		(end 105.19791 -250.962414)
		(stroke
			(width 0.254)
			(type default)
		)
		(layer "In8.Cu")
	)
	(gr_line
		(start 105.782364 -327.600564)
		(end 105.408222 -327.600564)
		(stroke
			(width 0.508)
			(type default)
		)
		(layer "In8.Cu")
	)
	(gr_circle
		(center 105.934002 -341.229442)
		(end 106.814112 -341.229442)
		(stroke
			(width 0.2)
			(type default)
		)
		(fill no)
		(layer "In8.Cu")
	)
	(gr_circle
		(center 105.934002 -340.492842)
		(end 106.814112 -340.492842)
		(stroke
			(width 0.2)
			(type default)
		)
		(fill no)
		(layer "In8.Cu")
	)
	(gr_line
		(start 105.968038 -267.608304)
		(end 105.497884 -266.798298)
		(stroke
			(width 0.254)
			(type default)
		)
		(layer "In8.Cu")
	)
	(gr_circle
		(center 106.14787 -176.183544)
		(end 107.02798 -176.183544)
		(stroke
			(width 0.2)
			(type default)
		)
		(fill no)
		(layer "In8.Cu")
	)
	(gr_circle
		(center 106.34345 -343.450164)
		(end 107.23245 -343.450164)
		(stroke
			(width 0.2)
			(type default)
		)
		(fill no)
		(layer "In8.Cu")
	)
	(gr_circle
		(center 106.34345 -342.713564)
		(end 107.23245 -342.713564)
		(stroke
			(width 0.2)
			(type default)
		)
		(fill no)
		(layer "In8.Cu")
	)
	(gr_line
		(start 106.348022 -261.323074)
		(end 105.490772 -262.180324)
		(stroke
			(width 0.254)
			(type default)
		)
		(layer "In8.Cu")
	)
	(gr_line
		(start 106.440986 -291.096192)
		(end 107.38104 -291.096192)
		(stroke
			(width 0.6096)
			(type default)
		)
		(layer "In8.Cu")
	)
	(gr_line
		(start 106.440986 -289.47618)
		(end 107.38104 -289.47618)
		(stroke
			(width 0.6096)
			(type default)
		)
		(layer "In8.Cu")
	)
	(gr_line
		(start 106.440986 -287.856422)
		(end 107.38104 -287.856422)
		(stroke
			(width 0.6096)
			(type default)
		)
		(layer "In8.Cu")
	)
	(gr_circle
		(center 106.76509 -176.183544)
		(end 107.6452 -176.183544)
		(stroke
			(width 0.2)
			(type default)
		)
		(fill no)
		(layer "In8.Cu")
	)
	(gr_line
		(start 106.856022 -143.076676)
		(end 113.67008 -143.076676)
		(stroke
			(width 0.508)
			(type default)
		)
		(layer "In8.Cu")
	)
	(gr_circle
		(center 106.98607 -342.540844)
		(end 107.87507 -342.540844)
		(stroke
			(width 0.2)
			(type default)
		)
		(fill no)
		(layer "In8.Cu")
	)
	(gr_circle
		(center 106.98607 -341.804244)
		(end 107.87507 -341.804244)
		(stroke
			(width 0.2)
			(type default)
		)
		(fill no)
		(layer "In8.Cu")
	)
	(gr_circle
		(center 107.01401 -343.986104)
		(end 107.90301 -343.986104)
		(stroke
			(width 0.2)
			(type default)
		)
		(fill no)
		(layer "In8.Cu")
	)
	(gr_circle
		(center 107.01401 -343.249504)
		(end 107.90301 -343.249504)
		(stroke
			(width 0.2)
			(type default)
		)
		(fill no)
		(layer "In8.Cu")
	)
	(gr_line
		(start 107.078018 -250.962414)
		(end 105.66781 -251.77242)
		(stroke
			(width 0.254)
			(type default)
		)
		(layer "In8.Cu")
	)
	(gr_line
		(start 107.081066 -247.724422)
		(end 106.141012 -247.724422)
		(stroke
			(width 0.6096)
			(type default)
		)
		(layer "In8.Cu")
	)
	(gr_line
		(start 107.081066 -246.10441)
		(end 106.141012 -246.10441)
		(stroke
			(width 0.6096)
			(type default)
		)
		(layer "In8.Cu")
	)
	(gr_line
		(start 107.081066 -244.484398)
		(end 106.141012 -244.484398)
		(stroke
			(width 0.6096)
			(type default)
		)
		(layer "In8.Cu")
	)
	(gr_line
		(start 107.377992 -266.798298)
		(end 105.968038 -267.608304)
		(stroke
			(width 0.254)
			(type default)
		)
		(layer "In8.Cu")
	)
	(gr_line
		(start 107.38104 -286.23641)
		(end 106.440986 -286.23641)
		(stroke
			(width 0.6096)
			(type default)
		)
		(layer "In8.Cu")
	)
	(gr_line
		(start 107.38104 -284.616398)
		(end 106.440986 -284.616398)
		(stroke
			(width 0.6096)
			(type default)
		)
		(layer "In8.Cu")
	)
	(gr_line
		(start 107.38104 -282.996386)
		(end 106.440986 -282.996386)
		(stroke
			(width 0.6096)
			(type default)
		)
		(layer "In8.Cu")
	)
	(gr_line
		(start 107.547918 -251.77242)
		(end 107.078018 -250.962414)
		(stroke
			(width 0.254)
			(type default)
		)
		(layer "In8.Cu")
	)
	(gr_line
		(start 107.847892 -265.988292)
		(end 107.377992 -266.798298)
		(stroke
			(width 0.254)
			(type default)
		)
		(layer "In8.Cu")
	)
	(gr_line
		(start 108.392976 -349.807784)
		(end 115.964208 -342.236552)
		(stroke
			(width 0.508)
			(type default)
		)
		(layer "In8.Cu")
	)
	(gr_line
		(start 108.790994 -290.286186)
		(end 109.731048 -290.286186)
		(stroke
			(width 0.6096)
			(type default)
		)
		(layer "In8.Cu")
	)
	(gr_line
		(start 108.790994 -288.666174)
		(end 109.731048 -288.666174)
		(stroke
			(width 0.6096)
			(type default)
		)
		(layer "In8.Cu")
	)
	(gr_line
		(start 108.790994 -287.046162)
		(end 109.731048 -287.046162)
		(stroke
			(width 0.6096)
			(type default)
		)
		(layer "In8.Cu")
	)
	(gr_line
		(start 108.957872 -250.962414)
		(end 107.547918 -251.77242)
		(stroke
			(width 0.254)
			(type default)
		)
		(layer "In8.Cu")
	)
	(gr_line
		(start 109.257846 -266.798298)
		(end 107.847892 -265.988292)
		(stroke
			(width 0.254)
			(type default)
		)
		(layer "In8.Cu")
	)
	(gr_line
		(start 109.428026 -250.152408)
		(end 108.957872 -250.962414)
		(stroke
			(width 0.254)
			(type default)
		)
		(layer "In8.Cu")
	)
	(gr_line
		(start 109.431074 -248.534428)
		(end 108.49102 -248.534428)
		(stroke
			(width 0.6096)
			(type default)
		)
		(layer "In8.Cu")
	)
	(gr_line
		(start 109.431074 -246.914416)
		(end 108.49102 -246.914416)
		(stroke
			(width 0.6096)
			(type default)
		)
		(layer "In8.Cu")
	)
	(gr_line
		(start 109.431074 -245.294404)
		(end 108.49102 -245.294404)
		(stroke
			(width 0.6096)
			(type default)
		)
		(layer "In8.Cu")
	)
	(gr_line
		(start 109.431074 -243.674392)
		(end 108.49102 -243.674392)
		(stroke
			(width 0.6096)
			(type default)
		)
		(layer "In8.Cu")
	)
	(gr_line
		(start 109.728 -267.608304)
		(end 109.257846 -266.798298)
		(stroke
			(width 0.254)
			(type default)
		)
		(layer "In8.Cu")
	)
	(gr_line
		(start 109.731048 -285.426404)
		(end 108.790994 -285.426404)
		(stroke
			(width 0.6096)
			(type default)
		)
		(layer "In8.Cu")
	)
	(gr_line
		(start 109.731048 -283.806392)
		(end 108.790994 -283.806392)
		(stroke
			(width 0.6096)
			(type default)
		)
		(layer "In8.Cu")
	)
	(gr_line
		(start 109.731048 -282.18638)
		(end 108.790994 -282.18638)
		(stroke
			(width 0.6096)
			(type default)
		)
		(layer "In8.Cu")
	)
	(gr_line
		(start 109.759496 -387.510274)
		(end 102.468934 -387.510274)
		(stroke
			(width 0.508)
			(type default)
		)
		(layer "In8.Cu")
	)
	(gr_circle
		(center 110.140496 -150.941786)
		(end 111.537496 -150.941786)
		(stroke
			(width 0.2)
			(type default)
		)
		(fill no)
		(layer "In8.Cu")
	)
	(gr_line
		(start 110.335568 -386.934202)
		(end 109.759496 -387.510274)
		(stroke
			(width 0.508)
			(type default)
		)
		(layer "In8.Cu")
	)
	(gr_line
		(start 110.335568 -384.090926)
		(end 110.335568 -386.934202)
		(stroke
			(width 0.508)
			(type default)
		)
		(layer "In8.Cu")
	)
	(gr_line
		(start 110.74908 -383.677414)
		(end 110.335568 -384.090926)
		(stroke
			(width 0.508)
			(type default)
		)
		(layer "In8.Cu")
	)
	(gr_line
		(start 110.83798 -250.962414)
		(end 109.428026 -250.152408)
		(stroke
			(width 0.254)
			(type default)
		)
		(layer "In8.Cu")
	)
	(gr_line
		(start 111.137954 -266.798298)
		(end 109.728 -267.608304)
		(stroke
			(width 0.254)
			(type default)
		)
		(layer "In8.Cu")
	)
	(gr_line
		(start 111.512858 -187.053474)
		(end 111.893858 -186.672474)
		(stroke
			(width 0.508)
			(type default)
		)
		(layer "In8.Cu")
	)
	(gr_line
		(start 111.893858 -187.434474)
		(end 111.512858 -187.053474)
		(stroke
			(width 0.508)
			(type default)
		)
		(layer "In8.Cu")
	)
	(gr_line
		(start 111.927386 -192.218564)
		(end 131.517898 -211.809076)
		(stroke
			(width 0.508)
			(type default)
		)
		(layer "In8.Cu")
	)
	(gr_line
		(start 111.927386 -187.053474)
		(end 104.421178 -187.053474)
		(stroke
			(width 0.508)
			(type default)
		)
		(layer "In8.Cu")
	)
	(gr_line
		(start 111.927386 -183.963564)
		(end 111.927386 -192.218564)
		(stroke
			(width 0.508)
			(type default)
		)
		(layer "In8.Cu")
	)
	(gr_circle
		(center 111.97463 -169.857674)
		(end 112.86363 -169.857674)
		(stroke
			(width 0.2)
			(type default)
		)
		(fill no)
		(layer "In8.Cu")
	)
	(gr_circle
		(center 111.97463 -169.121074)
		(end 112.86363 -169.121074)
		(stroke
			(width 0.2)
			(type default)
		)
		(fill no)
		(layer "In8.Cu")
	)
	(gr_circle
		(center 111.97463 -168.384474)
		(end 112.86363 -168.384474)
		(stroke
			(width 0.2)
			(type default)
		)
		(fill no)
		(layer "In8.Cu")
	)
	(gr_circle
		(center 112.50803 -168.740074)
		(end 113.39703 -168.740074)
		(stroke
			(width 0.2)
			(type default)
		)
		(fill no)
		(layer "In8.Cu")
	)
	(gr_circle
		(center 112.53343 -169.502074)
		(end 113.42243 -169.502074)
		(stroke
			(width 0.2)
			(type default)
		)
		(fill no)
		(layer "In8.Cu")
	)
	(gr_circle
		(center 113.058194 -169.062654)
		(end 113.947194 -169.062654)
		(stroke
			(width 0.2)
			(type default)
		)
		(fill no)
		(layer "In8.Cu")
	)
	(gr_circle
		(center 113.058194 -168.326054)
		(end 113.947194 -168.326054)
		(stroke
			(width 0.2)
			(type default)
		)
		(fill no)
		(layer "In8.Cu")
	)
	(gr_circle
		(center 113.591848 -171.33316)
		(end 114.480848 -171.33316)
		(stroke
			(width 0.2)
			(type default)
		)
		(fill no)
		(layer "In8.Cu")
	)
	(gr_circle
		(center 113.591848 -170.59656)
		(end 114.480848 -170.59656)
		(stroke
			(width 0.2)
			(type default)
		)
		(fill no)
		(layer "In8.Cu")
	)
	(gr_line
		(start 113.657888 -250.962414)
		(end 110.83798 -250.962414)
		(stroke
			(width 0.254)
			(type default)
		)
		(layer "In8.Cu")
	)
	(gr_line
		(start 113.67008 -143.076676)
		(end 115.1763 -144.582896)
		(stroke
			(width 0.508)
			(type default)
		)
		(layer "In8.Cu")
	)
	(gr_circle
		(center 113.76025 -169.935144)
		(end 114.64036 -169.935144)
		(stroke
			(width 0.2)
			(type default)
		)
		(fill no)
		(layer "In8.Cu")
	)
	(gr_line
		(start 113.957862 -266.798298)
		(end 111.137954 -266.798298)
		(stroke
			(width 0.254)
			(type default)
		)
		(layer "In8.Cu")
	)
	(gr_circle
		(center 114.37747 -169.935144)
		(end 115.25758 -169.935144)
		(stroke
			(width 0.2)
			(type default)
		)
		(fill no)
		(layer "In8.Cu")
	)
	(gr_line
		(start 114.424714 -285.426404)
		(end 115.364768 -285.426404)
		(stroke
			(width 0.6096)
			(type default)
		)
		(layer "In8.Cu")
	)
	(gr_line
		(start 114.424714 -283.806392)
		(end 115.364768 -283.806392)
		(stroke
			(width 0.6096)
			(type default)
		)
		(layer "In8.Cu")
	)
	(gr_line
		(start 114.424714 -282.18638)
		(end 115.364768 -282.18638)
		(stroke
			(width 0.6096)
			(type default)
		)
		(layer "In8.Cu")
	)
	(gr_circle
		(center 114.99469 -169.935144)
		(end 115.8748 -169.935144)
		(stroke
			(width 0.2)
			(type default)
		)
		(fill no)
		(layer "In8.Cu")
	)
	(gr_line
		(start 115.067842 -250.152408)
		(end 113.657888 -250.962414)
		(stroke
			(width 0.254)
			(type default)
		)
		(layer "In8.Cu")
	)
	(gr_line
		(start 115.1763 -146.67992)
		(end 115.7732 -147.27682)
		(stroke
			(width 0.508)
			(type default)
		)
		(layer "In8.Cu")
	)
	(gr_line
		(start 115.1763 -144.582896)
		(end 115.1763 -146.67992)
		(stroke
			(width 0.508)
			(type default)
		)
		(layer "In8.Cu")
	)
	(gr_line
		(start 115.367816 -265.988292)
		(end 113.957862 -266.798298)
		(stroke
			(width 0.254)
			(type default)
		)
		(layer "In8.Cu")
	)
	(gr_line
		(start 115.537996 -250.962414)
		(end 115.067842 -250.152408)
		(stroke
			(width 0.254)
			(type default)
		)
		(layer "In8.Cu")
	)
	(gr_line
		(start 115.7732 -147.27682)
		(end 121.17324 -147.27682)
		(stroke
			(width 0.508)
			(type default)
		)
		(layer "In8.Cu")
	)
	(gr_line
		(start 115.83797 -266.798298)
		(end 115.367816 -265.988292)
		(stroke
			(width 0.254)
			(type default)
		)
		(layer "In8.Cu")
	)
	(gr_line
		(start 115.964208 -342.236552)
		(end 132.236464 -342.236552)
		(stroke
			(width 0.508)
			(type default)
		)
		(layer "In8.Cu")
	)
	(gr_line
		(start 116.197888 -261.323074)
		(end 106.348022 -261.323074)
		(stroke
			(width 0.254)
			(type default)
		)
		(layer "In8.Cu")
	)
	(gr_circle
		(center 116.258594 -152.657556)
		(end 117.147594 -152.657556)
		(stroke
			(width 0.2)
			(type default)
		)
		(fill no)
		(layer "In8.Cu")
	)
	(gr_circle
		(center 116.258594 -152.022556)
		(end 117.147594 -152.022556)
		(stroke
			(width 0.2)
			(type default)
		)
		(fill no)
		(layer "In8.Cu")
	)
	(gr_line
		(start 116.545106 -261.670292)
		(end 116.197888 -261.323074)
		(stroke
			(width 0.254)
			(type default)
		)
		(layer "In8.Cu")
	)
	(gr_line
		(start 116.774722 -286.23641)
		(end 117.714776 -286.23641)
		(stroke
			(width 0.6096)
			(type default)
		)
		(layer "In8.Cu")
	)
	(gr_line
		(start 116.774722 -284.616398)
		(end 117.714776 -284.616398)
		(stroke
			(width 0.6096)
			(type default)
		)
		(layer "In8.Cu")
	)
	(gr_line
		(start 116.774722 -282.996386)
		(end 117.714776 -282.996386)
		(stroke
			(width 0.6096)
			(type default)
		)
		(layer "In8.Cu")
	)
	(gr_circle
		(center 116.893594 -152.657556)
		(end 117.782594 -152.657556)
		(stroke
			(width 0.2)
			(type default)
		)
		(fill no)
		(layer "In8.Cu")
	)
	(gr_circle
		(center 116.893594 -152.022556)
		(end 117.782594 -152.022556)
		(stroke
			(width 0.2)
			(type default)
		)
		(fill no)
		(layer "In8.Cu")
	)
	(gr_line
		(start 116.94795 -251.77242)
		(end 115.537996 -250.962414)
		(stroke
			(width 0.254)
			(type default)
		)
		(layer "In8.Cu")
	)
	(gr_line
		(start 117.247924 -267.608304)
		(end 115.83797 -266.798298)
		(stroke
			(width 0.254)
			(type default)
		)
		(layer "In8.Cu")
	)
	(gr_line
		(start 117.41785 -250.962414)
		(end 116.94795 -251.77242)
		(stroke
			(width 0.254)
			(type default)
		)
		(layer "In8.Cu")
	)
	(gr_circle
		(center 117.559074 -152.657556)
		(end 118.448074 -152.657556)
		(stroke
			(width 0.2)
			(type default)
		)
		(fill no)
		(layer "In8.Cu")
	)
	(gr_circle
		(center 117.559074 -152.022556)
		(end 118.448074 -152.022556)
		(stroke
			(width 0.2)
			(type default)
		)
		(fill no)
		(layer "In8.Cu")
	)
	(gr_line
		(start 117.717824 -266.798298)
		(end 117.247924 -267.608304)
		(stroke
			(width 0.254)
			(type default)
		)
		(layer "In8.Cu")
	)
	(gr_circle
		(center 118.194074 -152.657556)
		(end 119.083074 -152.657556)
		(stroke
			(width 0.2)
			(type default)
		)
		(fill no)
		(layer "In8.Cu")
	)
	(gr_circle
		(center 118.194074 -152.022556)
		(end 119.083074 -152.022556)
		(stroke
			(width 0.2)
			(type default)
		)
		(fill no)
		(layer "In8.Cu")
	)
	(gr_line
		(start 118.827804 -250.152408)
		(end 117.41785 -250.962414)
		(stroke
			(width 0.254)
			(type default)
		)
		(layer "In8.Cu")
	)
	(gr_circle
		(center 118.829074 -152.657556)
		(end 119.718074 -152.657556)
		(stroke
			(width 0.2)
			(type default)
		)
		(fill no)
		(layer "In8.Cu")
	)
	(gr_circle
		(center 118.829074 -152.022556)
		(end 119.718074 -152.022556)
		(stroke
			(width 0.2)
			(type default)
		)
		(fill no)
		(layer "In8.Cu")
	)
	(gr_line
		(start 119.127778 -265.988292)
		(end 117.717824 -266.798298)
		(stroke
			(width 0.254)
			(type default)
		)
		(layer "In8.Cu")
	)
	(gr_line
		(start 119.297958 -250.962414)
		(end 118.827804 -250.152408)
		(stroke
			(width 0.254)
			(type default)
		)
		(layer "In8.Cu")
	)
	(gr_circle
		(center 119.464074 -152.657556)
		(end 120.353074 -152.657556)
		(stroke
			(width 0.2)
			(type default)
		)
		(fill no)
		(layer "In8.Cu")
	)
	(gr_circle
		(center 119.464074 -152.022556)
		(end 120.353074 -152.022556)
		(stroke
			(width 0.2)
			(type default)
		)
		(fill no)
		(layer "In8.Cu")
	)
	(gr_line
		(start 119.59463 -286.23641)
		(end 120.534684 -286.23641)
		(stroke
			(width 0.6096)
			(type default)
		)
		(layer "In8.Cu")
	)
	(gr_line
		(start 119.59463 -284.616398)
		(end 120.534684 -284.616398)
		(stroke
			(width 0.6096)
			(type default)
		)
		(layer "In8.Cu")
	)
	(gr_line
		(start 119.59463 -282.996386)
		(end 120.534684 -282.996386)
		(stroke
			(width 0.6096)
			(type default)
		)
		(layer "In8.Cu")
	)
	(gr_line
		(start 119.597932 -266.798298)
		(end 119.127778 -265.988292)
		(stroke
			(width 0.254)
			(type default)
		)
		(layer "In8.Cu")
	)
	(gr_circle
		(center 120.25503 -163.126674)
		(end 121.14403 -163.126674)
		(stroke
			(width 0.2)
			(type default)
		)
		(fill no)
		(layer "In8.Cu")
	)
	(gr_circle
		(center 120.25503 -162.390074)
		(end 121.14403 -162.390074)
		(stroke
			(width 0.2)
			(type default)
		)
		(fill no)
		(layer "In8.Cu")
	)
	(gr_circle
		(center 120.25503 -161.653474)
		(end 121.14403 -161.653474)
		(stroke
			(width 0.2)
			(type default)
		)
		(fill no)
		(layer "In8.Cu")
	)
	(gr_line
		(start 120.270016 -261.670292)
		(end 116.545106 -261.670292)
		(stroke
			(width 0.254)
			(type default)
		)
		(layer "In8.Cu")
	)
	(gr_line
		(start 120.537986 -261.938262)
		(end 120.270016 -261.670292)
		(stroke
			(width 0.254)
			(type default)
		)
		(layer "In8.Cu")
	)
	(gr_line
		(start 120.707912 -251.77242)
		(end 119.297958 -250.962414)
		(stroke
			(width 0.254)
			(type default)
		)
		(layer "In8.Cu")
	)
	(gr_circle
		(center 120.78843 -162.009074)
		(end 121.67743 -162.009074)
		(stroke
			(width 0.2)
			(type default)
		)
		(fill no)
		(layer "In8.Cu")
	)
	(gr_line
		(start 120.79478 -383.677414)
		(end 110.74908 -383.677414)
		(stroke
			(width 0.508)
			(type default)
		)
		(layer "In8.Cu")
	)
	(gr_circle
		(center 120.81383 -162.771074)
		(end 121.70283 -162.771074)
		(stroke
			(width 0.2)
			(type default)
		)
		(fill no)
		(layer "In8.Cu")
	)
	(gr_line
		(start 121.007886 -267.608304)
		(end 119.597932 -266.798298)
		(stroke
			(width 0.254)
			(type default)
		)
		(layer "In8.Cu")
	)
	(gr_line
		(start 121.159524 -387.733286)
		(end 121.159524 -384.042158)
		(stroke
			(width 0.508)
			(type default)
		)
		(layer "In8.Cu")
	)
	(gr_line
		(start 121.159524 -384.042158)
		(end 120.79478 -383.677414)
		(stroke
			(width 0.508)
			(type default)
		)
		(layer "In8.Cu")
	)
	(gr_line
		(start 121.159524 -384.042158)
		(end 121.23166 -384.042158)
		(stroke
			(width 0.508)
			(type default)
		)
		(layer "In8.Cu")
	)
	(gr_line
		(start 121.17324 -147.27682)
		(end 121.65584 -146.79422)
		(stroke
			(width 0.508)
			(type default)
		)
		(layer "In8.Cu")
	)
	(gr_line
		(start 121.177812 -250.962414)
		(end 120.707912 -251.77242)
		(stroke
			(width 0.254)
			(type default)
		)
		(layer "In8.Cu")
	)
	(gr_line
		(start 121.23166 -384.042158)
		(end 121.796302 -383.477516)
		(stroke
			(width 0.508)
			(type default)
		)
		(layer "In8.Cu")
	)
	(gr_circle
		(center 121.338594 -162.331654)
		(end 122.227594 -162.331654)
		(stroke
			(width 0.2)
			(type default)
		)
		(fill no)
		(layer "In8.Cu")
	)
	(gr_circle
		(center 121.338594 -161.595054)
		(end 122.227594 -161.595054)
		(stroke
			(width 0.2)
			(type default)
		)
		(fill no)
		(layer "In8.Cu")
	)
	(gr_line
		(start 121.477786 -266.798298)
		(end 121.007886 -267.608304)
		(stroke
			(width 0.254)
			(type default)
		)
		(layer "In8.Cu")
	)
	(gr_line
		(start 121.642378 -388.21614)
		(end 121.159524 -387.733286)
		(stroke
			(width 0.508)
			(type default)
		)
		(layer "In8.Cu")
	)
	(gr_line
		(start 121.65584 -146.79422)
		(end 121.65584 -143.12646)
		(stroke
			(width 0.508)
			(type default)
		)
		(layer "In8.Cu")
	)
	(gr_line
		(start 121.65584 -143.12646)
		(end 123.258834 -141.523466)
		(stroke
			(width 0.508)
			(type default)
		)
		(layer "In8.Cu")
	)
	(gr_line
		(start 121.796302 -383.477516)
		(end 136.689338 -383.477516)
		(stroke
			(width 0.508)
			(type default)
		)
		(layer "In8.Cu")
	)
	(gr_circle
		(center 121.872248 -164.62756)
		(end 122.761248 -164.62756)
		(stroke
			(width 0.2)
			(type default)
		)
		(fill no)
		(layer "In8.Cu")
	)
	(gr_circle
		(center 121.872248 -163.89096)
		(end 122.761248 -163.89096)
		(stroke
			(width 0.2)
			(type default)
		)
		(fill no)
		(layer "In8.Cu")
	)
	(gr_line
		(start 121.94794 -262.748268)
		(end 120.537986 -261.938262)
		(stroke
			(width 0.254)
			(type default)
		)
		(layer "In8.Cu")
	)
	(gr_circle
		(center 122.04065 -163.204144)
		(end 122.92076 -163.204144)
		(stroke
			(width 0.2)
			(type default)
		)
		(fill no)
		(layer "In8.Cu")
	)
	(gr_line
		(start 122.414792 -286.23641)
		(end 123.354846 -286.23641)
		(stroke
			(width 0.6096)
			(type default)
		)
		(layer "In8.Cu")
	)
	(gr_line
		(start 122.414792 -284.616398)
		(end 123.354846 -284.616398)
		(stroke
			(width 0.6096)
			(type default)
		)
		(layer "In8.Cu")
	)
	(gr_line
		(start 122.414792 -282.996386)
		(end 123.354846 -282.996386)
		(stroke
			(width 0.6096)
			(type default)
		)
		(layer "In8.Cu")
	)
	(gr_line
		(start 122.414792 -281.376374)
		(end 123.354846 -281.376374)
		(stroke
			(width 0.6096)
			(type default)
		)
		(layer "In8.Cu")
	)
	(gr_line
		(start 122.41784 -261.938262)
		(end 121.94794 -262.748268)
		(stroke
			(width 0.254)
			(type default)
		)
		(layer "In8.Cu")
	)
	(gr_line
		(start 122.58802 -250.152408)
		(end 121.177812 -250.962414)
		(stroke
			(width 0.254)
			(type default)
		)
		(layer "In8.Cu")
	)
	(gr_circle
		(center 122.65787 -163.204144)
		(end 123.53798 -163.204144)
		(stroke
			(width 0.2)
			(type default)
		)
		(fill no)
		(layer "In8.Cu")
	)
	(gr_line
		(start 122.887994 -265.988292)
		(end 121.477786 -266.798298)
		(stroke
			(width 0.254)
			(type default)
		)
		(layer "In8.Cu")
	)
	(gr_line
		(start 123.05792 -250.962414)
		(end 122.58802 -250.152408)
		(stroke
			(width 0.254)
			(type default)
		)
		(layer "In8.Cu")
	)
	(gr_line
		(start 123.258834 -141.523466)
		(end 138.549126 -141.523466)
		(stroke
			(width 0.508)
			(type default)
		)
		(layer "In8.Cu")
	)
	(gr_circle
		(center 123.27509 -163.204144)
		(end 124.1552 -163.204144)
		(stroke
			(width 0.2)
			(type default)
		)
		(fill no)
		(layer "In8.Cu")
	)
	(gr_line
		(start 123.357894 -266.798298)
		(end 122.887994 -265.988292)
		(stroke
			(width 0.254)
			(type default)
		)
		(layer "In8.Cu")
	)
	(gr_line
		(start 123.827794 -262.748268)
		(end 122.41784 -261.938262)
		(stroke
			(width 0.254)
			(type default)
		)
		(layer "In8.Cu")
	)
	(gr_arc
		(start 124.102114 -11.780012)
		(mid 125.516325 -11.194227)
		(end 126.10211 -9.780016)
		(stroke
			(width 3.048)
			(type default)
		)
		(layer "In8.Cu")
	)
	(gr_line
		(start 124.457206 -388.21614)
		(end 121.642378 -388.21614)
		(stroke
			(width 0.508)
			(type default)
		)
		(layer "In8.Cu")
	)
	(gr_line
		(start 124.467874 -251.77242)
		(end 123.05792 -250.962414)
		(stroke
			(width 0.254)
			(type default)
		)
		(layer "In8.Cu")
	)
	(gr_line
		(start 124.767848 -267.608304)
		(end 123.357894 -266.798298)
		(stroke
			(width 0.254)
			(type default)
		)
		(layer "In8.Cu")
	)
	(gr_line
		(start 124.938028 -250.962414)
		(end 124.467874 -251.77242)
		(stroke
			(width 0.254)
			(type default)
		)
		(layer "In8.Cu")
	)
	(gr_line
		(start 125.2347 -284.616398)
		(end 126.174754 -284.616398)
		(stroke
			(width 0.6096)
			(type default)
		)
		(layer "In8.Cu")
	)
	(gr_line
		(start 125.2347 -282.996386)
		(end 126.174754 -282.996386)
		(stroke
			(width 0.6096)
			(type default)
		)
		(layer "In8.Cu")
	)
	(gr_line
		(start 125.2347 -281.376374)
		(end 126.174754 -281.376374)
		(stroke
			(width 0.6096)
			(type default)
		)
		(layer "In8.Cu")
	)
	(gr_line
		(start 125.238002 -266.798298)
		(end 124.767848 -267.608304)
		(stroke
			(width 0.254)
			(type default)
		)
		(layer "In8.Cu")
	)
	(gr_line
		(start 125.238002 -263.558274)
		(end 123.827794 -262.748268)
		(stroke
			(width 0.254)
			(type default)
		)
		(layer "In8.Cu")
	)
	(gr_line
		(start 125.707902 -262.748268)
		(end 125.238002 -263.558274)
		(stroke
			(width 0.254)
			(type default)
		)
		(layer "In8.Cu")
	)
	(gr_line
		(start 125.877828 -238.002318)
		(end 127.287782 -238.812324)
		(stroke
			(width 0.254)
			(type default)
		)
		(layer "In8.Cu")
	)
	(gr_line
		(start 126.100332 -386.573014)
		(end 124.457206 -388.21614)
		(stroke
			(width 0.508)
			(type default)
		)
		(layer "In8.Cu")
	)
	(gr_line
		(start 126.10211 -9.780016)
		(end 126.10211 -5.780024)
		(stroke
			(width 3.048)
			(type default)
		)
		(layer "In8.Cu")
	)
	(gr_line
		(start 126.177802 -279.758394)
		(end 127.58801 -278.948388)
		(stroke
			(width 0.254)
			(type default)
		)
		(layer "In8.Cu")
	)
	(gr_line
		(start 126.177802 -266.798298)
		(end 125.238002 -266.798298)
		(stroke
			(width 0.254)
			(type default)
		)
		(layer "In8.Cu")
	)
	(gr_line
		(start 126.347982 -250.152408)
		(end 124.938028 -250.962414)
		(stroke
			(width 0.254)
			(type default)
		)
		(layer "In8.Cu")
	)
	(gr_line
		(start 126.347982 -246.912384)
		(end 127.287782 -248.532396)
		(stroke
			(width 0.254)
			(type default)
		)
		(layer "In8.Cu")
	)
	(gr_line
		(start 126.347982 -243.67236)
		(end 127.287782 -245.292372)
		(stroke
			(width 0.254)
			(type default)
		)
		(layer "In8.Cu")
	)
	(gr_line
		(start 126.347982 -240.432336)
		(end 127.287782 -242.052348)
		(stroke
			(width 0.254)
			(type default)
		)
		(layer "In8.Cu")
	)
	(gr_line
		(start 126.347982 -235.5723)
		(end 126.817882 -236.382306)
		(stroke
			(width 0.254)
			(type default)
		)
		(layer "In8.Cu")
	)
	(gr_line
		(start 126.347982 -232.332276)
		(end 127.287782 -233.952288)
		(stroke
			(width 0.254)
			(type default)
		)
		(layer "In8.Cu")
	)
	(gr_line
		(start 126.347982 -230.712264)
		(end 126.817882 -231.52227)
		(stroke
			(width 0.254)
			(type default)
		)
		(layer "In8.Cu")
	)
	(gr_line
		(start 126.347982 -229.092252)
		(end 126.817882 -229.902258)
		(stroke
			(width 0.254)
			(type default)
		)
		(layer "In8.Cu")
	)
	(gr_line
		(start 126.426722 -169.464228)
		(end 111.927386 -183.963564)
		(stroke
			(width 0.508)
			(type default)
		)
		(layer "In8.Cu")
	)
	(gr_arc
		(start 126.601982 -5.279898)
		(mid 126.248489 -5.42646)
		(end 126.10211 -5.780024)
		(stroke
			(width 3.048)
			(type default)
		)
		(layer "In8.Cu")
	)
	(gr_line
		(start 126.601982 -5.279898)
		(end 194.20205 -5.279898)
		(stroke
			(width 3.048)
			(type default)
		)
		(layer "In8.Cu")
	)
	(gr_line
		(start 126.647956 -288.66846)
		(end 127.58801 -287.048448)
		(stroke
			(width 0.254)
			(type default)
		)
		(layer "In8.Cu")
	)
	(gr_line
		(start 126.647956 -285.428436)
		(end 127.58801 -283.808424)
		(stroke
			(width 0.254)
			(type default)
		)
		(layer "In8.Cu")
	)
	(gr_line
		(start 126.647956 -282.188412)
		(end 127.117856 -281.378406)
		(stroke
			(width 0.254)
			(type default)
		)
		(layer "In8.Cu")
	)
	(gr_line
		(start 126.647956 -277.328376)
		(end 127.58801 -275.708364)
		(stroke
			(width 0.254)
			(type default)
		)
		(layer "In8.Cu")
	)
	(gr_line
		(start 126.647956 -274.088352)
		(end 127.58801 -272.46834)
		(stroke
			(width 0.254)
			(type default)
		)
		(layer "In8.Cu")
	)
	(gr_line
		(start 126.647956 -270.848328)
		(end 127.58801 -269.228316)
		(stroke
			(width 0.254)
			(type default)
		)
		(layer "In8.Cu")
	)
	(gr_line
		(start 126.817882 -236.382306)
		(end 125.877828 -238.002318)
		(stroke
			(width 0.254)
			(type default)
		)
		(layer "In8.Cu")
	)
	(gr_line
		(start 126.817882 -231.52227)
		(end 126.347982 -232.332276)
		(stroke
			(width 0.254)
			(type default)
		)
		(layer "In8.Cu")
	)
	(gr_line
		(start 126.817882 -229.902258)
		(end 126.347982 -230.712264)
		(stroke
			(width 0.254)
			(type default)
		)
		(layer "In8.Cu")
	)
	(gr_line
		(start 126.817882 -228.282246)
		(end 126.347982 -229.092252)
		(stroke
			(width 0.254)
			(type default)
		)
		(layer "In8.Cu")
	)
	(gr_line
		(start 126.916434 -386.573014)
		(end 126.100332 -386.573014)
		(stroke
			(width 0.508)
			(type default)
		)
		(layer "In8.Cu")
	)
	(gr_line
		(start 127.117856 -281.378406)
		(end 126.177802 -279.758394)
		(stroke
			(width 0.254)
			(type default)
		)
		(layer "In8.Cu")
	)
	(gr_line
		(start 127.117856 -268.41831)
		(end 126.177802 -266.798298)
		(stroke
			(width 0.254)
			(type default)
		)
		(layer "In8.Cu")
	)
	(gr_line
		(start 127.117856 -263.558274)
		(end 125.707902 -262.748268)
		(stroke
			(width 0.254)
			(type default)
		)
		(layer "In8.Cu")
	)
	(gr_line
		(start 127.287782 -248.532396)
		(end 126.347982 -250.152408)
		(stroke
			(width 0.254)
			(type default)
		)
		(layer "In8.Cu")
	)
	(gr_line
		(start 127.287782 -245.292372)
		(end 126.347982 -246.912384)
		(stroke
			(width 0.254)
			(type default)
		)
		(layer "In8.Cu")
	)
	(gr_line
		(start 127.287782 -242.052348)
		(end 126.347982 -243.67236)
		(stroke
			(width 0.254)
			(type default)
		)
		(layer "In8.Cu")
	)
	(gr_line
		(start 127.287782 -238.812324)
		(end 126.347982 -240.432336)
		(stroke
			(width 0.254)
			(type default)
		)
		(layer "In8.Cu")
	)
	(gr_line
		(start 127.287782 -233.952288)
		(end 126.347982 -235.5723)
		(stroke
			(width 0.254)
			(type default)
		)
		(layer "In8.Cu")
	)
	(gr_line
		(start 127.58801 -290.288472)
		(end 126.647956 -288.66846)
		(stroke
			(width 0.254)
			(type default)
		)
		(layer "In8.Cu")
	)
	(gr_line
		(start 127.58801 -290.288472)
		(end 129.467864 -293.528242)
		(stroke
			(width 0.254)
			(type default)
		)
		(layer "In8.Cu")
	)
	(gr_line
		(start 127.58801 -287.048448)
		(end 126.647956 -285.428436)
		(stroke
			(width 0.254)
			(type default)
		)
		(layer "In8.Cu")
	)
	(gr_line
		(start 127.58801 -283.808424)
		(end 126.647956 -282.188412)
		(stroke
			(width 0.254)
			(type default)
		)
		(layer "In8.Cu")
	)
	(gr_line
		(start 127.58801 -278.948388)
		(end 126.647956 -277.328376)
		(stroke
			(width 0.254)
			(type default)
		)
		(layer "In8.Cu")
	)
	(gr_line
		(start 127.58801 -275.708364)
		(end 126.647956 -274.088352)
		(stroke
			(width 0.254)
			(type default)
		)
		(layer "In8.Cu")
	)
	(gr_line
		(start 127.58801 -272.46834)
		(end 126.647956 -270.848328)
		(stroke
			(width 0.254)
			(type default)
		)
		(layer "In8.Cu")
	)
	(gr_line
		(start 127.58801 -269.228316)
		(end 127.117856 -268.41831)
		(stroke
			(width 0.254)
			(type default)
		)
		(layer "In8.Cu")
	)
	(gr_line
		(start 127.58801 -262.748268)
		(end 127.117856 -263.558274)
		(stroke
			(width 0.254)
			(type default)
		)
		(layer "In8.Cu")
	)
	(gr_line
		(start 128.302004 -387.958584)
		(end 126.916434 -386.573014)
		(stroke
			(width 0.508)
			(type default)
		)
		(layer "In8.Cu")
	)
	(gr_line
		(start 128.463802 -169.464228)
		(end 126.426722 -169.464228)
		(stroke
			(width 0.508)
			(type default)
		)
		(layer "In8.Cu")
	)
	(gr_line
		(start 128.69799 -228.282246)
		(end 126.817882 -228.282246)
		(stroke
			(width 0.254)
			(type default)
		)
		(layer "In8.Cu")
	)
	(gr_circle
		(center 128.71323 -154.465274)
		(end 129.60223 -154.465274)
		(stroke
			(width 0.2)
			(type default)
		)
		(fill no)
		(layer "In8.Cu")
	)
	(gr_circle
		(center 128.71323 -153.728674)
		(end 129.60223 -153.728674)
		(stroke
			(width 0.2)
			(type default)
		)
		(fill no)
		(layer "In8.Cu")
	)
	(gr_circle
		(center 128.71323 -152.992074)
		(end 129.60223 -152.992074)
		(stroke
			(width 0.2)
			(type default)
		)
		(fill no)
		(layer "In8.Cu")
	)
	(gr_circle
		(center 129.24663 -153.347674)
		(end 130.13563 -153.347674)
		(stroke
			(width 0.2)
			(type default)
		)
		(fill no)
		(layer "In8.Cu")
	)
	(gr_circle
		(center 129.27203 -154.109674)
		(end 130.16103 -154.109674)
		(stroke
			(width 0.2)
			(type default)
		)
		(fill no)
		(layer "In8.Cu")
	)
	(gr_line
		(start 129.467864 -293.528242)
		(end 130.407918 -293.528242)
		(stroke
			(width 0.254)
			(type default)
		)
		(layer "In8.Cu")
	)
	(gr_circle
		(center 129.796794 -153.670254)
		(end 130.685794 -153.670254)
		(stroke
			(width 0.2)
			(type default)
		)
		(fill no)
		(layer "In8.Cu")
	)
	(gr_circle
		(center 129.796794 -152.933654)
		(end 130.685794 -152.933654)
		(stroke
			(width 0.2)
			(type default)
		)
		(fill no)
		(layer "In8.Cu")
	)
	(gr_line
		(start 129.885186 -168.042844)
		(end 128.463802 -169.464228)
		(stroke
			(width 0.508)
			(type default)
		)
		(layer "In8.Cu")
	)
	(gr_line
		(start 129.885186 -168.042844)
		(end 149.473666 -168.042844)
		(stroke
			(width 0.508)
			(type default)
		)
		(layer "In8.Cu")
	)
	(gr_circle
		(center 130.305048 -155.94076)
		(end 131.194048 -155.94076)
		(stroke
			(width 0.2)
			(type default)
		)
		(fill no)
		(layer "In8.Cu")
	)
	(gr_circle
		(center 130.305048 -155.20416)
		(end 131.194048 -155.20416)
		(stroke
			(width 0.2)
			(type default)
		)
		(fill no)
		(layer "In8.Cu")
	)
	(gr_line
		(start 130.407918 -293.528242)
		(end 131.347972 -295.148254)
		(stroke
			(width 0.254)
			(type default)
		)
		(layer "In8.Cu")
	)
	(gr_line
		(start 130.407918 -262.748268)
		(end 127.58801 -262.748268)
		(stroke
			(width 0.254)
			(type default)
		)
		(layer "In8.Cu")
	)
	(gr_line
		(start 130.416046 -122.633994)
		(end 103.886 -96.103948)
		(stroke
			(width 0.508)
			(type default)
		)
		(layer "In8.Cu")
	)
	(gr_circle
		(center 130.49885 -154.542744)
		(end 131.37896 -154.542744)
		(stroke
			(width 0.2)
			(type default)
		)
		(fill no)
		(layer "In8.Cu")
	)
	(gr_circle
		(center 131.11607 -154.542744)
		(end 131.99618 -154.542744)
		(stroke
			(width 0.2)
			(type default)
		)
		(fill no)
		(layer "In8.Cu")
	)
	(gr_line
		(start 131.231386 -327.600564)
		(end 131.818126 -327.600564)
		(stroke
			(width 0.508)
			(type default)
		)
		(layer "In8.Cu")
	)
	(gr_line
		(start 131.347972 -295.148254)
		(end 131.818126 -295.95826)
		(stroke
			(width 0.254)
			(type default)
		)
		(layer "In8.Cu")
	)
	(gr_line
		(start 131.517898 -223.422464)
		(end 128.69799 -228.282246)
		(stroke
			(width 0.254)
			(type default)
		)
		(layer "In8.Cu")
	)
	(gr_line
		(start 131.517898 -221.802452)
		(end 131.517898 -223.422464)
		(stroke
			(width 0.254)
			(type default)
		)
		(layer "In8.Cu")
	)
	(gr_line
		(start 131.517898 -211.809076)
		(end 131.517898 -221.802452)
		(stroke
			(width 0.508)
			(type default)
		)
		(layer "In8.Cu")
	)
	(gr_circle
		(center 131.73329 -154.542744)
		(end 132.6134 -154.542744)
		(stroke
			(width 0.2)
			(type default)
		)
		(fill no)
		(layer "In8.Cu")
	)
	(gr_line
		(start 131.817872 -263.558274)
		(end 130.407918 -262.748268)
		(stroke
			(width 0.254)
			(type default)
		)
		(layer "In8.Cu")
	)
	(gr_line
		(start 131.818126 -341.818214)
		(end 131.47802 -342.15832)
		(stroke
			(width 0.508)
			(type default)
		)
		(layer "In8.Cu")
	)
	(gr_line
		(start 131.818126 -327.600564)
		(end 131.818126 -341.818214)
		(stroke
			(width 0.508)
			(type default)
		)
		(layer "In8.Cu")
	)
	(gr_line
		(start 131.818126 -327.600564)
		(end 131.818126 -308.979824)
		(stroke
			(width 0.508)
			(type default)
		)
		(layer "In8.Cu")
	)
	(gr_line
		(start 131.818126 -327.013824)
		(end 131.231386 -327.600564)
		(stroke
			(width 0.508)
			(type default)
		)
		(layer "In8.Cu")
	)
	(gr_line
		(start 131.818126 -295.95826)
		(end 131.818126 -308.979824)
		(stroke
			(width 0.508)
			(type default)
		)
		(layer "In8.Cu")
	)
	(gr_line
		(start 132.236464 -342.236552)
		(end 131.818126 -341.818214)
		(stroke
			(width 0.508)
			(type default)
		)
		(layer "In8.Cu")
	)
	(gr_line
		(start 132.236464 -342.236552)
		(end 146.454114 -342.236552)
		(stroke
			(width 0.508)
			(type default)
		)
		(layer "In8.Cu")
	)
	(gr_line
		(start 135.653018 -152.836626)
		(end 104.23271 -152.836626)
		(stroke
			(width 0.508)
			(type default)
		)
		(layer "In8.Cu")
	)
	(gr_line
		(start 136.398 -167.985948)
		(end 136.398 -153.581608)
		(stroke
			(width 0.508)
			(type default)
		)
		(layer "In8.Cu")
	)
	(gr_line
		(start 136.398 -153.581608)
		(end 135.653018 -152.836626)
		(stroke
			(width 0.508)
			(type default)
		)
		(layer "In8.Cu")
	)
	(gr_line
		(start 136.517888 -263.558274)
		(end 131.817872 -263.558274)
		(stroke
			(width 0.254)
			(type default)
		)
		(layer "In8.Cu")
	)
	(gr_line
		(start 136.531858 -387.958584)
		(end 128.302004 -387.958584)
		(stroke
			(width 0.508)
			(type default)
		)
		(layer "In8.Cu")
	)
	(gr_line
		(start 136.689338 -383.477516)
		(end 137.033762 -383.82194)
		(stroke
			(width 0.508)
			(type default)
		)
		(layer "In8.Cu")
	)
	(gr_line
		(start 136.855962 -387.6167)
		(end 136.864852 -387.62559)
		(stroke
			(width 0.508)
			(type default)
		)
		(layer "In8.Cu")
	)
	(gr_line
		(start 136.855962 -386.689346)
		(end 136.855962 -387.6167)
		(stroke
			(width 0.508)
			(type default)
		)
		(layer "In8.Cu")
	)
	(gr_line
		(start 136.855962 -386.689346)
		(end 136.855962 -386.320538)
		(stroke
			(width 0.254)
			(type default)
		)
		(layer "In8.Cu")
	)
	(gr_line
		(start 136.855962 -386.320538)
		(end 137.033762 -386.142738)
		(stroke
			(width 0.254)
			(type default)
		)
		(layer "In8.Cu")
	)
	(gr_line
		(start 136.864852 -387.62559)
		(end 136.531858 -387.958584)
		(stroke
			(width 0.508)
			(type default)
		)
		(layer "In8.Cu")
	)
	(gr_line
		(start 136.988042 -264.36828)
		(end 136.517888 -263.558274)
		(stroke
			(width 0.254)
			(type default)
		)
		(layer "In8.Cu")
	)
	(gr_line
		(start 137.033762 -386.142738)
		(end 137.033762 -384.62077)
		(stroke
			(width 0.254)
			(type default)
		)
		(layer "In8.Cu")
	)
	(gr_line
		(start 137.033762 -384.62077)
		(end 137.033762 -383.82194)
		(stroke
			(width 0.508)
			(type default)
		)
		(layer "In8.Cu")
	)
	(gr_line
		(start 138.549126 -141.523466)
		(end 140.102336 -143.076676)
		(stroke
			(width 0.508)
			(type default)
		)
		(layer "In8.Cu")
	)
	(gr_line
		(start 138.588496 -387.62559)
		(end 136.864852 -387.62559)
		(stroke
			(width 0.508)
			(type default)
		)
		(layer "In8.Cu")
	)
	(gr_line
		(start 140.102336 -143.076676)
		(end 182.457598 -185.431938)
		(stroke
			(width 0.508)
			(type default)
		)
		(layer "In8.Cu")
	)
	(gr_line
		(start 140.222224 -385.991862)
		(end 138.588496 -387.62559)
		(stroke
			(width 0.508)
			(type default)
		)
		(layer "In8.Cu")
	)
	(gr_line
		(start 140.222224 -384.1369)
		(end 140.222224 -385.991862)
		(stroke
			(width 0.508)
			(type default)
		)
		(layer "In8.Cu")
	)
	(gr_line
		(start 141.01953 -383.339594)
		(end 140.222224 -384.1369)
		(stroke
			(width 0.508)
			(type default)
		)
		(layer "In8.Cu")
	)
	(gr_line
		(start 141.687804 -264.36828)
		(end 136.988042 -264.36828)
		(stroke
			(width 0.254)
			(type default)
		)
		(layer "In8.Cu")
	)
	(gr_line
		(start 143.098012 -266.798298)
		(end 141.687804 -264.36828)
		(stroke
			(width 0.254)
			(type default)
		)
		(layer "In8.Cu")
	)
	(gr_line
		(start 145.690844 -266.798298)
		(end 143.098012 -266.798298)
		(stroke
			(width 0.254)
			(type default)
		)
		(layer "In8.Cu")
	)
	(gr_line
		(start 146.454114 -342.236552)
		(end 193.797174 -342.236552)
		(stroke
			(width 0.508)
			(type default)
		)
		(layer "In8.Cu")
	)
	(gr_line
		(start 149.473666 -168.042844)
		(end 164.530786 -183.099964)
		(stroke
			(width 0.508)
			(type default)
		)
		(layer "In8.Cu")
	)
	(gr_line
		(start 153.72334 -387.74497)
		(end 153.72334 -383.490724)
		(stroke
			(width 0.508)
			(type default)
		)
		(layer "In8.Cu")
	)
	(gr_line
		(start 153.72334 -383.490724)
		(end 153.710132 -383.477516)
		(stroke
			(width 0.508)
			(type default)
		)
		(layer "In8.Cu")
	)
	(gr_line
		(start 154.297634 -388.319264)
		(end 153.72334 -387.74497)
		(stroke
			(width 0.508)
			(type default)
		)
		(layer "In8.Cu")
	)
	(gr_line
		(start 156.121862 -122.633994)
		(end 130.416046 -122.633994)
		(stroke
			(width 0.508)
			(type default)
		)
		(layer "In8.Cu")
	)
	(gr_line
		(start 157.044136 -388.319264)
		(end 154.297634 -388.319264)
		(stroke
			(width 0.508)
			(type default)
		)
		(layer "In8.Cu")
	)
	(gr_line
		(start 158.882588 -386.480812)
		(end 157.044136 -388.319264)
		(stroke
			(width 0.508)
			(type default)
		)
		(layer "In8.Cu")
	)
	(gr_line
		(start 159.434276 -386.480812)
		(end 158.882588 -386.480812)
		(stroke
			(width 0.508)
			(type default)
		)
		(layer "In8.Cu")
	)
	(gr_line
		(start 160.75025 -397.873728)
		(end 160.75025 -387.952996)
		(stroke
			(width 0.508)
			(type default)
		)
		(layer "In8.Cu")
	)
	(gr_line
		(start 160.75025 -387.952996)
		(end 160.75025 -387.796786)
		(stroke
			(width 0.508)
			(type default)
		)
		(layer "In8.Cu")
	)
	(gr_line
		(start 160.75025 -387.952996)
		(end 164.950902 -387.952996)
		(stroke
			(width 0.508)
			(type default)
		)
		(layer "In8.Cu")
	)
	(gr_line
		(start 160.75025 -387.796786)
		(end 159.434276 -386.480812)
		(stroke
			(width 0.508)
			(type default)
		)
		(layer "In8.Cu")
	)
	(gr_line
		(start 161.468816 -127.980948)
		(end 156.121862 -122.633994)
		(stroke
			(width 0.508)
			(type default)
		)
		(layer "In8.Cu")
	)
	(gr_line
		(start 163.546282 -413.779716)
		(end 165.123114 -412.202884)
		(stroke
			(width 0.508)
			(type default)
		)
		(layer "In8.Cu")
	)
	(gr_line
		(start 164.465 -194.401948)
		(end 164.973 -194.909948)
		(stroke
			(width 0.508)
			(type default)
		)
		(layer "In8.Cu")
	)
	(gr_line
		(start 164.530786 -266.386564)
		(end 164.187886 -266.729464)
		(stroke
			(width 0.508)
			(type default)
		)
		(layer "In8.Cu")
	)
	(gr_line
		(start 164.530786 -183.099964)
		(end 164.530786 -266.386564)
		(stroke
			(width 0.508)
			(type default)
		)
		(layer "In8.Cu")
	)
	(gr_line
		(start 164.846 -194.909948)
		(end 164.592 -195.163948)
		(stroke
			(width 0.508)
			(type default)
		)
		(layer "In8.Cu")
	)
	(gr_line
		(start 164.873686 -266.729464)
		(end 164.530786 -266.386564)
		(stroke
			(width 0.508)
			(type default)
		)
		(layer "In8.Cu")
	)
	(gr_line
		(start 164.950902 -387.952996)
		(end 166.28237 -389.284464)
		(stroke
			(width 0.508)
			(type default)
		)
		(layer "In8.Cu")
	)
	(gr_line
		(start 164.973 -194.909948)
		(end 164.846 -194.909948)
		(stroke
			(width 0.508)
			(type default)
		)
		(layer "In8.Cu")
	)
	(gr_line
		(start 164.973 -194.909948)
		(end 206.930752 -194.909948)
		(stroke
			(width 0.508)
			(type default)
		)
		(layer "In8.Cu")
	)
	(gr_line
		(start 165.123114 -412.202884)
		(end 165.123114 -402.246592)
		(stroke
			(width 0.508)
			(type default)
		)
		(layer "In8.Cu")
	)
	(gr_line
		(start 165.123114 -402.246592)
		(end 160.75025 -397.873728)
		(stroke
			(width 0.508)
			(type default)
		)
		(layer "In8.Cu")
	)
	(gr_line
		(start 166.28237 -389.284464)
		(end 168.764458 -389.284464)
		(stroke
			(width 0.508)
			(type default)
		)
		(layer "In8.Cu")
	)
	(gr_line
		(start 168.764458 -389.284464)
		(end 169.545762 -388.50316)
		(stroke
			(width 0.508)
			(type default)
		)
		(layer "In8.Cu")
	)
	(gr_line
		(start 169.051478 -383.339594)
		(end 141.01953 -383.339594)
		(stroke
			(width 0.508)
			(type default)
		)
		(layer "In8.Cu")
	)
	(gr_line
		(start 169.545762 -388.50316)
		(end 169.545762 -388.319518)
		(stroke
			(width 0.508)
			(type default)
		)
		(layer "In8.Cu")
	)
	(gr_line
		(start 169.545762 -388.319518)
		(end 169.545762 -383.833878)
		(stroke
			(width 0.508)
			(type default)
		)
		(layer "In8.Cu")
	)
	(gr_line
		(start 169.545762 -383.833878)
		(end 169.051478 -383.339594)
		(stroke
			(width 0.508)
			(type default)
		)
		(layer "In8.Cu")
	)
	(gr_line
		(start 170.556936 -389.330692)
		(end 169.545762 -388.319518)
		(stroke
			(width 0.508)
			(type default)
		)
		(layer "In8.Cu")
	)
	(gr_circle
		(center 170.995594 -404.792688)
		(end 173.154594 -404.792688)
		(stroke
			(width 4.318)
			(type default)
		)
		(fill no)
		(layer "In8.Cu")
	)
	(gr_circle
		(center 176.332134 -26.634948)
		(end 177.221134 -26.634948)
		(stroke
			(width 0.2)
			(type default)
		)
		(fill no)
		(layer "In8.Cu")
	)
	(gr_circle
		(center 176.713134 -25.949148)
		(end 177.602134 -25.949148)
		(stroke
			(width 0.2)
			(type default)
		)
		(fill no)
		(layer "In8.Cu")
	)
	(gr_circle
		(center 176.878234 -19.942048)
		(end 177.767234 -19.942048)
		(stroke
			(width 0.2)
			(type default)
		)
		(fill no)
		(layer "In8.Cu")
	)
	(gr_circle
		(center 176.968912 -21.349208)
		(end 177.857912 -21.349208)
		(stroke
			(width 0.2)
			(type default)
		)
		(fill no)
		(layer "In8.Cu")
	)
	(gr_circle
		(center 176.968912 -20.714208)
		(end 177.857912 -20.714208)
		(stroke
			(width 0.2)
			(type default)
		)
		(fill no)
		(layer "In8.Cu")
	)
	(gr_line
		(start 177.165 -29.936948)
		(end 202.819 -55.590948)
		(stroke
			(width 0.508)
			(type default)
		)
		(layer "In8.Cu")
	)
	(gr_circle
		(center 177.221134 -26.634948)
		(end 178.110134 -26.634948)
		(stroke
			(width 0.2)
			(type default)
		)
		(fill no)
		(layer "In8.Cu")
	)
	(gr_circle
		(center 177.472594 -21.85289)
		(end 178.361594 -21.85289)
		(stroke
			(width 0.2)
			(type default)
		)
		(fill no)
		(layer "In8.Cu")
	)
	(gr_circle
		(center 177.495454 -376.49658)
		(end 179.654454 -376.49658)
		(stroke
			(width 4.318)
			(type default)
		)
		(fill no)
		(layer "In8.Cu")
	)
	(gr_circle
		(center 177.602134 -25.949148)
		(end 178.491134 -25.949148)
		(stroke
			(width 0.2)
			(type default)
		)
		(fill no)
		(layer "In8.Cu")
	)
	(gr_circle
		(center 178.110134 -26.634948)
		(end 178.999134 -26.634948)
		(stroke
			(width 0.2)
			(type default)
		)
		(fill no)
		(layer "In8.Cu")
	)
	(gr_circle
		(center 178.491134 -25.949148)
		(end 179.380134 -25.949148)
		(stroke
			(width 0.2)
			(type default)
		)
		(fill no)
		(layer "In8.Cu")
	)
	(gr_circle
		(center 179.507134 -25.517348)
		(end 180.396134 -25.517348)
		(stroke
			(width 0.2)
			(type default)
		)
		(fill no)
		(layer "In8.Cu")
	)
	(gr_circle
		(center 180.921914 -27.107388)
		(end 181.810914 -27.107388)
		(stroke
			(width 0.2)
			(type default)
		)
		(fill no)
		(layer "In8.Cu")
	)
	(gr_line
		(start 181.47284 -389.330692)
		(end 170.556936 -389.330692)
		(stroke
			(width 0.508)
			(type default)
		)
		(layer "In8.Cu")
	)
	(gr_line
		(start 181.955948 -366.994186)
		(end 184.391808 -369.430046)
		(stroke
			(width 0.508)
			(type default)
		)
		(layer "In8.Cu")
	)
	(gr_line
		(start 182.457598 -185.431938)
		(end 205.629002 -185.431938)
		(stroke
			(width 0.508)
			(type default)
		)
		(layer "In8.Cu")
	)
	(gr_circle
		(center 183.610758 -353.283774)
		(end 184.490868 -353.283774)
		(stroke
			(width 0.2)
			(type default)
		)
		(fill no)
		(layer "In8.Cu")
	)
	(gr_circle
		(center 184.227978 -353.283774)
		(end 185.108088 -353.283774)
		(stroke
			(width 0.2)
			(type default)
		)
		(fill no)
		(layer "In8.Cu")
	)
	(gr_line
		(start 184.258458 -410.708348)
		(end 184.258458 -400.09572)
		(stroke
			(width 0.635)
			(type default)
		)
		(layer "In8.Cu")
	)
	(gr_line
		(start 184.258458 -400.09572)
		(end 184.463944 -399.890234)
		(stroke
			(width 0.635)
			(type default)
		)
		(layer "In8.Cu")
	)
	(gr_line
		(start 184.391808 -386.411724)
		(end 181.47284 -389.330692)
		(stroke
			(width 0.508)
			(type default)
		)
		(layer "In8.Cu")
	)
	(gr_line
		(start 184.391808 -369.430046)
		(end 184.391808 -386.411724)
		(stroke
			(width 0.508)
			(type default)
		)
		(layer "In8.Cu")
	)
	(gr_line
		(start 184.463944 -399.890234)
		(end 188.119004 -399.890234)
		(stroke
			(width 0.635)
			(type default)
		)
		(layer "In8.Cu")
	)
	(gr_line
		(start 184.8104 -411.26029)
		(end 184.258458 -410.708348)
		(stroke
			(width 0.635)
			(type default)
		)
		(layer "In8.Cu")
	)
	(gr_circle
		(center 184.845198 -353.283774)
		(end 185.725308 -353.283774)
		(stroke
			(width 0.2)
			(type default)
		)
		(fill no)
		(layer "In8.Cu")
	)
	(gr_circle
		(center 184.962292 -352.558604)
		(end 185.851292 -352.558604)
		(stroke
			(width 0.2)
			(type default)
		)
		(fill no)
		(layer "In8.Cu")
	)
	(gr_circle
		(center 184.962292 -351.822004)
		(end 185.851292 -351.822004)
		(stroke
			(width 0.2)
			(type default)
		)
		(fill no)
		(layer "In8.Cu")
	)
	(gr_circle
		(center 185.547254 -354.892864)
		(end 186.436254 -354.892864)
		(stroke
			(width 0.2)
			(type default)
		)
		(fill no)
		(layer "In8.Cu")
	)
	(gr_circle
		(center 185.547254 -354.156264)
		(end 186.436254 -354.156264)
		(stroke
			(width 0.2)
			(type default)
		)
		(fill no)
		(layer "In8.Cu")
	)
	(gr_circle
		(center 186.034172 -362.234988)
		(end 186.923172 -362.234988)
		(stroke
			(width 0.2)
			(type default)
		)
		(fill no)
		(layer "In8.Cu")
	)
	(gr_circle
		(center 186.034172 -361.472988)
		(end 186.923172 -361.472988)
		(stroke
			(width 0.2)
			(type default)
		)
		(fill no)
		(layer "In8.Cu")
	)
	(gr_circle
		(center 186.034172 -360.710988)
		(end 186.923172 -360.710988)
		(stroke
			(width 0.2)
			(type default)
		)
		(fill no)
		(layer "In8.Cu")
	)
	(gr_circle
		(center 186.072018 -353.716844)
		(end 186.961018 -353.716844)
		(stroke
			(width 0.2)
			(type default)
		)
		(fill no)
		(layer "In8.Cu")
	)
	(gr_circle
		(center 186.097418 -354.478844)
		(end 186.986418 -354.478844)
		(stroke
			(width 0.2)
			(type default)
		)
		(fill no)
		(layer "In8.Cu")
	)
	(gr_circle
		(center 186.630818 -354.834444)
		(end 187.519818 -354.834444)
		(stroke
			(width 0.2)
			(type default)
		)
		(fill no)
		(layer "In8.Cu")
	)
	(gr_circle
		(center 186.630818 -354.097844)
		(end 187.519818 -354.097844)
		(stroke
			(width 0.2)
			(type default)
		)
		(fill no)
		(layer "In8.Cu")
	)
	(gr_circle
		(center 186.630818 -353.361244)
		(end 187.519818 -353.361244)
		(stroke
			(width 0.2)
			(type default)
		)
		(fill no)
		(layer "In8.Cu")
	)
	(gr_circle
		(center 186.796172 -362.234988)
		(end 187.685172 -362.234988)
		(stroke
			(width 0.2)
			(type default)
		)
		(fill no)
		(layer "In8.Cu")
	)
	(gr_circle
		(center 186.796172 -361.472988)
		(end 187.685172 -361.472988)
		(stroke
			(width 0.2)
			(type default)
		)
		(fill no)
		(layer "In8.Cu")
	)
	(gr_circle
		(center 186.796172 -360.710988)
		(end 187.685172 -360.710988)
		(stroke
			(width 0.2)
			(type default)
		)
		(fill no)
		(layer "In8.Cu")
	)
	(gr_line
		(start 187.965334 -411.26029)
		(end 184.8104 -411.26029)
		(stroke
			(width 0.635)
			(type default)
		)
		(layer "In8.Cu")
	)
	(gr_line
		(start 188.119004 -399.890234)
		(end 188.303916 -400.075146)
		(stroke
			(width 0.635)
			(type default)
		)
		(layer "In8.Cu")
	)
	(gr_line
		(start 188.303916 -402.905976)
		(end 191.073786 -405.675846)
		(stroke
			(width 0.635)
			(type default)
		)
		(layer "In8.Cu")
	)
	(gr_line
		(start 188.303916 -400.075146)
		(end 188.303916 -402.905976)
		(stroke
			(width 0.635)
			(type default)
		)
		(layer "In8.Cu")
	)
	(gr_line
		(start 188.720222 -412.015178)
		(end 187.965334 -411.26029)
		(stroke
			(width 0.635)
			(type default)
		)
		(layer "In8.Cu")
	)
	(gr_circle
		(center 190.508636 -23.593552)
		(end 191.397636 -23.593552)
		(stroke
			(width 0.2)
			(type default)
		)
		(fill no)
		(layer "In8.Cu")
	)
	(gr_circle
		(center 190.508636 -22.856952)
		(end 191.397636 -22.856952)
		(stroke
			(width 0.2)
			(type default)
		)
		(fill no)
		(layer "In8.Cu")
	)
	(gr_line
		(start 191.073786 -405.675846)
		(end 195.418964 -405.675846)
		(stroke
			(width 0.635)
			(type default)
		)
		(layer "In8.Cu")
	)
	(gr_line
		(start 191.409066 -266.798298)
		(end 145.690844 -266.798298)
		(stroke
			(width 0.508)
			(type default)
		)
		(layer "In8.Cu")
	)
	(gr_circle
		(center 191.67983 -362.430568)
		(end 193.07683 -362.430568)
		(stroke
			(width 0.2)
			(type default)
		)
		(fill no)
		(layer "In8.Cu")
	)
	(gr_circle
		(center 191.927734 -13.106908)
		(end 192.816734 -13.106908)
		(stroke
			(width 0.2)
			(type default)
		)
		(fill no)
		(layer "In8.Cu")
	)
	(gr_circle
		(center 191.937386 -353.309174)
		(end 192.817496 -353.309174)
		(stroke
			(width 0.2)
			(type default)
		)
		(fill no)
		(layer "In8.Cu")
	)
	(gr_circle
		(center 192.461134 -16.416528)
		(end 193.350134 -16.416528)
		(stroke
			(width 0.2)
			(type default)
		)
		(fill no)
		(layer "In8.Cu")
	)
	(gr_circle
		(center 192.461134 -15.781528)
		(end 193.350134 -15.781528)
		(stroke
			(width 0.2)
			(type default)
		)
		(fill no)
		(layer "In8.Cu")
	)
	(gr_circle
		(center 192.554606 -353.309174)
		(end 193.434716 -353.309174)
		(stroke
			(width 0.2)
			(type default)
		)
		(fill no)
		(layer "In8.Cu")
	)
	(gr_circle
		(center 192.689734 -13.106908)
		(end 193.578734 -13.106908)
		(stroke
			(width 0.2)
			(type default)
		)
		(fill no)
		(layer "In8.Cu")
	)
	(gr_circle
		(center 193.096134 -16.416528)
		(end 193.985134 -16.416528)
		(stroke
			(width 0.2)
			(type default)
		)
		(fill no)
		(layer "In8.Cu")
	)
	(gr_circle
		(center 193.096134 -15.781528)
		(end 193.985134 -15.781528)
		(stroke
			(width 0.2)
			(type default)
		)
		(fill no)
		(layer "In8.Cu")
	)
	(gr_circle
		(center 193.171826 -353.309174)
		(end 194.051936 -353.309174)
		(stroke
			(width 0.2)
			(type default)
		)
		(fill no)
		(layer "In8.Cu")
	)
	(gr_circle
		(center 193.28892 -352.563684)
		(end 194.17792 -352.563684)
		(stroke
			(width 0.2)
			(type default)
		)
		(fill no)
		(layer "In8.Cu")
	)
	(gr_circle
		(center 193.28892 -351.827084)
		(end 194.17792 -351.827084)
		(stroke
			(width 0.2)
			(type default)
		)
		(fill no)
		(layer "In8.Cu")
	)
	(gr_circle
		(center 193.731134 -15.781528)
		(end 194.620134 -15.781528)
		(stroke
			(width 0.2)
			(type default)
		)
		(fill no)
		(layer "In8.Cu")
	)
	(gr_line
		(start 193.797174 -342.236552)
		(end 196.293994 -339.739732)
		(stroke
			(width 0.508)
			(type default)
		)
		(layer "In8.Cu")
	)
	(gr_circle
		(center 193.858134 -16.543528)
		(end 194.747134 -16.543528)
		(stroke
			(width 0.2)
			(type default)
		)
		(fill no)
		(layer "In8.Cu")
	)
	(gr_circle
		(center 193.873882 -354.918264)
		(end 194.762882 -354.918264)
		(stroke
			(width 0.2)
			(type default)
		)
		(fill no)
		(layer "In8.Cu")
	)
	(gr_circle
		(center 193.873882 -354.181664)
		(end 194.762882 -354.181664)
		(stroke
			(width 0.2)
			(type default)
		)
		(fill no)
		(layer "In8.Cu")
	)
	(gr_circle
		(center 194.398646 -353.742244)
		(end 195.287646 -353.742244)
		(stroke
			(width 0.2)
			(type default)
		)
		(fill no)
		(layer "In8.Cu")
	)
	(gr_circle
		(center 194.424046 -354.504244)
		(end 195.313046 -354.504244)
		(stroke
			(width 0.2)
			(type default)
		)
		(fill no)
		(layer "In8.Cu")
	)
	(gr_line
		(start 194.505072 -441.989972)
		(end 8.50011 -441.989972)
		(stroke
			(width 3.048)
			(type default)
		)
		(layer "In8.Cu")
	)
	(gr_arc
		(start 194.505072 -441.989972)
		(mid 194.858553 -441.843573)
		(end 195.004944 -441.4901)
		(stroke
			(width 3.048)
			(type default)
		)
		(layer "In8.Cu")
	)
	(gr_line
		(start 194.643502 -325.190612)
		(end 194.643502 -323.540882)
		(stroke
			(width 0.508)
			(type default)
		)
		(layer "In8.Cu")
	)
	(gr_line
		(start 194.643502 -323.540882)
		(end 196.293994 -321.89039)
		(stroke
			(width 0.508)
			(type default)
		)
		(layer "In8.Cu")
	)
	(gr_arc
		(start 194.701922 -9.780016)
		(mid 195.287707 -11.194227)
		(end 196.701918 -11.780012)
		(stroke
			(width 3.048)
			(type default)
		)
		(layer "In8.Cu")
	)
	(gr_arc
		(start 194.701922 -5.780024)
		(mid 194.555654 -5.42634)
		(end 194.20205 -5.279898)
		(stroke
			(width 3.048)
			(type default)
		)
		(layer "In8.Cu")
	)
	(gr_line
		(start 194.701922 -5.780024)
		(end 194.701922 -9.780016)
		(stroke
			(width 3.048)
			(type default)
		)
		(layer "In8.Cu")
	)
	(gr_circle
		(center 194.957446 -354.859844)
		(end 195.846446 -354.859844)
		(stroke
			(width 0.2)
			(type default)
		)
		(fill no)
		(layer "In8.Cu")
	)
	(gr_circle
		(center 194.957446 -354.123244)
		(end 195.846446 -354.123244)
		(stroke
			(width 0.2)
			(type default)
		)
		(fill no)
		(layer "In8.Cu")
	)
	(gr_circle
		(center 194.957446 -353.386644)
		(end 195.846446 -353.386644)
		(stroke
			(width 0.2)
			(type default)
		)
		(fill no)
		(layer "In8.Cu")
	)
	(gr_line
		(start 195.004944 -441.17006)
		(end 195.004944 -441.4901)
		(stroke
			(width 3.048)
			(type default)
		)
		(layer "In8.Cu")
	)
	(gr_line
		(start 195.270882 -412.015178)
		(end 188.720222 -412.015178)
		(stroke
			(width 0.635)
			(type default)
		)
		(layer "In8.Cu")
	)
	(gr_line
		(start 195.418964 -405.675846)
		(end 197.51167 -403.58314)
		(stroke
			(width 0.635)
			(type default)
		)
		(layer "In8.Cu")
	)
	(gr_arc
		(start 195.50507 -440.669934)
		(mid 195.151428 -440.816418)
		(end 195.004944 -441.17006)
		(stroke
			(width 3.048)
			(type default)
		)
		(layer "In8.Cu")
	)
	(gr_line
		(start 196.293994 -339.739732)
		(end 196.293994 -326.841104)
		(stroke
			(width 0.508)
			(type default)
		)
		(layer "In8.Cu")
	)
	(gr_line
		(start 196.293994 -326.841104)
		(end 194.643502 -325.190612)
		(stroke
			(width 0.508)
			(type default)
		)
		(layer "In8.Cu")
	)
	(gr_line
		(start 196.293994 -321.89039)
		(end 196.293994 -271.683226)
		(stroke
			(width 0.508)
			(type default)
		)
		(layer "In8.Cu")
	)
	(gr_line
		(start 196.293994 -271.683226)
		(end 191.409066 -266.798298)
		(stroke
			(width 0.508)
			(type default)
		)
		(layer "In8.Cu")
	)
	(gr_line
		(start 196.29755 -326.84466)
		(end 196.293994 -326.841104)
		(stroke
			(width 0.508)
			(type default)
		)
		(layer "In8.Cu")
	)
	(gr_line
		(start 196.432424 -421.71112)
		(end 196.432424 -413.17672)
		(stroke
			(width 0.635)
			(type default)
		)
		(layer "In8.Cu")
	)
	(gr_line
		(start 196.432424 -421.71112)
		(end 205.73746 -431.016156)
		(stroke
			(width 0.635)
			(type default)
		)
		(layer "In8.Cu")
	)
	(gr_line
		(start 196.432424 -413.17672)
		(end 195.270882 -412.015178)
		(stroke
			(width 0.635)
			(type default)
		)
		(layer "In8.Cu")
	)
	(gr_line
		(start 196.701918 -11.780012)
		(end 221.30004 -11.780012)
		(stroke
			(width 3.048)
			(type default)
		)
		(layer "In8.Cu")
	)
	(gr_line
		(start 197.51167 -403.58314)
		(end 197.51167 -400.104356)
		(stroke
			(width 0.635)
			(type default)
		)
		(layer "In8.Cu")
	)
	(gr_line
		(start 197.51167 -400.104356)
		(end 197.764146 -399.85188)
		(stroke
			(width 0.635)
			(type default)
		)
		(layer "In8.Cu")
	)
	(gr_line
		(start 197.764146 -399.85188)
		(end 201.33818 -399.85188)
		(stroke
			(width 0.635)
			(type default)
		)
		(layer "In8.Cu")
	)
	(gr_circle
		(center 198.160386 -37.328094)
		(end 199.049386 -37.328094)
		(stroke
			(width 0.2)
			(type default)
		)
		(fill no)
		(layer "In8.Cu")
	)
	(gr_circle
		(center 198.486014 -30.133798)
		(end 199.375014 -30.133798)
		(stroke
			(width 0.2)
			(type default)
		)
		(fill no)
		(layer "In8.Cu")
	)
	(gr_circle
		(center 198.836026 -37.965634)
		(end 199.725026 -37.965634)
		(stroke
			(width 0.2)
			(type default)
		)
		(fill no)
		(layer "In8.Cu")
	)
	(gr_circle
		(center 199.121014 -30.133798)
		(end 200.010014 -30.133798)
		(stroke
			(width 0.2)
			(type default)
		)
		(fill no)
		(layer "In8.Cu")
	)
	(gr_circle
		(center 199.435974 -30.720538)
		(end 200.324974 -30.720538)
		(stroke
			(width 0.2)
			(type default)
		)
		(fill no)
		(layer "In8.Cu")
	)
	(gr_circle
		(center 199.756014 -30.133798)
		(end 200.645014 -30.133798)
		(stroke
			(width 0.2)
			(type default)
		)
		(fill no)
		(layer "In8.Cu")
	)
	(gr_circle
		(center 200.070974 -30.720538)
		(end 200.959974 -30.720538)
		(stroke
			(width 0.2)
			(type default)
		)
		(fill no)
		(layer "In8.Cu")
	)
	(gr_circle
		(center 200.33234 -378.160534)
		(end 201.22134 -378.160534)
		(stroke
			(width 0.2)
			(type default)
		)
		(fill no)
		(layer "In8.Cu")
	)
	(gr_circle
		(center 200.391014 -30.133798)
		(end 201.280014 -30.133798)
		(stroke
			(width 0.2)
			(type default)
		)
		(fill no)
		(layer "In8.Cu")
	)
	(gr_circle
		(center 200.705974 -30.720538)
		(end 201.594974 -30.720538)
		(stroke
			(width 0.2)
			(type default)
		)
		(fill no)
		(layer "In8.Cu")
	)
	(gr_line
		(start 201.33818 -399.85188)
		(end 201.59853 -400.11223)
		(stroke
			(width 0.635)
			(type default)
		)
		(layer "In8.Cu")
	)
	(gr_circle
		(center 201.340974 -30.720538)
		(end 202.229974 -30.720538)
		(stroke
			(width 0.2)
			(type default)
		)
		(fill no)
		(layer "In8.Cu")
	)
	(gr_line
		(start 201.59853 -403.575266)
		(end 201.811636 -403.788372)
		(stroke
			(width 0.635)
			(type default)
		)
		(layer "In8.Cu")
	)
	(gr_line
		(start 201.59853 -400.11223)
		(end 201.59853 -403.575266)
		(stroke
			(width 0.635)
			(type default)
		)
		(layer "In8.Cu")
	)
	(gr_circle
		(center 201.745342 -346.583)
		(end 202.634342 -346.583)
		(stroke
			(width 0.2)
			(type default)
		)
		(fill no)
		(layer "In8.Cu")
	)
	(gr_circle
		(center 201.745342 -345.821)
		(end 202.634342 -345.821)
		(stroke
			(width 0.2)
			(type default)
		)
		(fill no)
		(layer "In8.Cu")
	)
	(gr_circle
		(center 201.745342 -344.8304)
		(end 202.634342 -344.8304)
		(stroke
			(width 0.2)
			(type default)
		)
		(fill no)
		(layer "In8.Cu")
	)
	(gr_circle
		(center 201.745342 -344.0684)
		(end 202.634342 -344.0684)
		(stroke
			(width 0.2)
			(type default)
		)
		(fill no)
		(layer "In8.Cu")
	)
	(gr_line
		(start 201.811636 -406.668732)
		(end 203.461112 -408.318208)
		(stroke
			(width 0.635)
			(type default)
		)
		(layer "In8.Cu")
	)
	(gr_line
		(start 201.811636 -403.788372)
		(end 201.811636 -406.668732)
		(stroke
			(width 0.635)
			(type default)
		)
		(layer "In8.Cu")
	)
	(gr_line
		(start 202.819 -55.590948)
		(end 253.238 -55.590948)
		(stroke
			(width 0.508)
			(type default)
		)
		(layer "In8.Cu")
	)
	(gr_line
		(start 203.461112 -408.318208)
		(end 205.948026 -408.318208)
		(stroke
			(width 0.635)
			(type default)
		)
		(layer "In8.Cu")
	)
	(gr_line
		(start 205.629002 -185.431938)
		(end 207.979772 -187.782708)
		(stroke
			(width 0.508)
			(type default)
		)
		(layer "In8.Cu")
	)
	(gr_line
		(start 205.73746 -435.231032)
		(end 207.302608 -436.79618)
		(stroke
			(width 0.635)
			(type default)
		)
		(layer "In8.Cu")
	)
	(gr_line
		(start 205.73746 -431.016156)
		(end 205.73746 -435.231032)
		(stroke
			(width 0.635)
			(type default)
		)
		(layer "In8.Cu")
	)
	(gr_line
		(start 205.948026 -408.318208)
		(end 207.991202 -406.275032)
		(stroke
			(width 0.635)
			(type default)
		)
		(layer "In8.Cu")
	)
	(gr_line
		(start 206.52486 -326.84466)
		(end 196.29755 -326.84466)
		(stroke
			(width 0.508)
			(type default)
		)
		(layer "In8.Cu")
	)
	(gr_line
		(start 206.930752 -194.909948)
		(end 207.117696 -194.723004)
		(stroke
			(width 0.508)
			(type default)
		)
		(layer "In8.Cu")
	)
	(gr_line
		(start 207.137 -326.23252)
		(end 206.52486 -326.84466)
		(stroke
			(width 0.508)
			(type default)
		)
		(layer "In8.Cu")
	)
	(gr_line
		(start 207.137 -195.925948)
		(end 207.137 -326.23252)
		(stroke
			(width 0.508)
			(type default)
		)
		(layer "In8.Cu")
	)
	(gr_line
		(start 207.137 -193.348102)
		(end 207.137 -195.925948)
		(stroke
			(width 0.508)
			(type default)
		)
		(layer "In8.Cu")
	)
	(gr_line
		(start 207.302608 -436.79618)
		(end 229.074472 -436.79618)
		(stroke
			(width 0.635)
			(type default)
		)
		(layer "In8.Cu")
	)
	(gr_line
		(start 207.979772 -192.50533)
		(end 207.137 -193.348102)
		(stroke
			(width 0.508)
			(type default)
		)
		(layer "In8.Cu")
	)
	(gr_line
		(start 207.979772 -187.782708)
		(end 207.979772 -192.50533)
		(stroke
			(width 0.508)
			(type default)
		)
		(layer "In8.Cu")
	)
	(gr_line
		(start 207.991202 -406.275032)
		(end 207.991202 -403.722586)
		(stroke
			(width 0.635)
			(type default)
		)
		(layer "In8.Cu")
	)
	(gr_line
		(start 207.991202 -403.722586)
		(end 208.17967 -403.534118)
		(stroke
			(width 0.635)
			(type default)
		)
		(layer "In8.Cu")
	)
	(gr_line
		(start 208.17967 -403.534118)
		(end 208.17967 -400.079464)
		(stroke
			(width 0.635)
			(type default)
		)
		(layer "In8.Cu")
	)
	(gr_line
		(start 208.17967 -400.079464)
		(end 208.42605 -399.833084)
		(stroke
			(width 0.635)
			(type default)
		)
		(layer "In8.Cu")
	)
	(gr_line
		(start 208.42605 -399.833084)
		(end 211.971128 -399.833084)
		(stroke
			(width 0.635)
			(type default)
		)
		(layer "In8.Cu")
	)
	(gr_circle
		(center 208.508854 -37.366448)
		(end 209.397854 -37.366448)
		(stroke
			(width 0.2)
			(type default)
		)
		(fill no)
		(layer "In8.Cu")
	)
	(gr_line
		(start 211.971128 -399.833084)
		(end 212.28304 -400.144996)
		(stroke
			(width 0.635)
			(type default)
		)
		(layer "In8.Cu")
	)
	(gr_line
		(start 212.28304 -403.63267)
		(end 212.414358 -403.763988)
		(stroke
			(width 0.635)
			(type default)
		)
		(layer "In8.Cu")
	)
	(gr_line
		(start 212.28304 -400.144996)
		(end 212.28304 -403.63267)
		(stroke
			(width 0.635)
			(type default)
		)
		(layer "In8.Cu")
	)
	(gr_line
		(start 212.414358 -406.410668)
		(end 214.347044 -408.343354)
		(stroke
			(width 0.635)
			(type default)
		)
		(layer "In8.Cu")
	)
	(gr_line
		(start 212.414358 -403.763988)
		(end 212.414358 -406.410668)
		(stroke
			(width 0.635)
			(type default)
		)
		(layer "In8.Cu")
	)
	(gr_circle
		(center 213.67496 -360.764074)
		(end 215.83396 -360.764074)
		(stroke
			(width 4.318)
			(type default)
		)
		(fill no)
		(layer "In8.Cu")
	)
	(gr_line
		(start 214.347044 -408.343354)
		(end 216.541604 -408.343354)
		(stroke
			(width 0.635)
			(type default)
		)
		(layer "In8.Cu")
	)
	(gr_line
		(start 216.541604 -408.343354)
		(end 218.667584 -406.217374)
		(stroke
			(width 0.635)
			(type default)
		)
		(layer "In8.Cu")
	)
	(gr_line
		(start 218.667584 -406.217374)
		(end 218.667584 -403.755606)
		(stroke
			(width 0.635)
			(type default)
		)
		(layer "In8.Cu")
	)
	(gr_line
		(start 218.667584 -403.755606)
		(end 218.839796 -403.583394)
		(stroke
			(width 0.635)
			(type default)
		)
		(layer "In8.Cu")
	)
	(gr_line
		(start 218.839796 -403.583394)
		(end 218.839796 -400.095974)
		(stroke
			(width 0.635)
			(type default)
		)
		(layer "In8.Cu")
	)
	(gr_line
		(start 218.839796 -400.095974)
		(end 219.045282 -399.890488)
		(stroke
			(width 0.635)
			(type default)
		)
		(layer "In8.Cu")
	)
	(gr_line
		(start 219.045282 -399.890488)
		(end 222.709232 -399.890488)
		(stroke
			(width 0.635)
			(type default)
		)
		(layer "In8.Cu")
	)
	(gr_line
		(start 222.709232 -399.890488)
		(end 222.906082 -400.087338)
		(stroke
			(width 0.635)
			(type default)
		)
		(layer "In8.Cu")
	)
	(gr_line
		(start 222.906082 -403.607778)
		(end 223.099122 -403.800818)
		(stroke
			(width 0.635)
			(type default)
		)
		(layer "In8.Cu")
	)
	(gr_line
		(start 222.906082 -400.087338)
		(end 222.906082 -403.607778)
		(stroke
			(width 0.635)
			(type default)
		)
		(layer "In8.Cu")
	)
	(gr_line
		(start 223.099122 -406.414732)
		(end 224.990406 -408.306016)
		(stroke
			(width 0.635)
			(type default)
		)
		(layer "In8.Cu")
	)
	(gr_line
		(start 223.099122 -403.800818)
		(end 223.099122 -406.414732)
		(stroke
			(width 0.635)
			(type default)
		)
		(layer "In8.Cu")
	)
	(gr_arc
		(start 223.300036 -34.120074)
		(mid 223.885821 -35.534285)
		(end 225.300032 -36.12007)
		(stroke
			(width 3.048)
			(type default)
		)
		(layer "In8.Cu")
	)
	(gr_arc
		(start 223.300036 -13.780008)
		(mid 222.714256 -12.365778)
		(end 221.30004 -11.780012)
		(stroke
			(width 3.048)
			(type default)
		)
		(layer "In8.Cu")
	)
	(gr_line
		(start 223.300036 -13.780008)
		(end 223.300036 -34.120074)
		(stroke
			(width 3.048)
			(type default)
		)
		(layer "In8.Cu")
	)
	(gr_line
		(start 224.990406 -408.306016)
		(end 227.218748 -408.306016)
		(stroke
			(width 0.635)
			(type default)
		)
		(layer "In8.Cu")
	)
	(gr_line
		(start 225.300032 -36.12007)
		(end 256.800096 -36.12007)
		(stroke
			(width 3.048)
			(type default)
		)
		(layer "In8.Cu")
	)
	(gr_line
		(start 227.218748 -408.306016)
		(end 229.331774 -406.19299)
		(stroke
			(width 0.635)
			(type default)
		)
		(layer "In8.Cu")
	)
	(gr_line
		(start 229.074472 -436.79618)
		(end 229.997 -435.873652)
		(stroke
			(width 0.635)
			(type default)
		)
		(layer "In8.Cu")
	)
	(gr_line
		(start 229.331774 -406.19299)
		(end 229.331774 -403.768052)
		(stroke
			(width 0.635)
			(type default)
		)
		(layer "In8.Cu")
	)
	(gr_line
		(start 229.331774 -403.768052)
		(end 229.516178 -403.583648)
		(stroke
			(width 0.635)
			(type default)
		)
		(layer "In8.Cu")
	)
	(gr_line
		(start 229.516178 -403.583648)
		(end 229.516178 -400.11223)
		(stroke
			(width 0.635)
			(type default)
		)
		(layer "In8.Cu")
	)
	(gr_line
		(start 229.516178 -400.11223)
		(end 229.746302 -399.882106)
		(stroke
			(width 0.635)
			(type default)
		)
		(layer "In8.Cu")
	)
	(gr_line
		(start 229.746302 -399.882106)
		(end 233.352594 -399.882106)
		(stroke
			(width 0.635)
			(type default)
		)
		(layer "In8.Cu")
	)
	(gr_line
		(start 229.997 -435.873652)
		(end 229.997 -422.180766)
		(stroke
			(width 0.635)
			(type default)
		)
		(layer "In8.Cu")
	)
	(gr_line
		(start 233.352594 -399.882106)
		(end 233.574336 -400.103848)
		(stroke
			(width 0.635)
			(type default)
		)
		(layer "In8.Cu")
	)
	(gr_line
		(start 233.574336 -403.673564)
		(end 233.820462 -403.91969)
		(stroke
			(width 0.635)
			(type default)
		)
		(layer "In8.Cu")
	)
	(gr_line
		(start 233.574336 -400.103848)
		(end 233.574336 -403.673564)
		(stroke
			(width 0.635)
			(type default)
		)
		(layer "In8.Cu")
	)
	(gr_line
		(start 233.820462 -404.855172)
		(end 234.522264 -405.556974)
		(stroke
			(width 0.635)
			(type default)
		)
		(layer "In8.Cu")
	)
	(gr_line
		(start 233.820462 -403.91969)
		(end 233.820462 -404.855172)
		(stroke
			(width 0.635)
			(type default)
		)
		(layer "In8.Cu")
	)
	(gr_line
		(start 234.522264 -405.556974)
		(end 238.715804 -405.556974)
		(stroke
			(width 0.635)
			(type default)
		)
		(layer "In8.Cu")
	)
	(gr_line
		(start 234.897676 -417.28009)
		(end 229.997 -422.180766)
		(stroke
			(width 0.635)
			(type default)
		)
		(layer "In8.Cu")
	)
	(gr_circle
		(center 237.629954 -44.025566)
		(end 238.518954 -44.025566)
		(stroke
			(width 0.2)
			(type default)
		)
		(fill no)
		(layer "In8.Cu")
	)
	(gr_circle
		(center 237.640114 -44.716446)
		(end 238.529114 -44.716446)
		(stroke
			(width 0.2)
			(type default)
		)
		(fill no)
		(layer "In8.Cu")
	)
	(gr_circle
		(center 238.292894 -44.802806)
		(end 239.181894 -44.802806)
		(stroke
			(width 0.2)
			(type default)
		)
		(fill no)
		(layer "In8.Cu")
	)
	(gr_circle
		(center 238.292894 -44.040806)
		(end 239.181894 -44.040806)
		(stroke
			(width 0.2)
			(type default)
		)
		(fill no)
		(layer "In8.Cu")
	)
	(gr_arc
		(start 238.695992 -393.003532)
		(mid 238.724179 -393.144586)
		(end 238.804196 -393.264136)
		(stroke
			(width 0.635)
			(type default)
		)
		(layer "In8.Cu")
	)
	(gr_line
		(start 238.695992 -384.337306)
		(end 238.695992 -393.003532)
		(stroke
			(width 0.635)
			(type default)
		)
		(layer "In8.Cu")
	)
	(gr_line
		(start 238.715804 -405.556974)
		(end 238.882682 -405.390096)
		(stroke
			(width 0.635)
			(type default)
		)
		(layer "In8.Cu")
	)
	(gr_line
		(start 238.752126 -384.198876)
		(end 238.695992 -384.337306)
		(stroke
			(width 0.635)
			(type default)
		)
		(layer "In8.Cu")
	)
	(gr_line
		(start 238.804196 -393.264136)
		(end 239.027716 -393.487656)
		(stroke
			(width 0.635)
			(type default)
		)
		(layer "In8.Cu")
	)
	(gr_line
		(start 238.805974 -384.146806)
		(end 238.752126 -384.198876)
		(stroke
			(width 0.635)
			(type default)
		)
		(layer "In8.Cu")
	)
	(gr_line
		(start 238.882682 -405.390096)
		(end 238.882682 -394.210794)
		(stroke
			(width 0.635)
			(type default)
		)
		(layer "In8.Cu")
	)
	(gr_line
		(start 238.882682 -394.210794)
		(end 279.615392 -394.210794)
		(stroke
			(width 0.635)
			(type default)
		)
		(layer "In8.Cu")
	)
	(gr_circle
		(center 238.943134 -44.802806)
		(end 239.832134 -44.802806)
		(stroke
			(width 0.2)
			(type default)
		)
		(fill no)
		(layer "In8.Cu")
	)
	(gr_circle
		(center 238.943134 -44.040806)
		(end 239.832134 -44.040806)
		(stroke
			(width 0.2)
			(type default)
		)
		(fill no)
		(layer "In8.Cu")
	)
	(gr_arc
		(start 239.027716 -393.487656)
		(mid 239.147257 -393.567682)
		(end 239.28832 -393.59586)
		(stroke
			(width 0.635)
			(type default)
		)
		(layer "In8.Cu")
	)
	(gr_line
		(start 239.281716 -383.671064)
		(end 238.805974 -384.146806)
		(stroke
			(width 0.635)
			(type default)
		)
		(layer "In8.Cu")
	)
	(gr_line
		(start 239.28832 -393.59586)
		(end 273.155664 -393.59586)
		(stroke
			(width 0.635)
			(type default)
		)
		(layer "In8.Cu")
	)
	(gr_arc
		(start 239.54232 -383.56286)
		(mid 239.401266 -383.591047)
		(end 239.281716 -383.671064)
		(stroke
			(width 0.635)
			(type default)
		)
		(layer "In8.Cu")
	)
	(gr_circle
		(center 239.578134 -44.802806)
		(end 240.467134 -44.802806)
		(stroke
			(width 0.2)
			(type default)
		)
		(fill no)
		(layer "In8.Cu")
	)
	(gr_circle
		(center 239.578134 -44.040806)
		(end 240.467134 -44.040806)
		(stroke
			(width 0.2)
			(type default)
		)
		(fill no)
		(layer "In8.Cu")
	)
	(gr_circle
		(center 240.213134 -44.802806)
		(end 241.102134 -44.802806)
		(stroke
			(width 0.2)
			(type default)
		)
		(fill no)
		(layer "In8.Cu")
	)
	(gr_circle
		(center 240.213134 -44.040806)
		(end 241.102134 -44.040806)
		(stroke
			(width 0.2)
			(type default)
		)
		(fill no)
		(layer "In8.Cu")
	)
	(gr_circle
		(center 240.893854 -44.830746)
		(end 241.782854 -44.830746)
		(stroke
			(width 0.2)
			(type default)
		)
		(fill no)
		(layer "In8.Cu")
	)
	(gr_circle
		(center 244.518942 -43.246802)
		(end 245.407942 -43.246802)
		(stroke
			(width 0.2)
			(type default)
		)
		(fill no)
		(layer "In8.Cu")
	)
	(gr_circle
		(center 244.518942 -42.611802)
		(end 245.407942 -42.611802)
		(stroke
			(width 0.2)
			(type default)
		)
		(fill no)
		(layer "In8.Cu")
	)
	(gr_circle
		(center 245.857522 -52.022502)
		(end 246.746522 -52.022502)
		(stroke
			(width 0.2)
			(type default)
		)
		(fill no)
		(layer "In8.Cu")
	)
	(gr_circle
		(center 246.873522 -52.022502)
		(end 247.762522 -52.022502)
		(stroke
			(width 0.2)
			(type default)
		)
		(fill no)
		(layer "In8.Cu")
	)
	(gr_circle
		(center 247.825514 -40.94988)
		(end 248.714514 -40.94988)
		(stroke
			(width 0.2)
			(type default)
		)
		(fill no)
		(layer "In8.Cu")
	)
	(gr_circle
		(center 247.840246 -51.320446)
		(end 248.729246 -51.320446)
		(stroke
			(width 0.2)
			(type default)
		)
		(fill no)
		(layer "In8.Cu")
	)
	(gr_circle
		(center 248.214134 -52.171346)
		(end 249.103134 -52.171346)
		(stroke
			(width 0.2)
			(type default)
		)
		(fill no)
		(layer "In8.Cu")
	)
	(gr_circle
		(center 248.881646 -51.320446)
		(end 249.770646 -51.320446)
		(stroke
			(width 0.2)
			(type default)
		)
		(fill no)
		(layer "In8.Cu")
	)
	(gr_circle
		(center 249.202448 -40.945816)
		(end 250.091448 -40.945816)
		(stroke
			(width 0.2)
			(type default)
		)
		(fill no)
		(layer "In8.Cu")
	)
	(gr_circle
		(center 249.905266 -51.349148)
		(end 250.794266 -51.349148)
		(stroke
			(width 0.2)
			(type default)
		)
		(fill no)
		(layer "In8.Cu")
	)
	(gr_circle
		(center 250.449334 -49.555146)
		(end 251.338334 -49.555146)
		(stroke
			(width 0.2)
			(type default)
		)
		(fill no)
		(layer "In8.Cu")
	)
	(gr_circle
		(center 250.779534 -52.222146)
		(end 251.668534 -52.222146)
		(stroke
			(width 0.2)
			(type default)
		)
		(fill no)
		(layer "In8.Cu")
	)
	(gr_circle
		(center 250.779534 -51.333146)
		(end 251.668534 -51.333146)
		(stroke
			(width 0.2)
			(type default)
		)
		(fill no)
		(layer "In8.Cu")
	)
	(gr_circle
		(center 250.779534 -50.444146)
		(end 251.668534 -50.444146)
		(stroke
			(width 0.2)
			(type default)
		)
		(fill no)
		(layer "In8.Cu")
	)
	(gr_circle
		(center 251.516134 -52.501546)
		(end 252.405134 -52.501546)
		(stroke
			(width 0.2)
			(type default)
		)
		(fill no)
		(layer "In8.Cu")
	)
	(gr_circle
		(center 251.516134 -51.612546)
		(end 252.405134 -51.612546)
		(stroke
			(width 0.2)
			(type default)
		)
		(fill no)
		(layer "In8.Cu")
	)
	(gr_circle
		(center 251.516134 -50.723546)
		(end 252.405134 -50.723546)
		(stroke
			(width 0.2)
			(type default)
		)
		(fill no)
		(layer "In8.Cu")
	)
	(gr_line
		(start 253.238 -55.590948)
		(end 254.127 -54.701948)
		(stroke
			(width 0.508)
			(type default)
		)
		(layer "In8.Cu")
	)
	(gr_line
		(start 254.127 -54.701948)
		(end 442.612526 -54.701948)
		(stroke
			(width 0.508)
			(type default)
		)
		(layer "In8.Cu")
	)
	(gr_circle
		(center 255.347978 -39.380922)
		(end 256.236978 -39.380922)
		(stroke
			(width 0.2)
			(type default)
		)
		(fill no)
		(layer "In8.Cu")
	)
	(gr_arc
		(start 256.800096 -36.12007)
		(mid 258.214307 -35.534285)
		(end 258.800092 -34.120074)
		(stroke
			(width 3.048)
			(type default)
		)
		(layer "In8.Cu")
	)
	(gr_circle
		(center 258.12496 -360.764074)
		(end 260.28396 -360.764074)
		(stroke
			(width 4.318)
			(type default)
		)
		(fill no)
		(layer "In8.Cu")
	)
	(gr_line
		(start 258.800092 -34.120074)
		(end 258.800092 -13.780008)
		(stroke
			(width 3.048)
			(type default)
		)
		(layer "In8.Cu")
	)
	(gr_arc
		(start 260.800088 -11.780012)
		(mid 259.385888 -12.365802)
		(end 258.800092 -13.780008)
		(stroke
			(width 3.048)
			(type default)
		)
		(layer "In8.Cu")
	)
	(gr_line
		(start 260.800088 -11.780012)
		(end 385.601972 -11.780012)
		(stroke
			(width 3.048)
			(type default)
		)
		(layer "In8.Cu")
	)
	(gr_line
		(start 263.830816 -335.218024)
		(end 263.830816 -194.53733)
		(stroke
			(width 0.508)
			(type default)
		)
		(layer "In8.Cu")
	)
	(gr_line
		(start 263.830816 -194.53733)
		(end 263.830816 -183.479948)
		(stroke
			(width 0.508)
			(type default)
		)
		(layer "In8.Cu")
	)
	(gr_line
		(start 263.830816 -194.53733)
		(end 264.416794 -193.951352)
		(stroke
			(width 0.508)
			(type default)
		)
		(layer "In8.Cu")
	)
	(gr_line
		(start 263.830816 -183.479948)
		(end 266.076684 -181.23408)
		(stroke
			(width 0.508)
			(type default)
		)
		(layer "In8.Cu")
	)
	(gr_line
		(start 264.10031 -335.487518)
		(end 263.830816 -335.218024)
		(stroke
			(width 0.508)
			(type default)
		)
		(layer "In8.Cu")
	)
	(gr_line
		(start 264.416794 -193.951352)
		(end 312.250328 -193.951352)
		(stroke
			(width 0.508)
			(type default)
		)
		(layer "In8.Cu")
	)
	(gr_line
		(start 266.076684 -181.23408)
		(end 291.808408 -181.23408)
		(stroke
			(width 0.508)
			(type default)
		)
		(layer "In8.Cu")
	)
	(gr_line
		(start 271.094962 -354.24491)
		(end 271.094962 -334.941418)
		(stroke
			(width 0.508)
			(type default)
		)
		(layer "In8.Cu")
	)
	(gr_line
		(start 271.094962 -334.941418)
		(end 271.094962 -227.143818)
		(stroke
			(width 0.508)
			(type default)
		)
		(layer "In8.Cu")
	)
	(gr_line
		(start 271.094962 -334.941418)
		(end 271.641062 -335.487518)
		(stroke
			(width 0.508)
			(type default)
		)
		(layer "In8.Cu")
	)
	(gr_line
		(start 271.270476 -226.968304)
		(end 325.372984 -226.968304)
		(stroke
			(width 0.508)
			(type default)
		)
		(layer "In8.Cu")
	)
	(gr_line
		(start 271.41043 -335.487518)
		(end 264.10031 -335.487518)
		(stroke
			(width 0.508)
			(type default)
		)
		(layer "In8.Cu")
	)
	(gr_line
		(start 271.41043 -335.487518)
		(end 271.145 -335.752948)
		(stroke
			(width 0.508)
			(type default)
		)
		(layer "In8.Cu")
	)
	(gr_line
		(start 272.19021 -417.28009)
		(end 234.897676 -417.28009)
		(stroke
			(width 0.635)
			(type default)
		)
		(layer "In8.Cu")
	)
	(gr_line
		(start 273.05 -356.199948)
		(end 271.094962 -354.24491)
		(stroke
			(width 0.508)
			(type default)
		)
		(layer "In8.Cu")
	)
	(gr_arc
		(start 273.155664 -393.59586)
		(mid 273.296718 -393.567673)
		(end 273.416268 -393.487656)
		(stroke
			(width 0.635)
			(type default)
		)
		(layer "In8.Cu")
	)
	(gr_line
		(start 273.296634 -127.980948)
		(end 161.468816 -127.980948)
		(stroke
			(width 0.508)
			(type default)
		)
		(layer "In8.Cu")
	)
	(gr_line
		(start 273.33067 -394.041884)
		(end 279.547066 -394.041884)
		(stroke
			(width 0.635)
			(type default)
		)
		(layer "In8.Cu")
	)
	(gr_line
		(start 273.416268 -393.487656)
		(end 273.893788 -393.010136)
		(stroke
			(width 0.635)
			(type default)
		)
		(layer "In8.Cu")
	)
	(gr_line
		(start 273.481546 -383.56286)
		(end 239.54232 -383.56286)
		(stroke
			(width 0.635)
			(type default)
		)
		(layer "In8.Cu")
	)
	(gr_line
		(start 273.619976 -383.618994)
		(end 273.481546 -383.56286)
		(stroke
			(width 0.635)
			(type default)
		)
		(layer "In8.Cu")
	)
	(gr_line
		(start 273.672046 -383.672842)
		(end 273.619976 -383.618994)
		(stroke
			(width 0.635)
			(type default)
		)
		(layer "In8.Cu")
	)
	(gr_arc
		(start 273.893788 -393.010136)
		(mid 273.97387 -392.890613)
		(end 274.001992 -392.749532)
		(stroke
			(width 0.635)
			(type default)
		)
		(layer "In8.Cu")
	)
	(gr_line
		(start 273.893788 -383.894584)
		(end 273.672046 -383.672842)
		(stroke
			(width 0.635)
			(type default)
		)
		(layer "In8.Cu")
	)
	(gr_line
		(start 274.001992 -392.749532)
		(end 274.001992 -384.155188)
		(stroke
			(width 0.635)
			(type default)
		)
		(layer "In8.Cu")
	)
	(gr_arc
		(start 274.001992 -384.155188)
		(mid 273.973805 -384.014134)
		(end 273.893788 -383.894584)
		(stroke
			(width 0.635)
			(type default)
		)
		(layer "In8.Cu")
	)
	(gr_line
		(start 274.123404 -393.697206)
		(end 279.133554 -393.697206)
		(stroke
			(width 0.635)
			(type default)
		)
		(layer "In8.Cu")
	)
	(gr_line
		(start 274.433792 -392.938762)
		(end 273.33067 -394.041884)
		(stroke
			(width 0.635)
			(type default)
		)
		(layer "In8.Cu")
	)
	(gr_line
		(start 274.433792 -392.938762)
		(end 274.50288 -392.869674)
		(stroke
			(width 0.635)
			(type default)
		)
		(layer "In8.Cu")
	)
	(gr_line
		(start 274.433792 -384.002788)
		(end 274.433792 -392.938762)
		(stroke
			(width 0.635)
			(type default)
		)
		(layer "In8.Cu")
	)
	(gr_line
		(start 274.50288 -392.869674)
		(end 279.110694 -392.869674)
		(stroke
			(width 0.635)
			(type default)
		)
		(layer "In8.Cu")
	)
	(gr_line
		(start 274.732496 -393.237466)
		(end 274.433792 -392.938762)
		(stroke
			(width 0.635)
			(type default)
		)
		(layer "In8.Cu")
	)
	(gr_line
		(start 274.778724 -392.605514)
		(end 274.192746 -392.019536)
		(stroke
			(width 0.635)
			(type default)
		)
		(layer "In8.Cu")
	)
	(gr_line
		(start 274.87372 -383.56286)
		(end 274.433792 -384.002788)
		(stroke
			(width 0.635)
			(type default)
		)
		(layer "In8.Cu")
	)
	(gr_line
		(start 274.875244 -127.980948)
		(end 272.509488 -127.980948)
		(stroke
			(width 0.508)
			(type default)
		)
		(layer "In8.Cu")
	)
	(gr_circle
		(center 276.112986 -348.704662)
		(end 276.993096 -348.704662)
		(stroke
			(width 0.2)
			(type default)
		)
		(fill no)
		(layer "In8.Cu")
	)
	(gr_line
		(start 276.314916 -440.669934)
		(end 195.50507 -440.669934)
		(stroke
			(width 3.048)
			(type default)
		)
		(layer "In8.Cu")
	)
	(gr_circle
		(center 276.730206 -348.704662)
		(end 277.610316 -348.704662)
		(stroke
			(width 0.2)
			(type default)
		)
		(fill no)
		(layer "In8.Cu")
	)
	(gr_line
		(start 276.815042 -441.4901)
		(end 276.815042 -441.17006)
		(stroke
			(width 3.048)
			(type default)
		)
		(layer "In8.Cu")
	)
	(gr_arc
		(start 276.815042 -441.4901)
		(mid 276.961452 -441.843558)
		(end 277.314914 -441.989972)
		(stroke
			(width 3.048)
			(type default)
		)
		(layer "In8.Cu")
	)
	(gr_arc
		(start 276.815042 -441.17006)
		(mid 276.668558 -440.816418)
		(end 276.314916 -440.669934)
		(stroke
			(width 3.048)
			(type default)
		)
		(layer "In8.Cu")
	)
	(gr_circle
		(center 277.347426 -348.704662)
		(end 278.227536 -348.704662)
		(stroke
			(width 0.2)
			(type default)
		)
		(fill no)
		(layer "In8.Cu")
	)
	(gr_circle
		(center 277.593806 -348.025212)
		(end 278.482806 -348.025212)
		(stroke
			(width 0.2)
			(type default)
		)
		(fill no)
		(layer "In8.Cu")
	)
	(gr_circle
		(center 277.593806 -347.288612)
		(end 278.482806 -347.288612)
		(stroke
			(width 0.2)
			(type default)
		)
		(fill no)
		(layer "In8.Cu")
	)
	(gr_circle
		(center 278.049482 -350.313752)
		(end 278.938482 -350.313752)
		(stroke
			(width 0.2)
			(type default)
		)
		(fill no)
		(layer "In8.Cu")
	)
	(gr_circle
		(center 278.049482 -349.577152)
		(end 278.938482 -349.577152)
		(stroke
			(width 0.2)
			(type default)
		)
		(fill no)
		(layer "In8.Cu")
	)
	(gr_circle
		(center 278.574246 -349.137732)
		(end 279.463246 -349.137732)
		(stroke
			(width 0.2)
			(type default)
		)
		(fill no)
		(layer "In8.Cu")
	)
	(gr_circle
		(center 278.599646 -349.899732)
		(end 279.488646 -349.899732)
		(stroke
			(width 0.2)
			(type default)
		)
		(fill no)
		(layer "In8.Cu")
	)
	(gr_line
		(start 278.892508 -393.237466)
		(end 274.732496 -393.237466)
		(stroke
			(width 0.635)
			(type default)
		)
		(layer "In8.Cu")
	)
	(gr_line
		(start 279.110694 -392.869674)
		(end 279.351994 -392.628374)
		(stroke
			(width 0.635)
			(type default)
		)
		(layer "In8.Cu")
	)
	(gr_circle
		(center 279.133046 -350.255332)
		(end 280.022046 -350.255332)
		(stroke
			(width 0.2)
			(type default)
		)
		(fill no)
		(layer "In8.Cu")
	)
	(gr_circle
		(center 279.133046 -349.518732)
		(end 280.022046 -349.518732)
		(stroke
			(width 0.2)
			(type default)
		)
		(fill no)
		(layer "In8.Cu")
	)
	(gr_circle
		(center 279.133046 -348.782132)
		(end 280.022046 -348.782132)
		(stroke
			(width 0.2)
			(type default)
		)
		(fill no)
		(layer "In8.Cu")
	)
	(gr_line
		(start 279.133554 -393.697206)
		(end 279.983946 -392.846814)
		(stroke
			(width 0.635)
			(type default)
		)
		(layer "In8.Cu")
	)
	(gr_line
		(start 279.329134 -392.605514)
		(end 274.778724 -392.605514)
		(stroke
			(width 0.635)
			(type default)
		)
		(layer "In8.Cu")
	)
	(gr_line
		(start 279.351994 -392.628374)
		(end 279.329134 -392.605514)
		(stroke
			(width 0.635)
			(type default)
		)
		(layer "In8.Cu")
	)
	(gr_line
		(start 279.547066 -394.041884)
		(end 280.477976 -393.110974)
		(stroke
			(width 0.635)
			(type default)
		)
		(layer "In8.Cu")
	)
	(gr_line
		(start 279.616408 -392.513566)
		(end 278.892508 -393.237466)
		(stroke
			(width 0.635)
			(type default)
		)
		(layer "In8.Cu")
	)
	(gr_line
		(start 279.616408 -383.780538)
		(end 279.616408 -392.513566)
		(stroke
			(width 0.635)
			(type default)
		)
		(layer "In8.Cu")
	)
	(gr_line
		(start 279.834086 -383.56286)
		(end 279.616408 -383.780538)
		(stroke
			(width 0.635)
			(type default)
		)
		(layer "In8.Cu")
	)
	(gr_arc
		(start 279.875996 -394.318998)
		(mid 279.756473 -394.238916)
		(end 279.615392 -394.210794)
		(stroke
			(width 0.635)
			(type default)
		)
		(layer "In8.Cu")
	)
	(gr_line
		(start 279.875996 -394.318998)
		(end 280.259536 -394.702538)
		(stroke
			(width 0.635)
			(type default)
		)
		(layer "In8.Cu")
	)
	(gr_line
		(start 279.983946 -392.846814)
		(end 279.983946 -383.781046)
		(stroke
			(width 0.635)
			(type default)
		)
		(layer "In8.Cu")
	)
	(gr_line
		(start 279.983946 -383.781046)
		(end 280.202132 -383.56286)
		(stroke
			(width 0.635)
			(type default)
		)
		(layer "In8.Cu")
	)
	(gr_line
		(start 280.202132 -383.56286)
		(end 274.87372 -383.56286)
		(stroke
			(width 0.635)
			(type default)
		)
		(layer "In8.Cu")
	)
	(gr_line
		(start 280.202132 -383.56286)
		(end 279.834086 -383.56286)
		(stroke
			(width 0.635)
			(type default)
		)
		(layer "In8.Cu")
	)
	(gr_line
		(start 280.36774 -409.10256)
		(end 272.19021 -417.28009)
		(stroke
			(width 0.635)
			(type default)
		)
		(layer "In8.Cu")
	)
	(gr_line
		(start 280.36774 -407.440384)
		(end 280.36774 -394.963142)
		(stroke
			(width 0.635)
			(type default)
		)
		(layer "In8.Cu")
	)
	(gr_arc
		(start 280.36774 -394.963142)
		(mid 280.339553 -394.822088)
		(end 280.259536 -394.702538)
		(stroke
			(width 0.635)
			(type default)
		)
		(layer "In8.Cu")
	)
	(gr_line
		(start 280.36774 -394.963142)
		(end 280.36774 -409.10256)
		(stroke
			(width 0.635)
			(type default)
		)
		(layer "In8.Cu")
	)
	(gr_line
		(start 280.477976 -393.110974)
		(end 280.477976 -383.838704)
		(stroke
			(width 0.635)
			(type default)
		)
		(layer "In8.Cu")
	)
	(gr_line
		(start 280.477976 -383.838704)
		(end 280.202132 -383.56286)
		(stroke
			(width 0.635)
			(type default)
		)
		(layer "In8.Cu")
	)
	(gr_line
		(start 280.9113 -393.283694)
		(end 279.875996 -394.318998)
		(stroke
			(width 0.635)
			(type default)
		)
		(layer "In8.Cu")
	)
	(gr_line
		(start 280.9113 -384.272028)
		(end 280.202132 -383.56286)
		(stroke
			(width 0.635)
			(type default)
		)
		(layer "In8.Cu")
	)
	(gr_line
		(start 280.9113 -384.272028)
		(end 280.9113 -393.283694)
		(stroke
			(width 0.635)
			(type default)
		)
		(layer "In8.Cu")
	)
	(gr_circle
		(center 284.393386 -348.704662)
		(end 285.273496 -348.704662)
		(stroke
			(width 0.2)
			(type default)
		)
		(fill no)
		(layer "In8.Cu")
	)
	(gr_circle
		(center 285.010606 -348.704662)
		(end 285.890716 -348.704662)
		(stroke
			(width 0.2)
			(type default)
		)
		(fill no)
		(layer "In8.Cu")
	)
	(gr_circle
		(center 285.627826 -348.704662)
		(end 286.507936 -348.704662)
		(stroke
			(width 0.2)
			(type default)
		)
		(fill no)
		(layer "In8.Cu")
	)
	(gr_circle
		(center 285.869126 -347.982032)
		(end 286.758126 -347.982032)
		(stroke
			(width 0.2)
			(type default)
		)
		(fill no)
		(layer "In8.Cu")
	)
	(gr_circle
		(center 285.869126 -347.245432)
		(end 286.758126 -347.245432)
		(stroke
			(width 0.2)
			(type default)
		)
		(fill no)
		(layer "In8.Cu")
	)
	(gr_circle
		(center 286.329882 -350.313752)
		(end 287.218882 -350.313752)
		(stroke
			(width 0.2)
			(type default)
		)
		(fill no)
		(layer "In8.Cu")
	)
	(gr_circle
		(center 286.329882 -349.577152)
		(end 287.218882 -349.577152)
		(stroke
			(width 0.2)
			(type default)
		)
		(fill no)
		(layer "In8.Cu")
	)
	(gr_circle
		(center 286.36595 -355.279198)
		(end 287.25495 -355.279198)
		(stroke
			(width 0.2)
			(type default)
		)
		(fill no)
		(layer "In8.Cu")
	)
	(gr_circle
		(center 286.37611 -356.584758)
		(end 287.26511 -356.584758)
		(stroke
			(width 0.2)
			(type default)
		)
		(fill no)
		(layer "In8.Cu")
	)
	(gr_circle
		(center 286.37611 -355.949758)
		(end 287.26511 -355.949758)
		(stroke
			(width 0.2)
			(type default)
		)
		(fill no)
		(layer "In8.Cu")
	)
	(gr_circle
		(center 286.854646 -349.137732)
		(end 287.743646 -349.137732)
		(stroke
			(width 0.2)
			(type default)
		)
		(fill no)
		(layer "In8.Cu")
	)
	(gr_circle
		(center 286.880046 -349.899732)
		(end 287.769046 -349.899732)
		(stroke
			(width 0.2)
			(type default)
		)
		(fill no)
		(layer "In8.Cu")
	)
	(gr_circle
		(center 287.00095 -355.279198)
		(end 287.88995 -355.279198)
		(stroke
			(width 0.2)
			(type default)
		)
		(fill no)
		(layer "In8.Cu")
	)
	(gr_circle
		(center 287.01111 -356.584758)
		(end 287.90011 -356.584758)
		(stroke
			(width 0.2)
			(type default)
		)
		(fill no)
		(layer "In8.Cu")
	)
	(gr_circle
		(center 287.01111 -355.949758)
		(end 287.90011 -355.949758)
		(stroke
			(width 0.2)
			(type default)
		)
		(fill no)
		(layer "In8.Cu")
	)
	(gr_circle
		(center 287.413446 -350.255332)
		(end 288.302446 -350.255332)
		(stroke
			(width 0.2)
			(type default)
		)
		(fill no)
		(layer "In8.Cu")
	)
	(gr_circle
		(center 287.413446 -349.518732)
		(end 288.302446 -349.518732)
		(stroke
			(width 0.2)
			(type default)
		)
		(fill no)
		(layer "In8.Cu")
	)
	(gr_circle
		(center 287.413446 -348.782132)
		(end 288.302446 -348.782132)
		(stroke
			(width 0.2)
			(type default)
		)
		(fill no)
		(layer "In8.Cu")
	)
	(gr_circle
		(center 287.63595 -355.279198)
		(end 288.52495 -355.279198)
		(stroke
			(width 0.2)
			(type default)
		)
		(fill no)
		(layer "In8.Cu")
	)
	(gr_circle
		(center 287.64611 -356.584758)
		(end 288.53511 -356.584758)
		(stroke
			(width 0.2)
			(type default)
		)
		(fill no)
		(layer "In8.Cu")
	)
	(gr_circle
		(center 287.64611 -355.949758)
		(end 288.53511 -355.949758)
		(stroke
			(width 0.2)
			(type default)
		)
		(fill no)
		(layer "In8.Cu")
	)
	(gr_line
		(start 288.036508 -398.662398)
		(end 289.207194 -399.833084)
		(stroke
			(width 0.508)
			(type default)
		)
		(layer "In8.Cu")
	)
	(gr_line
		(start 288.036508 -376.830082)
		(end 288.036508 -398.662398)
		(stroke
			(width 0.508)
			(type default)
		)
		(layer "In8.Cu")
	)
	(gr_circle
		(center 288.27095 -355.279198)
		(end 289.15995 -355.279198)
		(stroke
			(width 0.2)
			(type default)
		)
		(fill no)
		(layer "In8.Cu")
	)
	(gr_circle
		(center 288.28111 -356.584758)
		(end 289.17011 -356.584758)
		(stroke
			(width 0.2)
			(type default)
		)
		(fill no)
		(layer "In8.Cu")
	)
	(gr_circle
		(center 288.28111 -355.949758)
		(end 289.17011 -355.949758)
		(stroke
			(width 0.2)
			(type default)
		)
		(fill no)
		(layer "In8.Cu")
	)
	(gr_circle
		(center 288.90595 -355.279198)
		(end 289.79495 -355.279198)
		(stroke
			(width 0.2)
			(type default)
		)
		(fill no)
		(layer "In8.Cu")
	)
	(gr_circle
		(center 288.91611 -356.584758)
		(end 289.80511 -356.584758)
		(stroke
			(width 0.2)
			(type default)
		)
		(fill no)
		(layer "In8.Cu")
	)
	(gr_circle
		(center 288.91611 -355.949758)
		(end 289.80511 -355.949758)
		(stroke
			(width 0.2)
			(type default)
		)
		(fill no)
		(layer "In8.Cu")
	)
	(gr_line
		(start 289.207194 -399.833084)
		(end 296.033698 -399.833084)
		(stroke
			(width 0.508)
			(type default)
		)
		(layer "In8.Cu")
	)
	(gr_line
		(start 289.691318 -375.175272)
		(end 288.036508 -376.830082)
		(stroke
			(width 0.508)
			(type default)
		)
		(layer "In8.Cu")
	)
	(gr_circle
		(center 291.06749 -384.87858)
		(end 293.22649 -384.87858)
		(stroke
			(width 4.318)
			(type default)
		)
		(fill no)
		(layer "In8.Cu")
	)
	(gr_line
		(start 291.808408 -181.23408)
		(end 296.551858 -176.49063)
		(stroke
			(width 0.508)
			(type default)
		)
		(layer "In8.Cu")
	)
	(gr_circle
		(center 292.699186 -348.704662)
		(end 293.579296 -348.704662)
		(stroke
			(width 0.2)
			(type default)
		)
		(fill no)
		(layer "In8.Cu")
	)
	(gr_circle
		(center 293.316406 -348.704662)
		(end 294.196516 -348.704662)
		(stroke
			(width 0.2)
			(type default)
		)
		(fill no)
		(layer "In8.Cu")
	)
	(gr_circle
		(center 293.933626 -348.704662)
		(end 294.813736 -348.704662)
		(stroke
			(width 0.2)
			(type default)
		)
		(fill no)
		(layer "In8.Cu")
	)
	(gr_circle
		(center 294.146986 -347.959172)
		(end 295.035986 -347.959172)
		(stroke
			(width 0.2)
			(type default)
		)
		(fill no)
		(layer "In8.Cu")
	)
	(gr_circle
		(center 294.146986 -347.222572)
		(end 295.035986 -347.222572)
		(stroke
			(width 0.2)
			(type default)
		)
		(fill no)
		(layer "In8.Cu")
	)
	(gr_circle
		(center 294.635682 -350.313752)
		(end 295.524682 -350.313752)
		(stroke
			(width 0.2)
			(type default)
		)
		(fill no)
		(layer "In8.Cu")
	)
	(gr_circle
		(center 294.635682 -349.577152)
		(end 295.524682 -349.577152)
		(stroke
			(width 0.2)
			(type default)
		)
		(fill no)
		(layer "In8.Cu")
	)
	(gr_circle
		(center 295.160446 -349.137732)
		(end 296.049446 -349.137732)
		(stroke
			(width 0.2)
			(type default)
		)
		(fill no)
		(layer "In8.Cu")
	)
	(gr_circle
		(center 295.185846 -349.899732)
		(end 296.074846 -349.899732)
		(stroke
			(width 0.2)
			(type default)
		)
		(fill no)
		(layer "In8.Cu")
	)
	(gr_circle
		(center 295.719246 -350.255332)
		(end 296.608246 -350.255332)
		(stroke
			(width 0.2)
			(type default)
		)
		(fill no)
		(layer "In8.Cu")
	)
	(gr_circle
		(center 295.719246 -349.518732)
		(end 296.608246 -349.518732)
		(stroke
			(width 0.2)
			(type default)
		)
		(fill no)
		(layer "In8.Cu")
	)
	(gr_circle
		(center 295.719246 -348.782132)
		(end 296.608246 -348.782132)
		(stroke
			(width 0.2)
			(type default)
		)
		(fill no)
		(layer "In8.Cu")
	)
	(gr_line
		(start 296.033698 -418.729922)
		(end 299.426122 -422.122346)
		(stroke
			(width 0.508)
			(type default)
		)
		(layer "In8.Cu")
	)
	(gr_line
		(start 296.033698 -399.833084)
		(end 296.033698 -418.729922)
		(stroke
			(width 0.508)
			(type default)
		)
		(layer "In8.Cu")
	)
	(gr_circle
		(center 296.29989 -358.769666)
		(end 297.69689 -358.769666)
		(stroke
			(width 0.2)
			(type default)
		)
		(fill no)
		(layer "In8.Cu")
	)
	(gr_line
		(start 296.551858 -176.49063)
		(end 296.551858 -145.931128)
		(stroke
			(width 0.508)
			(type default)
		)
		(layer "In8.Cu")
	)
	(gr_line
		(start 296.551858 -145.931128)
		(end 307.766212 -134.716774)
		(stroke
			(width 0.508)
			(type default)
		)
		(layer "In8.Cu")
	)
	(gr_circle
		(center 297.567604 -413.174688)
		(end 299.726604 -413.174688)
		(stroke
			(width 4.318)
			(type default)
		)
		(fill no)
		(layer "In8.Cu")
	)
	(gr_line
		(start 299.426122 -422.122346)
		(end 435.404768 -422.122346)
		(stroke
			(width 0.508)
			(type default)
		)
		(layer "In8.Cu")
	)
	(gr_circle
		(center 301.055786 -348.704662)
		(end 301.935896 -348.704662)
		(stroke
			(width 0.2)
			(type default)
		)
		(fill no)
		(layer "In8.Cu")
	)
	(gr_line
		(start 301.192946 -394.673836)
		(end 296.033698 -399.833084)
		(stroke
			(width 0.508)
			(type default)
		)
		(layer "In8.Cu")
	)
	(gr_circle
		(center 301.673006 -348.704662)
		(end 302.553116 -348.704662)
		(stroke
			(width 0.2)
			(type default)
		)
		(fill no)
		(layer "In8.Cu")
	)
	(gr_circle
		(center 302.290226 -348.704662)
		(end 303.170336 -348.704662)
		(stroke
			(width 0.2)
			(type default)
		)
		(fill no)
		(layer "In8.Cu")
	)
	(gr_circle
		(center 302.526446 -348.002352)
		(end 303.415446 -348.002352)
		(stroke
			(width 0.2)
			(type default)
		)
		(fill no)
		(layer "In8.Cu")
	)
	(gr_circle
		(center 302.526446 -347.265752)
		(end 303.415446 -347.265752)
		(stroke
			(width 0.2)
			(type default)
		)
		(fill no)
		(layer "In8.Cu")
	)
	(gr_circle
		(center 302.992282 -350.313752)
		(end 303.881282 -350.313752)
		(stroke
			(width 0.2)
			(type default)
		)
		(fill no)
		(layer "In8.Cu")
	)
	(gr_circle
		(center 302.992282 -349.577152)
		(end 303.881282 -349.577152)
		(stroke
			(width 0.2)
			(type default)
		)
		(fill no)
		(layer "In8.Cu")
	)
	(gr_line
		(start 303.281842 -335.487518)
		(end 303.860962 -334.908398)
		(stroke
			(width 0.508)
			(type default)
		)
		(layer "In8.Cu")
	)
	(gr_circle
		(center 303.517046 -349.137732)
		(end 304.406046 -349.137732)
		(stroke
			(width 0.2)
			(type default)
		)
		(fill no)
		(layer "In8.Cu")
	)
	(gr_circle
		(center 303.542446 -349.899732)
		(end 304.431446 -349.899732)
		(stroke
			(width 0.2)
			(type default)
		)
		(fill no)
		(layer "In8.Cu")
	)
	(gr_line
		(start 303.860962 -334.908398)
		(end 303.860962 -309.058818)
		(stroke
			(width 0.508)
			(type default)
		)
		(layer "In8.Cu")
	)
	(gr_line
		(start 303.860962 -309.058818)
		(end 316.961266 -295.958514)
		(stroke
			(width 0.508)
			(type default)
		)
		(layer "In8.Cu")
	)
	(gr_line
		(start 304.023268 -98.832924)
		(end 274.875244 -127.980948)
		(stroke
			(width 0.508)
			(type default)
		)
		(layer "In8.Cu")
	)
	(gr_circle
		(center 304.075846 -350.255332)
		(end 304.964846 -350.255332)
		(stroke
			(width 0.2)
			(type default)
		)
		(fill no)
		(layer "In8.Cu")
	)
	(gr_circle
		(center 304.075846 -349.518732)
		(end 304.964846 -349.518732)
		(stroke
			(width 0.2)
			(type default)
		)
		(fill no)
		(layer "In8.Cu")
	)
	(gr_circle
		(center 304.075846 -348.782132)
		(end 304.964846 -348.782132)
		(stroke
			(width 0.2)
			(type default)
		)
		(fill no)
		(layer "In8.Cu")
	)
	(gr_line
		(start 304.440082 -335.487518)
		(end 303.860962 -334.908398)
		(stroke
			(width 0.508)
			(type default)
		)
		(layer "In8.Cu")
	)
	(gr_line
		(start 304.534062 -335.487518)
		(end 304.440082 -335.487518)
		(stroke
			(width 0.508)
			(type default)
		)
		(layer "In8.Cu")
	)
	(gr_line
		(start 307.766212 -134.716774)
		(end 344.861388 -134.716774)
		(stroke
			(width 0.508)
			(type default)
		)
		(layer "In8.Cu")
	)
	(gr_circle
		(center 309.386986 -348.704662)
		(end 310.267096 -348.704662)
		(stroke
			(width 0.2)
			(type default)
		)
		(fill no)
		(layer "In8.Cu")
	)
	(gr_circle
		(center 310.004206 -348.704662)
		(end 310.884316 -348.704662)
		(stroke
			(width 0.2)
			(type default)
		)
		(fill no)
		(layer "In8.Cu")
	)
	(gr_line
		(start 310.062626 -394.673836)
		(end 301.192946 -394.673836)
		(stroke
			(width 0.508)
			(type default)
		)
		(layer "In8.Cu")
	)
	(gr_line
		(start 310.125364 -396.33906)
		(end 310.572404 -396.7861)
		(stroke
			(width 0.508)
			(type default)
		)
		(layer "In8.Cu")
	)
	(gr_line
		(start 310.125364 -392.47064)
		(end 310.125364 -396.33906)
		(stroke
			(width 0.508)
			(type default)
		)
		(layer "In8.Cu")
	)
	(gr_line
		(start 310.463692 -392.132312)
		(end 310.125364 -392.47064)
		(stroke
			(width 0.508)
			(type default)
		)
		(layer "In8.Cu")
	)
	(gr_line
		(start 310.572404 -396.7861)
		(end 313.261248 -396.7861)
		(stroke
			(width 0.508)
			(type default)
		)
		(layer "In8.Cu")
	)
	(gr_circle
		(center 310.621426 -348.704662)
		(end 311.501536 -348.704662)
		(stroke
			(width 0.2)
			(type default)
		)
		(fill no)
		(layer "In8.Cu")
	)
	(gr_line
		(start 310.744362 -391.91438)
		(end 310.57215 -392.086592)
		(stroke
			(width 0.508)
			(type default)
		)
		(layer "In8.Cu")
	)
	(gr_circle
		(center 310.867806 -348.002352)
		(end 311.756806 -348.002352)
		(stroke
			(width 0.2)
			(type default)
		)
		(fill no)
		(layer "In8.Cu")
	)
	(gr_circle
		(center 310.867806 -347.265752)
		(end 311.756806 -347.265752)
		(stroke
			(width 0.2)
			(type default)
		)
		(fill no)
		(layer "In8.Cu")
	)
	(gr_circle
		(center 311.323482 -350.313752)
		(end 312.212482 -350.313752)
		(stroke
			(width 0.2)
			(type default)
		)
		(fill no)
		(layer "In8.Cu")
	)
	(gr_circle
		(center 311.323482 -349.577152)
		(end 312.212482 -349.577152)
		(stroke
			(width 0.2)
			(type default)
		)
		(fill no)
		(layer "In8.Cu")
	)
	(gr_line
		(start 311.623202 -335.487518)
		(end 271.41043 -335.487518)
		(stroke
			(width 0.508)
			(type default)
		)
		(layer "In8.Cu")
	)
	(gr_circle
		(center 311.848246 -349.137732)
		(end 312.737246 -349.137732)
		(stroke
			(width 0.2)
			(type default)
		)
		(fill no)
		(layer "In8.Cu")
	)
	(gr_circle
		(center 311.873646 -349.899732)
		(end 312.762646 -349.899732)
		(stroke
			(width 0.2)
			(type default)
		)
		(fill no)
		(layer "In8.Cu")
	)
	(gr_line
		(start 312.115962 -334.994758)
		(end 311.623202 -335.487518)
		(stroke
			(width 0.508)
			(type default)
		)
		(layer "In8.Cu")
	)
	(gr_line
		(start 312.115962 -330.394818)
		(end 312.115962 -334.994758)
		(stroke
			(width 0.508)
			(type default)
		)
		(layer "In8.Cu")
	)
	(gr_line
		(start 312.250328 -193.951352)
		(end 312.291222 -193.951352)
		(stroke
			(width 0.508)
			(type default)
		)
		(layer "In8.Cu")
	)
	(gr_line
		(start 312.250328 -193.951352)
		(end 312.612024 -193.589656)
		(stroke
			(width 0.508)
			(type default)
		)
		(layer "In8.Cu")
	)
	(gr_line
		(start 312.291222 -193.951352)
		(end 312.538364 -194.198494)
		(stroke
			(width 0.508)
			(type default)
		)
		(layer "In8.Cu")
	)
	(gr_circle
		(center 312.407046 -350.255332)
		(end 313.296046 -350.255332)
		(stroke
			(width 0.2)
			(type default)
		)
		(fill no)
		(layer "In8.Cu")
	)
	(gr_circle
		(center 312.407046 -349.518732)
		(end 313.296046 -349.518732)
		(stroke
			(width 0.2)
			(type default)
		)
		(fill no)
		(layer "In8.Cu")
	)
	(gr_circle
		(center 312.407046 -348.782132)
		(end 313.296046 -348.782132)
		(stroke
			(width 0.2)
			(type default)
		)
		(fill no)
		(layer "In8.Cu")
	)
	(gr_line
		(start 312.591958 -226.438206)
		(end 312.083958 -226.946206)
		(stroke
			(width 0.508)
			(type default)
		)
		(layer "In8.Cu")
	)
	(gr_line
		(start 312.591958 -226.438206)
		(end 312.591958 -150.730204)
		(stroke
			(width 0.508)
			(type default)
		)
		(layer "In8.Cu")
	)
	(gr_line
		(start 312.591958 -150.730204)
		(end 313.878214 -149.443948)
		(stroke
			(width 0.508)
			(type default)
		)
		(layer "In8.Cu")
	)
	(gr_line
		(start 312.877962 -329.632818)
		(end 312.115962 -330.394818)
		(stroke
			(width 0.508)
			(type default)
		)
		(layer "In8.Cu")
	)
	(gr_line
		(start 313.099958 -226.946206)
		(end 312.591958 -226.438206)
		(stroke
			(width 0.508)
			(type default)
		)
		(layer "In8.Cu")
	)
	(gr_line
		(start 313.226958 -226.946206)
		(end 313.099958 -226.946206)
		(stroke
			(width 0.508)
			(type default)
		)
		(layer "In8.Cu")
	)
	(gr_line
		(start 313.261248 -396.7861)
		(end 315.08827 -394.959078)
		(stroke
			(width 0.508)
			(type default)
		)
		(layer "In8.Cu")
	)
	(gr_line
		(start 313.878214 -149.443948)
		(end 337.382612 -149.443948)
		(stroke
			(width 0.508)
			(type default)
		)
		(layer "In8.Cu")
	)
	(gr_line
		(start 315.08827 -394.959078)
		(end 315.789056 -394.959078)
		(stroke
			(width 0.508)
			(type default)
		)
		(layer "In8.Cu")
	)
	(gr_line
		(start 315.789056 -394.959078)
		(end 317.145416 -396.315438)
		(stroke
			(width 0.508)
			(type default)
		)
		(layer "In8.Cu")
	)
	(gr_line
		(start 316.961266 -295.958514)
		(end 327.118472 -295.958514)
		(stroke
			(width 0.508)
			(type default)
		)
		(layer "In8.Cu")
	)
	(gr_line
		(start 317.145416 -396.315438)
		(end 325.182484 -396.315438)
		(stroke
			(width 0.508)
			(type default)
		)
		(layer "In8.Cu")
	)
	(gr_line
		(start 318.719962 -329.632818)
		(end 312.877962 -329.632818)
		(stroke
			(width 0.508)
			(type default)
		)
		(layer "In8.Cu")
	)
	(gr_circle
		(center 319.0367 -336.983578)
		(end 319.91681 -336.983578)
		(stroke
			(width 0.2)
			(type default)
		)
		(fill no)
		(layer "In8.Cu")
	)
	(gr_circle
		(center 319.65392 -336.983578)
		(end 320.53403 -336.983578)
		(stroke
			(width 0.2)
			(type default)
		)
		(fill no)
		(layer "In8.Cu")
	)
	(gr_circle
		(center 320.27114 -336.983578)
		(end 321.15125 -336.983578)
		(stroke
			(width 0.2)
			(type default)
		)
		(fill no)
		(layer "In8.Cu")
	)
	(gr_circle
		(center 320.5607 -336.239612)
		(end 321.4497 -336.239612)
		(stroke
			(width 0.2)
			(type default)
		)
		(fill no)
		(layer "In8.Cu")
	)
	(gr_circle
		(center 320.5607 -335.503012)
		(end 321.4497 -335.503012)
		(stroke
			(width 0.2)
			(type default)
		)
		(fill no)
		(layer "In8.Cu")
	)
	(gr_circle
		(center 320.973196 -338.592668)
		(end 321.862196 -338.592668)
		(stroke
			(width 0.2)
			(type default)
		)
		(fill no)
		(layer "In8.Cu")
	)
	(gr_circle
		(center 320.973196 -337.856068)
		(end 321.862196 -337.856068)
		(stroke
			(width 0.2)
			(type default)
		)
		(fill no)
		(layer "In8.Cu")
	)
	(gr_circle
		(center 321.49796 -337.416648)
		(end 322.38696 -337.416648)
		(stroke
			(width 0.2)
			(type default)
		)
		(fill no)
		(layer "In8.Cu")
	)
	(gr_circle
		(center 321.52336 -338.178648)
		(end 322.41236 -338.178648)
		(stroke
			(width 0.2)
			(type default)
		)
		(fill no)
		(layer "In8.Cu")
	)
	(gr_circle
		(center 322.05676 -338.534248)
		(end 322.94576 -338.534248)
		(stroke
			(width 0.2)
			(type default)
		)
		(fill no)
		(layer "In8.Cu")
	)
	(gr_circle
		(center 322.05676 -337.797648)
		(end 322.94576 -337.797648)
		(stroke
			(width 0.2)
			(type default)
		)
		(fill no)
		(layer "In8.Cu")
	)
	(gr_circle
		(center 322.05676 -337.061048)
		(end 322.94576 -337.061048)
		(stroke
			(width 0.2)
			(type default)
		)
		(fill no)
		(layer "In8.Cu")
	)
	(gr_line
		(start 322.402962 -325.949818)
		(end 318.719962 -329.632818)
		(stroke
			(width 0.508)
			(type default)
		)
		(layer "In8.Cu")
	)
	(gr_line
		(start 325.182484 -396.315438)
		(end 325.780146 -395.717776)
		(stroke
			(width 0.508)
			(type default)
		)
		(layer "In8.Cu")
	)
	(gr_line
		(start 325.372984 -226.968304)
		(end 327.011284 -226.968304)
		(stroke
			(width 0.508)
			(type default)
		)
		(layer "In8.Cu")
	)
	(gr_line
		(start 325.613522 -391.91438)
		(end 310.744362 -391.91438)
		(stroke
			(width 0.508)
			(type default)
		)
		(layer "In8.Cu")
	)
	(gr_line
		(start 325.780146 -395.717776)
		(end 325.780146 -395.12621)
		(stroke
			(width 0.508)
			(type default)
		)
		(layer "In8.Cu")
	)
	(gr_line
		(start 325.780146 -395.12621)
		(end 325.780146 -394.757402)
		(stroke
			(width 0.254)
			(type default)
		)
		(layer "In8.Cu")
	)
	(gr_line
		(start 325.780146 -394.757402)
		(end 325.957946 -394.579602)
		(stroke
			(width 0.254)
			(type default)
		)
		(layer "In8.Cu")
	)
	(gr_line
		(start 325.957946 -394.579602)
		(end 325.957946 -393.057634)
		(stroke
			(width 0.254)
			(type default)
		)
		(layer "In8.Cu")
	)
	(gr_line
		(start 325.957946 -393.057634)
		(end 325.957946 -392.258804)
		(stroke
			(width 0.508)
			(type default)
		)
		(layer "In8.Cu")
	)
	(gr_line
		(start 325.957946 -392.258804)
		(end 325.613522 -391.91438)
		(stroke
			(width 0.508)
			(type default)
		)
		(layer "In8.Cu")
	)
	(gr_line
		(start 327.011284 -226.968304)
		(end 335.190846 -226.968304)
		(stroke
			(width 0.254)
			(type default)
		)
		(layer "In8.Cu")
	)
	(gr_line
		(start 327.118472 -295.958514)
		(end 340.278466 -295.958514)
		(stroke
			(width 0.254)
			(type default)
		)
		(layer "In8.Cu")
	)
	(gr_circle
		(center 327.392284 -336.976466)
		(end 328.272394 -336.976466)
		(stroke
			(width 0.2)
			(type default)
		)
		(fill no)
		(layer "In8.Cu")
	)
	(gr_circle
		(center 327.692258 -104.30129)
		(end 328.581258 -104.30129)
		(stroke
			(width 0.2)
			(type default)
		)
		(fill no)
		(layer "In8.Cu")
	)
	(gr_line
		(start 327.727056 -395.717776)
		(end 325.780146 -395.717776)
		(stroke
			(width 0.508)
			(type default)
		)
		(layer "In8.Cu")
	)
	(gr_circle
		(center 327.951084 -349.43161)
		(end 329.348084 -349.43161)
		(stroke
			(width 0.2)
			(type default)
		)
		(fill no)
		(layer "In8.Cu")
	)
	(gr_circle
		(center 328.009504 -336.976466)
		(end 328.889614 -336.976466)
		(stroke
			(width 0.2)
			(type default)
		)
		(fill no)
		(layer "In8.Cu")
	)
	(gr_circle
		(center 328.626724 -336.976466)
		(end 329.506834 -336.976466)
		(stroke
			(width 0.2)
			(type default)
		)
		(fill no)
		(layer "In8.Cu")
	)
	(gr_circle
		(center 328.918824 -336.253836)
		(end 329.807824 -336.253836)
		(stroke
			(width 0.2)
			(type default)
		)
		(fill no)
		(layer "In8.Cu")
	)
	(gr_circle
		(center 328.918824 -335.517236)
		(end 329.807824 -335.517236)
		(stroke
			(width 0.2)
			(type default)
		)
		(fill no)
		(layer "In8.Cu")
	)
	(gr_line
		(start 329.302872 -394.14196)
		(end 327.727056 -395.717776)
		(stroke
			(width 0.508)
			(type default)
		)
		(layer "In8.Cu")
	)
	(gr_line
		(start 329.302872 -392.849354)
		(end 329.302872 -394.14196)
		(stroke
			(width 0.508)
			(type default)
		)
		(layer "In8.Cu")
	)
	(gr_circle
		(center 329.32878 -338.585556)
		(end 330.21778 -338.585556)
		(stroke
			(width 0.2)
			(type default)
		)
		(fill no)
		(layer "In8.Cu")
	)
	(gr_circle
		(center 329.32878 -337.848956)
		(end 330.21778 -337.848956)
		(stroke
			(width 0.2)
			(type default)
		)
		(fill no)
		(layer "In8.Cu")
	)
	(gr_circle
		(center 329.853544 -337.409536)
		(end 330.742544 -337.409536)
		(stroke
			(width 0.2)
			(type default)
		)
		(fill no)
		(layer "In8.Cu")
	)
	(gr_circle
		(center 329.878944 -338.171536)
		(end 330.767944 -338.171536)
		(stroke
			(width 0.2)
			(type default)
		)
		(fill no)
		(layer "In8.Cu")
	)
	(gr_line
		(start 330.003404 -392.148822)
		(end 329.302872 -392.849354)
		(stroke
			(width 0.508)
			(type default)
		)
		(layer "In8.Cu")
	)
	(gr_circle
		(center 330.412344 -338.527136)
		(end 331.301344 -338.527136)
		(stroke
			(width 0.2)
			(type default)
		)
		(fill no)
		(layer "In8.Cu")
	)
	(gr_circle
		(center 330.412344 -337.790536)
		(end 331.301344 -337.790536)
		(stroke
			(width 0.2)
			(type default)
		)
		(fill no)
		(layer "In8.Cu")
	)
	(gr_circle
		(center 330.412344 -337.053936)
		(end 331.301344 -337.053936)
		(stroke
			(width 0.2)
			(type default)
		)
		(fill no)
		(layer "In8.Cu")
	)
	(gr_line
		(start 333.165958 -214.990426)
		(end 339.977984 -221.802452)
		(stroke
			(width 0.508)
			(type default)
		)
		(layer "In8.Cu")
	)
	(gr_line
		(start 333.165958 -172.717206)
		(end 333.165958 -214.990426)
		(stroke
			(width 0.508)
			(type default)
		)
		(layer "In8.Cu")
	)
	(gr_line
		(start 333.673958 -172.209206)
		(end 333.165958 -172.717206)
		(stroke
			(width 0.508)
			(type default)
		)
		(layer "In8.Cu")
	)
	(gr_line
		(start 335.190846 -226.968304)
		(end 335.472278 -227.249736)
		(stroke
			(width 0.254)
			(type default)
		)
		(layer "In8.Cu")
	)
	(gr_circle
		(center 335.411064 -349.43161)
		(end 336.808064 -349.43161)
		(stroke
			(width 0.2)
			(type default)
		)
		(fill no)
		(layer "In8.Cu")
	)
	(gr_line
		(start 335.472278 -252.070108)
		(end 339.226652 -255.824482)
		(stroke
			(width 0.254)
			(type default)
		)
		(layer "In8.Cu")
	)
	(gr_line
		(start 335.472278 -227.249736)
		(end 335.472278 -252.070108)
		(stroke
			(width 0.254)
			(type default)
		)
		(layer "In8.Cu")
	)
	(gr_circle
		(center 335.7499 -336.961988)
		(end 336.63001 -336.961988)
		(stroke
			(width 0.2)
			(type default)
		)
		(fill no)
		(layer "In8.Cu")
	)
	(gr_circle
		(center 336.36712 -336.961988)
		(end 337.24723 -336.961988)
		(stroke
			(width 0.2)
			(type default)
		)
		(fill no)
		(layer "In8.Cu")
	)
	(gr_circle
		(center 336.98434 -336.961988)
		(end 337.86445 -336.961988)
		(stroke
			(width 0.2)
			(type default)
		)
		(fill no)
		(layer "In8.Cu")
	)
	(gr_circle
		(center 337.280504 -336.253836)
		(end 338.169504 -336.253836)
		(stroke
			(width 0.2)
			(type default)
		)
		(fill no)
		(layer "In8.Cu")
	)
	(gr_circle
		(center 337.280504 -335.517236)
		(end 338.169504 -335.517236)
		(stroke
			(width 0.2)
			(type default)
		)
		(fill no)
		(layer "In8.Cu")
	)
	(gr_line
		(start 337.382612 -149.443948)
		(end 337.899756 -149.961092)
		(stroke
			(width 0.508)
			(type default)
		)
		(layer "In8.Cu")
	)
	(gr_line
		(start 337.483958 -172.209206)
		(end 333.673958 -172.209206)
		(stroke
			(width 0.508)
			(type default)
		)
		(layer "In8.Cu")
	)
	(gr_line
		(start 337.483958 -172.209206)
		(end 337.899756 -171.793408)
		(stroke
			(width 0.508)
			(type default)
		)
		(layer "In8.Cu")
	)
	(gr_line
		(start 337.5406 -172.152564)
		(end 337.483958 -172.209206)
		(stroke
			(width 0.508)
			(type default)
		)
		(layer "In8.Cu")
	)
	(gr_circle
		(center 337.686396 -338.571078)
		(end 338.575396 -338.571078)
		(stroke
			(width 0.2)
			(type default)
		)
		(fill no)
		(layer "In8.Cu")
	)
	(gr_circle
		(center 337.686396 -337.834478)
		(end 338.575396 -337.834478)
		(stroke
			(width 0.2)
			(type default)
		)
		(fill no)
		(layer "In8.Cu")
	)
	(gr_line
		(start 337.899756 -171.793408)
		(end 337.899756 -150.000208)
		(stroke
			(width 0.508)
			(type default)
		)
		(layer "In8.Cu")
	)
	(gr_line
		(start 337.899756 -149.961092)
		(end 337.899756 -150.000208)
		(stroke
			(width 0.508)
			(type default)
		)
		(layer "In8.Cu")
	)
	(gr_line
		(start 337.981798 -157.053534)
		(end 338.44357 -156.591762)
		(stroke
			(width 0.508)
			(type default)
		)
		(layer "In8.Cu")
	)
	(gr_circle
		(center 338.21116 -337.395058)
		(end 339.10016 -337.395058)
		(stroke
			(width 0.2)
			(type default)
		)
		(fill no)
		(layer "In8.Cu")
	)
	(gr_circle
		(center 338.23656 -338.157058)
		(end 339.12556 -338.157058)
		(stroke
			(width 0.2)
			(type default)
		)
		(fill no)
		(layer "In8.Cu")
	)
	(gr_line
		(start 338.258912 -172.152564)
		(end 337.5406 -172.152564)
		(stroke
			(width 0.508)
			(type default)
		)
		(layer "In8.Cu")
	)
	(gr_line
		(start 338.258912 -172.152564)
		(end 337.899756 -171.793408)
		(stroke
			(width 0.508)
			(type default)
		)
		(layer "In8.Cu")
	)
	(gr_line
		(start 338.412328 -156.591762)
		(end 337.856068 -156.035502)
		(stroke
			(width 0.508)
			(type default)
		)
		(layer "In8.Cu")
	)
	(gr_line
		(start 338.44357 -156.591762)
		(end 338.412328 -156.591762)
		(stroke
			(width 0.508)
			(type default)
		)
		(layer "In8.Cu")
	)
	(gr_line
		(start 338.44357 -156.591762)
		(end 351.43567 -156.591762)
		(stroke
			(width 0.508)
			(type default)
		)
		(layer "In8.Cu")
	)
	(gr_circle
		(center 338.76996 -338.512658)
		(end 339.65896 -338.512658)
		(stroke
			(width 0.2)
			(type default)
		)
		(fill no)
		(layer "In8.Cu")
	)
	(gr_circle
		(center 338.76996 -337.776058)
		(end 339.65896 -337.776058)
		(stroke
			(width 0.2)
			(type default)
		)
		(fill no)
		(layer "In8.Cu")
	)
	(gr_circle
		(center 338.76996 -337.039458)
		(end 339.65896 -337.039458)
		(stroke
			(width 0.2)
			(type default)
		)
		(fill no)
		(layer "In8.Cu")
	)
	(gr_line
		(start 339.226652 -255.824482)
		(end 343.740994 -255.824482)
		(stroke
			(width 0.254)
			(type default)
		)
		(layer "In8.Cu")
	)
	(gr_circle
		(center 339.73897 -352.973132)
		(end 340.62797 -352.973132)
		(stroke
			(width 0.2)
			(type default)
		)
		(fill no)
		(layer "In8.Cu")
	)
	(gr_circle
		(center 339.739224 -352.215196)
		(end 340.628224 -352.215196)
		(stroke
			(width 0.2)
			(type default)
		)
		(fill no)
		(layer "In8.Cu")
	)
	(gr_circle
		(center 339.739224 -351.453196)
		(end 340.628224 -351.453196)
		(stroke
			(width 0.2)
			(type default)
		)
		(fill no)
		(layer "In8.Cu")
	)
	(gr_line
		(start 339.977984 -221.802452)
		(end 341.387938 -224.23247)
		(stroke
			(width 0.254)
			(type default)
		)
		(layer "In8.Cu")
	)
	(gr_line
		(start 340.278466 -295.958514)
		(end 340.74862 -295.148508)
		(stroke
			(width 0.254)
			(type default)
		)
		(layer "In8.Cu")
	)
	(gr_circle
		(center 340.501224 -352.215196)
		(end 341.390224 -352.215196)
		(stroke
			(width 0.2)
			(type default)
		)
		(fill no)
		(layer "In8.Cu")
	)
	(gr_circle
		(center 340.501224 -351.453196)
		(end 341.390224 -351.453196)
		(stroke
			(width 0.2)
			(type default)
		)
		(fill no)
		(layer "In8.Cu")
	)
	(gr_circle
		(center 340.667848 -353.010216)
		(end 341.556848 -353.010216)
		(stroke
			(width 0.2)
			(type default)
		)
		(fill no)
		(layer "In8.Cu")
	)
	(gr_circle
		(center 341.263224 -352.215196)
		(end 342.152224 -352.215196)
		(stroke
			(width 0.2)
			(type default)
		)
		(fill no)
		(layer "In8.Cu")
	)
	(gr_circle
		(center 341.263224 -351.453196)
		(end 342.152224 -351.453196)
		(stroke
			(width 0.2)
			(type default)
		)
		(fill no)
		(layer "In8.Cu")
	)
	(gr_circle
		(center 341.302848 -353.010216)
		(end 342.191848 -353.010216)
		(stroke
			(width 0.2)
			(type default)
		)
		(fill no)
		(layer "In8.Cu")
	)
	(gr_line
		(start 341.68842 -293.528496)
		(end 340.74862 -295.148508)
		(stroke
			(width 0.254)
			(type default)
		)
		(layer "In8.Cu")
	)
	(gr_circle
		(center 341.937848 -353.010216)
		(end 342.826848 -353.010216)
		(stroke
			(width 0.2)
			(type default)
		)
		(fill no)
		(layer "In8.Cu")
	)
	(gr_circle
		(center 342.025224 -352.215196)
		(end 342.914224 -352.215196)
		(stroke
			(width 0.2)
			(type default)
		)
		(fill no)
		(layer "In8.Cu")
	)
	(gr_circle
		(center 342.025224 -351.453196)
		(end 342.914224 -351.453196)
		(stroke
			(width 0.2)
			(type default)
		)
		(fill no)
		(layer "In8.Cu")
	)
	(gr_line
		(start 342.252808 -392.148822)
		(end 330.003404 -392.148822)
		(stroke
			(width 0.508)
			(type default)
		)
		(layer "In8.Cu")
	)
	(gr_circle
		(center 342.572848 -353.010216)
		(end 343.461848 -353.010216)
		(stroke
			(width 0.2)
			(type default)
		)
		(fill no)
		(layer "In8.Cu")
	)
	(gr_line
		(start 342.628474 -293.528496)
		(end 341.68842 -293.528496)
		(stroke
			(width 0.254)
			(type default)
		)
		(layer "In8.Cu")
	)
	(gr_line
		(start 342.630252 -396.234666)
		(end 342.630252 -392.526266)
		(stroke
			(width 0.508)
			(type default)
		)
		(layer "In8.Cu")
	)
	(gr_line
		(start 342.630252 -392.526266)
		(end 342.252808 -392.148822)
		(stroke
			(width 0.508)
			(type default)
		)
		(layer "In8.Cu")
	)
	(gr_line
		(start 342.630252 -392.526266)
		(end 342.630252 -392.431524)
		(stroke
			(width 0.508)
			(type default)
		)
		(layer "In8.Cu")
	)
	(gr_line
		(start 342.630252 -392.431524)
		(end 343.089992 -391.971784)
		(stroke
			(width 0.508)
			(type default)
		)
		(layer "In8.Cu")
	)
	(gr_circle
		(center 342.787224 -352.215196)
		(end 343.676224 -352.215196)
		(stroke
			(width 0.2)
			(type default)
		)
		(fill no)
		(layer "In8.Cu")
	)
	(gr_circle
		(center 342.787224 -351.453196)
		(end 343.676224 -351.453196)
		(stroke
			(width 0.2)
			(type default)
		)
		(fill no)
		(layer "In8.Cu")
	)
	(gr_line
		(start 343.066878 -396.671292)
		(end 342.630252 -396.234666)
		(stroke
			(width 0.508)
			(type default)
		)
		(layer "In8.Cu")
	)
	(gr_line
		(start 343.089992 -391.971784)
		(end 358.205532 -391.971784)
		(stroke
			(width 0.508)
			(type default)
		)
		(layer "In8.Cu")
	)
	(gr_line
		(start 343.098374 -292.71849)
		(end 342.628474 -293.528496)
		(stroke
			(width 0.254)
			(type default)
		)
		(layer "In8.Cu")
	)
	(gr_circle
		(center 343.46515 -353.006152)
		(end 344.35415 -353.006152)
		(stroke
			(width 0.2)
			(type default)
		)
		(fill no)
		(layer "In8.Cu")
	)
	(gr_circle
		(center 343.465404 -352.248216)
		(end 344.354404 -352.248216)
		(stroke
			(width 0.2)
			(type default)
		)
		(fill no)
		(layer "In8.Cu")
	)
	(gr_circle
		(center 343.465404 -351.486216)
		(end 344.354404 -351.486216)
		(stroke
			(width 0.2)
			(type default)
		)
		(fill no)
		(layer "In8.Cu")
	)
	(gr_line
		(start 343.568528 -291.908484)
		(end 343.098374 -292.71849)
		(stroke
			(width 0.254)
			(type default)
		)
		(layer "In8.Cu")
	)
	(gr_line
		(start 343.737946 -228.282246)
		(end 341.387938 -224.23247)
		(stroke
			(width 0.254)
			(type default)
		)
		(layer "In8.Cu")
	)
	(gr_line
		(start 343.740994 -255.824482)
		(end 345.151202 -256.634488)
		(stroke
			(width 0.254)
			(type default)
		)
		(layer "In8.Cu")
	)
	(gr_circle
		(center 344.016838 -159.073596)
		(end 344.905838 -159.073596)
		(stroke
			(width 0.2)
			(type default)
		)
		(fill no)
		(layer "In8.Cu")
	)
	(gr_circle
		(center 344.016838 -158.336996)
		(end 344.905838 -158.336996)
		(stroke
			(width 0.2)
			(type default)
		)
		(fill no)
		(layer "In8.Cu")
	)
	(gr_circle
		(center 344.016838 -157.600396)
		(end 344.905838 -157.600396)
		(stroke
			(width 0.2)
			(type default)
		)
		(fill no)
		(layer "In8.Cu")
	)
	(gr_line
		(start 344.038428 -291.098478)
		(end 343.568528 -291.908484)
		(stroke
			(width 0.254)
			(type default)
		)
		(layer "In8.Cu")
	)
	(gr_circle
		(center 344.0811 -337.012788)
		(end 344.96121 -337.012788)
		(stroke
			(width 0.2)
			(type default)
		)
		(fill no)
		(layer "In8.Cu")
	)
	(gr_line
		(start 344.207846 -248.532396)
		(end 345.1479 -246.912384)
		(stroke
			(width 0.254)
			(type default)
		)
		(layer "In8.Cu")
	)
	(gr_line
		(start 344.207846 -245.292372)
		(end 345.1479 -243.67236)
		(stroke
			(width 0.254)
			(type default)
		)
		(layer "In8.Cu")
	)
	(gr_line
		(start 344.207846 -242.052348)
		(end 345.1479 -240.432336)
		(stroke
			(width 0.254)
			(type default)
		)
		(layer "In8.Cu")
	)
	(gr_line
		(start 344.207846 -238.812324)
		(end 345.618054 -238.002318)
		(stroke
			(width 0.254)
			(type default)
		)
		(layer "In8.Cu")
	)
	(gr_line
		(start 344.207846 -233.952288)
		(end 345.1479 -232.332276)
		(stroke
			(width 0.254)
			(type default)
		)
		(layer "In8.Cu")
	)
	(gr_line
		(start 344.246962 -325.949818)
		(end 322.402962 -325.949818)
		(stroke
			(width 0.508)
			(type default)
		)
		(layer "In8.Cu")
	)
	(gr_line
		(start 344.508582 -290.288726)
		(end 344.038428 -291.098478)
		(stroke
			(width 0.254)
			(type default)
		)
		(layer "In8.Cu")
	)
	(gr_line
		(start 344.508582 -287.048702)
		(end 345.448382 -288.668714)
		(stroke
			(width 0.254)
			(type default)
		)
		(layer "In8.Cu")
	)
	(gr_line
		(start 344.508582 -283.808678)
		(end 345.448382 -285.42869)
		(stroke
			(width 0.254)
			(type default)
		)
		(layer "In8.Cu")
	)
	(gr_line
		(start 344.508582 -278.948642)
		(end 345.918536 -279.758648)
		(stroke
			(width 0.254)
			(type default)
		)
		(layer "In8.Cu")
	)
	(gr_line
		(start 344.508582 -275.708618)
		(end 345.448382 -277.32863)
		(stroke
			(width 0.254)
			(type default)
		)
		(layer "In8.Cu")
	)
	(gr_line
		(start 344.508582 -272.468594)
		(end 345.448382 -274.088606)
		(stroke
			(width 0.254)
			(type default)
		)
		(layer "In8.Cu")
	)
	(gr_line
		(start 344.508582 -269.22857)
		(end 345.448382 -270.848582)
		(stroke
			(width 0.254)
			(type default)
		)
		(layer "In8.Cu")
	)
	(gr_circle
		(center 344.550238 -157.955996)
		(end 345.439238 -157.955996)
		(stroke
			(width 0.2)
			(type default)
		)
		(fill no)
		(layer "In8.Cu")
	)
	(gr_circle
		(center 344.575638 -158.717996)
		(end 345.464638 -158.717996)
		(stroke
			(width 0.2)
			(type default)
		)
		(fill no)
		(layer "In8.Cu")
	)
	(gr_line
		(start 344.5764 -156.8704)
		(end 344.424 -157.0228)
		(stroke
			(width 0.254)
			(type default)
		)
		(layer "In8.Cu")
	)
	(gr_line
		(start 344.5764 -156.7434)
		(end 344.5764 -156.8704)
		(stroke
			(width 0.254)
			(type default)
		)
		(layer "In8.Cu")
	)
	(gr_line
		(start 344.678 -236.382306)
		(end 345.1479 -235.5723)
		(stroke
			(width 0.254)
			(type default)
		)
		(layer "In8.Cu")
	)
	(gr_line
		(start 344.678 -231.52227)
		(end 345.1479 -230.712264)
		(stroke
			(width 0.254)
			(type default)
		)
		(layer "In8.Cu")
	)
	(gr_line
		(start 344.678 -229.902258)
		(end 345.1479 -229.092252)
		(stroke
			(width 0.254)
			(type default)
		)
		(layer "In8.Cu")
	)
	(gr_line
		(start 344.678 -228.282246)
		(end 343.737946 -228.282246)
		(stroke
			(width 0.254)
			(type default)
		)
		(layer "In8.Cu")
	)
	(gr_circle
		(center 344.69832 -337.012788)
		(end 345.57843 -337.012788)
		(stroke
			(width 0.2)
			(type default)
		)
		(fill no)
		(layer "In8.Cu")
	)
	(gr_line
		(start 344.861388 -134.716774)
		(end 361.113578 -150.968964)
		(stroke
			(width 0.508)
			(type default)
		)
		(layer "In8.Cu")
	)
	(gr_line
		(start 344.978482 -281.37866)
		(end 345.448382 -282.188666)
		(stroke
			(width 0.254)
			(type default)
		)
		(layer "In8.Cu")
	)
	(gr_circle
		(center 345.100402 -158.278576)
		(end 345.989402 -158.278576)
		(stroke
			(width 0.2)
			(type default)
		)
		(fill no)
		(layer "In8.Cu")
	)
	(gr_circle
		(center 345.100402 -157.541976)
		(end 345.989402 -157.541976)
		(stroke
			(width 0.2)
			(type default)
		)
		(fill no)
		(layer "In8.Cu")
	)
	(gr_line
		(start 345.1479 -246.912384)
		(end 344.207846 -245.292372)
		(stroke
			(width 0.254)
			(type default)
		)
		(layer "In8.Cu")
	)
	(gr_line
		(start 345.1479 -243.67236)
		(end 344.207846 -242.052348)
		(stroke
			(width 0.254)
			(type default)
		)
		(layer "In8.Cu")
	)
	(gr_line
		(start 345.1479 -240.432336)
		(end 344.207846 -238.812324)
		(stroke
			(width 0.254)
			(type default)
		)
		(layer "In8.Cu")
	)
	(gr_line
		(start 345.1479 -235.5723)
		(end 344.207846 -233.952288)
		(stroke
			(width 0.254)
			(type default)
		)
		(layer "In8.Cu")
	)
	(gr_line
		(start 345.1479 -232.332276)
		(end 344.678 -231.52227)
		(stroke
			(width 0.254)
			(type default)
		)
		(layer "In8.Cu")
	)
	(gr_line
		(start 345.1479 -230.712264)
		(end 344.678 -229.902258)
		(stroke
			(width 0.254)
			(type default)
		)
		(layer "In8.Cu")
	)
	(gr_line
		(start 345.1479 -229.092252)
		(end 344.678 -228.282246)
		(stroke
			(width 0.254)
			(type default)
		)
		(layer "In8.Cu")
	)
	(gr_line
		(start 345.151202 -256.634488)
		(end 345.621102 -255.824482)
		(stroke
			(width 0.254)
			(type default)
		)
		(layer "In8.Cu")
	)
	(gr_circle
		(center 345.31554 -337.012788)
		(end 346.19565 -337.012788)
		(stroke
			(width 0.2)
			(type default)
		)
		(fill no)
		(layer "In8.Cu")
	)
	(gr_line
		(start 345.448382 -288.668714)
		(end 344.508582 -290.288726)
		(stroke
			(width 0.254)
			(type default)
		)
		(layer "In8.Cu")
	)
	(gr_line
		(start 345.448382 -285.42869)
		(end 344.508582 -287.048702)
		(stroke
			(width 0.254)
			(type default)
		)
		(layer "In8.Cu")
	)
	(gr_line
		(start 345.448382 -282.188666)
		(end 344.508582 -283.808678)
		(stroke
			(width 0.254)
			(type default)
		)
		(layer "In8.Cu")
	)
	(gr_line
		(start 345.448382 -280.568654)
		(end 344.978482 -281.37866)
		(stroke
			(width 0.254)
			(type default)
		)
		(layer "In8.Cu")
	)
	(gr_line
		(start 345.448382 -277.32863)
		(end 344.508582 -278.948642)
		(stroke
			(width 0.254)
			(type default)
		)
		(layer "In8.Cu")
	)
	(gr_line
		(start 345.448382 -274.088606)
		(end 344.508582 -275.708618)
		(stroke
			(width 0.254)
			(type default)
		)
		(layer "In8.Cu")
	)
	(gr_line
		(start 345.448382 -270.848582)
		(end 344.508582 -272.468594)
		(stroke
			(width 0.254)
			(type default)
		)
		(layer "In8.Cu")
	)
	(gr_line
		(start 345.448382 -267.608558)
		(end 344.508582 -269.22857)
		(stroke
			(width 0.254)
			(type default)
		)
		(layer "In8.Cu")
	)
	(gr_line
		(start 345.618054 -249.342402)
		(end 344.207846 -248.532396)
		(stroke
			(width 0.254)
			(type default)
		)
		(layer "In8.Cu")
	)
	(gr_line
		(start 345.618054 -238.002318)
		(end 344.678 -236.382306)
		(stroke
			(width 0.254)
			(type default)
		)
		(layer "In8.Cu")
	)
	(gr_line
		(start 345.621102 -255.824482)
		(end 347.031056 -256.634488)
		(stroke
			(width 0.254)
			(type default)
		)
		(layer "In8.Cu")
	)
	(gr_circle
		(center 345.623896 -336.317336)
		(end 346.512896 -336.317336)
		(stroke
			(width 0.2)
			(type default)
		)
		(fill no)
		(layer "In8.Cu")
	)
	(gr_circle
		(center 345.623896 -335.580736)
		(end 346.512896 -335.580736)
		(stroke
			(width 0.2)
			(type default)
		)
		(fill no)
		(layer "In8.Cu")
	)
	(gr_circle
		(center 345.684856 -160.633156)
		(end 346.573856 -160.633156)
		(stroke
			(width 0.2)
			(type default)
		)
		(fill no)
		(layer "In8.Cu")
	)
	(gr_circle
		(center 345.684856 -159.896556)
		(end 346.573856 -159.896556)
		(stroke
			(width 0.2)
			(type default)
		)
		(fill no)
		(layer "In8.Cu")
	)
	(gr_circle
		(center 345.802458 -159.151066)
		(end 346.682568 -159.151066)
		(stroke
			(width 0.2)
			(type default)
		)
		(fill no)
		(layer "In8.Cu")
	)
	(gr_line
		(start 345.918536 -279.758648)
		(end 345.448382 -280.568654)
		(stroke
			(width 0.254)
			(type default)
		)
		(layer "In8.Cu")
	)
	(gr_line
		(start 345.921076 -291.095938)
		(end 346.86113 -291.095938)
		(stroke
			(width 0.6096)
			(type default)
		)
		(layer "In8.Cu")
	)
	(gr_line
		(start 345.921076 -289.475926)
		(end 346.86113 -289.475926)
		(stroke
			(width 0.6096)
			(type default)
		)
		(layer "In8.Cu")
	)
	(gr_line
		(start 345.921076 -287.856168)
		(end 346.86113 -287.856168)
		(stroke
			(width 0.6096)
			(type default)
		)
		(layer "In8.Cu")
	)
	(gr_line
		(start 345.921076 -286.236156)
		(end 346.86113 -286.236156)
		(stroke
			(width 0.6096)
			(type default)
		)
		(layer "In8.Cu")
	)
	(gr_circle
		(center 346.017596 -339.358478)
		(end 346.906596 -339.358478)
		(stroke
			(width 0.2)
			(type default)
		)
		(fill no)
		(layer "In8.Cu")
	)
	(gr_circle
		(center 346.017596 -338.621878)
		(end 346.906596 -338.621878)
		(stroke
			(width 0.2)
			(type default)
		)
		(fill no)
		(layer "In8.Cu")
	)
	(gr_circle
		(center 346.017596 -337.885278)
		(end 346.906596 -337.885278)
		(stroke
			(width 0.2)
			(type default)
		)
		(fill no)
		(layer "In8.Cu")
	)
	(gr_line
		(start 346.05468 -396.671292)
		(end 343.066878 -396.671292)
		(stroke
			(width 0.508)
			(type default)
		)
		(layer "In8.Cu")
	)
	(gr_circle
		(center 346.419678 -159.151066)
		(end 347.299788 -159.151066)
		(stroke
			(width 0.2)
			(type default)
		)
		(fill no)
		(layer "In8.Cu")
	)
	(gr_circle
		(center 346.54236 -337.445858)
		(end 347.43136 -337.445858)
		(stroke
			(width 0.2)
			(type default)
		)
		(fill no)
		(layer "In8.Cu")
	)
	(gr_circle
		(center 346.56776 -339.731858)
		(end 347.45676 -339.731858)
		(stroke
			(width 0.2)
			(type default)
		)
		(fill no)
		(layer "In8.Cu")
	)
	(gr_circle
		(center 346.56776 -338.969858)
		(end 347.45676 -338.969858)
		(stroke
			(width 0.2)
			(type default)
		)
		(fill no)
		(layer "In8.Cu")
	)
	(gr_circle
		(center 346.56776 -338.207858)
		(end 347.45676 -338.207858)
		(stroke
			(width 0.2)
			(type default)
		)
		(fill no)
		(layer "In8.Cu")
	)
	(gr_line
		(start 346.71635 -328.419206)
		(end 344.246962 -325.949818)
		(stroke
			(width 0.508)
			(type default)
		)
		(layer "In8.Cu")
	)
	(gr_line
		(start 346.86113 -284.616144)
		(end 345.921076 -284.616144)
		(stroke
			(width 0.6096)
			(type default)
		)
		(layer "In8.Cu")
	)
	(gr_line
		(start 346.86113 -282.996132)
		(end 345.921076 -282.996132)
		(stroke
			(width 0.6096)
			(type default)
		)
		(layer "In8.Cu")
	)
	(gr_line
		(start 346.86113 -281.37612)
		(end 345.921076 -281.37612)
		(stroke
			(width 0.6096)
			(type default)
		)
		(layer "In8.Cu")
	)
	(gr_line
		(start 347.028008 -248.532396)
		(end 345.618054 -249.342402)
		(stroke
			(width 0.254)
			(type default)
		)
		(layer "In8.Cu")
	)
	(gr_line
		(start 347.031056 -256.634488)
		(end 347.50121 -255.824482)
		(stroke
			(width 0.254)
			(type default)
		)
		(layer "In8.Cu")
	)
	(gr_circle
		(center 347.036898 -159.151066)
		(end 347.917008 -159.151066)
		(stroke
			(width 0.2)
			(type default)
		)
		(fill no)
		(layer "In8.Cu")
	)
	(gr_line
		(start 347.32849 -267.608558)
		(end 345.448382 -267.608558)
		(stroke
			(width 0.254)
			(type default)
		)
		(layer "In8.Cu")
	)
	(gr_line
		(start 347.50121 -255.824482)
		(end 348.44101 -255.824482)
		(stroke
			(width 0.254)
			(type default)
		)
		(layer "In8.Cu")
	)
	(gr_line
		(start 347.75521 -394.970762)
		(end 346.05468 -396.671292)
		(stroke
			(width 0.508)
			(type default)
		)
		(layer "In8.Cu")
	)
	(gr_line
		(start 347.79839 -266.798552)
		(end 347.32849 -267.608558)
		(stroke
			(width 0.254)
			(type default)
		)
		(layer "In8.Cu")
	)
	(gr_line
		(start 347.968062 -255.012444)
		(end 349.378016 -254.202438)
		(stroke
			(width 0.254)
			(type default)
		)
		(layer "In8.Cu")
	)
	(gr_line
		(start 347.968062 -253.392432)
		(end 349.378016 -252.582426)
		(stroke
			(width 0.254)
			(type default)
		)
		(layer "In8.Cu")
	)
	(gr_line
		(start 347.968062 -250.152408)
		(end 347.028008 -248.532396)
		(stroke
			(width 0.254)
			(type default)
		)
		(layer "In8.Cu")
	)
	(gr_line
		(start 348.268544 -265.988546)
		(end 347.79839 -266.798552)
		(stroke
			(width 0.254)
			(type default)
		)
		(layer "In8.Cu")
	)
	(gr_line
		(start 348.268544 -264.368534)
		(end 349.678498 -265.17854)
		(stroke
			(width 0.254)
			(type default)
		)
		(layer "In8.Cu")
	)
	(gr_line
		(start 348.44482 -394.970762)
		(end 347.75521 -394.970762)
		(stroke
			(width 0.508)
			(type default)
		)
		(layer "In8.Cu")
	)
	(gr_line
		(start 348.741238 -291.095938)
		(end 349.681292 -291.095938)
		(stroke
			(width 0.6096)
			(type default)
		)
		(layer "In8.Cu")
	)
	(gr_line
		(start 348.741238 -289.475926)
		(end 349.681292 -289.475926)
		(stroke
			(width 0.6096)
			(type default)
		)
		(layer "In8.Cu")
	)
	(gr_line
		(start 348.741238 -287.856168)
		(end 349.681292 -287.856168)
		(stroke
			(width 0.6096)
			(type default)
		)
		(layer "In8.Cu")
	)
	(gr_line
		(start 348.907862 -256.632456)
		(end 347.968062 -255.012444)
		(stroke
			(width 0.254)
			(type default)
		)
		(layer "In8.Cu")
	)
	(gr_line
		(start 348.90837 -256.63271)
		(end 347.96857 -255.012698)
		(stroke
			(width 0.254)
			(type default)
		)
		(layer "In8.Cu")
	)
	(gr_line
		(start 348.90837 -256.63271)
		(end 350.79559 -257.93065)
		(stroke
			(width 0.254)
			(type default)
		)
		(layer "In8.Cu")
	)
	(gr_line
		(start 349.208598 -262.748522)
		(end 349.678498 -263.558528)
		(stroke
			(width 0.254)
			(type default)
		)
		(layer "In8.Cu")
	)
	(gr_line
		(start 349.208598 -261.12851)
		(end 349.678498 -261.938516)
		(stroke
			(width 0.254)
			(type default)
		)
		(layer "In8.Cu")
	)
	(gr_line
		(start 349.378016 -254.202438)
		(end 347.968062 -253.392432)
		(stroke
			(width 0.254)
			(type default)
		)
		(layer "In8.Cu")
	)
	(gr_line
		(start 349.378016 -252.582426)
		(end 349.847916 -251.77242)
		(stroke
			(width 0.254)
			(type default)
		)
		(layer "In8.Cu")
	)
	(gr_line
		(start 349.378016 -250.962414)
		(end 347.968062 -250.152408)
		(stroke
			(width 0.254)
			(type default)
		)
		(layer "In8.Cu")
	)
	(gr_line
		(start 349.678498 -266.798552)
		(end 348.268544 -265.988546)
		(stroke
			(width 0.254)
			(type default)
		)
		(layer "In8.Cu")
	)
	(gr_line
		(start 349.678498 -265.17854)
		(end 348.268544 -265.988546)
		(stroke
			(width 0.254)
			(type default)
		)
		(layer "In8.Cu")
	)
	(gr_line
		(start 349.678498 -263.558528)
		(end 348.268544 -264.368534)
		(stroke
			(width 0.254)
			(type default)
		)
		(layer "In8.Cu")
	)
	(gr_line
		(start 349.678498 -261.938516)
		(end 349.208598 -262.748522)
		(stroke
			(width 0.254)
			(type default)
		)
		(layer "In8.Cu")
	)
	(gr_line
		(start 349.681292 -286.236156)
		(end 348.741238 -286.236156)
		(stroke
			(width 0.6096)
			(type default)
		)
		(layer "In8.Cu")
	)
	(gr_line
		(start 349.681292 -284.616144)
		(end 348.741238 -284.616144)
		(stroke
			(width 0.6096)
			(type default)
		)
		(layer "In8.Cu")
	)
	(gr_line
		(start 349.681292 -282.996132)
		(end 348.741238 -282.996132)
		(stroke
			(width 0.6096)
			(type default)
		)
		(layer "In8.Cu")
	)
	(gr_line
		(start 349.681292 -281.37612)
		(end 348.741238 -281.37612)
		(stroke
			(width 0.6096)
			(type default)
		)
		(layer "In8.Cu")
	)
	(gr_line
		(start 349.829374 -396.355316)
		(end 348.44482 -394.970762)
		(stroke
			(width 0.508)
			(type default)
		)
		(layer "In8.Cu")
	)
	(gr_line
		(start 349.847916 -251.77242)
		(end 349.378016 -250.962414)
		(stroke
			(width 0.254)
			(type default)
		)
		(layer "In8.Cu")
	)
	(gr_line
		(start 350.14789 -264.36828)
		(end 349.67799 -263.558274)
		(stroke
			(width 0.254)
			(type default)
		)
		(layer "In8.Cu")
	)
	(gr_line
		(start 350.220534 -267.340588)
		(end 349.678498 -266.798552)
		(stroke
			(width 0.254)
			(type default)
		)
		(layer "In8.Cu")
	)
	(gr_line
		(start 350.618552 -267.340588)
		(end 350.220534 -267.340588)
		(stroke
			(width 0.254)
			(type default)
		)
		(layer "In8.Cu")
	)
	(gr_line
		(start 350.79559 -259.730494)
		(end 349.208598 -261.12851)
		(stroke
			(width 0.254)
			(type default)
		)
		(layer "In8.Cu")
	)
	(gr_line
		(start 350.79559 -257.93065)
		(end 350.79559 -259.730494)
		(stroke
			(width 0.254)
			(type default)
		)
		(layer "In8.Cu")
	)
	(gr_line
		(start 351.093532 -172.152564)
		(end 338.258912 -172.152564)
		(stroke
			(width 0.508)
			(type default)
		)
		(layer "In8.Cu")
	)
	(gr_line
		(start 351.093532 -172.152564)
		(end 351.855532 -172.914564)
		(stroke
			(width 0.508)
			(type default)
		)
		(layer "In8.Cu")
	)
	(gr_line
		(start 351.25787 -250.962414)
		(end 349.847916 -251.77242)
		(stroke
			(width 0.254)
			(type default)
		)
		(layer "In8.Cu")
	)
	(gr_line
		(start 351.43567 -156.591762)
		(end 358.13365 -163.289742)
		(stroke
			(width 0.508)
			(type default)
		)
		(layer "In8.Cu")
	)
	(gr_line
		(start 351.558098 -263.558274)
		(end 350.14789 -264.36828)
		(stroke
			(width 0.254)
			(type default)
		)
		(layer "In8.Cu")
	)
	(gr_line
		(start 351.558606 -266.798552)
		(end 350.618552 -267.340588)
		(stroke
			(width 0.254)
			(type default)
		)
		(layer "In8.Cu")
	)
	(gr_line
		(start 351.561146 -291.095938)
		(end 352.5012 -291.095938)
		(stroke
			(width 0.6096)
			(type default)
		)
		(layer "In8.Cu")
	)
	(gr_line
		(start 351.561146 -289.475926)
		(end 352.5012 -289.475926)
		(stroke
			(width 0.6096)
			(type default)
		)
		(layer "In8.Cu")
	)
	(gr_line
		(start 351.561146 -287.856168)
		(end 352.5012 -287.856168)
		(stroke
			(width 0.6096)
			(type default)
		)
		(layer "In8.Cu")
	)
	(gr_line
		(start 351.728024 -251.77242)
		(end 351.25787 -250.962414)
		(stroke
			(width 0.254)
			(type default)
		)
		(layer "In8.Cu")
	)
	(gr_line
		(start 351.855532 -178.629564)
		(end 353.633532 -180.407564)
		(stroke
			(width 0.508)
			(type default)
		)
		(layer "In8.Cu")
	)
	(gr_line
		(start 351.855532 -172.914564)
		(end 351.855532 -178.629564)
		(stroke
			(width 0.508)
			(type default)
		)
		(layer "In8.Cu")
	)
	(gr_line
		(start 352.028506 -265.988546)
		(end 351.558606 -266.798552)
		(stroke
			(width 0.254)
			(type default)
		)
		(layer "In8.Cu")
	)
	(gr_circle
		(center 352.322638 -167.430196)
		(end 353.211638 -167.430196)
		(stroke
			(width 0.2)
			(type default)
		)
		(fill no)
		(layer "In8.Cu")
	)
	(gr_circle
		(center 352.322638 -166.693596)
		(end 353.211638 -166.693596)
		(stroke
			(width 0.2)
			(type default)
		)
		(fill no)
		(layer "In8.Cu")
	)
	(gr_circle
		(center 352.322638 -165.956996)
		(end 353.211638 -165.956996)
		(stroke
			(width 0.2)
			(type default)
		)
		(fill no)
		(layer "In8.Cu")
	)
	(gr_circle
		(center 352.356928 -341.922862)
		(end 353.237038 -341.922862)
		(stroke
			(width 0.2)
			(type default)
		)
		(fill no)
		(layer "In8.Cu")
	)
	(gr_line
		(start 352.5012 -286.236156)
		(end 351.561146 -286.236156)
		(stroke
			(width 0.6096)
			(type default)
		)
		(layer "In8.Cu")
	)
	(gr_line
		(start 352.5012 -284.616144)
		(end 351.561146 -284.616144)
		(stroke
			(width 0.6096)
			(type default)
		)
		(layer "In8.Cu")
	)
	(gr_line
		(start 352.5012 -282.996132)
		(end 351.561146 -282.996132)
		(stroke
			(width 0.6096)
			(type default)
		)
		(layer "In8.Cu")
	)
	(gr_line
		(start 352.53041 -328.419206)
		(end 346.71635 -328.419206)
		(stroke
			(width 0.508)
			(type default)
		)
		(layer "In8.Cu")
	)
	(gr_circle
		(center 352.856038 -166.312596)
		(end 353.745038 -166.312596)
		(stroke
			(width 0.2)
			(type default)
		)
		(fill no)
		(layer "In8.Cu")
	)
	(gr_circle
		(center 352.881438 -167.074596)
		(end 353.770438 -167.074596)
		(stroke
			(width 0.2)
			(type default)
		)
		(fill no)
		(layer "In8.Cu")
	)
	(gr_circle
		(center 352.974148 -341.922862)
		(end 353.854258 -341.922862)
		(stroke
			(width 0.2)
			(type default)
		)
		(fill no)
		(layer "In8.Cu")
	)
	(gr_line
		(start 353.137978 -250.962414)
		(end 351.728024 -251.77242)
		(stroke
			(width 0.254)
			(type default)
		)
		(layer "In8.Cu")
	)
	(gr_line
		(start 353.348798 -327.600818)
		(end 352.53041 -328.419206)
		(stroke
			(width 0.508)
			(type default)
		)
		(layer "In8.Cu")
	)
	(gr_circle
		(center 353.406202 -166.635176)
		(end 354.295202 -166.635176)
		(stroke
			(width 0.2)
			(type default)
		)
		(fill no)
		(layer "In8.Cu")
	)
	(gr_circle
		(center 353.406202 -165.898576)
		(end 354.295202 -165.898576)
		(stroke
			(width 0.2)
			(type default)
		)
		(fill no)
		(layer "In8.Cu")
	)
	(gr_line
		(start 353.43084 -262.180324)
		(end 351.558098 -263.558274)
		(stroke
			(width 0.254)
			(type default)
		)
		(layer "In8.Cu")
	)
	(gr_line
		(start 353.43846 -266.798552)
		(end 352.028506 -265.988546)
		(stroke
			(width 0.254)
			(type default)
		)
		(layer "In8.Cu")
	)
	(gr_line
		(start 353.54641 -327.600818)
		(end 379.758702 -327.600818)
		(stroke
			(width 0.508)
			(type default)
		)
		(layer "In8.Cu")
	)
	(gr_circle
		(center 353.591368 -341.922862)
		(end 354.471478 -341.922862)
		(stroke
			(width 0.2)
			(type default)
		)
		(fill no)
		(layer "In8.Cu")
	)
	(gr_line
		(start 353.607878 -251.77242)
		(end 353.137978 -250.962414)
		(stroke
			(width 0.254)
			(type default)
		)
		(layer "In8.Cu")
	)
	(gr_line
		(start 353.633532 -180.407564)
		(end 359.221532 -180.407564)
		(stroke
			(width 0.508)
			(type default)
		)
		(layer "In8.Cu")
	)
	(gr_line
		(start 353.72294 -327.600818)
		(end 353.348798 -327.600818)
		(stroke
			(width 0.508)
			(type default)
		)
		(layer "In8.Cu")
	)
	(gr_circle
		(center 353.899724 -341.22741)
		(end 354.788724 -341.22741)
		(stroke
			(width 0.2)
			(type default)
		)
		(fill no)
		(layer "In8.Cu")
	)
	(gr_circle
		(center 353.899724 -340.49081)
		(end 354.788724 -340.49081)
		(stroke
			(width 0.2)
			(type default)
		)
		(fill no)
		(layer "In8.Cu")
	)
	(gr_line
		(start 353.908614 -267.608558)
		(end 353.43846 -266.798552)
		(stroke
			(width 0.254)
			(type default)
		)
		(layer "In8.Cu")
	)
	(gr_circle
		(center 353.990656 -168.982136)
		(end 354.879656 -168.982136)
		(stroke
			(width 0.2)
			(type default)
		)
		(fill no)
		(layer "In8.Cu")
	)
	(gr_circle
		(center 353.990656 -168.245536)
		(end 354.879656 -168.245536)
		(stroke
			(width 0.2)
			(type default)
		)
		(fill no)
		(layer "In8.Cu")
	)
	(gr_circle
		(center 354.108258 -167.507666)
		(end 354.988368 -167.507666)
		(stroke
			(width 0.2)
			(type default)
		)
		(fill no)
		(layer "In8.Cu")
	)
	(gr_line
		(start 354.28809 -261.323074)
		(end 353.43084 -262.180324)
		(stroke
			(width 0.254)
			(type default)
		)
		(layer "In8.Cu")
	)
	(gr_circle
		(center 354.293424 -343.531952)
		(end 355.182424 -343.531952)
		(stroke
			(width 0.2)
			(type default)
		)
		(fill no)
		(layer "In8.Cu")
	)
	(gr_circle
		(center 354.293424 -342.795352)
		(end 355.182424 -342.795352)
		(stroke
			(width 0.2)
			(type default)
		)
		(fill no)
		(layer "In8.Cu")
	)
	(gr_line
		(start 354.381054 -291.095938)
		(end 355.321108 -291.095938)
		(stroke
			(width 0.6096)
			(type default)
		)
		(layer "In8.Cu")
	)
	(gr_line
		(start 354.381054 -289.475926)
		(end 355.321108 -289.475926)
		(stroke
			(width 0.6096)
			(type default)
		)
		(layer "In8.Cu")
	)
	(gr_line
		(start 354.381054 -287.856168)
		(end 355.321108 -287.856168)
		(stroke
			(width 0.6096)
			(type default)
		)
		(layer "In8.Cu")
	)
	(gr_circle
		(center 354.725478 -167.507666)
		(end 355.605588 -167.507666)
		(stroke
			(width 0.2)
			(type default)
		)
		(fill no)
		(layer "In8.Cu")
	)
	(gr_circle
		(center 354.818188 -342.355932)
		(end 355.707188 -342.355932)
		(stroke
			(width 0.2)
			(type default)
		)
		(fill no)
		(layer "In8.Cu")
	)
	(gr_circle
		(center 354.843588 -343.117932)
		(end 355.732588 -343.117932)
		(stroke
			(width 0.2)
			(type default)
		)
		(fill no)
		(layer "In8.Cu")
	)
	(gr_line
		(start 355.018086 -250.962414)
		(end 353.607878 -251.77242)
		(stroke
			(width 0.254)
			(type default)
		)
		(layer "In8.Cu")
	)
	(gr_line
		(start 355.318568 -266.798552)
		(end 353.908614 -267.608558)
		(stroke
			(width 0.254)
			(type default)
		)
		(layer "In8.Cu")
	)
	(gr_line
		(start 355.321108 -286.236156)
		(end 354.381054 -286.236156)
		(stroke
			(width 0.6096)
			(type default)
		)
		(layer "In8.Cu")
	)
	(gr_line
		(start 355.321108 -284.616144)
		(end 354.381054 -284.616144)
		(stroke
			(width 0.6096)
			(type default)
		)
		(layer "In8.Cu")
	)
	(gr_line
		(start 355.321108 -282.996132)
		(end 354.381054 -282.996132)
		(stroke
			(width 0.6096)
			(type default)
		)
		(layer "In8.Cu")
	)
	(gr_circle
		(center 355.342698 -167.507666)
		(end 356.222808 -167.507666)
		(stroke
			(width 0.2)
			(type default)
		)
		(fill no)
		(layer "In8.Cu")
	)
	(gr_circle
		(center 355.376988 -343.473532)
		(end 356.265988 -343.473532)
		(stroke
			(width 0.2)
			(type default)
		)
		(fill no)
		(layer "In8.Cu")
	)
	(gr_circle
		(center 355.376988 -342.736932)
		(end 356.265988 -342.736932)
		(stroke
			(width 0.2)
			(type default)
		)
		(fill no)
		(layer "In8.Cu")
	)
	(gr_circle
		(center 355.376988 -342.000332)
		(end 356.265988 -342.000332)
		(stroke
			(width 0.2)
			(type default)
		)
		(fill no)
		(layer "In8.Cu")
	)
	(gr_line
		(start 355.487986 -251.77242)
		(end 355.018086 -250.962414)
		(stroke
			(width 0.254)
			(type default)
		)
		(layer "In8.Cu")
	)
	(gr_line
		(start 355.788468 -265.988546)
		(end 355.318568 -266.798552)
		(stroke
			(width 0.254)
			(type default)
		)
		(layer "In8.Cu")
	)
	(gr_line
		(start 356.731062 -290.285932)
		(end 357.671116 -290.285932)
		(stroke
			(width 0.6096)
			(type default)
		)
		(layer "In8.Cu")
	)
	(gr_line
		(start 356.731062 -288.66592)
		(end 357.671116 -288.66592)
		(stroke
			(width 0.6096)
			(type default)
		)
		(layer "In8.Cu")
	)
	(gr_line
		(start 356.731062 -287.045908)
		(end 357.671116 -287.045908)
		(stroke
			(width 0.6096)
			(type default)
		)
		(layer "In8.Cu")
	)
	(gr_line
		(start 356.89794 -250.962414)
		(end 355.487986 -251.77242)
		(stroke
			(width 0.254)
			(type default)
		)
		(layer "In8.Cu")
	)
	(gr_line
		(start 357.198422 -266.798552)
		(end 355.788468 -265.988546)
		(stroke
			(width 0.254)
			(type default)
		)
		(layer "In8.Cu")
	)
	(gr_line
		(start 357.368094 -250.152408)
		(end 356.89794 -250.962414)
		(stroke
			(width 0.254)
			(type default)
		)
		(layer "In8.Cu")
	)
	(gr_line
		(start 357.668576 -267.608558)
		(end 357.198422 -266.798552)
		(stroke
			(width 0.254)
			(type default)
		)
		(layer "In8.Cu")
	)
	(gr_line
		(start 357.671116 -285.42615)
		(end 356.731062 -285.42615)
		(stroke
			(width 0.6096)
			(type default)
		)
		(layer "In8.Cu")
	)
	(gr_line
		(start 357.671116 -283.806138)
		(end 356.731062 -283.806138)
		(stroke
			(width 0.6096)
			(type default)
		)
		(layer "In8.Cu")
	)
	(gr_line
		(start 357.671116 -282.186126)
		(end 356.731062 -282.186126)
		(stroke
			(width 0.6096)
			(type default)
		)
		(layer "In8.Cu")
	)
	(gr_line
		(start 358.084882 -396.355316)
		(end 349.829374 -396.355316)
		(stroke
			(width 0.508)
			(type default)
		)
		(layer "In8.Cu")
	)
	(gr_line
		(start 358.13365 -163.289742)
		(end 372.847616 -163.289742)
		(stroke
			(width 0.508)
			(type default)
		)
		(layer "In8.Cu")
	)
	(gr_line
		(start 358.205532 -391.971784)
		(end 358.485694 -392.251946)
		(stroke
			(width 0.508)
			(type default)
		)
		(layer "In8.Cu")
	)
	(gr_line
		(start 358.307894 -395.761972)
		(end 358.49306 -395.947138)
		(stroke
			(width 0.508)
			(type default)
		)
		(layer "In8.Cu")
	)
	(gr_line
		(start 358.307894 -395.12621)
		(end 358.307894 -395.761972)
		(stroke
			(width 0.508)
			(type default)
		)
		(layer "In8.Cu")
	)
	(gr_line
		(start 358.307894 -395.12621)
		(end 358.307894 -394.757402)
		(stroke
			(width 0.254)
			(type default)
		)
		(layer "In8.Cu")
	)
	(gr_line
		(start 358.307894 -394.757402)
		(end 358.485694 -394.579602)
		(stroke
			(width 0.254)
			(type default)
		)
		(layer "In8.Cu")
	)
	(gr_line
		(start 358.485694 -394.579602)
		(end 358.485694 -393.057634)
		(stroke
			(width 0.254)
			(type default)
		)
		(layer "In8.Cu")
	)
	(gr_line
		(start 358.485694 -392.251946)
		(end 358.485694 -393.057634)
		(stroke
			(width 0.508)
			(type default)
		)
		(layer "In8.Cu")
	)
	(gr_line
		(start 358.49306 -395.947138)
		(end 358.084882 -396.355316)
		(stroke
			(width 0.508)
			(type default)
		)
		(layer "In8.Cu")
	)
	(gr_line
		(start 358.778048 -250.962414)
		(end 357.368094 -250.152408)
		(stroke
			(width 0.254)
			(type default)
		)
		(layer "In8.Cu")
	)
	(gr_line
		(start 359.07853 -266.798552)
		(end 357.668576 -267.608558)
		(stroke
			(width 0.254)
			(type default)
		)
		(layer "In8.Cu")
	)
	(gr_line
		(start 359.221532 -180.407564)
		(end 360.237532 -181.423564)
		(stroke
			(width 0.508)
			(type default)
		)
		(layer "In8.Cu")
	)
	(gr_circle
		(center 359.58526 -152.71242)
		(end 360.98226 -152.71242)
		(stroke
			(width 0.2)
			(type default)
		)
		(fill no)
		(layer "In8.Cu")
	)
	(gr_line
		(start 360.237532 -187.011564)
		(end 362.015532 -188.789564)
		(stroke
			(width 0.508)
			(type default)
		)
		(layer "In8.Cu")
	)
	(gr_line
		(start 360.237532 -181.423564)
		(end 360.237532 -187.011564)
		(stroke
			(width 0.508)
			(type default)
		)
		(layer "In8.Cu")
	)
	(gr_circle
		(center 360.603038 -175.705516)
		(end 361.492038 -175.705516)
		(stroke
			(width 0.2)
			(type default)
		)
		(fill no)
		(layer "In8.Cu")
	)
	(gr_circle
		(center 360.603038 -174.968916)
		(end 361.492038 -174.968916)
		(stroke
			(width 0.2)
			(type default)
		)
		(fill no)
		(layer "In8.Cu")
	)
	(gr_circle
		(center 360.603038 -174.232316)
		(end 361.492038 -174.232316)
		(stroke
			(width 0.2)
			(type default)
		)
		(fill no)
		(layer "In8.Cu")
	)
	(gr_line
		(start 361.113578 -154.494484)
		(end 365.43742 -158.818326)
		(stroke
			(width 0.508)
			(type default)
		)
		(layer "In8.Cu")
	)
	(gr_line
		(start 361.113578 -150.968964)
		(end 361.113578 -154.494484)
		(stroke
			(width 0.508)
			(type default)
		)
		(layer "In8.Cu")
	)
	(gr_circle
		(center 361.136438 -174.587916)
		(end 362.025438 -174.587916)
		(stroke
			(width 0.2)
			(type default)
		)
		(fill no)
		(layer "In8.Cu")
	)
	(gr_circle
		(center 361.161838 -175.349916)
		(end 362.050838 -175.349916)
		(stroke
			(width 0.2)
			(type default)
		)
		(fill no)
		(layer "In8.Cu")
	)
	(gr_line
		(start 361.597956 -250.962414)
		(end 358.778048 -250.962414)
		(stroke
			(width 0.254)
			(type default)
		)
		(layer "In8.Cu")
	)
	(gr_circle
		(center 361.686602 -174.910496)
		(end 362.575602 -174.910496)
		(stroke
			(width 0.2)
			(type default)
		)
		(fill no)
		(layer "In8.Cu")
	)
	(gr_circle
		(center 361.686602 -174.173896)
		(end 362.575602 -174.173896)
		(stroke
			(width 0.2)
			(type default)
		)
		(fill no)
		(layer "In8.Cu")
	)
	(gr_line
		(start 361.898438 -266.798552)
		(end 359.07853 -266.798552)
		(stroke
			(width 0.254)
			(type default)
		)
		(layer "In8.Cu")
	)
	(gr_line
		(start 362.015532 -188.789564)
		(end 366.907318 -188.789564)
		(stroke
			(width 0.508)
			(type default)
		)
		(layer "In8.Cu")
	)
	(gr_circle
		(center 362.271056 -177.254916)
		(end 363.160056 -177.254916)
		(stroke
			(width 0.2)
			(type default)
		)
		(fill no)
		(layer "In8.Cu")
	)
	(gr_circle
		(center 362.271056 -176.518316)
		(end 363.160056 -176.518316)
		(stroke
			(width 0.2)
			(type default)
		)
		(fill no)
		(layer "In8.Cu")
	)
	(gr_line
		(start 362.364782 -285.42615)
		(end 363.304836 -285.42615)
		(stroke
			(width 0.6096)
			(type default)
		)
		(layer "In8.Cu")
	)
	(gr_line
		(start 362.364782 -283.806138)
		(end 363.304836 -283.806138)
		(stroke
			(width 0.6096)
			(type default)
		)
		(layer "In8.Cu")
	)
	(gr_line
		(start 362.364782 -282.186126)
		(end 363.304836 -282.186126)
		(stroke
			(width 0.6096)
			(type default)
		)
		(layer "In8.Cu")
	)
	(gr_circle
		(center 362.396278 -175.859186)
		(end 363.276388 -175.859186)
		(stroke
			(width 0.2)
			(type default)
		)
		(fill no)
		(layer "In8.Cu")
	)
	(gr_line
		(start 363.004862 -248.534174)
		(end 362.064808 -248.534174)
		(stroke
			(width 0.6096)
			(type default)
		)
		(layer "In8.Cu")
	)
	(gr_line
		(start 363.004862 -246.914162)
		(end 362.064808 -246.914162)
		(stroke
			(width 0.6096)
			(type default)
		)
		(layer "In8.Cu")
	)
	(gr_line
		(start 363.004862 -245.29415)
		(end 362.064808 -245.29415)
		(stroke
			(width 0.6096)
			(type default)
		)
		(layer "In8.Cu")
	)
	(gr_line
		(start 363.004862 -243.674138)
		(end 362.064808 -243.674138)
		(stroke
			(width 0.6096)
			(type default)
		)
		(layer "In8.Cu")
	)
	(gr_line
		(start 363.00791 -250.152408)
		(end 361.597956 -250.962414)
		(stroke
			(width 0.254)
			(type default)
		)
		(layer "In8.Cu")
	)
	(gr_circle
		(center 363.013498 -175.859186)
		(end 363.893608 -175.859186)
		(stroke
			(width 0.2)
			(type default)
		)
		(fill no)
		(layer "In8.Cu")
	)
	(gr_line
		(start 363.308392 -265.988546)
		(end 361.898438 -266.798552)
		(stroke
			(width 0.254)
			(type default)
		)
		(layer "In8.Cu")
	)
	(gr_line
		(start 363.478064 -250.962414)
		(end 363.00791 -250.152408)
		(stroke
			(width 0.254)
			(type default)
		)
		(layer "In8.Cu")
	)
	(gr_circle
		(center 363.630718 -175.859186)
		(end 364.510828 -175.859186)
		(stroke
			(width 0.2)
			(type default)
		)
		(fill no)
		(layer "In8.Cu")
	)
	(gr_line
		(start 363.778546 -266.798552)
		(end 363.308392 -265.988546)
		(stroke
			(width 0.254)
			(type default)
		)
		(layer "In8.Cu")
	)
	(gr_line
		(start 364.137956 -261.323074)
		(end 354.28809 -261.323074)
		(stroke
			(width 0.254)
			(type default)
		)
		(layer "In8.Cu")
	)
	(gr_line
		(start 364.485174 -261.670292)
		(end 364.137956 -261.323074)
		(stroke
			(width 0.254)
			(type default)
		)
		(layer "In8.Cu")
	)
	(gr_line
		(start 364.71479 -286.236156)
		(end 365.654844 -286.236156)
		(stroke
			(width 0.6096)
			(type default)
		)
		(layer "In8.Cu")
	)
	(gr_line
		(start 364.71479 -284.616144)
		(end 365.654844 -284.616144)
		(stroke
			(width 0.6096)
			(type default)
		)
		(layer "In8.Cu")
	)
	(gr_line
		(start 364.71479 -282.996132)
		(end 365.654844 -282.996132)
		(stroke
			(width 0.6096)
			(type default)
		)
		(layer "In8.Cu")
	)
	(gr_line
		(start 364.888018 -251.77242)
		(end 363.478064 -250.962414)
		(stroke
			(width 0.254)
			(type default)
		)
		(layer "In8.Cu")
	)
	(gr_line
		(start 365.1885 -267.608558)
		(end 363.778546 -266.798552)
		(stroke
			(width 0.254)
			(type default)
		)
		(layer "In8.Cu")
	)
	(gr_line
		(start 365.35487 -247.724168)
		(end 364.414816 -247.724168)
		(stroke
			(width 0.6096)
			(type default)
		)
		(layer "In8.Cu")
	)
	(gr_line
		(start 365.35487 -246.104156)
		(end 364.414816 -246.104156)
		(stroke
			(width 0.6096)
			(type default)
		)
		(layer "In8.Cu")
	)
	(gr_line
		(start 365.35487 -244.484144)
		(end 364.414816 -244.484144)
		(stroke
			(width 0.6096)
			(type default)
		)
		(layer "In8.Cu")
	)
	(gr_line
		(start 365.357918 -250.962414)
		(end 364.888018 -251.77242)
		(stroke
			(width 0.254)
			(type default)
		)
		(layer "In8.Cu")
	)
	(gr_line
		(start 365.43742 -158.818326)
		(end 380.716536 -158.818326)
		(stroke
			(width 0.508)
			(type default)
		)
		(layer "In8.Cu")
	)
	(gr_line
		(start 365.6584 -266.798552)
		(end 365.1885 -267.608558)
		(stroke
			(width 0.254)
			(type default)
		)
		(layer "In8.Cu")
	)
	(gr_line
		(start 365.783622 -395.947138)
		(end 358.49306 -395.947138)
		(stroke
			(width 0.508)
			(type default)
		)
		(layer "In8.Cu")
	)
	(gr_line
		(start 366.359694 -395.371066)
		(end 365.783622 -395.947138)
		(stroke
			(width 0.508)
			(type default)
		)
		(layer "In8.Cu")
	)
	(gr_line
		(start 366.359694 -392.52779)
		(end 366.359694 -395.371066)
		(stroke
			(width 0.508)
			(type default)
		)
		(layer "In8.Cu")
	)
	(gr_circle
		(center 366.744504 -164.53358)
		(end 367.633504 -164.53358)
		(stroke
			(width 0.2)
			(type default)
		)
		(fill no)
		(layer "In8.Cu")
	)
	(gr_circle
		(center 366.744504 -163.89858)
		(end 367.633504 -163.89858)
		(stroke
			(width 0.2)
			(type default)
		)
		(fill no)
		(layer "In8.Cu")
	)
	(gr_circle
		(center 366.757204 -165.19398)
		(end 367.646204 -165.19398)
		(stroke
			(width 0.2)
			(type default)
		)
		(fill no)
		(layer "In8.Cu")
	)
	(gr_line
		(start 366.767872 -250.152408)
		(end 365.357918 -250.962414)
		(stroke
			(width 0.254)
			(type default)
		)
		(layer "In8.Cu")
	)
	(gr_line
		(start 366.773206 -392.114278)
		(end 366.359694 -392.52779)
		(stroke
			(width 0.508)
			(type default)
		)
		(layer "In8.Cu")
	)
	(gr_line
		(start 366.907318 -188.789564)
		(end 371.860318 -193.742564)
		(stroke
			(width 0.508)
			(type default)
		)
		(layer "In8.Cu")
	)
	(gr_line
		(start 367.068354 -265.988546)
		(end 365.6584 -266.798552)
		(stroke
			(width 0.254)
			(type default)
		)
		(layer "In8.Cu")
	)
	(gr_line
		(start 367.238026 -250.962414)
		(end 366.767872 -250.152408)
		(stroke
			(width 0.254)
			(type default)
		)
		(layer "In8.Cu")
	)
	(gr_circle
		(center 367.379504 -164.53358)
		(end 368.268504 -164.53358)
		(stroke
			(width 0.2)
			(type default)
		)
		(fill no)
		(layer "In8.Cu")
	)
	(gr_circle
		(center 367.379504 -163.89858)
		(end 368.268504 -163.89858)
		(stroke
			(width 0.2)
			(type default)
		)
		(fill no)
		(layer "In8.Cu")
	)
	(gr_circle
		(center 367.392204 -165.19398)
		(end 368.281204 -165.19398)
		(stroke
			(width 0.2)
			(type default)
		)
		(fill no)
		(layer "In8.Cu")
	)
	(gr_line
		(start 367.534698 -286.236156)
		(end 368.474752 -286.236156)
		(stroke
			(width 0.6096)
			(type default)
		)
		(layer "In8.Cu")
	)
	(gr_line
		(start 367.534698 -284.616144)
		(end 368.474752 -284.616144)
		(stroke
			(width 0.6096)
			(type default)
		)
		(layer "In8.Cu")
	)
	(gr_line
		(start 367.534698 -282.996132)
		(end 368.474752 -282.996132)
		(stroke
			(width 0.6096)
			(type default)
		)
		(layer "In8.Cu")
	)
	(gr_line
		(start 367.538508 -266.798552)
		(end 367.068354 -265.988546)
		(stroke
			(width 0.254)
			(type default)
		)
		(layer "In8.Cu")
	)
	(gr_circle
		(center 368.044984 -164.53358)
		(end 368.933984 -164.53358)
		(stroke
			(width 0.2)
			(type default)
		)
		(fill no)
		(layer "In8.Cu")
	)
	(gr_circle
		(center 368.044984 -163.89858)
		(end 368.933984 -163.89858)
		(stroke
			(width 0.2)
			(type default)
		)
		(fill no)
		(layer "In8.Cu")
	)
	(gr_circle
		(center 368.057684 -165.19398)
		(end 368.946684 -165.19398)
		(stroke
			(width 0.2)
			(type default)
		)
		(fill no)
		(layer "In8.Cu")
	)
	(gr_line
		(start 368.174778 -247.724168)
		(end 367.234724 -247.724168)
		(stroke
			(width 0.6096)
			(type default)
		)
		(layer "In8.Cu")
	)
	(gr_line
		(start 368.174778 -246.104156)
		(end 367.234724 -246.104156)
		(stroke
			(width 0.6096)
			(type default)
		)
		(layer "In8.Cu")
	)
	(gr_line
		(start 368.174778 -244.484144)
		(end 367.234724 -244.484144)
		(stroke
			(width 0.6096)
			(type default)
		)
		(layer "In8.Cu")
	)
	(gr_line
		(start 368.210084 -261.670292)
		(end 364.485174 -261.670292)
		(stroke
			(width 0.254)
			(type default)
		)
		(layer "In8.Cu")
	)
	(gr_line
		(start 368.478054 -261.938262)
		(end 368.210084 -261.670292)
		(stroke
			(width 0.254)
			(type default)
		)
		(layer "In8.Cu")
	)
	(gr_line
		(start 368.64798 -251.77242)
		(end 367.238026 -250.962414)
		(stroke
			(width 0.254)
			(type default)
		)
		(layer "In8.Cu")
	)
	(gr_circle
		(center 368.679984 -164.53358)
		(end 369.568984 -164.53358)
		(stroke
			(width 0.2)
			(type default)
		)
		(fill no)
		(layer "In8.Cu")
	)
	(gr_circle
		(center 368.679984 -163.89858)
		(end 369.568984 -163.89858)
		(stroke
			(width 0.2)
			(type default)
		)
		(fill no)
		(layer "In8.Cu")
	)
	(gr_circle
		(center 368.692684 -165.19398)
		(end 369.581684 -165.19398)
		(stroke
			(width 0.2)
			(type default)
		)
		(fill no)
		(layer "In8.Cu")
	)
	(gr_line
		(start 368.948462 -267.608558)
		(end 367.538508 -266.798552)
		(stroke
			(width 0.254)
			(type default)
		)
		(layer "In8.Cu")
	)
	(gr_circle
		(center 368.96421 -179.204874)
		(end 369.85321 -179.204874)
		(stroke
			(width 0.2)
			(type default)
		)
		(fill no)
		(layer "In8.Cu")
	)
	(gr_line
		(start 369.11788 -250.962414)
		(end 368.64798 -251.77242)
		(stroke
			(width 0.254)
			(type default)
		)
		(layer "In8.Cu")
	)
	(gr_circle
		(center 369.314984 -164.53358)
		(end 370.203984 -164.53358)
		(stroke
			(width 0.2)
			(type default)
		)
		(fill no)
		(layer "In8.Cu")
	)
	(gr_circle
		(center 369.314984 -163.89858)
		(end 370.203984 -163.89858)
		(stroke
			(width 0.2)
			(type default)
		)
		(fill no)
		(layer "In8.Cu")
	)
	(gr_circle
		(center 369.327684 -165.19398)
		(end 370.216684 -165.19398)
		(stroke
			(width 0.2)
			(type default)
		)
		(fill no)
		(layer "In8.Cu")
	)
	(gr_line
		(start 369.418362 -266.798552)
		(end 368.948462 -267.608558)
		(stroke
			(width 0.254)
			(type default)
		)
		(layer "In8.Cu")
	)
	(gr_circle
		(center 369.49761 -179.560474)
		(end 370.38661 -179.560474)
		(stroke
			(width 0.2)
			(type default)
		)
		(fill no)
		(layer "In8.Cu")
	)
	(gr_circle
		(center 369.49761 -178.798474)
		(end 370.38661 -178.798474)
		(stroke
			(width 0.2)
			(type default)
		)
		(fill no)
		(layer "In8.Cu")
	)
	(gr_circle
		(center 369.49761 -178.036474)
		(end 370.38661 -178.036474)
		(stroke
			(width 0.2)
			(type default)
		)
		(fill no)
		(layer "In8.Cu")
	)
	(gr_circle
		(center 369.52301 -180.322474)
		(end 370.41201 -180.322474)
		(stroke
			(width 0.2)
			(type default)
		)
		(fill no)
		(layer "In8.Cu")
	)
	(gr_line
		(start 369.888008 -262.748268)
		(end 368.478054 -261.938262)
		(stroke
			(width 0.254)
			(type default)
		)
		(layer "In8.Cu")
	)
	(gr_circle
		(center 369.949984 -164.53358)
		(end 370.838984 -164.53358)
		(stroke
			(width 0.2)
			(type default)
		)
		(fill no)
		(layer "In8.Cu")
	)
	(gr_circle
		(center 369.949984 -163.89858)
		(end 370.838984 -163.89858)
		(stroke
			(width 0.2)
			(type default)
		)
		(fill no)
		(layer "In8.Cu")
	)
	(gr_circle
		(center 369.962684 -165.19398)
		(end 370.851684 -165.19398)
		(stroke
			(width 0.2)
			(type default)
		)
		(fill no)
		(layer "In8.Cu")
	)
	(gr_circle
		(center 370.047774 -179.883054)
		(end 370.936774 -179.883054)
		(stroke
			(width 0.2)
			(type default)
		)
		(fill no)
		(layer "In8.Cu")
	)
	(gr_circle
		(center 370.047774 -179.146454)
		(end 370.936774 -179.146454)
		(stroke
			(width 0.2)
			(type default)
		)
		(fill no)
		(layer "In8.Cu")
	)
	(gr_line
		(start 370.35486 -286.236156)
		(end 371.294914 -286.236156)
		(stroke
			(width 0.6096)
			(type default)
		)
		(layer "In8.Cu")
	)
	(gr_line
		(start 370.35486 -284.616144)
		(end 371.294914 -284.616144)
		(stroke
			(width 0.6096)
			(type default)
		)
		(layer "In8.Cu")
	)
	(gr_line
		(start 370.35486 -282.996132)
		(end 371.294914 -282.996132)
		(stroke
			(width 0.6096)
			(type default)
		)
		(layer "In8.Cu")
	)
	(gr_line
		(start 370.35486 -281.37612)
		(end 371.294914 -281.37612)
		(stroke
			(width 0.6096)
			(type default)
		)
		(layer "In8.Cu")
	)
	(gr_line
		(start 370.357908 -261.938262)
		(end 369.888008 -262.748268)
		(stroke
			(width 0.254)
			(type default)
		)
		(layer "In8.Cu")
	)
	(gr_line
		(start 370.528088 -250.152408)
		(end 369.11788 -250.962414)
		(stroke
			(width 0.254)
			(type default)
		)
		(layer "In8.Cu")
	)
	(gr_circle
		(center 370.529358 -182.141876)
		(end 371.418358 -182.141876)
		(stroke
			(width 0.2)
			(type default)
		)
		(fill no)
		(layer "In8.Cu")
	)
	(gr_circle
		(center 370.529358 -181.405276)
		(end 371.418358 -181.405276)
		(stroke
			(width 0.2)
			(type default)
		)
		(fill no)
		(layer "In8.Cu")
	)
	(gr_circle
		(center 370.686584 -164.53358)
		(end 371.575584 -164.53358)
		(stroke
			(width 0.2)
			(type default)
		)
		(fill no)
		(layer "In8.Cu")
	)
	(gr_circle
		(center 370.686584 -163.89858)
		(end 371.575584 -163.89858)
		(stroke
			(width 0.2)
			(type default)
		)
		(fill no)
		(layer "In8.Cu")
	)
	(gr_circle
		(center 370.699284 -165.19398)
		(end 371.588284 -165.19398)
		(stroke
			(width 0.2)
			(type default)
		)
		(fill no)
		(layer "In8.Cu")
	)
	(gr_circle
		(center 370.74221 -180.803804)
		(end 371.62232 -180.803804)
		(stroke
			(width 0.2)
			(type default)
		)
		(fill no)
		(layer "In8.Cu")
	)
	(gr_line
		(start 370.82857 -265.988546)
		(end 369.418362 -266.798552)
		(stroke
			(width 0.254)
			(type default)
		)
		(layer "In8.Cu")
	)
	(gr_line
		(start 370.99494 -247.724168)
		(end 370.054886 -247.724168)
		(stroke
			(width 0.6096)
			(type default)
		)
		(layer "In8.Cu")
	)
	(gr_line
		(start 370.99494 -246.104156)
		(end 370.054886 -246.104156)
		(stroke
			(width 0.6096)
			(type default)
		)
		(layer "In8.Cu")
	)
	(gr_line
		(start 370.99494 -244.484144)
		(end 370.054886 -244.484144)
		(stroke
			(width 0.6096)
			(type default)
		)
		(layer "In8.Cu")
	)
	(gr_line
		(start 370.997988 -250.962414)
		(end 370.528088 -250.152408)
		(stroke
			(width 0.254)
			(type default)
		)
		(layer "In8.Cu")
	)
	(gr_line
		(start 371.29847 -266.798552)
		(end 370.82857 -265.988546)
		(stroke
			(width 0.254)
			(type default)
		)
		(layer "In8.Cu")
	)
	(gr_circle
		(center 371.35943 -180.803804)
		(end 372.23954 -180.803804)
		(stroke
			(width 0.2)
			(type default)
		)
		(fill no)
		(layer "In8.Cu")
	)
	(gr_line
		(start 371.767862 -262.748268)
		(end 370.357908 -261.938262)
		(stroke
			(width 0.254)
			(type default)
		)
		(layer "In8.Cu")
	)
	(gr_line
		(start 371.860318 -193.742564)
		(end 393.30122 -193.742564)
		(stroke
			(width 0.508)
			(type default)
		)
		(layer "In8.Cu")
	)
	(gr_circle
		(center 371.97665 -180.803804)
		(end 372.85676 -180.803804)
		(stroke
			(width 0.2)
			(type default)
		)
		(fill no)
		(layer "In8.Cu")
	)
	(gr_line
		(start 372.407942 -251.77242)
		(end 370.997988 -250.962414)
		(stroke
			(width 0.254)
			(type default)
		)
		(layer "In8.Cu")
	)
	(gr_line
		(start 372.708424 -267.608558)
		(end 371.29847 -266.798552)
		(stroke
			(width 0.254)
			(type default)
		)
		(layer "In8.Cu")
	)
	(gr_line
		(start 372.847616 -163.289742)
		(end 375.76506 -166.207186)
		(stroke
			(width 0.508)
			(type default)
		)
		(layer "In8.Cu")
	)
	(gr_line
		(start 372.878096 -250.962414)
		(end 372.407942 -251.77242)
		(stroke
			(width 0.254)
			(type default)
		)
		(layer "In8.Cu")
	)
	(gr_line
		(start 373.174768 -284.616144)
		(end 374.114822 -284.616144)
		(stroke
			(width 0.6096)
			(type default)
		)
		(layer "In8.Cu")
	)
	(gr_line
		(start 373.174768 -282.996132)
		(end 374.114822 -282.996132)
		(stroke
			(width 0.6096)
			(type default)
		)
		(layer "In8.Cu")
	)
	(gr_line
		(start 373.174768 -281.37612)
		(end 374.114822 -281.37612)
		(stroke
			(width 0.6096)
			(type default)
		)
		(layer "In8.Cu")
	)
	(gr_line
		(start 373.17807 -263.558274)
		(end 371.767862 -262.748268)
		(stroke
			(width 0.254)
			(type default)
		)
		(layer "In8.Cu")
	)
	(gr_line
		(start 373.178578 -266.798552)
		(end 372.708424 -267.608558)
		(stroke
			(width 0.254)
			(type default)
		)
		(layer "In8.Cu")
	)
	(gr_line
		(start 373.64797 -262.748268)
		(end 373.17807 -263.558274)
		(stroke
			(width 0.254)
			(type default)
		)
		(layer "In8.Cu")
	)
	(gr_line
		(start 373.814848 -247.724168)
		(end 372.874794 -247.724168)
		(stroke
			(width 0.6096)
			(type default)
		)
		(layer "In8.Cu")
	)
	(gr_line
		(start 373.814848 -246.104156)
		(end 372.874794 -246.104156)
		(stroke
			(width 0.6096)
			(type default)
		)
		(layer "In8.Cu")
	)
	(gr_line
		(start 373.814848 -244.484144)
		(end 372.874794 -244.484144)
		(stroke
			(width 0.6096)
			(type default)
		)
		(layer "In8.Cu")
	)
	(gr_line
		(start 373.817896 -238.002318)
		(end 375.22785 -238.812324)
		(stroke
			(width 0.254)
			(type default)
		)
		(layer "In8.Cu")
	)
	(gr_line
		(start 374.118378 -279.758648)
		(end 375.528586 -278.948642)
		(stroke
			(width 0.254)
			(type default)
		)
		(layer "In8.Cu")
	)
	(gr_line
		(start 374.118378 -266.798552)
		(end 373.178578 -266.798552)
		(stroke
			(width 0.254)
			(type default)
		)
		(layer "In8.Cu")
	)
	(gr_line
		(start 374.28805 -250.152408)
		(end 372.878096 -250.962414)
		(stroke
			(width 0.254)
			(type default)
		)
		(layer "In8.Cu")
	)
	(gr_line
		(start 374.28805 -246.912384)
		(end 375.22785 -248.532396)
		(stroke
			(width 0.254)
			(type default)
		)
		(layer "In8.Cu")
	)
	(gr_line
		(start 374.28805 -243.67236)
		(end 375.22785 -245.292372)
		(stroke
			(width 0.254)
			(type default)
		)
		(layer "In8.Cu")
	)
	(gr_line
		(start 374.28805 -240.432336)
		(end 375.22785 -242.052348)
		(stroke
			(width 0.254)
			(type default)
		)
		(layer "In8.Cu")
	)
	(gr_line
		(start 374.28805 -235.5723)
		(end 374.75795 -236.382306)
		(stroke
			(width 0.254)
			(type default)
		)
		(layer "In8.Cu")
	)
	(gr_line
		(start 374.28805 -232.332276)
		(end 375.22785 -233.952288)
		(stroke
			(width 0.254)
			(type default)
		)
		(layer "In8.Cu")
	)
	(gr_line
		(start 374.28805 -230.712264)
		(end 374.75795 -231.52227)
		(stroke
			(width 0.254)
			(type default)
		)
		(layer "In8.Cu")
	)
	(gr_line
		(start 374.28805 -229.092252)
		(end 374.75795 -229.902258)
		(stroke
			(width 0.254)
			(type default)
		)
		(layer "In8.Cu")
	)
	(gr_line
		(start 374.588532 -288.668714)
		(end 375.528586 -287.048702)
		(stroke
			(width 0.254)
			(type default)
		)
		(layer "In8.Cu")
	)
	(gr_line
		(start 374.588532 -285.42869)
		(end 375.528586 -283.808678)
		(stroke
			(width 0.254)
			(type default)
		)
		(layer "In8.Cu")
	)
	(gr_line
		(start 374.588532 -282.188666)
		(end 375.058432 -281.37866)
		(stroke
			(width 0.254)
			(type default)
		)
		(layer "In8.Cu")
	)
	(gr_line
		(start 374.588532 -277.32863)
		(end 375.528586 -275.708618)
		(stroke
			(width 0.254)
			(type default)
		)
		(layer "In8.Cu")
	)
	(gr_line
		(start 374.588532 -274.088606)
		(end 375.528586 -272.468594)
		(stroke
			(width 0.254)
			(type default)
		)
		(layer "In8.Cu")
	)
	(gr_line
		(start 374.588532 -270.848582)
		(end 375.528586 -269.22857)
		(stroke
			(width 0.254)
			(type default)
		)
		(layer "In8.Cu")
	)
	(gr_line
		(start 374.75795 -236.382306)
		(end 373.817896 -238.002318)
		(stroke
			(width 0.254)
			(type default)
		)
		(layer "In8.Cu")
	)
	(gr_line
		(start 374.75795 -231.52227)
		(end 374.28805 -232.332276)
		(stroke
			(width 0.254)
			(type default)
		)
		(layer "In8.Cu")
	)
	(gr_line
		(start 374.75795 -229.902258)
		(end 374.28805 -230.712264)
		(stroke
			(width 0.254)
			(type default)
		)
		(layer "In8.Cu")
	)
	(gr_line
		(start 374.75795 -228.282246)
		(end 374.28805 -229.092252)
		(stroke
			(width 0.254)
			(type default)
		)
		(layer "In8.Cu")
	)
	(gr_line
		(start 375.057924 -263.558274)
		(end 373.64797 -262.748268)
		(stroke
			(width 0.254)
			(type default)
		)
		(layer "In8.Cu")
	)
	(gr_line
		(start 375.058432 -281.37866)
		(end 374.118378 -279.758648)
		(stroke
			(width 0.254)
			(type default)
		)
		(layer "In8.Cu")
	)
	(gr_line
		(start 375.058432 -268.418564)
		(end 374.118378 -266.798552)
		(stroke
			(width 0.254)
			(type default)
		)
		(layer "In8.Cu")
	)
	(gr_line
		(start 375.22785 -248.532396)
		(end 374.28805 -250.152408)
		(stroke
			(width 0.254)
			(type default)
		)
		(layer "In8.Cu")
	)
	(gr_line
		(start 375.22785 -245.292372)
		(end 374.28805 -246.912384)
		(stroke
			(width 0.254)
			(type default)
		)
		(layer "In8.Cu")
	)
	(gr_line
		(start 375.22785 -242.052348)
		(end 374.28805 -243.67236)
		(stroke
			(width 0.254)
			(type default)
		)
		(layer "In8.Cu")
	)
	(gr_line
		(start 375.22785 -238.812324)
		(end 374.28805 -240.432336)
		(stroke
			(width 0.254)
			(type default)
		)
		(layer "In8.Cu")
	)
	(gr_line
		(start 375.22785 -233.952288)
		(end 374.28805 -235.5723)
		(stroke
			(width 0.254)
			(type default)
		)
		(layer "In8.Cu")
	)
	(gr_line
		(start 375.528078 -262.748268)
		(end 375.057924 -263.558274)
		(stroke
			(width 0.254)
			(type default)
		)
		(layer "In8.Cu")
	)
	(gr_line
		(start 375.528586 -290.288726)
		(end 374.588532 -288.668714)
		(stroke
			(width 0.254)
			(type default)
		)
		(layer "In8.Cu")
	)
	(gr_line
		(start 375.528586 -290.288726)
		(end 377.40844 -293.528496)
		(stroke
			(width 0.254)
			(type default)
		)
		(layer "In8.Cu")
	)
	(gr_line
		(start 375.528586 -287.048702)
		(end 374.588532 -285.42869)
		(stroke
			(width 0.254)
			(type default)
		)
		(layer "In8.Cu")
	)
	(gr_line
		(start 375.528586 -283.808678)
		(end 374.588532 -282.188666)
		(stroke
			(width 0.254)
			(type default)
		)
		(layer "In8.Cu")
	)
	(gr_line
		(start 375.528586 -278.948642)
		(end 374.588532 -277.32863)
		(stroke
			(width 0.254)
			(type default)
		)
		(layer "In8.Cu")
	)
	(gr_line
		(start 375.528586 -275.708618)
		(end 374.588532 -274.088606)
		(stroke
			(width 0.254)
			(type default)
		)
		(layer "In8.Cu")
	)
	(gr_line
		(start 375.528586 -272.468594)
		(end 374.588532 -270.848582)
		(stroke
			(width 0.254)
			(type default)
		)
		(layer "In8.Cu")
	)
	(gr_line
		(start 375.528586 -269.22857)
		(end 375.058432 -268.418564)
		(stroke
			(width 0.254)
			(type default)
		)
		(layer "In8.Cu")
	)
	(gr_line
		(start 375.76506 -166.207186)
		(end 388.983728 -166.207186)
		(stroke
			(width 0.508)
			(type default)
		)
		(layer "In8.Cu")
	)
	(gr_line
		(start 376.638058 -228.282246)
		(end 374.75795 -228.282246)
		(stroke
			(width 0.254)
			(type default)
		)
		(layer "In8.Cu")
	)
	(gr_line
		(start 376.818906 -392.114278)
		(end 366.773206 -392.114278)
		(stroke
			(width 0.508)
			(type default)
		)
		(layer "In8.Cu")
	)
	(gr_line
		(start 377.18365 -396.17015)
		(end 377.18365 -392.479022)
		(stroke
			(width 0.508)
			(type default)
		)
		(layer "In8.Cu")
	)
	(gr_line
		(start 377.18365 -392.479022)
		(end 376.818906 -392.114278)
		(stroke
			(width 0.508)
			(type default)
		)
		(layer "In8.Cu")
	)
	(gr_line
		(start 377.18365 -392.479022)
		(end 377.255786 -392.479022)
		(stroke
			(width 0.508)
			(type default)
		)
		(layer "In8.Cu")
	)
	(gr_line
		(start 377.255786 -392.479022)
		(end 377.820428 -391.91438)
		(stroke
			(width 0.508)
			(type default)
		)
		(layer "In8.Cu")
	)
	(gr_circle
		(center 377.367038 -180.678074)
		(end 378.256038 -180.678074)
		(stroke
			(width 0.2)
			(type default)
		)
		(fill no)
		(layer "In8.Cu")
	)
	(gr_circle
		(center 377.367038 -179.941474)
		(end 378.256038 -179.941474)
		(stroke
			(width 0.2)
			(type default)
		)
		(fill no)
		(layer "In8.Cu")
	)
	(gr_circle
		(center 377.367038 -179.204874)
		(end 378.256038 -179.204874)
		(stroke
			(width 0.2)
			(type default)
		)
		(fill no)
		(layer "In8.Cu")
	)
	(gr_line
		(start 377.40844 -293.528496)
		(end 378.348494 -293.528496)
		(stroke
			(width 0.254)
			(type default)
		)
		(layer "In8.Cu")
	)
	(gr_line
		(start 377.666504 -396.653004)
		(end 377.18365 -396.17015)
		(stroke
			(width 0.508)
			(type default)
		)
		(layer "In8.Cu")
	)
	(gr_line
		(start 377.820428 -391.91438)
		(end 392.713464 -391.91438)
		(stroke
			(width 0.508)
			(type default)
		)
		(layer "In8.Cu")
	)
	(gr_circle
		(center 377.869958 -162.59683)
		(end 379.266958 -162.59683)
		(stroke
			(width 0.2)
			(type default)
		)
		(fill no)
		(layer "In8.Cu")
	)
	(gr_circle
		(center 377.900438 -179.560474)
		(end 378.789438 -179.560474)
		(stroke
			(width 0.2)
			(type default)
		)
		(fill no)
		(layer "In8.Cu")
	)
	(gr_circle
		(center 377.925838 -180.322474)
		(end 378.814838 -180.322474)
		(stroke
			(width 0.2)
			(type default)
		)
		(fill no)
		(layer "In8.Cu")
	)
	(gr_line
		(start 378.347986 -262.748268)
		(end 375.528078 -262.748268)
		(stroke
			(width 0.254)
			(type default)
		)
		(layer "In8.Cu")
	)
	(gr_line
		(start 378.348494 -293.528496)
		(end 379.288548 -295.148508)
		(stroke
			(width 0.254)
			(type default)
		)
		(layer "In8.Cu")
	)
	(gr_circle
		(center 378.450602 -179.883054)
		(end 379.339602 -179.883054)
		(stroke
			(width 0.2)
			(type default)
		)
		(fill no)
		(layer "In8.Cu")
	)
	(gr_circle
		(center 378.450602 -179.146454)
		(end 379.339602 -179.146454)
		(stroke
			(width 0.2)
			(type default)
		)
		(fill no)
		(layer "In8.Cu")
	)
	(gr_circle
		(center 379.035056 -182.230776)
		(end 379.924056 -182.230776)
		(stroke
			(width 0.2)
			(type default)
		)
		(fill no)
		(layer "In8.Cu")
	)
	(gr_circle
		(center 379.035056 -181.494176)
		(end 379.924056 -181.494176)
		(stroke
			(width 0.2)
			(type default)
		)
		(fill no)
		(layer "In8.Cu")
	)
	(gr_circle
		(center 379.152658 -180.755544)
		(end 380.032768 -180.755544)
		(stroke
			(width 0.2)
			(type default)
		)
		(fill no)
		(layer "In8.Cu")
	)
	(gr_line
		(start 379.171962 -327.600818)
		(end 379.758702 -327.014078)
		(stroke
			(width 0.508)
			(type default)
		)
		(layer "In8.Cu")
	)
	(gr_line
		(start 379.288548 -295.148508)
		(end 379.758702 -295.958514)
		(stroke
			(width 0.254)
			(type default)
		)
		(layer "In8.Cu")
	)
	(gr_line
		(start 379.75794 -263.558274)
		(end 378.347986 -262.748268)
		(stroke
			(width 0.254)
			(type default)
		)
		(layer "In8.Cu")
	)
	(gr_line
		(start 379.758702 -327.600818)
		(end 379.171962 -327.600818)
		(stroke
			(width 0.508)
			(type default)
		)
		(layer "In8.Cu")
	)
	(gr_line
		(start 379.758702 -327.600818)
		(end 379.758702 -308.980078)
		(stroke
			(width 0.508)
			(type default)
		)
		(layer "In8.Cu")
	)
	(gr_line
		(start 379.758702 -295.958514)
		(end 379.758702 -308.980078)
		(stroke
			(width 0.508)
			(type default)
		)
		(layer "In8.Cu")
	)
	(gr_circle
		(center 379.769878 -180.755544)
		(end 380.649988 -180.755544)
		(stroke
			(width 0.2)
			(type default)
		)
		(fill no)
		(layer "In8.Cu")
	)
	(gr_circle
		(center 380.387098 -180.755544)
		(end 381.267208 -180.755544)
		(stroke
			(width 0.2)
			(type default)
		)
		(fill no)
		(layer "In8.Cu")
	)
	(gr_line
		(start 380.39802 -221.802452)
		(end 376.638058 -228.282246)
		(stroke
			(width 0.254)
			(type default)
		)
		(layer "In8.Cu")
	)
	(gr_line
		(start 380.39802 -221.080076)
		(end 380.39802 -221.802452)
		(stroke
			(width 0.508)
			(type default)
		)
		(layer "In8.Cu")
	)
	(gr_line
		(start 380.481332 -396.653004)
		(end 377.666504 -396.653004)
		(stroke
			(width 0.508)
			(type default)
		)
		(layer "In8.Cu")
	)
	(gr_line
		(start 380.716536 -158.818326)
		(end 388.272782 -151.26208)
		(stroke
			(width 0.508)
			(type default)
		)
		(layer "In8.Cu")
	)
	(gr_line
		(start 382.124458 -395.009878)
		(end 380.481332 -396.653004)
		(stroke
			(width 0.508)
			(type default)
		)
		(layer "In8.Cu")
	)
	(gr_line
		(start 382.94056 -395.009878)
		(end 382.124458 -395.009878)
		(stroke
			(width 0.508)
			(type default)
		)
		(layer "In8.Cu")
	)
	(gr_line
		(start 384.32613 -396.395448)
		(end 382.94056 -395.009878)
		(stroke
			(width 0.508)
			(type default)
		)
		(layer "In8.Cu")
	)
	(gr_line
		(start 384.457956 -263.558274)
		(end 379.75794 -263.558274)
		(stroke
			(width 0.254)
			(type default)
		)
		(layer "In8.Cu")
	)
	(gr_line
		(start 384.92811 -264.36828)
		(end 384.457956 -263.558274)
		(stroke
			(width 0.254)
			(type default)
		)
		(layer "In8.Cu")
	)
	(gr_arc
		(start 385.601972 -11.780012)
		(mid 387.016183 -11.194227)
		(end 387.601968 -9.780016)
		(stroke
			(width 3.048)
			(type default)
		)
		(layer "In8.Cu")
	)
	(gr_circle
		(center 385.698238 -180.678074)
		(end 386.587238 -180.678074)
		(stroke
			(width 0.2)
			(type default)
		)
		(fill no)
		(layer "In8.Cu")
	)
	(gr_circle
		(center 385.698238 -179.941474)
		(end 386.587238 -179.941474)
		(stroke
			(width 0.2)
			(type default)
		)
		(fill no)
		(layer "In8.Cu")
	)
	(gr_circle
		(center 385.698238 -179.204874)
		(end 386.587238 -179.204874)
		(stroke
			(width 0.2)
			(type default)
		)
		(fill no)
		(layer "In8.Cu")
	)
	(gr_circle
		(center 386.231638 -179.560474)
		(end 387.120638 -179.560474)
		(stroke
			(width 0.2)
			(type default)
		)
		(fill no)
		(layer "In8.Cu")
	)
	(gr_circle
		(center 386.257038 -180.322474)
		(end 387.146038 -180.322474)
		(stroke
			(width 0.2)
			(type default)
		)
		(fill no)
		(layer "In8.Cu")
	)
	(gr_circle
		(center 386.781802 -179.883054)
		(end 387.670802 -179.883054)
		(stroke
			(width 0.2)
			(type default)
		)
		(fill no)
		(layer "In8.Cu")
	)
	(gr_circle
		(center 386.781802 -179.146454)
		(end 387.670802 -179.146454)
		(stroke
			(width 0.2)
			(type default)
		)
		(fill no)
		(layer "In8.Cu")
	)
	(gr_circle
		(center 387.206998 -162.65271)
		(end 388.603998 -162.65271)
		(stroke
			(width 0.2)
			(type default)
		)
		(fill no)
		(layer "In8.Cu")
	)
	(gr_circle
		(center 387.293358 -157.001972)
		(end 388.182358 -157.001972)
		(stroke
			(width 0.2)
			(type default)
		)
		(fill no)
		(layer "In8.Cu")
	)
	(gr_circle
		(center 387.293358 -156.366972)
		(end 388.182358 -156.366972)
		(stroke
			(width 0.2)
			(type default)
		)
		(fill no)
		(layer "In8.Cu")
	)
	(gr_circle
		(center 387.293358 -155.724352)
		(end 388.182358 -155.724352)
		(stroke
			(width 0.2)
			(type default)
		)
		(fill no)
		(layer "In8.Cu")
	)
	(gr_circle
		(center 387.293358 -155.089352)
		(end 388.182358 -155.089352)
		(stroke
			(width 0.2)
			(type default)
		)
		(fill no)
		(layer "In8.Cu")
	)
	(gr_circle
		(center 387.293358 -154.428952)
		(end 388.182358 -154.428952)
		(stroke
			(width 0.2)
			(type default)
		)
		(fill no)
		(layer "In8.Cu")
	)
	(gr_circle
		(center 387.293358 -153.793952)
		(end 388.182358 -153.793952)
		(stroke
			(width 0.2)
			(type default)
		)
		(fill no)
		(layer "In8.Cu")
	)
	(gr_circle
		(center 387.366256 -182.230776)
		(end 388.255256 -182.230776)
		(stroke
			(width 0.2)
			(type default)
		)
		(fill no)
		(layer "In8.Cu")
	)
	(gr_circle
		(center 387.366256 -181.494176)
		(end 388.255256 -181.494176)
		(stroke
			(width 0.2)
			(type default)
		)
		(fill no)
		(layer "In8.Cu")
	)
	(gr_circle
		(center 387.483858 -180.755544)
		(end 388.363968 -180.755544)
		(stroke
			(width 0.2)
			(type default)
		)
		(fill no)
		(layer "In8.Cu")
	)
	(gr_line
		(start 387.601968 -9.780016)
		(end 387.601968 -0.500126)
		(stroke
			(width 3.048)
			(type default)
		)
		(layer "In8.Cu")
	)
	(gr_circle
		(center 387.928358 -157.001972)
		(end 388.817358 -157.001972)
		(stroke
			(width 0.2)
			(type default)
		)
		(fill no)
		(layer "In8.Cu")
	)
	(gr_circle
		(center 387.928358 -156.366972)
		(end 388.817358 -156.366972)
		(stroke
			(width 0.2)
			(type default)
		)
		(fill no)
		(layer "In8.Cu")
	)
	(gr_circle
		(center 387.928358 -155.724352)
		(end 388.817358 -155.724352)
		(stroke
			(width 0.2)
			(type default)
		)
		(fill no)
		(layer "In8.Cu")
	)
	(gr_circle
		(center 387.928358 -155.089352)
		(end 388.817358 -155.089352)
		(stroke
			(width 0.2)
			(type default)
		)
		(fill no)
		(layer "In8.Cu")
	)
	(gr_circle
		(center 387.928358 -154.428952)
		(end 388.817358 -154.428952)
		(stroke
			(width 0.2)
			(type default)
		)
		(fill no)
		(layer "In8.Cu")
	)
	(gr_circle
		(center 387.928358 -153.793952)
		(end 388.817358 -153.793952)
		(stroke
			(width 0.2)
			(type default)
		)
		(fill no)
		(layer "In8.Cu")
	)
	(gr_circle
		(center 388.101078 -180.755544)
		(end 388.981188 -180.755544)
		(stroke
			(width 0.2)
			(type default)
		)
		(fill no)
		(layer "In8.Cu")
	)
	(gr_arc
		(start 388.102094 0)
		(mid 387.748465 -0.146487)
		(end 387.601968 -0.500126)
		(stroke
			(width 3.048)
			(type default)
		)
		(layer "In8.Cu")
	)
	(gr_line
		(start 388.102094 0)
		(end 455.701908 0)
		(stroke
			(width 3.048)
			(type default)
		)
		(layer "In8.Cu")
	)
	(gr_line
		(start 388.272782 -151.26208)
		(end 424.666918 -151.26208)
		(stroke
			(width 0.508)
			(type default)
		)
		(layer "In8.Cu")
	)
	(gr_circle
		(center 388.718298 -180.755544)
		(end 389.598408 -180.755544)
		(stroke
			(width 0.2)
			(type default)
		)
		(fill no)
		(layer "In8.Cu")
	)
	(gr_line
		(start 388.983728 -166.207186)
		(end 396.602966 -158.587948)
		(stroke
			(width 0.508)
			(type default)
		)
		(layer "In8.Cu")
	)
	(gr_line
		(start 389.627872 -264.36828)
		(end 384.92811 -264.36828)
		(stroke
			(width 0.254)
			(type default)
		)
		(layer "In8.Cu")
	)
	(gr_line
		(start 390.285224 -338.12734)
		(end 390.99109 -338.833206)
		(stroke
			(width 0.508)
			(type default)
		)
		(layer "In8.Cu")
	)
	(gr_line
		(start 390.909302 -338.751418)
		(end 379.758702 -327.600818)
		(stroke
			(width 0.508)
			(type default)
		)
		(layer "In8.Cu")
	)
	(gr_line
		(start 391.03808 -266.798298)
		(end 389.627872 -264.36828)
		(stroke
			(width 0.254)
			(type default)
		)
		(layer "In8.Cu")
	)
	(gr_line
		(start 392.555984 -396.395448)
		(end 384.32613 -396.395448)
		(stroke
			(width 0.508)
			(type default)
		)
		(layer "In8.Cu")
	)
	(gr_line
		(start 392.713464 -391.91438)
		(end 393.057888 -392.258804)
		(stroke
			(width 0.508)
			(type default)
		)
		(layer "In8.Cu")
	)
	(gr_line
		(start 392.880088 -396.053564)
		(end 392.888978 -396.062454)
		(stroke
			(width 0.508)
			(type default)
		)
		(layer "In8.Cu")
	)
	(gr_line
		(start 392.880088 -395.12621)
		(end 392.880088 -396.053564)
		(stroke
			(width 0.508)
			(type default)
		)
		(layer "In8.Cu")
	)
	(gr_line
		(start 392.880088 -395.12621)
		(end 392.880088 -394.757402)
		(stroke
			(width 0.254)
			(type default)
		)
		(layer "In8.Cu")
	)
	(gr_line
		(start 392.880088 -394.757402)
		(end 393.057888 -394.579602)
		(stroke
			(width 0.254)
			(type default)
		)
		(layer "In8.Cu")
	)
	(gr_line
		(start 392.888978 -396.062454)
		(end 392.555984 -396.395448)
		(stroke
			(width 0.508)
			(type default)
		)
		(layer "In8.Cu")
	)
	(gr_line
		(start 393.057888 -394.579602)
		(end 393.057888 -393.057634)
		(stroke
			(width 0.254)
			(type default)
		)
		(layer "In8.Cu")
	)
	(gr_line
		(start 393.057888 -393.057634)
		(end 393.057888 -392.258804)
		(stroke
			(width 0.508)
			(type default)
		)
		(layer "In8.Cu")
	)
	(gr_line
		(start 393.30122 -193.742564)
		(end 393.551918 -193.491866)
		(stroke
			(width 0.508)
			(type default)
		)
		(layer "In8.Cu")
	)
	(gr_line
		(start 393.304776 -193.742564)
		(end 393.30122 -193.742564)
		(stroke
			(width 0.508)
			(type default)
		)
		(layer "In8.Cu")
	)
	(gr_line
		(start 393.617958 -194.055746)
		(end 393.304776 -193.742564)
		(stroke
			(width 0.508)
			(type default)
		)
		(layer "In8.Cu")
	)
	(gr_line
		(start 393.630912 -266.798298)
		(end 391.03808 -266.798298)
		(stroke
			(width 0.254)
			(type default)
		)
		(layer "In8.Cu")
	)
	(gr_line
		(start 393.630912 -266.798298)
		(end 439.349388 -266.798298)
		(stroke
			(width 0.508)
			(type default)
		)
		(layer "In8.Cu")
	)
	(gr_line
		(start 393.638532 -207.839564)
		(end 380.39802 -221.080076)
		(stroke
			(width 0.508)
			(type default)
		)
		(layer "In8.Cu")
	)
	(gr_line
		(start 393.638532 -188.789564)
		(end 393.638532 -207.839564)
		(stroke
			(width 0.508)
			(type default)
		)
		(layer "In8.Cu")
	)
	(gr_line
		(start 394.273532 -188.154564)
		(end 393.638532 -188.789564)
		(stroke
			(width 0.508)
			(type default)
		)
		(layer "In8.Cu")
	)
	(gr_line
		(start 394.612622 -396.062454)
		(end 392.888978 -396.062454)
		(stroke
			(width 0.508)
			(type default)
		)
		(layer "In8.Cu")
	)
	(gr_circle
		(center 394.628878 -173.21911)
		(end 395.517878 -173.21911)
		(stroke
			(width 0.2)
			(type default)
		)
		(fill no)
		(layer "In8.Cu")
	)
	(gr_circle
		(center 394.628878 -172.45711)
		(end 395.517878 -172.45711)
		(stroke
			(width 0.2)
			(type default)
		)
		(fill no)
		(layer "In8.Cu")
	)
	(gr_circle
		(center 394.646658 -173.987714)
		(end 395.535658 -173.987714)
		(stroke
			(width 0.2)
			(type default)
		)
		(fill no)
		(layer "In8.Cu")
	)
	(gr_circle
		(center 394.672058 -174.749714)
		(end 395.561058 -174.749714)
		(stroke
			(width 0.2)
			(type default)
		)
		(fill no)
		(layer "In8.Cu")
	)
	(gr_circle
		(center 395.196822 -174.310294)
		(end 396.085822 -174.310294)
		(stroke
			(width 0.2)
			(type default)
		)
		(fill no)
		(layer "In8.Cu")
	)
	(gr_circle
		(center 395.196822 -173.573694)
		(end 396.085822 -173.573694)
		(stroke
			(width 0.2)
			(type default)
		)
		(fill no)
		(layer "In8.Cu")
	)
	(gr_circle
		(center 395.230858 -172.819314)
		(end 396.119858 -172.819314)
		(stroke
			(width 0.2)
			(type default)
		)
		(fill no)
		(layer "In8.Cu")
	)
	(gr_circle
		(center 395.781276 -176.657254)
		(end 396.670276 -176.657254)
		(stroke
			(width 0.2)
			(type default)
		)
		(fill no)
		(layer "In8.Cu")
	)
	(gr_circle
		(center 395.781276 -175.895254)
		(end 396.670276 -175.895254)
		(stroke
			(width 0.2)
			(type default)
		)
		(fill no)
		(layer "In8.Cu")
	)
	(gr_circle
		(center 395.898878 -175.182784)
		(end 396.778988 -175.182784)
		(stroke
			(width 0.2)
			(type default)
		)
		(fill no)
		(layer "In8.Cu")
	)
	(gr_line
		(start 396.24635 -394.428726)
		(end 394.612622 -396.062454)
		(stroke
			(width 0.508)
			(type default)
		)
		(layer "In8.Cu")
	)
	(gr_line
		(start 396.24635 -392.573764)
		(end 396.24635 -394.428726)
		(stroke
			(width 0.508)
			(type default)
		)
		(layer "In8.Cu")
	)
	(gr_circle
		(center 396.516098 -175.182784)
		(end 397.396208 -175.182784)
		(stroke
			(width 0.2)
			(type default)
		)
		(fill no)
		(layer "In8.Cu")
	)
	(gr_line
		(start 396.602966 -158.587948)
		(end 399.669508 -158.587948)
		(stroke
			(width 0.508)
			(type default)
		)
		(layer "In8.Cu")
	)
	(gr_line
		(start 397.043656 -391.776458)
		(end 396.24635 -392.573764)
		(stroke
			(width 0.508)
			(type default)
		)
		(layer "In8.Cu")
	)
	(gr_circle
		(center 397.133318 -175.182784)
		(end 398.013428 -175.182784)
		(stroke
			(width 0.2)
			(type default)
		)
		(fill no)
		(layer "In8.Cu")
	)
	(gr_circle
		(center 399.165064 -81.051146)
		(end 400.054064 -81.051146)
		(stroke
			(width 0.2)
			(type default)
		)
		(fill no)
		(layer "In8.Cu")
	)
	(gr_line
		(start 399.988532 -188.154564)
		(end 394.273532 -188.154564)
		(stroke
			(width 0.508)
			(type default)
		)
		(layer "In8.Cu")
	)
	(gr_line
		(start 401.893532 -186.249564)
		(end 399.988532 -188.154564)
		(stroke
			(width 0.508)
			(type default)
		)
		(layer "In8.Cu")
	)
	(gr_line
		(start 401.893532 -181.169564)
		(end 401.893532 -186.249564)
		(stroke
			(width 0.508)
			(type default)
		)
		(layer "In8.Cu")
	)
	(gr_circle
		(center 402.436838 -166.527988)
		(end 403.325838 -166.527988)
		(stroke
			(width 0.2)
			(type default)
		)
		(fill no)
		(layer "In8.Cu")
	)
	(gr_circle
		(center 402.436838 -165.791388)
		(end 403.325838 -165.791388)
		(stroke
			(width 0.2)
			(type default)
		)
		(fill no)
		(layer "In8.Cu")
	)
	(gr_circle
		(center 402.436838 -165.054788)
		(end 403.325838 -165.054788)
		(stroke
			(width 0.2)
			(type default)
		)
		(fill no)
		(layer "In8.Cu")
	)
	(gr_circle
		(center 402.970238 -165.410388)
		(end 403.859238 -165.410388)
		(stroke
			(width 0.2)
			(type default)
		)
		(fill no)
		(layer "In8.Cu")
	)
	(gr_circle
		(center 402.995638 -166.172388)
		(end 403.884638 -166.172388)
		(stroke
			(width 0.2)
			(type default)
		)
		(fill no)
		(layer "In8.Cu")
	)
	(gr_circle
		(center 403.520402 -165.732968)
		(end 404.409402 -165.732968)
		(stroke
			(width 0.2)
			(type default)
		)
		(fill no)
		(layer "In8.Cu")
	)
	(gr_circle
		(center 403.520402 -164.996368)
		(end 404.409402 -164.996368)
		(stroke
			(width 0.2)
			(type default)
		)
		(fill no)
		(layer "In8.Cu")
	)
	(gr_line
		(start 403.544532 -179.518564)
		(end 401.893532 -181.169564)
		(stroke
			(width 0.508)
			(type default)
		)
		(layer "In8.Cu")
	)
	(gr_circle
		(center 404.104856 -168.082214)
		(end 404.993856 -168.082214)
		(stroke
			(width 0.2)
			(type default)
		)
		(fill no)
		(layer "In8.Cu")
	)
	(gr_circle
		(center 404.104856 -167.320214)
		(end 404.993856 -167.320214)
		(stroke
			(width 0.2)
			(type default)
		)
		(fill no)
		(layer "In8.Cu")
	)
	(gr_circle
		(center 404.222458 -166.605458)
		(end 405.102568 -166.605458)
		(stroke
			(width 0.2)
			(type default)
		)
		(fill no)
		(layer "In8.Cu")
	)
	(gr_circle
		(center 404.839678 -166.605458)
		(end 405.719788 -166.605458)
		(stroke
			(width 0.2)
			(type default)
		)
		(fill no)
		(layer "In8.Cu")
	)
	(gr_circle
		(center 405.456898 -166.605458)
		(end 406.337008 -166.605458)
		(stroke
			(width 0.2)
			(type default)
		)
		(fill no)
		(layer "In8.Cu")
	)
	(gr_line
		(start 407.100532 -179.518564)
		(end 403.544532 -179.518564)
		(stroke
			(width 0.508)
			(type default)
		)
		(layer "In8.Cu")
	)
	(gr_line
		(start 409.747466 -396.181834)
		(end 409.747466 -391.927588)
		(stroke
			(width 0.508)
			(type default)
		)
		(layer "In8.Cu")
	)
	(gr_line
		(start 409.747466 -391.927588)
		(end 409.734258 -391.91438)
		(stroke
			(width 0.508)
			(type default)
		)
		(layer "In8.Cu")
	)
	(gr_line
		(start 410.32176 -396.756128)
		(end 409.747466 -396.181834)
		(stroke
			(width 0.508)
			(type default)
		)
		(layer "In8.Cu")
	)
	(gr_circle
		(center 410.818838 -161.701988)
		(end 411.707838 -161.701988)
		(stroke
			(width 0.2)
			(type default)
		)
		(fill no)
		(layer "In8.Cu")
	)
	(gr_circle
		(center 410.818838 -160.965388)
		(end 411.707838 -160.965388)
		(stroke
			(width 0.2)
			(type default)
		)
		(fill no)
		(layer "In8.Cu")
	)
	(gr_circle
		(center 410.818838 -160.228788)
		(end 411.707838 -160.228788)
		(stroke
			(width 0.2)
			(type default)
		)
		(fill no)
		(layer "In8.Cu")
	)
	(gr_circle
		(center 411.352238 -160.584388)
		(end 412.241238 -160.584388)
		(stroke
			(width 0.2)
			(type default)
		)
		(fill no)
		(layer "In8.Cu")
	)
	(gr_circle
		(center 411.377638 -161.346388)
		(end 412.266638 -161.346388)
		(stroke
			(width 0.2)
			(type default)
		)
		(fill no)
		(layer "In8.Cu")
	)
	(gr_circle
		(center 411.902402 -160.906968)
		(end 412.791402 -160.906968)
		(stroke
			(width 0.2)
			(type default)
		)
		(fill no)
		(layer "In8.Cu")
	)
	(gr_circle
		(center 411.902402 -160.170368)
		(end 412.791402 -160.170368)
		(stroke
			(width 0.2)
			(type default)
		)
		(fill no)
		(layer "In8.Cu")
	)
	(gr_line
		(start 411.926532 -174.692564)
		(end 407.100532 -179.518564)
		(stroke
			(width 0.508)
			(type default)
		)
		(layer "In8.Cu")
	)
	(gr_circle
		(center 412.486856 -163.256214)
		(end 413.375856 -163.256214)
		(stroke
			(width 0.2)
			(type default)
		)
		(fill no)
		(layer "In8.Cu")
	)
	(gr_circle
		(center 412.486856 -162.494214)
		(end 413.375856 -162.494214)
		(stroke
			(width 0.2)
			(type default)
		)
		(fill no)
		(layer "In8.Cu")
	)
	(gr_circle
		(center 412.604458 -161.779458)
		(end 413.484568 -161.779458)
		(stroke
			(width 0.2)
			(type default)
		)
		(fill no)
		(layer "In8.Cu")
	)
	(gr_line
		(start 413.068262 -396.756128)
		(end 410.32176 -396.756128)
		(stroke
			(width 0.508)
			(type default)
		)
		(layer "In8.Cu")
	)
	(gr_circle
		(center 413.221678 -161.779458)
		(end 414.101788 -161.779458)
		(stroke
			(width 0.2)
			(type default)
		)
		(fill no)
		(layer "In8.Cu")
	)
	(gr_line
		(start 413.300418 -338.833206)
		(end 390.99109 -338.833206)
		(stroke
			(width 0.508)
			(type default)
		)
		(layer "In8.Cu")
	)
	(gr_circle
		(center 413.838898 -161.779458)
		(end 414.719008 -161.779458)
		(stroke
			(width 0.2)
			(type default)
		)
		(fill no)
		(layer "In8.Cu")
	)
	(gr_line
		(start 414.906714 -394.917676)
		(end 413.068262 -396.756128)
		(stroke
			(width 0.508)
			(type default)
		)
		(layer "In8.Cu")
	)
	(gr_line
		(start 415.458402 -394.917676)
		(end 414.906714 -394.917676)
		(stroke
			(width 0.508)
			(type default)
		)
		(layer "In8.Cu")
	)
	(gr_line
		(start 416.31235 -341.845138)
		(end 413.300418 -338.833206)
		(stroke
			(width 0.508)
			(type default)
		)
		(layer "In8.Cu")
	)
	(gr_line
		(start 416.774376 -396.38986)
		(end 416.774376 -396.23365)
		(stroke
			(width 0.508)
			(type default)
		)
		(layer "In8.Cu")
	)
	(gr_line
		(start 416.774376 -396.23365)
		(end 415.458402 -394.917676)
		(stroke
			(width 0.508)
			(type default)
		)
		(layer "In8.Cu")
	)
	(gr_line
		(start 417.576 -158.587948)
		(end 399.270728 -158.587948)
		(stroke
			(width 0.508)
			(type default)
		)
		(layer "In8.Cu")
	)
	(gr_line
		(start 418.211 -174.589948)
		(end 418.211 -159.222948)
		(stroke
			(width 0.508)
			(type default)
		)
		(layer "In8.Cu")
	)
	(gr_line
		(start 418.211 -159.222948)
		(end 417.576 -158.587948)
		(stroke
			(width 0.508)
			(type default)
		)
		(layer "In8.Cu")
	)
	(gr_line
		(start 420.975028 -396.38986)
		(end 416.774376 -396.38986)
		(stroke
			(width 0.508)
			(type default)
		)
		(layer "In8.Cu")
	)
	(gr_line
		(start 422.306496 -397.721328)
		(end 420.975028 -396.38986)
		(stroke
			(width 0.508)
			(type default)
		)
		(layer "In8.Cu")
	)
	(gr_circle
		(center 424.33494 -353.10318)
		(end 425.21505 -353.10318)
		(stroke
			(width 0.2)
			(type default)
		)
		(fill no)
		(layer "In8.Cu")
	)
	(gr_line
		(start 424.666918 -151.26208)
		(end 455.919586 -182.514748)
		(stroke
			(width 0.508)
			(type default)
		)
		(layer "In8.Cu")
	)
	(gr_line
		(start 424.788584 -397.721328)
		(end 422.306496 -397.721328)
		(stroke
			(width 0.508)
			(type default)
		)
		(layer "In8.Cu")
	)
	(gr_circle
		(center 424.95216 -353.10318)
		(end 425.83227 -353.10318)
		(stroke
			(width 0.2)
			(type default)
		)
		(fill no)
		(layer "In8.Cu")
	)
	(gr_line
		(start 425.075604 -391.776458)
		(end 397.043656 -391.776458)
		(stroke
			(width 0.508)
			(type default)
		)
		(layer "In8.Cu")
	)
	(gr_line
		(start 425.076366 -174.692564)
		(end 411.926532 -174.692564)
		(stroke
			(width 0.508)
			(type default)
		)
		(layer "In8.Cu")
	)
	(gr_circle
		(center 425.56938 -353.10318)
		(end 426.44949 -353.10318)
		(stroke
			(width 0.2)
			(type default)
		)
		(fill no)
		(layer "In8.Cu")
	)
	(gr_line
		(start 425.569888 -396.940024)
		(end 424.788584 -397.721328)
		(stroke
			(width 0.508)
			(type default)
		)
		(layer "In8.Cu")
	)
	(gr_line
		(start 425.569888 -396.756382)
		(end 425.569888 -396.940024)
		(stroke
			(width 0.508)
			(type default)
		)
		(layer "In8.Cu")
	)
	(gr_line
		(start 425.569888 -396.756382)
		(end 425.569888 -392.270742)
		(stroke
			(width 0.508)
			(type default)
		)
		(layer "In8.Cu")
	)
	(gr_line
		(start 425.569888 -392.270742)
		(end 425.075604 -391.776458)
		(stroke
			(width 0.508)
			(type default)
		)
		(layer "In8.Cu")
	)
	(gr_circle
		(center 425.686474 -352.35769)
		(end 426.575474 -352.35769)
		(stroke
			(width 0.2)
			(type default)
		)
		(fill no)
		(layer "In8.Cu")
	)
	(gr_circle
		(center 425.686474 -351.62109)
		(end 426.575474 -351.62109)
		(stroke
			(width 0.2)
			(type default)
		)
		(fill no)
		(layer "In8.Cu")
	)
	(gr_line
		(start 425.797218 -266.400026)
		(end 425.797218 -175.413416)
		(stroke
			(width 0.508)
			(type default)
		)
		(layer "In8.Cu")
	)
	(gr_line
		(start 425.797218 -175.413416)
		(end 425.076366 -174.692564)
		(stroke
			(width 0.508)
			(type default)
		)
		(layer "In8.Cu")
	)
	(gr_line
		(start 425.86402 -195.968112)
		(end 425.86402 -196.010022)
		(stroke
			(width 0.508)
			(type default)
		)
		(layer "In8.Cu")
	)
	(gr_line
		(start 426.052996 -195.653406)
		(end 425.801028 -195.401438)
		(stroke
			(width 0.508)
			(type default)
		)
		(layer "In8.Cu")
	)
	(gr_line
		(start 426.178726 -195.653406)
		(end 425.86402 -195.968112)
		(stroke
			(width 0.508)
			(type default)
		)
		(layer "In8.Cu")
	)
	(gr_line
		(start 426.178726 -195.653406)
		(end 426.052996 -195.653406)
		(stroke
			(width 0.508)
			(type default)
		)
		(layer "In8.Cu")
	)
	(gr_line
		(start 426.197776 -375.175272)
		(end 289.691318 -375.175272)
		(stroke
			(width 0.508)
			(type default)
		)
		(layer "In8.Cu")
	)
	(gr_circle
		(center 426.271436 -354.71227)
		(end 427.160436 -354.71227)
		(stroke
			(width 0.2)
			(type default)
		)
		(fill no)
		(layer "In8.Cu")
	)
	(gr_circle
		(center 426.271436 -353.97567)
		(end 427.160436 -353.97567)
		(stroke
			(width 0.2)
			(type default)
		)
		(fill no)
		(layer "In8.Cu")
	)
	(gr_line
		(start 426.371766 -397.741902)
		(end 425.569888 -396.940024)
		(stroke
			(width 0.508)
			(type default)
		)
		(layer "In8.Cu")
	)
	(gr_circle
		(center 426.7962 -353.53625)
		(end 427.6852 -353.53625)
		(stroke
			(width 0.2)
			(type default)
		)
		(fill no)
		(layer "In8.Cu")
	)
	(gr_circle
		(center 426.8216 -354.29825)
		(end 427.7106 -354.29825)
		(stroke
			(width 0.2)
			(type default)
		)
		(fill no)
		(layer "In8.Cu")
	)
	(gr_circle
		(center 426.99559 -413.174688)
		(end 429.15459 -413.174688)
		(stroke
			(width 4.318)
			(type default)
		)
		(fill no)
		(layer "In8.Cu")
	)
	(gr_circle
		(center 427.355 -354.65385)
		(end 428.244 -354.65385)
		(stroke
			(width 0.2)
			(type default)
		)
		(fill no)
		(layer "In8.Cu")
	)
	(gr_circle
		(center 427.355 -353.91725)
		(end 428.244 -353.91725)
		(stroke
			(width 0.2)
			(type default)
		)
		(fill no)
		(layer "In8.Cu")
	)
	(gr_circle
		(center 427.355 -353.18065)
		(end 428.244 -353.18065)
		(stroke
			(width 0.2)
			(type default)
		)
		(fill no)
		(layer "In8.Cu")
	)
	(gr_line
		(start 429.29937 -397.741902)
		(end 426.371766 -397.741902)
		(stroke
			(width 0.508)
			(type default)
		)
		(layer "In8.Cu")
	)
	(gr_line
		(start 430.05756 -396.983712)
		(end 429.29937 -397.741902)
		(stroke
			(width 0.508)
			(type default)
		)
		(layer "In8.Cu")
	)
	(gr_line
		(start 430.05756 -386.633212)
		(end 430.05756 -396.983712)
		(stroke
			(width 0.508)
			(type default)
		)
		(layer "In8.Cu")
	)
	(gr_circle
		(center 432.01336 -361.827826)
		(end 433.41036 -361.827826)
		(stroke
			(width 0.2)
			(type default)
		)
		(fill no)
		(layer "In8.Cu")
	)
	(gr_line
		(start 432.062128 -381.039624)
		(end 426.197776 -375.175272)
		(stroke
			(width 0.508)
			(type default)
		)
		(layer "In8.Cu")
	)
	(gr_circle
		(center 432.661568 -353.12858)
		(end 433.541678 -353.12858)
		(stroke
			(width 0.2)
			(type default)
		)
		(fill no)
		(layer "In8.Cu")
	)
	(gr_circle
		(center 433.278788 -353.12858)
		(end 434.158898 -353.12858)
		(stroke
			(width 0.2)
			(type default)
		)
		(fill no)
		(layer "In8.Cu")
	)
	(gr_circle
		(center 433.49545 -384.87858)
		(end 435.65445 -384.87858)
		(stroke
			(width 4.318)
			(type default)
		)
		(fill no)
		(layer "In8.Cu")
	)
	(gr_circle
		(center 433.896008 -353.12858)
		(end 434.776118 -353.12858)
		(stroke
			(width 0.2)
			(type default)
		)
		(fill no)
		(layer "In8.Cu")
	)
	(gr_circle
		(center 434.013102 -352.38309)
		(end 434.902102 -352.38309)
		(stroke
			(width 0.2)
			(type default)
		)
		(fill no)
		(layer "In8.Cu")
	)
	(gr_circle
		(center 434.013102 -351.64649)
		(end 434.902102 -351.64649)
		(stroke
			(width 0.2)
			(type default)
		)
		(fill no)
		(layer "In8.Cu")
	)
	(gr_circle
		(center 434.598064 -354.73767)
		(end 435.487064 -354.73767)
		(stroke
			(width 0.2)
			(type default)
		)
		(fill no)
		(layer "In8.Cu")
	)
	(gr_circle
		(center 434.598064 -354.00107)
		(end 435.487064 -354.00107)
		(stroke
			(width 0.2)
			(type default)
		)
		(fill no)
		(layer "In8.Cu")
	)
	(gr_circle
		(center 435.122828 -353.56165)
		(end 436.011828 -353.56165)
		(stroke
			(width 0.2)
			(type default)
		)
		(fill no)
		(layer "In8.Cu")
	)
	(gr_circle
		(center 435.148228 -354.32365)
		(end 436.037228 -354.32365)
		(stroke
			(width 0.2)
			(type default)
		)
		(fill no)
		(layer "In8.Cu")
	)
	(gr_line
		(start 435.404768 -422.122346)
		(end 464.779106 -392.748008)
		(stroke
			(width 0.508)
			(type default)
		)
		(layer "In8.Cu")
	)
	(gr_circle
		(center 435.469538 -361.496102)
		(end 436.358538 -361.496102)
		(stroke
			(width 0.2)
			(type default)
		)
		(fill no)
		(layer "In8.Cu")
	)
	(gr_circle
		(center 435.469538 -360.734102)
		(end 436.358538 -360.734102)
		(stroke
			(width 0.2)
			(type default)
		)
		(fill no)
		(layer "In8.Cu")
	)
	(gr_circle
		(center 435.469538 -359.972102)
		(end 436.358538 -359.972102)
		(stroke
			(width 0.2)
			(type default)
		)
		(fill no)
		(layer "In8.Cu")
	)
	(gr_line
		(start 435.651148 -381.039624)
		(end 430.05756 -386.633212)
		(stroke
			(width 0.508)
			(type default)
		)
		(layer "In8.Cu")
	)
	(gr_line
		(start 435.651148 -381.039624)
		(end 432.062128 -381.039624)
		(stroke
			(width 0.508)
			(type default)
		)
		(layer "In8.Cu")
	)
	(gr_circle
		(center 435.681628 -354.67925)
		(end 436.570628 -354.67925)
		(stroke
			(width 0.2)
			(type default)
		)
		(fill no)
		(layer "In8.Cu")
	)
	(gr_circle
		(center 435.681628 -353.94265)
		(end 436.570628 -353.94265)
		(stroke
			(width 0.2)
			(type default)
		)
		(fill no)
		(layer "In8.Cu")
	)
	(gr_circle
		(center 435.681628 -353.20605)
		(end 436.570628 -353.20605)
		(stroke
			(width 0.2)
			(type default)
		)
		(fill no)
		(layer "In8.Cu")
	)
	(gr_circle
		(center 436.231538 -361.496102)
		(end 437.120538 -361.496102)
		(stroke
			(width 0.2)
			(type default)
		)
		(fill no)
		(layer "In8.Cu")
	)
	(gr_circle
		(center 436.231538 -360.734102)
		(end 437.120538 -360.734102)
		(stroke
			(width 0.2)
			(type default)
		)
		(fill no)
		(layer "In8.Cu")
	)
	(gr_circle
		(center 436.231538 -359.972102)
		(end 437.120538 -359.972102)
		(stroke
			(width 0.2)
			(type default)
		)
		(fill no)
		(layer "In8.Cu")
	)
	(gr_circle
		(center 437.703214 -12.400788)
		(end 438.592214 -12.400788)
		(stroke
			(width 0.2)
			(type default)
		)
		(fill no)
		(layer "In8.Cu")
	)
	(gr_circle
		(center 438.06999 -13.069316)
		(end 438.95899 -13.069316)
		(stroke
			(width 0.2)
			(type default)
		)
		(fill no)
		(layer "In8.Cu")
	)
	(gr_circle
		(center 438.592214 -12.400788)
		(end 439.481214 -12.400788)
		(stroke
			(width 0.2)
			(type default)
		)
		(fill no)
		(layer "In8.Cu")
	)
	(gr_circle
		(center 438.71515 -13.061696)
		(end 439.60415 -13.061696)
		(stroke
			(width 0.2)
			(type default)
		)
		(fill no)
		(layer "In8.Cu")
	)
	(gr_line
		(start 439.349388 -266.798298)
		(end 440.836558 -268.285468)
		(stroke
			(width 0.508)
			(type default)
		)
		(layer "In8.Cu")
	)
	(gr_line
		(start 439.349642 -341.845138)
		(end 416.31235 -341.845138)
		(stroke
			(width 0.508)
			(type default)
		)
		(layer "In8.Cu")
	)
	(gr_line
		(start 439.349642 -341.845138)
		(end 440.836558 -340.358222)
		(stroke
			(width 0.508)
			(type default)
		)
		(layer "In8.Cu")
	)
	(gr_line
		(start 439.349642 -266.798552)
		(end 393.63142 -266.798552)
		(stroke
			(width 0.508)
			(type default)
		)
		(layer "In8.Cu")
	)
	(gr_circle
		(center 439.39333 -13.043916)
		(end 440.28233 -13.043916)
		(stroke
			(width 0.2)
			(type default)
		)
		(fill no)
		(layer "In8.Cu")
	)
	(gr_circle
		(center 439.481214 -12.400788)
		(end 440.370214 -12.400788)
		(stroke
			(width 0.2)
			(type default)
		)
		(fill no)
		(layer "In8.Cu")
	)
	(gr_line
		(start 439.674 -356.199948)
		(end 273.05 -356.199948)
		(stroke
			(width 0.508)
			(type default)
		)
		(layer "In8.Cu")
	)
	(gr_line
		(start 440.836558 -355.03739)
		(end 439.674 -356.199948)
		(stroke
			(width 0.508)
			(type default)
		)
		(layer "In8.Cu")
	)
	(gr_line
		(start 440.836558 -268.285468)
		(end 440.836558 -355.03739)
		(stroke
			(width 0.508)
			(type default)
		)
		(layer "In8.Cu")
	)
	(gr_circle
		(center 440.945524 -11.261852)
		(end 441.834524 -11.261852)
		(stroke
			(width 0.2)
			(type default)
		)
		(fill no)
		(layer "In8.Cu")
	)
	(gr_circle
		(center 440.945524 -10.626852)
		(end 441.834524 -10.626852)
		(stroke
			(width 0.2)
			(type default)
		)
		(fill no)
		(layer "In8.Cu")
	)
	(gr_circle
		(center 441.129674 -25.982422)
		(end 442.018674 -25.982422)
		(stroke
			(width 0.2)
			(type default)
		)
		(fill no)
		(layer "In8.Cu")
	)
	(gr_circle
		(center 441.354718 -20.73656)
		(end 442.243718 -20.73656)
		(stroke
			(width 0.2)
			(type default)
		)
		(fill no)
		(layer "In8.Cu")
	)
	(gr_circle
		(center 441.354718 -20.10156)
		(end 442.243718 -20.10156)
		(stroke
			(width 0.2)
			(type default)
		)
		(fill no)
		(layer "In8.Cu")
	)
	(gr_circle
		(center 441.354718 -19.21256)
		(end 442.243718 -19.21256)
		(stroke
			(width 0.2)
			(type default)
		)
		(fill no)
		(layer "In8.Cu")
	)
	(gr_circle
		(center 441.354718 -18.57756)
		(end 442.243718 -18.57756)
		(stroke
			(width 0.2)
			(type default)
		)
		(fill no)
		(layer "In8.Cu")
	)
	(gr_circle
		(center 441.475622 -14.123162)
		(end 442.364622 -14.123162)
		(stroke
			(width 0.2)
			(type default)
		)
		(fill no)
		(layer "In8.Cu")
	)
	(gr_circle
		(center 441.475622 -13.488162)
		(end 442.364622 -13.488162)
		(stroke
			(width 0.2)
			(type default)
		)
		(fill no)
		(layer "In8.Cu")
	)
	(gr_circle
		(center 441.56249 -25.461976)
		(end 442.45149 -25.461976)
		(stroke
			(width 0.2)
			(type default)
		)
		(fill no)
		(layer "In8.Cu")
	)
	(gr_circle
		(center 442.018674 -25.982422)
		(end 442.907674 -25.982422)
		(stroke
			(width 0.2)
			(type default)
		)
		(fill no)
		(layer "In8.Cu")
	)
	(gr_circle
		(center 442.371734 -20.983702)
		(end 443.260734 -20.983702)
		(stroke
			(width 0.2)
			(type default)
		)
		(fill no)
		(layer "In8.Cu")
	)
	(gr_circle
		(center 442.371734 -20.348702)
		(end 443.260734 -20.348702)
		(stroke
			(width 0.2)
			(type default)
		)
		(fill no)
		(layer "In8.Cu")
	)
	(gr_circle
		(center 442.371734 -19.459702)
		(end 443.260734 -19.459702)
		(stroke
			(width 0.2)
			(type default)
		)
		(fill no)
		(layer "In8.Cu")
	)
	(gr_circle
		(center 442.371734 -18.824702)
		(end 443.260734 -18.824702)
		(stroke
			(width 0.2)
			(type default)
		)
		(fill no)
		(layer "In8.Cu")
	)
	(gr_circle
		(center 442.45149 -25.461976)
		(end 443.34049 -25.461976)
		(stroke
			(width 0.2)
			(type default)
		)
		(fill no)
		(layer "In8.Cu")
	)
	(gr_line
		(start 442.612526 -54.701948)
		(end 449.739258 -61.82868)
		(stroke
			(width 0.508)
			(type default)
		)
		(layer "In8.Cu")
	)
	(gr_circle
		(center 442.907674 -25.982422)
		(end 443.796674 -25.982422)
		(stroke
			(width 0.2)
			(type default)
		)
		(fill no)
		(layer "In8.Cu")
	)
	(gr_circle
		(center 443.34049 -25.461976)
		(end 444.22949 -25.461976)
		(stroke
			(width 0.2)
			(type default)
		)
		(fill no)
		(layer "In8.Cu")
	)
	(gr_circle
		(center 444.166244 -24.741632)
		(end 445.055244 -24.741632)
		(stroke
			(width 0.2)
			(type default)
		)
		(fill no)
		(layer "In8.Cu")
	)
	(gr_line
		(start 449.250054 -98.832924)
		(end 304.023268 -98.832924)
		(stroke
			(width 0.508)
			(type default)
		)
		(layer "In8.Cu")
	)
	(gr_line
		(start 449.739258 -61.82868)
		(end 457.817728 -61.82868)
		(stroke
			(width 0.508)
			(type default)
		)
		(layer "In8.Cu")
	)
	(gr_circle
		(center 450.669914 -14.526514)
		(end 451.558914 -14.526514)
		(stroke
			(width 0.2)
			(type default)
		)
		(fill no)
		(layer "In8.Cu")
	)
	(gr_circle
		(center 450.670676 -16.010382)
		(end 451.559676 -16.010382)
		(stroke
			(width 0.2)
			(type default)
		)
		(fill no)
		(layer "In8.Cu")
	)
	(gr_circle
		(center 450.670676 -15.273782)
		(end 451.559676 -15.273782)
		(stroke
			(width 0.2)
			(type default)
		)
		(fill no)
		(layer "In8.Cu")
	)
	(gr_circle
		(center 452.054976 -18.535142)
		(end 452.943976 -18.535142)
		(stroke
			(width 0.2)
			(type default)
		)
		(fill no)
		(layer "In8.Cu")
	)
	(gr_circle
		(center 452.054976 -17.798542)
		(end 452.943976 -17.798542)
		(stroke
			(width 0.2)
			(type default)
		)
		(fill no)
		(layer "In8.Cu")
	)
	(gr_line
		(start 452.291958 -95.79102)
		(end 449.250054 -98.832924)
		(stroke
			(width 0.508)
			(type default)
		)
		(layer "In8.Cu")
	)
	(gr_line
		(start 452.291958 -74.851768)
		(end 452.291958 -95.79102)
		(stroke
			(width 0.508)
			(type default)
		)
		(layer "In8.Cu")
	)
	(gr_line
		(start 453.267064 -73.876662)
		(end 452.291958 -74.851768)
		(stroke
			(width 0.508)
			(type default)
		)
		(layer "In8.Cu")
	)
	(gr_line
		(start 455.28992 -195.653406)
		(end 426.178726 -195.653406)
		(stroke
			(width 0.508)
			(type default)
		)
		(layer "In8.Cu")
	)
	(gr_line
		(start 455.919586 -195.02374)
		(end 455.28992 -195.653406)
		(stroke
			(width 0.508)
			(type default)
		)
		(layer "In8.Cu")
	)
	(gr_line
		(start 455.919586 -182.514748)
		(end 455.919586 -195.02374)
		(stroke
			(width 0.508)
			(type default)
		)
		(layer "In8.Cu")
	)
	(gr_arc
		(start 456.202034 -9.780016)
		(mid 456.787819 -11.194227)
		(end 458.20203 -11.780012)
		(stroke
			(width 3.048)
			(type default)
		)
		(layer "In8.Cu")
	)
	(gr_arc
		(start 456.202034 -0.500126)
		(mid 456.05556 -0.146464)
		(end 455.701908 0)
		(stroke
			(width 3.048)
			(type default)
		)
		(layer "In8.Cu")
	)
	(gr_line
		(start 456.202034 -0.500126)
		(end 456.202034 -9.780016)
		(stroke
			(width 3.048)
			(type default)
		)
		(layer "In8.Cu")
	)
	(gr_line
		(start 457.538582 -73.876662)
		(end 453.267064 -73.876662)
		(stroke
			(width 0.508)
			(type default)
		)
		(layer "In8.Cu")
	)
	(gr_line
		(start 457.817728 -61.82868)
		(end 459.674214 -63.685166)
		(stroke
			(width 0.508)
			(type default)
		)
		(layer "In8.Cu")
	)
	(gr_line
		(start 458.20203 -11.780012)
		(end 469.799924 -11.780012)
		(stroke
			(width 3.048)
			(type default)
		)
		(layer "In8.Cu")
	)
	(gr_line
		(start 459.674214 -71.74103)
		(end 457.538582 -73.876662)
		(stroke
			(width 0.508)
			(type default)
		)
		(layer "In8.Cu")
	)
	(gr_line
		(start 459.674214 -63.685166)
		(end 459.674214 -71.74103)
		(stroke
			(width 0.508)
			(type default)
		)
		(layer "In8.Cu")
	)
	(gr_line
		(start 463.300064 -441.989972)
		(end 277.314914 -441.989972)
		(stroke
			(width 3.048)
			(type default)
		)
		(layer "In8.Cu")
	)
	(gr_arc
		(start 463.300064 -441.989972)
		(mid 464.71429 -441.404198)
		(end 465.30006 -439.989976)
		(stroke
			(width 3.048)
			(type default)
		)
		(layer "In8.Cu")
	)
	(gr_line
		(start 464.385152 -381.039624)
		(end 435.651148 -381.039624)
		(stroke
			(width 0.508)
			(type default)
		)
		(layer "In8.Cu")
	)
	(gr_line
		(start 464.779106 -392.748008)
		(end 464.779106 -381.433578)
		(stroke
			(width 0.508)
			(type default)
		)
		(layer "In8.Cu")
	)
	(gr_line
		(start 464.779106 -381.433578)
		(end 464.385152 -381.039624)
		(stroke
			(width 0.508)
			(type default)
		)
		(layer "In8.Cu")
	)
	(gr_line
		(start 465.30006 -409.528518)
		(end 465.30006 -439.989976)
		(stroke
			(width 3.048)
			(type default)
		)
		(layer "In8.Cu")
	)
	(gr_arc
		(start 465.885784 -408.114246)
		(mid 465.452221 -408.76312)
		(end 465.30006 -409.528518)
		(stroke
			(width 3.048)
			(type default)
		)
		(layer "In8.Cu")
	)
	(gr_line
		(start 467.71433 -406.2857)
		(end 465.885784 -408.114246)
		(stroke
			(width 3.048)
			(type default)
		)
		(layer "In8.Cu")
	)
	(gr_arc
		(start 467.71433 -406.2857)
		(mid 468.147828 -405.636947)
		(end 468.300054 -404.871682)
		(stroke
			(width 3.048)
			(type default)
		)
		(layer "In8.Cu")
	)
	(gr_line
		(start 468.300054 -82.828384)
		(end 468.300054 -404.871682)
		(stroke
			(width 3.048)
			(type default)
		)
		(layer "In8.Cu")
	)
	(gr_arc
		(start 468.885778 -81.414112)
		(mid 468.452215 -82.062986)
		(end 468.300054 -82.828384)
		(stroke
			(width 3.048)
			(type default)
		)
		(layer "In8.Cu")
	)
	(gr_line
		(start 471.214196 -79.085694)
		(end 468.885778 -81.414112)
		(stroke
			(width 3.048)
			(type default)
		)
		(layer "In8.Cu")
	)
	(gr_arc
		(start 471.214196 -79.085694)
		(mid 471.6477 -78.436942)
		(end 471.79992 -77.671676)
		(stroke
			(width 3.048)
			(type default)
		)
		(layer "In8.Cu")
	)
	(gr_arc
		(start 471.79992 -13.780008)
		(mid 471.214139 -12.365784)
		(end 469.799924 -11.780012)
		(stroke
			(width 3.048)
			(type default)
		)
		(layer "In8.Cu")
	)
	(gr_line
		(start 471.79992 -13.780008)
		(end 471.79992 -77.671676)
		(stroke
			(width 3.048)
			(type default)
		)
		(layer "In8.Cu")
	)
	(gr_line
		(start 0 -77.671676)
		(end 0 -13.780008)
		(stroke
			(width 3.048)
			(type default)
		)
		(layer "In9.Cu")
	)
	(gr_arc
		(start 0 -77.671676)
		(mid 0.152237 -78.436936)
		(end 0.585724 -79.085694)
		(stroke
			(width 3.048)
			(type default)
		)
		(layer "In9.Cu")
	)
	(gr_poly
		(pts
			(arc
				(start 279.248108 -392.288014)
				(mid 279.284029 -392.273135)
				(end 279.298908 -392.237214)
			)
			(arc
				(start 279.298908 -383.93116)
				(mid 279.284029 -383.895239)
				(end 279.248108 -383.88036)
			)
			(arc
				(start 275.026374 -383.88036)
				(mid 275.006851 -383.884261)
				(end 274.990306 -383.895346)
			)
			(arc
				(start 274.766278 -384.119374)
				(mid 274.755167 -384.135908)
				(end 274.751292 -384.155442)
			)
			(arc
				(start 274.751292 -392.107928)
				(mid 274.755193 -392.127451)
				(end 274.766278 -392.143996)
			)
			(arc
				(start 274.89531 -392.273028)
				(mid 274.911844 -392.284139)
				(end 274.931378 -392.288014)
			)
		)
		(stroke
			(width 0)
			(type solid)
		)
		(fill yes)
		(layer "In9.Cu")
		(net "P12V_MAIN_R_0")
	)
	(gr_poly
		(pts
			(arc
				(start 273.15541 -393.27836)
				(mid 273.174933 -393.274459)
				(end 273.191478 -393.263374)
			)
			(xy 273.191732 -393.26312) (xy 273.669252 -392.7856)
			(arc
				(start 273.669506 -392.785346)
				(mid 273.680617 -392.768812)
				(end 273.684492 -392.749278)
			)
			(arc
				(start 273.684492 -384.155442)
				(mid 273.680591 -384.135919)
				(end 273.669506 -384.119374)
			)
			(xy 273.669252 -384.11912) (xy 273.447764 -383.897632) (xy 273.447256 -383.897124)
			(arc
				(start 273.445478 -383.895346)
				(mid 273.428944 -383.884235)
				(end 273.40941 -383.88036)
			)
			(arc
				(start 239.542574 -383.88036)
				(mid 239.523051 -383.884261)
				(end 239.506506 -383.895346)
			)
			(xy 239.506252 -383.8956) (xy 239.03051 -384.371342) (xy 239.030256 -384.371596)
			(arc
				(start 239.028478 -384.373374)
				(mid 239.017367 -384.389908)
				(end 239.013492 -384.409442)
			)
			(arc
				(start 239.013492 -393.003278)
				(mid 239.017393 -393.022801)
				(end 239.028478 -393.039346)
			)
			(xy 239.028732 -393.0396) (xy 239.252252 -393.26312)
			(arc
				(start 239.252506 -393.263374)
				(mid 239.26904 -393.274485)
				(end 239.288574 -393.27836)
			)
		)
		(stroke
			(width 0)
			(type solid)
		)
		(fill yes)
		(layer "In9.Cu")
		(net "P12V_MAIN_R")
	)
	(gr_poly
		(pts
			(arc
				(start 206.398622 -326.59066)
				(mid 206.418145 -326.586759)
				(end 206.43469 -326.575674)
			)
			(arc
				(start 206.868014 -326.14235)
				(mid 206.879125 -326.125816)
				(end 206.883 -326.106282)
			)
			(arc
				(start 206.883 -195.214748)
				(mid 206.868121 -195.178827)
				(end 206.8322 -195.163948)
			)
			(arc
				(start 205.382368 -195.163948)
				(mid 205.364098 -195.167347)
				(end 205.348332 -195.177156)
			)
			(arc
				(start 205.348332 -195.177156)
				(mid 205.229568 -195.250032)
				(end 205.092554 -195.275454)
			)
			(arc
				(start 205.092554 -195.275454)
				(mid 204.955518 -195.250091)
				(end 204.836776 -195.177156)
			)
			(arc
				(start 204.836776 -195.177156)
				(mid 204.820978 -195.16743)
				(end 204.80274 -195.163948)
			)
			(arc
				(start 203.563728 -195.163948)
				(mid 203.547063 -195.166759)
				(end 203.532232 -195.17487)
			)
			(arc
				(start 203.532232 -195.17487)
				(mid 203.424633 -195.233867)
				(end 203.303632 -195.254372)
			)
			(arc
				(start 203.303632 -195.254372)
				(mid 203.182603 -195.233948)
				(end 203.075032 -195.17487)
			)
			(arc
				(start 203.075032 -195.17487)
				(mid 203.060207 -195.166744)
				(end 203.043536 -195.163948)
			)
			(xy 201.03846 -195.163948)
			(arc
				(start 201.035412 -195.164202)
				(mid 201.013858 -195.166084)
				(end 200.992232 -195.166742)
			)
			(arc
				(start 200.992232 -195.166742)
				(mid 200.970606 -195.166085)
				(end 200.949052 -195.164202)
			)
			(xy 200.946004 -195.163948)
			(arc
				(start 197.838568 -195.163948)
				(mid 197.820298 -195.167347)
				(end 197.804532 -195.177156)
			)
			(arc
				(start 197.804532 -195.177156)
				(mid 197.5485 -195.275732)
				(end 197.292468 -195.177156)
			)
			(arc
				(start 197.292468 -195.177156)
				(mid 197.27667 -195.16743)
				(end 197.258432 -195.163948)
			)
			(arc
				(start 196.019928 -195.163948)
				(mid 196.003263 -195.166759)
				(end 195.988432 -195.17487)
			)
			(arc
				(start 195.988432 -195.17487)
				(mid 195.880833 -195.233867)
				(end 195.759832 -195.254372)
			)
			(arc
				(start 195.759832 -195.254372)
				(mid 195.638803 -195.233948)
				(end 195.531232 -195.17487)
			)
			(arc
				(start 195.531232 -195.17487)
				(mid 195.516407 -195.166744)
				(end 195.499736 -195.163948)
			)
			(xy 193.49466 -195.163948)
			(arc
				(start 193.491612 -195.164202)
				(mid 193.470058 -195.166084)
				(end 193.448432 -195.166742)
			)
			(arc
				(start 193.448432 -195.166742)
				(mid 193.426806 -195.166085)
				(end 193.405252 -195.164202)
			)
			(xy 193.402204 -195.163948)
			(arc
				(start 190.294514 -195.163948)
				(mid 190.276244 -195.167347)
				(end 190.260478 -195.177156)
			)
			(arc
				(start 190.260478 -195.177156)
				(mid 190.004446 -195.275732)
				(end 189.748414 -195.177156)
			)
			(arc
				(start 189.748414 -195.177156)
				(mid 189.732616 -195.16743)
				(end 189.714378 -195.163948)
			)
			(arc
				(start 188.475874 -195.163948)
				(mid 188.459209 -195.166759)
				(end 188.444378 -195.17487)
			)
			(arc
				(start 188.444378 -195.17487)
				(mid 188.336779 -195.233867)
				(end 188.215778 -195.254372)
			)
			(arc
				(start 188.215778 -195.254372)
				(mid 188.094749 -195.233948)
				(end 187.987178 -195.17487)
			)
			(arc
				(start 187.987178 -195.17487)
				(mid 187.972353 -195.166744)
				(end 187.955682 -195.163948)
			)
			(xy 184.81802 -195.163948)
			(arc
				(start 184.814972 -195.164202)
				(mid 184.793418 -195.166084)
				(end 184.771792 -195.166742)
			)
			(arc
				(start 184.771792 -195.166742)
				(mid 184.750166 -195.166085)
				(end 184.728612 -195.164202)
			)
			(xy 184.725564 -195.163948)
			(arc
				(start 182.750714 -195.163948)
				(mid 182.732444 -195.167347)
				(end 182.716678 -195.177156)
			)
			(arc
				(start 182.716678 -195.177156)
				(mid 182.460646 -195.275732)
				(end 182.204614 -195.177156)
			)
			(arc
				(start 182.204614 -195.177156)
				(mid 182.188816 -195.16743)
				(end 182.170578 -195.163948)
			)
			(arc
				(start 180.93182 -195.163948)
				(mid 180.915155 -195.166759)
				(end 180.900324 -195.17487)
			)
			(arc
				(start 180.900324 -195.17487)
				(mid 180.792725 -195.233867)
				(end 180.671724 -195.254372)
			)
			(arc
				(start 180.671724 -195.254372)
				(mid 180.550695 -195.233948)
				(end 180.443124 -195.17487)
			)
			(arc
				(start 180.443124 -195.17487)
				(mid 180.428299 -195.166744)
				(end 180.411628 -195.163948)
			)
			(xy 178.406552 -195.163948)
			(arc
				(start 178.403504 -195.164202)
				(mid 178.38195 -195.166084)
				(end 178.360324 -195.166742)
			)
			(arc
				(start 178.360324 -195.166742)
				(mid 178.338698 -195.166085)
				(end 178.317144 -195.164202)
			)
			(xy 178.314096 -195.163948)
			(arc
				(start 175.20666 -195.163948)
				(mid 175.18839 -195.167347)
				(end 175.172624 -195.177156)
			)
			(arc
				(start 175.172624 -195.177156)
				(mid 174.916592 -195.275732)
				(end 174.66056 -195.177156)
			)
			(arc
				(start 174.66056 -195.177156)
				(mid 174.644762 -195.16743)
				(end 174.626524 -195.163948)
			)
			(arc
				(start 173.387766 -195.163948)
				(mid 173.371101 -195.166759)
				(end 173.35627 -195.17487)
			)
			(arc
				(start 173.35627 -195.17487)
				(mid 173.248671 -195.233867)
				(end 173.12767 -195.254372)
			)
			(arc
				(start 173.12767 -195.254372)
				(mid 173.006641 -195.233948)
				(end 172.89907 -195.17487)
			)
			(arc
				(start 172.89907 -195.17487)
				(mid 172.884245 -195.166744)
				(end 172.867574 -195.163948)
			)
			(xy 170.862498 -195.163948)
			(arc
				(start 170.85945 -195.164202)
				(mid 170.837896 -195.166084)
				(end 170.81627 -195.166742)
			)
			(arc
				(start 170.81627 -195.166742)
				(mid 170.794644 -195.166085)
				(end 170.77309 -195.164202)
			)
			(xy 170.770042 -195.163948)
			(arc
				(start 167.662606 -195.163948)
				(mid 167.644336 -195.167347)
				(end 167.62857 -195.177156)
			)
			(arc
				(start 167.62857 -195.177156)
				(mid 167.372538 -195.275732)
				(end 167.116506 -195.177156)
			)
			(arc
				(start 167.116506 -195.177156)
				(mid 167.100708 -195.16743)
				(end 167.08247 -195.163948)
			)
			(arc
				(start 165.843712 -195.163948)
				(mid 165.827047 -195.166759)
				(end 165.812216 -195.17487)
			)
			(arc
				(start 165.812216 -195.17487)
				(mid 165.704617 -195.233867)
				(end 165.583616 -195.254372)
			)
			(arc
				(start 165.583616 -195.254372)
				(mid 165.462587 -195.233948)
				(end 165.355016 -195.17487)
			)
			(arc
				(start 165.355016 -195.17487)
				(mid 165.340191 -195.166744)
				(end 165.32352 -195.163948)
			)
			(arc
				(start 164.972238 -195.163948)
				(mid 164.952715 -195.167849)
				(end 164.93617 -195.178934)
			)
			(arc
				(start 164.799772 -195.315332)
				(mid 164.788661 -195.331866)
				(end 164.784786 -195.3514)
			)
			(xy 164.784786 -197.242176)
			(arc
				(start 164.78631 -197.248018)
				(mid 164.794144 -197.291394)
				(end 164.796724 -197.335394)
			)
			(arc
				(start 164.796724 -197.335394)
				(mid 164.794121 -197.379392)
				(end 164.78631 -197.42277)
			)
			(xy 164.784786 -197.428612) (xy 164.784786 -198.942198)
			(arc
				(start 164.78631 -198.94804)
				(mid 164.794144 -198.991416)
				(end 164.796724 -199.035416)
			)
			(arc
				(start 164.796724 -199.035416)
				(mid 164.794121 -199.079414)
				(end 164.78631 -199.122792)
			)
			(xy 164.784786 -199.128634) (xy 164.784786 -204.892148)
			(arc
				(start 164.78631 -204.89799)
				(mid 164.794144 -204.941366)
				(end 164.796724 -204.985366)
			)
			(arc
				(start 164.796724 -204.985366)
				(mid 164.794121 -205.029364)
				(end 164.78631 -205.072742)
			)
			(xy 164.784786 -205.078584) (xy 164.784786 -206.59217)
			(arc
				(start 164.78631 -206.598012)
				(mid 164.794144 -206.641388)
				(end 164.796724 -206.685388)
			)
			(arc
				(start 164.796724 -206.685388)
				(mid 164.794121 -206.729386)
				(end 164.78631 -206.772764)
			)
			(xy 164.784786 -206.778606) (xy 164.784786 -208.292192)
			(arc
				(start 164.78631 -208.298034)
				(mid 164.794144 -208.34141)
				(end 164.796724 -208.38541)
			)
			(arc
				(start 164.796724 -208.38541)
				(mid 164.794121 -208.429408)
				(end 164.78631 -208.472786)
			)
			(xy 164.784786 -208.478628) (xy 164.784786 -214.242142)
			(arc
				(start 164.78631 -214.247984)
				(mid 164.794144 -214.29136)
				(end 164.796724 -214.33536)
			)
			(arc
				(start 164.796724 -214.33536)
				(mid 164.794121 -214.379358)
				(end 164.78631 -214.422736)
			)
			(xy 164.784786 -214.428578) (xy 164.784786 -215.942164)
			(arc
				(start 164.78631 -215.948006)
				(mid 164.794144 -215.991382)
				(end 164.796724 -216.035382)
			)
			(arc
				(start 164.796724 -216.035382)
				(mid 164.794121 -216.07938)
				(end 164.78631 -216.122758)
			)
			(xy 164.784786 -216.1286) (xy 164.784786 -217.642186)
			(arc
				(start 164.78631 -217.648028)
				(mid 164.794144 -217.691404)
				(end 164.796724 -217.735404)
			)
			(arc
				(start 164.796724 -217.735404)
				(mid 164.794121 -217.779402)
				(end 164.78631 -217.82278)
			)
			(xy 164.784786 -217.828622) (xy 164.784786 -223.592136)
			(arc
				(start 164.78631 -223.597978)
				(mid 164.794144 -223.641354)
				(end 164.796724 -223.685354)
			)
			(arc
				(start 164.796724 -223.685354)
				(mid 164.794121 -223.729352)
				(end 164.78631 -223.77273)
			)
			(xy 164.784786 -223.778572) (xy 164.784786 -225.292158)
			(arc
				(start 164.78631 -225.298)
				(mid 164.794144 -225.341376)
				(end 164.796724 -225.385376)
			)
			(arc
				(start 164.796724 -225.385376)
				(mid 164.794121 -225.429374)
				(end 164.78631 -225.472752)
			)
			(xy 164.784786 -225.478594) (xy 164.784786 -226.99218)
			(arc
				(start 164.78631 -226.998022)
				(mid 164.794144 -227.041398)
				(end 164.796724 -227.085398)
			)
			(arc
				(start 164.796724 -227.085398)
				(mid 164.794121 -227.129396)
				(end 164.78631 -227.172774)
			)
			(xy 164.784786 -227.178616) (xy 164.784786 -232.94213)
			(arc
				(start 164.78631 -232.947972)
				(mid 164.794144 -232.991348)
				(end 164.796724 -233.035348)
			)
			(arc
				(start 164.796724 -233.035348)
				(mid 164.794121 -233.079346)
				(end 164.78631 -233.122724)
			)
			(xy 164.784786 -233.128566) (xy 164.784786 -234.642152)
			(arc
				(start 164.78631 -234.647994)
				(mid 164.794144 -234.69137)
				(end 164.796724 -234.73537)
			)
			(arc
				(start 164.796724 -234.73537)
				(mid 164.794121 -234.779368)
				(end 164.78631 -234.822746)
			)
			(xy 164.784786 -234.828588) (xy 164.784786 -236.342174)
			(arc
				(start 164.78631 -236.348016)
				(mid 164.794144 -236.391392)
				(end 164.796724 -236.435392)
			)
			(arc
				(start 164.796724 -236.435392)
				(mid 164.794121 -236.47939)
				(end 164.78631 -236.522768)
			)
			(xy 164.784786 -236.52861) (xy 164.784786 -242.292124)
			(arc
				(start 164.78631 -242.297966)
				(mid 164.794144 -242.341342)
				(end 164.796724 -242.385342)
			)
			(arc
				(start 164.796724 -242.385342)
				(mid 164.794121 -242.42934)
				(end 164.78631 -242.472718)
			)
			(xy 164.784786 -242.47856) (xy 164.784786 -243.992146)
			(arc
				(start 164.78631 -243.997988)
				(mid 164.794144 -244.041364)
				(end 164.796724 -244.085364)
			)
			(arc
				(start 164.796724 -244.085364)
				(mid 164.794121 -244.129362)
				(end 164.78631 -244.17274)
			)
			(xy 164.784786 -244.178582) (xy 164.784786 -245.692168)
			(arc
				(start 164.78631 -245.69801)
				(mid 164.794144 -245.741386)
				(end 164.796724 -245.785386)
			)
			(arc
				(start 164.796724 -245.785386)
				(mid 164.794121 -245.829384)
				(end 164.78631 -245.872762)
			)
			(xy 164.784786 -245.878604) (xy 164.784786 -247.39219)
			(arc
				(start 164.78631 -247.398032)
				(mid 164.794144 -247.441408)
				(end 164.796724 -247.485408)
			)
			(arc
				(start 164.796724 -247.485408)
				(mid 164.794121 -247.529406)
				(end 164.78631 -247.572784)
			)
			(xy 164.784786 -247.578626) (xy 164.784786 -249.092212)
			(arc
				(start 164.78631 -249.098054)
				(mid 164.794144 -249.14143)
				(end 164.796724 -249.18543)
			)
			(arc
				(start 164.796724 -249.18543)
				(mid 164.794121 -249.229428)
				(end 164.78631 -249.272806)
			)
			(xy 164.784786 -249.278648) (xy 164.784786 -250.79198)
			(arc
				(start 164.78631 -250.797822)
				(mid 164.794144 -250.841198)
				(end 164.796724 -250.885198)
			)
			(arc
				(start 164.796724 -250.885198)
				(mid 164.794121 -250.929196)
				(end 164.78631 -250.972574)
			)
			(xy 164.784786 -250.978416) (xy 164.784786 -252.492002)
			(arc
				(start 164.78631 -252.497844)
				(mid 164.794144 -252.54122)
				(end 164.796724 -252.58522)
			)
			(arc
				(start 164.796724 -252.58522)
				(mid 164.794121 -252.629218)
				(end 164.78631 -252.672596)
			)
			(xy 164.784786 -252.678438) (xy 164.784786 -255.042162)
			(arc
				(start 164.78631 -255.048004)
				(mid 164.794144 -255.09138)
				(end 164.796724 -255.13538)
			)
			(arc
				(start 164.796724 -255.13538)
				(mid 164.794121 -255.179378)
				(end 164.78631 -255.222756)
			)
			(xy 164.784786 -255.228598) (xy 164.784786 -262.692134)
			(arc
				(start 164.78631 -262.697976)
				(mid 164.794144 -262.741352)
				(end 164.796724 -262.785352)
			)
			(arc
				(start 164.796724 -262.785352)
				(mid 164.794121 -262.82935)
				(end 164.78631 -262.872728)
			)
			(xy 164.784786 -262.87857) (xy 164.784786 -264.392156)
			(arc
				(start 164.78631 -264.397998)
				(mid 164.794144 -264.441374)
				(end 164.796724 -264.485374)
			)
			(arc
				(start 164.796724 -264.485374)
				(mid 164.794121 -264.529372)
				(end 164.78631 -264.57275)
			)
			(xy 164.784786 -264.578592) (xy 164.784786 -266.092178)
			(arc
				(start 164.78631 -266.09802)
				(mid 164.794144 -266.141396)
				(end 164.796724 -266.185396)
			)
			(arc
				(start 164.796724 -266.185396)
				(mid 164.795076 -266.220477)
				(end 164.79012 -266.255246)
			)
			(xy 164.78758 -266.267692) (xy 164.794946 -266.291568)
			(arc
				(start 165.03269 -266.529312)
				(mid 165.049224 -266.540423)
				(end 165.068758 -266.544298)
			)
			(arc
				(start 191.409066 -266.544298)
				(mid 191.506253 -266.563648)
				(end 191.588644 -266.61872)
			)
			(arc
				(start 196.473572 -271.503648)
				(mid 196.528678 -271.586025)
				(end 196.547994 -271.683226)
			)
			(arc
				(start 196.547994 -321.89039)
				(mid 196.528644 -321.987577)
				(end 196.473572 -322.069968)
			)
			(arc
				(start 194.912488 -323.631052)
				(mid 194.901377 -323.647586)
				(end 194.897502 -323.66712)
			)
			(arc
				(start 194.897502 -325.064374)
				(mid 194.901403 -325.083897)
				(end 194.912488 -325.100442)
			)
			(arc
				(start 196.38772 -326.575674)
				(mid 196.404254 -326.586785)
				(end 196.423788 -326.59066)
			)
		)
		(stroke
			(width 0)
			(type solid)
		)
		(fill yes)
		(layer "In9.Cu")
		(net "GND")
	)
	(gr_poly
		(pts
			(arc
				(start 270.790162 -335.233518)
				(mid 270.826083 -335.218639)
				(end 270.840962 -335.182718)
			)
			(arc
				(start 270.840962 -244.368828)
				(mid 270.836564 -244.348152)
				(end 270.824198 -244.330982)
			)
			(arc
				(start 270.824198 -244.330982)
				(mid 270.74315 -244.219724)
				(end 270.71447 -244.08511)
			)
			(arc
				(start 270.71447 -244.08511)
				(mid 270.743209 -243.950522)
				(end 270.824198 -243.839238)
			)
			(arc
				(start 270.824198 -243.839238)
				(mid 270.836655 -243.822109)
				(end 270.840962 -243.801392)
			)
			(arc
				(start 270.840962 -227.143818)
				(mid 270.885666 -226.999983)
				(end 271.00403 -226.906836)
			)
			(arc
				(start 271.00403 -226.906836)
				(mid 271.021922 -226.895264)
				(end 271.033494 -226.877372)
			)
			(arc
				(start 271.033494 -226.877372)
				(mid 271.126645 -226.759015)
				(end 271.270476 -226.714304)
			)
			(arc
				(start 312.386218 -226.714304)
				(mid 312.414405 -226.705767)
				(end 312.433208 -226.683062)
			)
			(xy 312.439304 -226.668584) (xy 312.433208 -226.638612)
			(arc
				(start 312.41238 -226.617784)
				(mid 312.357274 -226.535407)
				(end 312.337958 -226.438206)
			)
			(arc
				(start 312.337958 -194.253866)
				(mid 312.323079 -194.217945)
				(end 312.287158 -194.203066)
			)
			(xy 312.28411 -194.203066) (xy 312.281062 -194.203574) (xy 312.250836 -194.205352)
			(arc
				(start 308.78145 -194.205352)
				(mid 308.764019 -194.208436)
				(end 308.748684 -194.21729)
			)
			(arc
				(start 308.748684 -194.21729)
				(mid 308.511194 -194.303925)
				(end 308.273704 -194.21729)
			)
			(arc
				(start 308.273704 -194.21729)
				(mid 308.25838 -194.208406)
				(end 308.240938 -194.205352)
			)
			(arc
				(start 306.541932 -194.205352)
				(mid 306.519783 -194.210435)
				(end 306.502054 -194.224656)
			)
			(arc
				(start 306.502054 -194.224656)
				(mid 306.212494 -194.365074)
				(end 305.922934 -194.224656)
			)
			(arc
				(start 305.922934 -194.224656)
				(mid 305.905212 -194.21042)
				(end 305.883056 -194.205352)
			)
			(arc
				(start 304.753264 -194.205352)
				(mid 304.731115 -194.210435)
				(end 304.713386 -194.224656)
			)
			(arc
				(start 304.713386 -194.224656)
				(mid 304.423826 -194.365074)
				(end 304.134266 -194.224656)
			)
			(arc
				(start 304.134266 -194.224656)
				(mid 304.116544 -194.21042)
				(end 304.094388 -194.205352)
			)
			(arc
				(start 302.382682 -194.205352)
				(mid 302.365251 -194.208436)
				(end 302.349916 -194.21729)
			)
			(arc
				(start 302.349916 -194.21729)
				(mid 302.112426 -194.303925)
				(end 301.874936 -194.21729)
			)
			(arc
				(start 301.874936 -194.21729)
				(mid 301.859612 -194.208406)
				(end 301.84217 -194.205352)
			)
			(arc
				(start 301.237396 -194.205352)
				(mid 301.219965 -194.208436)
				(end 301.20463 -194.21729)
			)
			(arc
				(start 301.20463 -194.21729)
				(mid 300.96714 -194.303925)
				(end 300.72965 -194.21729)
			)
			(arc
				(start 300.72965 -194.21729)
				(mid 300.714326 -194.208406)
				(end 300.696884 -194.205352)
			)
			(arc
				(start 298.997878 -194.205352)
				(mid 298.975729 -194.210435)
				(end 298.958 -194.224656)
			)
			(arc
				(start 298.958 -194.224656)
				(mid 298.66844 -194.365074)
				(end 298.37888 -194.224656)
			)
			(arc
				(start 298.37888 -194.224656)
				(mid 298.361158 -194.21042)
				(end 298.339002 -194.205352)
			)
			(arc
				(start 297.20921 -194.205352)
				(mid 297.187061 -194.210435)
				(end 297.169332 -194.224656)
			)
			(arc
				(start 297.169332 -194.224656)
				(mid 296.879772 -194.365074)
				(end 296.590212 -194.224656)
			)
			(arc
				(start 296.590212 -194.224656)
				(mid 296.57249 -194.21042)
				(end 296.550334 -194.205352)
			)
			(arc
				(start 294.838628 -194.205352)
				(mid 294.821197 -194.208436)
				(end 294.805862 -194.21729)
			)
			(arc
				(start 294.805862 -194.21729)
				(mid 294.568372 -194.303925)
				(end 294.330882 -194.21729)
			)
			(arc
				(start 294.330882 -194.21729)
				(mid 294.315558 -194.208406)
				(end 294.298116 -194.205352)
			)
			(arc
				(start 293.693342 -194.205352)
				(mid 293.675911 -194.208436)
				(end 293.660576 -194.21729)
			)
			(arc
				(start 293.660576 -194.21729)
				(mid 293.423086 -194.303925)
				(end 293.185596 -194.21729)
			)
			(arc
				(start 293.185596 -194.21729)
				(mid 293.170272 -194.208406)
				(end 293.15283 -194.205352)
			)
			(arc
				(start 291.454078 -194.205352)
				(mid 291.431929 -194.210435)
				(end 291.4142 -194.224656)
			)
			(arc
				(start 291.4142 -194.224656)
				(mid 291.12464 -194.365074)
				(end 290.83508 -194.224656)
			)
			(arc
				(start 290.83508 -194.224656)
				(mid 290.817358 -194.21042)
				(end 290.795202 -194.205352)
			)
			(arc
				(start 289.665156 -194.205352)
				(mid 289.643007 -194.210435)
				(end 289.625278 -194.224656)
			)
			(arc
				(start 289.625278 -194.224656)
				(mid 289.335718 -194.365074)
				(end 289.046158 -194.224656)
			)
			(arc
				(start 289.046158 -194.224656)
				(mid 289.028436 -194.21042)
				(end 289.00628 -194.205352)
			)
			(arc
				(start 287.294574 -194.205352)
				(mid 287.277143 -194.208436)
				(end 287.261808 -194.21729)
			)
			(arc
				(start 287.261808 -194.21729)
				(mid 287.024318 -194.303925)
				(end 286.786828 -194.21729)
			)
			(arc
				(start 286.786828 -194.21729)
				(mid 286.771504 -194.208406)
				(end 286.754062 -194.205352)
			)
			(arc
				(start 286.149288 -194.205352)
				(mid 286.131857 -194.208436)
				(end 286.116522 -194.21729)
			)
			(arc
				(start 286.116522 -194.21729)
				(mid 285.879032 -194.303925)
				(end 285.641542 -194.21729)
			)
			(arc
				(start 285.641542 -194.21729)
				(mid 285.626218 -194.208406)
				(end 285.608776 -194.205352)
			)
			(arc
				(start 283.910024 -194.205352)
				(mid 283.887875 -194.210435)
				(end 283.870146 -194.224656)
			)
			(arc
				(start 283.870146 -194.224656)
				(mid 283.580586 -194.365074)
				(end 283.291026 -194.224656)
			)
			(arc
				(start 283.291026 -194.224656)
				(mid 283.273304 -194.21042)
				(end 283.251148 -194.205352)
			)
			(arc
				(start 282.121102 -194.205352)
				(mid 282.098953 -194.210435)
				(end 282.081224 -194.224656)
			)
			(arc
				(start 282.081224 -194.224656)
				(mid 281.791664 -194.365074)
				(end 281.502104 -194.224656)
			)
			(arc
				(start 281.502104 -194.224656)
				(mid 281.484382 -194.21042)
				(end 281.462226 -194.205352)
			)
			(arc
				(start 279.75052 -194.205352)
				(mid 279.733089 -194.208436)
				(end 279.717754 -194.21729)
			)
			(arc
				(start 279.717754 -194.21729)
				(mid 279.480264 -194.303925)
				(end 279.242774 -194.21729)
			)
			(arc
				(start 279.242774 -194.21729)
				(mid 279.22745 -194.208406)
				(end 279.210008 -194.205352)
			)
			(arc
				(start 278.605488 -194.205352)
				(mid 278.588057 -194.208436)
				(end 278.572722 -194.21729)
			)
			(arc
				(start 278.572722 -194.21729)
				(mid 278.335232 -194.303925)
				(end 278.097742 -194.21729)
			)
			(arc
				(start 278.097742 -194.21729)
				(mid 278.082418 -194.208406)
				(end 278.064976 -194.205352)
			)
			(arc
				(start 276.36597 -194.205352)
				(mid 276.343821 -194.210435)
				(end 276.326092 -194.224656)
			)
			(arc
				(start 276.326092 -194.224656)
				(mid 276.036532 -194.365074)
				(end 275.746972 -194.224656)
			)
			(arc
				(start 275.746972 -194.224656)
				(mid 275.72925 -194.21042)
				(end 275.707094 -194.205352)
			)
			(arc
				(start 274.577302 -194.205352)
				(mid 274.555153 -194.210435)
				(end 274.537424 -194.224656)
			)
			(arc
				(start 274.537424 -194.224656)
				(mid 274.247864 -194.365074)
				(end 273.958304 -194.224656)
			)
			(arc
				(start 273.958304 -194.224656)
				(mid 273.940582 -194.21042)
				(end 273.918426 -194.205352)
			)
			(arc
				(start 272.20672 -194.205352)
				(mid 272.189289 -194.208436)
				(end 272.173954 -194.21729)
			)
			(arc
				(start 272.173954 -194.21729)
				(mid 271.936464 -194.303925)
				(end 271.698974 -194.21729)
			)
			(arc
				(start 271.698974 -194.21729)
				(mid 271.68365 -194.208406)
				(end 271.666208 -194.205352)
			)
			(arc
				(start 271.061434 -194.205352)
				(mid 271.044003 -194.208436)
				(end 271.028668 -194.21729)
			)
			(arc
				(start 271.028668 -194.21729)
				(mid 270.791178 -194.303925)
				(end 270.553688 -194.21729)
			)
			(arc
				(start 270.553688 -194.21729)
				(mid 270.538364 -194.208406)
				(end 270.520922 -194.205352)
			)
			(arc
				(start 268.821916 -194.205352)
				(mid 268.799767 -194.210435)
				(end 268.782038 -194.224656)
			)
			(arc
				(start 268.782038 -194.224656)
				(mid 268.492478 -194.365074)
				(end 268.202918 -194.224656)
			)
			(arc
				(start 268.202918 -194.224656)
				(mid 268.185196 -194.21042)
				(end 268.16304 -194.205352)
			)
			(arc
				(start 267.033248 -194.205352)
				(mid 267.011099 -194.210435)
				(end 266.99337 -194.224656)
			)
			(arc
				(start 266.99337 -194.224656)
				(mid 266.70381 -194.365074)
				(end 266.41425 -194.224656)
			)
			(arc
				(start 266.41425 -194.224656)
				(mid 266.396528 -194.21042)
				(end 266.374372 -194.205352)
			)
			(arc
				(start 264.662666 -194.205352)
				(mid 264.645235 -194.208436)
				(end 264.6299 -194.21729)
			)
			(arc
				(start 264.6299 -194.21729)
				(mid 264.54161 -194.272401)
				(end 264.441432 -194.300602)
			)
			(xy 264.43305 -194.301872) (xy 264.418318 -194.308984)
			(arc
				(start 264.099802 -194.6275)
				(mid 264.088691 -194.644034)
				(end 264.084816 -194.663568)
			)
			(arc
				(start 264.084816 -196.49694)
				(mid 264.089964 -196.519479)
				(end 264.104628 -196.537326)
			)
			(arc
				(start 264.104628 -196.537326)
				(mid 264.253701 -196.83984)
				(end 264.104628 -197.142354)
			)
			(arc
				(start 264.104628 -197.142354)
				(mid 264.090052 -197.160243)
				(end 264.084816 -197.18274)
			)
			(xy 264.084816 -323.566028) (xy 264.107168 -323.593714)
			(arc
				(start 264.124948 -323.597524)
				(mid 264.341407 -323.730748)
				(end 264.426192 -323.970396)
			)
			(arc
				(start 264.426192 -323.970396)
				(mid 264.376683 -324.158346)
				(end 264.241026 -324.297548)
			)
			(xy 264.229342 -324.30466) (xy 264.216388 -324.328028) (xy 264.218166 -324.443344) (xy 264.231882 -324.466458)
			(arc
				(start 264.24382 -324.473316)
				(mid 264.386894 -324.613217)
				(end 264.4394 -324.80631)
			)
			(arc
				(start 264.4394 -324.80631)
				(mid 264.350918 -325.050705)
				(end 264.126472 -325.181722)
			)
			(xy 264.108184 -325.185024) (xy 264.084816 -325.213218)
			(arc
				(start 264.084816 -335.091786)
				(mid 264.088717 -335.111309)
				(end 264.099802 -335.127854)
			)
			(arc
				(start 264.19048 -335.218532)
				(mid 264.207014 -335.229643)
				(end 264.226548 -335.233518)
			)
		)
		(stroke
			(width 0)
			(type solid)
		)
		(fill yes)
		(layer "In9.Cu")
		(net "GND")
	)
	(gr_poly
		(pts
			(arc
				(start 228.921818 -436.47868)
				(mid 228.941341 -436.474779)
				(end 228.957886 -436.463694)
			)
			(arc
				(start 229.664514 -435.757066)
				(mid 229.675625 -435.740532)
				(end 229.6795 -435.720998)
			)
			(arc
				(start 229.6795 -422.180766)
				(mid 229.703653 -422.05925)
				(end 229.772464 -421.95623)
			)
			(arc
				(start 234.67314 -417.055554)
				(mid 234.776172 -416.986773)
				(end 234.897676 -416.96259)
			)
			(arc
				(start 272.037556 -416.96259)
				(mid 272.057079 -416.958689)
				(end 272.073624 -416.947604)
			)
			(arc
				(start 280.035254 -408.985974)
				(mid 280.046365 -408.96944)
				(end 280.05024 -408.949906)
			)
			(arc
				(start 280.05024 -394.963396)
				(mid 280.046339 -394.943873)
				(end 280.035254 -394.927328)
			)
			(xy 280.035 -394.927074) (xy 279.65146 -394.543534)
			(arc
				(start 279.651206 -394.54328)
				(mid 279.634672 -394.532169)
				(end 279.615138 -394.528294)
			)
			(arc
				(start 278.051514 -394.528294)
				(mid 278.036928 -394.530433)
				(end 278.023574 -394.536676)
			)
			(arc
				(start 278.023574 -394.536676)
				(mid 277.823537 -394.629726)
				(end 277.605236 -394.661644)
			)
			(arc
				(start 277.605236 -394.661644)
				(mid 277.421236 -394.639047)
				(end 277.248112 -394.572744)
			)
			(arc
				(start 277.248112 -394.572744)
				(mid 277.224236 -394.566797)
				(end 277.20036 -394.572744)
			)
			(arc
				(start 277.20036 -394.572744)
				(mid 277.027244 -394.639078)
				(end 276.843236 -394.661644)
			)
			(arc
				(start 276.843236 -394.661644)
				(mid 276.624932 -394.629737)
				(end 276.424898 -394.536676)
			)
			(arc
				(start 276.424898 -394.536676)
				(mid 276.411542 -394.53044)
				(end 276.396958 -394.528294)
			)
			(arc
				(start 269.04569 -394.528294)
				(mid 269.030398 -394.53065)
				(end 269.01648 -394.537438)
			)
			(arc
				(start 269.01648 -394.537438)
				(mid 268.808203 -394.640414)
				(end 268.578584 -394.675868)
			)
			(arc
				(start 268.578584 -394.675868)
				(mid 268.394584 -394.653271)
				(end 268.22146 -394.586968)
			)
			(arc
				(start 268.22146 -394.586968)
				(mid 268.197584 -394.581021)
				(end 268.173708 -394.586968)
			)
			(arc
				(start 268.173708 -394.586968)
				(mid 268.000592 -394.653302)
				(end 267.816584 -394.675868)
			)
			(arc
				(start 267.816584 -394.675868)
				(mid 267.586971 -394.640395)
				(end 267.378688 -394.537438)
			)
			(arc
				(start 267.378688 -394.537438)
				(mid 267.364793 -394.530577)
				(end 267.349478 -394.528294)
			)
			(arc
				(start 261.01929 -394.528294)
				(mid 261.003998 -394.53065)
				(end 260.99008 -394.537438)
			)
			(arc
				(start 260.99008 -394.537438)
				(mid 260.781803 -394.640414)
				(end 260.552184 -394.675868)
			)
			(arc
				(start 260.552184 -394.675868)
				(mid 260.368184 -394.653271)
				(end 260.19506 -394.586968)
			)
			(arc
				(start 260.19506 -394.586968)
				(mid 260.171184 -394.581021)
				(end 260.147308 -394.586968)
			)
			(arc
				(start 260.147308 -394.586968)
				(mid 259.974192 -394.653302)
				(end 259.790184 -394.675868)
			)
			(arc
				(start 259.790184 -394.675868)
				(mid 259.560571 -394.640395)
				(end 259.352288 -394.537438)
			)
			(arc
				(start 259.352288 -394.537438)
				(mid 259.338393 -394.530577)
				(end 259.323078 -394.528294)
			)
			(arc
				(start 252.99289 -394.528294)
				(mid 252.977598 -394.53065)
				(end 252.96368 -394.537438)
			)
			(arc
				(start 252.96368 -394.537438)
				(mid 252.755403 -394.640414)
				(end 252.525784 -394.675868)
			)
			(arc
				(start 252.525784 -394.675868)
				(mid 252.341784 -394.653271)
				(end 252.16866 -394.586968)
			)
			(arc
				(start 252.16866 -394.586968)
				(mid 252.144784 -394.581021)
				(end 252.120908 -394.586968)
			)
			(arc
				(start 252.120908 -394.586968)
				(mid 251.947792 -394.653302)
				(end 251.763784 -394.675868)
			)
			(arc
				(start 251.763784 -394.675868)
				(mid 251.534171 -394.640395)
				(end 251.325888 -394.537438)
			)
			(arc
				(start 251.325888 -394.537438)
				(mid 251.311993 -394.530577)
				(end 251.296678 -394.528294)
			)
			(arc
				(start 244.9576 -394.528294)
				(mid 244.942576 -394.530567)
				(end 244.928898 -394.537184)
			)
			(arc
				(start 244.928898 -394.537184)
				(mid 244.722849 -394.637373)
				(end 244.496336 -394.671804)
			)
			(arc
				(start 244.496336 -394.671804)
				(mid 244.312336 -394.649207)
				(end 244.139212 -394.582904)
			)
			(arc
				(start 244.139212 -394.582904)
				(mid 244.115336 -394.576957)
				(end 244.09146 -394.582904)
			)
			(arc
				(start 244.09146 -394.582904)
				(mid 243.918344 -394.649238)
				(end 243.734336 -394.671804)
			)
			(arc
				(start 243.734336 -394.671804)
				(mid 243.507823 -394.637371)
				(end 243.301774 -394.537184)
			)
			(arc
				(start 243.301774 -394.537184)
				(mid 243.288095 -394.53057)
				(end 243.273072 -394.528294)
			)
			(arc
				(start 239.250982 -394.528294)
				(mid 239.215061 -394.543173)
				(end 239.200182 -394.579094)
			)
			(arc
				(start 239.200182 -405.390096)
				(mid 239.176029 -405.511612)
				(end 239.107218 -405.614632)
			)
			(arc
				(start 238.94034 -405.78151)
				(mid 238.837308 -405.850291)
				(end 238.715804 -405.874474)
			)
			(arc
				(start 234.522264 -405.874474)
				(mid 234.400748 -405.850321)
				(end 234.297728 -405.78151)
			)
			(arc
				(start 233.595926 -405.079708)
				(mid 233.527145 -404.976676)
				(end 233.502962 -404.855172)
			)
			(arc
				(start 233.502962 -404.072344)
				(mid 233.499061 -404.052821)
				(end 233.487976 -404.036276)
			)
			(arc
				(start 233.3498 -403.8981)
				(mid 233.281019 -403.795068)
				(end 233.256836 -403.673564)
			)
			(arc
				(start 233.256836 -400.256502)
				(mid 233.252935 -400.236979)
				(end 233.24185 -400.220434)
			)
			(arc
				(start 233.236008 -400.214592)
				(mid 233.219474 -400.203481)
				(end 233.19994 -400.199606)
			)
			(arc
				(start 229.898956 -400.199606)
				(mid 229.879433 -400.203507)
				(end 229.862888 -400.214592)
			)
			(arc
				(start 229.848664 -400.228816)
				(mid 229.837553 -400.24535)
				(end 229.833678 -400.264884)
			)
			(arc
				(start 229.833678 -403.583648)
				(mid 229.809525 -403.705164)
				(end 229.740714 -403.808184)
			)
			(arc
				(start 229.66426 -403.884638)
				(mid 229.653149 -403.901172)
				(end 229.649274 -403.920706)
			)
			(arc
				(start 229.649274 -406.19299)
				(mid 229.625121 -406.314506)
				(end 229.55631 -406.417526)
			)
			(arc
				(start 227.443284 -408.530552)
				(mid 227.340252 -408.599333)
				(end 227.218748 -408.623516)
			)
			(arc
				(start 225.642424 -408.623516)
				(mid 225.623565 -408.627146)
				(end 225.607372 -408.637486)
			)
			(arc
				(start 225.607372 -408.637486)
				(mid 225.364908 -408.792887)
				(end 225.0821 -408.84729)
			)
			(arc
				(start 225.0821 -408.84729)
				(mid 224.549885 -408.630828)
				(end 224.319846 -408.10434)
			)
			(xy 224.319592 -408.094434) (xy 224.311972 -408.076654)
			(arc
				(start 222.874586 -406.639268)
				(mid 222.805805 -406.536236)
				(end 222.781622 -406.414732)
			)
			(arc
				(start 222.781622 -403.953472)
				(mid 222.777721 -403.933949)
				(end 222.766636 -403.917404)
			)
			(arc
				(start 222.681546 -403.832314)
				(mid 222.612765 -403.729282)
				(end 222.588582 -403.607778)
			)
			(xy 222.588582 -400.229832) (xy 222.580962 -400.21129) (xy 222.57766 -400.207988)
			(arc
				(start 219.197936 -400.207988)
				(mid 219.178413 -400.211889)
				(end 219.161868 -400.222974)
			)
			(xy 219.157296 -400.227546)
			(arc
				(start 219.157296 -403.583394)
				(mid 219.133143 -403.70491)
				(end 219.064332 -403.80793)
			)
			(arc
				(start 219.00007 -403.872192)
				(mid 218.988959 -403.888726)
				(end 218.985084 -403.90826)
			)
			(arc
				(start 218.985084 -406.217374)
				(mid 218.960931 -406.33889)
				(end 218.89212 -406.44191)
			)
			(arc
				(start 216.76614 -408.56789)
				(mid 216.663108 -408.636671)
				(end 216.541604 -408.660854)
			)
			(arc
				(start 214.93226 -408.660854)
				(mid 214.915131 -408.66392)
				(end 214.900002 -408.672538)
			)
			(arc
				(start 214.900002 -408.672538)
				(mid 214.672289 -408.802264)
				(end 214.4141 -408.84729)
			)
			(arc
				(start 214.4141 -408.84729)
				(mid 213.886272 -408.635069)
				(end 213.652354 -408.116532)
			)
			(xy 213.651846 -408.10688) (xy 213.644226 -408.089608)
			(arc
				(start 212.189822 -406.635204)
				(mid 212.121041 -406.532172)
				(end 212.096858 -406.410668)
			)
			(arc
				(start 212.096858 -403.916642)
				(mid 212.092957 -403.897119)
				(end 212.081872 -403.880574)
			)
			(arc
				(start 212.058504 -403.857206)
				(mid 211.989723 -403.754174)
				(end 211.96554 -403.63267)
			)
			(arc
				(start 211.96554 -400.29765)
				(mid 211.961639 -400.278127)
				(end 211.950554 -400.261582)
			)
			(arc
				(start 211.854542 -400.16557)
				(mid 211.838008 -400.154459)
				(end 211.818474 -400.150584)
			)
			(arc
				(start 208.578704 -400.150584)
				(mid 208.559181 -400.154485)
				(end 208.542636 -400.16557)
			)
			(arc
				(start 208.512156 -400.19605)
				(mid 208.501045 -400.212584)
				(end 208.49717 -400.232118)
			)
			(arc
				(start 208.49717 -403.534118)
				(mid 208.473017 -403.655634)
				(end 208.404206 -403.758654)
			)
			(arc
				(start 208.323688 -403.839172)
				(mid 208.312577 -403.855706)
				(end 208.308702 -403.87524)
			)
			(arc
				(start 208.308702 -406.275032)
				(mid 208.284549 -406.396548)
				(end 208.215738 -406.499568)
			)
			(arc
				(start 206.172562 -408.542744)
				(mid 206.06953 -408.611525)
				(end 205.948026 -408.635708)
			)
			(arc
				(start 204.293216 -408.635708)
				(mid 204.274946 -408.639107)
				(end 204.25918 -408.648916)
			)
			(arc
				(start 204.25918 -408.648916)
				(mid 204.021144 -408.79596)
				(end 203.7461 -408.84729)
			)
			(arc
				(start 203.7461 -408.84729)
				(mid 203.306844 -408.708001)
				(end 203.028042 -408.341068)
			)
			(xy 203.023978 -408.330146)
			(arc
				(start 201.5871 -406.893268)
				(mid 201.518319 -406.790236)
				(end 201.494136 -406.668732)
			)
			(arc
				(start 201.494136 -403.941026)
				(mid 201.490235 -403.921503)
				(end 201.47915 -403.904958)
			)
			(arc
				(start 201.373994 -403.799802)
				(mid 201.305213 -403.69677)
				(end 201.28103 -403.575266)
			)
			(arc
				(start 201.28103 -400.264884)
				(mid 201.277129 -400.245361)
				(end 201.266044 -400.228816)
			)
			(arc
				(start 201.221594 -400.184366)
				(mid 201.20506 -400.173255)
				(end 201.185526 -400.16938)
			)
			(arc
				(start 197.9168 -400.16938)
				(mid 197.897277 -400.173281)
				(end 197.880732 -400.184366)
			)
			(arc
				(start 197.844156 -400.220942)
				(mid 197.833045 -400.237476)
				(end 197.82917 -400.25701)
			)
			(arc
				(start 197.82917 -403.58314)
				(mid 197.805017 -403.704656)
				(end 197.736206 -403.807676)
			)
			(arc
				(start 195.6435 -405.900382)
				(mid 195.540468 -405.969163)
				(end 195.418964 -405.993346)
			)
			(arc
				(start 191.073786 -405.993346)
				(mid 190.95227 -405.969193)
				(end 190.84925 -405.900382)
			)
			(arc
				(start 188.07938 -403.130512)
				(mid 188.010599 -403.02748)
				(end 187.986416 -402.905976)
			)
			(arc
				(start 187.986416 -400.258534)
				(mid 187.971537 -400.222613)
				(end 187.935616 -400.207734)
			)
			(arc
				(start 184.616598 -400.207734)
				(mid 184.597075 -400.211635)
				(end 184.58053 -400.22272)
			)
			(xy 184.575958 -400.227292) (xy 184.575958 -405.83104) (xy 184.598818 -405.85898)
			(arc
				(start 184.617106 -405.862536)
				(mid 184.925224 -406.236932)
				(end 184.617106 -406.611328)
			)
			(xy 184.598818 -406.614884) (xy 184.575958 -406.642824)
			(arc
				(start 184.575958 -410.555694)
				(mid 184.579859 -410.575217)
				(end 184.590944 -410.591762)
			)
			(arc
				(start 184.926986 -410.927804)
				(mid 184.94352 -410.938915)
				(end 184.963054 -410.94279)
			)
			(arc
				(start 187.965334 -410.94279)
				(mid 188.08685 -410.966943)
				(end 188.18987 -411.035754)
			)
			(arc
				(start 188.836808 -411.682692)
				(mid 188.853342 -411.693803)
				(end 188.872876 -411.697678)
			)
			(arc
				(start 195.270882 -411.697678)
				(mid 195.392398 -411.721831)
				(end 195.495418 -411.790642)
			)
			(arc
				(start 196.65696 -412.952184)
				(mid 196.725741 -413.055216)
				(end 196.749924 -413.17672)
			)
			(arc
				(start 196.749924 -421.558466)
				(mid 196.753825 -421.577989)
				(end 196.76491 -421.594534)
			)
			(arc
				(start 205.961996 -430.79162)
				(mid 206.030777 -430.894652)
				(end 206.05496 -431.016156)
			)
			(arc
				(start 206.05496 -435.078378)
				(mid 206.058861 -435.097901)
				(end 206.069946 -435.114446)
			)
			(arc
				(start 207.419194 -436.463694)
				(mid 207.435728 -436.474805)
				(end 207.455262 -436.47868)
			)
		)
		(stroke
			(width 0)
			(type solid)
		)
		(fill yes)
		(layer "In9.Cu")
		(net "P12V_PSU")
	)
	(gr_poly
		(pts
			(xy 380.355094 -396.399004) (xy 380.365165 -396.398582) (xy 380.383771 -396.39087) (xy 380.391162 -396.384018)
			(xy 381.94488 -394.8303) (xy 381.95885 -394.817346) (xy 381.968248 -394.809218) (xy 381.977392 -394.786358)
			(xy 381.96647 -394.678662) (xy 381.953008 -394.657834) (xy 381.942086 -394.651738) (xy 381.923282 -394.640765)
			(xy 381.888705 -394.614311) (xy 381.858242 -394.583209) (xy 381.83251 -394.548091) (xy 381.821944 -394.529056)
			(xy 381.821436 -394.528294) (xy 381.423672 -393.839954) (xy 381.411735 -393.817294) (xy 381.394778 -393.76897)
			(xy 381.386128 -393.718493) (xy 381.385572 -393.692888) (xy 381.385572 -393.69238) (xy 381.386021 -393.668375)
			(xy 381.393538 -393.620956) (xy 381.408383 -393.575298) (xy 381.430191 -393.532526) (xy 381.458425 -393.493694)
			(xy 381.492388 -393.45976) (xy 381.531243 -393.431559) (xy 381.574033 -393.409786) (xy 381.619703 -393.394978)
			(xy 381.667128 -393.387501) (xy 381.691134 -393.387072) (xy 381.715067 -393.387539) (xy 381.762348 -393.395007)
			(xy 381.807886 -393.409754) (xy 381.850568 -393.43142) (xy 381.889351 -393.459475) (xy 381.923286 -393.493233)
			(xy 381.951544 -393.531869) (xy 381.962914 -393.552934) (xy 381.963422 -393.55395) (xy 382.043728 -393.692888)
			(xy 382.585976 -393.692888) (xy 382.585976 -393.69238) (xy 382.586444 -393.668389) (xy 382.593953 -393.620998)
			(xy 382.608782 -393.575365) (xy 382.630567 -393.532614) (xy 382.65877 -393.493796) (xy 382.692699 -393.459868)
			(xy 382.731517 -393.431664) (xy 382.774269 -393.40988) (xy 382.819902 -393.395052) (xy 382.867293 -393.387544)
			(xy 382.891284 -393.387072) (xy 382.91522 -393.387511) (xy 382.962506 -393.394974) (xy 383.008049 -393.40972)
			(xy 383.050736 -393.431388) (xy 383.089521 -393.459448) (xy 383.123456 -393.493214) (xy 383.15171 -393.531858)
			(xy 383.163064 -393.552934) (xy 383.163572 -393.55395) (xy 383.243878 -393.692888) (xy 383.785872 -393.692888)
			(xy 383.785872 -393.69238) (xy 383.786344 -393.668389) (xy 383.793853 -393.620999) (xy 383.808681 -393.575366)
			(xy 383.830466 -393.532615) (xy 383.858669 -393.493797) (xy 383.892597 -393.459869) (xy 383.931415 -393.431666)
			(xy 383.974166 -393.409881) (xy 384.019799 -393.395053) (xy 384.067189 -393.387544) (xy 384.09118 -393.387072)
			(xy 384.115116 -393.387515) (xy 384.162401 -393.394977) (xy 384.207945 -393.409722) (xy 384.250631 -393.43139)
			(xy 384.289417 -393.459449) (xy 384.323352 -393.493214) (xy 384.351606 -393.531858) (xy 384.36296 -393.552934)
			(xy 384.363468 -393.55395) (xy 384.443774 -393.692888) (xy 384.985768 -393.692888) (xy 384.985768 -393.69238)
			(xy 384.986244 -393.668389) (xy 384.993752 -393.620999) (xy 385.008581 -393.575367) (xy 385.030365 -393.532616)
			(xy 385.058568 -393.493799) (xy 385.092496 -393.459871) (xy 385.131313 -393.431667) (xy 385.174063 -393.409883)
			(xy 385.219695 -393.395053) (xy 385.267085 -393.387544) (xy 385.291076 -393.387072) (xy 385.315011 -393.387518)
			(xy 385.362297 -393.39498) (xy 385.40784 -393.409724) (xy 385.450527 -393.431391) (xy 385.489312 -393.45945)
			(xy 385.523247 -393.493215) (xy 385.551501 -393.531858) (xy 385.562856 -393.552934) (xy 385.563364 -393.55395)
			(xy 385.64367 -393.692888) (xy 386.185664 -393.692888) (xy 386.185664 -393.69238) (xy 386.186121 -393.668375)
			(xy 386.193637 -393.620957) (xy 386.208482 -393.5753) (xy 386.23029 -393.532528) (xy 386.258522 -393.493697)
			(xy 386.292484 -393.459762) (xy 386.331339 -393.431561) (xy 386.374127 -393.409788) (xy 386.419797 -393.39498)
			(xy 386.467221 -393.387501) (xy 386.491226 -393.387072) (xy 386.51516 -393.387558) (xy 386.562444 -393.395013)
			(xy 386.607986 -393.40975) (xy 386.650673 -393.43141) (xy 386.689459 -393.459463) (xy 386.723395 -393.493222)
			(xy 386.751651 -393.53186) (xy 386.763006 -393.552934) (xy 386.763514 -393.55395) (xy 386.84382 -393.692888)
			(xy 387.38556 -393.692888) (xy 387.38556 -393.69238) (xy 387.386021 -393.668375) (xy 387.393537 -393.620958)
			(xy 387.408382 -393.575301) (xy 387.430189 -393.53253) (xy 387.458421 -393.493698) (xy 387.492383 -393.459764)
			(xy 387.531236 -393.431563) (xy 387.574025 -393.409789) (xy 387.619693 -393.394981) (xy 387.667117 -393.387502)
			(xy 387.691122 -393.387072) (xy 387.715056 -393.387562) (xy 387.762339 -393.395015) (xy 387.807882 -393.409752)
			(xy 387.850568 -393.431412) (xy 387.889354 -393.459464) (xy 387.923291 -393.493222) (xy 387.951547 -393.531861)
			(xy 387.962902 -393.552934) (xy 387.96341 -393.55395) (xy 388.043716 -393.692888) (xy 388.585964 -393.692888)
			(xy 388.585964 -393.69238) (xy 388.586444 -393.66839) (xy 388.593952 -393.621) (xy 388.608781 -393.575368)
			(xy 388.630564 -393.532617) (xy 388.658767 -393.4938) (xy 388.692694 -393.459872) (xy 388.73151 -393.431668)
			(xy 388.774261 -393.409884) (xy 388.819892 -393.395054) (xy 388.867282 -393.387545) (xy 388.891272 -393.387072)
			(xy 388.915207 -393.387521) (xy 388.962493 -393.394982) (xy 389.008036 -393.409727) (xy 389.050723 -393.431393)
			(xy 389.089508 -393.459451) (xy 389.123443 -393.493215) (xy 389.151697 -393.531858) (xy 389.163052 -393.552934)
			(xy 389.16356 -393.55395) (xy 389.55599 -394.232892) (xy 389.568819 -394.256222) (xy 389.587037 -394.306246)
			(xy 389.596295 -394.358673) (xy 389.596884 -394.385292) (xy 389.596453 -394.409299) (xy 389.588939 -394.456721)
			(xy 389.574095 -394.502382) (xy 389.552286 -394.545157) (xy 389.524051 -394.583991) (xy 389.490085 -394.617927)
			(xy 389.451226 -394.646128) (xy 389.408432 -394.667898) (xy 389.362758 -394.682702) (xy 389.315329 -394.690175)
			(xy 389.291322 -394.6906) (xy 389.267749 -394.690188) (xy 389.221161 -394.68295) (xy 389.176243 -394.668628)
			(xy 389.134065 -394.647562) (xy 389.095631 -394.620255) (xy 389.061859 -394.587358) (xy 389.033553 -394.549655)
			(xy 389.022082 -394.529056) (xy 389.021574 -394.528294) (xy 388.62381 -393.839954) (xy 388.611948 -393.81727)
			(xy 388.595093 -393.76894) (xy 388.586513 -393.71848) (xy 388.585964 -393.692888) (xy 388.043716 -393.692888)
			(xy 388.35584 -394.232892) (xy 388.368594 -394.256247) (xy 388.386701 -394.30628) (xy 388.395902 -394.358688)
			(xy 388.39648 -394.385292) (xy 388.396054 -394.409286) (xy 388.388548 -394.456684) (xy 388.373719 -394.502324)
			(xy 388.351932 -394.545082) (xy 388.323724 -394.583905) (xy 388.28979 -394.617837) (xy 388.250965 -394.646042)
			(xy 388.208206 -394.667826) (xy 388.162565 -394.682653) (xy 388.115166 -394.690156) (xy 388.091172 -394.6906)
			(xy 388.067597 -394.690229) (xy 388.021008 -394.682983) (xy 387.976089 -394.668653) (xy 387.93391 -394.647581)
			(xy 387.895478 -394.620268) (xy 387.861707 -394.587365) (xy 387.833402 -394.549657) (xy 387.821932 -394.529056)
			(xy 387.821424 -394.528294) (xy 387.42366 -393.839954) (xy 387.41173 -393.817293) (xy 387.394797 -393.768964)
			(xy 387.386143 -393.718491) (xy 387.38556 -393.692888) (xy 386.84382 -393.692888) (xy 387.155944 -394.232892)
			(xy 387.168698 -394.256247) (xy 387.186805 -394.30628) (xy 387.196006 -394.358688) (xy 387.196584 -394.385292)
			(xy 387.196154 -394.409286) (xy 387.188648 -394.456684) (xy 387.173819 -394.502323) (xy 387.152033 -394.545081)
			(xy 387.123825 -394.583904) (xy 387.089892 -394.617836) (xy 387.051067 -394.646041) (xy 387.008308 -394.667825)
			(xy 386.962668 -394.682652) (xy 386.91527 -394.690156) (xy 386.891276 -394.6906) (xy 386.867701 -394.690226)
			(xy 386.821112 -394.68298) (xy 386.776193 -394.668651) (xy 386.734015 -394.647579) (xy 386.695582 -394.620267)
			(xy 386.661811 -394.587365) (xy 386.633506 -394.549657) (xy 386.622036 -394.529056) (xy 386.621528 -394.528294)
			(xy 386.223764 -393.839954) (xy 386.211835 -393.817292) (xy 386.194901 -393.768964) (xy 386.186248 -393.718491)
			(xy 386.185664 -393.692888) (xy 385.64367 -393.692888) (xy 385.955794 -394.232892) (xy 385.968623 -394.256222)
			(xy 385.986841 -394.306246) (xy 385.996099 -394.358673) (xy 385.996688 -394.385292) (xy 385.996253 -394.409299)
			(xy 385.988739 -394.45672) (xy 385.973895 -394.502381) (xy 385.952087 -394.545156) (xy 385.923852 -394.58399)
			(xy 385.889887 -394.617925) (xy 385.851029 -394.646126) (xy 385.808235 -394.667897) (xy 385.762561 -394.682702)
			(xy 385.715133 -394.690174) (xy 385.691126 -394.6906) (xy 385.667553 -394.690185) (xy 385.620965 -394.682948)
			(xy 385.576047 -394.668626) (xy 385.533869 -394.64756) (xy 385.495436 -394.620254) (xy 385.461663 -394.587357)
			(xy 385.433357 -394.549655) (xy 385.421886 -394.529056) (xy 385.421378 -394.528294) (xy 385.023614 -393.839954)
			(xy 385.011752 -393.81727) (xy 384.994897 -393.76894) (xy 384.986317 -393.71848) (xy 384.985768 -393.692888)
			(xy 384.443774 -393.692888) (xy 384.755898 -394.232892) (xy 384.768719 -394.256226) (xy 384.786942 -394.306248)
			(xy 384.796203 -394.358674) (xy 384.796792 -394.385292) (xy 384.796353 -394.409298) (xy 384.78884 -394.45672)
			(xy 384.773996 -394.50238) (xy 384.752188 -394.545155) (xy 384.723953 -394.583988) (xy 384.689989 -394.617924)
			(xy 384.651131 -394.646125) (xy 384.608338 -394.667896) (xy 384.562664 -394.682701) (xy 384.515237 -394.690174)
			(xy 384.49123 -394.6906) (xy 384.467657 -394.690182) (xy 384.42107 -394.682945) (xy 384.376152 -394.668624)
			(xy 384.333973 -394.647559) (xy 384.29554 -394.620253) (xy 384.261768 -394.587357) (xy 384.233461 -394.549654)
			(xy 384.22199 -394.529056) (xy 384.221482 -394.528294) (xy 383.823718 -393.839954) (xy 383.811856 -393.81727)
			(xy 383.795001 -393.76894) (xy 383.786421 -393.71848) (xy 383.785872 -393.692888) (xy 383.243878 -393.692888)
			(xy 383.556002 -394.232892) (xy 383.568824 -394.256226) (xy 383.587046 -394.306248) (xy 383.596307 -394.358674)
			(xy 383.596896 -394.385292) (xy 383.596453 -394.409298) (xy 383.58894 -394.456719) (xy 383.574096 -394.502379)
			(xy 383.552288 -394.545153) (xy 383.524055 -394.583987) (xy 383.49009 -394.617922) (xy 383.451233 -394.646123)
			(xy 383.408441 -394.667895) (xy 383.362768 -394.6827) (xy 383.315341 -394.690174) (xy 383.291334 -394.6906)
			(xy 383.267761 -394.690179) (xy 383.221174 -394.682942) (xy 383.176256 -394.668622) (xy 383.134078 -394.647557)
			(xy 383.095644 -394.620252) (xy 383.061872 -394.587356) (xy 383.033565 -394.549654) (xy 383.022094 -394.529056)
			(xy 383.021586 -394.528294) (xy 382.623822 -393.839954) (xy 382.611961 -393.81727) (xy 382.595105 -393.76894)
			(xy 382.586526 -393.71848) (xy 382.585976 -393.692888) (xy 382.043728 -393.692888) (xy 382.355852 -394.232892)
			(xy 382.368658 -394.256225) (xy 382.386803 -394.306257) (xy 382.395981 -394.358681) (xy 382.396492 -394.385292)
			(xy 382.396492 -394.395706) (xy 382.395984 -394.405866) (xy 382.402842 -394.424408) (xy 382.465326 -394.491972)
			(xy 382.483106 -394.500354) (xy 382.49352 -394.500608) (xy 382.518066 -394.502168) (xy 382.566329 -394.511642)
			(xy 382.612655 -394.52816) (xy 382.656023 -394.551359) (xy 382.695477 -394.580727) (xy 382.730144 -394.615615)
			(xy 382.759261 -394.655253) (xy 382.782184 -394.698768) (xy 382.7907 -394.721842) (xy 382.796034 -394.737082)
			(xy 382.82245 -394.755878) (xy 382.94056 -394.755878) (xy 382.965514 -394.756495) (xy 383.014463 -394.766242)
			(xy 383.06057 -394.785349) (xy 383.102064 -394.813083) (xy 383.120138 -394.8303) (xy 383.47015 -395.180312)
			(xy 383.503424 -395.184884) (xy 383.51841 -395.176756) (xy 383.54306 -395.163759) (xy 383.59564 -395.145315)
			(xy 383.65057 -395.135954) (xy 383.67843 -395.135354) (xy 383.704417 -395.135866) (xy 383.75575 -395.144)
			(xy 383.805179 -395.160063) (xy 383.851487 -395.18366) (xy 383.893534 -395.214209) (xy 383.930285 -395.25096)
			(xy 383.960836 -395.293006) (xy 383.984434 -395.339314) (xy 384.000498 -395.388742) (xy 384.008634 -395.440075)
			(xy 384.009138 -395.466062) (xy 384.008542 -395.493923) (xy 383.999172 -395.548851) (xy 383.980741 -395.601436)
			(xy 383.967736 -395.626082) (xy 383.959608 -395.641068) (xy 383.96418 -395.674342) (xy 384.4163 -396.126462)
			(xy 384.423697 -396.133313) (xy 384.442295 -396.141053) (xy 384.452368 -396.141448) (xy 392.429746 -396.141448)
			(xy 392.439811 -396.141015) (xy 392.458399 -396.133283) (xy 392.465814 -396.126462) (xy 392.611102 -395.981174)
			(xy 392.617944 -395.973774) (xy 392.625669 -395.955176) (xy 392.626088 -395.945106) (xy 392.626088 -395.12621)
			(xy 392.626654 -395.102112) (xy 392.635742 -395.05478) (xy 392.653594 -395.010011) (xy 392.67957 -394.969414)
			(xy 392.712737 -394.934444) (xy 392.732006 -394.919962) (xy 392.741424 -394.912298) (xy 392.752415 -394.890685)
			(xy 392.753088 -394.87856) (xy 392.753088 -394.756894) (xy 392.75365 -394.740317) (xy 392.762253 -394.708298)
			(xy 392.778823 -394.679581) (xy 392.790172 -394.667486) (xy 392.915902 -394.54201) (xy 392.92275 -394.534612)
			(xy 392.930488 -394.516014) (xy 392.930888 -394.505942) (xy 392.930888 -393.305284) (xy 392.93026 -393.29315)
			(xy 392.919243 -393.271536) (xy 392.909806 -393.263882) (xy 392.890552 -393.249382) (xy 392.857384 -393.214419)
			(xy 392.83141 -393.173825) (xy 392.813561 -393.12906) (xy 392.80448 -393.08173) (xy 392.803888 -393.057634)
			(xy 392.803888 -392.385042) (xy 392.803454 -392.374977) (xy 392.795723 -392.356389) (xy 392.788902 -392.348974)
			(xy 392.623294 -392.183366) (xy 392.615898 -392.176513) (xy 392.5973 -392.16877) (xy 392.587226 -392.16838)
			(xy 377.946666 -392.16838) (xy 377.936598 -392.168809) (xy 377.918001 -392.17653) (xy 377.910598 -392.183366)
			(xy 377.452636 -392.641328) (xy 377.44579 -392.648726) (xy 377.43806 -392.667325) (xy 377.43765 -392.677396)
			(xy 377.43765 -393.692888) (xy 377.785884 -393.692888) (xy 377.785884 -393.69238) (xy 377.786344 -393.668389)
			(xy 377.793853 -393.620997) (xy 377.808683 -393.575363) (xy 377.830468 -393.532611) (xy 377.858673 -393.493793)
			(xy 377.892602 -393.459865) (xy 377.931421 -393.431662) (xy 377.974174 -393.409878) (xy 378.019809 -393.39505)
			(xy 378.067201 -393.387543) (xy 378.091192 -393.387072) (xy 378.115128 -393.387505) (xy 378.162414 -393.394969)
			(xy 378.207958 -393.409716) (xy 378.250644 -393.431385) (xy 378.28943 -393.459446) (xy 378.323364 -393.493212)
			(xy 378.351618 -393.531857) (xy 378.362972 -393.552934) (xy 378.36348 -393.55395) (xy 378.443786 -393.692888)
			(xy 378.98578 -393.692888) (xy 378.98578 -393.69238) (xy 378.986244 -393.668389) (xy 378.993753 -393.620998)
			(xy 379.008582 -393.575364) (xy 379.030367 -393.532612) (xy 379.058571 -393.493795) (xy 379.092501 -393.459866)
			(xy 379.131319 -393.431663) (xy 379.174072 -393.409879) (xy 379.219705 -393.395051) (xy 379.267097 -393.387543)
			(xy 379.291088 -393.387072) (xy 379.315024 -393.387508) (xy 379.36231 -393.394972) (xy 379.407853 -393.409718)
			(xy 379.45054 -393.431387) (xy 379.489325 -393.459447) (xy 379.52326 -393.493213) (xy 379.551514 -393.531858)
			(xy 379.562868 -393.552934) (xy 379.563376 -393.55395) (xy 379.643682 -393.692888) (xy 380.185676 -393.692888)
			(xy 380.185676 -393.69238) (xy 380.186121 -393.668374) (xy 380.193638 -393.620955) (xy 380.208483 -393.575297)
			(xy 380.230292 -393.532525) (xy 380.258526 -393.493693) (xy 380.292489 -393.459758) (xy 380.331345 -393.431557)
			(xy 380.374136 -393.409785) (xy 380.419807 -393.394977) (xy 380.467232 -393.3875) (xy 380.491238 -393.387072)
			(xy 380.515172 -393.387549) (xy 380.562456 -393.395005) (xy 380.607999 -393.409744) (xy 380.650686 -393.431406)
			(xy 380.689472 -393.45946) (xy 380.723407 -393.49322) (xy 380.751663 -393.53186) (xy 380.763018 -393.552934)
			(xy 380.763526 -393.55395) (xy 381.155956 -394.232892) (xy 381.168711 -394.256246) (xy 381.186817 -394.30628)
			(xy 381.196018 -394.358688) (xy 381.196596 -394.385292) (xy 381.196154 -394.409286) (xy 381.188648 -394.456682)
			(xy 381.17382 -394.50232) (xy 381.152035 -394.545077) (xy 381.123829 -394.5839) (xy 381.089897 -394.617831)
			(xy 381.051074 -394.646037) (xy 381.008317 -394.667822) (xy 380.962678 -394.682649) (xy 380.915282 -394.690155)
			(xy 380.891288 -394.6906) (xy 380.867714 -394.690216) (xy 380.821125 -394.682973) (xy 380.776206 -394.668645)
			(xy 380.734028 -394.647575) (xy 380.695595 -394.620264) (xy 380.661823 -394.587363) (xy 380.633518 -394.549656)
			(xy 380.622048 -394.529056) (xy 380.62154 -394.528294) (xy 380.223776 -393.839954) (xy 380.21184 -393.817296)
			(xy 380.19491 -393.768965) (xy 380.186259 -393.718492) (xy 380.185676 -393.692888) (xy 379.643682 -393.692888)
			(xy 379.955806 -394.232892) (xy 379.968628 -394.256226) (xy 379.98685 -394.306248) (xy 379.996111 -394.358674)
			(xy 379.9967 -394.385292) (xy 379.996254 -394.409298) (xy 379.98874 -394.456718) (xy 379.973896 -394.502378)
			(xy 379.952089 -394.545152) (xy 379.923856 -394.583985) (xy 379.889892 -394.617921) (xy 379.851035 -394.646122)
			(xy 379.808243 -394.667894) (xy 379.762571 -394.682699) (xy 379.715144 -394.690173) (xy 379.691138 -394.6906)
			(xy 379.667565 -394.690176) (xy 379.620978 -394.68294) (xy 379.57606 -394.66862) (xy 379.533882 -394.647556)
			(xy 379.495448 -394.620251) (xy 379.461676 -394.587356) (xy 379.433369 -394.549654) (xy 379.421898 -394.529056)
			(xy 379.42139 -394.528294) (xy 379.023626 -393.839954) (xy 379.011765 -393.81727) (xy 378.994909 -393.76894)
			(xy 378.98633 -393.71848) (xy 378.98578 -393.692888) (xy 378.443786 -393.692888) (xy 378.75591 -394.232892)
			(xy 378.768732 -394.256226) (xy 378.786954 -394.306248) (xy 378.796215 -394.358673) (xy 378.796804 -394.385292)
			(xy 378.796354 -394.409298) (xy 378.78884 -394.456718) (xy 378.773997 -394.502377) (xy 378.75219 -394.545151)
			(xy 378.723957 -394.583984) (xy 378.689994 -394.61792) (xy 378.651137 -394.646121) (xy 378.608346 -394.667893)
			(xy 378.562674 -394.682698) (xy 378.515248 -394.690173) (xy 378.491242 -394.6906) (xy 378.467669 -394.690172)
			(xy 378.421083 -394.682937) (xy 378.376165 -394.668617) (xy 378.333986 -394.647554) (xy 378.295553 -394.62025)
			(xy 378.26178 -394.587355) (xy 378.233473 -394.549654) (xy 378.222002 -394.529056) (xy 378.221494 -394.528294)
			(xy 377.82373 -393.839954) (xy 377.811869 -393.81727) (xy 377.795013 -393.76894) (xy 377.786434 -393.71848)
			(xy 377.785884 -393.692888) (xy 377.43765 -393.692888) (xy 377.43765 -394.014452) (xy 377.437851 -394.021118)
			(xy 377.441335 -394.033986) (xy 377.444508 -394.039852) (xy 377.556014 -394.232892) (xy 377.568802 -394.256241)
			(xy 377.587003 -394.306264) (xy 377.596296 -394.358678) (xy 377.596908 -394.385292) (xy 377.596401 -394.410382)
			(xy 377.588196 -394.459887) (xy 377.572007 -394.507384) (xy 377.548269 -394.551594) (xy 377.517621 -394.591327)
			(xy 377.480888 -394.625514) (xy 377.460256 -394.6398) (xy 377.450194 -394.647316) (xy 377.438338 -394.669424)
			(xy 377.43765 -394.681964) (xy 377.43765 -396.043912) (xy 377.438077 -396.05398) (xy 377.4458 -396.072577)
			(xy 377.452636 -396.07998) (xy 377.756674 -396.384018) (xy 377.764073 -396.390862) (xy 377.782672 -396.398582)
			(xy 377.792742 -396.399004)
		)
		(stroke
			(width 0)
			(type solid)
		)
		(fill yes)
		(layer "In9.Cu")
		(net "P1V8_CPU0_RT3_1A")
	)
	(gr_poly
		(pts
			(xy 124.330968 -387.96214) (xy 124.341031 -387.961703) (xy 124.359612 -387.953964) (xy 124.367036 -387.947154)
			(xy 125.003814 -387.310376) (xy 125.007878 -387.27507) (xy 124.99848 -387.260084) (xy 124.986448 -387.240227)
			(xy 124.967461 -387.197857) (xy 124.954589 -387.153248) (xy 124.948084 -387.107277) (xy 124.94768 -387.084062)
			(xy 124.948192 -387.058076) (xy 124.956328 -387.006746) (xy 124.972392 -386.95732) (xy 124.995989 -386.911015)
			(xy 125.02654 -386.868971) (xy 125.06329 -386.832223) (xy 125.105337 -386.801676) (xy 125.151644 -386.778082)
			(xy 125.201071 -386.762022) (xy 125.252402 -386.75389) (xy 125.278388 -386.753354) (xy 125.301603 -386.753747)
			(xy 125.347576 -386.760249) (xy 125.392185 -386.773126) (xy 125.434551 -386.792124) (xy 125.45441 -386.804154)
			(xy 125.469396 -386.813552) (xy 125.504702 -386.809488) (xy 125.920754 -386.393436) (xy 125.929371 -386.384995)
			(xy 125.947942 -386.369599) (xy 125.957838 -386.362702) (xy 125.966325 -386.356341) (xy 125.977624 -386.338421)
			(xy 125.980722 -386.317463) (xy 125.97509 -386.297041) (xy 125.961689 -386.280633) (xy 125.952504 -386.275326)
			(xy 125.931995 -386.26437) (xy 125.894268 -386.237196) (xy 125.861103 -386.204609) (xy 125.833269 -386.167366)
			(xy 125.821948 -386.147056) (xy 125.82144 -386.146294) (xy 125.423676 -385.457954) (xy 125.411739 -385.435294)
			(xy 125.394782 -385.38697) (xy 125.386132 -385.336493) (xy 125.385576 -385.310888) (xy 125.385576 -385.31038)
			(xy 125.386025 -385.286375) (xy 125.393542 -385.238956) (xy 125.408387 -385.193299) (xy 125.430196 -385.150527)
			(xy 125.458429 -385.111696) (xy 125.492392 -385.077761) (xy 125.531247 -385.049561) (xy 125.574037 -385.027788)
			(xy 125.619708 -385.012981) (xy 125.667132 -385.005504) (xy 125.691138 -385.005072) (xy 125.715071 -385.00554)
			(xy 125.762351 -385.013008) (xy 125.807889 -385.027755) (xy 125.850571 -385.049421) (xy 125.889353 -385.077476)
			(xy 125.923288 -385.111235) (xy 125.951545 -385.14987) (xy 125.962918 -385.170934) (xy 125.963426 -385.17195)
			(xy 126.043732 -385.310888) (xy 126.58598 -385.310888) (xy 126.58598 -385.31038) (xy 126.586444 -385.286389)
			(xy 126.593953 -385.238998) (xy 126.608782 -385.193364) (xy 126.630567 -385.150612) (xy 126.658771 -385.111795)
			(xy 126.692701 -385.077866) (xy 126.731519 -385.049663) (xy 126.774272 -385.027879) (xy 126.819905 -385.013051)
			(xy 126.867297 -385.005543) (xy 126.891288 -385.005072) (xy 126.915224 -385.005508) (xy 126.96251 -385.012972)
			(xy 127.008053 -385.027718) (xy 127.05074 -385.049387) (xy 127.089525 -385.077447) (xy 127.12346 -385.111213)
			(xy 127.151714 -385.149858) (xy 127.163068 -385.170934) (xy 127.163576 -385.17195) (xy 127.243882 -385.310888)
			(xy 127.785876 -385.310888) (xy 127.785876 -385.31038) (xy 127.786344 -385.286389) (xy 127.793853 -385.238998)
			(xy 127.808682 -385.193365) (xy 127.830467 -385.150614) (xy 127.85867 -385.111796) (xy 127.892599 -385.077868)
			(xy 127.931417 -385.049664) (xy 127.974169 -385.02788) (xy 128.019802 -385.013052) (xy 128.067193 -385.005544)
			(xy 128.091184 -385.005072) (xy 128.11512 -385.005511) (xy 128.162406 -385.012974) (xy 128.207949 -385.02772)
			(xy 128.250636 -385.049388) (xy 128.289421 -385.077448) (xy 128.323356 -385.111214) (xy 128.35161 -385.149858)
			(xy 128.362964 -385.170934) (xy 128.363472 -385.17195) (xy 128.443778 -385.310888) (xy 128.985772 -385.310888)
			(xy 128.985772 -385.31038) (xy 128.986244 -385.286389) (xy 128.993753 -385.238999) (xy 129.008581 -385.193366)
			(xy 129.030366 -385.150615) (xy 129.058569 -385.111797) (xy 129.092497 -385.077869) (xy 129.131315 -385.049666)
			(xy 129.174066 -385.027881) (xy 129.219699 -385.013053) (xy 129.267089 -385.005544) (xy 129.29108 -385.005072)
			(xy 129.315016 -385.005515) (xy 129.362301 -385.012977) (xy 129.407845 -385.027722) (xy 129.450531 -385.04939)
			(xy 129.489317 -385.077449) (xy 129.523252 -385.111214) (xy 129.551506 -385.149858) (xy 129.56286 -385.170934)
			(xy 129.563368 -385.17195) (xy 129.643674 -385.310888) (xy 130.185668 -385.310888) (xy 130.185668 -385.31038)
			(xy 130.186121 -385.286375) (xy 130.193637 -385.238957) (xy 130.208483 -385.193299) (xy 130.230291 -385.150527)
			(xy 130.258524 -385.111696) (xy 130.292486 -385.077761) (xy 130.331341 -385.04956) (xy 130.37413 -385.027787)
			(xy 130.4198 -385.012979) (xy 130.467224 -385.005501) (xy 130.49123 -385.005072) (xy 130.515164 -385.005555)
			(xy 130.562448 -385.01301) (xy 130.60799 -385.027748) (xy 130.650677 -385.049409) (xy 130.689463 -385.077462)
			(xy 130.723399 -385.111221) (xy 130.751655 -385.14986) (xy 130.76301 -385.170934) (xy 130.763518 -385.17195)
			(xy 130.843824 -385.310888) (xy 131.385564 -385.310888) (xy 131.385564 -385.31038) (xy 131.386021 -385.286375)
			(xy 131.393537 -385.238957) (xy 131.408382 -385.1933) (xy 131.43019 -385.150528) (xy 131.458422 -385.111697)
			(xy 131.492384 -385.077762) (xy 131.531239 -385.049561) (xy 131.574027 -385.027788) (xy 131.619697 -385.01298)
			(xy 131.667121 -385.005501) (xy 131.691126 -385.005072) (xy 131.71506 -385.005558) (xy 131.762344 -385.013013)
			(xy 131.807886 -385.02775) (xy 131.850573 -385.04941) (xy 131.889359 -385.077463) (xy 131.923295 -385.111222)
			(xy 131.951551 -385.14986) (xy 131.962906 -385.170934) (xy 131.963414 -385.17195) (xy 132.04372 -385.310888)
			(xy 132.585968 -385.310888) (xy 132.585968 -385.31038) (xy 132.586444 -385.286389) (xy 132.593952 -385.238999)
			(xy 132.608781 -385.193367) (xy 132.630565 -385.150616) (xy 132.658768 -385.111799) (xy 132.692696 -385.077871)
			(xy 132.731513 -385.049667) (xy 132.774263 -385.027883) (xy 132.819895 -385.013053) (xy 132.867285 -385.005544)
			(xy 132.891276 -385.005072) (xy 132.915211 -385.005518) (xy 132.962497 -385.01298) (xy 133.00804 -385.027724)
			(xy 133.050727 -385.049391) (xy 133.089512 -385.07745) (xy 133.123447 -385.111215) (xy 133.151701 -385.149858)
			(xy 133.163056 -385.170934) (xy 133.163564 -385.17195) (xy 133.555994 -385.850892) (xy 133.568823 -385.874222)
			(xy 133.587041 -385.924246) (xy 133.596299 -385.976673) (xy 133.596888 -386.003292) (xy 133.596453 -386.027299)
			(xy 133.588939 -386.07472) (xy 133.574095 -386.120381) (xy 133.552287 -386.163156) (xy 133.524052 -386.20199)
			(xy 133.490087 -386.235925) (xy 133.451229 -386.264126) (xy 133.408435 -386.285897) (xy 133.362761 -386.300702)
			(xy 133.315333 -386.308174) (xy 133.291326 -386.3086) (xy 133.267753 -386.308185) (xy 133.221165 -386.300948)
			(xy 133.176247 -386.286626) (xy 133.134069 -386.26556) (xy 133.095636 -386.238254) (xy 133.061863 -386.205357)
			(xy 133.033557 -386.167655) (xy 133.022086 -386.147056) (xy 133.021578 -386.146294) (xy 132.623814 -385.457954)
			(xy 132.611952 -385.43527) (xy 132.595097 -385.38694) (xy 132.586517 -385.33648) (xy 132.585968 -385.310888)
			(xy 132.04372 -385.310888) (xy 132.355844 -385.850892) (xy 132.368598 -385.874247) (xy 132.386705 -385.92428)
			(xy 132.395906 -385.976688) (xy 132.396484 -386.003292) (xy 132.396054 -386.027286) (xy 132.388548 -386.074684)
			(xy 132.373719 -386.120323) (xy 132.351933 -386.163081) (xy 132.323725 -386.201904) (xy 132.289792 -386.235836)
			(xy 132.250967 -386.264041) (xy 132.208208 -386.285825) (xy 132.162568 -386.300652) (xy 132.11517 -386.308156)
			(xy 132.091176 -386.3086) (xy 132.067601 -386.308226) (xy 132.021012 -386.30098) (xy 131.976093 -386.286651)
			(xy 131.933915 -386.265579) (xy 131.895482 -386.238267) (xy 131.861711 -386.205365) (xy 131.833406 -386.167657)
			(xy 131.821936 -386.147056) (xy 131.821428 -386.146294) (xy 131.423664 -385.457954) (xy 131.411735 -385.435292)
			(xy 131.394801 -385.386964) (xy 131.386148 -385.336491) (xy 131.385564 -385.310888) (xy 130.843824 -385.310888)
			(xy 131.155948 -385.850892) (xy 131.168702 -385.874247) (xy 131.186809 -385.92428) (xy 131.19601 -385.976688)
			(xy 131.196588 -386.003292) (xy 131.196154 -386.027286) (xy 131.188648 -386.074683) (xy 131.17382 -386.120322)
			(xy 131.152033 -386.16308) (xy 131.123826 -386.201902) (xy 131.089893 -386.235834) (xy 131.05107 -386.26404)
			(xy 131.008311 -386.285824) (xy 130.962671 -386.300651) (xy 130.915274 -386.308155) (xy 130.89128 -386.3086)
			(xy 130.867705 -386.308222) (xy 130.821116 -386.300978) (xy 130.776197 -386.286649) (xy 130.734019 -386.265578)
			(xy 130.695586 -386.238266) (xy 130.661815 -386.205364) (xy 130.63351 -386.167657) (xy 130.62204 -386.147056)
			(xy 130.621532 -386.146294) (xy 130.223768 -385.457954) (xy 130.211839 -385.435292) (xy 130.194906 -385.386964)
			(xy 130.186252 -385.336491) (xy 130.185668 -385.310888) (xy 129.643674 -385.310888) (xy 129.955798 -385.850892)
			(xy 129.968619 -385.874226) (xy 129.986842 -385.924248) (xy 129.996103 -385.976674) (xy 129.996692 -386.003292)
			(xy 129.996253 -386.027298) (xy 129.98874 -386.07472) (xy 129.973896 -386.12038) (xy 129.952088 -386.163155)
			(xy 129.923853 -386.201988) (xy 129.889889 -386.235924) (xy 129.851031 -386.264125) (xy 129.808238 -386.285896)
			(xy 129.762564 -386.300701) (xy 129.715137 -386.308174) (xy 129.69113 -386.3086) (xy 129.667557 -386.308182)
			(xy 129.62097 -386.300945) (xy 129.576052 -386.286624) (xy 129.533873 -386.265559) (xy 129.49544 -386.238253)
			(xy 129.461668 -386.205357) (xy 129.433361 -386.167654) (xy 129.42189 -386.147056) (xy 129.421382 -386.146294)
			(xy 129.023618 -385.457954) (xy 129.011756 -385.43527) (xy 128.994901 -385.38694) (xy 128.986321 -385.33648)
			(xy 128.985772 -385.310888) (xy 128.443778 -385.310888) (xy 128.755902 -385.850892) (xy 128.768724 -385.874226)
			(xy 128.786946 -385.924248) (xy 128.796207 -385.976674) (xy 128.796796 -386.003292) (xy 128.796353 -386.027298)
			(xy 128.78884 -386.074719) (xy 128.773996 -386.120379) (xy 128.752188 -386.163153) (xy 128.723955 -386.201987)
			(xy 128.68999 -386.235922) (xy 128.651133 -386.264123) (xy 128.608341 -386.285895) (xy 128.562668 -386.3007)
			(xy 128.515241 -386.308174) (xy 128.491234 -386.3086) (xy 128.467661 -386.308179) (xy 128.421074 -386.300942)
			(xy 128.376156 -386.286622) (xy 128.333978 -386.265557) (xy 128.295544 -386.238252) (xy 128.261772 -386.205356)
			(xy 128.233465 -386.167654) (xy 128.221994 -386.147056) (xy 128.221486 -386.146294) (xy 127.823722 -385.457954)
			(xy 127.811861 -385.43527) (xy 127.795005 -385.38694) (xy 127.786426 -385.33648) (xy 127.785876 -385.310888)
			(xy 127.243882 -385.310888) (xy 127.556006 -385.850892) (xy 127.568828 -385.874226) (xy 127.58705 -385.924248)
			(xy 127.596311 -385.976674) (xy 127.5969 -386.003292) (xy 127.596454 -386.027298) (xy 127.58894 -386.074718)
			(xy 127.574096 -386.120378) (xy 127.552289 -386.163152) (xy 127.524056 -386.201985) (xy 127.490092 -386.235921)
			(xy 127.451235 -386.264122) (xy 127.408443 -386.285894) (xy 127.362771 -386.300699) (xy 127.315344 -386.308173)
			(xy 127.291338 -386.3086) (xy 127.267765 -386.308176) (xy 127.221178 -386.30094) (xy 127.17626 -386.28662)
			(xy 127.134082 -386.265556) (xy 127.095648 -386.238251) (xy 127.061876 -386.205356) (xy 127.033569 -386.167654)
			(xy 127.022098 -386.147056) (xy 127.02159 -386.146294) (xy 126.623826 -385.457954) (xy 126.611965 -385.43527)
			(xy 126.595109 -385.38694) (xy 126.58653 -385.33648) (xy 126.58598 -385.310888) (xy 126.043732 -385.310888)
			(xy 126.355856 -385.850892) (xy 126.368662 -385.874225) (xy 126.386807 -385.924257) (xy 126.395984 -385.976681)
			(xy 126.396496 -386.003292) (xy 126.396496 -386.013706) (xy 126.395988 -386.023866) (xy 126.402846 -386.042408)
			(xy 126.46533 -386.109972) (xy 126.48311 -386.118354) (xy 126.493524 -386.118608) (xy 126.517857 -386.120164)
			(xy 126.565707 -386.129532) (xy 126.611663 -386.145821) (xy 126.654731 -386.168679) (xy 126.693978 -386.197611)
			(xy 126.728554 -386.231989) (xy 126.757709 -386.27107) (xy 126.769622 -386.292344) (xy 126.77648 -386.30479)
			(xy 126.800356 -386.319014) (xy 126.916434 -386.319014) (xy 126.941389 -386.319629) (xy 126.990339 -386.329372)
			(xy 127.036448 -386.348478) (xy 127.077943 -386.376213) (xy 127.096012 -386.393436) (xy 127.489712 -386.787136)
			(xy 127.521208 -386.792724) (xy 127.53594 -386.785612) (xy 127.558303 -386.77544) (xy 127.605283 -386.761074)
			(xy 127.65387 -386.753806) (xy 127.678434 -386.753354) (xy 127.704421 -386.753866) (xy 127.755753 -386.762001)
			(xy 127.805182 -386.778064) (xy 127.851489 -386.801661) (xy 127.893536 -386.832211) (xy 127.930287 -386.868961)
			(xy 127.960837 -386.911007) (xy 127.984434 -386.957315) (xy 128.000498 -387.006743) (xy 128.008634 -387.058075)
			(xy 128.009142 -387.084062) (xy 128.008696 -387.108627) (xy 128.001434 -387.157216) (xy 127.987065 -387.204196)
			(xy 127.976884 -387.226556) (xy 127.969772 -387.241288) (xy 127.97536 -387.272784) (xy 128.392174 -387.689598)
			(xy 128.399577 -387.696433) (xy 128.418175 -387.704141) (xy 128.428242 -387.704584) (xy 136.40562 -387.704584)
			(xy 136.415688 -387.704157) (xy 136.434286 -387.696436) (xy 136.441688 -387.689598) (xy 136.586976 -387.54431)
			(xy 136.593826 -387.536913) (xy 136.601568 -387.518315) (xy 136.601962 -387.508242) (xy 136.601962 -386.689346)
			(xy 136.602534 -386.665252) (xy 136.611634 -386.617929) (xy 136.629498 -386.573173) (xy 136.655483 -386.532591)
			(xy 136.688657 -386.497638) (xy 136.70788 -386.483098) (xy 136.717308 -386.475439) (xy 136.72832 -386.453826)
			(xy 136.728962 -386.441696) (xy 136.728962 -386.32003) (xy 136.729533 -386.303458) (xy 136.738153 -386.271451)
			(xy 136.754739 -386.242753) (xy 136.766046 -386.230622) (xy 136.891776 -386.105146) (xy 136.898616 -386.097746)
			(xy 136.906335 -386.079147) (xy 136.906762 -386.069078) (xy 136.906762 -384.86842) (xy 136.906141 -384.856283)
			(xy 136.895129 -384.83466) (xy 136.88568 -384.827018) (xy 136.866425 -384.812518) (xy 136.833256 -384.777555)
			(xy 136.807278 -384.736962) (xy 136.789426 -384.692196) (xy 136.780339 -384.644867) (xy 136.779762 -384.62077)
			(xy 136.779762 -383.948178) (xy 136.779334 -383.93811) (xy 136.77161 -383.919515) (xy 136.764776 -383.91211)
			(xy 136.599168 -383.746502) (xy 136.591768 -383.73966) (xy 136.57317 -383.731937) (xy 136.5631 -383.731516)
			(xy 121.92254 -383.731516) (xy 121.912475 -383.731951) (xy 121.893888 -383.739682) (xy 121.886472 -383.746502)
			(xy 121.42851 -384.204464) (xy 121.421673 -384.211866) (xy 121.41396 -384.230464) (xy 121.413524 -384.240532)
			(xy 121.413524 -385.310888) (xy 121.785888 -385.310888) (xy 121.785888 -385.31038) (xy 121.786344 -385.286388)
			(xy 121.793853 -385.238996) (xy 121.808683 -385.193362) (xy 121.830469 -385.15061) (xy 121.858674 -385.111792)
			(xy 121.892604 -385.077863) (xy 121.931424 -385.04966) (xy 121.974177 -385.027877) (xy 122.019812 -385.013049)
			(xy 122.067204 -385.005543) (xy 122.091196 -385.005072) (xy 122.115132 -385.005502) (xy 122.162418 -385.012966)
			(xy 122.207962 -385.027714) (xy 122.250649 -385.049384) (xy 122.289434 -385.077445) (xy 122.323368 -385.111212)
			(xy 122.351622 -385.149857) (xy 122.362976 -385.170934) (xy 122.363484 -385.17195) (xy 122.44379 -385.310888)
			(xy 122.985784 -385.310888) (xy 122.985784 -385.31038) (xy 122.986244 -385.286389) (xy 122.993753 -385.238997)
			(xy 123.008583 -385.193363) (xy 123.030368 -385.150611) (xy 123.058573 -385.111793) (xy 123.092502 -385.077865)
			(xy 123.131321 -385.049662) (xy 123.174074 -385.027878) (xy 123.219709 -385.01305) (xy 123.267101 -385.005543)
			(xy 123.291092 -385.005072) (xy 123.315028 -385.005505) (xy 123.362314 -385.012969) (xy 123.407858 -385.027716)
			(xy 123.450544 -385.049385) (xy 123.48933 -385.077446) (xy 123.523264 -385.111212) (xy 123.551518 -385.149857)
			(xy 123.562872 -385.170934) (xy 123.56338 -385.17195) (xy 123.643686 -385.310888) (xy 124.18568 -385.310888)
			(xy 124.18568 -385.31038) (xy 124.186121 -385.286374) (xy 124.193638 -385.238955) (xy 124.208484 -385.193296)
			(xy 124.230293 -385.150524) (xy 124.258527 -385.111692) (xy 124.292491 -385.077757) (xy 124.331347 -385.049556)
			(xy 124.374139 -385.027783) (xy 124.41981 -385.012977) (xy 124.467236 -385.0055) (xy 124.491242 -385.005072)
			(xy 124.515176 -385.005545) (xy 124.562461 -385.013002) (xy 124.608003 -385.027742) (xy 124.65069 -385.049404)
			(xy 124.689476 -385.077459) (xy 124.723412 -385.11122) (xy 124.751667 -385.14986) (xy 124.763022 -385.170934)
			(xy 124.76353 -385.17195) (xy 125.15596 -385.850892) (xy 125.168715 -385.874246) (xy 125.186821 -385.92428)
			(xy 125.196022 -385.976688) (xy 125.1966 -386.003292) (xy 125.196154 -386.027285) (xy 125.188649 -386.074681)
			(xy 125.173821 -386.12032) (xy 125.152036 -386.163076) (xy 125.12383 -386.201898) (xy 125.089898 -386.23583)
			(xy 125.051076 -386.264036) (xy 125.00832 -386.285821) (xy 124.962681 -386.300649) (xy 124.915285 -386.308154)
			(xy 124.891292 -386.3086) (xy 124.867718 -386.308213) (xy 124.821129 -386.30097) (xy 124.77621 -386.286643)
			(xy 124.734032 -386.265573) (xy 124.695599 -386.238263) (xy 124.661828 -386.205362) (xy 124.633522 -386.167656)
			(xy 124.622052 -386.147056) (xy 124.621544 -386.146294) (xy 124.22378 -385.457954) (xy 124.211844 -385.435296)
			(xy 124.194915 -385.386965) (xy 124.186263 -385.336492) (xy 124.18568 -385.310888) (xy 123.643686 -385.310888)
			(xy 123.95581 -385.850892) (xy 123.968632 -385.874226) (xy 123.986854 -385.924248) (xy 123.996115 -385.976673)
			(xy 123.996704 -386.003292) (xy 123.996254 -386.027298) (xy 123.98874 -386.074718) (xy 123.973897 -386.120377)
			(xy 123.95209 -386.163151) (xy 123.923857 -386.201984) (xy 123.889894 -386.23592) (xy 123.851037 -386.264121)
			(xy 123.808246 -386.285893) (xy 123.762574 -386.300698) (xy 123.715148 -386.308173) (xy 123.691142 -386.3086)
			(xy 123.667569 -386.308172) (xy 123.620983 -386.300937) (xy 123.576065 -386.286617) (xy 123.533886 -386.265554)
			(xy 123.495453 -386.23825) (xy 123.46168 -386.205355) (xy 123.433373 -386.167654) (xy 123.421902 -386.147056)
			(xy 123.421394 -386.146294) (xy 123.02363 -385.457954) (xy 123.011769 -385.43527) (xy 122.994913 -385.38694)
			(xy 122.986334 -385.33648) (xy 122.985784 -385.310888) (xy 122.44379 -385.310888) (xy 122.755914 -385.850892)
			(xy 122.768737 -385.874226) (xy 122.786958 -385.924248) (xy 122.796219 -385.976673) (xy 122.796808 -386.003292)
			(xy 122.796354 -386.027298) (xy 122.78884 -386.074717) (xy 122.773997 -386.120377) (xy 122.752191 -386.16315)
			(xy 122.723958 -386.201983) (xy 122.689995 -386.235918) (xy 122.65114 -386.264119) (xy 122.608349 -386.285891)
			(xy 122.562678 -386.300698) (xy 122.515252 -386.308173) (xy 122.491246 -386.3086) (xy 122.467673 -386.308169)
			(xy 122.421087 -386.300935) (xy 122.376169 -386.286615) (xy 122.333991 -386.265553) (xy 122.295557 -386.238249)
			(xy 122.261784 -386.205355) (xy 122.233477 -386.167654) (xy 122.222006 -386.147056) (xy 122.221498 -386.146294)
			(xy 121.823734 -385.457954) (xy 121.811874 -385.43527) (xy 121.795018 -385.38694) (xy 121.786438 -385.33648)
			(xy 121.785888 -385.310888) (xy 121.413524 -385.310888) (xy 121.413524 -385.590542) (xy 121.413723 -385.597208)
			(xy 121.417203 -385.610079) (xy 121.420382 -385.615942) (xy 121.556018 -385.850892) (xy 121.568806 -385.874241)
			(xy 121.587007 -385.924264) (xy 121.5963 -385.976678) (xy 121.596912 -386.003292) (xy 121.596478 -386.026514)
			(xy 121.589443 -386.072421) (xy 121.575534 -386.116733) (xy 121.555072 -386.158425) (xy 121.528529 -386.196537)
			(xy 121.496519 -386.230187) (xy 121.459781 -386.258599) (xy 121.439686 -386.270246) (xy 121.427494 -386.277104)
			(xy 121.413524 -386.300726) (xy 121.413524 -387.607048) (xy 121.413956 -387.617114) (xy 121.421686 -387.635703)
			(xy 121.42851 -387.643116) (xy 121.732548 -387.947154) (xy 121.739947 -387.953998) (xy 121.758546 -387.961722)
			(xy 121.768616 -387.96214)
		)
		(stroke
			(width 0)
			(type solid)
		)
		(fill yes)
		(layer "In9.Cu")
		(net "P1V8_CPU1_RT3_1A")
	)
	(gr_poly
		(pts
			(xy 344.367612 -396.415514) (xy 344.386879 -396.410732) (xy 344.426248 -396.405633) (xy 344.446098 -396.405354)
			(xy 344.465946 -396.405659) (xy 344.505312 -396.410758) (xy 344.524584 -396.415514) (xy 344.530934 -396.417292)
			(xy 345.561158 -396.417292) (xy 345.567508 -396.415514) (xy 345.586775 -396.410732) (xy 345.626144 -396.405632)
			(xy 345.645994 -396.405354) (xy 345.665842 -396.405659) (xy 345.705208 -396.410757) (xy 345.72448 -396.415514)
			(xy 345.73083 -396.417292) (xy 345.928442 -396.417292) (xy 345.938509 -396.416861) (xy 345.957101 -396.409135)
			(xy 345.96451 -396.402306) (xy 347.571822 -394.794994) (xy 347.579188 -394.781278) (xy 347.580458 -394.773404)
			(xy 347.584776 -394.753084) (xy 347.53296 -394.690346) (xy 347.518736 -394.6906) (xy 347.495167 -394.690157)
			(xy 347.448591 -394.6829) (xy 347.403685 -394.668568) (xy 347.361516 -394.647501) (xy 347.323087 -394.620202)
			(xy 347.289313 -394.587319) (xy 347.260997 -394.549634) (xy 347.249496 -394.529056) (xy 347.248988 -394.528294)
			(xy 346.851224 -393.839954) (xy 346.839289 -393.817294) (xy 346.822334 -393.76897) (xy 346.813686 -393.718493)
			(xy 346.813124 -393.692888) (xy 346.813124 -393.69238) (xy 346.813573 -393.668376) (xy 346.82109 -393.62096)
			(xy 346.835936 -393.575306) (xy 346.857745 -393.532538) (xy 346.88598 -393.49371) (xy 346.919943 -393.459781)
			(xy 346.958799 -393.431585) (xy 347.001589 -393.409819) (xy 347.047258 -393.395019) (xy 347.094682 -393.387549)
			(xy 347.118686 -393.387072) (xy 347.142621 -393.387536) (xy 347.189906 -393.394997) (xy 347.23545 -393.409739)
			(xy 347.278138 -393.431401) (xy 347.316927 -393.459455) (xy 347.350868 -393.493212) (xy 347.379131 -393.531849)
			(xy 347.390466 -393.552934) (xy 347.390974 -393.55395) (xy 347.783404 -394.232892) (xy 347.796208 -394.256225)
			(xy 347.81435 -394.306258) (xy 347.823526 -394.358681) (xy 347.824044 -394.385292) (xy 347.824044 -394.395706)
			(xy 347.823536 -394.405866) (xy 347.830394 -394.424408) (xy 347.892878 -394.491972) (xy 347.910658 -394.500354)
			(xy 347.921072 -394.500608) (xy 347.946518 -394.502227) (xy 347.996495 -394.512315) (xy 348.044331 -394.529958)
			(xy 348.08889 -394.554738) (xy 348.129115 -394.586066) (xy 348.164053 -394.6232) (xy 348.192874 -394.665258)
			(xy 348.204282 -394.68806) (xy 348.210632 -394.701268) (xy 348.23527 -394.716762) (xy 348.44482 -394.716762)
			(xy 348.458192 -394.716942) (xy 348.484789 -394.719743) (xy 348.497906 -394.72235) (xy 348.50771 -394.723998)
			(xy 348.527265 -394.720531) (xy 348.544038 -394.709898) (xy 348.555517 -394.693691) (xy 348.559981 -394.674339)
			(xy 348.556762 -394.654742) (xy 348.546342 -394.637835) (xy 348.538546 -394.631672) (xy 348.520364 -394.617854)
			(xy 348.48796 -394.585679) (xy 348.460721 -394.549027) (xy 348.449646 -394.529056) (xy 348.449138 -394.528294)
			(xy 348.051374 -393.839954) (xy 348.039479 -393.817285) (xy 348.022611 -393.768954) (xy 348.014058 -393.718483)
			(xy 348.013528 -393.692888) (xy 348.013528 -393.69238) (xy 348.013976 -393.668389) (xy 348.021485 -393.620998)
			(xy 348.036316 -393.575365) (xy 348.058103 -393.532615) (xy 348.08631 -393.493799) (xy 348.120241 -393.459873)
			(xy 348.159062 -393.431674) (xy 348.201817 -393.409894) (xy 348.247452 -393.395072) (xy 348.294845 -393.387571)
			(xy 348.318836 -393.387072) (xy 348.342769 -393.387539) (xy 348.390049 -393.395007) (xy 348.435587 -393.409754)
			(xy 348.478269 -393.43142) (xy 348.517052 -393.459476) (xy 348.550987 -393.493234) (xy 348.579244 -393.53187)
			(xy 348.590616 -393.552934) (xy 348.591124 -393.55395) (xy 348.67143 -393.692888) (xy 349.213424 -393.692888)
			(xy 349.213424 -393.69238) (xy 349.21382 -393.668385) (xy 349.221331 -393.620985) (xy 349.236164 -393.575345)
			(xy 349.257954 -393.532586) (xy 349.286166 -393.493764) (xy 349.320103 -393.459832) (xy 349.358931 -393.431627)
			(xy 349.401693 -393.409844) (xy 349.447336 -393.395018) (xy 349.494737 -393.387516) (xy 349.518732 -393.387072)
			(xy 349.542666 -393.387554) (xy 349.58995 -393.395009) (xy 349.635493 -393.409747) (xy 349.678179 -393.431408)
			(xy 349.716965 -393.459462) (xy 349.750901 -393.493221) (xy 349.779157 -393.53186) (xy 349.790512 -393.552934)
			(xy 349.79102 -393.55395) (xy 349.871326 -393.692888) (xy 350.41332 -393.692888) (xy 350.41332 -393.69238)
			(xy 350.41372 -393.668385) (xy 350.42123 -393.620986) (xy 350.436063 -393.575346) (xy 350.457854 -393.532588)
			(xy 350.486065 -393.493765) (xy 350.520001 -393.459833) (xy 350.558829 -393.431629) (xy 350.60159 -393.409845)
			(xy 350.647233 -393.395019) (xy 350.694633 -393.387516) (xy 350.718628 -393.387072) (xy 350.718882 -393.387072)
			(xy 350.742818 -393.387513) (xy 350.790103 -393.394976) (xy 350.835647 -393.409721) (xy 350.878334 -393.431389)
			(xy 350.917119 -393.459449) (xy 350.951054 -393.493214) (xy 350.979308 -393.531858) (xy 350.990662 -393.552934)
			(xy 350.99117 -393.55395) (xy 351.071476 -393.692888) (xy 351.613216 -393.692888) (xy 351.613216 -393.69238)
			(xy 351.613621 -393.668372) (xy 351.621139 -393.620949) (xy 351.635987 -393.575288) (xy 351.657799 -393.532513)
			(xy 351.686038 -393.493679) (xy 351.720006 -393.459744) (xy 351.758867 -393.431543) (xy 351.801664 -393.409773)
			(xy 351.84734 -393.394969) (xy 351.89477 -393.387497) (xy 351.918778 -393.387072) (xy 351.942713 -393.387516)
			(xy 351.989999 -393.394978) (xy 352.035543 -393.409723) (xy 352.078229 -393.431391) (xy 352.117015 -393.45945)
			(xy 352.150949 -393.493214) (xy 352.179204 -393.531858) (xy 352.190558 -393.552934) (xy 352.191066 -393.55395)
			(xy 352.271372 -393.692888) (xy 352.813112 -393.692888) (xy 352.813112 -393.69238) (xy 352.813521 -393.668373)
			(xy 352.821039 -393.62095) (xy 352.835887 -393.575289) (xy 352.857699 -393.532514) (xy 352.885937 -393.493681)
			(xy 352.919904 -393.459745) (xy 352.958765 -393.431545) (xy 353.001561 -393.409774) (xy 353.047236 -393.39497)
			(xy 353.094666 -393.387498) (xy 353.118674 -393.387072) (xy 353.118928 -393.387072) (xy 353.142862 -393.387557)
			(xy 353.190146 -393.395011) (xy 353.235688 -393.409749) (xy 353.278375 -393.43141) (xy 353.317161 -393.459463)
			(xy 353.351097 -393.493222) (xy 353.379353 -393.53186) (xy 353.390708 -393.552934) (xy 353.391216 -393.55395)
			(xy 353.471522 -393.692888) (xy 354.013516 -393.692888) (xy 354.013516 -393.69238) (xy 354.01392 -393.668385)
			(xy 354.02143 -393.620987) (xy 354.036263 -393.575347) (xy 354.058053 -393.532589) (xy 354.086263 -393.493766)
			(xy 354.1202 -393.459835) (xy 354.159026 -393.43163) (xy 354.201787 -393.409846) (xy 354.247429 -393.39502)
			(xy 354.294829 -393.387516) (xy 354.318824 -393.387072) (xy 354.342758 -393.38756) (xy 354.390042 -393.395014)
			(xy 354.435584 -393.409751) (xy 354.478271 -393.431411) (xy 354.517057 -393.459464) (xy 354.550993 -393.493222)
			(xy 354.579249 -393.53186) (xy 354.590604 -393.552934) (xy 354.591112 -393.55395) (xy 354.983542 -394.232892)
			(xy 354.996367 -394.256224) (xy 355.014587 -394.306247) (xy 355.023847 -394.358673) (xy 355.024436 -394.385292)
			(xy 355.023954 -394.409296) (xy 355.016441 -394.456713) (xy 355.0016 -394.50237) (xy 354.979796 -394.545141)
			(xy 354.951566 -394.583973) (xy 354.917607 -394.617908) (xy 354.878755 -394.64611) (xy 354.835968 -394.667883)
			(xy 354.790301 -394.682692) (xy 354.742879 -394.690171) (xy 354.718874 -394.6906) (xy 354.695299 -394.690227)
			(xy 354.64871 -394.682982) (xy 354.603791 -394.668652) (xy 354.561613 -394.64758) (xy 354.52318 -394.620267)
			(xy 354.489409 -394.587365) (xy 354.461104 -394.549657) (xy 354.449634 -394.529056) (xy 354.449126 -394.528294)
			(xy 354.051362 -393.839954) (xy 354.039504 -393.817268) (xy 354.022646 -393.76894) (xy 354.014066 -393.71848)
			(xy 354.013516 -393.692888) (xy 353.471522 -393.692888) (xy 353.783646 -394.232892) (xy 353.796471 -394.256224)
			(xy 353.814691 -394.306247) (xy 353.823951 -394.358673) (xy 353.82454 -394.385292) (xy 353.824054 -394.409296)
			(xy 353.816541 -394.456713) (xy 353.8017 -394.502369) (xy 353.779896 -394.54514) (xy 353.751667 -394.583972)
			(xy 353.717709 -394.617907) (xy 353.678857 -394.646108) (xy 353.636071 -394.667882) (xy 353.590404 -394.682691)
			(xy 353.542982 -394.69017) (xy 353.518978 -394.6906) (xy 353.518724 -394.6906) (xy 353.495151 -394.690187)
			(xy 353.448563 -394.682949) (xy 353.403645 -394.668627) (xy 353.361467 -394.647561) (xy 353.323033 -394.620255)
			(xy 353.289261 -394.587358) (xy 353.260955 -394.549655) (xy 353.249484 -394.529056) (xy 353.248976 -394.528294)
			(xy 352.851212 -393.839954) (xy 352.839279 -393.817295) (xy 352.822347 -393.768965) (xy 352.813695 -393.718491)
			(xy 352.813112 -393.692888) (xy 352.271372 -393.692888) (xy 352.583496 -394.232892) (xy 352.596246 -394.256249)
			(xy 352.614355 -394.306281) (xy 352.623558 -394.358688) (xy 352.624136 -394.385292) (xy 352.62363 -394.409282)
			(xy 352.616126 -394.45667) (xy 352.601301 -394.502302) (xy 352.579521 -394.545053) (xy 352.551322 -394.58387)
			(xy 352.517397 -394.617798) (xy 352.478583 -394.646002) (xy 352.435835 -394.667788) (xy 352.390205 -394.682618)
			(xy 352.342818 -394.690127) (xy 352.318828 -394.6906) (xy 352.295255 -394.690184) (xy 352.248668 -394.682946)
			(xy 352.20375 -394.668625) (xy 352.161571 -394.64756) (xy 352.123138 -394.620254) (xy 352.089365 -394.587357)
			(xy 352.061059 -394.549654) (xy 352.049588 -394.529056) (xy 352.04908 -394.528294) (xy 351.651316 -393.839954)
			(xy 351.639383 -393.817294) (xy 351.622452 -393.768965) (xy 351.613799 -393.718491) (xy 351.613216 -393.692888)
			(xy 351.071476 -393.692888) (xy 351.3836 -394.232892) (xy 351.39635 -394.256249) (xy 351.41446 -394.306281)
			(xy 351.423662 -394.358688) (xy 351.42424 -394.385292) (xy 351.42373 -394.409281) (xy 351.416226 -394.45667)
			(xy 351.401402 -394.502301) (xy 351.379622 -394.545051) (xy 351.351423 -394.583869) (xy 351.317499 -394.617797)
			(xy 351.278686 -394.646001) (xy 351.235938 -394.667787) (xy 351.190309 -394.682617) (xy 351.142921 -394.690127)
			(xy 351.118932 -394.6906) (xy 351.118678 -394.6906) (xy 351.095103 -394.690224) (xy 351.048514 -394.682979)
			(xy 351.003595 -394.66865) (xy 350.961417 -394.647579) (xy 350.922984 -394.620266) (xy 350.889213 -394.587364)
			(xy 350.860908 -394.549657) (xy 350.849438 -394.529056) (xy 350.84893 -394.528294) (xy 350.451166 -393.839954)
			(xy 350.439308 -393.817268) (xy 350.42245 -393.76894) (xy 350.41387 -393.71848) (xy 350.41332 -393.692888)
			(xy 349.871326 -393.692888) (xy 350.18345 -394.232892) (xy 350.196276 -394.256224) (xy 350.214495 -394.306247)
			(xy 350.223755 -394.358673) (xy 350.224344 -394.385292) (xy 350.223854 -394.409296) (xy 350.216341 -394.456712)
			(xy 350.201501 -394.502368) (xy 350.179697 -394.545139) (xy 350.151469 -394.58397) (xy 350.11751 -394.617905)
			(xy 350.07866 -394.646107) (xy 350.035874 -394.667881) (xy 349.990207 -394.68269) (xy 349.942786 -394.69017)
			(xy 349.918782 -394.6906) (xy 349.895207 -394.690221) (xy 349.848619 -394.682977) (xy 349.8037 -394.668648)
			(xy 349.761521 -394.647577) (xy 349.723088 -394.620265) (xy 349.689317 -394.587364) (xy 349.661012 -394.549657)
			(xy 349.649542 -394.529056) (xy 349.649034 -394.528294) (xy 349.25127 -393.839954) (xy 349.239412 -393.817268)
			(xy 349.222555 -393.768939) (xy 349.213974 -393.71848) (xy 349.213424 -393.692888) (xy 348.67143 -393.692888)
			(xy 348.983554 -394.232892) (xy 348.99634 -394.256242) (xy 349.014539 -394.306265) (xy 349.023831 -394.358678)
			(xy 349.024448 -394.385292) (xy 349.024001 -394.409299) (xy 349.016488 -394.456723) (xy 349.001645 -394.502386)
			(xy 348.979839 -394.545163) (xy 348.951606 -394.584) (xy 348.917643 -394.61794) (xy 348.878787 -394.646147)
			(xy 348.835995 -394.667924) (xy 348.790322 -394.682736) (xy 348.742894 -394.690218) (xy 348.718886 -394.6906)
			(xy 348.700285 -394.690354) (xy 348.663351 -394.685898) (xy 348.645226 -394.68171) (xy 348.63553 -394.679801)
			(xy 348.615999 -394.68268) (xy 348.599004 -394.692728) (xy 348.587068 -394.708454) (xy 348.581961 -394.727524)
			(xy 348.584441 -394.74711) (xy 348.594139 -394.764306) (xy 348.601538 -394.770864) (xy 348.624398 -394.791184)
			(xy 348.977458 -395.144244) (xy 349.003874 -395.151102) (xy 349.017336 -395.147546) (xy 349.039059 -395.141876)
			(xy 349.083535 -395.135763) (xy 349.105982 -395.135354) (xy 349.131971 -395.135862) (xy 349.18331 -395.14399)
			(xy 349.232745 -395.160049) (xy 349.27906 -395.183643) (xy 349.321114 -395.214192) (xy 349.357871 -395.250943)
			(xy 349.388427 -395.292992) (xy 349.412029 -395.339303) (xy 349.428097 -395.388735) (xy 349.436233 -395.440073)
			(xy 349.43669 -395.466062) (xy 349.4363 -395.48851) (xy 349.430185 -395.532989) (xy 349.424498 -395.554708)
			(xy 349.420942 -395.56817) (xy 349.4278 -395.594586) (xy 349.919544 -396.08633) (xy 349.926941 -396.093177)
			(xy 349.94554 -396.100907) (xy 349.955612 -396.101316) (xy 357.958644 -396.101316) (xy 357.968711 -396.100885)
			(xy 357.987305 -396.093162) (xy 357.994712 -396.08633) (xy 358.113584 -395.967458) (xy 358.116378 -395.929866)
			(xy 358.104694 -395.914372) (xy 358.092758 -395.897772) (xy 358.073788 -395.861556) (xy 358.060864 -395.82277)
			(xy 358.054319 -395.782414) (xy 358.053894 -395.761972) (xy 358.053894 -395.12621) (xy 358.05446 -395.102112)
			(xy 358.063549 -395.05478) (xy 358.081401 -395.010012) (xy 358.107377 -394.969415) (xy 358.140544 -394.934446)
			(xy 358.159812 -394.919962) (xy 358.169229 -394.912298) (xy 358.180218 -394.890685) (xy 358.180894 -394.87856)
			(xy 358.180894 -394.756894) (xy 358.181456 -394.740317) (xy 358.190059 -394.708298) (xy 358.20663 -394.679581)
			(xy 358.217978 -394.667486) (xy 358.343708 -394.54201) (xy 358.350555 -394.534612) (xy 358.358292 -394.516014)
			(xy 358.358694 -394.505942) (xy 358.358694 -393.305284) (xy 358.358066 -393.29315) (xy 358.34705 -393.271535)
			(xy 358.337612 -393.263882) (xy 358.318358 -393.249383) (xy 358.285189 -393.21442) (xy 358.259214 -393.173826)
			(xy 358.241365 -393.12906) (xy 358.232284 -393.081731) (xy 358.231694 -393.057634) (xy 358.231694 -392.378184)
			(xy 358.231268 -392.368115) (xy 358.223549 -392.349516) (xy 358.216708 -392.342116) (xy 358.115362 -392.24077)
			(xy 358.107965 -392.233922) (xy 358.089366 -392.22619) (xy 358.079294 -392.225784) (xy 343.21623 -392.225784)
			(xy 343.206165 -392.226219) (xy 343.187578 -392.23395) (xy 343.180162 -392.24077) (xy 342.899238 -392.521694)
			(xy 342.892387 -392.52909) (xy 342.884644 -392.547689) (xy 342.884252 -392.557762) (xy 342.884252 -393.692888)
			(xy 343.213436 -393.692888) (xy 343.213436 -393.69238) (xy 343.21382 -393.668384) (xy 343.221331 -393.620984)
			(xy 343.236165 -393.575342) (xy 343.257957 -393.532583) (xy 343.286169 -393.493759) (xy 343.320108 -393.459828)
			(xy 343.358938 -393.431623) (xy 343.401701 -393.40984) (xy 343.447346 -393.395016) (xy 343.494748 -393.387515)
			(xy 343.518744 -393.387072) (xy 343.542678 -393.387544) (xy 343.589963 -393.395001) (xy 343.635506 -393.409741)
			(xy 343.678192 -393.431404) (xy 343.716978 -393.459459) (xy 343.750914 -393.493219) (xy 343.779169 -393.53186)
			(xy 343.790524 -393.552934) (xy 343.791032 -393.55395) (xy 343.871338 -393.692888) (xy 344.413332 -393.692888)
			(xy 344.413332 -393.69238) (xy 344.41372 -393.668384) (xy 344.421231 -393.620984) (xy 344.436065 -393.575343)
			(xy 344.457856 -393.532584) (xy 344.486068 -393.493761) (xy 344.520006 -393.459829) (xy 344.558835 -393.431624)
			(xy 344.601598 -393.409842) (xy 344.647243 -393.395017) (xy 344.694644 -393.387515) (xy 344.71864 -393.387072)
			(xy 344.718894 -393.387072) (xy 344.74283 -393.387503) (xy 344.790116 -393.394968) (xy 344.83566 -393.409715)
			(xy 344.878347 -393.431385) (xy 344.917132 -393.459446) (xy 344.951066 -393.493212) (xy 344.97932 -393.531857)
			(xy 344.990674 -393.552934) (xy 344.991182 -393.55395) (xy 345.071488 -393.692888) (xy 345.613228 -393.692888)
			(xy 345.613228 -393.69238) (xy 345.613621 -393.668372) (xy 345.621139 -393.620948) (xy 345.635988 -393.575285)
			(xy 345.657802 -393.532509) (xy 345.686041 -393.493675) (xy 345.720011 -393.45974) (xy 345.758874 -393.431539)
			(xy 345.801672 -393.40977) (xy 345.84735 -393.394967) (xy 345.894781 -393.387497) (xy 345.91879 -393.387072)
			(xy 345.942726 -393.387506) (xy 345.990012 -393.39497) (xy 346.035556 -393.409717) (xy 346.078242 -393.431386)
			(xy 346.117027 -393.459447) (xy 346.150962 -393.493213) (xy 346.179216 -393.531857) (xy 346.19057 -393.552934)
			(xy 346.191078 -393.55395) (xy 346.583508 -394.232892) (xy 346.596259 -394.256248) (xy 346.614368 -394.306281)
			(xy 346.62357 -394.358688) (xy 346.624148 -394.385292) (xy 346.62363 -394.409281) (xy 346.616126 -394.456669)
			(xy 346.601303 -394.502299) (xy 346.579524 -394.545049) (xy 346.551325 -394.583866) (xy 346.517403 -394.617794)
			(xy 346.47859 -394.645998) (xy 346.435843 -394.667784) (xy 346.390215 -394.682615) (xy 346.342829 -394.690126)
			(xy 346.31884 -394.6906) (xy 346.295267 -394.690174) (xy 346.24868 -394.682939) (xy 346.203763 -394.668618)
			(xy 346.161584 -394.647555) (xy 346.123151 -394.620251) (xy 346.089378 -394.587355) (xy 346.061071 -394.549654)
			(xy 346.0496 -394.529056) (xy 346.049092 -394.528294) (xy 345.651328 -393.839954) (xy 345.639396 -393.817294)
			(xy 345.622464 -393.768965) (xy 345.613811 -393.718491) (xy 345.613228 -393.692888) (xy 345.071488 -393.692888)
			(xy 345.383612 -394.232892) (xy 345.396363 -394.256248) (xy 345.414472 -394.306281) (xy 345.423674 -394.358688)
			(xy 345.424252 -394.385292) (xy 345.42373 -394.409281) (xy 345.416227 -394.456668) (xy 345.401403 -394.502298)
			(xy 345.379624 -394.545048) (xy 345.351427 -394.583865) (xy 345.317504 -394.617793) (xy 345.278692 -394.645997)
			(xy 345.235946 -394.667783) (xy 345.190319 -394.682614) (xy 345.142933 -394.690126) (xy 345.118944 -394.6906)
			(xy 345.11869 -394.6906) (xy 345.095116 -394.690214) (xy 345.048527 -394.682971) (xy 345.003608 -394.668644)
			(xy 344.96143 -394.647574) (xy 344.922997 -394.620263) (xy 344.889226 -394.587363) (xy 344.86092 -394.549656)
			(xy 344.84945 -394.529056) (xy 344.848942 -394.528294) (xy 344.451178 -393.839954) (xy 344.439321 -393.817268)
			(xy 344.422463 -393.768939) (xy 344.413882 -393.718479) (xy 344.413332 -393.692888) (xy 343.871338 -393.692888)
			(xy 344.183462 -394.232892) (xy 344.196289 -394.256224) (xy 344.214508 -394.306247) (xy 344.223767 -394.358673)
			(xy 344.224356 -394.385292) (xy 344.223854 -394.409295) (xy 344.216342 -394.45671) (xy 344.201502 -394.502365)
			(xy 344.179699 -394.545135) (xy 344.151472 -394.583966) (xy 344.117515 -394.617901) (xy 344.078666 -394.646103)
			(xy 344.035882 -394.667878) (xy 343.990217 -394.682688) (xy 343.942798 -394.690169) (xy 343.918794 -394.6906)
			(xy 343.89522 -394.690211) (xy 343.848631 -394.682969) (xy 343.803713 -394.668642) (xy 343.761534 -394.647573)
			(xy 343.723101 -394.620262) (xy 343.68933 -394.587362) (xy 343.661024 -394.549656) (xy 343.649554 -394.529056)
			(xy 343.649046 -394.528294) (xy 343.251282 -393.839954) (xy 343.239425 -393.817268) (xy 343.222567 -393.768939)
			(xy 343.213986 -393.718479) (xy 343.213436 -393.692888) (xy 342.884252 -393.692888) (xy 342.884252 -394.047218)
			(xy 342.884449 -394.053885) (xy 342.887925 -394.066757) (xy 342.89111 -394.072618) (xy 342.983566 -394.232892)
			(xy 342.996352 -394.256242) (xy 343.01455 -394.306265) (xy 343.023842 -394.358678) (xy 343.02446 -394.385292)
			(xy 343.024013 -394.408694) (xy 343.016872 -394.454949) (xy 343.002757 -394.499573) (xy 342.981996 -394.541521)
			(xy 342.955078 -394.579809) (xy 342.922633 -394.613541) (xy 342.904318 -394.628116) (xy 342.89532 -394.635704)
			(xy 342.884838 -394.656749) (xy 342.884252 -394.668502) (xy 342.884252 -396.108428) (xy 342.884682 -396.118495)
			(xy 342.892409 -396.137087) (xy 342.899238 -396.144496) (xy 343.15908 -396.404338) (xy 343.182448 -396.411704)
			(xy 343.19464 -396.409672) (xy 343.207371 -396.407656) (xy 343.233059 -396.405497) (xy 343.245948 -396.405354)
			(xy 343.265796 -396.405656) (xy 343.305164 -396.410749) (xy 343.324434 -396.415514) (xy 343.330784 -396.417292)
			(xy 344.361262 -396.417292)
		)
		(stroke
			(width 0)
			(type solid)
		)
		(fill yes)
		(layer "In9.Cu")
		(net "P1V8_CPU0_RT1_1A")
	)
	(gr_poly
		(pts
			(xy 424.662346 -397.467328) (xy 424.672413 -397.466897) (xy 424.691008 -397.459174) (xy 424.698414 -397.452342)
			(xy 424.777916 -397.37284) (xy 424.782996 -397.340074) (xy 424.775376 -397.325088) (xy 424.761649 -397.297614)
			(xy 424.742185 -397.239368) (xy 424.732306 -397.178756) (xy 424.731688 -397.14805) (xy 424.732148 -397.120795)
			(xy 424.739899 -397.066838) (xy 424.755251 -397.014534) (xy 424.77789 -396.964947) (xy 424.807357 -396.919088)
			(xy 424.843051 -396.877889) (xy 424.884244 -396.842189) (xy 424.9301 -396.812716) (xy 424.979683 -396.79007)
			(xy 425.031985 -396.774711) (xy 425.085941 -396.766952) (xy 425.113196 -396.766542) (xy 425.133287 -396.766785)
			(xy 425.173249 -396.770984) (xy 425.192952 -396.774924) (xy 425.204382 -396.777464) (xy 425.226734 -396.77213)
			(xy 425.297092 -396.715234) (xy 425.305518 -396.707562) (xy 425.315255 -396.686991) (xy 425.315888 -396.67561)
			(xy 425.315888 -392.39698) (xy 425.315461 -392.386912) (xy 425.30774 -392.368314) (xy 425.300902 -392.360912)
			(xy 424.985434 -392.045444) (xy 424.978034 -392.038603) (xy 424.959435 -392.030886) (xy 424.949366 -392.030458)
			(xy 410.052266 -392.030458) (xy 410.04226 -392.030951) (xy 410.023772 -392.038615) (xy 410.00962 -392.052766)
			(xy 410.001953 -392.071252) (xy 410.001466 -392.081258) (xy 410.001466 -393.692888) (xy 410.313632 -393.692888)
			(xy 410.313632 -393.69238) (xy 410.31402 -393.668384) (xy 410.321531 -393.620984) (xy 410.336365 -393.575343)
			(xy 410.358156 -393.532584) (xy 410.386368 -393.493761) (xy 410.420306 -393.459829) (xy 410.459135 -393.431624)
			(xy 410.501898 -393.409842) (xy 410.547543 -393.395017) (xy 410.594944 -393.387515) (xy 410.61894 -393.387072)
			(xy 410.642874 -393.387547) (xy 410.690159 -393.395003) (xy 410.735701 -393.409743) (xy 410.778388 -393.431405)
			(xy 410.817174 -393.45946) (xy 410.85111 -393.49322) (xy 410.879365 -393.53186) (xy 410.89072 -393.552934)
			(xy 410.891228 -393.55395) (xy 410.971534 -393.692888) (xy 411.513528 -393.692888) (xy 411.513528 -393.69238)
			(xy 411.51392 -393.668385) (xy 411.521431 -393.620985) (xy 411.536264 -393.575344) (xy 411.558055 -393.532585)
			(xy 411.586267 -393.493762) (xy 411.620205 -393.45983) (xy 411.659033 -393.431626) (xy 411.701796 -393.409843)
			(xy 411.747439 -393.395018) (xy 411.79484 -393.387515) (xy 411.818836 -393.387072) (xy 411.84277 -393.38755)
			(xy 411.890054 -393.395006) (xy 411.935597 -393.409745) (xy 411.978284 -393.431407) (xy 412.017069 -393.459461)
			(xy 412.051005 -393.49322) (xy 412.079261 -393.53186) (xy 412.090616 -393.552934) (xy 412.091124 -393.55395)
			(xy 412.17143 -393.692888) (xy 412.713424 -393.692888) (xy 412.713424 -393.69238) (xy 412.713821 -393.668372)
			(xy 412.721339 -393.620948) (xy 412.736188 -393.575286) (xy 412.758001 -393.53251) (xy 412.78624 -393.493676)
			(xy 412.820209 -393.459741) (xy 412.859072 -393.431541) (xy 412.901869 -393.409771) (xy 412.947546 -393.394968)
			(xy 412.994978 -393.387497) (xy 413.018986 -393.387072) (xy 413.042922 -393.38751) (xy 413.090208 -393.394973)
			(xy 413.135751 -393.409719) (xy 413.178438 -393.431388) (xy 413.217223 -393.459448) (xy 413.251158 -393.493213)
			(xy 413.279412 -393.531858) (xy 413.290766 -393.552934) (xy 413.291274 -393.55395) (xy 413.683704 -394.232892)
			(xy 413.696455 -394.256249) (xy 413.714564 -394.306281) (xy 413.723766 -394.358688) (xy 413.724344 -394.385292)
			(xy 413.72383 -394.409281) (xy 413.716326 -394.456669) (xy 413.701502 -394.5023) (xy 413.679723 -394.54505)
			(xy 413.651524 -394.583867) (xy 413.617601 -394.617796) (xy 413.578788 -394.646) (xy 413.536041 -394.667785)
			(xy 413.490412 -394.682616) (xy 413.443025 -394.690127) (xy 413.419036 -394.6906) (xy 413.395463 -394.690177)
			(xy 413.348876 -394.682941) (xy 413.303958 -394.668621) (xy 413.26178 -394.647557) (xy 413.223346 -394.620252)
			(xy 413.189574 -394.587356) (xy 413.161267 -394.549654) (xy 413.149796 -394.529056) (xy 413.149288 -394.528294)
			(xy 412.751524 -393.839954) (xy 412.739592 -393.817294) (xy 412.72266 -393.768965) (xy 412.714007 -393.718491)
			(xy 412.713424 -393.692888) (xy 412.17143 -393.692888) (xy 412.483554 -394.232892) (xy 412.49638 -394.256224)
			(xy 412.514599 -394.306247) (xy 412.523859 -394.358673) (xy 412.524448 -394.385292) (xy 412.523954 -394.409296)
			(xy 412.516441 -394.456711) (xy 412.501601 -394.502367) (xy 412.479798 -394.545138) (xy 412.45157 -394.583969)
			(xy 412.417612 -394.617904) (xy 412.378762 -394.646106) (xy 412.335977 -394.66788) (xy 412.290311 -394.68269)
			(xy 412.24289 -394.69017) (xy 412.218886 -394.6906) (xy 412.195312 -394.690217) (xy 412.148723 -394.682974)
			(xy 412.103804 -394.668646) (xy 412.061626 -394.647576) (xy 412.023193 -394.620264) (xy 411.989421 -394.587363)
			(xy 411.961116 -394.549656) (xy 411.949646 -394.529056) (xy 411.949138 -394.528294) (xy 411.551374 -393.839954)
			(xy 411.539517 -393.817268) (xy 411.522659 -393.768939) (xy 411.514078 -393.718479) (xy 411.513528 -393.692888)
			(xy 410.971534 -393.692888) (xy 411.283658 -394.232892) (xy 411.296484 -394.256224) (xy 411.314704 -394.306247)
			(xy 411.323963 -394.358673) (xy 411.324552 -394.385292) (xy 411.324054 -394.409295) (xy 411.316542 -394.456711)
			(xy 411.301701 -394.502366) (xy 411.279899 -394.545137) (xy 411.251671 -394.583968) (xy 411.217714 -394.617902)
			(xy 411.178864 -394.646104) (xy 411.136079 -394.667879) (xy 411.090414 -394.682689) (xy 411.042994 -394.690169)
			(xy 411.01899 -394.6906) (xy 410.995416 -394.690214) (xy 410.948827 -394.682971) (xy 410.903908 -394.668644)
			(xy 410.86173 -394.647574) (xy 410.823297 -394.620263) (xy 410.789526 -394.587363) (xy 410.76122 -394.549656)
			(xy 410.74975 -394.529056) (xy 410.749242 -394.528294) (xy 410.351478 -393.839954) (xy 410.339621 -393.817268)
			(xy 410.322763 -393.768939) (xy 410.314182 -393.718479) (xy 410.313632 -393.692888) (xy 410.001466 -393.692888)
			(xy 410.001466 -394.076682) (xy 410.001658 -394.08335) (xy 410.005128 -394.096227) (xy 410.008324 -394.102082)
			(xy 410.083762 -394.232892) (xy 410.096548 -394.256242) (xy 410.114747 -394.306265) (xy 410.124038 -394.358678)
			(xy 410.124656 -394.385292) (xy 410.124092 -394.411494) (xy 410.115111 -394.463125) (xy 410.097461 -394.512469)
			(xy 410.071658 -394.558082) (xy 410.038459 -394.598631) (xy 410.018992 -394.616178) (xy 410.011087 -394.623735)
			(xy 410.002015 -394.643609) (xy 410.001466 -394.654532) (xy 410.001466 -396.055596) (xy 410.00189 -396.065665)
			(xy 410.009611 -396.084264) (xy 410.016452 -396.091664) (xy 410.322268 -396.39748) (xy 410.340556 -396.405354)
			(xy 410.350462 -396.405354) (xy 410.373097 -396.406083) (xy 410.417787 -396.413405) (xy 410.460903 -396.427255)
			(xy 410.501497 -396.447329) (xy 410.538677 -396.473184) (xy 410.55544 -396.488412) (xy 410.56273 -396.494695)
			(xy 410.580621 -396.501743) (xy 410.590238 -396.502128) (xy 411.3022 -396.502128) (xy 411.311808 -396.501711)
			(xy 411.329687 -396.49466) (xy 411.336998 -396.488412) (xy 411.356023 -396.471216) (xy 411.398704 -396.442792)
			(xy 411.445533 -396.421898) (xy 411.495195 -396.409122) (xy 411.546294 -396.404823) (xy 411.597393 -396.409122)
			(xy 411.647055 -396.421898) (xy 411.693884 -396.442792) (xy 411.736565 -396.471216) (xy 411.75559 -396.488412)
			(xy 411.762878 -396.494702) (xy 411.780769 -396.501768) (xy 411.790388 -396.502128) (xy 412.502096 -396.502128)
			(xy 412.511705 -396.501712) (xy 412.529584 -396.494662) (xy 412.536894 -396.488412) (xy 412.553982 -396.472901)
			(xy 412.591956 -396.446679) (xy 412.633442 -396.426467) (xy 412.677496 -396.412726) (xy 412.723116 -396.405768)
			(xy 412.74619 -396.405354) (xy 412.771358 -396.405869) (xy 412.821011 -396.414134) (xy 412.868632 -396.430441)
			(xy 412.912929 -396.454346) (xy 412.933134 -396.469362) (xy 412.948374 -396.481046) (xy 412.986474 -396.47876)
			(xy 414.672526 -394.792708) (xy 414.679638 -394.779246) (xy 414.680908 -394.771626) (xy 414.684972 -394.753084)
			(xy 414.633156 -394.690346) (xy 414.618932 -394.6906) (xy 414.595363 -394.690157) (xy 414.548788 -394.682899)
			(xy 414.503882 -394.668566) (xy 414.461713 -394.6475) (xy 414.423285 -394.6202) (xy 414.389512 -394.587317)
			(xy 414.361195 -394.549632) (xy 414.349692 -394.529056) (xy 414.349184 -394.528294) (xy 413.95142 -393.839954)
			(xy 413.939485 -393.817293) (xy 413.922531 -393.768969) (xy 413.913883 -393.718493) (xy 413.91332 -393.692888)
			(xy 413.91332 -393.69238) (xy 413.913769 -393.668376) (xy 413.921286 -393.62096) (xy 413.936132 -393.575305)
			(xy 413.957941 -393.532537) (xy 413.986175 -393.493709) (xy 414.020139 -393.459779) (xy 414.058995 -393.431583)
			(xy 414.101785 -393.409816) (xy 414.147454 -393.395015) (xy 414.194878 -393.387545) (xy 414.218882 -393.387072)
			(xy 414.242817 -393.387535) (xy 414.290103 -393.394996) (xy 414.335647 -393.409738) (xy 414.378336 -393.4314)
			(xy 414.417125 -393.459453) (xy 414.451067 -393.49321) (xy 414.47933 -393.531847) (xy 414.490662 -393.552934)
			(xy 414.49117 -393.55395) (xy 414.8836 -394.232892) (xy 414.896404 -394.256225) (xy 414.914546 -394.306258)
			(xy 414.923722 -394.358681) (xy 414.92424 -394.385292) (xy 414.92424 -394.395706) (xy 414.923732 -394.405866)
			(xy 414.93059 -394.424408) (xy 414.993074 -394.491972) (xy 415.010854 -394.500354) (xy 415.021268 -394.500608)
			(xy 415.046493 -394.502231) (xy 415.09605 -394.512178) (xy 415.143515 -394.529552) (xy 415.187783 -394.553947)
			(xy 415.227822 -394.584797) (xy 415.262699 -394.62138) (xy 415.277554 -394.641832) (xy 415.285171 -394.651492)
			(xy 415.306931 -394.662886) (xy 415.31921 -394.663676) (xy 415.458402 -394.663676) (xy 415.480174 -394.664126)
			(xy 415.523083 -394.671534) (xy 415.543746 -394.678408) (xy 415.553069 -394.681308) (xy 415.572563 -394.680605)
			(xy 415.590387 -394.672678) (xy 415.603966 -394.658674) (xy 415.611338 -394.640614) (xy 415.611439 -394.621107)
			(xy 415.604253 -394.602972) (xy 415.597848 -394.595604) (xy 415.58392 -394.580443) (xy 415.559833 -394.547056)
			(xy 415.549842 -394.529056) (xy 415.549334 -394.528294) (xy 415.15157 -393.839954) (xy 415.139675 -393.817285)
			(xy 415.122807 -393.768954) (xy 415.114254 -393.718483) (xy 415.113724 -393.692888) (xy 415.113724 -393.69238)
			(xy 415.114172 -393.668389) (xy 415.121681 -393.620998) (xy 415.136512 -393.575365) (xy 415.158299 -393.532614)
			(xy 415.186505 -393.493797) (xy 415.220437 -393.459871) (xy 415.259258 -393.431672) (xy 415.302013 -393.409892)
			(xy 415.347648 -393.395069) (xy 415.395041 -393.387568) (xy 415.419032 -393.387072) (xy 415.442965 -393.387539)
			(xy 415.490246 -393.395006) (xy 415.535784 -393.409753) (xy 415.578467 -393.431419) (xy 415.61725 -393.459474)
			(xy 415.651185 -393.493232) (xy 415.679443 -393.531868) (xy 415.690812 -393.552934) (xy 415.69132 -393.55395)
			(xy 415.771626 -393.692888) (xy 416.31362 -393.692888) (xy 416.31362 -393.69238) (xy 416.31402 -393.668385)
			(xy 416.32153 -393.620986) (xy 416.336363 -393.575346) (xy 416.358154 -393.532588) (xy 416.386365 -393.493765)
			(xy 416.420301 -393.459833) (xy 416.459129 -393.431629) (xy 416.50189 -393.409845) (xy 416.547533 -393.395019)
			(xy 416.594933 -393.387516) (xy 416.618928 -393.387072) (xy 416.642862 -393.387557) (xy 416.690146 -393.395011)
			(xy 416.735688 -393.409749) (xy 416.778375 -393.43141) (xy 416.817161 -393.459463) (xy 416.851097 -393.493222)
			(xy 416.879353 -393.53186) (xy 416.890708 -393.552934) (xy 416.891216 -393.55395) (xy 416.971522 -393.692888)
			(xy 417.513516 -393.692888) (xy 417.513516 -393.69238) (xy 417.51392 -393.668385) (xy 417.52143 -393.620987)
			(xy 417.536263 -393.575347) (xy 417.558053 -393.532589) (xy 417.586263 -393.493766) (xy 417.6202 -393.459835)
			(xy 417.659026 -393.43163) (xy 417.701787 -393.409846) (xy 417.747429 -393.39502) (xy 417.794829 -393.387516)
			(xy 417.818824 -393.387072) (xy 417.842758 -393.38756) (xy 417.890042 -393.395014) (xy 417.935584 -393.409751)
			(xy 417.978271 -393.431411) (xy 418.017057 -393.459464) (xy 418.050993 -393.493222) (xy 418.079249 -393.53186)
			(xy 418.090604 -393.552934) (xy 418.091112 -393.55395) (xy 418.171418 -393.692888) (xy 418.713412 -393.692888)
			(xy 418.713412 -393.69238) (xy 418.713821 -393.668373) (xy 418.721339 -393.62095) (xy 418.736187 -393.575289)
			(xy 418.757999 -393.532514) (xy 418.786237 -393.493681) (xy 418.820204 -393.459745) (xy 418.859065 -393.431545)
			(xy 418.901861 -393.409774) (xy 418.947536 -393.39497) (xy 418.994966 -393.387498) (xy 419.018974 -393.387072)
			(xy 419.042909 -393.387519) (xy 419.090195 -393.394981) (xy 419.135738 -393.409726) (xy 419.178425 -393.431392)
			(xy 419.21721 -393.459451) (xy 419.251145 -393.493215) (xy 419.279399 -393.531858) (xy 419.290754 -393.552934)
			(xy 419.291262 -393.55395) (xy 419.371568 -393.692888) (xy 419.913308 -393.692888) (xy 419.913308 -393.69238)
			(xy 419.913721 -393.668373) (xy 419.921239 -393.620951) (xy 419.936087 -393.57529) (xy 419.957898 -393.532515)
			(xy 419.986135 -393.493682) (xy 420.020103 -393.459747) (xy 420.058963 -393.431546) (xy 420.101758 -393.409775)
			(xy 420.147433 -393.394971) (xy 420.194862 -393.387498) (xy 420.21887 -393.387072) (xy 420.242805 -393.387523)
			(xy 420.290091 -393.394984) (xy 420.335634 -393.409728) (xy 420.378321 -393.431394) (xy 420.417106 -393.459452)
			(xy 420.451041 -393.493216) (xy 420.479295 -393.531858) (xy 420.49065 -393.552934) (xy 420.491158 -393.55395)
			(xy 420.571464 -393.692888) (xy 421.113712 -393.692888) (xy 421.113712 -393.69238) (xy 421.114144 -393.668387)
			(xy 421.121654 -393.620993) (xy 421.136485 -393.575357) (xy 421.158273 -393.532603) (xy 421.186481 -393.493784)
			(xy 421.220414 -393.459855) (xy 421.259237 -393.431652) (xy 421.301994 -393.40987) (xy 421.347632 -393.395045)
			(xy 421.395027 -393.387541) (xy 421.41902 -393.387072) (xy 421.442954 -393.387563) (xy 421.490237 -393.395017)
			(xy 421.53578 -393.409753) (xy 421.578466 -393.431413) (xy 421.617252 -393.459465) (xy 421.651189 -393.493223)
			(xy 421.679444 -393.531861) (xy 421.6908 -393.552934) (xy 421.691308 -393.55395) (xy 422.083738 -394.232892)
			(xy 422.096563 -394.256225) (xy 422.114783 -394.306247) (xy 422.124043 -394.358673) (xy 422.124632 -394.385292)
			(xy 422.124154 -394.409296) (xy 422.116641 -394.456714) (xy 422.101799 -394.502371) (xy 422.079995 -394.545143)
			(xy 422.051765 -394.583974) (xy 422.017805 -394.617909) (xy 421.978953 -394.646111) (xy 421.936165 -394.667885)
			(xy 421.890498 -394.682693) (xy 421.843075 -394.690171) (xy 421.81907 -394.6906) (xy 421.795495 -394.69023)
			(xy 421.748906 -394.682984) (xy 421.703987 -394.668654) (xy 421.661808 -394.647582) (xy 421.623376 -394.620268)
			(xy 421.589605 -394.587365) (xy 421.5613 -394.549657) (xy 421.54983 -394.529056) (xy 421.549322 -394.528294)
			(xy 421.151558 -393.839954) (xy 421.139699 -393.817269) (xy 421.122842 -393.76894) (xy 421.114262 -393.71848)
			(xy 421.113712 -393.692888) (xy 420.571464 -393.692888) (xy 420.883588 -394.232892) (xy 420.896337 -394.256249)
			(xy 420.914447 -394.306281) (xy 420.92365 -394.358688) (xy 420.924228 -394.385292) (xy 420.92373 -394.409282)
			(xy 420.916226 -394.456672) (xy 420.901401 -394.502304) (xy 420.87962 -394.545055) (xy 420.85142 -394.583873)
			(xy 420.817494 -394.617801) (xy 420.778679 -394.646005) (xy 420.73593 -394.66779) (xy 420.690299 -394.682619)
			(xy 420.64291 -394.690128) (xy 420.61892 -394.6906) (xy 420.595347 -394.69019) (xy 420.548759 -394.682952)
			(xy 420.503841 -394.668629) (xy 420.461662 -394.647563) (xy 420.423229 -394.620256) (xy 420.389457 -394.587358)
			(xy 420.361151 -394.549655) (xy 420.34968 -394.529056) (xy 420.349172 -394.528294) (xy 419.951408 -393.839954)
			(xy 419.939474 -393.817295) (xy 419.922543 -393.768965) (xy 419.913891 -393.718491) (xy 419.913308 -393.692888)
			(xy 419.371568 -393.692888) (xy 419.683692 -394.232892) (xy 419.696442 -394.256249) (xy 419.714551 -394.306281)
			(xy 419.723754 -394.358688) (xy 419.724332 -394.385292) (xy 419.72383 -394.409282) (xy 419.716326 -394.456671)
			(xy 419.701501 -394.502303) (xy 419.679721 -394.545054) (xy 419.651521 -394.583871) (xy 419.617596 -394.6178)
			(xy 419.578781 -394.646004) (xy 419.536032 -394.667789) (xy 419.490402 -394.682618) (xy 419.443014 -394.690128)
			(xy 419.419024 -394.6906) (xy 419.395451 -394.690187) (xy 419.348863 -394.682949) (xy 419.303945 -394.668627)
			(xy 419.261767 -394.647561) (xy 419.223333 -394.620255) (xy 419.189561 -394.587358) (xy 419.161255 -394.549655)
			(xy 419.149784 -394.529056) (xy 419.149276 -394.528294) (xy 418.751512 -393.839954) (xy 418.739579 -393.817295)
			(xy 418.722647 -393.768965) (xy 418.713995 -393.718491) (xy 418.713412 -393.692888) (xy 418.171418 -393.692888)
			(xy 418.483542 -394.232892) (xy 418.496367 -394.256224) (xy 418.514587 -394.306247) (xy 418.523847 -394.358673)
			(xy 418.524436 -394.385292) (xy 418.523954 -394.409296) (xy 418.516441 -394.456713) (xy 418.5016 -394.50237)
			(xy 418.479796 -394.545141) (xy 418.451566 -394.583973) (xy 418.417607 -394.617908) (xy 418.378755 -394.64611)
			(xy 418.335968 -394.667883) (xy 418.290301 -394.682692) (xy 418.242879 -394.690171) (xy 418.218874 -394.6906)
			(xy 418.195299 -394.690227) (xy 418.14871 -394.682982) (xy 418.103791 -394.668652) (xy 418.061613 -394.64758)
			(xy 418.02318 -394.620267) (xy 417.989409 -394.587365) (xy 417.961104 -394.549657) (xy 417.949634 -394.529056)
			(xy 417.949126 -394.528294) (xy 417.551362 -393.839954) (xy 417.539504 -393.817268) (xy 417.522646 -393.76894)
			(xy 417.514066 -393.71848) (xy 417.513516 -393.692888) (xy 416.971522 -393.692888) (xy 417.283646 -394.232892)
			(xy 417.296471 -394.256224) (xy 417.314691 -394.306247) (xy 417.323951 -394.358673) (xy 417.32454 -394.385292)
			(xy 417.324054 -394.409296) (xy 417.316541 -394.456713) (xy 417.3017 -394.502369) (xy 417.279896 -394.54514)
			(xy 417.251667 -394.583972) (xy 417.217709 -394.617907) (xy 417.178857 -394.646108) (xy 417.136071 -394.667882)
			(xy 417.090404 -394.682691) (xy 417.042982 -394.69017) (xy 417.018978 -394.6906) (xy 416.995403 -394.690224)
			(xy 416.948814 -394.682979) (xy 416.903895 -394.66865) (xy 416.861717 -394.647579) (xy 416.823284 -394.620266)
			(xy 416.789513 -394.587364) (xy 416.761208 -394.549657) (xy 416.749738 -394.529056) (xy 416.74923 -394.528294)
			(xy 416.351466 -393.839954) (xy 416.339608 -393.817268) (xy 416.32275 -393.76894) (xy 416.31417 -393.71848)
			(xy 416.31362 -393.692888) (xy 415.771626 -393.692888) (xy 416.08375 -394.232892) (xy 416.096537 -394.256242)
			(xy 416.114736 -394.306264) (xy 416.124028 -394.358678) (xy 416.124644 -394.385292) (xy 416.124197 -394.409299)
			(xy 416.116684 -394.456722) (xy 416.101841 -394.502385) (xy 416.080035 -394.545162) (xy 416.051802 -394.583999)
			(xy 416.017839 -394.617939) (xy 415.978983 -394.646145) (xy 415.936191 -394.667922) (xy 415.890518 -394.682733)
			(xy 415.84309 -394.690214) (xy 415.819082 -394.6906) (xy 415.790394 -394.689995) (xy 415.734009 -394.679392)
			(xy 415.707068 -394.669518) (xy 415.692844 -394.663676) (xy 415.66338 -394.670026) (xy 415.652458 -394.680694)
			(xy 415.645628 -394.688061) (xy 415.637904 -394.706588) (xy 415.637914 -394.726661) (xy 415.645656 -394.74518)
			(xy 415.652458 -394.752576) (xy 416.053016 -395.153134) (xy 416.081464 -395.159484) (xy 416.095434 -395.154404)
			(xy 416.122245 -395.145486) (xy 416.177928 -395.135911) (xy 416.206178 -395.135354) (xy 416.232167 -395.135862)
			(xy 416.283507 -395.143989) (xy 416.332943 -395.160048) (xy 416.379258 -395.183642) (xy 416.421312 -395.214191)
			(xy 416.45807 -395.250942) (xy 416.488626 -395.292991) (xy 416.512229 -395.339302) (xy 416.528297 -395.388735)
			(xy 416.536433 -395.440073) (xy 416.536886 -395.466062) (xy 416.536305 -395.494309) (xy 416.52672 -395.549985)
			(xy 416.517836 -395.576806) (xy 416.512756 -395.590776) (xy 416.519106 -395.619224) (xy 416.953954 -396.054072)
			(xy 416.966144 -396.06672) (xy 416.987302 -396.094759) (xy 416.996118 -396.109952) (xy 417.002976 -396.122144)
			(xy 417.026344 -396.13586) (xy 420.975028 -396.13586) (xy 420.999987 -396.136434) (xy 421.048944 -396.14618)
			(xy 421.095059 -396.165291) (xy 421.136558 -396.193032) (xy 421.154606 -396.210282) (xy 422.396666 -397.452342)
			(xy 422.404065 -397.459184) (xy 422.422664 -397.466904) (xy 422.432734 -397.467328)
		)
		(stroke
			(width 0)
			(type solid)
		)
		(fill yes)
		(layer "In9.Cu")
		(net "P1V8_CPU0_RT2_1A")
	)
	(gr_poly
		(pts
			(xy 167.146986 -389.005572) (xy 167.149526 -388.986522) (xy 167.153585 -388.960437) (xy 167.168901 -388.909921)
			(xy 167.192049 -388.86248) (xy 167.22244 -388.819319) (xy 167.259302 -388.781534) (xy 167.301699 -388.750086)
			(xy 167.348553 -388.725773) (xy 167.398676 -388.709213) (xy 167.450792 -388.700826) (xy 167.50358 -388.700826)
			(xy 167.555696 -388.709213) (xy 167.605819 -388.725773) (xy 167.652673 -388.750086) (xy 167.69507 -388.781534)
			(xy 167.731932 -388.819319) (xy 167.762323 -388.86248) (xy 167.785471 -388.909921) (xy 167.800787 -388.960437)
			(xy 167.804846 -388.986522) (xy 167.807386 -389.005572) (xy 167.836088 -389.030464) (xy 168.63822 -389.030464)
			(xy 168.648288 -389.030036) (xy 168.666884 -389.022313) (xy 168.674288 -389.015478) (xy 168.75252 -388.937246)
			(xy 168.759124 -388.908544) (xy 168.754044 -388.894574) (xy 168.74361 -388.863473) (xy 168.732365 -388.798848)
			(xy 168.731692 -388.76605) (xy 168.732152 -388.738795) (xy 168.739903 -388.684838) (xy 168.755255 -388.632535)
			(xy 168.777894 -388.582948) (xy 168.807361 -388.537089) (xy 168.843055 -388.49589) (xy 168.884249 -388.460191)
			(xy 168.930104 -388.430718) (xy 168.979688 -388.408072) (xy 169.03199 -388.392714) (xy 169.085945 -388.384955)
			(xy 169.1132 -388.384542) (xy 169.128443 -388.384681) (xy 169.158833 -388.387095) (xy 169.173906 -388.389368)
			(xy 169.185082 -388.391146) (xy 169.206418 -388.385304) (xy 169.273982 -388.3279) (xy 169.282047 -388.320278)
			(xy 169.291273 -388.300124) (xy 169.291762 -388.289038) (xy 169.291762 -383.960116) (xy 169.291323 -383.950053)
			(xy 169.283583 -383.931475) (xy 169.276776 -383.924048) (xy 168.961308 -383.60858) (xy 168.953914 -383.601723)
			(xy 168.935315 -383.593973) (xy 168.92524 -383.593594) (xy 154.02814 -383.593594) (xy 154.018113 -383.594007)
			(xy 153.999581 -383.601669) (xy 153.985395 -383.615843) (xy 153.977716 -383.634367) (xy 153.97734 -383.644394)
			(xy 153.97734 -385.310888) (xy 154.313636 -385.310888) (xy 154.313636 -385.31038) (xy 154.31402 -385.286384)
			(xy 154.321531 -385.238984) (xy 154.336365 -385.193342) (xy 154.358157 -385.150583) (xy 154.386369 -385.111759)
			(xy 154.420308 -385.077828) (xy 154.459138 -385.049623) (xy 154.501901 -385.02784) (xy 154.547546 -385.013016)
			(xy 154.594948 -385.005515) (xy 154.618944 -385.005072) (xy 154.642878 -385.005544) (xy 154.690163 -385.013001)
			(xy 154.735706 -385.027741) (xy 154.778392 -385.049404) (xy 154.817178 -385.077459) (xy 154.851114 -385.111219)
			(xy 154.879369 -385.14986) (xy 154.890724 -385.170934) (xy 154.891232 -385.17195) (xy 154.971538 -385.310888)
			(xy 155.513532 -385.310888) (xy 155.513532 -385.31038) (xy 155.51392 -385.286384) (xy 155.521431 -385.238984)
			(xy 155.536265 -385.193343) (xy 155.558056 -385.150584) (xy 155.586268 -385.111761) (xy 155.620206 -385.077829)
			(xy 155.659035 -385.049624) (xy 155.701798 -385.027842) (xy 155.747443 -385.013017) (xy 155.794844 -385.005515)
			(xy 155.81884 -385.005072) (xy 155.842774 -385.005547) (xy 155.890059 -385.013003) (xy 155.935601 -385.027743)
			(xy 155.978288 -385.049405) (xy 156.017074 -385.07746) (xy 156.05101 -385.11122) (xy 156.079265 -385.14986)
			(xy 156.09062 -385.170934) (xy 156.091128 -385.17195) (xy 156.171434 -385.310888) (xy 156.713428 -385.310888)
			(xy 156.713428 -385.31038) (xy 156.713821 -385.286372) (xy 156.721339 -385.238948) (xy 156.736188 -385.193285)
			(xy 156.758002 -385.150509) (xy 156.786241 -385.111675) (xy 156.820211 -385.07774) (xy 156.859074 -385.049539)
			(xy 156.901872 -385.02777) (xy 156.94755 -385.012967) (xy 156.994981 -385.005497) (xy 157.01899 -385.005072)
			(xy 157.042926 -385.005506) (xy 157.090212 -385.01297) (xy 157.135756 -385.027717) (xy 157.178442 -385.049386)
			(xy 157.217227 -385.077447) (xy 157.251162 -385.111213) (xy 157.279416 -385.149857) (xy 157.29077 -385.170934)
			(xy 157.291278 -385.17195) (xy 157.683708 -385.850892) (xy 157.696459 -385.874248) (xy 157.714568 -385.924281)
			(xy 157.72377 -385.976688) (xy 157.724348 -386.003292) (xy 157.72383 -386.027281) (xy 157.716326 -386.074669)
			(xy 157.701503 -386.120299) (xy 157.679724 -386.163049) (xy 157.651525 -386.201866) (xy 157.617603 -386.235794)
			(xy 157.57879 -386.263998) (xy 157.536043 -386.285784) (xy 157.490415 -386.300615) (xy 157.443029 -386.308126)
			(xy 157.41904 -386.3086) (xy 157.395467 -386.308174) (xy 157.34888 -386.300939) (xy 157.303963 -386.286618)
			(xy 157.261784 -386.265555) (xy 157.223351 -386.238251) (xy 157.189578 -386.205355) (xy 157.161271 -386.167654)
			(xy 157.1498 -386.147056) (xy 157.149292 -386.146294) (xy 156.751528 -385.457954) (xy 156.739596 -385.435294)
			(xy 156.722664 -385.386965) (xy 156.714011 -385.336491) (xy 156.713428 -385.310888) (xy 156.171434 -385.310888)
			(xy 156.483558 -385.850892) (xy 156.496384 -385.874224) (xy 156.514604 -385.924247) (xy 156.523863 -385.976673)
			(xy 156.524452 -386.003292) (xy 156.523954 -386.027295) (xy 156.516442 -386.074711) (xy 156.501601 -386.120366)
			(xy 156.479799 -386.163137) (xy 156.451571 -386.201968) (xy 156.417614 -386.235902) (xy 156.378764 -386.264104)
			(xy 156.335979 -386.285879) (xy 156.290314 -386.300689) (xy 156.242894 -386.308169) (xy 156.21889 -386.3086)
			(xy 156.195316 -386.308214) (xy 156.148727 -386.300971) (xy 156.103808 -386.286644) (xy 156.06163 -386.265574)
			(xy 156.023197 -386.238263) (xy 155.989426 -386.205363) (xy 155.96112 -386.167656) (xy 155.94965 -386.147056)
			(xy 155.949142 -386.146294) (xy 155.551378 -385.457954) (xy 155.539521 -385.435268) (xy 155.522663 -385.386939)
			(xy 155.514082 -385.336479) (xy 155.513532 -385.310888) (xy 154.971538 -385.310888) (xy 155.283662 -385.850892)
			(xy 155.296489 -385.874224) (xy 155.314708 -385.924247) (xy 155.323967 -385.976673) (xy 155.324556 -386.003292)
			(xy 155.324054 -386.027295) (xy 155.316542 -386.07471) (xy 155.301702 -386.120365) (xy 155.279899 -386.163135)
			(xy 155.251672 -386.201966) (xy 155.217715 -386.235901) (xy 155.178866 -386.264103) (xy 155.136082 -386.285878)
			(xy 155.090417 -386.300688) (xy 155.042998 -386.308169) (xy 155.018994 -386.3086) (xy 154.99542 -386.308211)
			(xy 154.948831 -386.300969) (xy 154.903913 -386.286642) (xy 154.861734 -386.265573) (xy 154.823301 -386.238262)
			(xy 154.78953 -386.205362) (xy 154.761224 -386.167656) (xy 154.749754 -386.147056) (xy 154.749246 -386.146294)
			(xy 154.351482 -385.457954) (xy 154.339625 -385.435268) (xy 154.322767 -385.386939) (xy 154.314186 -385.336479)
			(xy 154.313636 -385.310888) (xy 153.97734 -385.310888) (xy 153.97734 -385.653026) (xy 153.977537 -385.659693)
			(xy 153.981015 -385.672565) (xy 153.984198 -385.678426) (xy 154.083766 -385.850892) (xy 154.096552 -385.874242)
			(xy 154.11475 -385.924265) (xy 154.124042 -385.976678) (xy 154.12466 -386.003292) (xy 154.124212 -386.027334)
			(xy 154.116682 -386.074824) (xy 154.101808 -386.120548) (xy 154.079955 -386.163379) (xy 154.051665 -386.202259)
			(xy 154.017634 -386.236228) (xy 153.998422 -386.250688) (xy 153.989033 -386.258297) (xy 153.978019 -386.279771)
			(xy 153.97734 -386.291836) (xy 153.97734 -387.618732) (xy 153.97777 -387.628799) (xy 153.985497 -387.647391)
			(xy 153.992326 -387.6548) (xy 154.354276 -388.01675) (xy 154.36977 -388.024116) (xy 154.37866 -388.025132)
			(xy 154.407722 -388.028857) (xy 154.463744 -388.045989) (xy 154.489912 -388.059168) (xy 154.4955 -388.062216)
			(xy 154.507438 -388.065264) (xy 155.385008 -388.065264) (xy 155.396946 -388.062216) (xy 155.402534 -388.059168)
			(xy 155.424794 -388.04787) (xy 155.472081 -388.031881) (xy 155.521339 -388.023803) (xy 155.546298 -388.023354)
			(xy 155.571254 -388.023833) (xy 155.620508 -388.031913) (xy 155.667794 -388.04789) (xy 155.690062 -388.059168)
			(xy 155.69565 -388.062216) (xy 155.707588 -388.065264) (xy 156.584904 -388.065264) (xy 156.596842 -388.062216)
			(xy 156.60243 -388.059168) (xy 156.62469 -388.04787) (xy 156.671977 -388.03188) (xy 156.721235 -388.023801)
			(xy 156.746194 -388.023354) (xy 156.77115 -388.023833) (xy 156.820404 -388.031912) (xy 156.86769 -388.047889)
			(xy 156.889958 -388.059168) (xy 156.895546 -388.062216) (xy 156.907484 -388.065264) (xy 156.917898 -388.065264)
			(xy 156.927968 -388.064841) (xy 156.946569 -388.057123) (xy 156.953966 -388.050278) (xy 158.54807 -386.456174)
			(xy 158.556531 -386.446663) (xy 158.563717 -386.422276) (xy 158.561786 -386.409692) (xy 158.540958 -386.313426)
			(xy 158.52394 -386.293868) (xy 158.511748 -386.289296) (xy 158.486141 -386.279062) (xy 158.438834 -386.250733)
			(xy 158.397398 -386.214353) (xy 158.363186 -386.171108) (xy 158.349696 -386.147056) (xy 158.349188 -386.146294)
			(xy 157.951424 -385.457954) (xy 157.939489 -385.435294) (xy 157.922534 -385.38697) (xy 157.913886 -385.336493)
			(xy 157.913324 -385.310888) (xy 157.913324 -385.31038) (xy 157.913773 -385.286376) (xy 157.92129 -385.23896)
			(xy 157.936136 -385.193306) (xy 157.957945 -385.150538) (xy 157.98618 -385.11171) (xy 158.020143 -385.077781)
			(xy 158.058999 -385.049585) (xy 158.101789 -385.027819) (xy 158.147458 -385.013019) (xy 158.194882 -385.005549)
			(xy 158.218886 -385.005072) (xy 158.242821 -385.005536) (xy 158.290106 -385.012997) (xy 158.33565 -385.027739)
			(xy 158.378338 -385.049401) (xy 158.417127 -385.077455) (xy 158.451068 -385.111212) (xy 158.479331 -385.149849)
			(xy 158.490666 -385.170934) (xy 158.491174 -385.17195) (xy 158.883604 -385.850892) (xy 158.896408 -385.874225)
			(xy 158.91455 -385.924258) (xy 158.923726 -385.976681) (xy 158.924244 -386.003292) (xy 158.924244 -386.013706)
			(xy 158.923736 -386.023866) (xy 158.930594 -386.042408) (xy 158.993078 -386.109972) (xy 159.010858 -386.118354)
			(xy 159.021272 -386.118608) (xy 159.045298 -386.120157) (xy 159.092559 -386.129332) (xy 159.137994 -386.145255)
			(xy 159.180644 -386.167589) (xy 159.219611 -386.195863) (xy 159.237172 -386.212334) (xy 159.244553 -386.218915)
			(xy 159.262853 -386.226362) (xy 159.272732 -386.226812) (xy 159.434276 -386.226812) (xy 159.451054 -386.227096)
			(xy 159.484312 -386.23155) (xy 159.50057 -386.235702) (xy 159.510435 -386.237913) (xy 159.53046 -386.235244)
			(xy 159.547903 -386.225054) (xy 159.560063 -386.208922) (xy 159.565055 -386.189347) (xy 159.562106 -386.169362)
			(xy 159.557212 -386.160518) (xy 159.549846 -386.147056) (xy 159.549338 -386.146294) (xy 159.151574 -385.457954)
			(xy 159.139679 -385.435285) (xy 159.122811 -385.386954) (xy 159.114258 -385.336483) (xy 159.113728 -385.310888)
			(xy 159.113728 -385.31038) (xy 159.114176 -385.286389) (xy 159.121685 -385.238998) (xy 159.136516 -385.193365)
			(xy 159.158303 -385.150615) (xy 159.18651 -385.111799) (xy 159.220441 -385.077873) (xy 159.259262 -385.049674)
			(xy 159.302017 -385.027894) (xy 159.347652 -385.013072) (xy 159.395045 -385.005571) (xy 159.419036 -385.005072)
			(xy 159.442969 -385.005539) (xy 159.490249 -385.013007) (xy 159.535787 -385.027754) (xy 159.578469 -385.04942)
			(xy 159.617252 -385.077476) (xy 159.651187 -385.111234) (xy 159.679444 -385.14987) (xy 159.690816 -385.170934)
			(xy 159.691324 -385.17195) (xy 159.77163 -385.310888) (xy 160.313624 -385.310888) (xy 160.313624 -385.31038)
			(xy 160.31402 -385.286385) (xy 160.321531 -385.238985) (xy 160.336364 -385.193345) (xy 160.358154 -385.150586)
			(xy 160.386366 -385.111764) (xy 160.420303 -385.077832) (xy 160.459131 -385.049627) (xy 160.501893 -385.027844)
			(xy 160.547536 -385.013018) (xy 160.594937 -385.005516) (xy 160.618932 -385.005072) (xy 160.642866 -385.005554)
			(xy 160.69015 -385.013009) (xy 160.735693 -385.027747) (xy 160.778379 -385.049408) (xy 160.817165 -385.077462)
			(xy 160.851101 -385.111221) (xy 160.879357 -385.14986) (xy 160.890712 -385.170934) (xy 160.89122 -385.17195)
			(xy 160.971526 -385.310888) (xy 161.51352 -385.310888) (xy 161.51352 -385.31038) (xy 161.51392 -385.286385)
			(xy 161.52143 -385.238986) (xy 161.536263 -385.193346) (xy 161.558054 -385.150588) (xy 161.586265 -385.111765)
			(xy 161.620201 -385.077833) (xy 161.659029 -385.049629) (xy 161.70179 -385.027845) (xy 161.747433 -385.013019)
			(xy 161.794833 -385.005516) (xy 161.818828 -385.005072) (xy 161.842762 -385.005557) (xy 161.890046 -385.013011)
			(xy 161.935588 -385.027749) (xy 161.978275 -385.04941) (xy 162.017061 -385.077463) (xy 162.050997 -385.111222)
			(xy 162.079253 -385.14986) (xy 162.090608 -385.170934) (xy 162.091116 -385.17195) (xy 162.171422 -385.310888)
			(xy 162.713416 -385.310888) (xy 162.713416 -385.31038) (xy 162.713821 -385.286372) (xy 162.721339 -385.238949)
			(xy 162.736187 -385.193288) (xy 162.757999 -385.150513) (xy 162.786238 -385.111679) (xy 162.820206 -385.077744)
			(xy 162.859067 -385.049543) (xy 162.901864 -385.027773) (xy 162.94754 -385.012969) (xy 162.99497 -385.005497)
			(xy 163.018978 -385.005072) (xy 163.042913 -385.005516) (xy 163.090199 -385.012978) (xy 163.135743 -385.027723)
			(xy 163.178429 -385.049391) (xy 163.217215 -385.07745) (xy 163.251149 -385.111214) (xy 163.279404 -385.149858)
			(xy 163.290758 -385.170934) (xy 163.291266 -385.17195) (xy 163.371572 -385.310888) (xy 163.913312 -385.310888)
			(xy 163.913312 -385.31038) (xy 163.913721 -385.286373) (xy 163.921239 -385.23895) (xy 163.936087 -385.193289)
			(xy 163.957899 -385.150514) (xy 163.986137 -385.111681) (xy 164.020104 -385.077745) (xy 164.058965 -385.049545)
			(xy 164.101761 -385.027774) (xy 164.147436 -385.01297) (xy 164.194866 -385.005498) (xy 164.218874 -385.005072)
			(xy 164.242809 -385.005519) (xy 164.290095 -385.012981) (xy 164.335638 -385.027726) (xy 164.378325 -385.049392)
			(xy 164.41711 -385.077451) (xy 164.451045 -385.111215) (xy 164.479299 -385.149858) (xy 164.490654 -385.170934)
			(xy 164.491162 -385.17195) (xy 164.571468 -385.310888) (xy 165.113716 -385.310888) (xy 165.113716 -385.31038)
			(xy 165.11412 -385.286385) (xy 165.12163 -385.238987) (xy 165.136463 -385.193347) (xy 165.158253 -385.150589)
			(xy 165.186463 -385.111766) (xy 165.2204 -385.077835) (xy 165.259226 -385.04963) (xy 165.301987 -385.027846)
			(xy 165.347629 -385.01302) (xy 165.395029 -385.005516) (xy 165.419024 -385.005072) (xy 165.442958 -385.00556)
			(xy 165.490242 -385.013014) (xy 165.535784 -385.027751) (xy 165.578471 -385.049411) (xy 165.617257 -385.077464)
			(xy 165.651193 -385.111222) (xy 165.679449 -385.14986) (xy 165.690804 -385.170934) (xy 165.691312 -385.17195)
			(xy 166.083742 -385.850892) (xy 166.096567 -385.874224) (xy 166.114787 -385.924247) (xy 166.124047 -385.976673)
			(xy 166.124636 -386.003292) (xy 166.124154 -386.027296) (xy 166.116641 -386.074713) (xy 166.1018 -386.12037)
			(xy 166.079996 -386.163141) (xy 166.051766 -386.201973) (xy 166.017807 -386.235908) (xy 165.978955 -386.26411)
			(xy 165.936168 -386.285883) (xy 165.890501 -386.300692) (xy 165.843079 -386.308171) (xy 165.819074 -386.3086)
			(xy 165.795499 -386.308227) (xy 165.74891 -386.300982) (xy 165.703991 -386.286652) (xy 165.661813 -386.26558)
			(xy 165.62338 -386.238267) (xy 165.589609 -386.205365) (xy 165.561304 -386.167657) (xy 165.549834 -386.147056)
			(xy 165.549326 -386.146294) (xy 165.151562 -385.457954) (xy 165.139704 -385.435268) (xy 165.122846 -385.38694)
			(xy 165.114266 -385.33648) (xy 165.113716 -385.310888) (xy 164.571468 -385.310888) (xy 164.883592 -385.850892)
			(xy 164.896342 -385.874249) (xy 164.914451 -385.924281) (xy 164.923654 -385.976688) (xy 164.924232 -386.003292)
			(xy 164.92373 -386.027282) (xy 164.916226 -386.074671) (xy 164.901401 -386.120303) (xy 164.879621 -386.163054)
			(xy 164.851421 -386.201871) (xy 164.817496 -386.2358) (xy 164.778681 -386.264004) (xy 164.735932 -386.285789)
			(xy 164.690302 -386.300618) (xy 164.642914 -386.308128) (xy 164.618924 -386.3086) (xy 164.595351 -386.308187)
			(xy 164.548763 -386.300949) (xy 164.503845 -386.286627) (xy 164.461667 -386.265561) (xy 164.423233 -386.238255)
			(xy 164.389461 -386.205358) (xy 164.361155 -386.167655) (xy 164.349684 -386.147056) (xy 164.349176 -386.146294)
			(xy 163.951412 -385.457954) (xy 163.939479 -385.435295) (xy 163.922547 -385.386965) (xy 163.913895 -385.336491)
			(xy 163.913312 -385.310888) (xy 163.371572 -385.310888) (xy 163.683696 -385.850892) (xy 163.696446 -385.874249)
			(xy 163.714555 -385.924281) (xy 163.723758 -385.976688) (xy 163.724336 -386.003292) (xy 163.72383 -386.027282)
			(xy 163.716326 -386.07467) (xy 163.701501 -386.120302) (xy 163.679721 -386.163053) (xy 163.651522 -386.20187)
			(xy 163.617597 -386.235798) (xy 163.578783 -386.264002) (xy 163.536035 -386.285788) (xy 163.490405 -386.300618)
			(xy 163.443018 -386.308127) (xy 163.419028 -386.3086) (xy 163.395455 -386.308184) (xy 163.348868 -386.300946)
			(xy 163.30395 -386.286625) (xy 163.261771 -386.26556) (xy 163.223338 -386.238254) (xy 163.189565 -386.205357)
			(xy 163.161259 -386.167654) (xy 163.149788 -386.147056) (xy 163.14928 -386.146294) (xy 162.751516 -385.457954)
			(xy 162.739583 -385.435294) (xy 162.722652 -385.386965) (xy 162.713999 -385.336491) (xy 162.713416 -385.310888)
			(xy 162.171422 -385.310888) (xy 162.483546 -385.850892) (xy 162.496371 -385.874224) (xy 162.514591 -385.924247)
			(xy 162.523851 -385.976673) (xy 162.52444 -386.003292) (xy 162.523954 -386.027296) (xy 162.516441 -386.074713)
			(xy 162.5016 -386.120369) (xy 162.479796 -386.16314) (xy 162.451567 -386.201972) (xy 162.417609 -386.235907)
			(xy 162.378757 -386.264108) (xy 162.335971 -386.285882) (xy 162.290304 -386.300691) (xy 162.242882 -386.30817)
			(xy 162.218878 -386.3086) (xy 162.195303 -386.308224) (xy 162.148714 -386.300979) (xy 162.103795 -386.28665)
			(xy 162.061617 -386.265579) (xy 162.023184 -386.238266) (xy 161.989413 -386.205364) (xy 161.961108 -386.167657)
			(xy 161.949638 -386.147056) (xy 161.94913 -386.146294) (xy 161.551366 -385.457954) (xy 161.539508 -385.435268)
			(xy 161.52265 -385.38694) (xy 161.51407 -385.33648) (xy 161.51352 -385.310888) (xy 160.971526 -385.310888)
			(xy 161.28365 -385.850892) (xy 161.296476 -385.874224) (xy 161.314695 -385.924247) (xy 161.323955 -385.976673)
			(xy 161.324544 -386.003292) (xy 161.324054 -386.027296) (xy 161.316541 -386.074712) (xy 161.301701 -386.120368)
			(xy 161.279897 -386.163139) (xy 161.251669 -386.20197) (xy 161.21771 -386.235905) (xy 161.17886 -386.264107)
			(xy 161.136074 -386.285881) (xy 161.090407 -386.30069) (xy 161.042986 -386.30817) (xy 161.018982 -386.3086)
			(xy 160.995407 -386.308221) (xy 160.948819 -386.300977) (xy 160.9039 -386.286648) (xy 160.861721 -386.265577)
			(xy 160.823288 -386.238265) (xy 160.789517 -386.205364) (xy 160.761212 -386.167657) (xy 160.749742 -386.147056)
			(xy 160.749234 -386.146294) (xy 160.35147 -385.457954) (xy 160.339612 -385.435268) (xy 160.322755 -385.386939)
			(xy 160.314174 -385.33648) (xy 160.313624 -385.310888) (xy 159.77163 -385.310888) (xy 160.083754 -385.850892)
			(xy 160.09654 -385.874242) (xy 160.114739 -385.924265) (xy 160.124031 -385.976678) (xy 160.124648 -386.003292)
			(xy 160.124201 -386.027299) (xy 160.116688 -386.074723) (xy 160.101845 -386.120386) (xy 160.080039 -386.163163)
			(xy 160.051806 -386.202) (xy 160.017843 -386.23594) (xy 159.978987 -386.264147) (xy 159.936195 -386.285924)
			(xy 159.890522 -386.300736) (xy 159.843094 -386.308218) (xy 159.819086 -386.3086) (xy 159.800549 -386.30834)
			(xy 159.763744 -386.30388) (xy 159.74568 -386.29971) (xy 159.732726 -386.296662) (xy 159.707072 -386.303774)
			(xy 159.697674 -386.313172) (xy 159.690838 -386.320538) (xy 159.683103 -386.339069) (xy 159.683107 -386.359149)
			(xy 159.690849 -386.377677) (xy 159.697674 -386.385054) (xy 160.075626 -386.763006) (xy 160.102296 -386.769864)
			(xy 160.115504 -386.766054) (xy 160.137705 -386.760131) (xy 160.183208 -386.75375) (xy 160.206182 -386.753354)
			(xy 160.232171 -386.753862) (xy 160.28351 -386.76199) (xy 160.332945 -386.778049) (xy 160.37926 -386.801643)
			(xy 160.421314 -386.832192) (xy 160.458071 -386.868943) (xy 160.488627 -386.910992) (xy 160.512229 -386.957303)
			(xy 160.528297 -387.006735) (xy 160.536433 -387.058073) (xy 160.53689 -387.084062) (xy 160.5365 -387.107037)
			(xy 160.530133 -387.152544) (xy 160.52419 -387.17474) (xy 160.52038 -387.187948) (xy 160.527238 -387.214618)
			(xy 160.929828 -387.617208) (xy 160.942014 -387.629859) (xy 160.963163 -387.657903) (xy 160.971992 -387.673088)
			(xy 160.97885 -387.68528) (xy 161.002218 -387.698996) (xy 164.950902 -387.698996) (xy 164.975859 -387.699608)
			(xy 165.024813 -387.709345) (xy 165.070926 -387.728446) (xy 165.112428 -387.756177) (xy 165.13048 -387.773418)
			(xy 166.37254 -389.015478) (xy 166.37994 -389.022321) (xy 166.398538 -389.030044) (xy 166.408608 -389.030464)
			(xy 167.118284 -389.030464)
		)
		(stroke
			(width 0)
			(type solid)
		)
		(fill yes)
		(layer "In9.Cu")
		(net "P1V8_CPU1_RT2_1A")
	)
	(gr_poly
		(pts
			(xy 531.7998 -462.519268) (xy 531.855569 -462.518759) (xy 531.966796 -462.510424) (xy 532.077089 -462.4938)
			(xy 532.185831 -462.46898) (xy 532.292414 -462.436103) (xy 532.396243 -462.395354) (xy 532.496736 -462.346959)
			(xy 532.593331 -462.291189) (xy 532.685488 -462.228357) (xy 532.772692 -462.158813) (xy 532.854456 -462.082947)
			(xy 532.930321 -462.001183) (xy 532.999864 -461.913979) (xy 533.062695 -461.821821) (xy 533.118464 -461.725225)
			(xy 533.166858 -461.624732) (xy 533.207607 -461.520903) (xy 533.240483 -461.41432) (xy 533.265302 -461.305577)
			(xy 533.281925 -461.195284) (xy 533.29026 -461.084057) (xy 533.29078 -461.028288) (xy 533.29078 -455.0283)
			(xy 533.290259 -454.972531) (xy 533.281923 -454.861305) (xy 533.265299 -454.751013) (xy 533.24048 -454.642271)
			(xy 533.207603 -454.535688) (xy 533.166854 -454.43186) (xy 533.118459 -454.331368) (xy 533.06269 -454.234773)
			(xy 532.999859 -454.142616) (xy 532.930316 -454.055412) (xy 532.854451 -453.973649) (xy 532.772688 -453.897784)
			(xy 532.685484 -453.828241) (xy 532.593327 -453.76541) (xy 532.496732 -453.709641) (xy 532.39624 -453.661246)
			(xy 532.292412 -453.620497) (xy 532.185829 -453.58762) (xy 532.077087 -453.562801) (xy 531.966795 -453.546177)
			(xy 531.855569 -453.537841) (xy 531.7998 -453.53732) (xy 516.019796 -453.53732) (xy 515.949414 -453.536826)
			(xy 515.808871 -453.528933) (xy 515.668991 -453.513172) (xy 515.530216 -453.489593) (xy 515.392981 -453.45827)
			(xy 515.257718 -453.419302) (xy 515.124852 -453.37281) (xy 514.994803 -453.318942) (xy 514.867978 -453.257866)
			(xy 514.744778 -453.189776) (xy 514.625589 -453.114884) (xy 514.510787 -453.033428) (xy 514.400733 -452.945663)
			(xy 514.295773 -452.851865) (xy 514.196238 -452.75233) (xy 514.10244 -452.64737) (xy 514.014674 -452.537316)
			(xy 513.933218 -452.422514) (xy 513.858326 -452.303325) (xy 513.790236 -452.180125) (xy 513.72916 -452.053301)
			(xy 513.675292 -451.923251) (xy 513.6288 -451.790386) (xy 513.589831 -451.655123) (xy 513.558507 -451.517888)
			(xy 513.534928 -451.379113) (xy 513.519167 -451.239233) (xy 513.511274 -451.09869) (xy 513.510784 -451.028308)
			(xy 513.510784 -312.408316) (xy 513.511268 -312.337933) (xy 513.51916 -312.197389) (xy 513.53492 -312.057508)
			(xy 513.558498 -311.918731) (xy 513.589821 -311.781495) (xy 513.628789 -311.646231) (xy 513.67528 -311.513364)
			(xy 513.729148 -311.383313) (xy 513.790224 -311.256488) (xy 513.858314 -311.133286) (xy 513.933205 -311.014096)
			(xy 514.014662 -310.899292) (xy 514.102427 -310.789237) (xy 514.196225 -310.684276) (xy 514.295761 -310.584739)
			(xy 514.400722 -310.49094) (xy 514.510776 -310.403174) (xy 514.625579 -310.321716) (xy 514.744769 -310.246824)
			(xy 514.86797 -310.178733) (xy 514.994795 -310.117656) (xy 515.124845 -310.063787) (xy 515.257712 -310.017295)
			(xy 515.392976 -309.978326) (xy 515.530212 -309.947002) (xy 515.668989 -309.923423) (xy 515.808869 -309.907662)
			(xy 515.949413 -309.899769) (xy 516.019796 -309.899304) (xy 531.7998 -309.899304) (xy 531.855569 -309.898783)
			(xy 531.966796 -309.890447) (xy 532.077089 -309.873823) (xy 532.185831 -309.849004) (xy 532.292415 -309.816128)
			(xy 532.396243 -309.775378) (xy 532.496737 -309.726984) (xy 532.593332 -309.671215) (xy 532.68549 -309.608384)
			(xy 532.772695 -309.538841) (xy 532.854459 -309.462976) (xy 532.930326 -309.381213) (xy 532.99987 -309.294009)
			(xy 533.062703 -309.201852) (xy 533.118473 -309.105258) (xy 533.166869 -309.004765) (xy 533.20762 -308.900937)
			(xy 533.240498 -308.794355) (xy 533.265319 -308.685613) (xy 533.281945 -308.57532) (xy 533.290282 -308.464093)
			(xy 533.29078 -308.408324) (xy 533.29078 10.40003) (xy 533.290257 10.455798) (xy 533.28192 10.567023)
			(xy 533.265294 10.677313) (xy 533.240473 10.786053) (xy 533.207596 10.892634) (xy 533.166845 10.99646)
			(xy 533.11845 11.09695) (xy 533.06268 11.193543) (xy 532.999848 11.285698) (xy 532.930305 11.3729)
			(xy 532.85444 11.454661) (xy 532.772677 11.530525) (xy 532.685474 11.600066) (xy 532.593318 11.662896)
			(xy 532.496724 11.718664) (xy 532.396232 11.767057) (xy 532.292406 11.807806) (xy 532.185824 11.840681)
			(xy 532.077084 11.8655) (xy 531.966793 11.882123) (xy 531.855568 11.890459) (xy 531.7998 11.89101)
			(xy 475.799912 11.89101) (xy 475.744142 11.890489) (xy 475.632915 11.882155) (xy 475.522621 11.865531)
			(xy 475.413878 11.840713) (xy 475.307293 11.807837) (xy 475.203464 11.767088) (xy 475.10297 11.718694)
			(xy 475.006373 11.662926) (xy 474.914214 11.600094) (xy 474.827008 11.530552) (xy 474.745243 11.454687)
			(xy 474.669376 11.372924) (xy 474.599831 11.28572) (xy 474.536997 11.193563) (xy 474.481225 11.096967)
			(xy 474.432829 10.996475) (xy 474.392077 10.892646) (xy 474.359198 10.786063) (xy 474.334376 10.67732)
			(xy 474.31775 10.567027) (xy 474.309413 10.4558) (xy 474.308932 10.40003) (xy 474.308932 7.335466)
			(xy 526.704041 7.335466) (xy 526.704041 7.464606) (xy 526.711991 7.593501) (xy 526.727861 7.721661)
			(xy 526.75159 7.848602) (xy 526.783089 7.973841) (xy 526.822238 8.096904) (xy 526.868889 8.217323)
			(xy 526.922864 8.334642) (xy 526.983959 8.448416) (xy 527.051942 8.558213) (xy 527.126556 8.663616)
			(xy 527.207517 8.764226) (xy 527.294517 8.859661) (xy 527.387228 8.94956) (xy 527.485298 9.033581)
			(xy 527.588353 9.111405) (xy 527.696004 9.182737) (xy 527.807843 9.247307) (xy 527.923444 9.304869)
			(xy 528.042369 9.355206) (xy 528.164168 9.398126) (xy 528.288378 9.433467) (xy 528.414527 9.461094)
			(xy 528.542139 9.480903) (xy 528.670728 9.492819) (xy 528.799806 9.496796) (xy 528.928884 9.492819)
			(xy 529.057473 9.480903) (xy 529.185085 9.461094) (xy 529.311234 9.433467) (xy 529.435444 9.398126)
			(xy 529.557243 9.355206) (xy 529.676168 9.304869) (xy 529.791769 9.247307) (xy 529.903608 9.182737)
			(xy 530.011259 9.111405) (xy 530.114314 9.033581) (xy 530.212384 8.94956) (xy 530.305095 8.859661)
			(xy 530.392095 8.764226) (xy 530.473056 8.663616) (xy 530.54767 8.558213) (xy 530.615653 8.448416)
			(xy 530.676748 8.334642) (xy 530.730723 8.217323) (xy 530.777374 8.096904) (xy 530.816523 7.973841)
			(xy 530.848022 7.848602) (xy 530.871751 7.721661) (xy 530.887621 7.593501) (xy 530.895571 7.464606)
			(xy 530.896068 7.400036) (xy 530.895571 7.335466) (xy 530.887621 7.206571) (xy 530.871751 7.078411)
			(xy 530.848022 6.95147) (xy 530.816523 6.826231) (xy 530.777374 6.703168) (xy 530.730723 6.582749)
			(xy 530.676748 6.46543) (xy 530.615653 6.351656) (xy 530.54767 6.241859) (xy 530.473056 6.136456)
			(xy 530.392095 6.035846) (xy 530.305095 5.940411) (xy 530.212384 5.850512) (xy 530.114314 5.766491)
			(xy 530.011259 5.688667) (xy 529.903608 5.617335) (xy 529.791769 5.552765) (xy 529.676168 5.495203)
			(xy 529.557243 5.444866) (xy 529.435444 5.401946) (xy 529.311234 5.366605) (xy 529.185085 5.338978)
			(xy 529.057473 5.319169) (xy 528.928884 5.307253) (xy 528.799806 5.303277) (xy 528.670728 5.307253)
			(xy 528.542139 5.319169) (xy 528.414527 5.338978) (xy 528.288378 5.366605) (xy 528.164168 5.401946)
			(xy 528.042369 5.444866) (xy 527.923444 5.495203) (xy 527.807843 5.552765) (xy 527.696004 5.617335)
			(xy 527.588353 5.688667) (xy 527.485298 5.766491) (xy 527.387228 5.850512) (xy 527.294517 5.940411)
			(xy 527.207517 6.035846) (xy 527.126556 6.136456) (xy 527.051942 6.241859) (xy 526.983959 6.351656)
			(xy 526.922864 6.46543) (xy 526.868889 6.582749) (xy 526.822238 6.703168) (xy 526.783089 6.826231)
			(xy 526.75159 6.95147) (xy 526.727861 7.078411) (xy 526.711991 7.206571) (xy 526.704041 7.335466)
			(xy 474.308932 7.335466) (xy 474.308932 -12.515904) (xy 476.704141 -12.515904) (xy 476.704141 -12.386764)
			(xy 476.712091 -12.257869) (xy 476.727961 -12.129709) (xy 476.75169 -12.002768) (xy 476.783189 -11.877529)
			(xy 476.822338 -11.754466) (xy 476.868989 -11.634047) (xy 476.922964 -11.516728) (xy 476.984059 -11.402954)
			(xy 477.052042 -11.293157) (xy 477.126656 -11.187754) (xy 477.207617 -11.087144) (xy 477.294617 -10.991709)
			(xy 477.387328 -10.90181) (xy 477.485398 -10.817789) (xy 477.588453 -10.739965) (xy 477.696104 -10.668633)
			(xy 477.807943 -10.604063) (xy 477.923544 -10.546501) (xy 478.042469 -10.496164) (xy 478.164268 -10.453244)
			(xy 478.288478 -10.417903) (xy 478.414627 -10.390276) (xy 478.542239 -10.370467) (xy 478.670828 -10.358551)
			(xy 478.799906 -10.354575) (xy 478.928984 -10.358551) (xy 479.057573 -10.370467) (xy 479.185185 -10.390276)
			(xy 479.311334 -10.417903) (xy 479.435544 -10.453244) (xy 479.557343 -10.496164) (xy 479.676268 -10.546501)
			(xy 479.791869 -10.604063) (xy 479.903708 -10.668633) (xy 480.011359 -10.739965) (xy 480.114414 -10.817789)
			(xy 480.212484 -10.90181) (xy 480.305195 -10.991709) (xy 480.392195 -11.087144) (xy 480.473156 -11.187754)
			(xy 480.54777 -11.293157) (xy 480.615753 -11.402954) (xy 480.676848 -11.516728) (xy 480.730823 -11.634047)
			(xy 480.777474 -11.754466) (xy 480.816623 -11.877529) (xy 480.848122 -12.002768) (xy 480.871851 -12.129709)
			(xy 480.887721 -12.257869) (xy 480.895671 -12.386764) (xy 480.896168 -12.451334) (xy 480.895671 -12.515904)
			(xy 480.887721 -12.644799) (xy 480.871851 -12.772959) (xy 480.848122 -12.8999) (xy 480.816623 -13.025139)
			(xy 480.777474 -13.148202) (xy 480.730823 -13.268621) (xy 480.676848 -13.38594) (xy 480.615753 -13.499714)
			(xy 480.54777 -13.609511) (xy 480.473156 -13.714914) (xy 480.392195 -13.815524) (xy 480.305195 -13.910959)
			(xy 480.212484 -14.000858) (xy 480.114414 -14.084879) (xy 480.011359 -14.162703) (xy 479.903708 -14.234035)
			(xy 479.791869 -14.298605) (xy 479.676268 -14.356167) (xy 479.557343 -14.406504) (xy 479.435544 -14.449424)
			(xy 479.311334 -14.484765) (xy 479.185185 -14.512392) (xy 479.057573 -14.532201) (xy 478.928984 -14.544117)
			(xy 478.799906 -14.548094) (xy 478.670828 -14.544117) (xy 478.542239 -14.532201) (xy 478.414627 -14.512392)
			(xy 478.288478 -14.484765) (xy 478.164268 -14.449424) (xy 478.042469 -14.406504) (xy 477.923544 -14.356167)
			(xy 477.807943 -14.298605) (xy 477.696104 -14.234035) (xy 477.588453 -14.162703) (xy 477.485398 -14.084879)
			(xy 477.387328 -14.000858) (xy 477.294617 -13.910959) (xy 477.207617 -13.815524) (xy 477.126656 -13.714914)
			(xy 477.052042 -13.609511) (xy 476.984059 -13.499714) (xy 476.922964 -13.38594) (xy 476.868989 -13.268621)
			(xy 476.822338 -13.148202) (xy 476.783189 -13.025139) (xy 476.75169 -12.8999) (xy 476.727961 -12.772959)
			(xy 476.712091 -12.644799) (xy 476.704141 -12.515904) (xy 474.308932 -12.515904) (xy 474.308932 -77.67193)
			(xy 474.308458 -77.765117) (xy 474.300759 -77.951331) (xy 474.28537 -78.137067) (xy 474.262318 -78.32201)
			(xy 474.231642 -78.505841) (xy 474.193396 -78.688247) (xy 474.147643 -78.868917) (xy 474.094463 -79.047542)
			(xy 474.033945 -79.223817) (xy 473.966195 -79.397439) (xy 473.891327 -79.568113) (xy 473.809469 -79.735548)
			(xy 473.720761 -79.899456) (xy 473.625355 -80.059558) (xy 473.523414 -80.21558) (xy 473.415112 -80.367256)
			(xy 473.300633 -80.514327) (xy 473.180175 -80.65654) (xy 473.053942 -80.793654) (xy 472.988386 -80.859884)
			(xy 471.245946 -82.602324) (xy 471.208633 -82.640304) (xy 471.138899 -82.72077) (xy 471.07508 -82.806006)
			(xy 471.017504 -82.895576) (xy 470.966464 -82.989025) (xy 470.922218 -83.085876) (xy 470.884993 -83.185636)
			(xy 470.854978 -83.287798) (xy 470.832326 -83.391839) (xy 470.817153 -83.497232) (xy 470.809535 -83.603438)
			(xy 470.809066 -83.656678) (xy 470.809066 -328.137828) (xy 473.204275 -328.137828) (xy 473.204275 -328.008688)
			(xy 473.212225 -327.879793) (xy 473.228095 -327.751633) (xy 473.251824 -327.624692) (xy 473.283323 -327.499453)
			(xy 473.322472 -327.37639) (xy 473.369123 -327.255971) (xy 473.423098 -327.138652) (xy 473.484193 -327.024878)
			(xy 473.552176 -326.915081) (xy 473.62679 -326.809678) (xy 473.707751 -326.709068) (xy 473.794751 -326.613633)
			(xy 473.887462 -326.523734) (xy 473.985532 -326.439713) (xy 474.088587 -326.361889) (xy 474.196238 -326.290557)
			(xy 474.308077 -326.225987) (xy 474.423678 -326.168425) (xy 474.542603 -326.118088) (xy 474.664402 -326.075168)
			(xy 474.788612 -326.039827) (xy 474.914761 -326.0122) (xy 475.042373 -325.992391) (xy 475.170962 -325.980475)
			(xy 475.30004 -325.976499) (xy 475.429118 -325.980475) (xy 475.557707 -325.992391) (xy 475.685319 -326.0122)
			(xy 475.811468 -326.039827) (xy 475.935678 -326.075168) (xy 476.057477 -326.118088) (xy 476.176402 -326.168425)
			(xy 476.292003 -326.225987) (xy 476.403842 -326.290557) (xy 476.511493 -326.361889) (xy 476.614548 -326.439713)
			(xy 476.712618 -326.523734) (xy 476.805329 -326.613633) (xy 476.892329 -326.709068) (xy 476.97329 -326.809678)
			(xy 477.047904 -326.915081) (xy 477.115887 -327.024878) (xy 477.176982 -327.138652) (xy 477.230957 -327.255971)
			(xy 477.277608 -327.37639) (xy 477.316757 -327.499453) (xy 477.348256 -327.624692) (xy 477.371985 -327.751633)
			(xy 477.387855 -327.879793) (xy 477.395805 -328.008688) (xy 477.396302 -328.073258) (xy 477.395805 -328.137828)
			(xy 477.387855 -328.266723) (xy 477.371985 -328.394883) (xy 477.348256 -328.521824) (xy 477.316757 -328.647063)
			(xy 477.277608 -328.770126) (xy 477.230957 -328.890545) (xy 477.176982 -329.007864) (xy 477.115887 -329.121638)
			(xy 477.047904 -329.231435) (xy 476.97329 -329.336838) (xy 476.892329 -329.437448) (xy 476.805329 -329.532883)
			(xy 476.712618 -329.622782) (xy 476.614548 -329.706803) (xy 476.511493 -329.784627) (xy 476.403842 -329.855959)
			(xy 476.292003 -329.920529) (xy 476.176402 -329.978091) (xy 476.057477 -330.028428) (xy 475.935678 -330.071348)
			(xy 475.811468 -330.106689) (xy 475.685319 -330.134316) (xy 475.557707 -330.154125) (xy 475.429118 -330.166041)
			(xy 475.30004 -330.170018) (xy 475.170962 -330.166041) (xy 475.042373 -330.154125) (xy 474.914761 -330.134316)
			(xy 474.788612 -330.106689) (xy 474.664402 -330.071348) (xy 474.542603 -330.028428) (xy 474.423678 -329.978091)
			(xy 474.308077 -329.920529) (xy 474.196238 -329.855959) (xy 474.088587 -329.784627) (xy 473.985532 -329.706803)
			(xy 473.887462 -329.622782) (xy 473.794751 -329.532883) (xy 473.707751 -329.437448) (xy 473.62679 -329.336838)
			(xy 473.552176 -329.231435) (xy 473.484193 -329.121638) (xy 473.423098 -329.007864) (xy 473.369123 -328.890545)
			(xy 473.322472 -328.770126) (xy 473.283323 -328.647063) (xy 473.251824 -328.521824) (xy 473.228095 -328.394883)
			(xy 473.212225 -328.266723) (xy 473.204275 -328.137828) (xy 470.809066 -328.137828) (xy 470.809066 -404.871936)
			(xy 470.808592 -404.965123) (xy 470.800892 -405.151337) (xy 470.785503 -405.337074) (xy 470.762451 -405.522016)
			(xy 470.731776 -405.705847) (xy 470.693529 -405.888254) (xy 470.647776 -406.068924) (xy 470.594596 -406.247549)
			(xy 470.534079 -406.423823) (xy 470.466329 -406.597446) (xy 470.391461 -406.76812) (xy 470.309603 -406.935555)
			(xy 470.220896 -407.099463) (xy 470.12549 -407.259566) (xy 470.02355 -407.415588) (xy 469.915248 -407.567265)
			(xy 469.80077 -407.714335) (xy 469.680312 -407.856549) (xy 469.554079 -407.993664) (xy 469.48852 -408.05989)
			(xy 468.245698 -409.302712) (xy 468.208406 -409.340689) (xy 468.138712 -409.421147) (xy 468.074932 -409.506369)
			(xy 468.017391 -409.595922) (xy 467.966382 -409.68935) (xy 467.922165 -409.786178) (xy 467.884964 -409.885911)
			(xy 467.85497 -409.988044) (xy 467.832334 -410.092055) (xy 467.817172 -410.197416) (xy 467.809562 -410.303589)
			(xy 467.809072 -410.356812) (xy 467.809072 -439.989976) (xy 467.809593 -440.045746) (xy 467.817926 -440.156975)
			(xy 467.834548 -440.26727) (xy 467.859367 -440.376014) (xy 467.892242 -440.4826) (xy 467.93299 -440.586431)
			(xy 467.981383 -440.686926) (xy 468.037152 -440.783525) (xy 468.099983 -440.875685) (xy 468.169525 -440.962893)
			(xy 468.24539 -441.044659) (xy 468.327153 -441.120528) (xy 468.414357 -441.190075) (xy 468.506514 -441.25291)
			(xy 468.60311 -441.308683) (xy 468.703603 -441.357081) (xy 468.807432 -441.397835) (xy 468.914016 -441.430715)
			(xy 469.022759 -441.455538) (xy 469.133053 -441.472166) (xy 469.244282 -441.480505) (xy 469.300052 -441.480956)
			(xy 471.79992 -441.480956) (xy 471.870302 -441.48145) (xy 472.010845 -441.489344) (xy 472.150724 -441.505105)
			(xy 472.2895 -441.528685) (xy 472.426735 -441.560009) (xy 472.561998 -441.598978) (xy 472.694863 -441.64547)
			(xy 472.824912 -441.699339) (xy 472.951736 -441.760414) (xy 473.074936 -441.828505) (xy 473.194125 -441.903396)
			(xy 473.308927 -441.984852) (xy 473.418981 -442.072617) (xy 473.523941 -442.166415) (xy 473.623477 -442.26595)
			(xy 473.717275 -442.37091) (xy 473.80504 -442.480964) (xy 473.886497 -442.595765) (xy 473.961389 -442.714953)
			(xy 474.02948 -442.838153) (xy 474.090556 -442.964977) (xy 474.144426 -443.095026) (xy 474.190918 -443.227891)
			(xy 474.229888 -443.363154) (xy 474.261212 -443.500389) (xy 474.284793 -443.639164) (xy 474.300555 -443.779043)
			(xy 474.308449 -443.919586) (xy 474.308932 -443.989968) (xy 474.308932 -458.092864) (xy 526.704041 -458.092864)
			(xy 526.704041 -457.963724) (xy 526.711991 -457.834829) (xy 526.727861 -457.706669) (xy 526.75159 -457.579728)
			(xy 526.783089 -457.454489) (xy 526.822238 -457.331426) (xy 526.868889 -457.211007) (xy 526.922864 -457.093688)
			(xy 526.983959 -456.979914) (xy 527.051942 -456.870117) (xy 527.126556 -456.764714) (xy 527.207517 -456.664104)
			(xy 527.294517 -456.568669) (xy 527.387228 -456.47877) (xy 527.485298 -456.394749) (xy 527.588353 -456.316925)
			(xy 527.696004 -456.245593) (xy 527.807843 -456.181023) (xy 527.923444 -456.123461) (xy 528.042369 -456.073124)
			(xy 528.164168 -456.030204) (xy 528.288378 -455.994863) (xy 528.414527 -455.967236) (xy 528.542139 -455.947427)
			(xy 528.670728 -455.935511) (xy 528.799806 -455.931535) (xy 528.928884 -455.935511) (xy 529.057473 -455.947427)
			(xy 529.185085 -455.967236) (xy 529.311234 -455.994863) (xy 529.435444 -456.030204) (xy 529.557243 -456.073124)
			(xy 529.676168 -456.123461) (xy 529.791769 -456.181023) (xy 529.903608 -456.245593) (xy 530.011259 -456.316925)
			(xy 530.114314 -456.394749) (xy 530.212384 -456.47877) (xy 530.305095 -456.568669) (xy 530.392095 -456.664104)
			(xy 530.473056 -456.764714) (xy 530.54767 -456.870117) (xy 530.615653 -456.979914) (xy 530.676748 -457.093688)
			(xy 530.730723 -457.211007) (xy 530.777374 -457.331426) (xy 530.816523 -457.454489) (xy 530.848022 -457.579728)
			(xy 530.871751 -457.706669) (xy 530.887621 -457.834829) (xy 530.895571 -457.963724) (xy 530.896068 -458.028294)
			(xy 530.895571 -458.092864) (xy 530.887621 -458.221759) (xy 530.871751 -458.349919) (xy 530.848022 -458.47686)
			(xy 530.816523 -458.602099) (xy 530.777374 -458.725162) (xy 530.730723 -458.845581) (xy 530.676748 -458.9629)
			(xy 530.615653 -459.076674) (xy 530.54767 -459.186471) (xy 530.473056 -459.291874) (xy 530.392095 -459.392484)
			(xy 530.305095 -459.487919) (xy 530.212384 -459.577818) (xy 530.114314 -459.661839) (xy 530.011259 -459.739663)
			(xy 529.903608 -459.810995) (xy 529.791769 -459.875565) (xy 529.676168 -459.933127) (xy 529.557243 -459.983464)
			(xy 529.435444 -460.026384) (xy 529.311234 -460.061725) (xy 529.185085 -460.089352) (xy 529.057473 -460.109161)
			(xy 528.928884 -460.121077) (xy 528.799806 -460.125054) (xy 528.670728 -460.121077) (xy 528.542139 -460.109161)
			(xy 528.414527 -460.089352) (xy 528.288378 -460.061725) (xy 528.164168 -460.026384) (xy 528.042369 -459.983464)
			(xy 527.923444 -459.933127) (xy 527.807843 -459.875565) (xy 527.696004 -459.810995) (xy 527.588353 -459.739663)
			(xy 527.485298 -459.661839) (xy 527.387228 -459.577818) (xy 527.294517 -459.487919) (xy 527.207517 -459.392484)
			(xy 527.126556 -459.291874) (xy 527.051942 -459.186471) (xy 526.983959 -459.076674) (xy 526.922864 -458.9629)
			(xy 526.868889 -458.845581) (xy 526.822238 -458.725162) (xy 526.783089 -458.602099) (xy 526.75159 -458.47686)
			(xy 526.727861 -458.349919) (xy 526.711991 -458.221759) (xy 526.704041 -458.092864) (xy 474.308932 -458.092864)
			(xy 474.308932 -461.028288) (xy 474.30944 -461.084058) (xy 474.317775 -461.195285) (xy 474.334398 -461.305579)
			(xy 474.359217 -461.414322) (xy 474.392093 -461.520906) (xy 474.432843 -461.624735) (xy 474.481238 -461.725228)
			(xy 474.537007 -461.821824) (xy 474.599839 -461.913982) (xy 474.669383 -462.001187) (xy 474.745248 -462.082952)
			(xy 474.827013 -462.158817) (xy 474.914218 -462.228361) (xy 475.006376 -462.291193) (xy 475.102972 -462.346962)
			(xy 475.203465 -462.395357) (xy 475.307294 -462.436107) (xy 475.413878 -462.468983) (xy 475.522621 -462.493802)
			(xy 475.632915 -462.510425) (xy 475.744142 -462.51876) (xy 475.799912 -462.519268)
		)
		(stroke
			(width 0)
			(type solid)
		)
		(fill yes)
		(layer "In9.Cu")
		(net "T1_GND")
	)
	(gr_poly
		(pts
			(xy 89.904316 -387.980428) (xy 89.914386 -387.980003) (xy 89.932988 -387.972287) (xy 89.940384 -387.965442)
			(xy 91.449144 -386.456682) (xy 91.454921 -386.45045) (xy 91.462341 -386.435172) (xy 91.464367 -386.418309)
			(xy 91.46286 -386.409946) (xy 91.441778 -386.31368) (xy 91.425014 -386.294122) (xy 91.412568 -386.28955)
			(xy 91.386842 -386.279344) (xy 91.339301 -386.251016) (xy 91.297655 -386.214571) (xy 91.263273 -386.171206)
			(xy 91.249754 -386.147056) (xy 91.249246 -386.146294) (xy 90.851482 -385.457954) (xy 90.839587 -385.435285)
			(xy 90.822718 -385.386954) (xy 90.814165 -385.336483) (xy 90.813636 -385.310888) (xy 90.813636 -385.31038)
			(xy 90.814084 -385.286389) (xy 90.821593 -385.238999) (xy 90.836424 -385.193366) (xy 90.858211 -385.150616)
			(xy 90.886418 -385.111801) (xy 90.92035 -385.077876) (xy 90.959171 -385.049678) (xy 91.001926 -385.0279)
			(xy 91.047561 -385.013078) (xy 91.094953 -385.005579) (xy 91.118944 -385.005072) (xy 91.142877 -385.00554)
			(xy 91.190156 -385.013009) (xy 91.235693 -385.027757) (xy 91.278374 -385.049424) (xy 91.317156 -385.077479)
			(xy 91.35109 -385.111237) (xy 91.379346 -385.149873) (xy 91.390724 -385.170934) (xy 91.391232 -385.17195)
			(xy 91.783662 -385.850892) (xy 91.796448 -385.874242) (xy 91.814647 -385.924265) (xy 91.823938 -385.976678)
			(xy 91.824556 -386.003292) (xy 91.824302 -386.013706) (xy 91.823794 -386.023866) (xy 91.830652 -386.042408)
			(xy 91.893136 -386.109972) (xy 91.910916 -386.118354) (xy 91.92133 -386.118608) (xy 91.946403 -386.120215)
			(xy 91.99567 -386.13006) (xy 92.042882 -386.147241) (xy 92.086954 -386.171364) (xy 92.126871 -386.201872)
			(xy 92.161717 -386.238065) (xy 92.1766 -386.258308) (xy 92.184172 -386.267899) (xy 92.205804 -386.279177)
			(xy 92.218002 -386.279898) (xy 92.420694 -386.279898) (xy 92.440506 -386.28066) (xy 92.450457 -386.280968)
			(xy 92.46939 -386.274875) (xy 92.484583 -386.26204) (xy 92.493756 -386.244392) (xy 92.495528 -386.224582)
			(xy 92.489636 -386.205586) (xy 92.483686 -386.197602) (xy 92.474143 -386.185734) (xy 92.457222 -386.160411)
			(xy 92.449904 -386.147056) (xy 92.449396 -386.146294) (xy 92.051632 -385.457954) (xy 92.039697 -385.435294)
			(xy 92.022742 -385.38697) (xy 92.014093 -385.336493) (xy 92.013532 -385.310888) (xy 92.013532 -385.31038)
			(xy 92.013981 -385.286376) (xy 92.021498 -385.238961) (xy 92.036344 -385.193307) (xy 92.058154 -385.15054)
			(xy 92.086388 -385.111713) (xy 92.120352 -385.077784) (xy 92.159208 -385.049589) (xy 92.201998 -385.027824)
			(xy 92.247667 -385.013025) (xy 92.29509 -385.005556) (xy 92.319094 -385.005072) (xy 92.343029 -385.005536)
			(xy 92.390313 -385.012998) (xy 92.435856 -385.027741) (xy 92.478543 -385.049404) (xy 92.517331 -385.077458)
			(xy 92.551271 -385.111216) (xy 92.579533 -385.149852) (xy 92.590874 -385.170934) (xy 92.591382 -385.17195)
			(xy 92.671688 -385.310888) (xy 93.213428 -385.310888) (xy 93.213428 -385.31038) (xy 93.213821 -385.286372)
			(xy 93.221339 -385.238948) (xy 93.236188 -385.193285) (xy 93.258002 -385.150509) (xy 93.286241 -385.111675)
			(xy 93.320211 -385.07774) (xy 93.359074 -385.049539) (xy 93.401872 -385.02777) (xy 93.44755 -385.012967)
			(xy 93.494981 -385.005497) (xy 93.51899 -385.005072) (xy 93.542926 -385.005506) (xy 93.590212 -385.01297)
			(xy 93.635756 -385.027717) (xy 93.678442 -385.049386) (xy 93.717227 -385.077447) (xy 93.751162 -385.111213)
			(xy 93.779416 -385.149857) (xy 93.79077 -385.170934) (xy 93.791278 -385.17195) (xy 93.871584 -385.310888)
			(xy 94.413324 -385.310888) (xy 94.413324 -385.31038) (xy 94.413721 -385.286372) (xy 94.421239 -385.238948)
			(xy 94.436088 -385.193286) (xy 94.457901 -385.15051) (xy 94.48614 -385.111676) (xy 94.520109 -385.077741)
			(xy 94.558972 -385.049541) (xy 94.601769 -385.027771) (xy 94.647446 -385.012968) (xy 94.694878 -385.005497)
			(xy 94.718886 -385.005072) (xy 94.742822 -385.00551) (xy 94.790108 -385.012973) (xy 94.835651 -385.027719)
			(xy 94.878338 -385.049388) (xy 94.917123 -385.077448) (xy 94.951058 -385.111213) (xy 94.979312 -385.149858)
			(xy 94.990666 -385.170934) (xy 94.991174 -385.17195) (xy 95.07148 -385.310888) (xy 95.613728 -385.310888)
			(xy 95.613728 -385.31038) (xy 95.61412 -385.286385) (xy 95.621631 -385.238985) (xy 95.636464 -385.193344)
			(xy 95.658255 -385.150585) (xy 95.686467 -385.111762) (xy 95.720405 -385.07783) (xy 95.759233 -385.049626)
			(xy 95.801996 -385.027843) (xy 95.847639 -385.013018) (xy 95.89504 -385.005515) (xy 95.919036 -385.005072)
			(xy 95.94297 -385.00555) (xy 95.990254 -385.013006) (xy 96.035797 -385.027745) (xy 96.078484 -385.049407)
			(xy 96.117269 -385.077461) (xy 96.151205 -385.11122) (xy 96.179461 -385.14986) (xy 96.190816 -385.170934)
			(xy 96.191324 -385.17195) (xy 96.27163 -385.310888) (xy 96.813624 -385.310888) (xy 96.813624 -385.31038)
			(xy 96.81402 -385.286385) (xy 96.821531 -385.238985) (xy 96.836364 -385.193345) (xy 96.858154 -385.150586)
			(xy 96.886366 -385.111764) (xy 96.920303 -385.077832) (xy 96.959131 -385.049627) (xy 97.001893 -385.027844)
			(xy 97.047536 -385.013018) (xy 97.094937 -385.005516) (xy 97.118932 -385.005072) (xy 97.142866 -385.005554)
			(xy 97.19015 -385.013009) (xy 97.235693 -385.027747) (xy 97.278379 -385.049408) (xy 97.317165 -385.077462)
			(xy 97.351101 -385.111221) (xy 97.379357 -385.14986) (xy 97.390712 -385.170934) (xy 97.39122 -385.17195)
			(xy 97.471526 -385.310888) (xy 98.01352 -385.310888) (xy 98.01352 -385.31038) (xy 98.013921 -385.286372)
			(xy 98.021439 -385.238949) (xy 98.036288 -385.193287) (xy 98.0581 -385.150512) (xy 98.086339 -385.111678)
			(xy 98.120308 -385.077742) (xy 98.15917 -385.049542) (xy 98.201966 -385.027772) (xy 98.247643 -385.012969)
			(xy 98.295074 -385.005497) (xy 98.319082 -385.005072) (xy 98.343018 -385.005513) (xy 98.390303 -385.012976)
			(xy 98.435847 -385.027721) (xy 98.478534 -385.049389) (xy 98.517319 -385.077449) (xy 98.551254 -385.111214)
			(xy 98.579508 -385.149858) (xy 98.590862 -385.170934) (xy 98.59137 -385.17195) (xy 98.9838 -385.850892)
			(xy 98.99655 -385.874249) (xy 99.01466 -385.924281) (xy 99.023862 -385.976688) (xy 99.02444 -386.003292)
			(xy 99.02393 -386.027281) (xy 99.016426 -386.07467) (xy 99.001602 -386.120301) (xy 98.979822 -386.163051)
			(xy 98.951623 -386.201869) (xy 98.917699 -386.235797) (xy 98.878886 -386.264001) (xy 98.836138 -386.285787)
			(xy 98.790509 -386.300617) (xy 98.743121 -386.308127) (xy 98.719132 -386.3086) (xy 98.695559 -386.30818)
			(xy 98.648972 -386.300944) (xy 98.604054 -386.286623) (xy 98.561875 -386.265558) (xy 98.523442 -386.238253)
			(xy 98.48967 -386.205357) (xy 98.461363 -386.167654) (xy 98.449892 -386.147056) (xy 98.449384 -386.146294)
			(xy 98.05162 -385.457954) (xy 98.039687 -385.435294) (xy 98.022756 -385.386965) (xy 98.014103 -385.336491)
			(xy 98.01352 -385.310888) (xy 97.471526 -385.310888) (xy 97.78365 -385.850892) (xy 97.796476 -385.874224)
			(xy 97.814695 -385.924247) (xy 97.823955 -385.976673) (xy 97.824544 -386.003292) (xy 97.824054 -386.027296)
			(xy 97.816541 -386.074712) (xy 97.801701 -386.120368) (xy 97.779897 -386.163139) (xy 97.751669 -386.20197)
			(xy 97.71771 -386.235905) (xy 97.67886 -386.264107) (xy 97.636074 -386.285881) (xy 97.590407 -386.30069)
			(xy 97.542986 -386.30817) (xy 97.518982 -386.3086) (xy 97.495407 -386.308221) (xy 97.448819 -386.300977)
			(xy 97.4039 -386.286648) (xy 97.361721 -386.265577) (xy 97.323288 -386.238265) (xy 97.289517 -386.205364)
			(xy 97.261212 -386.167657) (xy 97.249742 -386.147056) (xy 97.249234 -386.146294) (xy 96.85147 -385.457954)
			(xy 96.839612 -385.435268) (xy 96.822755 -385.386939) (xy 96.814174 -385.33648) (xy 96.813624 -385.310888)
			(xy 96.27163 -385.310888) (xy 96.583754 -385.850892) (xy 96.59658 -385.874224) (xy 96.614799 -385.924247)
			(xy 96.624059 -385.976673) (xy 96.624648 -386.003292) (xy 96.624154 -386.027296) (xy 96.616641 -386.074711)
			(xy 96.601801 -386.120367) (xy 96.579998 -386.163138) (xy 96.55177 -386.201969) (xy 96.517812 -386.235904)
			(xy 96.478962 -386.264106) (xy 96.436177 -386.28588) (xy 96.390511 -386.30069) (xy 96.34309 -386.30817)
			(xy 96.319086 -386.3086) (xy 96.295512 -386.308217) (xy 96.248923 -386.300974) (xy 96.204004 -386.286646)
			(xy 96.161826 -386.265576) (xy 96.123393 -386.238264) (xy 96.089621 -386.205363) (xy 96.061316 -386.167656)
			(xy 96.049846 -386.147056) (xy 96.049338 -386.146294) (xy 95.651574 -385.457954) (xy 95.639717 -385.435268)
			(xy 95.622859 -385.386939) (xy 95.614278 -385.336479) (xy 95.613728 -385.310888) (xy 95.07148 -385.310888)
			(xy 95.383604 -385.850892) (xy 95.396355 -385.874249) (xy 95.414464 -385.924281) (xy 95.423666 -385.976688)
			(xy 95.424244 -386.003292) (xy 95.42373 -386.027281) (xy 95.416226 -386.074669) (xy 95.401402 -386.1203)
			(xy 95.379623 -386.16305) (xy 95.351424 -386.201867) (xy 95.317501 -386.235796) (xy 95.278688 -386.264)
			(xy 95.235941 -386.285785) (xy 95.190312 -386.300616) (xy 95.142925 -386.308127) (xy 95.118936 -386.3086)
			(xy 95.095363 -386.308177) (xy 95.048776 -386.300941) (xy 95.003858 -386.286621) (xy 94.96168 -386.265557)
			(xy 94.923246 -386.238252) (xy 94.889474 -386.205356) (xy 94.861167 -386.167654) (xy 94.849696 -386.147056)
			(xy 94.849188 -386.146294) (xy 94.451424 -385.457954) (xy 94.439492 -385.435294) (xy 94.42256 -385.386965)
			(xy 94.413907 -385.336491) (xy 94.413324 -385.310888) (xy 93.871584 -385.310888) (xy 94.183708 -385.850892)
			(xy 94.196459 -385.874248) (xy 94.214568 -385.924281) (xy 94.22377 -385.976688) (xy 94.224348 -386.003292)
			(xy 94.22383 -386.027281) (xy 94.216326 -386.074669) (xy 94.201503 -386.120299) (xy 94.179724 -386.163049)
			(xy 94.151525 -386.201866) (xy 94.117603 -386.235794) (xy 94.07879 -386.263998) (xy 94.036043 -386.285784)
			(xy 93.990415 -386.300615) (xy 93.943029 -386.308126) (xy 93.91904 -386.3086) (xy 93.895467 -386.308174)
			(xy 93.84888 -386.300939) (xy 93.803963 -386.286618) (xy 93.761784 -386.265555) (xy 93.723351 -386.238251)
			(xy 93.689578 -386.205355) (xy 93.661271 -386.167654) (xy 93.6498 -386.147056) (xy 93.649292 -386.146294)
			(xy 93.251528 -385.457954) (xy 93.239596 -385.435294) (xy 93.222664 -385.386965) (xy 93.214011 -385.336491)
			(xy 93.213428 -385.310888) (xy 92.671688 -385.310888) (xy 92.983812 -385.850892) (xy 92.996616 -385.874226)
			(xy 93.014757 -385.924258) (xy 93.023933 -385.976681) (xy 93.024452 -386.003292) (xy 93.023982 -386.027285)
			(xy 93.016477 -386.07468) (xy 93.001651 -386.120318) (xy 92.979869 -386.163075) (xy 92.951666 -386.201898)
			(xy 92.917738 -386.235832) (xy 92.878919 -386.264041) (xy 92.836166 -386.285831) (xy 92.790531 -386.300665)
			(xy 92.743137 -386.308178) (xy 92.719144 -386.3086) (xy 92.709531 -386.308554) (xy 92.69034 -386.30741)
			(xy 92.68079 -386.306314) (xy 92.669106 -386.30479) (xy 92.647008 -386.31241) (xy 92.638626 -386.320792)
			(xy 92.631789 -386.328156) (xy 92.624053 -386.346684) (xy 92.624062 -386.366762) (xy 92.631815 -386.385283)
			(xy 92.638626 -386.392674) (xy 93.001592 -386.75564) (xy 93.025976 -386.763006) (xy 93.038676 -386.760212)
			(xy 93.055377 -386.756967) (xy 93.089227 -386.753529) (xy 93.10624 -386.753354) (xy 93.132226 -386.753866)
			(xy 93.183558 -386.762002) (xy 93.232986 -386.778066) (xy 93.279292 -386.801663) (xy 93.321338 -386.832213)
			(xy 93.358088 -386.868963) (xy 93.388638 -386.911009) (xy 93.412235 -386.957316) (xy 93.428299 -387.006744)
			(xy 93.436434 -387.058076) (xy 93.436948 -387.084062) (xy 93.436755 -387.101074) (xy 93.433318 -387.134922)
			(xy 93.43009 -387.151626) (xy 93.427296 -387.164326) (xy 93.434662 -387.18871) (xy 93.895418 -387.649466)
			(xy 93.902816 -387.656313) (xy 93.921414 -387.664047) (xy 93.931486 -387.664452) (xy 94.091506 -387.664452)
			(xy 94.119192 -387.6421) (xy 94.123002 -387.62432) (xy 94.12906 -387.598556) (xy 94.148257 -387.549238)
			(xy 94.175063 -387.503606) (xy 94.208795 -387.462827) (xy 94.248591 -387.42794) (xy 94.293436 -387.399836)
			(xy 94.342183 -387.379234) (xy 94.39359 -387.366658) (xy 94.446344 -387.36243) (xy 94.499098 -387.366658)
			(xy 94.550505 -387.379234) (xy 94.599252 -387.399836) (xy 94.644097 -387.42794) (xy 94.683893 -387.462827)
			(xy 94.717625 -387.503606) (xy 94.744431 -387.549238) (xy 94.763628 -387.598556) (xy 94.769686 -387.62432)
			(xy 94.773496 -387.6421) (xy 94.801182 -387.664452) (xy 95.291402 -387.664452) (xy 95.319088 -387.6421)
			(xy 95.322898 -387.62432) (xy 95.328956 -387.598556) (xy 95.348153 -387.549238) (xy 95.374959 -387.503606)
			(xy 95.408691 -387.462827) (xy 95.448487 -387.42794) (xy 95.493332 -387.399836) (xy 95.542079 -387.379234)
			(xy 95.593486 -387.366658) (xy 95.64624 -387.36243) (xy 95.698994 -387.366658) (xy 95.750401 -387.379234)
			(xy 95.799148 -387.399836) (xy 95.843993 -387.42794) (xy 95.883789 -387.462827) (xy 95.917521 -387.503606)
			(xy 95.944327 -387.549238) (xy 95.963524 -387.598556) (xy 95.969582 -387.62432) (xy 95.973392 -387.6421)
			(xy 96.001078 -387.664452) (xy 96.491552 -387.664452) (xy 96.519238 -387.6421) (xy 96.523048 -387.62432)
			(xy 96.529106 -387.598556) (xy 96.548303 -387.549238) (xy 96.575109 -387.503606) (xy 96.608841 -387.462827)
			(xy 96.648637 -387.42794) (xy 96.693482 -387.399836) (xy 96.742229 -387.379234) (xy 96.793636 -387.366658)
			(xy 96.84639 -387.36243) (xy 96.899144 -387.366658) (xy 96.950551 -387.379234) (xy 96.999298 -387.399836)
			(xy 97.044143 -387.42794) (xy 97.083939 -387.462827) (xy 97.117671 -387.503606) (xy 97.144477 -387.549238)
			(xy 97.163674 -387.598556) (xy 97.169732 -387.62432) (xy 97.173542 -387.6421) (xy 97.201228 -387.664452)
			(xy 97.691448 -387.664452) (xy 97.719134 -387.6421) (xy 97.722944 -387.62432) (xy 97.729002 -387.598556)
			(xy 97.748199 -387.549238) (xy 97.775005 -387.503606) (xy 97.808737 -387.462827) (xy 97.848533 -387.42794)
			(xy 97.893378 -387.399836) (xy 97.942125 -387.379234) (xy 97.993532 -387.366658) (xy 98.046286 -387.36243)
			(xy 98.09904 -387.366658) (xy 98.150447 -387.379234) (xy 98.199194 -387.399836) (xy 98.244039 -387.42794)
			(xy 98.283835 -387.462827) (xy 98.317567 -387.503606) (xy 98.344373 -387.549238) (xy 98.36357 -387.598556)
			(xy 98.369628 -387.62432) (xy 98.373438 -387.6421) (xy 98.401124 -387.664452) (xy 101.934518 -387.664452)
			(xy 101.944586 -387.664024) (xy 101.963181 -387.6563) (xy 101.970586 -387.649466) (xy 102.089458 -387.530594)
			(xy 102.092252 -387.493002) (xy 102.080568 -387.477508) (xy 102.068631 -387.460908) (xy 102.049658 -387.424693)
			(xy 102.036729 -387.385906) (xy 102.03018 -387.34555) (xy 102.029768 -387.325108) (xy 102.029768 -386.689346)
			(xy 102.030339 -386.66525) (xy 102.039437 -386.617925) (xy 102.057296 -386.573164) (xy 102.083275 -386.532574)
			(xy 102.116443 -386.497612) (xy 102.135686 -386.483098) (xy 102.145113 -386.475438) (xy 102.156124 -386.453825)
			(xy 102.156768 -386.441696) (xy 102.156768 -386.32003) (xy 102.157339 -386.303458) (xy 102.165959 -386.271452)
			(xy 102.182546 -386.242753) (xy 102.193852 -386.230622) (xy 102.319582 -386.105146) (xy 102.326422 -386.097746)
			(xy 102.33414 -386.079147) (xy 102.334568 -386.069078) (xy 102.334568 -384.86842) (xy 102.333947 -384.856283)
			(xy 102.322936 -384.834659) (xy 102.313486 -384.827018) (xy 102.294231 -384.812518) (xy 102.261061 -384.777555)
			(xy 102.235083 -384.736962) (xy 102.217229 -384.692197) (xy 102.208142 -384.644867) (xy 102.207568 -384.62077)
			(xy 102.207568 -383.94132) (xy 102.20713 -383.931257) (xy 102.199391 -383.912677) (xy 102.192582 -383.905252)
			(xy 102.091236 -383.803906) (xy 102.083834 -383.797069) (xy 102.065236 -383.789357) (xy 102.055168 -383.78892)
			(xy 87.192104 -383.78892) (xy 87.182034 -383.789343) (xy 87.16343 -383.797058) (xy 87.156036 -383.803906)
			(xy 86.875112 -384.08483) (xy 86.868269 -384.09223) (xy 86.860544 -384.110828) (xy 86.860126 -384.120898)
			(xy 86.860126 -385.310888) (xy 87.21344 -385.310888) (xy 87.21344 -385.31038) (xy 87.213821 -385.286371)
			(xy 87.22134 -385.238946) (xy 87.23619 -385.193282) (xy 87.258004 -385.150506) (xy 87.286245 -385.111671)
			(xy 87.320216 -385.077735) (xy 87.359081 -385.049535) (xy 87.40188 -385.027766) (xy 87.44756 -385.012965)
			(xy 87.494993 -385.005496) (xy 87.519002 -385.005072) (xy 87.542935 -385.005578) (xy 87.590218 -385.013028)
			(xy 87.63576 -385.027763) (xy 87.678447 -385.04942) (xy 87.717233 -385.077469) (xy 87.75117 -385.111225)
			(xy 87.779426 -385.149861) (xy 87.790782 -385.170934) (xy 87.79129 -385.17195) (xy 87.871596 -385.310888)
			(xy 88.413336 -385.310888) (xy 88.413336 -385.31038) (xy 88.413721 -385.286371) (xy 88.42124 -385.238947)
			(xy 88.436089 -385.193283) (xy 88.457903 -385.150507) (xy 88.486144 -385.111672) (xy 88.520115 -385.077737)
			(xy 88.558979 -385.049537) (xy 88.601777 -385.027767) (xy 88.647456 -385.012965) (xy 88.694889 -385.005496)
			(xy 88.718898 -385.005072) (xy 88.742834 -385.0055) (xy 88.790121 -385.012965) (xy 88.835664 -385.027713)
			(xy 88.878351 -385.049383) (xy 88.917136 -385.077445) (xy 88.95107 -385.111212) (xy 88.979324 -385.149857)
			(xy 88.990678 -385.170934) (xy 88.991186 -385.17195) (xy 89.071492 -385.310888) (xy 89.61374 -385.310888)
			(xy 89.61374 -385.31038) (xy 89.61412 -385.286384) (xy 89.621631 -385.238983) (xy 89.636465 -385.193341)
			(xy 89.658257 -385.150582) (xy 89.68647 -385.111758) (xy 89.72041 -385.077826) (xy 89.75924 -385.049622)
			(xy 89.802004 -385.027839) (xy 89.847649 -385.013015) (xy 89.895052 -385.005515) (xy 89.919048 -385.005072)
			(xy 89.942983 -385.005541) (xy 89.990267 -385.012998) (xy 90.03581 -385.027739) (xy 90.078497 -385.049402)
			(xy 90.117282 -385.077458) (xy 90.151218 -385.111219) (xy 90.179473 -385.149859) (xy 90.190828 -385.170934)
			(xy 90.191336 -385.17195) (xy 90.583766 -385.850892) (xy 90.596593 -385.874223) (xy 90.614812 -385.924247)
			(xy 90.624071 -385.976673) (xy 90.62466 -386.003292) (xy 90.624253 -386.0273) (xy 90.616738 -386.074724)
			(xy 90.601893 -386.120388) (xy 90.580082 -386.163164) (xy 90.551844 -386.201999) (xy 90.517875 -386.235935)
			(xy 90.479013 -386.264136) (xy 90.436216 -386.285905) (xy 90.390538 -386.300707) (xy 90.343106 -386.308176)
			(xy 90.319098 -386.3086) (xy 90.295524 -386.308208) (xy 90.248936 -386.300966) (xy 90.204017 -386.28664)
			(xy 90.161839 -386.265571) (xy 90.123406 -386.238261) (xy 90.089634 -386.205361) (xy 90.061328 -386.167656)
			(xy 90.049858 -386.147056) (xy 90.04935 -386.146294) (xy 89.651586 -385.457954) (xy 89.63973 -385.435267)
			(xy 89.622871 -385.386939) (xy 89.61429 -385.336479) (xy 89.61374 -385.310888) (xy 89.071492 -385.310888)
			(xy 89.383616 -385.850892) (xy 89.396368 -385.874248) (xy 89.414476 -385.924281) (xy 89.423678 -385.976688)
			(xy 89.424256 -386.003292) (xy 89.42373 -386.027281) (xy 89.416227 -386.074667) (xy 89.401403 -386.120297)
			(xy 89.379625 -386.163047) (xy 89.351428 -386.201863) (xy 89.317506 -386.235791) (xy 89.278694 -386.263996)
			(xy 89.235949 -386.285782) (xy 89.190322 -386.300614) (xy 89.142937 -386.308126) (xy 89.118948 -386.3086)
			(xy 89.095375 -386.308168) (xy 89.048789 -386.300933) (xy 89.003871 -386.286614) (xy 88.961693 -386.265552)
			(xy 88.923259 -386.238248) (xy 88.889486 -386.205354) (xy 88.861179 -386.167654) (xy 88.849708 -386.147056)
			(xy 88.8492 -386.146294) (xy 88.451436 -385.457954) (xy 88.439505 -385.435294) (xy 88.422572 -385.386964)
			(xy 88.413919 -385.336491) (xy 88.413336 -385.310888) (xy 87.871596 -385.310888) (xy 88.18372 -385.850892)
			(xy 88.196472 -385.874248) (xy 88.21458 -385.924281) (xy 88.223782 -385.976688) (xy 88.22436 -386.003292)
			(xy 88.223954 -386.027287) (xy 88.216447 -386.074687) (xy 88.201617 -386.120329) (xy 88.179828 -386.163088)
			(xy 88.151618 -386.201912) (xy 88.117682 -386.235844) (xy 88.078854 -386.264049) (xy 88.036092 -386.285832)
			(xy 87.990448 -386.300657) (xy 87.943047 -386.308157) (xy 87.919052 -386.3086) (xy 87.895479 -386.308164)
			(xy 87.848893 -386.300931) (xy 87.803976 -386.286612) (xy 87.761797 -386.265551) (xy 87.723364 -386.238247)
			(xy 87.689591 -386.205354) (xy 87.661283 -386.167653) (xy 87.649812 -386.147056) (xy 87.649304 -386.146294)
			(xy 87.25154 -385.457954) (xy 87.239609 -385.435293) (xy 87.222676 -385.386964) (xy 87.214023 -385.336491)
			(xy 87.21344 -385.310888) (xy 86.860126 -385.310888) (xy 86.860126 -385.623054) (xy 86.860327 -385.62972)
			(xy 86.863809 -385.642588) (xy 86.866984 -385.648454) (xy 86.983824 -385.850892) (xy 86.996627 -385.874226)
			(xy 87.014768 -385.924258) (xy 87.023943 -385.976681) (xy 87.024464 -386.003292) (xy 87.02395 -386.028812)
			(xy 87.015463 -386.079141) (xy 86.998723 -386.127357) (xy 86.974198 -386.172118) (xy 86.94257 -386.212176)
			(xy 86.90472 -386.246417) (xy 86.883494 -386.260594) (xy 86.876497 -386.265474) (xy 86.865964 -386.278881)
			(xy 86.860395 -386.294995) (xy 86.860126 -386.30352) (xy 86.860126 -387.671564) (xy 86.860561 -387.681628)
			(xy 86.868295 -387.700214) (xy 86.875112 -387.707632) (xy 87.132922 -387.965442) (xy 87.140319 -387.972291)
			(xy 87.158918 -387.980027) (xy 87.16899 -387.980428)
		)
		(stroke
			(width 0)
			(type solid)
		)
		(fill yes)
		(layer "In9.Cu")
		(net "P1V8_CPU1_RT1_1A")
	)
	(gr_poly
		(pts
			(xy 311.646062 -396.5321) (xy 311.657169 -396.531534) (xy 311.677318 -396.52218) (xy 311.684924 -396.514066)
			(xy 311.700842 -396.49586) (xy 311.73742 -396.464227) (xy 311.77853 -396.438763) (xy 311.823144 -396.420104)
			(xy 311.870143 -396.408718) (xy 311.91835 -396.404891) (xy 311.966557 -396.408718) (xy 312.013556 -396.420104)
			(xy 312.05817 -396.438763) (xy 312.09928 -396.464227) (xy 312.135858 -396.49586) (xy 312.151776 -396.514066)
			(xy 312.15937 -396.522192) (xy 312.179529 -396.531527) (xy 312.190638 -396.5321) (xy 312.845958 -396.5321)
			(xy 312.857065 -396.531535) (xy 312.877215 -396.522182) (xy 312.88482 -396.514066) (xy 312.902383 -396.494078)
			(xy 312.943166 -396.459911) (xy 312.989253 -396.43333) (xy 313.039251 -396.41514) (xy 313.091644 -396.405892)
			(xy 313.118246 -396.405354) (xy 313.144973 -396.405902) (xy 313.197607 -396.415224) (xy 313.222894 -396.423896)
			(xy 313.236864 -396.428976) (xy 313.265566 -396.422626) (xy 314.908692 -394.7795) (xy 314.923678 -394.765784)
			(xy 314.931675 -394.758248) (xy 314.940891 -394.738325) (xy 314.940957 -394.716374) (xy 314.931859 -394.696396)
			(xy 314.915258 -394.682035) (xy 314.904882 -394.678408) (xy 314.881726 -394.671093) (xy 314.83791 -394.650162)
			(xy 314.797961 -394.622558) (xy 314.762885 -394.588979) (xy 314.733567 -394.550269) (xy 314.721748 -394.529056)
			(xy 314.72124 -394.528294) (xy 314.323476 -393.839954) (xy 314.311539 -393.817294) (xy 314.294582 -393.76897)
			(xy 314.285932 -393.718493) (xy 314.285376 -393.692888) (xy 314.285376 -393.69238) (xy 314.285881 -393.667453)
			(xy 314.294032 -393.618269) (xy 314.31011 -393.571078) (xy 314.321444 -393.54887) (xy 314.321444 -393.548616)
			(xy 314.333087 -393.52771) (xy 314.361866 -393.489481) (xy 314.396256 -393.456209) (xy 314.435413 -393.428707)
			(xy 314.47838 -393.407648) (xy 314.524106 -393.393548) (xy 314.571472 -393.386752) (xy 314.619317 -393.387425)
			(xy 314.666473 -393.395553) (xy 314.711783 -393.410935) (xy 314.75414 -393.433196) (xy 314.792508 -393.46179)
			(xy 314.825946 -393.496017) (xy 314.853637 -393.535041) (xy 314.86475 -393.556236) (xy 314.865512 -393.55776)
			(xy 314.929947 -393.669225) (xy 315.485986 -393.669225) (xy 315.493312 -393.621681) (xy 315.507999 -393.575872)
			(xy 315.529685 -393.532932) (xy 315.557833 -393.493922) (xy 315.591748 -393.459806) (xy 315.630591 -393.431428)
			(xy 315.673402 -393.409489) (xy 315.719123 -393.394531) (xy 315.766623 -393.386925) (xy 315.814729 -393.386858)
			(xy 315.86225 -393.394332) (xy 315.908012 -393.409163) (xy 315.950884 -393.430983) (xy 315.989806 -393.459253)
			(xy 316.023816 -393.493274) (xy 316.052072 -393.532206) (xy 316.063376 -393.553442) (xy 316.063884 -393.554712)
			(xy 316.143736 -393.692888) (xy 316.685676 -393.692888) (xy 316.685676 -393.69238) (xy 316.686166 -393.667466)
			(xy 316.694263 -393.6183) (xy 316.710223 -393.571096) (xy 316.72149 -393.54887) (xy 316.72149 -393.548616)
			(xy 316.733168 -393.527733) (xy 316.761958 -393.489523) (xy 316.796353 -393.456267) (xy 316.83551 -393.428779)
			(xy 316.878474 -393.407731) (xy 316.924194 -393.393637) (xy 316.971551 -393.386841) (xy 317.019389 -393.387511)
			(xy 317.066538 -393.395629) (xy 317.111845 -393.410998) (xy 317.154203 -393.43324) (xy 317.192576 -393.461814)
			(xy 317.226025 -393.496019) (xy 317.253735 -393.535021) (xy 317.264796 -393.556236) (xy 317.265558 -393.55776)
			(xy 317.329994 -393.669227) (xy 317.885945 -393.669227) (xy 317.893271 -393.621675) (xy 317.90796 -393.575859)
			(xy 317.929649 -393.532911) (xy 317.957803 -393.493895) (xy 317.991723 -393.459773) (xy 318.030573 -393.431391)
			(xy 318.073392 -393.409449) (xy 318.119121 -393.39449) (xy 318.166629 -393.386884) (xy 318.214742 -393.386818)
			(xy 318.262271 -393.394295) (xy 318.30804 -393.40913) (xy 318.350919 -393.430956) (xy 318.389845 -393.459233)
			(xy 318.423859 -393.493262) (xy 318.452118 -393.532202) (xy 318.463422 -393.553442) (xy 318.46393 -393.554712)
			(xy 318.530109 -393.669227) (xy 319.085848 -393.669227) (xy 319.093174 -393.621675) (xy 319.107863 -393.57586)
			(xy 319.129552 -393.532913) (xy 319.157705 -393.493897) (xy 319.191626 -393.459776) (xy 319.230475 -393.431394)
			(xy 319.273293 -393.409452) (xy 319.319021 -393.394493) (xy 319.366529 -393.386887) (xy 319.414641 -393.386822)
			(xy 319.462169 -393.394299) (xy 319.507938 -393.409133) (xy 319.550816 -393.430958) (xy 319.589742 -393.459235)
			(xy 319.623755 -393.493263) (xy 319.652014 -393.532202) (xy 319.663318 -393.553442) (xy 319.663826 -393.554712)
			(xy 319.730003 -393.669225) (xy 320.286093 -393.669225) (xy 320.293419 -393.621682) (xy 320.308106 -393.575875)
			(xy 320.329791 -393.532936) (xy 320.357938 -393.493927) (xy 320.391852 -393.459812) (xy 320.430694 -393.431435)
			(xy 320.473504 -393.409496) (xy 320.519224 -393.394539) (xy 320.566722 -393.386932) (xy 320.614826 -393.386865)
			(xy 320.662346 -393.394339) (xy 320.708107 -393.409169) (xy 320.750978 -393.430987) (xy 320.789899 -393.459256)
			(xy 320.823908 -393.493277) (xy 320.852164 -393.532207) (xy 320.863468 -393.553442) (xy 320.863976 -393.554712)
			(xy 320.930153 -393.669224) (xy 321.485997 -393.669224) (xy 321.493322 -393.621682) (xy 321.508009 -393.575876)
			(xy 321.529694 -393.532938) (xy 321.557841 -393.493929) (xy 321.591754 -393.459815) (xy 321.630596 -393.431438)
			(xy 321.673405 -393.409499) (xy 321.719124 -393.394542) (xy 321.766622 -393.386936) (xy 321.814725 -393.386869)
			(xy 321.862244 -393.394342) (xy 321.908005 -393.409171) (xy 321.950875 -393.43099) (xy 321.989796 -393.459258)
			(xy 322.023804 -393.493278) (xy 322.052061 -393.532207) (xy 322.063364 -393.553442) (xy 322.063872 -393.554712)
			(xy 322.455794 -394.232892) (xy 322.456048 -394.2334) (xy 322.456302 -394.2334) (xy 322.457572 -394.23594)
			(xy 322.469822 -394.258867) (xy 322.487237 -394.307839) (xy 322.49612 -394.359051) (xy 322.496688 -394.385038)
			(xy 322.496688 -394.385292) (xy 322.496253 -394.409299) (xy 322.488739 -394.45672) (xy 322.473895 -394.502381)
			(xy 322.452087 -394.545156) (xy 322.423852 -394.58399) (xy 322.389887 -394.617925) (xy 322.351029 -394.646126)
			(xy 322.308235 -394.667897) (xy 322.262561 -394.682702) (xy 322.215133 -394.690174) (xy 322.191126 -394.6906)
			(xy 322.167461 -394.690167) (xy 322.120698 -394.682859) (xy 322.075621 -394.668429) (xy 322.033308 -394.647222)
			(xy 321.99477 -394.619746) (xy 321.960928 -394.586656) (xy 321.932592 -394.548745) (xy 321.921124 -394.52804)
			(xy 321.92087 -394.527278) (xy 321.523614 -393.839954) (xy 321.511421 -393.816744) (xy 321.494316 -393.767188)
			(xy 321.489578 -393.741402) (xy 321.489578 -393.741148) (xy 321.486214 -393.717327) (xy 321.485997 -393.669224)
			(xy 320.930153 -393.669224) (xy 321.255898 -394.232892) (xy 321.256152 -394.2334) (xy 321.256406 -394.2334)
			(xy 321.257676 -394.23594) (xy 321.269926 -394.258866) (xy 321.287341 -394.307839) (xy 321.296224 -394.359051)
			(xy 321.296792 -394.385038) (xy 321.296792 -394.385292) (xy 321.296353 -394.409298) (xy 321.28884 -394.45672)
			(xy 321.273996 -394.50238) (xy 321.252188 -394.545155) (xy 321.223953 -394.583988) (xy 321.189989 -394.617924)
			(xy 321.151131 -394.646125) (xy 321.108338 -394.667896) (xy 321.062664 -394.682701) (xy 321.015237 -394.690174)
			(xy 320.99123 -394.6906) (xy 320.967565 -394.690164) (xy 320.920803 -394.682856) (xy 320.875726 -394.668427)
			(xy 320.833412 -394.647221) (xy 320.794874 -394.619745) (xy 320.761032 -394.586656) (xy 320.732696 -394.548745)
			(xy 320.721228 -394.52804) (xy 320.720974 -394.527278) (xy 320.323718 -393.839954) (xy 320.311526 -393.816744)
			(xy 320.29442 -393.767188) (xy 320.289682 -393.741402) (xy 320.289682 -393.741148) (xy 320.28631 -393.717328)
			(xy 320.286093 -393.669225) (xy 319.730003 -393.669225) (xy 320.055748 -394.232892) (xy 320.056002 -394.2334)
			(xy 320.056256 -394.2334) (xy 320.057526 -394.23594) (xy 320.069741 -394.258873) (xy 320.087067 -394.307855)
			(xy 320.095862 -394.35906) (xy 320.096388 -394.385038) (xy 320.096388 -394.385292) (xy 320.095954 -394.409286)
			(xy 320.088448 -394.456683) (xy 320.07362 -394.502322) (xy 320.051833 -394.54508) (xy 320.023626 -394.583902)
			(xy 319.989693 -394.617834) (xy 319.95087 -394.64604) (xy 319.908111 -394.667824) (xy 319.862471 -394.682651)
			(xy 319.815074 -394.690155) (xy 319.79108 -394.6906) (xy 319.767414 -394.690204) (xy 319.720649 -394.682889)
			(xy 319.675571 -394.668453) (xy 319.633258 -394.64724) (xy 319.59472 -394.619758) (xy 319.56088 -394.586663)
			(xy 319.532545 -394.548747) (xy 319.521078 -394.52804) (xy 319.520824 -394.527278) (xy 319.123568 -393.839954)
			(xy 319.111379 -393.816742) (xy 319.09427 -393.767188) (xy 319.089532 -393.741402) (xy 319.089532 -393.741148)
			(xy 319.086066 -393.717339) (xy 319.085848 -393.669227) (xy 318.530109 -393.669227) (xy 318.855852 -394.232892)
			(xy 318.856106 -394.2334) (xy 318.85636 -394.2334) (xy 318.85763 -394.23594) (xy 318.869845 -394.258873)
			(xy 318.887171 -394.307855) (xy 318.895966 -394.35906) (xy 318.896492 -394.385038) (xy 318.896492 -394.385292)
			(xy 318.896054 -394.409286) (xy 318.888548 -394.456682) (xy 318.87372 -394.502321) (xy 318.851934 -394.545079)
			(xy 318.823728 -394.583901) (xy 318.789795 -394.617833) (xy 318.750972 -394.646038) (xy 318.708214 -394.667823)
			(xy 318.662575 -394.68265) (xy 318.615178 -394.690155) (xy 318.591184 -394.6906) (xy 318.567518 -394.690201)
			(xy 318.520753 -394.682887) (xy 318.475676 -394.668451) (xy 318.433362 -394.647238) (xy 318.394825 -394.619757)
			(xy 318.360984 -394.586662) (xy 318.33265 -394.548747) (xy 318.321182 -394.52804) (xy 318.320928 -394.527278)
			(xy 317.923672 -393.839954) (xy 317.911483 -393.816742) (xy 317.894374 -393.767188) (xy 317.889636 -393.741402)
			(xy 317.889636 -393.741148) (xy 317.886163 -393.71734) (xy 317.885945 -393.669227) (xy 317.329994 -393.669227)
			(xy 317.637922 -394.201904) (xy 317.638176 -394.202412) (xy 317.657734 -394.23594) (xy 317.669949 -394.258873)
			(xy 317.687275 -394.307854) (xy 317.69607 -394.35906) (xy 317.696596 -394.385038) (xy 317.696596 -394.385292)
			(xy 317.696154 -394.409286) (xy 317.688648 -394.456682) (xy 317.67382 -394.50232) (xy 317.652035 -394.545077)
			(xy 317.623829 -394.5839) (xy 317.589897 -394.617831) (xy 317.551074 -394.646037) (xy 317.508317 -394.667822)
			(xy 317.462678 -394.682649) (xy 317.415282 -394.690155) (xy 317.391288 -394.6906) (xy 317.391034 -394.6906)
			(xy 317.367461 -394.690179) (xy 317.320874 -394.682942) (xy 317.275956 -394.668622) (xy 317.233778 -394.647557)
			(xy 317.195344 -394.620252) (xy 317.161572 -394.587356) (xy 317.133265 -394.549654) (xy 317.121794 -394.529056)
			(xy 317.121286 -394.528294) (xy 316.723522 -393.839954) (xy 316.711661 -393.81727) (xy 316.694805 -393.76894)
			(xy 316.686226 -393.71848) (xy 316.685676 -393.692888) (xy 316.143736 -393.692888) (xy 316.455806 -394.232892)
			(xy 316.45606 -394.2334) (xy 316.456314 -394.2334) (xy 316.457584 -394.23594) (xy 316.469835 -394.258866)
			(xy 316.487249 -394.307839) (xy 316.496132 -394.359051) (xy 316.4967 -394.385038) (xy 316.4967 -394.385292)
			(xy 316.496254 -394.409298) (xy 316.48874 -394.456718) (xy 316.473896 -394.502378) (xy 316.452089 -394.545152)
			(xy 316.423856 -394.583985) (xy 316.389892 -394.617921) (xy 316.351035 -394.646122) (xy 316.308243 -394.667894)
			(xy 316.262571 -394.682699) (xy 316.215144 -394.690173) (xy 316.191138 -394.6906) (xy 316.167473 -394.690157)
			(xy 316.120711 -394.682851) (xy 316.075634 -394.668423) (xy 316.033321 -394.647218) (xy 315.994782 -394.619743)
			(xy 315.960941 -394.586655) (xy 315.932604 -394.548745) (xy 315.921136 -394.52804) (xy 315.920882 -394.527278)
			(xy 315.523626 -393.839954) (xy 315.511434 -393.816744) (xy 315.494328 -393.767188) (xy 315.48959 -393.741402)
			(xy 315.48959 -393.741148) (xy 315.486203 -393.71733) (xy 315.485986 -393.669225) (xy 314.929947 -393.669225)
			(xy 315.237876 -394.201904) (xy 315.23813 -394.202412) (xy 315.257688 -394.23594) (xy 315.26996 -394.258856)
			(xy 315.287376 -394.307832) (xy 315.296252 -394.359049) (xy 315.296804 -394.385038) (xy 315.296804 -394.385292)
			(xy 315.29655 -394.395706) (xy 315.296042 -394.405866) (xy 315.3029 -394.424408) (xy 315.365384 -394.491972)
			(xy 315.383164 -394.500354) (xy 315.393324 -394.500608) (xy 315.417955 -394.502179) (xy 315.46638 -394.511714)
			(xy 315.512848 -394.528344) (xy 315.556327 -394.551698) (xy 315.59585 -394.581257) (xy 315.630538 -394.616365)
			(xy 315.65962 -394.65624) (xy 315.671454 -394.6779) (xy 315.678058 -394.690346) (xy 315.702188 -394.705078)
			(xy 315.789056 -394.705078) (xy 315.814011 -394.705695) (xy 315.862959 -394.715441) (xy 315.909067 -394.734548)
			(xy 315.950561 -394.762281) (xy 315.968634 -394.7795) (xy 316.369446 -395.180312) (xy 316.402974 -395.185138)
			(xy 316.41796 -395.176756) (xy 316.442652 -395.163747) (xy 316.495317 -395.145288) (xy 316.550331 -395.13592)
			(xy 316.578234 -395.135354) (xy 316.604221 -395.135866) (xy 316.655553 -395.144001) (xy 316.704982 -395.160064)
			(xy 316.751289 -395.183661) (xy 316.793336 -395.214211) (xy 316.830087 -395.250961) (xy 316.860637 -395.293007)
			(xy 316.884234 -395.339315) (xy 316.900298 -395.388743) (xy 316.908434 -395.440075) (xy 316.908942 -395.466062)
			(xy 316.908367 -395.493966) (xy 316.899013 -395.548983) (xy 316.880564 -395.601652) (xy 316.86754 -395.626336)
			(xy 316.859158 -395.641322) (xy 316.863984 -395.67485) (xy 317.235586 -396.046452) (xy 317.242987 -396.05329)
			(xy 317.261586 -396.061001) (xy 317.271654 -396.061438) (xy 317.56096 -396.061438) (xy 317.589408 -396.037562)
			(xy 317.592456 -396.019274) (xy 317.597324 -395.994007) (xy 317.613843 -395.945277) (xy 317.63771 -395.899693)
			(xy 317.668348 -395.858356) (xy 317.705018 -395.822262) (xy 317.746836 -395.792282) (xy 317.792792 -395.769141)
			(xy 317.841778 -395.753396) (xy 317.892611 -395.745427) (xy 317.944065 -395.745427) (xy 317.994898 -395.753396)
			(xy 318.043884 -395.769141) (xy 318.08984 -395.792282) (xy 318.131658 -395.822262) (xy 318.168328 -395.858356)
			(xy 318.198966 -395.899693) (xy 318.222833 -395.945277) (xy 318.239352 -395.994007) (xy 318.24422 -396.019274)
			(xy 318.247268 -396.037562) (xy 318.275716 -396.061438) (xy 318.760856 -396.061438) (xy 318.789304 -396.037562)
			(xy 318.792352 -396.019274) (xy 318.79722 -395.994007) (xy 318.813739 -395.945277) (xy 318.837606 -395.899693)
			(xy 318.868244 -395.858356) (xy 318.904914 -395.822262) (xy 318.946732 -395.792282) (xy 318.992688 -395.769141)
			(xy 319.041674 -395.753396) (xy 319.092507 -395.745427) (xy 319.143961 -395.745427) (xy 319.194794 -395.753396)
			(xy 319.24378 -395.769141) (xy 319.289736 -395.792282) (xy 319.331554 -395.822262) (xy 319.368224 -395.858356)
			(xy 319.398862 -395.899693) (xy 319.422729 -395.945277) (xy 319.439248 -395.994007) (xy 319.444116 -396.019274)
			(xy 319.447164 -396.037562) (xy 319.475612 -396.061438) (xy 319.961006 -396.061438) (xy 319.989454 -396.037562)
			(xy 319.992502 -396.019274) (xy 319.99737 -395.994007) (xy 320.013889 -395.945277) (xy 320.037756 -395.899693)
			(xy 320.068394 -395.858356) (xy 320.105064 -395.822262) (xy 320.146882 -395.792282) (xy 320.192838 -395.769141)
			(xy 320.241824 -395.753396) (xy 320.292657 -395.745427) (xy 320.344111 -395.745427) (xy 320.394944 -395.753396)
			(xy 320.44393 -395.769141) (xy 320.489886 -395.792282) (xy 320.531704 -395.822262) (xy 320.568374 -395.858356)
			(xy 320.599012 -395.899693) (xy 320.622879 -395.945277) (xy 320.639398 -395.994007) (xy 320.644266 -396.019274)
			(xy 320.647314 -396.037562) (xy 320.675762 -396.061438) (xy 321.160902 -396.061438) (xy 321.18935 -396.037562)
			(xy 321.192398 -396.019274) (xy 321.197266 -395.994007) (xy 321.213785 -395.945277) (xy 321.237652 -395.899693)
			(xy 321.26829 -395.858356) (xy 321.30496 -395.822262) (xy 321.346778 -395.792282) (xy 321.392734 -395.769141)
			(xy 321.44172 -395.753396) (xy 321.492553 -395.745427) (xy 321.544007 -395.745427) (xy 321.59484 -395.753396)
			(xy 321.643826 -395.769141) (xy 321.689782 -395.792282) (xy 321.7316 -395.822262) (xy 321.76827 -395.858356)
			(xy 321.798908 -395.899693) (xy 321.822775 -395.945277) (xy 321.839294 -395.994007) (xy 321.844162 -396.019274)
			(xy 321.84721 -396.037562) (xy 321.875658 -396.061438) (xy 325.056246 -396.061438) (xy 325.066311 -396.061005)
			(xy 325.084898 -396.053272) (xy 325.092314 -396.046452) (xy 325.51116 -395.627606) (xy 325.518012 -395.62021)
			(xy 325.525755 -395.601611) (xy 325.526146 -395.591538) (xy 325.526146 -395.12621) (xy 325.526712 -395.102112)
			(xy 325.535802 -395.054782) (xy 325.553657 -395.010017) (xy 325.579637 -394.969424) (xy 325.612807 -394.93446)
			(xy 325.632064 -394.919962) (xy 325.641488 -394.912301) (xy 325.652488 -394.890688) (xy 325.653146 -394.87856)
			(xy 325.653146 -394.756894) (xy 325.653708 -394.740318) (xy 325.662315 -394.708301) (xy 325.67889 -394.679589)
			(xy 325.69023 -394.667486) (xy 325.81596 -394.54201) (xy 325.822812 -394.534614) (xy 325.830557 -394.516016)
			(xy 325.830946 -394.505942) (xy 325.830946 -393.305284) (xy 325.83032 -393.293148) (xy 325.819311 -393.271525)
			(xy 325.809864 -393.263882) (xy 325.790613 -393.249381) (xy 325.75745 -393.214415) (xy 325.73148 -393.173821)
			(xy 325.713635 -393.129057) (xy 325.704555 -393.081729) (xy 325.703946 -393.057634) (xy 325.703946 -392.385042)
			(xy 325.703511 -392.374978) (xy 325.695776 -392.356394) (xy 325.68896 -392.348974) (xy 325.523352 -392.183366)
			(xy 325.515954 -392.17652) (xy 325.497355 -392.168792) (xy 325.487284 -392.16838) (xy 310.8706 -392.16838)
			(xy 310.860529 -392.168802) (xy 310.841923 -392.176515) (xy 310.834532 -392.183366) (xy 310.751728 -392.26617)
			(xy 310.734983 -392.282211) (xy 310.69681 -392.308529) (xy 310.654494 -392.327481) (xy 310.632094 -392.33348)
			(xy 310.625236 -392.335004) (xy 310.613298 -392.341862) (xy 310.39435 -392.56081) (xy 310.3875 -392.568207)
			(xy 310.379761 -392.586805) (xy 310.379364 -392.596878) (xy 310.379364 -393.692888) (xy 310.685688 -393.692888)
			(xy 310.685688 -393.69238) (xy 310.686144 -393.668388) (xy 310.693653 -393.620996) (xy 310.708483 -393.575362)
			(xy 310.730269 -393.53261) (xy 310.758474 -393.493792) (xy 310.792404 -393.459863) (xy 310.831224 -393.43166)
			(xy 310.873977 -393.409877) (xy 310.919612 -393.395049) (xy 310.967004 -393.387543) (xy 310.990996 -393.387072)
			(xy 311.014932 -393.387502) (xy 311.062218 -393.394966) (xy 311.107762 -393.409714) (xy 311.150449 -393.431384)
			(xy 311.189234 -393.459445) (xy 311.223168 -393.493212) (xy 311.251422 -393.531857) (xy 311.262776 -393.552934)
			(xy 311.263284 -393.55395) (xy 311.34359 -393.692888) (xy 311.885584 -393.692888) (xy 311.885584 -393.69238)
			(xy 311.886044 -393.668389) (xy 311.893553 -393.620997) (xy 311.908383 -393.575363) (xy 311.930168 -393.532611)
			(xy 311.958373 -393.493793) (xy 311.992302 -393.459865) (xy 312.031121 -393.431662) (xy 312.073874 -393.409878)
			(xy 312.119509 -393.39505) (xy 312.166901 -393.387543) (xy 312.190892 -393.387072) (xy 312.191146 -393.387072)
			(xy 312.215081 -393.387542) (xy 312.262365 -393.394999) (xy 312.307908 -393.40974) (xy 312.350594 -393.431403)
			(xy 312.38938 -393.459458) (xy 312.423316 -393.493219) (xy 312.451571 -393.531859) (xy 312.462926 -393.552934)
			(xy 312.463434 -393.55395) (xy 312.54374 -393.692888) (xy 313.08548 -393.692888) (xy 313.08548 -393.69238)
			(xy 313.085974 -393.667452) (xy 313.094125 -393.618266) (xy 313.110204 -393.571073) (xy 313.121548 -393.54887)
			(xy 313.121548 -393.548616) (xy 313.133139 -393.527682) (xy 313.161937 -393.489468) (xy 313.19634 -393.45621)
			(xy 313.235507 -393.428721) (xy 313.27848 -393.407673) (xy 313.324208 -393.39358) (xy 313.371574 -393.386788)
			(xy 313.41942 -393.387462) (xy 313.466576 -393.395586) (xy 313.51189 -393.41096) (xy 313.554252 -393.43321)
			(xy 313.592629 -393.461792) (xy 313.626082 -393.496006) (xy 313.653793 -393.535016) (xy 313.664854 -393.556236)
			(xy 313.665616 -393.55776) (xy 314.03798 -394.201904) (xy 314.038234 -394.202412) (xy 314.057792 -394.23594)
			(xy 314.070043 -394.258866) (xy 314.087457 -394.307839) (xy 314.09634 -394.359051) (xy 314.096908 -394.385038)
			(xy 314.096908 -394.385292) (xy 314.096454 -394.409298) (xy 314.08894 -394.456717) (xy 314.074097 -394.502377)
			(xy 314.052291 -394.54515) (xy 314.024058 -394.583983) (xy 313.990095 -394.617918) (xy 313.95124 -394.646119)
			(xy 313.908449 -394.667891) (xy 313.862778 -394.682698) (xy 313.815352 -394.690173) (xy 313.791346 -394.6906)
			(xy 313.791092 -394.6906) (xy 313.767518 -394.690213) (xy 313.720929 -394.68297) (xy 313.67601 -394.668643)
			(xy 313.633832 -394.647573) (xy 313.595399 -394.620263) (xy 313.561628 -394.587362) (xy 313.533322 -394.549656)
			(xy 313.521852 -394.529056) (xy 313.521344 -394.528294) (xy 313.12358 -393.839954) (xy 313.111644 -393.817296)
			(xy 313.094715 -393.768965) (xy 313.086063 -393.718492) (xy 313.08548 -393.692888) (xy 312.54374 -393.692888)
			(xy 312.855864 -394.232892) (xy 312.86862 -394.256246) (xy 312.886726 -394.30628) (xy 312.895926 -394.358688)
			(xy 312.896504 -394.385292) (xy 312.896054 -394.409285) (xy 312.888549 -394.456681) (xy 312.873721 -394.502319)
			(xy 312.851936 -394.545075) (xy 312.823731 -394.583897) (xy 312.7898 -394.617829) (xy 312.750978 -394.646034)
			(xy 312.708222 -394.66782) (xy 312.662585 -394.682648) (xy 312.615189 -394.690154) (xy 312.591196 -394.6906)
			(xy 312.590942 -394.6906) (xy 312.567369 -394.690172) (xy 312.520783 -394.682937) (xy 312.475865 -394.668617)
			(xy 312.433686 -394.647554) (xy 312.395253 -394.62025) (xy 312.36148 -394.587355) (xy 312.333173 -394.549654)
			(xy 312.321702 -394.529056) (xy 312.321194 -394.528294) (xy 311.92343 -393.839954) (xy 311.911569 -393.81727)
			(xy 311.894713 -393.76894) (xy 311.886134 -393.71848) (xy 311.885584 -393.692888) (xy 311.34359 -393.692888)
			(xy 311.655714 -394.232892) (xy 311.668537 -394.256226) (xy 311.686758 -394.306248) (xy 311.696019 -394.358673)
			(xy 311.696608 -394.385292) (xy 311.696154 -394.409298) (xy 311.68864 -394.456717) (xy 311.673797 -394.502377)
			(xy 311.651991 -394.54515) (xy 311.623758 -394.583983) (xy 311.589795 -394.617918) (xy 311.55094 -394.646119)
			(xy 311.508149 -394.667891) (xy 311.462478 -394.682698) (xy 311.415052 -394.690173) (xy 311.391046 -394.6906)
			(xy 311.367473 -394.690169) (xy 311.320887 -394.682935) (xy 311.275969 -394.668615) (xy 311.233791 -394.647553)
			(xy 311.195357 -394.620249) (xy 311.161584 -394.587355) (xy 311.133277 -394.549654) (xy 311.121806 -394.529056)
			(xy 311.121298 -394.528294) (xy 310.723534 -393.839954) (xy 310.711674 -393.81727) (xy 310.694818 -393.76894)
			(xy 310.686238 -393.71848) (xy 310.685688 -393.692888) (xy 310.379364 -393.692888) (xy 310.379364 -394.086842)
			(xy 310.379564 -394.093508) (xy 310.383046 -394.106377) (xy 310.386222 -394.112242) (xy 310.455818 -394.232892)
			(xy 310.468606 -394.256241) (xy 310.486807 -394.306264) (xy 310.4961 -394.358678) (xy 310.496712 -394.385292)
			(xy 310.496197 -394.410833) (xy 310.487699 -394.461205) (xy 310.47094 -394.50946) (xy 310.446385 -394.554254)
			(xy 310.41472 -394.594339) (xy 310.396128 -394.61186) (xy 310.388614 -394.619403) (xy 310.379942 -394.638822)
			(xy 310.379364 -394.649452) (xy 310.379364 -396.212822) (xy 310.379793 -396.222889) (xy 310.38752 -396.241482)
			(xy 310.39435 -396.24889) (xy 310.568848 -396.423388) (xy 310.597804 -396.429738) (xy 310.611774 -396.424404)
			(xy 310.637475 -396.415505) (xy 310.691008 -396.405923) (xy 310.7182 -396.405354) (xy 310.744799 -396.405932)
			(xy 310.797191 -396.415163) (xy 310.847187 -396.433345) (xy 310.893269 -396.459926) (xy 310.93404 -396.4941)
			(xy 310.951626 -396.514066) (xy 310.959217 -396.5222) (xy 310.979375 -396.531555) (xy 310.990488 -396.5321)
		)
		(stroke
			(width 0)
			(type solid)
		)
		(fill yes)
		(layer "In9.Cu")
		(net "P1V8_CPU0_RT0_1A")
	)
	(gr_poly
		(pts
			(xy 55.703978 -388.095236) (xy 55.712235 -388.094953) (xy 55.72791 -388.089766) (xy 55.734712 -388.085076)
			(xy 55.754693 -388.070562) (xy 55.798364 -388.047511) (xy 55.845181 -388.031801) (xy 55.893917 -388.023842)
			(xy 55.918608 -388.023354) (xy 55.943297 -388.023851) (xy 55.992027 -388.031833) (xy 56.038842 -388.04754)
			(xy 56.082525 -388.070563) (xy 56.102504 -388.085076) (xy 56.109301 -388.089774) (xy 56.12498 -388.094958)
			(xy 56.133238 -388.095236) (xy 56.903874 -388.095236) (xy 56.912131 -388.094954) (xy 56.927807 -388.089767)
			(xy 56.934608 -388.085076) (xy 56.954588 -388.070562) (xy 56.99826 -388.04751) (xy 57.045076 -388.031799)
			(xy 57.093813 -388.02384) (xy 57.118504 -388.023354) (xy 57.131267 -388.023491) (xy 57.156701 -388.025651)
			(xy 57.169304 -388.027672) (xy 57.18175 -388.029704) (xy 57.204864 -388.022338) (xy 57.909206 -387.317996)
			(xy 57.912762 -387.281928) (xy 57.902856 -387.266688) (xy 57.889822 -387.246291) (xy 57.869219 -387.202489)
			(xy 57.855231 -387.15615) (xy 57.848157 -387.108264) (xy 57.847738 -387.084062) (xy 57.848224 -387.058076)
			(xy 57.85636 -387.006745) (xy 57.872426 -386.957318) (xy 57.896027 -386.911014) (xy 57.926581 -386.868971)
			(xy 57.963335 -386.832226) (xy 58.005385 -386.801683) (xy 58.051696 -386.778094) (xy 58.101127 -386.762041)
			(xy 58.15246 -386.753917) (xy 58.178446 -386.753354) (xy 58.202644 -386.75382) (xy 58.250518 -386.760913)
			(xy 58.296851 -386.774897) (xy 58.340655 -386.795475) (xy 58.361072 -386.808472) (xy 58.371116 -386.814468)
			(xy 58.394285 -386.817498) (xy 58.416405 -386.80997) (xy 58.42508 -386.802122) (xy 58.823352 -386.40385)
			(xy 58.830769 -386.39568) (xy 58.838401 -386.375002) (xy 58.838084 -386.363972) (xy 58.831226 -386.276088)
			(xy 58.820304 -386.25653) (xy 58.811414 -386.249926) (xy 58.793133 -386.236092) (xy 58.760543 -386.20385)
			(xy 58.733147 -386.167092) (xy 58.722006 -386.147056) (xy 58.721498 -386.146294) (xy 58.323734 -385.457954)
			(xy 58.31184 -385.435284) (xy 58.294975 -385.386953) (xy 58.286423 -385.336483) (xy 58.285888 -385.310888)
			(xy 58.285888 -385.31038) (xy 58.286375 -385.285464) (xy 58.294454 -385.236293) (xy 58.310412 -385.189086)
			(xy 58.321702 -385.16687) (xy 58.321702 -385.166616) (xy 58.333345 -385.145707) (xy 58.362126 -385.107471)
			(xy 58.396517 -385.074193) (xy 58.435677 -385.046685) (xy 58.478649 -385.025621) (xy 58.524379 -385.011516)
			(xy 58.57175 -385.004716) (xy 58.619602 -385.005387) (xy 58.666763 -385.013512) (xy 58.71208 -385.028894)
			(xy 58.754444 -385.051154) (xy 58.792818 -385.079749) (xy 58.826263 -385.113979) (xy 58.85396 -385.153006)
			(xy 58.865008 -385.174236) (xy 58.86577 -385.17576) (xy 58.943884 -385.310888) (xy 59.485784 -385.310888)
			(xy 59.485784 -385.31038) (xy 59.486277 -385.285452) (xy 59.494428 -385.236266) (xy 59.510508 -385.189073)
			(xy 59.521852 -385.16687) (xy 59.521852 -385.166616) (xy 59.533437 -385.145679) (xy 59.562236 -385.107464)
			(xy 59.59664 -385.074206) (xy 59.635807 -385.046717) (xy 59.67878 -385.025669) (xy 59.724509 -385.011576)
			(xy 59.771876 -385.004784) (xy 59.819722 -385.005458) (xy 59.866879 -385.013583) (xy 59.912193 -385.028958)
			(xy 59.954556 -385.051208) (xy 59.992933 -385.07979) (xy 60.026386 -385.114005) (xy 60.054097 -385.153016)
			(xy 60.065158 -385.174236) (xy 60.06592 -385.17576) (xy 60.144034 -385.310888) (xy 60.68568 -385.310888)
			(xy 60.68568 -385.31038) (xy 60.686174 -385.285452) (xy 60.694325 -385.236266) (xy 60.710404 -385.189073)
			(xy 60.721748 -385.16687) (xy 60.721748 -385.166616) (xy 60.733339 -385.145682) (xy 60.762137 -385.107468)
			(xy 60.79654 -385.07421) (xy 60.835707 -385.046721) (xy 60.87868 -385.025673) (xy 60.924408 -385.01158)
			(xy 60.971774 -385.004788) (xy 61.01962 -385.005462) (xy 61.066776 -385.013586) (xy 61.11209 -385.02896)
			(xy 61.154452 -385.05121) (xy 61.192829 -385.079792) (xy 61.226282 -385.114006) (xy 61.253993 -385.153016)
			(xy 61.265054 -385.174236) (xy 61.265816 -385.17576) (xy 61.34393 -385.310888) (xy 61.885576 -385.310888)
			(xy 61.885576 -385.31038) (xy 61.88607 -385.285452) (xy 61.894221 -385.236266) (xy 61.9103 -385.189073)
			(xy 61.921644 -385.16687) (xy 61.921644 -385.166616) (xy 61.933241 -385.145686) (xy 61.962039 -385.107472)
			(xy 61.996441 -385.074214) (xy 62.035607 -385.046725) (xy 62.078579 -385.025677) (xy 62.124307 -385.011584)
			(xy 62.171673 -385.004792) (xy 62.219518 -385.005465) (xy 62.266674 -385.013589) (xy 62.311986 -385.028963)
			(xy 62.354349 -385.051212) (xy 62.392726 -385.079793) (xy 62.426178 -385.114007) (xy 62.453889 -385.153016)
			(xy 62.46495 -385.174236) (xy 62.465712 -385.17576) (xy 62.543826 -385.310888) (xy 63.08598 -385.310888)
			(xy 63.08598 -385.31038) (xy 63.086469 -385.285466) (xy 63.094566 -385.2363) (xy 63.110527 -385.189096)
			(xy 63.121794 -385.16687) (xy 63.121794 -385.166616) (xy 63.133466 -385.14573) (xy 63.162257 -385.107519)
			(xy 63.196652 -385.074263) (xy 63.23581 -385.046775) (xy 63.278774 -385.025727) (xy 63.324495 -385.011633)
			(xy 63.371853 -385.004838) (xy 63.419691 -385.005508) (xy 63.46684 -385.013626) (xy 63.512148 -385.028995)
			(xy 63.554506 -385.051238) (xy 63.592879 -385.079812) (xy 63.626329 -385.114018) (xy 63.654039 -385.15302)
			(xy 63.6651 -385.174236) (xy 63.665862 -385.17576) (xy 63.743976 -385.310888) (xy 64.285876 -385.310888)
			(xy 64.285876 -385.31038) (xy 64.286366 -385.285466) (xy 64.294463 -385.2363) (xy 64.310423 -385.189096)
			(xy 64.32169 -385.16687) (xy 64.32169 -385.166616) (xy 64.333368 -385.145733) (xy 64.362158 -385.107523)
			(xy 64.396553 -385.074267) (xy 64.43571 -385.046779) (xy 64.478674 -385.025731) (xy 64.524394 -385.011637)
			(xy 64.571751 -385.004841) (xy 64.619589 -385.005511) (xy 64.666738 -385.013629) (xy 64.712045 -385.028998)
			(xy 64.754403 -385.05124) (xy 64.792776 -385.079814) (xy 64.826225 -385.114019) (xy 64.853935 -385.153021)
			(xy 64.864996 -385.174236) (xy 64.865758 -385.17576) (xy 64.943872 -385.310888) (xy 65.485772 -385.310888)
			(xy 65.485772 -385.31038) (xy 65.486267 -385.285452) (xy 65.494417 -385.236266) (xy 65.510496 -385.189073)
			(xy 65.52184 -385.16687) (xy 65.52184 -385.166616) (xy 65.533443 -385.145689) (xy 65.56224 -385.107475)
			(xy 65.596642 -385.074218) (xy 65.635808 -385.046729) (xy 65.678779 -385.025681) (xy 65.724506 -385.011588)
			(xy 65.771871 -385.004795) (xy 65.819716 -385.005469) (xy 65.866871 -385.013592) (xy 65.912183 -385.028966)
			(xy 65.954546 -385.051215) (xy 65.992922 -385.079795) (xy 66.026374 -385.114008) (xy 66.054085 -385.153017)
			(xy 66.065146 -385.174236) (xy 66.065908 -385.17576) (xy 66.438272 -385.819904) (xy 66.438526 -385.820412)
			(xy 66.458084 -385.85394) (xy 66.470335 -385.876866) (xy 66.487749 -385.925839) (xy 66.496632 -385.977051)
			(xy 66.4972 -386.003038) (xy 66.4972 -386.003292) (xy 66.496754 -386.027298) (xy 66.48924 -386.074718)
			(xy 66.474396 -386.120378) (xy 66.452589 -386.163152) (xy 66.424356 -386.201985) (xy 66.390392 -386.235921)
			(xy 66.351535 -386.264122) (xy 66.308743 -386.285894) (xy 66.263071 -386.300699) (xy 66.215644 -386.308173)
			(xy 66.191638 -386.3086) (xy 66.191384 -386.3086) (xy 66.16781 -386.308219) (xy 66.121221 -386.300975)
			(xy 66.076302 -386.286647) (xy 66.034123 -386.265576) (xy 65.995691 -386.238265) (xy 65.961919 -386.205363)
			(xy 65.933614 -386.167656) (xy 65.922144 -386.147056) (xy 65.921636 -386.146294) (xy 65.523872 -385.457954)
			(xy 65.511936 -385.435296) (xy 65.495006 -385.386965) (xy 65.486355 -385.336492) (xy 65.485772 -385.310888)
			(xy 64.943872 -385.310888) (xy 65.238122 -385.819904) (xy 65.238376 -385.820412) (xy 65.257934 -385.85394)
			(xy 65.270149 -385.876873) (xy 65.287475 -385.925854) (xy 65.29627 -385.97706) (xy 65.296796 -386.003038)
			(xy 65.296796 -386.003292) (xy 65.296354 -386.027286) (xy 65.288848 -386.074682) (xy 65.27402 -386.12032)
			(xy 65.252235 -386.163077) (xy 65.224029 -386.2019) (xy 65.190097 -386.235831) (xy 65.151274 -386.264037)
			(xy 65.108517 -386.285822) (xy 65.062878 -386.300649) (xy 65.015482 -386.308155) (xy 64.991488 -386.3086)
			(xy 64.991234 -386.3086) (xy 64.967661 -386.308179) (xy 64.921074 -386.300942) (xy 64.876156 -386.286622)
			(xy 64.833978 -386.265557) (xy 64.795544 -386.238252) (xy 64.761772 -386.205356) (xy 64.733465 -386.167654)
			(xy 64.721994 -386.147056) (xy 64.721486 -386.146294) (xy 64.323722 -385.457954) (xy 64.311861 -385.43527)
			(xy 64.295005 -385.38694) (xy 64.286426 -385.33648) (xy 64.285876 -385.310888) (xy 63.743976 -385.310888)
			(xy 64.038226 -385.819904) (xy 64.03848 -385.820412) (xy 64.058038 -385.85394) (xy 64.070253 -385.876873)
			(xy 64.087579 -385.925854) (xy 64.096374 -385.97706) (xy 64.0969 -386.003038) (xy 64.0969 -386.003292)
			(xy 64.096454 -386.027285) (xy 64.088949 -386.074681) (xy 64.074121 -386.12032) (xy 64.052336 -386.163076)
			(xy 64.02413 -386.201898) (xy 63.990198 -386.23583) (xy 63.951376 -386.264036) (xy 63.90862 -386.285821)
			(xy 63.862981 -386.300649) (xy 63.815585 -386.308154) (xy 63.791592 -386.3086) (xy 63.791338 -386.3086)
			(xy 63.767765 -386.308176) (xy 63.721178 -386.30094) (xy 63.67626 -386.28662) (xy 63.634082 -386.265556)
			(xy 63.595648 -386.238251) (xy 63.561876 -386.205356) (xy 63.533569 -386.167654) (xy 63.522098 -386.147056)
			(xy 63.52159 -386.146294) (xy 63.123826 -385.457954) (xy 63.111965 -385.43527) (xy 63.095109 -385.38694)
			(xy 63.08653 -385.33648) (xy 63.08598 -385.310888) (xy 62.543826 -385.310888) (xy 62.838076 -385.819904)
			(xy 62.83833 -385.820412) (xy 62.857888 -385.85394) (xy 62.870139 -385.876866) (xy 62.887553 -385.925839)
			(xy 62.896436 -385.977051) (xy 62.897004 -386.003038) (xy 62.897004 -386.003292) (xy 62.896554 -386.027298)
			(xy 62.88904 -386.074718) (xy 62.874197 -386.120377) (xy 62.85239 -386.163151) (xy 62.824157 -386.201984)
			(xy 62.790194 -386.23592) (xy 62.751337 -386.264121) (xy 62.708546 -386.285893) (xy 62.662874 -386.300698)
			(xy 62.615448 -386.308173) (xy 62.591442 -386.3086) (xy 62.591188 -386.3086) (xy 62.567614 -386.308216)
			(xy 62.521025 -386.300973) (xy 62.476106 -386.286645) (xy 62.433928 -386.265575) (xy 62.395495 -386.238264)
			(xy 62.361723 -386.205363) (xy 62.333418 -386.167656) (xy 62.321948 -386.147056) (xy 62.32144 -386.146294)
			(xy 61.923676 -385.457954) (xy 61.91174 -385.435296) (xy 61.89481 -385.386965) (xy 61.886159 -385.336492)
			(xy 61.885576 -385.310888) (xy 61.34393 -385.310888) (xy 61.63818 -385.819904) (xy 61.638434 -385.820412)
			(xy 61.657992 -385.85394) (xy 61.670243 -385.876866) (xy 61.687657 -385.925839) (xy 61.69654 -385.977051)
			(xy 61.697108 -386.003038) (xy 61.697108 -386.003292) (xy 61.696654 -386.027298) (xy 61.68914 -386.074717)
			(xy 61.674297 -386.120377) (xy 61.652491 -386.16315) (xy 61.624258 -386.201983) (xy 61.590295 -386.235918)
			(xy 61.55144 -386.264119) (xy 61.508649 -386.285891) (xy 61.462978 -386.300698) (xy 61.415552 -386.308173)
			(xy 61.391546 -386.3086) (xy 61.391292 -386.3086) (xy 61.367718 -386.308213) (xy 61.321129 -386.30097)
			(xy 61.27621 -386.286643) (xy 61.234032 -386.265573) (xy 61.195599 -386.238263) (xy 61.161828 -386.205362)
			(xy 61.133522 -386.167656) (xy 61.122052 -386.147056) (xy 61.121544 -386.146294) (xy 60.72378 -385.457954)
			(xy 60.711844 -385.435296) (xy 60.694915 -385.386965) (xy 60.686263 -385.336492) (xy 60.68568 -385.310888)
			(xy 60.144034 -385.310888) (xy 60.438284 -385.819904) (xy 60.438538 -385.820412) (xy 60.458096 -385.85394)
			(xy 60.470348 -385.876866) (xy 60.487761 -385.925839) (xy 60.496644 -385.977051) (xy 60.497212 -386.003038)
			(xy 60.497212 -386.003292) (xy 60.496754 -386.027297) (xy 60.48924 -386.074717) (xy 60.474398 -386.120376)
			(xy 60.452591 -386.163149) (xy 60.424359 -386.201981) (xy 60.390397 -386.235917) (xy 60.351542 -386.264118)
			(xy 60.308752 -386.28589) (xy 60.263081 -386.300697) (xy 60.215656 -386.308172) (xy 60.19165 -386.3086)
			(xy 60.191396 -386.3086) (xy 60.167822 -386.308209) (xy 60.121233 -386.300967) (xy 60.076315 -386.286641)
			(xy 60.034136 -386.265572) (xy 59.995703 -386.238262) (xy 59.961932 -386.205362) (xy 59.933626 -386.167656)
			(xy 59.922156 -386.147056) (xy 59.921648 -386.146294) (xy 59.523884 -385.457954) (xy 59.511948 -385.435296)
			(xy 59.495019 -385.386965) (xy 59.486367 -385.336492) (xy 59.485784 -385.310888) (xy 58.943884 -385.310888)
			(xy 59.238134 -385.819904) (xy 59.238388 -385.820412) (xy 59.257946 -385.85394) (xy 59.270177 -385.876865)
			(xy 59.287505 -385.925848) (xy 59.296284 -385.977059) (xy 59.296808 -386.003038) (xy 59.296808 -386.003292)
			(xy 59.296808 -386.013706) (xy 59.2963 -386.023866) (xy 59.303158 -386.042408) (xy 59.365642 -386.109972)
			(xy 59.383422 -386.118354) (xy 59.393582 -386.118608) (xy 59.417613 -386.120136) (xy 59.46489 -386.12927)
			(xy 59.510346 -386.145153) (xy 59.553024 -386.16745) (xy 59.592023 -386.195692) (xy 59.626522 -386.229283)
			(xy 59.641486 -386.248148) (xy 59.649034 -386.257084) (xy 59.66994 -386.26752) (xy 59.681618 -386.268214)
			(xy 59.76493 -386.268214) (xy 59.789889 -386.268788) (xy 59.838848 -386.278533) (xy 59.884964 -386.297641)
			(xy 59.926467 -386.32538) (xy 59.944508 -386.342636) (xy 60.389262 -386.78739) (xy 60.420758 -386.792978)
			(xy 60.435744 -386.785866) (xy 60.458136 -386.775631) (xy 60.505194 -386.761163) (xy 60.553876 -386.753832)
			(xy 60.578492 -386.753354) (xy 60.604481 -386.753863) (xy 60.655818 -386.761992) (xy 60.705252 -386.778052)
			(xy 60.751566 -386.801647) (xy 60.793618 -386.832196) (xy 60.830374 -386.868947) (xy 60.860929 -386.910995)
			(xy 60.88453 -386.957305) (xy 60.900597 -387.006737) (xy 60.908733 -387.058073) (xy 60.9092 -387.084062)
			(xy 60.908729 -387.108678) (xy 60.901393 -387.157361) (xy 60.886924 -387.204418) (xy 60.876688 -387.22681)
			(xy 60.869576 -387.241796) (xy 60.875164 -387.273292) (xy 61.21146 -387.609588) (xy 61.218861 -387.616426)
			(xy 61.237459 -387.624141) (xy 61.247528 -387.624574) (xy 61.573156 -387.624574) (xy 61.599318 -387.605524)
			(xy 61.604652 -387.589776) (xy 61.613256 -387.565369) (xy 61.636967 -387.519373) (xy 61.667553 -387.477632)
			(xy 61.704267 -387.441165) (xy 61.746214 -387.410861) (xy 61.792369 -387.387462) (xy 61.841606 -387.371537)
			(xy 61.892722 -387.363477) (xy 61.94447 -387.363477) (xy 61.995586 -387.371537) (xy 62.044823 -387.387462)
			(xy 62.090978 -387.410861) (xy 62.132925 -387.441165) (xy 62.169639 -387.477632) (xy 62.200225 -387.519373)
			(xy 62.223936 -387.565369) (xy 62.23254 -387.589776) (xy 62.237874 -387.605524) (xy 62.264036 -387.624574)
			(xy 62.773052 -387.624574) (xy 62.799214 -387.605524) (xy 62.804548 -387.589776) (xy 62.813152 -387.565369)
			(xy 62.836863 -387.519373) (xy 62.867449 -387.477632) (xy 62.904163 -387.441165) (xy 62.94611 -387.410861)
			(xy 62.992265 -387.387462) (xy 63.041502 -387.371537) (xy 63.092618 -387.363477) (xy 63.144366 -387.363477)
			(xy 63.195482 -387.371537) (xy 63.244719 -387.387462) (xy 63.290874 -387.410861) (xy 63.332821 -387.441165)
			(xy 63.369535 -387.477632) (xy 63.400121 -387.519373) (xy 63.423832 -387.565369) (xy 63.432436 -387.589776)
			(xy 63.43777 -387.605524) (xy 63.463932 -387.624574) (xy 63.973202 -387.624574) (xy 63.999364 -387.605524)
			(xy 64.004698 -387.589776) (xy 64.013302 -387.565369) (xy 64.037013 -387.519373) (xy 64.067599 -387.477632)
			(xy 64.104313 -387.441165) (xy 64.14626 -387.410861) (xy 64.192415 -387.387462) (xy 64.241652 -387.371537)
			(xy 64.292768 -387.363477) (xy 64.344516 -387.363477) (xy 64.395632 -387.371537) (xy 64.444869 -387.387462)
			(xy 64.491024 -387.410861) (xy 64.532971 -387.441165) (xy 64.569685 -387.477632) (xy 64.600271 -387.519373)
			(xy 64.623982 -387.565369) (xy 64.632586 -387.589776) (xy 64.63792 -387.605524) (xy 64.664082 -387.624574)
			(xy 65.173098 -387.624574) (xy 65.19926 -387.605524) (xy 65.204594 -387.589776) (xy 65.213198 -387.565369)
			(xy 65.236909 -387.519373) (xy 65.267495 -387.477632) (xy 65.304209 -387.441165) (xy 65.346156 -387.410861)
			(xy 65.392311 -387.387462) (xy 65.441548 -387.371537) (xy 65.492664 -387.363477) (xy 65.544412 -387.363477)
			(xy 65.595528 -387.371537) (xy 65.644765 -387.387462) (xy 65.69092 -387.410861) (xy 65.732867 -387.441165)
			(xy 65.769581 -387.477632) (xy 65.800167 -387.519373) (xy 65.823878 -387.565369) (xy 65.832482 -387.589776)
			(xy 65.837816 -387.605524) (xy 65.863978 -387.624574) (xy 69.03212 -387.624574) (xy 69.042188 -387.624147)
			(xy 69.060785 -387.616424) (xy 69.068188 -387.609588) (xy 69.487034 -387.190742) (xy 69.493879 -387.183344)
			(xy 69.501602 -387.164745) (xy 69.50202 -387.154674) (xy 69.50202 -386.689346) (xy 69.502592 -386.665251)
			(xy 69.511691 -386.617927) (xy 69.529552 -386.573169) (xy 69.555535 -386.532583) (xy 69.588706 -386.497626)
			(xy 69.607938 -386.483098) (xy 69.617372 -386.475442) (xy 69.628393 -386.453828) (xy 69.62902 -386.441696)
			(xy 69.62902 -386.32003) (xy 69.62959 -386.303457) (xy 69.638208 -386.271449) (xy 69.65479 -386.242746)
			(xy 69.666104 -386.230622) (xy 69.791834 -386.105146) (xy 69.798679 -386.097748) (xy 69.806404 -386.079149)
			(xy 69.80682 -386.069078) (xy 69.80682 -384.86842) (xy 69.806201 -384.856281) (xy 69.795197 -384.834649)
			(xy 69.785738 -384.827018) (xy 69.76648 -384.812521) (xy 69.733303 -384.77756) (xy 69.707319 -384.736967)
			(xy 69.689462 -384.692201) (xy 69.680373 -384.644868) (xy 69.67982 -384.62077) (xy 69.67982 -383.948178)
			(xy 69.679394 -383.938109) (xy 69.671676 -383.919509) (xy 69.664834 -383.91211) (xy 69.499226 -383.746502)
			(xy 69.491823 -383.739667) (xy 69.473225 -383.731959) (xy 69.463158 -383.731516) (xy 54.846474 -383.731516)
			(xy 54.836406 -383.731944) (xy 54.81781 -383.739667) (xy 54.810406 -383.746502) (xy 54.727602 -383.829306)
			(xy 54.710861 -383.845355) (xy 54.672694 -383.87169) (xy 54.63038 -383.890659) (xy 54.607968 -383.896616)
			(xy 54.60111 -383.89814) (xy 54.589172 -383.904998) (xy 54.370224 -384.123946) (xy 54.363382 -384.131346)
			(xy 54.355661 -384.149944) (xy 54.355238 -384.160014) (xy 54.355238 -385.310888) (xy 54.685692 -385.310888)
			(xy 54.685692 -385.31038) (xy 54.686121 -385.286374) (xy 54.693638 -385.238953) (xy 54.708485 -385.193293)
			(xy 54.730295 -385.15052) (xy 54.758531 -385.111687) (xy 54.792496 -385.077752) (xy 54.831354 -385.049552)
			(xy 54.874147 -385.02778) (xy 54.91982 -385.012974) (xy 54.967247 -385.005499) (xy 54.991254 -385.005072)
			(xy 55.015189 -385.005536) (xy 55.062474 -385.012994) (xy 55.108017 -385.027736) (xy 55.150703 -385.0494)
			(xy 55.189489 -385.077456) (xy 55.223424 -385.111218) (xy 55.251679 -385.149859) (xy 55.263034 -385.170934)
			(xy 55.263542 -385.17195) (xy 55.343848 -385.310888) (xy 55.885588 -385.310888) (xy 55.885588 -385.31038)
			(xy 55.886021 -385.286374) (xy 55.893538 -385.238954) (xy 55.908385 -385.193294) (xy 55.930194 -385.150521)
			(xy 55.95843 -385.111689) (xy 55.992394 -385.077754) (xy 56.031252 -385.049553) (xy 56.074044 -385.027781)
			(xy 56.119717 -385.012975) (xy 56.167143 -385.0055) (xy 56.19115 -385.005072) (xy 56.215085 -385.005539)
			(xy 56.262369 -385.012997) (xy 56.307912 -385.027738) (xy 56.350599 -385.049401) (xy 56.389384 -385.077457)
			(xy 56.42332 -385.111218) (xy 56.451575 -385.149859) (xy 56.46293 -385.170934) (xy 56.463438 -385.17195)
			(xy 56.543744 -385.310888) (xy 57.085992 -385.310888) (xy 57.085992 -385.31038) (xy 57.08648 -385.285466)
			(xy 57.094577 -385.236299) (xy 57.110538 -385.189096) (xy 57.121806 -385.16687) (xy 57.121806 -385.166616)
			(xy 57.13346 -385.145719) (xy 57.162252 -385.107508) (xy 57.196649 -385.074251) (xy 57.235809 -385.046763)
			(xy 57.278776 -385.025715) (xy 57.324498 -385.011621) (xy 57.371858 -385.004827) (xy 57.419698 -385.005498)
			(xy 57.466848 -385.013617) (xy 57.512157 -385.028987) (xy 57.554516 -385.051232) (xy 57.59289 -385.079808)
			(xy 57.626341 -385.114016) (xy 57.654051 -385.153019) (xy 57.665112 -385.174236) (xy 57.665874 -385.17576)
			(xy 58.038238 -385.819904) (xy 58.038492 -385.820412) (xy 58.05805 -385.85394) (xy 58.070266 -385.876872)
			(xy 58.087592 -385.925854) (xy 58.096386 -385.97706) (xy 58.096912 -386.003038) (xy 58.096912 -386.003292)
			(xy 58.096454 -386.027285) (xy 58.088949 -386.07468) (xy 58.074122 -386.120317) (xy 58.052338 -386.163073)
			(xy 58.024134 -386.201894) (xy 57.990203 -386.235826) (xy 57.951383 -386.264032) (xy 57.908628 -386.285817)
			(xy 57.862991 -386.300646) (xy 57.815597 -386.308154) (xy 57.791604 -386.3086) (xy 57.79135 -386.3086)
			(xy 57.767777 -386.308166) (xy 57.721191 -386.300932) (xy 57.676273 -386.286613) (xy 57.634095 -386.265551)
			(xy 57.595661 -386.238248) (xy 57.561888 -386.205354) (xy 57.533581 -386.167653) (xy 57.52211 -386.147056)
			(xy 57.521602 -386.146294) (xy 57.123838 -385.457954) (xy 57.111978 -385.435269) (xy 57.095122 -385.38694)
			(xy 57.086542 -385.33648) (xy 57.085992 -385.310888) (xy 56.543744 -385.310888) (xy 56.855868 -385.850892)
			(xy 56.868624 -385.874246) (xy 56.88673 -385.92428) (xy 56.89593 -385.976688) (xy 56.896508 -386.003292)
			(xy 56.896054 -386.027285) (xy 56.888549 -386.07468) (xy 56.873721 -386.120318) (xy 56.851937 -386.163074)
			(xy 56.823732 -386.201896) (xy 56.789802 -386.235827) (xy 56.750981 -386.264033) (xy 56.708225 -386.285818)
			(xy 56.662588 -386.300647) (xy 56.615193 -386.308154) (xy 56.5912 -386.3086) (xy 56.567626 -386.308206)
			(xy 56.521038 -386.300965) (xy 56.476119 -386.286639) (xy 56.433941 -386.26557) (xy 56.395508 -386.238261)
			(xy 56.361736 -386.205361) (xy 56.33343 -386.167656) (xy 56.32196 -386.147056) (xy 56.321452 -386.146294)
			(xy 55.923688 -385.457954) (xy 55.911753 -385.435296) (xy 55.894823 -385.386965) (xy 55.886171 -385.336491)
			(xy 55.885588 -385.310888) (xy 55.343848 -385.310888) (xy 55.655972 -385.850892) (xy 55.668728 -385.874246)
			(xy 55.686834 -385.92428) (xy 55.696034 -385.976688) (xy 55.696612 -386.003292) (xy 55.696154 -386.027285)
			(xy 55.688649 -386.07468) (xy 55.673822 -386.120317) (xy 55.652038 -386.163073) (xy 55.623834 -386.201894)
			(xy 55.589903 -386.235826) (xy 55.551083 -386.264032) (xy 55.508328 -386.285817) (xy 55.462691 -386.300646)
			(xy 55.415297 -386.308154) (xy 55.391304 -386.3086) (xy 55.36773 -386.308203) (xy 55.321142 -386.300962)
			(xy 55.276223 -386.286637) (xy 55.234045 -386.265569) (xy 55.195612 -386.23826) (xy 55.16184 -386.205361)
			(xy 55.133535 -386.167656) (xy 55.122064 -386.147056) (xy 55.121556 -386.146294) (xy 54.723792 -385.457954)
			(xy 54.711857 -385.435295) (xy 54.694927 -385.386965) (xy 54.686275 -385.336491) (xy 54.685692 -385.310888)
			(xy 54.355238 -385.310888) (xy 54.355238 -385.662678) (xy 54.355429 -385.669347) (xy 54.358896 -385.682225)
			(xy 54.362096 -385.688078) (xy 54.456076 -385.850892) (xy 54.468881 -385.874225) (xy 54.487025 -385.924258)
			(xy 54.496201 -385.976681) (xy 54.496716 -386.003292) (xy 54.496305 -386.026824) (xy 54.48913 -386.073336)
			(xy 54.474903 -386.118197) (xy 54.45396 -386.160343) (xy 54.426799 -386.198777) (xy 54.394061 -386.232587)
			(xy 54.375558 -386.247132) (xy 54.366484 -386.254681) (xy 54.355872 -386.275733) (xy 54.355238 -386.287518)
			(xy 54.355238 -387.775958) (xy 54.355672 -387.786023) (xy 54.363406 -387.804608) (xy 54.370224 -387.812026)
			(xy 54.591204 -388.033006) (xy 54.618382 -388.039864) (xy 54.63159 -388.036054) (xy 54.652818 -388.030135)
			(xy 54.696424 -388.023755) (xy 54.718458 -388.023354) (xy 54.743146 -388.023855) (xy 54.791872 -388.031844)
			(xy 54.838682 -388.047557) (xy 54.88236 -388.070586) (xy 54.902354 -388.085076) (xy 54.909153 -388.089767)
			(xy 54.924832 -388.094936) (xy 54.933088 -388.095236)
		)
		(stroke
			(width 0)
			(type solid)
		)
		(fill yes)
		(layer "In9.Cu")
		(net "P1V8_CPU1_RT0_1A")
	)
	(gr_poly
		(pts
			(xy 346.84208 -256.362454) (xy 346.854018 -256.354834) (xy 346.873964 -256.342667) (xy 346.916558 -256.323466)
			(xy 346.961434 -256.310465) (xy 347.007695 -256.303924) (xy 347.031056 -256.303526) (xy 347.044772 -256.30378)
			(xy 347.058742 -256.304288) (xy 347.083634 -256.290826) (xy 347.229176 -256.040382) (xy 347.228668 -256.011934)
			(xy 347.221048 -255.999996) (xy 347.209073 -255.980154) (xy 347.190182 -255.937834) (xy 347.177378 -255.893292)
			(xy 347.17091 -255.847401) (xy 347.170502 -255.824228) (xy 347.170983 -255.798238) (xy 347.179111 -255.746896)
			(xy 347.195171 -255.697459) (xy 347.218767 -255.651142) (xy 347.249319 -255.609088) (xy 347.286074 -255.572331)
			(xy 347.328127 -255.541777) (xy 347.374442 -255.518178) (xy 347.423879 -255.502115) (xy 347.47522 -255.493984)
			(xy 347.50121 -255.49352) (xy 347.526889 -255.494006) (xy 347.57763 -255.501948) (xy 347.626533 -255.517639)
			(xy 347.672421 -255.540702) (xy 347.714193 -255.570582) (xy 347.750842 -255.606562) (xy 347.781489 -255.647774)
			(xy 347.793818 -255.670304) (xy 347.800422 -255.68275) (xy 347.824806 -255.697482) (xy 348.117414 -255.697482)
			(xy 348.141798 -255.68275) (xy 348.148402 -255.670304) (xy 348.160086 -255.64973) (xy 348.167452 -255.637792)
			(xy 348.16796 -255.609852) (xy 348.021656 -255.35763) (xy 347.997272 -255.344168) (xy 347.983048 -255.344676)
			(xy 347.97111 -255.34493) (xy 347.945118 -255.344448) (xy 347.893775 -255.336317) (xy 347.844336 -255.320255)
			(xy 347.798018 -255.296656) (xy 347.755963 -255.266102) (xy 347.719205 -255.229345) (xy 347.688649 -255.18729)
			(xy 347.665049 -255.140973) (xy 347.648985 -255.091534) (xy 347.640853 -255.040191) (xy 347.640853 -254.988209)
			(xy 347.648985 -254.936866) (xy 347.665049 -254.887427) (xy 347.688649 -254.84111) (xy 347.719205 -254.799055)
			(xy 347.755963 -254.762298) (xy 347.798018 -254.731744) (xy 347.844336 -254.708145) (xy 347.893775 -254.692083)
			(xy 347.945118 -254.683952) (xy 347.97111 -254.683514) (xy 347.994066 -254.683921) (xy 348.039532 -254.690301)
			(xy 348.083678 -254.70291) (xy 348.125656 -254.721504) (xy 348.145354 -254.733298) (xy 348.157292 -254.740664)
			(xy 348.185232 -254.741172) (xy 349.037148 -254.251714) (xy 349.050864 -254.22733) (xy 349.050356 -254.21336)
			(xy 349.050356 -254.204216) (xy 349.05061 -254.192024) (xy 349.051118 -254.178054) (xy 349.037402 -254.153162)
			(xy 348.18828 -253.665482) (xy 348.159832 -253.66599) (xy 348.147894 -253.67361) (xy 348.127975 -253.685761)
			(xy 348.085443 -253.704943) (xy 348.040633 -253.717944) (xy 347.994439 -253.724503) (xy 347.97111 -253.724918)
			(xy 347.945119 -253.724436) (xy 347.893778 -253.716305) (xy 347.844341 -253.700244) (xy 347.798025 -253.676646)
			(xy 347.755971 -253.646093) (xy 347.719214 -253.609337) (xy 347.68866 -253.567284) (xy 347.66506 -253.520968)
			(xy 347.648997 -253.471532) (xy 347.640865 -253.420191) (xy 347.640865 -253.368209) (xy 347.648997 -253.316868)
			(xy 347.66506 -253.267432) (xy 347.68866 -253.221116) (xy 347.719214 -253.179063) (xy 347.755971 -253.142307)
			(xy 347.798025 -253.111754) (xy 347.844341 -253.088156) (xy 347.893778 -253.072095) (xy 347.945119 -253.063964)
			(xy 347.97111 -253.063502) (xy 347.994066 -253.063909) (xy 348.039532 -253.070289) (xy 348.083679 -253.082897)
			(xy 348.125657 -253.10149) (xy 348.145354 -253.113286) (xy 348.157292 -253.120652) (xy 348.185232 -253.12116)
			(xy 349.037148 -252.631702) (xy 349.050864 -252.607318) (xy 349.050356 -252.593348) (xy 349.050356 -252.584204)
			(xy 349.050865 -252.558216) (xy 349.058995 -252.506879) (xy 349.075055 -252.457445) (xy 349.09865 -252.411132)
			(xy 349.129199 -252.369081) (xy 349.16595 -252.332325) (xy 349.207998 -252.301771) (xy 349.254308 -252.278171)
			(xy 349.30374 -252.262104) (xy 349.355076 -252.253968) (xy 349.381064 -252.253496) (xy 349.391224 -252.25375)
			(xy 349.405194 -252.254004) (xy 349.429578 -252.240542) (xy 349.576898 -251.986796) (xy 349.57639 -251.958856)
			(xy 349.569024 -251.946918) (xy 349.557493 -251.927337) (xy 349.539322 -251.885686) (xy 349.527029 -251.841938)
			(xy 349.520844 -251.796919) (xy 349.52051 -251.774198) (xy 349.520897 -251.751325) (xy 349.527199 -251.706015)
			(xy 349.539682 -251.662005) (xy 349.558109 -251.620134) (xy 349.569786 -251.600462) (xy 349.577406 -251.58827)
			(xy 349.57766 -251.56033) (xy 349.431102 -251.3076) (xy 349.406718 -251.294138) (xy 349.392494 -251.294646)
			(xy 349.381064 -251.2949) (xy 349.355079 -251.294388) (xy 349.303749 -251.286253) (xy 349.254324 -251.270188)
			(xy 349.20802 -251.246591) (xy 349.165978 -251.21604) (xy 349.129231 -251.179289) (xy 349.098686 -251.137242)
			(xy 349.075095 -251.090935) (xy 349.059037 -251.041508) (xy 349.050909 -250.990177) (xy 349.050356 -250.964192)
			(xy 349.05061 -250.952254) (xy 349.051118 -250.93803) (xy 349.037656 -250.913646) (xy 348.187772 -250.425458)
			(xy 348.159832 -250.425966) (xy 348.147894 -250.43384) (xy 348.127961 -250.445948) (xy 348.085416 -250.465051)
			(xy 348.040609 -250.477988) (xy 347.994429 -250.4845) (xy 347.97111 -250.484894) (xy 347.945121 -250.484412)
			(xy 347.893782 -250.476282) (xy 347.844347 -250.46022) (xy 347.798033 -250.436623) (xy 347.755981 -250.40607)
			(xy 347.719227 -250.369316) (xy 347.688675 -250.327263) (xy 347.665078 -250.28095) (xy 347.649018 -250.231514)
			(xy 347.640888 -250.180175) (xy 347.640402 -250.154186) (xy 347.640794 -250.131272) (xy 347.647132 -250.085883)
			(xy 347.659684 -250.041806) (xy 347.678208 -249.999888) (xy 347.689932 -249.980196) (xy 347.697298 -249.968258)
			(xy 347.697552 -249.940318) (xy 347.550994 -249.687588) (xy 347.52661 -249.674126) (xy 347.51264 -249.674634)
			(xy 347.50121 -249.674888) (xy 347.475221 -249.674406) (xy 347.423882 -249.666275) (xy 347.374448 -249.650214)
			(xy 347.328134 -249.626616) (xy 347.286083 -249.596064) (xy 347.24933 -249.559309) (xy 347.218778 -249.517257)
			(xy 347.195182 -249.470943) (xy 347.179122 -249.421508) (xy 347.170994 -249.370169) (xy 347.170502 -249.34418)
			(xy 347.17089 -249.321307) (xy 347.177194 -249.275998) (xy 347.189679 -249.231989) (xy 347.208108 -249.19012)
			(xy 347.219778 -249.170444) (xy 347.227398 -249.158252) (xy 347.227652 -249.130566) (xy 347.081094 -248.877582)
			(xy 347.05671 -248.86412) (xy 347.042486 -248.864628) (xy 347.031056 -248.864882) (xy 347.007355 -248.864472)
			(xy 346.960438 -248.857699) (xy 346.914968 -248.844298) (xy 346.871877 -248.824544) (xy 346.851732 -248.81205)
			(xy 346.839794 -248.804176) (xy 346.8116 -248.803668) (xy 345.96451 -249.290332) (xy 345.950794 -249.31497)
			(xy 345.951556 -249.329448) (xy 345.95181 -249.34418) (xy 345.9513 -249.370167) (xy 345.94317 -249.421502)
			(xy 345.927109 -249.470932) (xy 345.903513 -249.517242) (xy 345.872963 -249.55929) (xy 345.836212 -249.596041)
			(xy 345.794164 -249.626591) (xy 345.747854 -249.650187) (xy 345.698424 -249.666248) (xy 345.647089 -249.674378)
			(xy 345.595115 -249.674378) (xy 345.54378 -249.666248) (xy 345.49435 -249.650187) (xy 345.44804 -249.626591)
			(xy 345.405992 -249.596041) (xy 345.369241 -249.55929) (xy 345.338691 -249.517242) (xy 345.315095 -249.470932)
			(xy 345.299034 -249.421502) (xy 345.290904 -249.370167) (xy 345.290394 -249.34418) (xy 345.290648 -249.332496)
			(xy 345.291156 -249.318018) (xy 345.277694 -249.293634) (xy 344.427556 -248.8057) (xy 344.39987 -248.806208)
			(xy 344.387678 -248.813828) (xy 344.367773 -248.82592) (xy 344.32529 -248.845005) (xy 344.280548 -248.857939)
			(xy 344.234435 -248.864467) (xy 344.211148 -248.864882) (xy 344.185158 -248.864403) (xy 344.133818 -248.856278)
			(xy 344.084381 -248.840221) (xy 344.038065 -248.816628) (xy 343.99601 -248.786079) (xy 343.959252 -248.749327)
			(xy 343.928697 -248.707276) (xy 343.905097 -248.660964) (xy 343.889033 -248.611529) (xy 343.880901 -248.56019)
			(xy 343.880901 -248.50821) (xy 343.889033 -248.456871) (xy 343.905097 -248.407436) (xy 343.928697 -248.361124)
			(xy 343.959252 -248.319073) (xy 343.99601 -248.282321) (xy 344.038065 -248.251772) (xy 344.084381 -248.228179)
			(xy 344.133818 -248.212122) (xy 344.185158 -248.203997) (xy 344.211148 -248.203466) (xy 344.2208 -248.20372)
			(xy 344.23477 -248.203974) (xy 344.259154 -248.190512) (xy 344.406474 -247.936512) (xy 344.40622 -247.908572)
			(xy 344.398854 -247.896634) (xy 344.387345 -247.877079) (xy 344.369206 -247.835488) (xy 344.356927 -247.791806)
			(xy 344.350738 -247.746855) (xy 344.35034 -247.724168) (xy 344.350826 -247.698182) (xy 344.358961 -247.64685)
			(xy 344.375027 -247.597423) (xy 344.398627 -247.551117) (xy 344.429181 -247.509074) (xy 344.465935 -247.472329)
			(xy 344.507986 -247.441785) (xy 344.554297 -247.418196) (xy 344.603728 -247.402142) (xy 344.655062 -247.394019)
			(xy 344.681048 -247.39346) (xy 344.6907 -247.393714) (xy 344.70467 -247.393968) (xy 344.729054 -247.380506)
			(xy 344.876628 -247.125998) (xy 344.876374 -247.098566) (xy 344.869008 -247.086374) (xy 344.85751 -247.066848)
			(xy 344.83938 -247.02532) (xy 344.827094 -246.981704) (xy 344.820881 -246.936818) (xy 344.820494 -246.914162)
			(xy 344.820883 -246.89129) (xy 344.827189 -246.845981) (xy 344.839676 -246.801974) (xy 344.858106 -246.760105)
			(xy 344.86977 -246.740426) (xy 344.877136 -246.728488) (xy 344.877644 -246.700548) (xy 344.730832 -246.447818)
			(xy 344.706448 -246.434102) (xy 344.692224 -246.43461) (xy 344.681048 -246.434864) (xy 344.655058 -246.434384)
			(xy 344.603716 -246.426259) (xy 344.554278 -246.4102) (xy 344.507961 -246.386604) (xy 344.465907 -246.356052)
			(xy 344.42915 -246.319297) (xy 344.398598 -246.277242) (xy 344.375001 -246.230926) (xy 344.358942 -246.181488)
			(xy 344.350816 -246.130146) (xy 344.35034 -246.104156) (xy 344.350723 -246.081282) (xy 344.357018 -246.035969)
			(xy 344.369496 -245.991955) (xy 344.387919 -245.95008) (xy 344.399616 -245.93042) (xy 344.407236 -245.918228)
			(xy 344.40749 -245.890288) (xy 344.260932 -245.637812) (xy 344.236548 -245.624096) (xy 344.222324 -245.624604)
			(xy 344.211148 -245.624858) (xy 344.185152 -245.624378) (xy 344.1338 -245.616252) (xy 344.084352 -245.600191)
			(xy 344.038025 -245.576593) (xy 343.995961 -245.546037) (xy 343.959195 -245.509276) (xy 343.928633 -245.467216)
			(xy 343.905027 -245.420893) (xy 343.888959 -245.371447) (xy 343.880825 -245.320096) (xy 343.880825 -245.268104)
			(xy 343.888959 -245.216753) (xy 343.905027 -245.167307) (xy 343.928633 -245.120984) (xy 343.959195 -245.078924)
			(xy 343.995961 -245.042163) (xy 344.038025 -245.011607) (xy 344.084352 -244.988009) (xy 344.1338 -244.971948)
			(xy 344.185152 -244.963822) (xy 344.211148 -244.963442) (xy 344.220546 -244.963696) (xy 344.234516 -244.96395)
			(xy 344.2589 -244.950488) (xy 344.406474 -244.696234) (xy 344.405966 -244.668294) (xy 344.398854 -244.656356)
			(xy 344.387355 -244.636831) (xy 344.369225 -244.595302) (xy 344.35694 -244.551686) (xy 344.350729 -244.506801)
			(xy 344.35034 -244.484144) (xy 344.35082 -244.458154) (xy 344.358946 -244.406813) (xy 344.375005 -244.357375)
			(xy 344.398601 -244.31106) (xy 344.429153 -244.269006) (xy 344.465909 -244.232251) (xy 344.507963 -244.201699)
			(xy 344.554279 -244.178103) (xy 344.603717 -244.162045) (xy 344.655058 -244.15392) (xy 344.681048 -244.153436)
			(xy 344.6907 -244.15369) (xy 344.70467 -244.153944) (xy 344.729054 -244.140482) (xy 344.876628 -243.885974)
			(xy 344.876374 -243.858542) (xy 344.868754 -243.84635) (xy 344.857296 -243.826812) (xy 344.83924 -243.785272)
			(xy 344.827016 -243.741658) (xy 344.82085 -243.696785) (xy 344.820494 -243.674138) (xy 344.820878 -243.651264)
			(xy 344.827175 -243.605952) (xy 344.839653 -243.561939) (xy 344.858076 -243.520064) (xy 344.86977 -243.500402)
			(xy 344.877136 -243.488464) (xy 344.877644 -243.460524) (xy 344.730832 -243.207794) (xy 344.706448 -243.194078)
			(xy 344.692224 -243.194586) (xy 344.681048 -243.19484) (xy 344.655055 -243.19436) (xy 344.603709 -243.186235)
			(xy 344.554266 -243.170178) (xy 344.507944 -243.146583) (xy 344.465883 -243.116032) (xy 344.42912 -243.079278)
			(xy 344.398559 -243.037224) (xy 344.374953 -242.990908) (xy 344.358883 -242.941469) (xy 344.350746 -242.890125)
			(xy 344.35034 -242.864132) (xy 344.350724 -242.841258) (xy 344.357023 -242.795947) (xy 344.369503 -242.751935)
			(xy 344.387929 -242.710062) (xy 344.399616 -242.690396) (xy 344.407236 -242.678204) (xy 344.40749 -242.650264)
			(xy 344.260932 -242.397788) (xy 344.236548 -242.384072) (xy 344.222324 -242.38458) (xy 344.211148 -242.384834)
			(xy 344.185154 -242.384354) (xy 344.133806 -242.376228) (xy 344.084361 -242.360169) (xy 344.038037 -242.336572)
			(xy 343.995976 -242.306018) (xy 343.959213 -242.26926) (xy 343.928653 -242.227203) (xy 343.905049 -242.180883)
			(xy 343.888983 -242.131441) (xy 343.880849 -242.080094) (xy 343.880849 -242.028106) (xy 343.888983 -241.976759)
			(xy 343.905049 -241.927317) (xy 343.928653 -241.880997) (xy 343.959213 -241.83894) (xy 343.995976 -241.802182)
			(xy 344.038038 -241.771628) (xy 344.084361 -241.748031) (xy 344.133806 -241.731972) (xy 344.185154 -241.723846)
			(xy 344.211148 -241.723418) (xy 344.220546 -241.723672) (xy 344.234516 -241.723926) (xy 344.2589 -241.710464)
			(xy 344.406474 -241.45621) (xy 344.405966 -241.42827) (xy 344.398854 -241.416332) (xy 344.387357 -241.396806)
			(xy 344.36923 -241.355277) (xy 344.356947 -241.311661) (xy 344.350739 -241.266776) (xy 344.35034 -241.24412)
			(xy 344.350822 -241.218131) (xy 344.358951 -241.166793) (xy 344.375012 -241.117359) (xy 344.398609 -241.071046)
			(xy 344.429162 -241.028996) (xy 344.465917 -240.992244) (xy 344.50797 -240.961695) (xy 344.554285 -240.938101)
			(xy 344.60372 -240.922044) (xy 344.655059 -240.913919) (xy 344.681048 -240.913412) (xy 344.6907 -240.913666)
			(xy 344.70467 -240.91392) (xy 344.729054 -240.900458) (xy 344.876628 -240.64595) (xy 344.876374 -240.618518)
			(xy 344.868754 -240.606326) (xy 344.857297 -240.586788) (xy 344.839245 -240.545247) (xy 344.827023 -240.501633)
			(xy 344.820861 -240.456761) (xy 344.820494 -240.434114) (xy 344.82088 -240.411241) (xy 344.827179 -240.365929)
			(xy 344.839661 -240.321918) (xy 344.858085 -240.280045) (xy 344.86977 -240.260378) (xy 344.877136 -240.24844)
			(xy 344.877644 -240.2205) (xy 344.731086 -239.967516) (xy 344.706448 -239.954054) (xy 344.692478 -239.954562)
			(xy 344.681048 -239.954816) (xy 344.655056 -239.954336) (xy 344.603711 -239.946211) (xy 344.55427 -239.930153)
			(xy 344.507949 -239.906558) (xy 344.465891 -239.876007) (xy 344.429129 -239.839252) (xy 344.398571 -239.797199)
			(xy 344.374968 -239.750882) (xy 344.358902 -239.701443) (xy 344.350768 -239.6501) (xy 344.35034 -239.624108)
			(xy 344.350731 -239.601193) (xy 344.357067 -239.555804) (xy 344.369617 -239.511727) (xy 344.388142 -239.469808)
			(xy 344.39987 -239.450118) (xy 344.407236 -239.43818) (xy 344.407744 -239.41024) (xy 344.261186 -239.15751)
			(xy 344.236802 -239.144048) (xy 344.222578 -239.144556) (xy 344.211148 -239.14481) (xy 344.185156 -239.14433)
			(xy 344.133811 -239.136205) (xy 344.08437 -239.120147) (xy 344.03805 -239.096552) (xy 343.995992 -239.066)
			(xy 343.959231 -239.029245) (xy 343.928673 -238.987191) (xy 343.905071 -238.940874) (xy 343.889006 -238.891435)
			(xy 343.880873 -238.840092) (xy 343.880873 -238.788108) (xy 343.889006 -238.736765) (xy 343.905071 -238.687326)
			(xy 343.928673 -238.641009) (xy 343.959231 -238.598955) (xy 343.995992 -238.5622) (xy 344.03805 -238.531648)
			(xy 344.08437 -238.508053) (xy 344.133811 -238.491995) (xy 344.185156 -238.48387) (xy 344.211148 -238.483394)
			(xy 344.234064 -238.483782) (xy 344.279456 -238.490111) (xy 344.323537 -238.502655) (xy 344.365461 -238.521173)
			(xy 344.385138 -238.532924) (xy 344.397076 -238.54029) (xy 344.425016 -238.540798) (xy 345.277186 -238.05134)
			(xy 345.290902 -238.026956) (xy 345.290394 -238.012986) (xy 345.290394 -238.004096) (xy 345.290786 -237.981181)
			(xy 345.297122 -237.935792) (xy 345.309672 -237.891715) (xy 345.328195 -237.849796) (xy 345.339924 -237.830106)
			(xy 345.34729 -237.818168) (xy 345.347544 -237.790228) (xy 345.200986 -237.537752) (xy 345.176602 -237.524036)
			(xy 345.162378 -237.524544) (xy 345.151202 -237.524798) (xy 345.125213 -237.524315) (xy 345.073875 -237.516184)
			(xy 345.024441 -237.500122) (xy 344.978128 -237.476524) (xy 344.936077 -237.445972) (xy 344.899323 -237.409217)
			(xy 344.868772 -237.367165) (xy 344.845175 -237.320852) (xy 344.829114 -237.271418) (xy 344.820984 -237.220079)
			(xy 344.820494 -237.19409) (xy 344.820881 -237.171217) (xy 344.827184 -237.125907) (xy 344.839668 -237.081897)
			(xy 344.858095 -237.040027) (xy 344.86977 -237.020354) (xy 344.87739 -237.008162) (xy 344.877644 -236.980222)
			(xy 344.731086 -236.727492) (xy 344.706702 -236.71403) (xy 344.692478 -236.714538) (xy 344.681048 -236.714792)
			(xy 344.655058 -236.714313) (xy 344.603716 -236.706188) (xy 344.554277 -236.69013) (xy 344.507959 -236.666536)
			(xy 344.465903 -236.635986) (xy 344.429145 -236.599233) (xy 344.398589 -236.557182) (xy 344.374988 -236.510867)
			(xy 344.358924 -236.461431) (xy 344.350791 -236.41009) (xy 344.350791 -236.35811) (xy 344.358924 -236.306769)
			(xy 344.374988 -236.257333) (xy 344.398589 -236.211018) (xy 344.429145 -236.168967) (xy 344.465903 -236.132214)
			(xy 344.507959 -236.101664) (xy 344.554277 -236.07807) (xy 344.603716 -236.062012) (xy 344.655058 -236.053887)
			(xy 344.681048 -236.053376) (xy 344.6907 -236.05363) (xy 344.70467 -236.053884) (xy 344.729054 -236.040422)
			(xy 344.876628 -235.785914) (xy 344.876374 -235.758482) (xy 344.869008 -235.74629) (xy 344.857509 -235.726765)
			(xy 344.839377 -235.685236) (xy 344.827089 -235.64162) (xy 344.820874 -235.596735) (xy 344.820494 -235.574078)
			(xy 344.820882 -235.551205) (xy 344.827186 -235.505896) (xy 344.839672 -235.461887) (xy 344.8581 -235.420018)
			(xy 344.86977 -235.400342) (xy 344.877136 -235.388404) (xy 344.877644 -235.360464) (xy 344.730832 -235.107734)
			(xy 344.706448 -235.094018) (xy 344.692224 -235.094526) (xy 344.681048 -235.09478) (xy 344.655057 -235.0943)
			(xy 344.603714 -235.086175) (xy 344.554275 -235.070117) (xy 344.507957 -235.046521) (xy 344.465902 -235.015969)
			(xy 344.429144 -234.979214) (xy 344.398589 -234.93716) (xy 344.374991 -234.890843) (xy 344.35893 -234.841405)
			(xy 344.350801 -234.790063) (xy 344.35034 -234.764072) (xy 344.350729 -234.741199) (xy 344.357034 -234.695891)
			(xy 344.369522 -234.651883) (xy 344.387953 -234.610016) (xy 344.399616 -234.590336) (xy 344.407236 -234.578144)
			(xy 344.40749 -234.550204) (xy 344.260932 -234.297728) (xy 344.236548 -234.284012) (xy 344.222324 -234.28452)
			(xy 344.211148 -234.284774) (xy 344.185159 -234.284295) (xy 344.13382 -234.27617) (xy 344.084384 -234.260114)
			(xy 344.038069 -234.236521) (xy 343.996015 -234.205973) (xy 343.959258 -234.169221) (xy 343.928704 -234.127172)
			(xy 343.905105 -234.08086) (xy 343.889041 -234.031427) (xy 343.880909 -233.980089) (xy 343.880909 -233.928111)
			(xy 343.889041 -233.876773) (xy 343.905105 -233.82734) (xy 343.928704 -233.781028) (xy 343.959258 -233.738979)
			(xy 343.996015 -233.702227) (xy 344.038069 -233.671679) (xy 344.084384 -233.648086) (xy 344.13382 -233.63203)
			(xy 344.185159 -233.623905) (xy 344.211148 -233.623358) (xy 344.220546 -233.623612) (xy 344.234516 -233.623866)
			(xy 344.2589 -233.610404) (xy 344.406474 -233.35615) (xy 344.405966 -233.32821) (xy 344.398854 -233.316272)
			(xy 344.387354 -233.296747) (xy 344.369222 -233.255219) (xy 344.356935 -233.211603) (xy 344.350721 -233.166717)
			(xy 344.35034 -233.14406) (xy 344.350826 -233.118074) (xy 344.358963 -233.066743) (xy 344.375029 -233.017317)
			(xy 344.39863 -232.971013) (xy 344.429183 -232.928971) (xy 344.465938 -232.892226) (xy 344.507988 -232.861684)
			(xy 344.554299 -232.838095) (xy 344.603729 -232.822042) (xy 344.655062 -232.813919) (xy 344.681048 -232.813352)
			(xy 344.6907 -232.813606) (xy 344.70467 -232.81386) (xy 344.729054 -232.800398) (xy 344.876628 -232.54589)
			(xy 344.876374 -232.518458) (xy 344.868754 -232.506266) (xy 344.857295 -232.486728) (xy 344.839237 -232.445188)
			(xy 344.827011 -232.401575) (xy 344.820843 -232.356702) (xy 344.820494 -232.334054) (xy 344.820877 -232.31118)
			(xy 344.827171 -232.265866) (xy 344.839648 -232.221852) (xy 344.858069 -232.179976) (xy 344.86977 -232.160318)
			(xy 344.877136 -232.14838) (xy 344.877644 -232.12044) (xy 344.731086 -231.867456) (xy 344.706702 -231.853994)
			(xy 344.692478 -231.854502) (xy 344.681048 -231.854756) (xy 344.655053 -231.854276) (xy 344.603701 -231.84615)
			(xy 344.554253 -231.83009) (xy 344.507926 -231.806491) (xy 344.465862 -231.775935) (xy 344.429096 -231.739175)
			(xy 344.398534 -231.697115) (xy 344.374929 -231.650792) (xy 344.358861 -231.601346) (xy 344.350727 -231.549995)
			(xy 344.350727 -231.498005) (xy 344.358861 -231.446654) (xy 344.374929 -231.397208) (xy 344.398534 -231.350885)
			(xy 344.429096 -231.308825) (xy 344.465862 -231.272065) (xy 344.507926 -231.241509) (xy 344.554253 -231.21791)
			(xy 344.603701 -231.20185) (xy 344.655053 -231.193724) (xy 344.681048 -231.19334) (xy 344.6907 -231.193594)
			(xy 344.70467 -231.193848) (xy 344.729054 -231.180386) (xy 344.890852 -230.90124) (xy 344.891106 -230.874824)
			(xy 344.884502 -230.862886) (xy 344.872378 -230.840013) (xy 344.855162 -230.791197) (xy 344.846421 -230.740177)
			(xy 344.845894 -230.714296) (xy 344.846438 -230.688072) (xy 344.855401 -230.636396) (xy 344.873063 -230.587012)
			(xy 344.885518 -230.563928) (xy 344.892122 -230.55199) (xy 344.892122 -230.52532) (xy 344.731086 -230.247444)
			(xy 344.706702 -230.233982) (xy 344.692478 -230.23449) (xy 344.681048 -230.234744) (xy 344.655053 -230.234264)
			(xy 344.603703 -230.226138) (xy 344.554257 -230.210078) (xy 344.507932 -230.186481) (xy 344.46587 -230.155926)
			(xy 344.429105 -230.119167) (xy 344.398544 -230.077109) (xy 344.37494 -230.030787) (xy 344.358873 -229.981343)
			(xy 344.350739 -229.929994) (xy 344.350739 -229.878006) (xy 344.358873 -229.826657) (xy 344.37494 -229.777213)
			(xy 344.398544 -229.730891) (xy 344.429105 -229.688833) (xy 344.46587 -229.652074) (xy 344.507932 -229.621519)
			(xy 344.554257 -229.597922) (xy 344.603703 -229.581862) (xy 344.655053 -229.573736) (xy 344.681048 -229.573328)
			(xy 344.6907 -229.573582) (xy 344.70467 -229.573836) (xy 344.729054 -229.560374) (xy 344.876628 -229.30612)
			(xy 344.87612 -229.278434) (xy 344.868754 -229.266496) (xy 344.857299 -229.246957) (xy 344.839251 -229.205416)
			(xy 344.827033 -229.161802) (xy 344.820875 -229.11693) (xy 344.820494 -229.094284) (xy 344.820882 -229.071411)
			(xy 344.827185 -229.026102) (xy 344.83967 -228.982092) (xy 344.858097 -228.940222) (xy 344.86977 -228.920548)
			(xy 344.87739 -228.908356) (xy 344.877644 -228.880416) (xy 344.731086 -228.627686) (xy 344.706702 -228.614224)
			(xy 344.692478 -228.614732) (xy 344.681048 -228.614986) (xy 344.655265 -228.614488) (xy 344.604325 -228.606476)
			(xy 344.555246 -228.590654) (xy 344.509218 -228.567405) (xy 344.467357 -228.537293) (xy 344.430677 -228.501049)
			(xy 344.400068 -228.45955) (xy 344.387678 -228.436932) (xy 344.381074 -228.424232) (xy 344.356944 -228.4095)
			(xy 344.065098 -228.4095) (xy 344.040968 -228.424232) (xy 344.034364 -228.436932) (xy 344.022024 -228.459579)
			(xy 343.991408 -228.50108) (xy 343.95472 -228.537324) (xy 343.91285 -228.567434) (xy 343.866814 -228.59068)
			(xy 343.817727 -228.606496) (xy 343.76678 -228.614501) (xy 343.740994 -228.614986) (xy 343.715006 -228.614502)
			(xy 343.663669 -228.60637) (xy 343.614237 -228.590307) (xy 343.567926 -228.566709) (xy 343.525877 -228.536156)
			(xy 343.489126 -228.499402) (xy 343.458577 -228.45735) (xy 343.434982 -228.411037) (xy 343.418923 -228.361604)
			(xy 343.410795 -228.310266) (xy 343.410286 -228.284278) (xy 343.410679 -228.261364) (xy 343.417017 -228.215975)
			(xy 343.429569 -228.171899) (xy 343.448094 -228.129981) (xy 343.459816 -228.110288) (xy 343.467182 -228.098096)
			(xy 343.46769 -228.070156) (xy 343.321132 -227.81768) (xy 343.296748 -227.804218) (xy 343.282524 -227.804726)
			(xy 343.271094 -227.80498) (xy 343.245106 -227.804496) (xy 343.19377 -227.796364) (xy 343.144338 -227.780301)
			(xy 343.098027 -227.756703) (xy 343.055979 -227.72615) (xy 343.019228 -227.689395) (xy 342.98868 -227.647344)
			(xy 342.965086 -227.601031) (xy 342.949028 -227.551597) (xy 342.940901 -227.50026) (xy 342.940386 -227.474272)
			(xy 342.940779 -227.451358) (xy 342.947118 -227.40597) (xy 342.959671 -227.361894) (xy 342.978196 -227.319977)
			(xy 342.989916 -227.300282) (xy 342.997282 -227.288344) (xy 342.99779 -227.260404) (xy 342.851232 -227.007674)
			(xy 342.826594 -226.994212) (xy 342.812624 -226.99472) (xy 342.801194 -226.994974) (xy 342.775206 -226.99449)
			(xy 342.72387 -226.986358) (xy 342.674439 -226.970295) (xy 342.628129 -226.946696) (xy 342.586081 -226.916143)
			(xy 342.549331 -226.879389) (xy 342.518783 -226.837337) (xy 342.49519 -226.791024) (xy 342.479132 -226.741591)
			(xy 342.471006 -226.690254) (xy 342.470486 -226.664266) (xy 342.470875 -226.641393) (xy 342.47718 -226.596085)
			(xy 342.489667 -226.552077) (xy 342.508096 -226.510208) (xy 342.519762 -226.49053) (xy 342.527382 -226.478338)
			(xy 342.527636 -226.450398) (xy 342.381078 -226.197668) (xy 342.356694 -226.184206) (xy 342.34247 -226.184714)
			(xy 342.33104 -226.184968) (xy 342.30505 -226.184488) (xy 342.253709 -226.176361) (xy 342.204271 -226.160302)
			(xy 342.157956 -226.136706) (xy 342.115902 -226.106154) (xy 342.079146 -226.069398) (xy 342.048594 -226.027344)
			(xy 342.024998 -225.981029) (xy 342.008939 -225.931591) (xy 342.000812 -225.88025) (xy 342.000332 -225.85426)
			(xy 342.00072 -225.831344) (xy 342.007049 -225.785952) (xy 342.019593 -225.741871) (xy 342.038112 -225.699947)
			(xy 342.049862 -225.68027) (xy 342.057228 -225.668332) (xy 342.057482 -225.640392) (xy 341.910924 -225.387916)
			(xy 341.88654 -225.3742) (xy 341.872316 -225.374708) (xy 341.86114 -225.374962) (xy 341.83515 -225.374482)
			(xy 341.783809 -225.366355) (xy 341.734372 -225.350296) (xy 341.688057 -225.3267) (xy 341.646004 -225.296147)
			(xy 341.609249 -225.259392) (xy 341.578697 -225.217338) (xy 341.555102 -225.171022) (xy 341.539043 -225.121585)
			(xy 341.530918 -225.070244) (xy 341.530432 -225.044254) (xy 341.530815 -225.02138) (xy 341.53711 -224.976067)
			(xy 341.549588 -224.932053) (xy 341.568011 -224.890178) (xy 341.579708 -224.870518) (xy 341.587328 -224.858326)
			(xy 341.587582 -224.83064) (xy 341.441024 -224.577656) (xy 341.41664 -224.564194) (xy 341.402416 -224.564702)
			(xy 341.390986 -224.564956) (xy 341.364998 -224.564445) (xy 341.313663 -224.556313) (xy 341.264231 -224.540252)
			(xy 341.21792 -224.516656) (xy 341.17587 -224.486107) (xy 341.139115 -224.449356) (xy 341.108562 -224.407309)
			(xy 341.084961 -224.361001) (xy 341.068894 -224.311571) (xy 341.060757 -224.260236) (xy 341.060278 -224.234248)
			(xy 341.060666 -224.211332) (xy 341.066995 -224.16594) (xy 341.079539 -224.121859) (xy 341.098057 -224.079935)
			(xy 341.109808 -224.060258) (xy 341.117174 -224.04832) (xy 341.117428 -224.02038) (xy 340.50097 -222.957898)
			(xy 340.476586 -222.944182) (xy 340.462362 -222.94469) (xy 340.451186 -222.944944) (xy 340.425199 -222.944433)
			(xy 340.373864 -222.936301) (xy 340.324433 -222.92024) (xy 340.278122 -222.896644) (xy 340.236073 -222.866094)
			(xy 340.19932 -222.829344) (xy 340.168768 -222.787296) (xy 340.145169 -222.740988) (xy 340.129104 -222.691558)
			(xy 340.120968 -222.640223) (xy 340.120478 -222.614236) (xy 340.120862 -222.591362) (xy 340.127159 -222.54605)
			(xy 340.139637 -222.502036) (xy 340.158059 -222.460161) (xy 340.169754 -222.4405) (xy 340.177374 -222.428308)
			(xy 340.177628 -222.400368) (xy 339.985858 -222.06966) (xy 339.965284 -222.056452) (xy 339.953092 -222.055182)
			(xy 339.931412 -222.05259) (xy 339.889333 -222.040945) (xy 339.849864 -222.022279) (xy 339.814167 -221.997142)
			(xy 339.798406 -221.98203) (xy 332.98638 -215.170004) (xy 332.969123 -215.151962) (xy 332.941372 -215.110467)
			(xy 332.922266 -215.064349) (xy 332.912543 -215.015386) (xy 332.911958 -214.990426) (xy 332.911958 -172.717206)
			(xy 332.912538 -172.69225) (xy 332.922295 -172.643299) (xy 332.941414 -172.597193) (xy 332.969161 -172.555703)
			(xy 332.98638 -172.537628) (xy 333.49438 -172.029628) (xy 333.51242 -172.012367) (xy 333.553913 -171.984608)
			(xy 333.600032 -171.965496) (xy 333.648997 -171.955767) (xy 333.673958 -171.955206) (xy 337.35772 -171.955206)
			(xy 337.367789 -171.95478) (xy 337.386389 -171.947061) (xy 337.393788 -171.94022) (xy 337.63077 -171.703238)
			(xy 337.63761 -171.695838) (xy 337.645326 -171.677239) (xy 337.645756 -171.66717) (xy 337.645756 -156.184854)
			(xy 337.645248 -156.184346) (xy 337.645248 -150.087584) (xy 337.644797 -150.077558) (xy 337.637201 -150.059004)
			(xy 337.630516 -150.051516) (xy 337.292188 -149.713188) (xy 337.284762 -149.706414) (xy 337.266166 -149.698826)
			(xy 337.25612 -149.698456) (xy 314.004452 -149.698456) (xy 313.994421 -149.698894) (xy 313.975849 -149.706474)
			(xy 313.968384 -149.713188) (xy 312.861198 -150.820374) (xy 312.854363 -150.827777) (xy 312.846656 -150.846375)
			(xy 312.846212 -150.856442) (xy 312.846212 -193.715132) (xy 312.845958 -193.71564) (xy 312.845958 -195.123816)
			(xy 312.865516 -195.15074) (xy 312.881518 -195.155566) (xy 312.906691 -195.163999) (xy 312.954405 -195.187269)
			(xy 312.998139 -195.217362) (xy 313.036922 -195.253611) (xy 313.069897 -195.295214) (xy 313.096334 -195.34125)
			(xy 313.115646 -195.390699) (xy 313.127407 -195.442466) (xy 313.131356 -195.495405) (xy 313.127405 -195.548345)
			(xy 313.115643 -195.600112) (xy 313.096329 -195.64956) (xy 313.069891 -195.695595) (xy 313.036915 -195.737197)
			(xy 312.99813 -195.773445) (xy 312.954396 -195.803537) (xy 312.906681 -195.826805) (xy 312.881518 -195.83527)
			(xy 312.865516 -195.840096) (xy 312.845958 -195.86702) (xy 312.845958 -212.980016) (xy 326.752462 -212.980016)
			(xy 326.756491 -212.837695) (xy 326.768566 -212.69583) (xy 326.788647 -212.554876) (xy 326.81667 -212.415283)
			(xy 326.852546 -212.277499) (xy 326.89616 -212.141966) (xy 326.947372 -212.009117) (xy 327.006018 -211.879378)
			(xy 327.071909 -211.753165) (xy 327.144836 -211.630882) (xy 327.224564 -211.51292) (xy 327.310838 -211.399658)
			(xy 327.403382 -211.291459) (xy 327.501898 -211.188668) (xy 327.606073 -211.091616) (xy 327.715571 -211.000612)
			(xy 327.830042 -210.91595) (xy 327.94912 -210.837899) (xy 328.072423 -210.76671) (xy 328.199556 -210.702611)
			(xy 328.330112 -210.645807) (xy 328.463672 -210.596481) (xy 328.599809 -210.554789) (xy 328.738087 -210.520866)
			(xy 328.878062 -210.494821) (xy 329.019287 -210.476736) (xy 329.161308 -210.466671) (xy 329.303672 -210.464656)
			(xy 329.445922 -210.470699) (xy 329.587602 -210.484779) (xy 329.728258 -210.506853) (xy 329.86744 -210.536849)
			(xy 330.004702 -210.574671) (xy 330.139605 -210.620199) (xy 330.271716 -210.673285) (xy 330.400612 -210.733761)
			(xy 330.52588 -210.801432) (xy 330.647119 -210.876082) (xy 330.76394 -210.957471) (xy 330.87597 -211.045339)
			(xy 330.982849 -211.139405) (xy 331.084235 -211.239366) (xy 331.179804 -211.344904) (xy 331.269249 -211.455679)
			(xy 331.352283 -211.571337) (xy 331.428641 -211.691507) (xy 331.498078 -211.815805) (xy 331.560371 -211.943832)
			(xy 331.615322 -212.075179) (xy 331.662754 -212.209424) (xy 331.702515 -212.346137) (xy 331.734477 -212.484881)
			(xy 331.758539 -212.625211) (xy 331.774623 -212.766677) (xy 331.782679 -212.908827) (xy 331.783182 -212.980016)
			(xy 331.782679 -213.051205) (xy 331.774623 -213.193355) (xy 331.758539 -213.334821) (xy 331.734477 -213.475151)
			(xy 331.702515 -213.613895) (xy 331.662754 -213.750608) (xy 331.615322 -213.884853) (xy 331.560371 -214.0162)
			(xy 331.498078 -214.144227) (xy 331.428641 -214.268525) (xy 331.352283 -214.388695) (xy 331.269249 -214.504353)
			(xy 331.179804 -214.615128) (xy 331.084235 -214.720666) (xy 330.982849 -214.820627) (xy 330.87597 -214.914693)
			(xy 330.76394 -215.002561) (xy 330.647119 -215.08395) (xy 330.52588 -215.1586) (xy 330.400612 -215.226271)
			(xy 330.271716 -215.286747) (xy 330.139605 -215.339833) (xy 330.004702 -215.385361) (xy 329.86744 -215.423183)
			(xy 329.728258 -215.453179) (xy 329.587602 -215.475253) (xy 329.445922 -215.489333) (xy 329.303672 -215.495376)
			(xy 329.161308 -215.493361) (xy 329.019287 -215.483296) (xy 328.878062 -215.465211) (xy 328.738087 -215.439166)
			(xy 328.599809 -215.405243) (xy 328.463672 -215.363551) (xy 328.330112 -215.314225) (xy 328.199556 -215.257421)
			(xy 328.072423 -215.193322) (xy 327.94912 -215.122133) (xy 327.830042 -215.044082) (xy 327.715571 -214.95942)
			(xy 327.606073 -214.868416) (xy 327.501898 -214.771364) (xy 327.403382 -214.668573) (xy 327.310838 -214.560374)
			(xy 327.224564 -214.447112) (xy 327.144836 -214.32915) (xy 327.071909 -214.206867) (xy 327.006018 -214.080654)
			(xy 326.947372 -213.950915) (xy 326.89616 -213.818066) (xy 326.852546 -213.682533) (xy 326.81667 -213.544749)
			(xy 326.788647 -213.405156) (xy 326.768566 -213.264202) (xy 326.756491 -213.122337) (xy 326.752462 -212.980016)
			(xy 312.845958 -212.980016) (xy 312.845958 -226.311968) (xy 312.846395 -226.322031) (xy 312.854133 -226.340612)
			(xy 312.860944 -226.348036) (xy 313.212226 -226.699318) (xy 313.219622 -226.706169) (xy 313.238221 -226.713907)
			(xy 313.248294 -226.714304) (xy 327.011284 -226.714304) (xy 327.035382 -226.71487) (xy 327.082714 -226.723957)
			(xy 327.127483 -226.74181) (xy 327.16808 -226.767786) (xy 327.203049 -226.800954) (xy 327.217532 -226.820222)
			(xy 327.225197 -226.829639) (xy 327.246809 -226.840629) (xy 327.258934 -226.841304) (xy 335.191354 -226.841304)
			(xy 335.207928 -226.841872) (xy 335.239939 -226.850486) (xy 335.268646 -226.867064) (xy 335.280762 -226.878388)
			(xy 335.562194 -227.15982) (xy 335.573525 -227.171932) (xy 335.590107 -227.200641) (xy 335.598738 -227.232652)
			(xy 335.599278 -227.249228) (xy 335.599278 -228.194108) (xy 335.601056 -228.200458) (xy 335.606067 -228.221049)
			(xy 335.611418 -228.263088) (xy 335.611724 -228.284278) (xy 335.611419 -228.305468) (xy 335.60607 -228.347508)
			(xy 335.601056 -228.368098) (xy 335.599278 -228.374448) (xy 335.599278 -229.813866) (xy 335.601056 -229.820216)
			(xy 335.606069 -229.840807) (xy 335.611426 -229.882846) (xy 335.611724 -229.904036) (xy 335.611415 -229.925225)
			(xy 335.606059 -229.967263) (xy 335.601056 -229.987856) (xy 335.599278 -229.994206) (xy 335.599278 -231.433878)
			(xy 335.601056 -231.440228) (xy 335.606069 -231.460819) (xy 335.611424 -231.502858) (xy 335.611724 -231.524048)
			(xy 335.611421 -231.545238) (xy 335.606076 -231.587279) (xy 335.601056 -231.607868) (xy 335.599278 -231.614218)
			(xy 335.599278 -233.05389) (xy 335.601056 -233.06024) (xy 335.606068 -233.080831) (xy 335.611421 -233.12287)
			(xy 335.611724 -233.14406) (xy 335.61142 -233.16525) (xy 335.606073 -233.20729) (xy 335.601056 -233.22788)
			(xy 335.599278 -233.23423) (xy 335.599278 -234.673902) (xy 335.601056 -234.680252) (xy 335.606067 -234.700843)
			(xy 335.611419 -234.742882) (xy 335.611724 -234.764072) (xy 335.611419 -234.785262) (xy 335.606071 -234.827302)
			(xy 335.601056 -234.847892) (xy 335.599278 -234.854242) (xy 335.599278 -236.293914) (xy 335.601056 -236.300264)
			(xy 335.606066 -236.320855) (xy 335.611417 -236.362894) (xy 335.611724 -236.384084) (xy 335.611419 -236.405274)
			(xy 335.606069 -236.447313) (xy 335.601056 -236.467904) (xy 335.599278 -236.474254) (xy 335.599278 -237.913926)
			(xy 335.601056 -237.920276) (xy 335.606066 -237.940867) (xy 335.611415 -237.982906) (xy 335.611724 -238.004096)
			(xy 335.611418 -238.025286) (xy 335.606067 -238.067325) (xy 335.601056 -238.087916) (xy 335.599278 -238.094266)
			(xy 335.599278 -239.533938) (xy 335.601056 -239.540288) (xy 335.606065 -239.560879) (xy 335.611412 -239.602918)
			(xy 335.611724 -239.624108) (xy 335.611417 -239.645298) (xy 335.606064 -239.687336) (xy 335.601056 -239.707928)
			(xy 335.599278 -239.714278) (xy 335.599278 -241.15395) (xy 335.601056 -241.1603) (xy 335.606064 -241.180891)
			(xy 335.61141 -241.222931) (xy 335.611724 -241.24412) (xy 335.611416 -241.265309) (xy 335.606062 -241.307348)
			(xy 335.601056 -241.32794) (xy 335.599278 -241.33429) (xy 335.599278 -242.773962) (xy 335.601056 -242.780312)
			(xy 335.606063 -242.800903) (xy 335.611408 -242.842943) (xy 335.611724 -242.864132) (xy 335.611416 -242.885321)
			(xy 335.60606 -242.927359) (xy 335.601056 -242.947952) (xy 335.599278 -242.954302) (xy 335.599278 -244.393974)
			(xy 335.601056 -244.400324) (xy 335.606069 -244.420915) (xy 335.611424 -244.462954) (xy 335.611724 -244.484144)
			(xy 335.611421 -244.505334) (xy 335.606076 -244.547375) (xy 335.601056 -244.567964) (xy 335.599278 -244.574314)
			(xy 335.599278 -246.013986) (xy 335.601056 -246.020336) (xy 335.606068 -246.040927) (xy 335.611422 -246.082966)
			(xy 335.611724 -246.104156) (xy 335.61142 -246.125346) (xy 335.606074 -246.167387) (xy 335.601056 -246.187976)
			(xy 335.599278 -246.194326) (xy 335.599278 -247.633998) (xy 335.601056 -247.640348) (xy 335.606067 -247.660939)
			(xy 335.61142 -247.702978) (xy 335.611724 -247.724168) (xy 335.61142 -247.745358) (xy 335.606072 -247.787398)
			(xy 335.601056 -247.807988) (xy 335.599278 -247.814338) (xy 335.599278 -249.25401) (xy 335.601056 -249.26036)
			(xy 335.606067 -249.280951) (xy 335.611418 -249.32299) (xy 335.611724 -249.34418) (xy 335.611419 -249.36537)
			(xy 335.60607 -249.40741) (xy 335.601056 -249.428) (xy 335.599278 -249.43435) (xy 335.599278 -251.996448)
			(xy 335.599709 -252.006515) (xy 335.607433 -252.025109) (xy 335.614264 -252.032516) (xy 336.6389 -253.057152)
			(xy 336.65922 -253.064772) (xy 336.670396 -253.064264) (xy 336.691224 -253.063502) (xy 336.71721 -253.064013)
			(xy 336.768541 -253.072147) (xy 336.817967 -253.08821) (xy 336.864273 -253.111807) (xy 336.906317 -253.142358)
			(xy 336.943064 -253.179109) (xy 336.97361 -253.221156) (xy 336.997203 -253.267464) (xy 337.013261 -253.316892)
			(xy 337.021389 -253.368224) (xy 337.021932 -253.39421) (xy 337.02117 -253.415038) (xy 337.020662 -253.426214)
			(xy 337.028282 -253.446534) (xy 338.331302 -254.749554) (xy 338.367624 -254.752856) (xy 338.382864 -254.742188)
			(xy 338.403726 -254.72834) (xy 338.448741 -254.706415) (xy 338.496543 -254.691513) (xy 338.546043 -254.683975)
			(xy 338.571078 -254.683514) (xy 338.597068 -254.683995) (xy 338.648408 -254.692124) (xy 338.697844 -254.708185)
			(xy 338.744158 -254.731782) (xy 338.786211 -254.762334) (xy 338.822966 -254.799089) (xy 338.853518 -254.841142)
			(xy 338.877115 -254.887456) (xy 338.893176 -254.936892) (xy 338.901305 -254.988232) (xy 338.901786 -255.014222)
			(xy 338.901351 -255.039261) (xy 338.893843 -255.088773) (xy 338.878943 -255.136582) (xy 338.856992 -255.181592)
			(xy 338.843112 -255.202436) (xy 338.832444 -255.217676) (xy 338.835746 -255.253998) (xy 339.07095 -255.489202)
			(xy 339.085174 -255.496314) (xy 339.093048 -255.497584) (xy 339.118246 -255.502112) (xy 339.166941 -255.517909)
			(xy 339.212624 -255.541016) (xy 339.254204 -255.57088) (xy 339.29069 -255.606791) (xy 339.321212 -255.647891)
			(xy 339.333586 -255.670304) (xy 339.34019 -255.68275) (xy 339.364574 -255.697482) (xy 339.657436 -255.697482)
			(xy 339.68182 -255.68275) (xy 339.688424 -255.670304) (xy 339.700795 -255.647795) (xy 339.731422 -255.606565)
			(xy 339.768058 -255.570569) (xy 339.809821 -255.540674) (xy 339.855707 -255.517599) (xy 339.904609 -255.5019)
			(xy 339.955352 -255.493955) (xy 340.006712 -255.493955) (xy 340.057455 -255.5019) (xy 340.106357 -255.517599)
			(xy 340.152243 -255.540674) (xy 340.194006 -255.570569) (xy 340.230642 -255.606565) (xy 340.261269 -255.647795)
			(xy 340.27364 -255.670304) (xy 340.280244 -255.68275) (xy 340.304628 -255.697482) (xy 340.59749 -255.697482)
			(xy 340.621874 -255.68275) (xy 340.628478 -255.670304) (xy 340.640849 -255.647795) (xy 340.671476 -255.606565)
			(xy 340.708112 -255.570569) (xy 340.749875 -255.540674) (xy 340.795761 -255.517599) (xy 340.844663 -255.5019)
			(xy 340.895406 -255.493955) (xy 340.946766 -255.493955) (xy 340.997509 -255.5019) (xy 341.046411 -255.517599)
			(xy 341.092297 -255.540674) (xy 341.13406 -255.570569) (xy 341.170696 -255.606565) (xy 341.201323 -255.647795)
			(xy 341.213694 -255.670304) (xy 341.220298 -255.68275) (xy 341.244682 -255.697482) (xy 341.537544 -255.697482)
			(xy 341.561928 -255.68275) (xy 341.568532 -255.670304) (xy 341.580903 -255.647795) (xy 341.61153 -255.606565)
			(xy 341.648166 -255.570569) (xy 341.689929 -255.540674) (xy 341.735815 -255.517599) (xy 341.784717 -255.5019)
			(xy 341.83546 -255.493955) (xy 341.88682 -255.493955) (xy 341.937563 -255.5019) (xy 341.986465 -255.517599)
			(xy 342.032351 -255.540674) (xy 342.074114 -255.570569) (xy 342.11075 -255.606565) (xy 342.141377 -255.647795)
			(xy 342.153748 -255.670304) (xy 342.160352 -255.68275) (xy 342.184736 -255.697482) (xy 342.477598 -255.697482)
			(xy 342.501982 -255.68275) (xy 342.508586 -255.670304) (xy 342.520957 -255.647795) (xy 342.551584 -255.606565)
			(xy 342.58822 -255.570569) (xy 342.629983 -255.540674) (xy 342.675869 -255.517599) (xy 342.724771 -255.5019)
			(xy 342.775514 -255.493955) (xy 342.826874 -255.493955) (xy 342.877617 -255.5019) (xy 342.926519 -255.517599)
			(xy 342.972405 -255.540674) (xy 343.014168 -255.570569) (xy 343.050804 -255.606565) (xy 343.081431 -255.647795)
			(xy 343.093802 -255.670304) (xy 343.100406 -255.68275) (xy 343.12479 -255.697482) (xy 343.417398 -255.697482)
			(xy 343.441782 -255.68275) (xy 343.448386 -255.670304) (xy 343.460751 -255.647789) (xy 343.49137 -255.606549)
			(xy 343.528003 -255.570545) (xy 343.569768 -255.540645) (xy 343.615657 -255.517569) (xy 343.664564 -255.501875)
			(xy 343.715312 -255.493939) (xy 343.740994 -255.49352) (xy 343.766983 -255.494003) (xy 343.81832 -255.502133)
			(xy 343.867754 -255.518195) (xy 343.914066 -255.541793) (xy 343.956116 -255.572346) (xy 343.992868 -255.609101)
			(xy 344.023418 -255.651153) (xy 344.047013 -255.697466) (xy 344.063072 -255.746901) (xy 344.071199 -255.798239)
			(xy 344.071702 -255.824228) (xy 344.071448 -255.83642) (xy 344.07094 -255.850644) (xy 344.084656 -255.875282)
			(xy 344.933778 -256.363216) (xy 344.962226 -256.362454) (xy 344.974164 -256.354834) (xy 344.99411 -256.342664)
			(xy 345.036702 -256.323456) (xy 345.081578 -256.310447) (xy 345.12784 -256.303899) (xy 345.151202 -256.303526)
			(xy 345.164664 -256.30378) (xy 345.178888 -256.304288) (xy 345.20378 -256.290826) (xy 345.349068 -256.040382)
			(xy 345.34856 -256.012188) (xy 345.34094 -255.999996) (xy 345.328965 -255.980154) (xy 345.310074 -255.937833)
			(xy 345.297271 -255.893292) (xy 345.290804 -255.8474) (xy 345.290394 -255.824228) (xy 345.290904 -255.798241)
			(xy 345.299034 -255.746906) (xy 345.315095 -255.697476) (xy 345.338691 -255.651166) (xy 345.369241 -255.609118)
			(xy 345.405992 -255.572367) (xy 345.44804 -255.541817) (xy 345.49435 -255.518221) (xy 345.54378 -255.50216)
			(xy 345.595115 -255.49403) (xy 345.647089 -255.49403) (xy 345.698424 -255.50216) (xy 345.747854 -255.518221)
			(xy 345.794164 -255.541817) (xy 345.836212 -255.572367) (xy 345.872963 -255.609118) (xy 345.903513 -255.651166)
			(xy 345.927109 -255.697476) (xy 345.94317 -255.746906) (xy 345.9513 -255.798241) (xy 345.95181 -255.824228)
			(xy 345.951556 -255.83642) (xy 345.951048 -255.850644) (xy 345.964764 -255.875282) (xy 346.813886 -256.363216)
		)
		(stroke
			(width 0)
			(type solid)
		)
		(fill yes)
		(layer "In9.Cu")
		(net "PVDD18_S5_P0")
	)
	(gr_poly
		(pts
			(xy 89.391744 -256.49301)
			(arc
				(start 89.398348 -256.480564)
				(mid 89.690956 -256.303728)
				(end 89.983564 -256.480564)
			)
			(xy 89.990168 -256.49301) (xy 90.014552 -256.507742) (xy 90.307414 -256.507742) (xy 90.331798 -256.49301)
			(arc
				(start 90.338402 -256.480564)
				(mid 90.63101 -256.303728)
				(end 90.923618 -256.480564)
			)
			(xy 90.930222 -256.49301) (xy 90.954606 -256.507742) (xy 91.247468 -256.507742) (xy 91.271852 -256.49301)
			(arc
				(start 91.278456 -256.480564)
				(mid 91.571064 -256.303728)
				(end 91.863672 -256.480564)
			)
			(xy 91.870276 -256.49301) (xy 91.89466 -256.507742) (xy 92.21597 -256.507742) (xy 92.239592 -256.494026)
			(arc
				(start 92.24645 -256.482342)
				(mid 92.511118 -256.329205)
				(end 92.775786 -256.482342)
			)
			(xy 92.782644 -256.494026) (xy 92.806266 -256.507742) (xy 93.127322 -256.507742) (xy 93.151706 -256.49301)
			(arc
				(start 93.15831 -256.480564)
				(mid 93.450918 -256.303728)
				(end 93.743526 -256.480564)
			)
			(xy 93.75013 -256.49301) (xy 93.774514 -256.507742) (xy 94.067376 -256.507742) (xy 94.09176 -256.49301)
			(arc
				(start 94.098364 -256.480564)
				(mid 94.390972 -256.303728)
				(end 94.68358 -256.480564)
			)
			(xy 94.690184 -256.49301) (xy 94.714568 -256.507742) (xy 95.035878 -256.507742) (xy 95.0595 -256.494026)
			(arc
				(start 95.066358 -256.482342)
				(mid 95.178467 -256.370058)
				(end 95.331788 -256.32918)
			)
			(xy 95.345758 -256.32918) (xy 95.368872 -256.315972) (xy 95.528892 -256.040636) (xy 95.528384 -256.012188)
			(arc
				(start 95.520764 -256.00025)
				(mid 95.483115 -255.915926)
				(end 95.470218 -255.824482)
			)
			(arc
				(start 95.470218 -255.824482)
				(mid 95.800926 -255.493774)
				(end 96.131634 -255.824482)
			)
			(xy 96.13138 -255.83642) (xy 96.130872 -255.850644) (xy 96.144588 -255.875282) (xy 96.993964 -256.363216)
			(xy 97.022158 -256.362708)
			(arc
				(start 97.03435 -256.355088)
				(mid 97.119096 -256.316858)
				(end 97.211134 -256.30378)
			)
			(xy 97.224596 -256.304034) (xy 97.23882 -256.304542) (xy 97.263458 -256.291334) (xy 97.409 -256.040382)
			(xy 97.408492 -256.012188)
			(arc
				(start 97.400872 -256.00025)
				(mid 97.363223 -255.915926)
				(end 97.350326 -255.824482)
			)
			(arc
				(start 97.350326 -255.824482)
				(mid 97.681034 -255.493774)
				(end 98.011742 -255.824482)
			)
			(xy 98.011488 -255.83642) (xy 98.01098 -255.850644) (xy 98.024696 -255.875282) (xy 98.873818 -256.363216)
			(xy 98.902266 -256.362708)
			(arc
				(start 98.914204 -256.355088)
				(mid 98.99895 -256.316858)
				(end 99.090988 -256.30378)
			)
			(xy 99.10445 -256.304034) (xy 99.118928 -256.304542) (xy 99.143312 -256.291334) (xy 99.288854 -256.040382)
			(xy 99.2886 -256.012188)
			(arc
				(start 99.28098 -256.00025)
				(mid 99.243331 -255.915926)
				(end 99.230434 -255.824482)
			)
			(arc
				(start 99.230434 -255.824482)
				(mid 99.327296 -255.590636)
				(end 99.561142 -255.493774)
			)
			(arc
				(start 99.561142 -255.493774)
				(mid 99.732 -255.54133)
				(end 99.85375 -255.670304)
			)
			(xy 99.860354 -255.68275) (xy 99.884484 -255.697482) (xy 100.1776 -255.697482) (xy 100.20173 -255.68275)
			(xy 100.208334 -255.670304) (xy 100.220018 -255.649984) (xy 100.227638 -255.637792) (xy 100.227892 -255.610106)
			(xy 100.081588 -255.357884) (xy 100.057204 -255.344422) (xy 100.04298 -255.34493)
			(arc
				(start 100.031042 -255.345184)
				(mid 99.700334 -255.014476)
				(end 100.031042 -254.683768)
			)
			(arc
				(start 100.031042 -254.683768)
				(mid 100.121632 -254.696345)
				(end 100.205286 -254.733298)
			)
			(xy 100.217224 -254.740664) (xy 100.245164 -254.741172) (xy 101.09708 -254.251714) (xy 101.110796 -254.22733)
			(xy 101.110288 -254.21336) (xy 101.110288 -254.20447) (xy 101.110542 -254.192278) (xy 101.11105 -254.178054)
			(xy 101.097334 -254.153162) (xy 100.248212 -253.665482) (xy 100.220018 -253.666244)
			(arc
				(start 100.20808 -253.673864)
				(mid 100.123212 -253.71213)
				(end 100.031042 -253.725172)
			)
			(arc
				(start 100.031042 -253.725172)
				(mid 99.700334 -253.394464)
				(end 100.031042 -253.063756)
			)
			(arc
				(start 100.031042 -253.063756)
				(mid 100.121632 -253.076333)
				(end 100.205286 -253.113286)
			)
			(xy 100.217224 -253.120652) (xy 100.245164 -253.12116) (xy 101.09708 -252.631702) (xy 101.110796 -252.607318)
			(xy 101.110288 -252.593348)
			(arc
				(start 101.110288 -252.584458)
				(mid 101.20715 -252.350612)
				(end 101.440996 -252.25375)
			)
			(xy 101.450902 -252.254004) (xy 101.464872 -252.254258) (xy 101.489256 -252.240796) (xy 101.636576 -251.986796)
			(xy 101.636322 -251.958856)
			(arc
				(start 101.628956 -251.946918)
				(mid 101.59279 -251.864034)
				(end 101.580442 -251.774452)
			)
			(arc
				(start 101.580442 -251.774452)
				(mid 101.593063 -251.683999)
				(end 101.629972 -251.600462)
			)
			(xy 101.637338 -251.588524) (xy 101.637846 -251.560584) (xy 101.491034 -251.307854) (xy 101.46665 -251.294392)
			(xy 101.452426 -251.2949)
			(arc
				(start 101.440996 -251.295154)
				(mid 101.20715 -251.198292)
				(end 101.110288 -250.964446)
			)
			(xy 101.110542 -250.952508) (xy 101.11105 -250.938284) (xy 101.097334 -250.913646) (xy 100.247958 -250.425712)
			(xy 100.220018 -250.42622)
			(arc
				(start 100.207826 -250.43384)
				(mid 100.12308 -250.47207)
				(end 100.031042 -250.485148)
			)
			(arc
				(start 100.031042 -250.485148)
				(mid 99.797196 -250.388286)
				(end 99.700334 -250.15444)
			)
			(arc
				(start 99.700334 -250.15444)
				(mid 99.712955 -250.063987)
				(end 99.749864 -249.98045)
			)
			(xy 99.75723 -249.968258) (xy 99.757738 -249.940572) (xy 99.61118 -249.687842) (xy 99.586796 -249.67438)
			(xy 99.572572 -249.674888)
			(arc
				(start 99.561142 -249.675142)
				(mid 99.327296 -249.57828)
				(end 99.230434 -249.344434)
			)
			(arc
				(start 99.230434 -249.344434)
				(mid 99.243055 -249.253981)
				(end 99.279964 -249.170444)
			)
			(xy 99.28733 -249.158506) (xy 99.287584 -249.130566) (xy 99.141026 -248.877836) (xy 99.116642 -248.864374)
			(xy 99.102418 -248.864882)
			(arc
				(start 99.090988 -248.865136)
				(mid 98.997517 -248.851652)
				(end 98.911664 -248.812304)
			)
			(xy 98.899472 -248.80443) (xy 98.871278 -248.803668) (xy 98.024188 -249.290332) (xy 98.010726 -249.31497)
			(xy 98.011488 -249.329448)
			(arc
				(start 98.011742 -249.344434)
				(mid 97.681034 -249.675142)
				(end 97.350326 -249.344434)
			)
			(xy 97.35058 -249.332496) (xy 97.351088 -249.318272) (xy 97.337372 -249.293634) (xy 96.487742 -248.8057)
			(xy 96.460056 -248.806208)
			(arc
				(start 96.447864 -248.814082)
				(mid 96.363094 -248.852153)
				(end 96.27108 -248.865136)
			)
			(arc
				(start 96.27108 -248.865136)
				(mid 95.940372 -248.534428)
				(end 96.27108 -248.20372)
			)
			(xy 96.280478 -248.203974) (xy 96.294448 -248.204228) (xy 96.318832 -248.190766) (xy 96.466406 -247.936512)
			(xy 96.465898 -247.908572)
			(arc
				(start 96.458786 -247.896634)
				(mid 96.422654 -247.813872)
				(end 96.410272 -247.724422)
			)
			(arc
				(start 96.410272 -247.724422)
				(mid 96.507134 -247.490576)
				(end 96.74098 -247.393714)
			)
			(xy 96.750378 -247.393968) (xy 96.764348 -247.394222) (xy 96.788732 -247.38076) (xy 96.93656 -247.126252)
			(xy 96.936052 -247.098566)
			(arc
				(start 96.928686 -247.086628)
				(mid 96.892709 -247.003844)
				(end 96.880426 -246.914416)
			)
			(arc
				(start 96.880426 -246.914416)
				(mid 96.892982 -246.824121)
				(end 96.929702 -246.74068)
			)
			(xy 96.937322 -246.728488) (xy 96.937576 -246.700548) (xy 96.791018 -246.447818) (xy 96.766634 -246.434356)
			(xy 96.75241 -246.434864)
			(arc
				(start 96.74098 -246.435118)
				(mid 96.507134 -246.338256)
				(end 96.410272 -246.10441)
			)
			(arc
				(start 96.410272 -246.10441)
				(mid 96.422893 -246.013957)
				(end 96.459802 -245.93042)
			)
			(xy 96.467168 -245.918482) (xy 96.467676 -245.890542) (xy 96.321118 -245.637812) (xy 96.29648 -245.62435)
			(xy 96.28251 -245.624858)
			(arc
				(start 96.27108 -245.625112)
				(mid 95.940372 -245.294404)
				(end 96.27108 -244.963696)
			)
			(xy 96.280478 -244.96395) (xy 96.294702 -244.964204) (xy 96.318578 -244.950742) (xy 96.466152 -244.696488)
			(xy 96.465898 -244.668548)
			(arc
				(start 96.458532 -244.65661)
				(mid 96.422555 -244.573826)
				(end 96.410272 -244.484398)
			)
			(arc
				(start 96.410272 -244.484398)
				(mid 96.507134 -244.250552)
				(end 96.74098 -244.15369)
			)
			(xy 96.750378 -244.153944) (xy 96.764348 -244.154198) (xy 96.788732 -244.140736) (xy 96.936306 -243.886228)
			(xy 96.936052 -243.858542)
			(arc
				(start 96.928686 -243.846604)
				(mid 96.892709 -243.76382)
				(end 96.880426 -243.674392)
			)
			(arc
				(start 96.880426 -243.674392)
				(mid 96.892982 -243.584097)
				(end 96.929702 -243.500656)
			)
			(xy 96.937322 -243.488464) (xy 96.937576 -243.460524) (xy 96.791018 -243.207794) (xy 96.766634 -243.194332)
			(xy 96.75241 -243.19484)
			(arc
				(start 96.74098 -243.195094)
				(mid 96.507134 -243.098232)
				(end 96.410272 -242.864386)
			)
			(arc
				(start 96.410272 -242.864386)
				(mid 96.422893 -242.773933)
				(end 96.459802 -242.690396)
			)
			(xy 96.467168 -242.678458) (xy 96.467676 -242.650518) (xy 96.321118 -242.397788) (xy 96.29648 -242.384326)
			(xy 96.28251 -242.384834)
			(arc
				(start 96.27108 -242.385088)
				(mid 95.940372 -242.05438)
				(end 96.27108 -241.723672)
			)
			(xy 96.280478 -241.723926) (xy 96.294702 -241.72418) (xy 96.318578 -241.710718) (xy 96.466152 -241.456464)
			(xy 96.465898 -241.428524)
			(arc
				(start 96.458532 -241.416586)
				(mid 96.422555 -241.333802)
				(end 96.410272 -241.244374)
			)
			(arc
				(start 96.410272 -241.244374)
				(mid 96.507134 -241.010528)
				(end 96.74098 -240.913666)
			)
			(xy 96.750378 -240.91392) (xy 96.764348 -240.914174) (xy 96.788732 -240.900712) (xy 96.936306 -240.646204)
			(xy 96.936052 -240.618518)
			(arc
				(start 96.928686 -240.60658)
				(mid 96.892709 -240.523796)
				(end 96.880426 -240.434368)
			)
			(arc
				(start 96.880426 -240.434368)
				(mid 96.892982 -240.344073)
				(end 96.929702 -240.260632)
			)
			(xy 96.937322 -240.24844) (xy 96.937576 -240.2205) (xy 96.791018 -239.96777) (xy 96.766634 -239.954308)
			(xy 96.75241 -239.954816)
			(arc
				(start 96.74098 -239.95507)
				(mid 96.507134 -239.858208)
				(end 96.410272 -239.624362)
			)
			(arc
				(start 96.410272 -239.624362)
				(mid 96.422893 -239.533909)
				(end 96.459802 -239.450372)
			)
			(xy 96.467168 -239.43818) (xy 96.467676 -239.410494) (xy 96.321118 -239.157764) (xy 96.296734 -239.144302)
			(xy 96.28251 -239.14481)
			(arc
				(start 96.27108 -239.145064)
				(mid 95.940372 -238.814356)
				(end 96.27108 -238.483648)
			)
			(arc
				(start 96.27108 -238.483648)
				(mid 96.361375 -238.496204)
				(end 96.444816 -238.532924)
			)
			(xy 96.456754 -238.54029) (xy 96.484694 -238.540798) (xy 97.337118 -238.05134) (xy 97.350834 -238.026956)
			(xy 97.350326 -238.012986)
			(arc
				(start 97.350326 -238.00435)
				(mid 97.362947 -237.913897)
				(end 97.399856 -237.83036)
			)
			(xy 97.407222 -237.818422) (xy 97.40773 -237.790482) (xy 97.261172 -237.537752) (xy 97.236788 -237.52429)
			(xy 97.222564 -237.524798)
			(arc
				(start 97.211134 -237.525052)
				(mid 96.977288 -237.42819)
				(end 96.880426 -237.194344)
			)
			(arc
				(start 96.880426 -237.194344)
				(mid 96.893047 -237.103891)
				(end 96.929956 -237.020354)
			)
			(xy 96.937322 -237.008416) (xy 96.93783 -236.980476) (xy 96.791018 -236.727746) (xy 96.766634 -236.714284)
			(xy 96.752664 -236.714792)
			(arc
				(start 96.74098 -236.715046)
				(mid 96.410272 -236.384338)
				(end 96.74098 -236.05363)
			)
			(xy 96.750378 -236.053884) (xy 96.764348 -236.054138) (xy 96.788986 -236.040676) (xy 96.93656 -235.786168)
			(xy 96.936052 -235.758482)
			(arc
				(start 96.928686 -235.746544)
				(mid 96.892709 -235.66376)
				(end 96.880426 -235.574332)
			)
			(arc
				(start 96.880426 -235.574332)
				(mid 96.892982 -235.484037)
				(end 96.929702 -235.400596)
			)
			(xy 96.937322 -235.388404) (xy 96.937576 -235.360464) (xy 96.791018 -235.107734) (xy 96.766634 -235.094272)
			(xy 96.75241 -235.09478)
			(arc
				(start 96.74098 -235.095034)
				(mid 96.507134 -234.998172)
				(end 96.410272 -234.764326)
			)
			(arc
				(start 96.410272 -234.764326)
				(mid 96.422893 -234.673873)
				(end 96.459802 -234.590336)
			)
			(xy 96.467168 -234.578398) (xy 96.467676 -234.550458) (xy 96.321118 -234.297728) (xy 96.29648 -234.284266)
			(xy 96.28251 -234.284774)
			(arc
				(start 96.27108 -234.285028)
				(mid 95.940372 -233.95432)
				(end 96.27108 -233.623612)
			)
			(xy 96.280478 -233.623866) (xy 96.294702 -233.62412) (xy 96.318578 -233.610658) (xy 96.466152 -233.356404)
			(xy 96.465898 -233.328464)
			(arc
				(start 96.458532 -233.316526)
				(mid 96.422555 -233.233742)
				(end 96.410272 -233.144314)
			)
			(arc
				(start 96.410272 -233.144314)
				(mid 96.507134 -232.910468)
				(end 96.74098 -232.813606)
			)
			(xy 96.750378 -232.81386) (xy 96.764348 -232.814114) (xy 96.788732 -232.800652) (xy 96.936306 -232.546144)
			(xy 96.936052 -232.518458)
			(arc
				(start 96.928686 -232.50652)
				(mid 96.892709 -232.423736)
				(end 96.880426 -232.334308)
			)
			(arc
				(start 96.880426 -232.334308)
				(mid 96.892982 -232.244013)
				(end 96.929702 -232.160572)
			)
			(xy 96.937322 -232.14838) (xy 96.937576 -232.12044) (xy 96.791018 -231.86771) (xy 96.766634 -231.854248)
			(xy 96.75241 -231.854756)
			(arc
				(start 96.74098 -231.85501)
				(mid 96.410272 -231.524302)
				(end 96.74098 -231.193594)
			)
			(xy 96.750378 -231.193848) (xy 96.764348 -231.194102) (xy 96.788986 -231.18064) (xy 96.950784 -230.901494)
			(xy 96.951038 -230.874824)
			(arc
				(start 96.944434 -230.86314)
				(mid 96.915642 -230.791311)
				(end 96.905826 -230.71455)
			)
			(arc
				(start 96.905826 -230.71455)
				(mid 96.9159 -230.636801)
				(end 96.94545 -230.564182)
			)
			(xy 96.952308 -230.552244) (xy 96.952054 -230.52532) (xy 96.791018 -230.247698) (xy 96.766634 -230.234236)
			(xy 96.75241 -230.234744)
			(arc
				(start 96.74098 -230.234998)
				(mid 96.410272 -229.90429)
				(end 96.74098 -229.573582)
			)
			(xy 96.750378 -229.573836) (xy 96.764348 -229.57409) (xy 96.788986 -229.560628) (xy 96.936306 -229.30612)
			(xy 96.936052 -229.278688)
			(arc
				(start 96.928686 -229.266496)
				(mid 96.892716 -229.18384)
				(end 96.880426 -229.094538)
			)
			(arc
				(start 96.880426 -229.094538)
				(mid 96.893047 -229.004085)
				(end 96.929956 -228.920548)
			)
			(xy 96.937322 -228.90861) (xy 96.93783 -228.88067) (xy 96.791272 -228.62794) (xy 96.766634 -228.614478)
			(xy 96.752664 -228.614986)
			(arc
				(start 96.74098 -228.61524)
				(mid 96.507134 -228.518378)
				(end 96.410272 -228.284532)
			)
			(arc
				(start 96.410272 -228.284532)
				(mid 96.416779 -228.219507)
				(end 96.435926 -228.157024)
			)
			(xy 96.44126 -228.143816) (xy 96.437196 -228.116384) (xy 96.173544 -227.79482) (xy 96.162876 -227.7872)
			(arc
				(start 96.156272 -227.78466)
				(mid 96.015352 -227.684209)
				(end 95.944436 -227.526342)
			)
			(xy 95.94342 -227.519484) (xy 95.937832 -227.507292) (xy 94.147132 -225.323146) (xy 94.10954 -225.316796)
			(arc
				(start 94.093284 -225.326702)
				(mid 94.010522 -225.362834)
				(end 93.921072 -225.375216)
			)
			(arc
				(start 93.921072 -225.375216)
				(mid 93.687226 -225.278354)
				(end 93.590364 -225.044508)
			)
			(arc
				(start 93.590364 -225.044508)
				(mid 93.613056 -224.924117)
				(end 93.677994 -224.820226)
			)
			(xy 93.690948 -224.806256) (xy 93.691964 -224.76841) (xy 93.529912 -224.570544) (xy 93.505782 -224.560892)
			(arc
				(start 93.492574 -224.56267)
				(mid 93.471786 -224.564596)
				(end 93.450918 -224.56521)
			)
			(arc
				(start 93.450918 -224.56521)
				(mid 93.217072 -224.468348)
				(end 93.12021 -224.234502)
			)
			(arc
				(start 93.12021 -224.234502)
				(mid 93.124572 -224.181221)
				(end 93.137482 -224.129346)
			)
			(xy 93.141546 -224.116646) (xy 93.136974 -224.091246) (xy 93.01734 -223.94545) (xy 93.014038 -223.94164)
			(arc
				(start 92.891864 -223.820228)
				(mid 92.88089 -223.803665)
				(end 92.877132 -223.78416)
			)
			(arc
				(start 92.877132 -222.28556)
				(mid 92.880965 -222.266203)
				(end 92.891864 -222.249746)
			)
			(arc
				(start 92.989146 -222.152718)
				(mid 93.000208 -222.136301)
				(end 93.004132 -222.116904)
			)
			(arc
				(start 93.004132 -219.978224)
				(mid 93.000231 -219.958701)
				(end 92.989146 -219.942156)
			)
			(arc
				(start 92.458794 -219.411804)
				(mid 92.442231 -219.40083)
				(end 92.422726 -219.397072)
			)
			(arc
				(start 84.869782 -219.397072)
				(mid 84.846514 -219.402583)
				(end 84.82838 -219.418154)
			)
			(arc
				(start 84.82838 -219.418154)
				(mid 84.738083 -219.495676)
				(end 84.622386 -219.523564)
			)
			(arc
				(start 76.748386 -219.523564)
				(mid 76.651199 -219.504214)
				(end 76.568808 -219.449142)
			)
			(arc
				(start 59.947302 -202.827636)
				(mid 59.892196 -202.745259)
				(end 59.87288 -202.648058)
			)
			(arc
				(start 59.87288 -192.51803)
				(mid 59.872046 -192.508864)
				(end 59.869578 -192.499996)
			)
			(arc
				(start 59.869578 -192.499996)
				(mid 59.821314 -192.235328)
				(end 59.869578 -191.97066)
			)
			(arc
				(start 59.869578 -191.97066)
				(mid 59.872052 -191.961793)
				(end 59.87288 -191.952626)
			)
			(xy 59.87288 -161.727134) (xy 59.872372 -161.726626)
			(arc
				(start 59.872372 -155.16606)
				(mid 59.868119 -155.145712)
				(end 59.856116 -155.128722)
			)
			(arc
				(start 59.856116 -155.128722)
				(mid 59.765629 -155.001433)
				(end 59.733688 -154.84856)
			)
			(arc
				(start 59.733688 -154.84856)
				(mid 59.746537 -154.75038)
				(end 59.784234 -154.658822)
			)
			(xy 59.79287 -154.643836) (xy 59.788298 -154.6098)
			(arc
				(start 58.85053 -153.672032)
				(mid 58.833967 -153.661058)
				(end 58.814462 -153.6573)
			)
			(arc
				(start 56.927496 -153.6573)
				(mid 56.9116 -153.659851)
				(end 56.89727 -153.667206)
			)
			(arc
				(start 56.89727 -153.667206)
				(mid 56.670194 -153.742143)
				(end 56.443118 -153.667206)
			)
			(arc
				(start 56.443118 -153.667206)
				(mid 56.428804 -153.659802)
				(end 56.412892 -153.6573)
			)
			(arc
				(start 56.165496 -153.6573)
				(mid 56.1496 -153.659851)
				(end 56.13527 -153.667206)
			)
			(arc
				(start 56.13527 -153.667206)
				(mid 55.908194 -153.742143)
				(end 55.681118 -153.667206)
			)
			(arc
				(start 55.681118 -153.667206)
				(mid 55.666804 -153.659802)
				(end 55.650892 -153.6573)
			)
			(arc
				(start 47.703486 -153.6573)
				(mid 47.683992 -153.661084)
				(end 47.667418 -153.672032)
			)
			(arc
				(start 44.534074 -156.805376)
				(mid 44.522963 -156.82191)
				(end 44.519088 -156.841444)
			)
			(arc
				(start 44.519088 -172.36186)
				(mid 44.522989 -172.381383)
				(end 44.534074 -172.397928)
			)
			(arc
				(start 45.441616 -173.305216)
				(mid 45.45259 -173.321779)
				(end 45.456348 -173.341284)
			)
			(arc
				(start 45.456348 -176.40554)
				(mid 45.452564 -176.425034)
				(end 45.441616 -176.441608)
			)
			(arc
				(start 41.076626 -180.806344)
				(mid 41.065515 -180.822878)
				(end 41.06164 -180.842412)
			)
			(xy 41.06164 -195.8848) (xy 41.061386 -195.8848)
			(arc
				(start 41.061386 -226.357434)
				(mid 41.076265 -226.393355)
				(end 41.112186 -226.408234)
			)
			(arc
				(start 76.774802 -226.408234)
				(mid 76.790565 -226.405644)
				(end 76.804774 -226.398328)
			)
			(arc
				(start 76.804774 -226.398328)
				(mid 77.001116 -226.3338)
				(end 77.197458 -226.398328)
			)
			(arc
				(start 77.197458 -226.398328)
				(mid 77.211651 -226.405692)
				(end 77.22743 -226.408234)
			)
			(arc
				(start 79.59471 -226.408234)
				(mid 79.610473 -226.405644)
				(end 79.624682 -226.398328)
			)
			(arc
				(start 79.624682 -226.398328)
				(mid 79.717687 -226.350346)
				(end 79.821024 -226.333812)
			)
			(arc
				(start 79.821024 -226.333812)
				(mid 79.990944 -226.380761)
				(end 80.112616 -226.50831)
			)
			(xy 80.11922 -226.52101) (xy 80.143096 -226.535234) (xy 80.439006 -226.535234) (xy 80.462882 -226.52101)
			(arc
				(start 80.469486 -226.50831)
				(mid 80.761078 -226.333856)
				(end 81.05267 -226.50831)
			)
			(xy 81.059274 -226.52101) (xy 81.08315 -226.535234) (xy 81.37906 -226.535234) (xy 81.402936 -226.52101)
			(arc
				(start 81.40954 -226.50831)
				(mid 81.701132 -226.333856)
				(end 81.992724 -226.50831)
			)
			(xy 81.999328 -226.52101) (xy 82.023204 -226.535234) (xy 82.31886 -226.535234) (xy 82.342736 -226.52101)
			(arc
				(start 82.34934 -226.50831)
				(mid 82.640932 -226.333856)
				(end 82.932524 -226.50831)
			)
			(xy 82.939128 -226.52101) (xy 82.963004 -226.535234) (xy 83.258914 -226.535234) (xy 83.28279 -226.52101)
			(arc
				(start 83.289394 -226.50831)
				(mid 83.580986 -226.333856)
				(end 83.872578 -226.50831)
			)
			(xy 83.879182 -226.52101) (xy 83.903058 -226.535234) (xy 84.198968 -226.535234) (xy 84.222844 -226.52101)
			(arc
				(start 84.229448 -226.50831)
				(mid 84.52104 -226.333856)
				(end 84.812632 -226.50831)
			)
			(xy 84.819236 -226.52101) (xy 84.843112 -226.535234) (xy 85.139022 -226.535234) (xy 85.162898 -226.52101)
			(arc
				(start 85.169502 -226.50831)
				(mid 85.461094 -226.333856)
				(end 85.752686 -226.50831)
			)
			(xy 85.75929 -226.52101) (xy 85.783166 -226.535234) (xy 86.079076 -226.535234) (xy 86.102952 -226.52101)
			(arc
				(start 86.109556 -226.50831)
				(mid 86.401148 -226.333856)
				(end 86.69274 -226.50831)
			)
			(xy 86.699344 -226.52101) (xy 86.72322 -226.535234)
			(arc
				(start 86.946994 -226.535234)
				(mid 86.995375 -226.544915)
				(end 87.036402 -226.572318)
			)
			(arc
				(start 87.593678 -227.129594)
				(mid 87.621063 -227.170628)
				(end 87.630762 -227.219002)
			)
			(xy 87.630762 -228.11867) (xy 87.633556 -228.1301)
			(arc
				(start 87.636096 -228.135688)
				(mid 87.662585 -228.208027)
				(end 87.671656 -228.284532)
			)
			(arc
				(start 87.671656 -228.284532)
				(mid 87.662623 -228.361046)
				(end 87.636096 -228.433376)
			)
			(xy 87.633556 -228.438964) (xy 87.630762 -228.450394) (xy 87.630762 -229.738428) (xy 87.633556 -229.749858)
			(arc
				(start 87.636096 -229.755446)
				(mid 87.662585 -229.827785)
				(end 87.671656 -229.90429)
			)
			(arc
				(start 87.671656 -229.90429)
				(mid 87.662623 -229.980804)
				(end 87.636096 -230.053134)
			)
			(xy 87.633556 -230.058722) (xy 87.630762 -230.070152) (xy 87.630762 -231.35844) (xy 87.633556 -231.36987)
			(arc
				(start 87.636096 -231.375458)
				(mid 87.662585 -231.447797)
				(end 87.671656 -231.524302)
			)
			(arc
				(start 87.671656 -231.524302)
				(mid 87.662623 -231.600816)
				(end 87.636096 -231.673146)
			)
			(xy 87.633556 -231.678734) (xy 87.630762 -231.690164) (xy 87.630762 -232.978452) (xy 87.633556 -232.989882)
			(arc
				(start 87.636096 -232.99547)
				(mid 87.662585 -233.067809)
				(end 87.671656 -233.144314)
			)
			(arc
				(start 87.671656 -233.144314)
				(mid 87.662623 -233.220828)
				(end 87.636096 -233.293158)
			)
			(xy 87.633556 -233.298746) (xy 87.630762 -233.310176) (xy 87.630762 -234.598464) (xy 87.633556 -234.609894)
			(arc
				(start 87.636096 -234.615482)
				(mid 87.662585 -234.687821)
				(end 87.671656 -234.764326)
			)
			(arc
				(start 87.671656 -234.764326)
				(mid 87.662623 -234.84084)
				(end 87.636096 -234.91317)
			)
			(xy 87.633556 -234.918758) (xy 87.630762 -234.930188) (xy 87.630762 -236.218476) (xy 87.633556 -236.229906)
			(arc
				(start 87.636096 -236.235494)
				(mid 87.662585 -236.307833)
				(end 87.671656 -236.384338)
			)
			(arc
				(start 87.671656 -236.384338)
				(mid 87.662623 -236.460852)
				(end 87.636096 -236.533182)
			)
			(xy 87.633556 -236.53877) (xy 87.630762 -236.5502) (xy 87.630762 -237.838488) (xy 87.633556 -237.849918)
			(arc
				(start 87.636096 -237.855506)
				(mid 87.662585 -237.927845)
				(end 87.671656 -238.00435)
			)
			(arc
				(start 87.671656 -238.00435)
				(mid 87.662623 -238.080864)
				(end 87.636096 -238.153194)
			)
			(xy 87.633556 -238.158782) (xy 87.630762 -238.170212) (xy 87.630762 -239.4585) (xy 87.633556 -239.46993)
			(arc
				(start 87.636096 -239.475518)
				(mid 87.662585 -239.547857)
				(end 87.671656 -239.624362)
			)
			(arc
				(start 87.671656 -239.624362)
				(mid 87.662623 -239.700876)
				(end 87.636096 -239.773206)
			)
			(xy 87.633556 -239.778794) (xy 87.630762 -239.790224) (xy 87.630762 -241.078512) (xy 87.633556 -241.089942)
			(arc
				(start 87.636096 -241.09553)
				(mid 87.662585 -241.167869)
				(end 87.671656 -241.244374)
			)
			(arc
				(start 87.671656 -241.244374)
				(mid 87.662623 -241.320888)
				(end 87.636096 -241.393218)
			)
			(xy 87.633556 -241.398806) (xy 87.630762 -241.410236) (xy 87.630762 -242.698524) (xy 87.633556 -242.709954)
			(arc
				(start 87.636096 -242.715542)
				(mid 87.662585 -242.787881)
				(end 87.671656 -242.864386)
			)
			(arc
				(start 87.671656 -242.864386)
				(mid 87.662623 -242.9409)
				(end 87.636096 -243.01323)
			)
			(xy 87.633556 -243.018818) (xy 87.630762 -243.030248) (xy 87.630762 -244.318536) (xy 87.633556 -244.329966)
			(arc
				(start 87.636096 -244.335554)
				(mid 87.662585 -244.407893)
				(end 87.671656 -244.484398)
			)
			(arc
				(start 87.671656 -244.484398)
				(mid 87.662623 -244.560912)
				(end 87.636096 -244.633242)
			)
			(xy 87.633556 -244.63883) (xy 87.630762 -244.65026) (xy 87.630762 -245.938548) (xy 87.633556 -245.949978)
			(arc
				(start 87.636096 -245.955566)
				(mid 87.662585 -246.027905)
				(end 87.671656 -246.10441)
			)
			(arc
				(start 87.671656 -246.10441)
				(mid 87.662623 -246.180924)
				(end 87.636096 -246.253254)
			)
			(xy 87.633556 -246.258842) (xy 87.630762 -246.270272) (xy 87.630762 -247.55856) (xy 87.633556 -247.56999)
			(arc
				(start 87.636096 -247.575578)
				(mid 87.662585 -247.647917)
				(end 87.671656 -247.724422)
			)
			(arc
				(start 87.671656 -247.724422)
				(mid 87.662623 -247.800936)
				(end 87.636096 -247.873266)
			)
			(xy 87.633556 -247.878854) (xy 87.630762 -247.890284) (xy 87.630762 -249.178572) (xy 87.633556 -249.190002)
			(arc
				(start 87.636096 -249.19559)
				(mid 87.662585 -249.267929)
				(end 87.671656 -249.344434)
			)
			(arc
				(start 87.671656 -249.344434)
				(mid 87.662623 -249.420948)
				(end 87.636096 -249.493278)
			)
			(xy 87.633556 -249.498866) (xy 87.630762 -249.510296) (xy 87.630762 -250.86818)
			(arc
				(start 87.633048 -250.875292)
				(mid 87.64297 -250.919378)
				(end 87.646256 -250.964446)
			)
			(arc
				(start 87.646256 -250.964446)
				(mid 87.64295 -251.009511)
				(end 87.633048 -251.0536)
			)
			(xy 87.630762 -251.060712) (xy 87.630762 -252.418596) (xy 87.633556 -252.430026)
			(arc
				(start 87.636096 -252.435614)
				(mid 87.662585 -252.507953)
				(end 87.671656 -252.584458)
			)
			(arc
				(start 87.671656 -252.584458)
				(mid 87.662623 -252.660972)
				(end 87.636096 -252.733302)
			)
			(xy 87.633556 -252.73889) (xy 87.630762 -252.75032) (xy 87.630762 -254.038608) (xy 87.633556 -254.050038)
			(arc
				(start 87.636096 -254.055626)
				(mid 87.662585 -254.127965)
				(end 87.671656 -254.20447)
			)
			(arc
				(start 87.671656 -254.20447)
				(mid 87.662623 -254.280984)
				(end 87.636096 -254.353314)
			)
			(xy 87.633556 -254.358902) (xy 87.630762 -254.370332)
			(arc
				(start 87.630762 -255.090422)
				(mid 87.634663 -255.109945)
				(end 87.645748 -255.12649)
			)
			(xy 88.063578 -255.54432) (xy 88.097868 -255.548638)
			(arc
				(start 88.112854 -255.539748)
				(mid 88.193842 -255.505472)
				(end 88.281002 -255.493774)
			)
			(arc
				(start 88.281002 -255.493774)
				(mid 88.514848 -255.590636)
				(end 88.61171 -255.824482)
			)
			(arc
				(start 88.61171 -255.824482)
				(mid 88.600008 -255.911641)
				(end 88.565736 -255.99263)
			)
			(arc
				(start 88.565736 -255.99263)
				(mid 88.559182 -256.024801)
				(end 88.57361 -256.054352)
			)
			(xy 88.874092 -256.354834)
			(arc
				(start 88.88222 -256.358644)
				(mid 88.958418 -256.410334)
				(end 89.015824 -256.482342)
			)
			(xy 89.022682 -256.494026) (xy 89.046304 -256.507742) (xy 89.36736 -256.507742)
		)
		(stroke
			(width 0)
			(type solid)
		)
		(fill yes)
		(layer "In9.Cu")
		(net "PVDD18_S5_P1")
	)
	(gr_poly
		(pts
			(xy 303.155604 -335.233518) (xy 303.165674 -335.233095) (xy 303.184279 -335.225381) (xy 303.191672 -335.218532)
			(xy 303.591976 -334.818228) (xy 303.598814 -334.810827) (xy 303.606526 -334.792228) (xy 303.606962 -334.78216)
			(xy 303.606962 -325.083424) (xy 303.606743 -325.076383) (xy 303.602883 -325.062842) (xy 303.599342 -325.056754)
			(xy 303.575673 -325.017544) (xy 303.534828 -324.935561) (xy 303.50172 -324.850159) (xy 303.476634 -324.762067)
			(xy 303.459782 -324.672037) (xy 303.451309 -324.580835) (xy 303.450752 -324.535038) (xy 303.451277 -324.48924)
			(xy 303.459753 -324.398037) (xy 303.476609 -324.308005) (xy 303.5017 -324.219912) (xy 303.534814 -324.13451)
			(xy 303.575666 -324.052529) (xy 303.599342 -324.013322) (xy 303.602844 -324.007216) (xy 303.60671 -323.993686)
			(xy 303.606962 -323.986652) (xy 303.606962 -309.058818) (xy 303.607581 -309.033864) (xy 303.617331 -308.984918)
			(xy 303.63644 -308.938813) (xy 303.664175 -308.897321) (xy 303.681384 -308.87924) (xy 316.781688 -295.778936)
			(xy 316.799731 -295.761681) (xy 316.841226 -295.733933) (xy 316.887344 -295.714829) (xy 316.936307 -295.705106)
			(xy 316.961266 -295.704514) (xy 326.888348 -295.704514) (xy 326.896705 -295.704132) (xy 326.912512 -295.698686)
			(xy 326.919336 -295.693846) (xy 326.941168 -295.677737) (xy 326.988992 -295.652118) (xy 327.040357 -295.634653)
			(xy 327.093885 -295.625811) (xy 327.121012 -295.625266) (xy 327.146851 -295.625766) (xy 327.197899 -295.63381)
			(xy 327.247073 -295.649701) (xy 327.293175 -295.673052) (xy 327.335081 -295.703292) (xy 327.37177 -295.739686)
			(xy 327.402348 -295.781347) (xy 327.414636 -295.804082) (xy 327.421494 -295.816782) (xy 327.44537 -295.831514)
			(xy 330.585064 -295.831514) (xy 330.608686 -295.817798) (xy 330.615544 -295.805606) (xy 330.628186 -295.784255)
			(xy 330.659286 -295.745594) (xy 330.696228 -295.712472) (xy 330.738041 -295.68576) (xy 330.783623 -295.666162)
			(xy 330.831775 -295.654192) (xy 330.881228 -295.650167) (xy 330.930681 -295.654192) (xy 330.978833 -295.666162)
			(xy 331.024415 -295.68576) (xy 331.066228 -295.712472) (xy 331.10317 -295.745594) (xy 331.13427 -295.784255)
			(xy 331.146912 -295.805606) (xy 331.15377 -295.817798) (xy 331.177392 -295.831514) (xy 331.49667 -295.831514)
			(xy 331.520546 -295.816782) (xy 331.527404 -295.804082) (xy 331.539704 -295.781353) (xy 331.570276 -295.739686)
			(xy 331.606961 -295.703287) (xy 331.648865 -295.673042) (xy 331.694966 -295.649688) (xy 331.74414 -295.633796)
			(xy 331.795189 -295.625751) (xy 331.846867 -295.625751) (xy 331.897916 -295.633796) (xy 331.94709 -295.649688)
			(xy 331.993191 -295.673042) (xy 332.035095 -295.703287) (xy 332.07178 -295.739686) (xy 332.102352 -295.781353)
			(xy 332.114652 -295.804082) (xy 332.12151 -295.816782) (xy 332.145386 -295.831514) (xy 332.436724 -295.831514)
			(xy 332.4606 -295.816782) (xy 332.467458 -295.804082) (xy 332.479758 -295.781353) (xy 332.51033 -295.739686)
			(xy 332.547015 -295.703287) (xy 332.588919 -295.673042) (xy 332.63502 -295.649688) (xy 332.684194 -295.633796)
			(xy 332.735243 -295.625751) (xy 332.786921 -295.625751) (xy 332.83797 -295.633796) (xy 332.887144 -295.649688)
			(xy 332.933245 -295.673042) (xy 332.975149 -295.703287) (xy 333.011834 -295.739686) (xy 333.042406 -295.781353)
			(xy 333.054706 -295.804082) (xy 333.061564 -295.816782) (xy 333.08544 -295.831514) (xy 333.376778 -295.831514)
			(xy 333.400654 -295.816782) (xy 333.407512 -295.804082) (xy 333.419812 -295.781353) (xy 333.450384 -295.739686)
			(xy 333.487069 -295.703287) (xy 333.528973 -295.673042) (xy 333.575074 -295.649688) (xy 333.624248 -295.633796)
			(xy 333.675297 -295.625751) (xy 333.726975 -295.625751) (xy 333.778024 -295.633796) (xy 333.827198 -295.649688)
			(xy 333.873299 -295.673042) (xy 333.915203 -295.703287) (xy 333.951888 -295.739686) (xy 333.98246 -295.781353)
			(xy 333.99476 -295.804082) (xy 334.001618 -295.816782) (xy 334.025494 -295.831514) (xy 334.345026 -295.831514)
			(xy 334.368648 -295.817798) (xy 334.375506 -295.805606) (xy 334.388148 -295.784255) (xy 334.419248 -295.745594)
			(xy 334.45619 -295.712472) (xy 334.498003 -295.68576) (xy 334.543585 -295.666162) (xy 334.591737 -295.654192)
			(xy 334.64119 -295.650167) (xy 334.690643 -295.654192) (xy 334.738795 -295.666162) (xy 334.784377 -295.68576)
			(xy 334.82619 -295.712472) (xy 334.863132 -295.745594) (xy 334.894232 -295.784255) (xy 334.906874 -295.805606)
			(xy 334.913732 -295.817798) (xy 334.937354 -295.831514) (xy 336.196686 -295.831514) (xy 336.220562 -295.816782)
			(xy 336.22742 -295.804082) (xy 336.23972 -295.781353) (xy 336.270292 -295.739686) (xy 336.306977 -295.703287)
			(xy 336.348881 -295.673042) (xy 336.394982 -295.649688) (xy 336.444156 -295.633796) (xy 336.495205 -295.625751)
			(xy 336.546883 -295.625751) (xy 336.597932 -295.633796) (xy 336.647106 -295.649688) (xy 336.693207 -295.673042)
			(xy 336.735111 -295.703287) (xy 336.771796 -295.739686) (xy 336.802368 -295.781353) (xy 336.814668 -295.804082)
			(xy 336.821526 -295.816782) (xy 336.845402 -295.831514) (xy 338.076794 -295.831514) (xy 338.10067 -295.816782)
			(xy 338.107528 -295.804082) (xy 338.119828 -295.781353) (xy 338.1504 -295.739686) (xy 338.187085 -295.703287)
			(xy 338.228989 -295.673042) (xy 338.27509 -295.649688) (xy 338.324264 -295.633796) (xy 338.375313 -295.625751)
			(xy 338.426991 -295.625751) (xy 338.47804 -295.633796) (xy 338.527214 -295.649688) (xy 338.573315 -295.673042)
			(xy 338.615219 -295.703287) (xy 338.651904 -295.739686) (xy 338.682476 -295.781353) (xy 338.694776 -295.804082)
			(xy 338.701634 -295.816782) (xy 338.72551 -295.831514) (xy 339.016848 -295.831514) (xy 339.040724 -295.816782)
			(xy 339.047582 -295.804082) (xy 339.059882 -295.781353) (xy 339.090454 -295.739686) (xy 339.127139 -295.703287)
			(xy 339.169043 -295.673042) (xy 339.215144 -295.649688) (xy 339.264318 -295.633796) (xy 339.315367 -295.625751)
			(xy 339.367045 -295.625751) (xy 339.418094 -295.633796) (xy 339.467268 -295.649688) (xy 339.513369 -295.673042)
			(xy 339.555273 -295.703287) (xy 339.591958 -295.739686) (xy 339.62253 -295.781353) (xy 339.63483 -295.804082)
			(xy 339.641688 -295.816782) (xy 339.665564 -295.831514) (xy 339.956648 -295.831514) (xy 339.980524 -295.816782)
			(xy 339.987382 -295.804082) (xy 339.999681 -295.781352) (xy 340.030252 -295.739684) (xy 340.066936 -295.703283)
			(xy 340.10884 -295.673037) (xy 340.154942 -295.649682) (xy 340.204117 -295.633789) (xy 340.255166 -295.625745)
			(xy 340.281006 -295.625266) (xy 340.293706 -295.62552) (xy 340.30793 -295.626028) (xy 340.332314 -295.612566)
			(xy 340.492842 -295.336214) (xy 340.492842 -295.309544) (xy 340.485984 -295.297606) (xy 340.473352 -295.274351)
			(xy 340.455431 -295.224562) (xy 340.446371 -295.172427) (xy 340.445852 -295.145968) (xy 340.446325 -295.121977)
			(xy 340.453835 -295.074587) (xy 340.468665 -295.028955) (xy 340.490449 -294.986204) (xy 340.518652 -294.947386)
			(xy 340.55258 -294.913458) (xy 340.591397 -294.885253) (xy 340.634147 -294.863468) (xy 340.679779 -294.848637)
			(xy 340.727169 -294.841126) (xy 340.75116 -294.84066) (xy 340.760053 -294.840326) (xy 340.776765 -294.834244)
			(xy 340.79038 -294.822803) (xy 340.795102 -294.81526) (xy 340.962742 -294.526462) (xy 340.962996 -294.499538)
			(xy 340.956138 -294.4876) (xy 340.943483 -294.464347) (xy 340.925494 -294.414564) (xy 340.916332 -294.362428)
			(xy 340.915752 -294.335962) (xy 340.916225 -294.311972) (xy 340.923736 -294.264582) (xy 340.938566 -294.218951)
			(xy 340.960351 -294.1762) (xy 340.988555 -294.137384) (xy 341.022482 -294.103456) (xy 341.061299 -294.075252)
			(xy 341.104049 -294.053467) (xy 341.14968 -294.038636) (xy 341.19707 -294.031126) (xy 341.22106 -294.030654)
			(xy 341.229952 -294.03032) (xy 341.246664 -294.024237) (xy 341.260278 -294.012795) (xy 341.265002 -294.005254)
			(xy 341.418418 -293.74084) (xy 341.418164 -293.7129) (xy 341.410544 -293.700962) (xy 341.398687 -293.68118)
			(xy 341.379969 -293.63903) (xy 341.367286 -293.594689) (xy 341.360886 -293.549016) (xy 341.360506 -293.525956)
			(xy 341.361019 -293.499971) (xy 341.369155 -293.448643) (xy 341.38522 -293.399219) (xy 341.408818 -293.352917)
			(xy 341.439369 -293.310876) (xy 341.47612 -293.274131) (xy 341.518167 -293.243588) (xy 341.564473 -293.219998)
			(xy 341.6139 -293.203941) (xy 341.665229 -293.195814) (xy 341.691214 -293.195248) (xy 341.717052 -293.195748)
			(xy 341.768097 -293.203794) (xy 341.817267 -293.219688) (xy 341.863365 -293.243041) (xy 341.905265 -293.273286)
			(xy 341.941946 -293.309684) (xy 341.972515 -293.351348) (xy 341.984838 -293.374064) (xy 341.991696 -293.386764)
			(xy 342.015572 -293.401496) (xy 342.306656 -293.401496) (xy 342.330532 -293.386764) (xy 342.33739 -293.374064)
			(xy 342.34969 -293.351335) (xy 342.380262 -293.30967) (xy 342.416948 -293.273272) (xy 342.458851 -293.243029)
			(xy 342.504952 -293.219677) (xy 342.554127 -293.203786) (xy 342.605175 -293.195743) (xy 342.631014 -293.195248)
			(xy 342.643714 -293.195502) (xy 342.657938 -293.19601) (xy 342.682322 -293.182548) (xy 342.828372 -292.930834)
			(xy 342.828118 -292.902894) (xy 342.820498 -292.890702) (xy 342.808648 -292.870953) (xy 342.789937 -292.828867)
			(xy 342.777261 -292.784589) (xy 342.770864 -292.738979) (xy 342.77046 -292.71595) (xy 342.770939 -292.689957)
			(xy 342.779064 -292.638611) (xy 342.795122 -292.589168) (xy 342.818716 -292.542845) (xy 342.849267 -292.500784)
			(xy 342.886022 -292.46402) (xy 342.928075 -292.433459) (xy 342.974392 -292.409853) (xy 343.023831 -292.393783)
			(xy 343.075175 -292.385646) (xy 343.101168 -292.385242) (xy 343.113614 -292.385496) (xy 343.128092 -292.386004)
			(xy 343.152476 -292.372542) (xy 343.298526 -292.120828) (xy 343.298018 -292.093142) (xy 343.290398 -292.08095)
			(xy 343.278543 -292.061167) (xy 343.259829 -292.019017) (xy 343.24715 -291.974676) (xy 343.240752 -291.929003)
			(xy 343.24036 -291.905944) (xy 343.24084 -291.879952) (xy 343.248965 -291.828606) (xy 343.265023 -291.779163)
			(xy 343.288618 -291.732842) (xy 343.319169 -291.690782) (xy 343.355924 -291.654019) (xy 343.397977 -291.623458)
			(xy 343.444293 -291.599852) (xy 343.493732 -291.583783) (xy 343.545076 -291.575646) (xy 343.571068 -291.575236)
			(xy 343.583768 -291.57549) (xy 343.597992 -291.575998) (xy 343.622376 -291.562536) (xy 343.768426 -291.310822)
			(xy 343.768172 -291.282882) (xy 343.760552 -291.270944) (xy 343.748696 -291.251162) (xy 343.729979 -291.209012)
			(xy 343.717299 -291.16467) (xy 343.710901 -291.118997) (xy 343.710514 -291.095938) (xy 343.710994 -291.069947)
			(xy 343.719121 -291.018606) (xy 343.73518 -290.969167) (xy 343.758776 -290.92285) (xy 343.789328 -290.880796)
			(xy 343.826083 -290.844039) (xy 343.868137 -290.813485) (xy 343.914453 -290.789886) (xy 343.96389 -290.773825)
			(xy 344.015231 -290.765696) (xy 344.041222 -290.76523) (xy 344.053922 -290.765484) (xy 344.068146 -290.765992)
			(xy 344.09253 -290.75253) (xy 344.23858 -290.50107) (xy 344.238072 -290.47313) (xy 344.230452 -290.460938)
			(xy 344.218596 -290.441156) (xy 344.19988 -290.399006) (xy 344.187201 -290.354664) (xy 344.180804 -290.308991)
			(xy 344.180414 -290.285932) (xy 344.180895 -290.259942) (xy 344.189022 -290.208601) (xy 344.205082 -290.159163)
			(xy 344.228678 -290.112847) (xy 344.25923 -290.070793) (xy 344.295985 -290.034037) (xy 344.338039 -290.003483)
			(xy 344.384354 -289.979886) (xy 344.433791 -289.963824) (xy 344.485132 -289.955696) (xy 344.511122 -289.955224)
			(xy 344.523822 -289.955478) (xy 344.5383 -289.955986) (xy 344.562684 -289.942524) (xy 344.70848 -289.691064)
			(xy 344.707972 -289.663124) (xy 344.700606 -289.651186) (xy 344.68868 -289.631397) (xy 344.669871 -289.589194)
			(xy 344.657127 -289.544783) (xy 344.650698 -289.499028) (xy 344.650314 -289.475926) (xy 344.650795 -289.449936)
			(xy 344.658923 -289.398596) (xy 344.674984 -289.349159) (xy 344.69858 -289.302844) (xy 344.729132 -289.260791)
			(xy 344.765888 -289.224035) (xy 344.80794 -289.193482) (xy 344.854255 -289.169885) (xy 344.903692 -289.153824)
			(xy 344.955032 -289.145696) (xy 344.981022 -289.145218) (xy 344.993722 -289.145472) (xy 345.0082 -289.14598)
			(xy 345.032584 -289.132518) (xy 345.178634 -288.880804) (xy 345.178126 -288.852864) (xy 345.170506 -288.840926)
			(xy 345.158653 -288.821143) (xy 345.139941 -288.778992) (xy 345.127265 -288.734651) (xy 345.12087 -288.688979)
			(xy 345.120468 -288.66592) (xy 345.12084 -288.643231) (xy 345.127038 -288.598279) (xy 345.139319 -288.554595)
			(xy 345.157453 -288.512999) (xy 345.168982 -288.493454) (xy 345.176348 -288.481262) (xy 345.176602 -288.453576)
			(xy 345.029536 -288.19983) (xy 345.005152 -288.186368) (xy 344.991182 -288.186622) (xy 344.981022 -288.186876)
			(xy 344.955033 -288.186394) (xy 344.903693 -288.178266) (xy 344.854258 -288.162205) (xy 344.807944 -288.138608)
			(xy 344.765892 -288.108056) (xy 344.729138 -288.0713) (xy 344.698587 -288.029248) (xy 344.674991 -287.982933)
			(xy 344.658932 -287.933497) (xy 344.650805 -287.882157) (xy 344.650314 -287.856168) (xy 344.650699 -287.833409)
			(xy 344.656943 -287.788322) (xy 344.669296 -287.744512) (xy 344.687525 -287.702804) (xy 344.699082 -287.683194)
			(xy 344.706448 -287.671256) (xy 344.706702 -287.643316) (xy 344.559636 -287.38957) (xy 344.535252 -287.376108)
			(xy 344.521282 -287.376362) (xy 344.511122 -287.376616) (xy 344.485131 -287.376134) (xy 344.433789 -287.368006)
			(xy 344.38435 -287.351945) (xy 344.338032 -287.328348) (xy 344.295977 -287.297795) (xy 344.259219 -287.26104)
			(xy 344.228664 -287.218986) (xy 344.205063 -287.172671) (xy 344.188999 -287.123233) (xy 344.180867 -287.071891)
			(xy 344.180867 -287.019909) (xy 344.188999 -286.968567) (xy 344.205063 -286.919129) (xy 344.228664 -286.872814)
			(xy 344.259219 -286.83076) (xy 344.295977 -286.794005) (xy 344.338032 -286.763452) (xy 344.38435 -286.739855)
			(xy 344.433789 -286.723794) (xy 344.485131 -286.715666) (xy 344.511122 -286.7152) (xy 344.523822 -286.715454)
			(xy 344.5383 -286.715962) (xy 344.562684 -286.7025) (xy 344.70848 -286.451294) (xy 344.707972 -286.423354)
			(xy 344.700352 -286.411162) (xy 344.688495 -286.39138) (xy 344.669776 -286.34923) (xy 344.657093 -286.304889)
			(xy 344.650693 -286.259216) (xy 344.650314 -286.236156) (xy 344.650827 -286.210172) (xy 344.658963 -286.158844)
			(xy 344.675028 -286.109421) (xy 344.698627 -286.063119) (xy 344.729178 -286.021078) (xy 344.765929 -285.984335)
			(xy 344.807975 -285.953792) (xy 344.854282 -285.930203) (xy 344.903708 -285.914148) (xy 344.955038 -285.906022)
			(xy 344.981022 -285.905448) (xy 344.993722 -285.905702) (xy 345.007946 -285.90621) (xy 345.03233 -285.892748)
			(xy 345.17838 -285.641034) (xy 345.178126 -285.613094) (xy 345.170506 -285.600902) (xy 345.158655 -285.581153)
			(xy 345.139945 -285.539067) (xy 345.127268 -285.494789) (xy 345.120871 -285.449179) (xy 345.120468 -285.42615)
			(xy 345.120838 -285.403419) (xy 345.127062 -285.358385) (xy 345.139411 -285.314633) (xy 345.157652 -285.272991)
			(xy 345.169236 -285.25343) (xy 345.176348 -285.241492) (xy 345.176856 -285.213552) (xy 345.029536 -284.959806)
			(xy 345.005152 -284.946344) (xy 344.991182 -284.946598) (xy 344.981022 -284.946852) (xy 344.955032 -284.946344)
			(xy 344.903693 -284.938217) (xy 344.854256 -284.922158) (xy 344.807941 -284.898564) (xy 344.765886 -284.868015)
			(xy 344.729127 -284.831264) (xy 344.69857 -284.789216) (xy 344.674967 -284.742905) (xy 344.658899 -284.693472)
			(xy 344.650761 -284.642133) (xy 344.650314 -284.616144) (xy 344.650701 -284.593386) (xy 344.656948 -284.548299)
			(xy 344.669303 -284.504491) (xy 344.687534 -284.462785) (xy 344.699082 -284.44317) (xy 344.706448 -284.431232)
			(xy 344.706702 -284.403292) (xy 344.559636 -284.1498) (xy 344.535252 -284.136338) (xy 344.521282 -284.136592)
			(xy 344.511122 -284.136846) (xy 344.485129 -284.136364) (xy 344.433781 -284.128235) (xy 344.384338 -284.112173)
			(xy 344.338017 -284.088574) (xy 344.295957 -284.058018) (xy 344.259196 -284.021259) (xy 344.228638 -283.979202)
			(xy 344.205036 -283.932882) (xy 344.18897 -283.88344) (xy 344.180837 -283.832093) (xy 344.180837 -283.780107)
			(xy 344.18897 -283.72876) (xy 344.205036 -283.679318) (xy 344.228638 -283.632998) (xy 344.259196 -283.590941)
			(xy 344.295957 -283.554182) (xy 344.338017 -283.523626) (xy 344.384338 -283.500027) (xy 344.433782 -283.483965)
			(xy 344.485129 -283.475836) (xy 344.511122 -283.47543) (xy 344.523822 -283.475684) (xy 344.538046 -283.476192)
			(xy 344.56243 -283.46273) (xy 344.70848 -283.21127) (xy 344.707972 -283.18333) (xy 344.700352 -283.171138)
			(xy 344.688496 -283.151356) (xy 344.66978 -283.109206) (xy 344.657101 -283.064864) (xy 344.650704 -283.019191)
			(xy 344.650314 -282.996132) (xy 344.650795 -282.970142) (xy 344.658922 -282.918801) (xy 344.674982 -282.869363)
			(xy 344.698578 -282.823047) (xy 344.72913 -282.780993) (xy 344.765885 -282.744237) (xy 344.807939 -282.713683)
			(xy 344.854254 -282.690086) (xy 344.903691 -282.674024) (xy 344.955032 -282.665896) (xy 344.981022 -282.665424)
			(xy 344.993722 -282.665678) (xy 345.007946 -282.666186) (xy 345.03233 -282.652724) (xy 345.17838 -282.40101)
			(xy 345.178126 -282.37307) (xy 345.170506 -282.360878) (xy 345.158657 -282.341128) (xy 345.139949 -282.299043)
			(xy 345.127275 -282.254764) (xy 345.120882 -282.209154) (xy 345.120468 -282.186126) (xy 345.12084 -282.163395)
			(xy 345.127066 -282.118363) (xy 345.139418 -282.074612) (xy 345.157661 -282.032972) (xy 345.169236 -282.013406)
			(xy 345.176348 -282.001468) (xy 345.176856 -281.973528) (xy 345.029536 -281.719782) (xy 345.005152 -281.70632)
			(xy 344.991182 -281.706574) (xy 344.981022 -281.706828) (xy 344.95503 -281.706346) (xy 344.903686 -281.698217)
			(xy 344.854245 -281.682156) (xy 344.807926 -281.658558) (xy 344.765869 -281.628005) (xy 344.72911 -281.591248)
			(xy 344.698553 -281.549193) (xy 344.674952 -281.502875) (xy 344.658888 -281.453436) (xy 344.650755 -281.402092)
			(xy 344.650755 -281.350108) (xy 344.658888 -281.298764) (xy 344.674952 -281.249325) (xy 344.698553 -281.203007)
			(xy 344.72911 -281.160952) (xy 344.765869 -281.124195) (xy 344.807926 -281.093642) (xy 344.854245 -281.070044)
			(xy 344.903686 -281.053983) (xy 344.95503 -281.045854) (xy 344.981022 -281.045412) (xy 344.993722 -281.045666)
			(xy 345.007946 -281.046174) (xy 345.03233 -281.032712) (xy 345.17838 -280.780998) (xy 345.178126 -280.753058)
			(xy 345.170506 -280.74112) (xy 345.158653 -280.721337) (xy 345.139942 -280.679186) (xy 345.127267 -280.634845)
			(xy 345.120873 -280.589173) (xy 345.120468 -280.566114) (xy 345.120976 -280.540125) (xy 345.129105 -280.488788)
			(xy 345.145165 -280.439354) (xy 345.168759 -280.393041) (xy 345.199308 -280.350989) (xy 345.23606 -280.314233)
			(xy 345.278108 -280.283679) (xy 345.324419 -280.260079) (xy 345.373851 -280.244014) (xy 345.425187 -280.235879)
			(xy 345.451176 -280.235406) (xy 345.463622 -280.23566) (xy 345.477846 -280.236168) (xy 345.50223 -280.222706)
			(xy 345.64828 -279.970992) (xy 345.648026 -279.943052) (xy 345.640406 -279.93086) (xy 345.628552 -279.911112)
			(xy 345.609834 -279.869027) (xy 345.597149 -279.824749) (xy 345.590744 -279.779138) (xy 345.590368 -279.756108)
			(xy 345.590368 -279.747472) (xy 345.590876 -279.733248) (xy 345.57716 -279.709118) (xy 344.72499 -279.219406)
			(xy 344.69705 -279.219914) (xy 344.685112 -279.22728) (xy 344.665426 -279.239015) (xy 344.623504 -279.257537)
			(xy 344.579427 -279.270092) (xy 344.534037 -279.276438) (xy 344.511122 -279.27681) (xy 344.485131 -279.276329)
			(xy 344.43379 -279.2682) (xy 344.384352 -279.25214) (xy 344.338036 -279.228543) (xy 344.295981 -279.197991)
			(xy 344.259223 -279.161236) (xy 344.228669 -279.119183) (xy 344.205069 -279.072868) (xy 344.189005 -279.023432)
			(xy 344.180873 -278.972091) (xy 344.180873 -278.920109) (xy 344.189005 -278.868768) (xy 344.205069 -278.819332)
			(xy 344.228669 -278.773017) (xy 344.259223 -278.730964) (xy 344.295981 -278.694209) (xy 344.338036 -278.663657)
			(xy 344.384352 -278.64006) (xy 344.43379 -278.624) (xy 344.485131 -278.615871) (xy 344.511122 -278.615394)
			(xy 344.523822 -278.615648) (xy 344.538046 -278.616156) (xy 344.56243 -278.602694) (xy 344.70848 -278.351234)
			(xy 344.707972 -278.323294) (xy 344.700352 -278.311102) (xy 344.688499 -278.291319) (xy 344.669787 -278.249168)
			(xy 344.657112 -278.204827) (xy 344.65072 -278.159155) (xy 344.650314 -278.136096) (xy 344.650797 -278.110108)
			(xy 344.658929 -278.058771) (xy 344.674992 -278.009338) (xy 344.698591 -277.963027) (xy 344.729143 -277.920978)
			(xy 344.765898 -277.884226) (xy 344.807949 -277.853677) (xy 344.854262 -277.830082) (xy 344.903696 -277.814023)
			(xy 344.955034 -277.805895) (xy 344.981022 -277.805388) (xy 344.993722 -277.805642) (xy 345.007946 -277.80615)
			(xy 345.03233 -277.792688) (xy 345.17838 -277.540974) (xy 345.178126 -277.513034) (xy 345.170506 -277.500842)
			(xy 345.158653 -277.481093) (xy 345.139937 -277.439009) (xy 345.127255 -277.394731) (xy 345.120852 -277.349119)
			(xy 345.120468 -277.32609) (xy 345.120842 -277.30336) (xy 345.127073 -277.25833) (xy 345.139429 -277.214581)
			(xy 345.157676 -277.172945) (xy 345.169236 -277.15337) (xy 345.176348 -277.141432) (xy 345.176856 -277.113492)
			(xy 345.029536 -276.859746) (xy 345.005152 -276.846284) (xy 344.991182 -276.846538) (xy 344.981022 -276.846792)
			(xy 344.955032 -276.846311) (xy 344.903692 -276.838182) (xy 344.854255 -276.822121) (xy 344.80794 -276.798525)
			(xy 344.765887 -276.767972) (xy 344.729131 -276.731218) (xy 344.698579 -276.689165) (xy 344.674981 -276.64285)
			(xy 344.65892 -276.593414) (xy 344.65079 -276.542074) (xy 344.650314 -276.516084) (xy 344.650698 -276.493325)
			(xy 344.65694 -276.448236) (xy 344.669291 -276.404426) (xy 344.687518 -276.362716) (xy 344.699082 -276.34311)
			(xy 344.706448 -276.331172) (xy 344.706702 -276.303232) (xy 344.559636 -276.04974) (xy 344.535252 -276.036278)
			(xy 344.521282 -276.036532) (xy 344.511122 -276.036786) (xy 344.485133 -276.036305) (xy 344.433796 -276.028177)
			(xy 344.384361 -276.012117) (xy 344.338048 -275.988522) (xy 344.295996 -275.957973) (xy 344.259242 -275.92122)
			(xy 344.228689 -275.879171) (xy 344.205091 -275.832859) (xy 344.189029 -275.783426) (xy 344.180897 -275.732089)
			(xy 344.180897 -275.680111) (xy 344.189029 -275.628774) (xy 344.205091 -275.579341) (xy 344.228689 -275.533029)
			(xy 344.259242 -275.49098) (xy 344.295996 -275.454227) (xy 344.338048 -275.423678) (xy 344.384361 -275.400083)
			(xy 344.433796 -275.384023) (xy 344.485133 -275.375895) (xy 344.511122 -275.37537) (xy 344.523822 -275.375624)
			(xy 344.538046 -275.376132) (xy 344.56243 -275.36267) (xy 344.70848 -275.11121) (xy 344.707972 -275.08327)
			(xy 344.700352 -275.071078) (xy 344.688494 -275.051296) (xy 344.669773 -275.009147) (xy 344.657088 -274.964806)
			(xy 344.650686 -274.919132) (xy 344.650314 -274.896072) (xy 344.650826 -274.870087) (xy 344.65896 -274.818757)
			(xy 344.675024 -274.769332) (xy 344.698621 -274.723028) (xy 344.729172 -274.680985) (xy 344.765923 -274.644239)
			(xy 344.80797 -274.613695) (xy 344.854278 -274.590104) (xy 344.903706 -274.574048) (xy 344.955037 -274.565922)
			(xy 344.981022 -274.565364) (xy 344.993722 -274.565618) (xy 345.007946 -274.566126) (xy 345.03233 -274.552664)
			(xy 345.17838 -274.30095) (xy 345.178126 -274.27301) (xy 345.170506 -274.260818) (xy 345.158654 -274.241069)
			(xy 345.139942 -274.198984) (xy 345.127263 -274.154706) (xy 345.120863 -274.109095) (xy 345.120468 -274.086066)
			(xy 345.120837 -274.063335) (xy 345.127058 -274.0183) (xy 345.139406 -273.974546) (xy 345.157645 -273.932903)
			(xy 345.169236 -273.913346) (xy 345.176348 -273.901408) (xy 345.176856 -273.873468) (xy 345.029536 -273.619722)
			(xy 345.005152 -273.60626) (xy 344.991182 -273.606514) (xy 344.981022 -273.606768) (xy 344.955033 -273.606286)
			(xy 344.903694 -273.598158) (xy 344.854259 -273.582097) (xy 344.807946 -273.5585) (xy 344.765894 -273.527947)
			(xy 344.729141 -273.491192) (xy 344.698591 -273.449139) (xy 344.674996 -273.402824) (xy 344.658938 -273.353389)
			(xy 344.650812 -273.302049) (xy 344.650314 -273.27606) (xy 344.6507 -273.253301) (xy 344.656945 -273.208214)
			(xy 344.669298 -273.164405) (xy 344.687528 -273.122697) (xy 344.699082 -273.103086) (xy 344.706448 -273.091148)
			(xy 344.706702 -273.063208) (xy 344.559636 -272.809716) (xy 344.535252 -272.796254) (xy 344.521282 -272.796508)
			(xy 344.511122 -272.796762) (xy 344.485135 -272.796281) (xy 344.433801 -272.788153) (xy 344.384371 -272.772095)
			(xy 344.338061 -272.748502) (xy 344.296012 -272.717954) (xy 344.25926 -272.681205) (xy 344.22871 -272.639158)
			(xy 344.205113 -272.59285) (xy 344.189052 -272.54342) (xy 344.180921 -272.492087) (xy 344.180921 -272.440113)
			(xy 344.189052 -272.38878) (xy 344.205113 -272.33935) (xy 344.22871 -272.293042) (xy 344.25926 -272.250995)
			(xy 344.296012 -272.214246) (xy 344.338061 -272.183698) (xy 344.384371 -272.160105) (xy 344.433801 -272.144047)
			(xy 344.485135 -272.135919) (xy 344.511122 -272.135346) (xy 344.523822 -272.1356) (xy 344.538046 -272.136108)
			(xy 344.56243 -272.122646) (xy 344.70848 -271.871186) (xy 344.707972 -271.843246) (xy 344.700352 -271.831054)
			(xy 344.688495 -271.811272) (xy 344.669777 -271.769122) (xy 344.657096 -271.724781) (xy 344.650697 -271.679108)
			(xy 344.650314 -271.656048) (xy 344.650794 -271.630057) (xy 344.658919 -271.578714) (xy 344.674977 -271.529274)
			(xy 344.698573 -271.482956) (xy 344.729125 -271.4409) (xy 344.76588 -271.404141) (xy 344.807934 -271.373586)
			(xy 344.85425 -271.349987) (xy 344.903688 -271.333925) (xy 344.955031 -271.325796) (xy 344.981022 -271.32534)
			(xy 344.993722 -271.325594) (xy 345.007946 -271.326102) (xy 345.03233 -271.31264) (xy 345.17838 -271.060926)
			(xy 345.178126 -271.032986) (xy 345.170506 -271.020794) (xy 345.158656 -271.001045) (xy 345.139946 -270.958959)
			(xy 345.12727 -270.914681) (xy 345.120874 -270.86907) (xy 345.120468 -270.846042) (xy 345.120839 -270.823311)
			(xy 345.127063 -270.778278) (xy 345.139413 -270.734526) (xy 345.157655 -270.692885) (xy 345.169236 -270.673322)
			(xy 345.176348 -270.661384) (xy 345.176856 -270.633444) (xy 345.029536 -270.379698) (xy 345.005152 -270.366236)
			(xy 344.991182 -270.36649) (xy 344.981022 -270.366744) (xy 344.955033 -270.366236) (xy 344.903693 -270.358109)
			(xy 344.854258 -270.34205) (xy 344.807942 -270.318456) (xy 344.765888 -270.287907) (xy 344.729131 -270.251156)
			(xy 344.698575 -270.209107) (xy 344.674972 -270.162796) (xy 344.658905 -270.113363) (xy 344.650768 -270.062025)
			(xy 344.650314 -270.036036) (xy 344.650701 -270.013278) (xy 344.656949 -269.968192) (xy 344.669305 -269.924385)
			(xy 344.687537 -269.882679) (xy 344.699082 -269.863062) (xy 344.706448 -269.851124) (xy 344.706702 -269.823184)
			(xy 344.559636 -269.569692) (xy 344.535252 -269.55623) (xy 344.521282 -269.556484) (xy 344.511122 -269.556738)
			(xy 344.485133 -269.55623) (xy 344.433794 -269.548102) (xy 344.384359 -269.532044) (xy 344.338044 -269.50845)
			(xy 344.29599 -269.477901) (xy 344.259233 -269.441149) (xy 344.228678 -269.399101) (xy 344.205076 -269.35279)
			(xy 344.18901 -269.303357) (xy 344.180874 -269.252019) (xy 344.180414 -269.22603) (xy 344.180871 -269.201313)
			(xy 344.188218 -269.152429) (xy 344.202755 -269.105181) (xy 344.224156 -269.060621) (xy 344.251947 -269.019739)
			(xy 344.28551 -268.983446) (xy 344.324097 -268.952547) (xy 344.34526 -268.939772) (xy 344.354404 -268.934692)
			(xy 344.36685 -268.918182) (xy 344.389202 -268.826742) (xy 344.3859 -268.806422) (xy 344.380312 -268.797532)
			(xy 344.359175 -268.763239) (xy 344.323917 -268.690804) (xy 344.297069 -268.61485) (xy 344.278976 -268.536348)
			(xy 344.26987 -268.456304) (xy 344.269314 -268.416024) (xy 344.269784 -268.378749) (xy 344.277574 -268.304608)
			(xy 344.293072 -268.231687) (xy 344.316108 -268.160786) (xy 344.346429 -268.092681) (xy 344.383702 -268.028119)
			(xy 344.427521 -267.967807) (xy 344.477404 -267.912406) (xy 344.532805 -267.862522) (xy 344.593117 -267.818704)
			(xy 344.657679 -267.781429) (xy 344.725784 -267.751108) (xy 344.796685 -267.728073) (xy 344.869606 -267.712575)
			(xy 344.943747 -267.704784) (xy 344.981022 -267.704316) (xy 344.994878 -267.704354) (xy 345.022572 -267.705369)
			(xy 345.036394 -267.706348) (xy 345.047062 -267.707364) (xy 345.066874 -267.700506) (xy 345.137486 -267.635228)
			(xy 345.145868 -267.616178) (xy 345.145868 -267.60551) (xy 345.146375 -267.581543) (xy 345.153942 -267.534209)
			(xy 345.168812 -267.488639) (xy 345.190621 -267.445953) (xy 345.218833 -267.407199) (xy 345.252754 -267.37333)
			(xy 345.291551 -267.345177) (xy 345.33427 -267.323434) (xy 345.379863 -267.308633) (xy 345.427209 -267.301138)
			(xy 345.451176 -267.30071) (xy 345.474211 -267.301128) (xy 345.519759 -267.30805) (xy 345.56375 -267.321738)
			(xy 345.605183 -267.341884) (xy 345.643117 -267.368028) (xy 345.67669 -267.399577) (xy 345.705141 -267.435814)
			(xy 345.71686 -267.45565) (xy 345.723718 -267.467842) (xy 345.74734 -267.481558) (xy 346.066872 -267.481558)
			(xy 346.090748 -267.466826) (xy 346.097606 -267.454126) (xy 346.109906 -267.431397) (xy 346.140478 -267.38973)
			(xy 346.177163 -267.353331) (xy 346.219067 -267.323086) (xy 346.265168 -267.299732) (xy 346.314342 -267.28384)
			(xy 346.365391 -267.275795) (xy 346.417069 -267.275795) (xy 346.468118 -267.28384) (xy 346.517292 -267.299732)
			(xy 346.563393 -267.323086) (xy 346.605297 -267.353331) (xy 346.641982 -267.38973) (xy 346.672554 -267.431397)
			(xy 346.684854 -267.454126) (xy 346.691712 -267.466826) (xy 346.715588 -267.481558) (xy 347.034866 -267.481558)
			(xy 347.058488 -267.467842) (xy 347.065346 -267.45565) (xy 347.077059 -267.435811) (xy 347.105519 -267.399585)
			(xy 347.139098 -267.368045) (xy 347.177033 -267.341906) (xy 347.218464 -267.321762) (xy 347.262451 -267.308069)
			(xy 347.307996 -267.301139) (xy 347.33103 -267.30071) (xy 347.344746 -267.30071) (xy 347.368114 -267.287248)
			(xy 347.528388 -267.010896) (xy 347.528134 -266.982956) (xy 347.520514 -266.970764) (xy 347.508659 -266.951016)
			(xy 347.48994 -266.908932) (xy 347.477255 -266.864654) (xy 347.470849 -266.819042) (xy 347.470476 -266.796012)
			(xy 347.470985 -266.770024) (xy 347.479114 -266.718687) (xy 347.495173 -266.669254) (xy 347.518768 -266.622941)
			(xy 347.549318 -266.58089) (xy 347.586069 -266.544136) (xy 347.628117 -266.513583) (xy 347.674428 -266.489984)
			(xy 347.72386 -266.47392) (xy 347.775196 -266.465787) (xy 347.801184 -266.465304) (xy 347.81363 -266.465558)
			(xy 347.828108 -266.466066) (xy 347.852492 -266.452604) (xy 347.998542 -266.20089) (xy 347.998034 -266.173204)
			(xy 347.990414 -266.161012) (xy 347.978561 -266.141229) (xy 347.959851 -266.099078) (xy 347.947176 -266.054737)
			(xy 347.940783 -266.009065) (xy 347.940376 -265.986006) (xy 347.940885 -265.960018) (xy 347.949015 -265.908682)
			(xy 347.965075 -265.85925) (xy 347.98867 -265.812938) (xy 348.01922 -265.770888) (xy 348.055971 -265.734134)
			(xy 348.098019 -265.703582) (xy 348.144329 -265.679983) (xy 348.19376 -265.66392) (xy 348.245096 -265.655787)
			(xy 348.271084 -265.655298) (xy 348.294525 -265.655725) (xy 348.340935 -265.662376) (xy 348.385942 -265.675506)
			(xy 348.428648 -265.694851) (xy 348.44863 -265.707114) (xy 348.460822 -265.714734) (xy 348.489016 -265.715242)
			(xy 349.337376 -265.22807) (xy 349.351092 -265.203178) (xy 349.350584 -265.188954) (xy 349.35033 -265.176)
			(xy 349.35033 -265.167364) (xy 349.350838 -265.153394) (xy 349.337122 -265.12901) (xy 348.484952 -264.639298)
			(xy 348.457012 -264.639806) (xy 348.445074 -264.647172) (xy 348.425387 -264.658905) (xy 348.383465 -264.677423)
			(xy 348.339387 -264.689972) (xy 348.293999 -264.696314) (xy 348.271084 -264.696702) (xy 348.245098 -264.696191)
			(xy 348.193766 -264.688059) (xy 348.144339 -264.671997) (xy 348.098033 -264.6484) (xy 348.055987 -264.617851)
			(xy 348.019239 -264.5811) (xy 347.988691 -264.539054) (xy 347.965097 -264.492746) (xy 347.949037 -264.443318)
			(xy 347.940907 -264.391986) (xy 347.940907 -264.340014) (xy 347.949037 -264.288682) (xy 347.965097 -264.239254)
			(xy 347.988691 -264.192946) (xy 348.019239 -264.1509) (xy 348.055987 -264.114149) (xy 348.098033 -264.0836)
			(xy 348.144339 -264.060003) (xy 348.193766 -264.043941) (xy 348.245098 -264.035809) (xy 348.271084 -264.035286)
			(xy 348.294557 -264.035695) (xy 348.341033 -264.042328) (xy 348.386104 -264.055462) (xy 348.428867 -264.074835)
			(xy 348.448884 -264.087102) (xy 348.460822 -264.094722) (xy 348.489016 -264.095484) (xy 349.337376 -263.608058)
			(xy 349.351092 -263.58342) (xy 349.350584 -263.569196) (xy 349.35033 -263.555988) (xy 349.350705 -263.5333)
			(xy 349.356907 -263.48835) (xy 349.369194 -263.444669) (xy 349.387334 -263.403077) (xy 349.398844 -263.383522)
			(xy 349.40621 -263.371584) (xy 349.406464 -263.343644) (xy 349.259144 -263.089644) (xy 349.23476 -263.076182)
			(xy 349.22079 -263.076436) (xy 349.211138 -263.07669) (xy 349.185148 -263.07621) (xy 349.133808 -263.068084)
			(xy 349.084371 -263.052026) (xy 349.038055 -263.028431) (xy 348.996001 -262.997881) (xy 348.959243 -262.961128)
			(xy 348.928689 -262.919078) (xy 348.905089 -262.872764) (xy 348.889025 -262.823329) (xy 348.880893 -262.77199)
			(xy 348.880893 -262.72001) (xy 348.889025 -262.668671) (xy 348.905089 -262.619236) (xy 348.928689 -262.572922)
			(xy 348.959243 -262.530872) (xy 348.996001 -262.494119) (xy 349.038055 -262.463569) (xy 349.084371 -262.439974)
			(xy 349.133808 -262.423916) (xy 349.185148 -262.41579) (xy 349.211138 -262.415274) (xy 349.22333 -262.415528)
			(xy 349.237554 -262.416036) (xy 349.261938 -262.402574) (xy 349.408242 -262.150606) (xy 349.407734 -262.122666)
			(xy 349.400114 -262.110474) (xy 349.388321 -262.090739) (xy 349.369707 -262.048703) (xy 349.357096 -262.004493)
			(xy 349.350731 -261.958963) (xy 349.35033 -261.935976) (xy 349.350705 -261.913288) (xy 349.356909 -261.868339)
			(xy 349.369197 -261.824659) (xy 349.387339 -261.783068) (xy 349.398844 -261.76351) (xy 349.40621 -261.751572)
			(xy 349.406464 -261.723632) (xy 349.259144 -261.469632) (xy 349.23476 -261.45617) (xy 349.22079 -261.456424)
			(xy 349.211138 -261.456678) (xy 349.185149 -261.456198) (xy 349.133811 -261.448072) (xy 349.084375 -261.432015)
			(xy 349.038061 -261.408421) (xy 348.996008 -261.377872) (xy 348.959253 -261.341121) (xy 348.928699 -261.299071)
			(xy 348.9051 -261.25276) (xy 348.889037 -261.203326) (xy 348.880905 -261.151989) (xy 348.880905 -261.100011)
			(xy 348.889037 -261.048674) (xy 348.9051 -260.99924) (xy 348.928699 -260.952929) (xy 348.959252 -260.910879)
			(xy 348.996008 -260.874128) (xy 349.038061 -260.843579) (xy 349.084375 -260.819985) (xy 349.133811 -260.803928)
			(xy 349.185149 -260.795802) (xy 349.211138 -260.795262) (xy 349.241218 -260.79592) (xy 349.30039 -260.806779)
			(xy 349.32874 -260.816852) (xy 349.341948 -260.821932) (xy 349.36938 -260.816852) (xy 350.437196 -259.876544)
			(xy 350.445324 -259.848096) (xy 350.44126 -259.833872) (xy 350.434254 -259.808474) (xy 350.426739 -259.756328)
			(xy 350.426274 -259.729986) (xy 350.426737 -259.703855) (xy 350.434131 -259.652117) (xy 350.448754 -259.601941)
			(xy 350.470314 -259.554332) (xy 350.498379 -259.510244) (xy 350.532387 -259.470558) (xy 350.571656 -259.436071)
			(xy 350.6154 -259.407473) (xy 350.638872 -259.395976) (xy 350.652334 -259.389626) (xy 350.668336 -259.364734)
			(xy 350.668336 -259.195316) (xy 350.652334 -259.170424) (xy 350.638872 -259.164074) (xy 350.613826 -259.151816)
			(xy 350.567432 -259.120885) (xy 350.526225 -259.083319) (xy 350.491148 -259.039975) (xy 350.462999 -258.991842)
			(xy 350.442422 -258.940018) (xy 350.429885 -258.885685) (xy 350.425676 -258.830085) (xy 350.42989 -258.774484)
			(xy 350.442431 -258.720153) (xy 350.463012 -258.668331) (xy 350.491165 -258.6202) (xy 350.526246 -258.576859)
			(xy 350.567456 -258.539296) (xy 350.613853 -258.508369) (xy 350.638872 -258.496054) (xy 350.652334 -258.489704)
			(xy 350.668336 -258.464812) (xy 350.668336 -258.295394) (xy 350.652334 -258.270502) (xy 350.638872 -258.264152)
			(xy 350.615382 -258.252684) (xy 350.571616 -258.224103) (xy 350.53233 -258.189623) (xy 350.498311 -258.149936)
			(xy 350.470243 -258.105839) (xy 350.448689 -258.058218) (xy 350.434083 -258.008028) (xy 350.426717 -257.956278)
			(xy 350.426274 -257.930142) (xy 350.426403 -257.915088) (xy 350.42882 -257.885079) (xy 350.4311 -257.870198)
			(xy 350.43364 -257.855212) (xy 350.42221 -257.828542) (xy 349.104712 -256.922524) (xy 349.077026 -256.920746)
			(xy 349.064326 -256.92735) (xy 349.040546 -256.939183) (xy 348.990149 -256.955943) (xy 348.93772 -256.96443)
			(xy 348.911164 -256.964942) (xy 348.885178 -256.96443) (xy 348.833846 -256.956295) (xy 348.784418 -256.940231)
			(xy 348.738111 -256.916634) (xy 348.696065 -256.886084) (xy 348.659314 -256.849334) (xy 348.628765 -256.807288)
			(xy 348.605168 -256.76098) (xy 348.589105 -256.711552) (xy 348.58097 -256.66022) (xy 348.580456 -256.634234)
			(xy 348.580846 -256.611319) (xy 348.587178 -256.565928) (xy 348.599726 -256.521849) (xy 348.618249 -256.479929)
			(xy 348.629986 -256.460244) (xy 348.637352 -256.448052) (xy 348.63786 -256.420366) (xy 348.491302 -256.167636)
			(xy 348.466918 -256.154174) (xy 348.452694 -256.154682) (xy 348.44101 -256.154936) (xy 348.415388 -256.154448)
			(xy 348.364759 -256.146533) (xy 348.315957 -256.130907) (xy 348.270147 -256.107942) (xy 348.228426 -256.078188)
			(xy 348.191791 -256.042357) (xy 348.16112 -256.001307) (xy 348.148656 -255.978914) (xy 348.142052 -255.966214)
			(xy 348.118176 -255.951736) (xy 347.824044 -255.951736) (xy 347.800168 -255.966214) (xy 347.793564 -255.978914)
			(xy 347.781155 -256.00134) (xy 347.750484 -256.042403) (xy 347.713845 -256.078242) (xy 347.672115 -256.107997)
			(xy 347.626293 -256.130957) (xy 347.577477 -256.146572) (xy 347.526836 -256.154466) (xy 347.50121 -256.154936)
			(xy 347.488002 -256.154682) (xy 347.473778 -256.154174) (xy 347.449394 -256.167636) (xy 347.303344 -256.418842)
			(xy 347.303852 -256.446782) (xy 347.311472 -256.458974) (xy 347.323398 -256.478763) (xy 347.342208 -256.520966)
			(xy 347.354954 -256.565377) (xy 347.361387 -256.611132) (xy 347.361764 -256.634234) (xy 347.361254 -256.660221)
			(xy 347.353124 -256.711556) (xy 347.337063 -256.760986) (xy 347.313467 -256.807296) (xy 347.282917 -256.849344)
			(xy 347.246166 -256.886095) (xy 347.204118 -256.916645) (xy 347.157808 -256.940241) (xy 347.108378 -256.956302)
			(xy 347.057043 -256.964432) (xy 347.005069 -256.964432) (xy 346.953734 -256.956302) (xy 346.904304 -256.940241)
			(xy 346.857994 -256.916645) (xy 346.815946 -256.886095) (xy 346.779195 -256.849344) (xy 346.748645 -256.807296)
			(xy 346.725049 -256.760986) (xy 346.708988 -256.711556) (xy 346.700858 -256.660221) (xy 346.700348 -256.634234)
			(xy 346.700602 -256.62255) (xy 346.70111 -256.608326) (xy 346.687648 -256.583942) (xy 345.83751 -256.095754)
			(xy 345.809824 -256.096262) (xy 345.797632 -256.103882) (xy 345.777729 -256.115979) (xy 345.735246 -256.135073)
			(xy 345.690505 -256.148016) (xy 345.64439 -256.154553) (xy 345.621102 -256.154936) (xy 345.608148 -256.154682)
			(xy 345.59367 -256.154174) (xy 345.569286 -256.167636) (xy 345.42349 -256.418842) (xy 345.423998 -256.446782)
			(xy 345.431618 -256.45872) (xy 345.443548 -256.478542) (xy 345.462358 -256.52081) (xy 345.4751 -256.565285)
			(xy 345.481524 -256.611102) (xy 345.48191 -256.634234) (xy 345.4814 -256.660221) (xy 345.47327 -256.711556)
			(xy 345.457209 -256.760986) (xy 345.433613 -256.807296) (xy 345.403063 -256.849344) (xy 345.366312 -256.886095)
			(xy 345.324264 -256.916645) (xy 345.277954 -256.940241) (xy 345.228524 -256.956302) (xy 345.177189 -256.964432)
			(xy 345.125215 -256.964432) (xy 345.07388 -256.956302) (xy 345.02445 -256.940241) (xy 344.97814 -256.916645)
			(xy 344.936092 -256.886095) (xy 344.899341 -256.849344) (xy 344.868791 -256.807296) (xy 344.845195 -256.760986)
			(xy 344.829134 -256.711556) (xy 344.821004 -256.660221) (xy 344.820494 -256.634234) (xy 344.820748 -256.62255)
			(xy 344.821256 -256.608326) (xy 344.807794 -256.583942) (xy 343.957402 -256.095754) (xy 343.929716 -256.096262)
			(xy 343.917524 -256.103882) (xy 343.89762 -256.115979) (xy 343.855138 -256.135071) (xy 343.810397 -256.148014)
			(xy 343.764282 -256.154549) (xy 343.740994 -256.154936) (xy 343.715369 -256.154455) (xy 343.664732 -256.146551)
			(xy 343.61592 -256.130932) (xy 343.5701 -256.107974) (xy 343.528368 -256.078224) (xy 343.491724 -256.042394)
			(xy 343.461042 -256.001343) (xy 343.44864 -255.978914) (xy 343.442036 -255.966214) (xy 343.41816 -255.951736)
			(xy 343.124028 -255.951736) (xy 343.100152 -255.966214) (xy 343.093548 -255.978914) (xy 343.081138 -256.001341)
			(xy 343.050466 -256.042405) (xy 343.013827 -256.078245) (xy 342.972097 -256.108005) (xy 342.926277 -256.130972)
			(xy 342.877462 -256.146595) (xy 342.826821 -256.154502) (xy 342.775567 -256.154502) (xy 342.724926 -256.146595)
			(xy 342.676111 -256.130972) (xy 342.630291 -256.108005) (xy 342.588561 -256.078245) (xy 342.551922 -256.042405)
			(xy 342.52125 -256.001341) (xy 342.50884 -255.978914) (xy 342.502236 -255.966214) (xy 342.47836 -255.951736)
			(xy 342.183974 -255.951736) (xy 342.160098 -255.966214) (xy 342.153494 -255.978914) (xy 342.141084 -256.001341)
			(xy 342.110412 -256.042405) (xy 342.073773 -256.078245) (xy 342.032043 -256.108005) (xy 341.986223 -256.130972)
			(xy 341.937408 -256.146595) (xy 341.886767 -256.154502) (xy 341.835513 -256.154502) (xy 341.784872 -256.146595)
			(xy 341.736057 -256.130972) (xy 341.690237 -256.108005) (xy 341.648507 -256.078245) (xy 341.611868 -256.042405)
			(xy 341.581196 -256.001341) (xy 341.568786 -255.978914) (xy 341.562182 -255.966214) (xy 341.538306 -255.951736)
			(xy 341.24392 -255.951736) (xy 341.220044 -255.966214) (xy 341.21344 -255.978914) (xy 341.20103 -256.001341)
			(xy 341.170358 -256.042405) (xy 341.133719 -256.078245) (xy 341.091989 -256.108005) (xy 341.046169 -256.130972)
			(xy 340.997354 -256.146595) (xy 340.946713 -256.154502) (xy 340.895459 -256.154502) (xy 340.844818 -256.146595)
			(xy 340.796003 -256.130972) (xy 340.750183 -256.108005) (xy 340.708453 -256.078245) (xy 340.671814 -256.042405)
			(xy 340.641142 -256.001341) (xy 340.628732 -255.978914) (xy 340.622128 -255.966214) (xy 340.598252 -255.951736)
			(xy 340.303866 -255.951736) (xy 340.27999 -255.966214) (xy 340.273386 -255.978914) (xy 340.260976 -256.001341)
			(xy 340.230304 -256.042405) (xy 340.193665 -256.078245) (xy 340.151935 -256.108005) (xy 340.106115 -256.130972)
			(xy 340.0573 -256.146595) (xy 340.006659 -256.154502) (xy 339.955405 -256.154502) (xy 339.904764 -256.146595)
			(xy 339.855949 -256.130972) (xy 339.810129 -256.108005) (xy 339.768399 -256.078245) (xy 339.73176 -256.042405)
			(xy 339.701088 -256.001341) (xy 339.688678 -255.978914) (xy 339.682074 -255.966214) (xy 339.658198 -255.951736)
			(xy 339.194902 -255.951736) (xy 339.184934 -255.951263) (xy 339.166488 -255.943697) (xy 339.159088 -255.937004)
			(xy 338.57438 -255.352296) (xy 338.55787 -255.344676) (xy 338.548472 -255.344168) (xy 338.522207 -255.341853)
			(xy 338.470846 -255.329947) (xy 338.422024 -255.310044) (xy 338.376978 -255.282647) (xy 338.336849 -255.248451)
			(xy 338.302653 -255.208322) (xy 338.275256 -255.163276) (xy 338.255353 -255.114454) (xy 338.243447 -255.063093)
			(xy 338.241132 -255.036828) (xy 338.240624 -255.02743) (xy 338.233004 -255.01092) (xy 336.901282 -253.679198)
			(xy 336.8675 -253.674626) (xy 336.852514 -253.682754) (xy 336.8277 -253.695965) (xy 336.77472 -253.714746)
			(xy 336.719329 -253.72431) (xy 336.691224 -253.724918) (xy 336.665233 -253.724437) (xy 336.613891 -253.716308)
			(xy 336.564453 -253.700248) (xy 336.518136 -253.676652) (xy 336.47608 -253.646101) (xy 336.439322 -253.609346)
			(xy 336.408766 -253.567294) (xy 336.385165 -253.520979) (xy 336.369099 -253.471542) (xy 336.360966 -253.420201)
			(xy 336.360516 -253.39421) (xy 336.361097 -253.366102) (xy 336.370642 -253.3107) (xy 336.389424 -253.257713)
			(xy 336.40268 -253.23292) (xy 336.410808 -253.217934) (xy 336.406236 -253.184152) (xy 336.12201 -252.899926)
			(xy 336.111088 -252.896116) (xy 336.088022 -252.887501) (xy 336.044531 -252.864422) (xy 336.004941 -252.835151)
			(xy 335.970128 -252.800334) (xy 335.94086 -252.760741) (xy 335.917786 -252.717247) (xy 335.909158 -252.694186)
			(xy 335.905348 -252.683264) (xy 335.359756 -252.137672) (xy 335.353081 -252.130259) (xy 335.345516 -252.111823)
			(xy 335.345024 -252.101858) (xy 335.345024 -227.323396) (xy 335.344601 -227.313326) (xy 335.336888 -227.29472)
			(xy 335.330038 -227.287328) (xy 335.153254 -227.110544) (xy 335.14583 -227.103764) (xy 335.127234 -227.096159)
			(xy 335.117186 -227.095812) (xy 327.25868 -227.095812) (xy 327.246547 -227.096441) (xy 327.224934 -227.107459)
			(xy 327.217278 -227.116894) (xy 327.202757 -227.136065) (xy 327.167792 -227.169076) (xy 327.127243 -227.194923)
			(xy 327.082556 -227.212684) (xy 327.035327 -227.221724) (xy 327.011284 -227.222304) (xy 303.628552 -227.222304)
			(xy 303.604422 -227.23729) (xy 303.597818 -227.250244) (xy 303.585208 -227.274372) (xy 303.553964 -227.318955)
			(xy 303.516503 -227.358457) (xy 303.473639 -227.39202) (xy 303.426305 -227.418912) (xy 303.37553 -227.438551)
			(xy 303.322418 -227.450507) (xy 303.268126 -227.454522) (xy 303.213834 -227.450507) (xy 303.160722 -227.438551)
			(xy 303.109947 -227.418912) (xy 303.062613 -227.39202) (xy 303.019749 -227.358457) (xy 302.982288 -227.318955)
			(xy 302.951044 -227.274372) (xy 302.938434 -227.250244) (xy 302.93183 -227.23729) (xy 302.9077 -227.222304)
			(xy 300.184566 -227.222304) (xy 300.160436 -227.23729) (xy 300.153832 -227.250244) (xy 300.141222 -227.274372)
			(xy 300.109978 -227.318955) (xy 300.072517 -227.358457) (xy 300.029653 -227.39202) (xy 299.982319 -227.418912)
			(xy 299.931544 -227.438551) (xy 299.878432 -227.450507) (xy 299.82414 -227.454522) (xy 299.769848 -227.450507)
			(xy 299.716736 -227.438551) (xy 299.665961 -227.418912) (xy 299.618627 -227.39202) (xy 299.575763 -227.358457)
			(xy 299.538302 -227.318955) (xy 299.507058 -227.274372) (xy 299.494448 -227.250244) (xy 299.487844 -227.23729)
			(xy 299.463714 -227.222304) (xy 296.084498 -227.222304) (xy 296.060368 -227.23729) (xy 296.053764 -227.250244)
			(xy 296.041154 -227.274372) (xy 296.00991 -227.318955) (xy 295.972449 -227.358457) (xy 295.929585 -227.39202)
			(xy 295.882251 -227.418912) (xy 295.831476 -227.438551) (xy 295.778364 -227.450507) (xy 295.724072 -227.454522)
			(xy 295.66978 -227.450507) (xy 295.616668 -227.438551) (xy 295.565893 -227.418912) (xy 295.518559 -227.39202)
			(xy 295.475695 -227.358457) (xy 295.438234 -227.318955) (xy 295.40699 -227.274372) (xy 295.39438 -227.250244)
			(xy 295.387776 -227.23729) (xy 295.363646 -227.222304) (xy 292.640512 -227.222304) (xy 292.616382 -227.23729)
			(xy 292.609778 -227.250244) (xy 292.597168 -227.274372) (xy 292.565924 -227.318955) (xy 292.528463 -227.358457)
			(xy 292.485599 -227.39202) (xy 292.438265 -227.418912) (xy 292.38749 -227.438551) (xy 292.334378 -227.450507)
			(xy 292.280086 -227.454522) (xy 292.225794 -227.450507) (xy 292.172682 -227.438551) (xy 292.121907 -227.418912)
			(xy 292.074573 -227.39202) (xy 292.031709 -227.358457) (xy 291.994248 -227.318955) (xy 291.963004 -227.274372)
			(xy 291.950394 -227.250244) (xy 291.94379 -227.23729) (xy 291.91966 -227.222304) (xy 288.540444 -227.222304)
			(xy 288.516314 -227.23729) (xy 288.50971 -227.250244) (xy 288.4971 -227.274372) (xy 288.465856 -227.318955)
			(xy 288.428395 -227.358457) (xy 288.385531 -227.39202) (xy 288.338197 -227.418912) (xy 288.287422 -227.438551)
			(xy 288.23431 -227.450507) (xy 288.180018 -227.454522) (xy 288.125726 -227.450507) (xy 288.072614 -227.438551)
			(xy 288.021839 -227.418912) (xy 287.974505 -227.39202) (xy 287.931641 -227.358457) (xy 287.89418 -227.318955)
			(xy 287.862936 -227.274372) (xy 287.850326 -227.250244) (xy 287.843722 -227.23729) (xy 287.819592 -227.222304)
			(xy 285.096458 -227.222304) (xy 285.072328 -227.23729) (xy 285.065724 -227.250244) (xy 285.053114 -227.274372)
			(xy 285.02187 -227.318955) (xy 284.984409 -227.358457) (xy 284.941545 -227.39202) (xy 284.894211 -227.418912)
			(xy 284.843436 -227.438551) (xy 284.790324 -227.450507) (xy 284.736032 -227.454522) (xy 284.68174 -227.450507)
			(xy 284.628628 -227.438551) (xy 284.577853 -227.418912) (xy 284.530519 -227.39202) (xy 284.487655 -227.358457)
			(xy 284.450194 -227.318955) (xy 284.41895 -227.274372) (xy 284.40634 -227.250244) (xy 284.399736 -227.23729)
			(xy 284.375606 -227.222304) (xy 280.99639 -227.222304) (xy 280.97226 -227.23729) (xy 280.965656 -227.250244)
			(xy 280.953046 -227.274372) (xy 280.921802 -227.318955) (xy 280.884341 -227.358457) (xy 280.841477 -227.39202)
			(xy 280.794143 -227.418912) (xy 280.743368 -227.438551) (xy 280.690256 -227.450507) (xy 280.635964 -227.454522)
			(xy 280.581672 -227.450507) (xy 280.52856 -227.438551) (xy 280.477785 -227.418912) (xy 280.430451 -227.39202)
			(xy 280.387587 -227.358457) (xy 280.350126 -227.318955) (xy 280.318882 -227.274372) (xy 280.306272 -227.250244)
			(xy 280.299668 -227.23729) (xy 280.275538 -227.222304) (xy 277.552658 -227.222304) (xy 277.528528 -227.23729)
			(xy 277.521924 -227.250244) (xy 277.509314 -227.274372) (xy 277.47807 -227.318955) (xy 277.440609 -227.358457)
			(xy 277.397745 -227.39202) (xy 277.350411 -227.418912) (xy 277.299636 -227.438551) (xy 277.246524 -227.450507)
			(xy 277.192232 -227.454522) (xy 277.13794 -227.450507) (xy 277.084828 -227.438551) (xy 277.034053 -227.418912)
			(xy 276.986719 -227.39202) (xy 276.943855 -227.358457) (xy 276.906394 -227.318955) (xy 276.87515 -227.274372)
			(xy 276.86254 -227.250244) (xy 276.855936 -227.23729) (xy 276.831806 -227.222304) (xy 273.45259 -227.222304)
			(xy 273.42846 -227.23729) (xy 273.421856 -227.250244) (xy 273.409246 -227.274372) (xy 273.378002 -227.318955)
			(xy 273.340541 -227.358457) (xy 273.297677 -227.39202) (xy 273.250343 -227.418912) (xy 273.199568 -227.438551)
			(xy 273.146456 -227.450507) (xy 273.092164 -227.454522) (xy 273.037872 -227.450507) (xy 272.98476 -227.438551)
			(xy 272.933985 -227.418912) (xy 272.886651 -227.39202) (xy 272.843787 -227.358457) (xy 272.806326 -227.318955)
			(xy 272.775082 -227.274372) (xy 272.762472 -227.250244) (xy 272.755868 -227.23729) (xy 272.731738 -227.222304)
			(xy 271.399762 -227.222304) (xy 271.38976 -227.222799) (xy 271.371282 -227.230465) (xy 271.357142 -227.244617)
			(xy 271.34949 -227.263101) (xy 271.348962 -227.273104) (xy 271.348962 -243.860828) (xy 271.34921 -243.868009)
			(xy 271.353207 -243.881804) (xy 271.356836 -243.888006) (xy 271.370366 -243.910221) (xy 271.391725 -243.957647)
			(xy 271.406205 -244.007604) (xy 271.413516 -244.059102) (xy 271.413515 -244.111115) (xy 271.406201 -244.162612)
			(xy 271.391719 -244.212569) (xy 271.370358 -244.259994) (xy 271.356836 -244.282214) (xy 271.353197 -244.288412)
			(xy 271.34919 -244.302209) (xy 271.348962 -244.309392) (xy 271.348962 -258.880102) (xy 315.252104 -258.880102)
			(xy 315.256134 -258.737767) (xy 315.268209 -258.595887) (xy 315.288292 -258.454919) (xy 315.316319 -258.315312)
			(xy 315.352199 -258.177514) (xy 315.395817 -258.041967) (xy 315.447034 -257.909105) (xy 315.505685 -257.779353)
			(xy 315.571583 -257.653127) (xy 315.644517 -257.530831) (xy 315.724254 -257.412858) (xy 315.810536 -257.299585)
			(xy 315.903089 -257.191374) (xy 316.001616 -257.088573) (xy 316.105801 -256.991511) (xy 316.21531 -256.900499)
			(xy 316.329793 -256.815827) (xy 316.448883 -256.737769) (xy 316.572198 -256.666573) (xy 316.699344 -256.602467)
			(xy 316.829913 -256.545658) (xy 316.963487 -256.496326) (xy 317.099638 -256.45463) (xy 317.237929 -256.420704)
			(xy 317.377919 -256.394656) (xy 317.519158 -256.37657) (xy 317.661194 -256.366503) (xy 317.803572 -256.364488)
			(xy 317.945836 -256.370531) (xy 318.08753 -256.384613) (xy 318.2282 -256.406689) (xy 318.367397 -256.436689)
			(xy 318.504673 -256.474515) (xy 318.639589 -256.520047) (xy 318.771713 -256.573138) (xy 318.900622 -256.63362)
			(xy 319.025903 -256.701298) (xy 319.147154 -256.775955) (xy 319.263987 -256.857353) (xy 319.376028 -256.94523)
			(xy 319.482918 -257.039305) (xy 319.584315 -257.139277) (xy 319.679893 -257.244825) (xy 319.769347 -257.355611)
			(xy 319.852389 -257.47128) (xy 319.928755 -257.591463) (xy 319.998199 -257.715773) (xy 320.060499 -257.843814)
			(xy 320.115455 -257.975173) (xy 320.162892 -258.109432) (xy 320.202656 -258.246159) (xy 320.234622 -258.384917)
			(xy 320.258687 -258.525261) (xy 320.274773 -258.666742) (xy 320.282828 -258.808906) (xy 320.283332 -258.880102)
			(xy 320.282828 -258.951298) (xy 320.274773 -259.093462) (xy 320.258687 -259.234943) (xy 320.234622 -259.375287)
			(xy 320.202656 -259.514045) (xy 320.162892 -259.650772) (xy 320.115455 -259.785031) (xy 320.060499 -259.91639)
			(xy 319.998199 -260.044431) (xy 319.928755 -260.168741) (xy 319.852389 -260.288924) (xy 319.769347 -260.404593)
			(xy 319.679893 -260.515379) (xy 319.584315 -260.620927) (xy 319.482918 -260.720899) (xy 319.376028 -260.814974)
			(xy 319.263987 -260.902851) (xy 319.147154 -260.984249) (xy 319.025903 -261.058906) (xy 318.900622 -261.126584)
			(xy 318.771713 -261.187066) (xy 318.639589 -261.240157) (xy 318.504673 -261.285689) (xy 318.367397 -261.323515)
			(xy 318.2282 -261.353515) (xy 318.08753 -261.375591) (xy 317.945836 -261.389673) (xy 317.803572 -261.395716)
			(xy 317.661194 -261.393701) (xy 317.519158 -261.383634) (xy 317.377919 -261.365548) (xy 317.237929 -261.3395)
			(xy 317.099638 -261.305574) (xy 316.963487 -261.263878) (xy 316.829913 -261.214546) (xy 316.699344 -261.157737)
			(xy 316.572198 -261.093631) (xy 316.448883 -261.022435) (xy 316.329793 -260.944377) (xy 316.21531 -260.859705)
			(xy 316.105801 -260.768693) (xy 316.001616 -260.671631) (xy 315.903089 -260.56883) (xy 315.810536 -260.460619)
			(xy 315.724254 -260.347346) (xy 315.644517 -260.229373) (xy 315.571583 -260.107077) (xy 315.505685 -259.980851)
			(xy 315.447034 -259.851099) (xy 315.395817 -259.718237) (xy 315.352199 -259.58269) (xy 315.316319 -259.444892)
			(xy 315.288292 -259.305285) (xy 315.268209 -259.164317) (xy 315.256134 -259.022437) (xy 315.252104 -258.880102)
			(xy 271.348962 -258.880102) (xy 271.348962 -334.81518) (xy 271.349401 -334.825242) (xy 271.357143 -334.84382)
			(xy 271.363948 -334.851248) (xy 271.731232 -335.218532) (xy 271.738629 -335.225381) (xy 271.757228 -335.233114)
			(xy 271.7673 -335.233518)
		)
		(stroke
			(width 0)
			(type solid)
		)
		(fill yes)
		(layer "In9.Cu")
		(net "PVDDIO_P0")
	)
	(gr_poly
		(pts
			(xy 56.104028 -335.233264) (xy 56.114095 -335.232835) (xy 56.132689 -335.225109) (xy 56.140096 -335.218278)
			(xy 56.5404 -334.817974) (xy 56.547242 -334.810574) (xy 56.554967 -334.791976) (xy 56.555386 -334.781906)
			(xy 56.555386 -325.5772) (xy 56.554966 -325.56718) (xy 56.547296 -325.548665) (xy 56.533123 -325.534496)
			(xy 56.514606 -325.526831) (xy 56.504586 -325.5264) (xy 56.501792 -325.5264) (xy 56.457304 -325.525901)
			(xy 56.368687 -325.517924) (xy 56.281142 -325.502037) (xy 56.195373 -325.478365) (xy 56.112071 -325.447101)
			(xy 56.031907 -325.408495) (xy 55.955527 -325.36286) (xy 55.883544 -325.310561) (xy 55.81654 -325.25202)
			(xy 55.755052 -325.187709) (xy 55.699577 -325.118145) (xy 55.650561 -325.043888) (xy 55.608399 -324.965537)
			(xy 55.573429 -324.883721) (xy 55.545935 -324.799101) (xy 55.526136 -324.712356) (xy 55.514192 -324.624186)
			(xy 55.5102 -324.5353) (xy 55.514192 -324.446414) (xy 55.526136 -324.358244) (xy 55.545935 -324.271499)
			(xy 55.573429 -324.186879) (xy 55.608399 -324.105063) (xy 55.650561 -324.026712) (xy 55.699577 -323.952455)
			(xy 55.755052 -323.882891) (xy 55.81654 -323.81858) (xy 55.883544 -323.760039) (xy 55.955527 -323.70774)
			(xy 56.031907 -323.662105) (xy 56.112071 -323.623499) (xy 56.195373 -323.592235) (xy 56.281142 -323.568563)
			(xy 56.368687 -323.552676) (xy 56.457304 -323.544699) (xy 56.501792 -323.544184) (xy 56.504586 -323.544184)
			(xy 56.514608 -323.543767) (xy 56.533127 -323.536099) (xy 56.5473 -323.521925) (xy 56.554967 -323.503406)
			(xy 56.555386 -323.493384) (xy 56.555386 -315.849762) (xy 56.554944 -315.840865) (xy 56.54876 -315.824175)
			(xy 56.537253 -315.810595) (xy 56.529732 -315.80582) (xy 56.505874 -315.791632) (xy 56.462326 -315.757215)
			(xy 56.424424 -315.716664) (xy 56.393023 -315.670894) (xy 56.36883 -315.620937) (xy 56.352393 -315.56792)
			(xy 56.344082 -315.513039) (xy 56.344084 -315.457533) (xy 56.3524 -315.402653) (xy 56.368841 -315.349637)
			(xy 56.393037 -315.299682) (xy 56.424441 -315.253914) (xy 56.462347 -315.213366) (xy 56.505897 -315.178952)
			(xy 56.529732 -315.164724) (xy 56.537309 -315.160019) (xy 56.548833 -315.146422) (xy 56.554984 -315.129693)
			(xy 56.555386 -315.120782) (xy 56.555386 -313.299856) (xy 56.554943 -313.29096) (xy 56.548758 -313.274271)
			(xy 56.537251 -313.260693) (xy 56.529732 -313.255914) (xy 56.505875 -313.241726) (xy 56.462327 -313.207309)
			(xy 56.424426 -313.166759) (xy 56.393026 -313.120989) (xy 56.368834 -313.071032) (xy 56.352398 -313.018016)
			(xy 56.344087 -312.963136) (xy 56.34409 -312.90763) (xy 56.352405 -312.852751) (xy 56.368847 -312.799736)
			(xy 56.393043 -312.749782) (xy 56.424447 -312.704015) (xy 56.462352 -312.663468) (xy 56.505903 -312.629055)
			(xy 56.529732 -312.614818) (xy 56.537308 -312.610113) (xy 56.54883 -312.596516) (xy 56.554979 -312.579787)
			(xy 56.555386 -312.570876) (xy 56.555386 -308.169564) (xy 56.556001 -308.144609) (xy 56.565744 -308.095658)
			(xy 56.584849 -308.049548) (xy 56.612581 -308.008051) (xy 56.629808 -307.989986) (xy 68.841112 -295.778682)
			(xy 68.859152 -295.761418) (xy 68.900644 -295.733653) (xy 68.946762 -295.714532) (xy 68.995727 -295.704793)
			(xy 69.02069 -295.70426) (xy 78.948788 -295.70426) (xy 78.957133 -295.703969) (xy 78.972948 -295.698651)
			(xy 78.979776 -295.693846) (xy 79.001575 -295.677821) (xy 79.049295 -295.652333) (xy 79.100522 -295.634936)
			(xy 79.153894 -295.62609) (xy 79.180944 -295.62552) (xy 79.206759 -295.626011) (xy 79.257762 -295.634022)
			(xy 79.306903 -295.649857) (xy 79.352988 -295.673133) (xy 79.394898 -295.703284) (xy 79.431617 -295.739578)
			(xy 79.462252 -295.781136) (xy 79.474568 -295.803828) (xy 79.481172 -295.816528) (xy 79.505302 -295.83126)
			(xy 82.644996 -295.83126) (xy 82.668618 -295.817544) (xy 82.675476 -295.805606) (xy 82.688111 -295.784283)
			(xy 82.71919 -295.745676) (xy 82.756102 -295.712602) (xy 82.797874 -295.685929) (xy 82.843408 -295.666359)
			(xy 82.891507 -295.654407) (xy 82.940906 -295.650388) (xy 82.990305 -295.654407) (xy 83.038404 -295.666359)
			(xy 83.083938 -295.685929) (xy 83.12571 -295.712602) (xy 83.162622 -295.745676) (xy 83.193701 -295.784283)
			(xy 83.206336 -295.805606) (xy 83.213194 -295.817544) (xy 83.236816 -295.83126) (xy 83.556602 -295.83126)
			(xy 83.580732 -295.816528) (xy 83.587336 -295.803828) (xy 83.599682 -295.781155) (xy 83.630318 -295.739605)
			(xy 83.667034 -295.703317) (xy 83.70894 -295.67317) (xy 83.755018 -295.649895) (xy 83.804152 -295.634058)
			(xy 83.855149 -295.626042) (xy 83.906771 -295.626042) (xy 83.957768 -295.634058) (xy 84.006902 -295.649895)
			(xy 84.05298 -295.67317) (xy 84.094886 -295.703317) (xy 84.131602 -295.739605) (xy 84.162238 -295.781155)
			(xy 84.174584 -295.803828) (xy 84.181188 -295.816528) (xy 84.205318 -295.83126) (xy 84.525104 -295.83126)
			(xy 84.548726 -295.817544) (xy 84.555584 -295.805606) (xy 84.568219 -295.784283) (xy 84.599298 -295.745676)
			(xy 84.63621 -295.712602) (xy 84.677982 -295.685929) (xy 84.723516 -295.666359) (xy 84.771615 -295.654407)
			(xy 84.821014 -295.650388) (xy 84.870413 -295.654407) (xy 84.918512 -295.666359) (xy 84.964046 -295.685929)
			(xy 85.005818 -295.712602) (xy 85.04273 -295.745676) (xy 85.073809 -295.784283) (xy 85.086444 -295.805606)
			(xy 85.093302 -295.817544) (xy 85.116924 -295.83126) (xy 85.43671 -295.83126) (xy 85.46084 -295.816528)
			(xy 85.467444 -295.803828) (xy 85.47979 -295.781155) (xy 85.510426 -295.739605) (xy 85.547142 -295.703317)
			(xy 85.589048 -295.67317) (xy 85.635126 -295.649895) (xy 85.68426 -295.634058) (xy 85.735257 -295.626042)
			(xy 85.786879 -295.626042) (xy 85.837876 -295.634058) (xy 85.88701 -295.649895) (xy 85.933088 -295.67317)
			(xy 85.974994 -295.703317) (xy 86.01171 -295.739605) (xy 86.042346 -295.781155) (xy 86.054692 -295.803828)
			(xy 86.061296 -295.816528) (xy 86.085426 -295.83126) (xy 86.405212 -295.83126) (xy 86.428834 -295.817544)
			(xy 86.435692 -295.805606) (xy 86.448327 -295.784283) (xy 86.479406 -295.745676) (xy 86.516318 -295.712602)
			(xy 86.55809 -295.685929) (xy 86.603624 -295.666359) (xy 86.651723 -295.654407) (xy 86.701122 -295.650388)
			(xy 86.750521 -295.654407) (xy 86.79862 -295.666359) (xy 86.844154 -295.685929) (xy 86.885926 -295.712602)
			(xy 86.922838 -295.745676) (xy 86.953917 -295.784283) (xy 86.966552 -295.805606) (xy 86.97341 -295.817544)
			(xy 86.997032 -295.83126) (xy 88.256618 -295.83126) (xy 88.280748 -295.816528) (xy 88.287352 -295.803828)
			(xy 88.299698 -295.781155) (xy 88.330334 -295.739605) (xy 88.36705 -295.703317) (xy 88.408956 -295.67317)
			(xy 88.455034 -295.649895) (xy 88.504168 -295.634058) (xy 88.555165 -295.626042) (xy 88.606787 -295.626042)
			(xy 88.657784 -295.634058) (xy 88.706918 -295.649895) (xy 88.752996 -295.67317) (xy 88.794902 -295.703317)
			(xy 88.831618 -295.739605) (xy 88.862254 -295.781155) (xy 88.8746 -295.803828) (xy 88.881204 -295.816528)
			(xy 88.905334 -295.83126) (xy 89.22512 -295.83126) (xy 89.248742 -295.817544) (xy 89.2556 -295.805606)
			(xy 89.268235 -295.784283) (xy 89.299314 -295.745676) (xy 89.336226 -295.712602) (xy 89.377998 -295.685929)
			(xy 89.423532 -295.666359) (xy 89.471631 -295.654407) (xy 89.52103 -295.650388) (xy 89.570429 -295.654407)
			(xy 89.618528 -295.666359) (xy 89.664062 -295.685929) (xy 89.705834 -295.712602) (xy 89.742746 -295.745676)
			(xy 89.773825 -295.784283) (xy 89.78646 -295.805606) (xy 89.793318 -295.817544) (xy 89.81694 -295.83126)
			(xy 90.136726 -295.83126) (xy 90.160856 -295.816528) (xy 90.16746 -295.803828) (xy 90.179806 -295.781155)
			(xy 90.210442 -295.739605) (xy 90.247158 -295.703317) (xy 90.289064 -295.67317) (xy 90.335142 -295.649895)
			(xy 90.384276 -295.634058) (xy 90.435273 -295.626042) (xy 90.486895 -295.626042) (xy 90.537892 -295.634058)
			(xy 90.587026 -295.649895) (xy 90.633104 -295.67317) (xy 90.67501 -295.703317) (xy 90.711726 -295.739605)
			(xy 90.742362 -295.781155) (xy 90.754708 -295.803828) (xy 90.761312 -295.816528) (xy 90.785442 -295.83126)
			(xy 91.105228 -295.83126) (xy 91.12885 -295.817544) (xy 91.135708 -295.805606) (xy 91.148343 -295.784283)
			(xy 91.179422 -295.745676) (xy 91.216334 -295.712602) (xy 91.258106 -295.685929) (xy 91.30364 -295.666359)
			(xy 91.351739 -295.654407) (xy 91.401138 -295.650388) (xy 91.450537 -295.654407) (xy 91.498636 -295.666359)
			(xy 91.54417 -295.685929) (xy 91.585942 -295.712602) (xy 91.622854 -295.745676) (xy 91.653933 -295.784283)
			(xy 91.666568 -295.805606) (xy 91.673426 -295.817544) (xy 91.697048 -295.83126) (xy 92.01658 -295.83126)
			(xy 92.04071 -295.816528) (xy 92.047314 -295.803828) (xy 92.059659 -295.781153) (xy 92.090294 -295.739599)
			(xy 92.127009 -295.703306) (xy 92.168914 -295.673152) (xy 92.214993 -295.649871) (xy 92.264127 -295.634025)
			(xy 92.315125 -295.626001) (xy 92.340938 -295.62552) (xy 92.352876 -295.625774) (xy 92.3671 -295.626282)
			(xy 92.391484 -295.61282) (xy 92.552266 -295.33596) (xy 92.55252 -295.309036) (xy 92.545662 -295.297098)
			(xy 92.533138 -295.273944) (xy 92.515363 -295.224399) (xy 92.506349 -295.17254) (xy 92.505784 -295.146222)
			(xy 92.506251 -295.122255) (xy 92.513738 -295.074909) (xy 92.528533 -295.029315) (xy 92.550271 -294.986593)
			(xy 92.578418 -294.947793) (xy 92.612283 -294.913868) (xy 92.651033 -294.885653) (xy 92.693717 -294.863839)
			(xy 92.739285 -294.848965) (xy 92.786618 -294.841394) (xy 92.810584 -294.840914) (xy 92.824046 -294.840914)
			(xy 92.847414 -294.827452) (xy 93.02242 -294.525954) (xy 93.02242 -294.49903) (xy 93.015562 -294.487346)
			(xy 93.003016 -294.464154) (xy 92.98522 -294.414526) (xy 92.976212 -294.362578) (xy 92.975684 -294.336216)
			(xy 92.976151 -294.312249) (xy 92.98364 -294.264904) (xy 92.998435 -294.21931) (xy 93.020173 -294.176589)
			(xy 93.04832 -294.13779) (xy 93.082185 -294.103866) (xy 93.120935 -294.075651) (xy 93.163618 -294.053839)
			(xy 93.209186 -294.038964) (xy 93.256518 -294.031394) (xy 93.280484 -294.030908) (xy 93.293946 -294.030908)
			(xy 93.317314 -294.017446) (xy 93.478096 -293.740586) (xy 93.477588 -293.712646) (xy 93.470222 -293.700454)
			(xy 93.458445 -293.680747) (xy 93.439851 -293.638772) (xy 93.427242 -293.594628) (xy 93.420862 -293.549164)
			(xy 93.420438 -293.52621) (xy 93.42092 -293.500222) (xy 93.429051 -293.448884) (xy 93.445113 -293.399452)
			(xy 93.468711 -293.35314) (xy 93.499263 -293.311091) (xy 93.536019 -293.27434) (xy 93.578071 -293.243792)
			(xy 93.624385 -293.220199) (xy 93.67382 -293.204142) (xy 93.725157 -293.196018) (xy 93.751146 -293.195502)
			(xy 93.776961 -293.195993) (xy 93.827965 -293.204004) (xy 93.877106 -293.219839) (xy 93.923192 -293.243114)
			(xy 93.965103 -293.273264) (xy 94.001823 -293.309558) (xy 94.03246 -293.351115) (xy 94.04477 -293.37381)
			(xy 94.051374 -293.38651) (xy 94.075504 -293.401242) (xy 94.366588 -293.401242) (xy 94.390718 -293.38651)
			(xy 94.397322 -293.37381) (xy 94.409668 -293.351136) (xy 94.440304 -293.309585) (xy 94.47702 -293.273295)
			(xy 94.518926 -293.243144) (xy 94.565003 -293.219865) (xy 94.614137 -293.204022) (xy 94.665134 -293.195999)
			(xy 94.690946 -293.195502) (xy 94.702884 -293.195756) (xy 94.717108 -293.196264) (xy 94.741492 -293.182802)
			(xy 94.88805 -292.930326) (xy 94.887542 -292.90264) (xy 94.879922 -292.890448) (xy 94.868186 -292.870728)
			(xy 94.849668 -292.828741) (xy 94.837122 -292.784599) (xy 94.830788 -292.739149) (xy 94.830392 -292.716204)
			(xy 94.830875 -292.690215) (xy 94.839006 -292.638875) (xy 94.855067 -292.58944) (xy 94.878665 -292.543127)
			(xy 94.909217 -292.501075) (xy 94.945972 -292.46432) (xy 94.988023 -292.433767) (xy 95.034337 -292.410169)
			(xy 95.083772 -292.394106) (xy 95.135111 -292.385975) (xy 95.1611 -292.385496) (xy 95.173038 -292.38575)
			(xy 95.187262 -292.386258) (xy 95.211646 -292.372796) (xy 95.35795 -292.120574) (xy 95.357442 -292.092634)
			(xy 95.350076 -292.080696) (xy 95.338283 -292.060961) (xy 95.319668 -292.018925) (xy 95.307055 -291.974715)
			(xy 95.300688 -291.929185) (xy 95.300292 -291.906198) (xy 95.300802 -291.880211) (xy 95.308933 -291.828877)
			(xy 95.324994 -291.779446) (xy 95.34859 -291.733137) (xy 95.379139 -291.691089) (xy 95.415891 -291.654338)
			(xy 95.457939 -291.623789) (xy 95.504248 -291.600193) (xy 95.553679 -291.584132) (xy 95.605013 -291.576002)
			(xy 95.631 -291.57549) (xy 95.642938 -291.575744) (xy 95.657162 -291.576252) (xy 95.681546 -291.56279)
			(xy 95.828104 -291.310568) (xy 95.827596 -291.282628) (xy 95.82023 -291.270436) (xy 95.808448 -291.25073)
			(xy 95.789843 -291.208757) (xy 95.777223 -291.164613) (xy 95.770831 -291.119148) (xy 95.770446 -291.096192)
			(xy 95.770956 -291.070204) (xy 95.779087 -291.018868) (xy 95.795148 -290.969435) (xy 95.818744 -290.923124)
			(xy 95.849293 -290.881073) (xy 95.886044 -290.844318) (xy 95.928091 -290.813764) (xy 95.9744 -290.790163)
			(xy 96.023831 -290.774096) (xy 96.075166 -290.765959) (xy 96.101154 -290.765484) (xy 96.113092 -290.765738)
			(xy 96.127316 -290.766246) (xy 96.1517 -290.752784) (xy 96.298004 -290.500562) (xy 96.29775 -290.472876)
			(xy 96.29013 -290.460684) (xy 96.278336 -290.440949) (xy 96.25972 -290.398913) (xy 96.247107 -290.354704)
			(xy 96.24074 -290.309173) (xy 96.240346 -290.286186) (xy 96.240857 -290.260198) (xy 96.248989 -290.208863)
			(xy 96.26505 -290.159431) (xy 96.288646 -290.11312) (xy 96.319195 -290.07107) (xy 96.355946 -290.034316)
			(xy 96.397993 -290.003763) (xy 96.444301 -289.980162) (xy 96.493732 -289.964096) (xy 96.545066 -289.955959)
			(xy 96.571054 -289.955478) (xy 96.583246 -289.955732) (xy 96.59747 -289.95624) (xy 96.621854 -289.942778)
			(xy 96.767904 -289.69081) (xy 96.76765 -289.66287) (xy 96.76003 -289.650678) (xy 96.748236 -289.630943)
			(xy 96.729621 -289.588907) (xy 96.717009 -289.544697) (xy 96.710642 -289.499167) (xy 96.710246 -289.47618)
			(xy 96.710757 -289.450193) (xy 96.71889 -289.398858) (xy 96.734952 -289.349427) (xy 96.758548 -289.303117)
			(xy 96.789097 -289.261068) (xy 96.825848 -289.224314) (xy 96.867895 -289.193762) (xy 96.914203 -289.170162)
			(xy 96.963632 -289.154096) (xy 97.014967 -289.145959) (xy 97.040954 -289.145472) (xy 97.053146 -289.145726)
			(xy 97.06737 -289.146234) (xy 97.091754 -289.132772) (xy 97.238058 -288.88055) (xy 97.23755 -288.85261)
			(xy 97.230184 -288.840418) (xy 97.218404 -288.820712) (xy 97.199804 -288.778737) (xy 97.187188 -288.734594)
			(xy 97.1808 -288.689129) (xy 97.1804 -288.666174) (xy 97.180776 -288.643486) (xy 97.186979 -288.598537)
			(xy 97.199266 -288.554856) (xy 97.217407 -288.513265) (xy 97.228914 -288.493708) (xy 97.23628 -288.48177)
			(xy 97.236534 -288.45383) (xy 97.089214 -288.200084) (xy 97.06483 -288.186622) (xy 97.05086 -288.186876)
			(xy 97.040954 -288.18713) (xy 97.014969 -288.186617) (xy 96.963638 -288.178481) (xy 96.914213 -288.162416)
			(xy 96.867908 -288.138818) (xy 96.825864 -288.108268) (xy 96.789116 -288.071518) (xy 96.758569 -288.029472)
			(xy 96.734975 -287.983165) (xy 96.718913 -287.933738) (xy 96.710781 -287.882407) (xy 96.710246 -287.856422)
			(xy 96.710618 -287.833692) (xy 96.716846 -287.78866) (xy 96.729201 -287.744911) (xy 96.747449 -287.703274)
			(xy 96.759014 -287.683702) (xy 96.76638 -287.671764) (xy 96.766634 -287.643824) (xy 96.619314 -287.389824)
			(xy 96.59493 -287.376362) (xy 96.58096 -287.376616) (xy 96.571054 -287.37687) (xy 96.545072 -287.376357)
			(xy 96.493749 -287.368221) (xy 96.444331 -287.352158) (xy 96.398033 -287.328563) (xy 96.355996 -287.298016)
			(xy 96.319255 -287.261269) (xy 96.288713 -287.219228) (xy 96.265124 -287.172927) (xy 96.249068 -287.123506)
			(xy 96.24094 -287.072182) (xy 96.24094 -287.020218) (xy 96.249068 -286.968894) (xy 96.265124 -286.919473)
			(xy 96.288713 -286.873172) (xy 96.319255 -286.831131) (xy 96.355996 -286.794384) (xy 96.398033 -286.763837)
			(xy 96.444331 -286.740242) (xy 96.493749 -286.724179) (xy 96.545072 -286.716043) (xy 96.571054 -286.715454)
			(xy 96.583246 -286.715708) (xy 96.59747 -286.716216) (xy 96.621854 -286.702754) (xy 96.767904 -286.450786)
			(xy 96.767396 -286.422846) (xy 96.76003 -286.410908) (xy 96.748235 -286.391174) (xy 96.729615 -286.349138)
			(xy 96.716999 -286.304928) (xy 96.710629 -286.259397) (xy 96.710246 -286.23641) (xy 96.710755 -286.210421)
			(xy 96.718884 -286.159083) (xy 96.734943 -286.109648) (xy 96.758538 -286.063334) (xy 96.789087 -286.02128)
			(xy 96.825838 -285.984523) (xy 96.867886 -285.953967) (xy 96.914196 -285.930365) (xy 96.963628 -285.914297)
			(xy 97.014965 -285.906159) (xy 97.040954 -285.905702) (xy 97.052892 -285.905956) (xy 97.067116 -285.906464)
			(xy 97.0915 -285.893002) (xy 97.237804 -285.640526) (xy 97.23755 -285.61284) (xy 97.22993 -285.600648)
			(xy 97.218194 -285.580928) (xy 97.199675 -285.538941) (xy 97.187129 -285.494799) (xy 97.180795 -285.449349)
			(xy 97.1804 -285.426404) (xy 97.180774 -285.403716) (xy 97.186973 -285.358764) (xy 97.199257 -285.315082)
			(xy 97.217395 -285.273488) (xy 97.228914 -285.253938) (xy 97.23628 -285.242) (xy 97.236534 -285.21406)
			(xy 97.089214 -284.96006) (xy 97.06483 -284.946598) (xy 97.05086 -284.946852) (xy 97.040954 -284.947106)
			(xy 97.014969 -284.946593) (xy 96.96364 -284.938457) (xy 96.914216 -284.922392) (xy 96.867913 -284.898793)
			(xy 96.825871 -284.868243) (xy 96.789126 -284.831492) (xy 96.758582 -284.789446) (xy 96.73499 -284.743139)
			(xy 96.718932 -284.693713) (xy 96.710803 -284.642383) (xy 96.710246 -284.616398) (xy 96.71062 -284.593668)
			(xy 96.716851 -284.548638) (xy 96.729209 -284.50489) (xy 96.747458 -284.463255) (xy 96.759014 -284.443678)
			(xy 96.76638 -284.43174) (xy 96.766634 -284.4038) (xy 96.619568 -284.150054) (xy 96.595184 -284.136592)
			(xy 96.58096 -284.136846) (xy 96.571054 -284.1371) (xy 96.54507 -284.136587) (xy 96.493742 -284.128451)
			(xy 96.444319 -284.112386) (xy 96.398017 -284.088789) (xy 96.355976 -284.058239) (xy 96.319231 -284.021489)
			(xy 96.288687 -283.979444) (xy 96.265096 -283.933139) (xy 96.249038 -283.883713) (xy 96.240909 -283.832384)
			(xy 96.240909 -283.780416) (xy 96.249038 -283.729087) (xy 96.265096 -283.679661) (xy 96.288687 -283.633356)
			(xy 96.319231 -283.591311) (xy 96.355976 -283.554561) (xy 96.398017 -283.524011) (xy 96.444319 -283.500414)
			(xy 96.493742 -283.484349) (xy 96.54507 -283.476213) (xy 96.571054 -283.475684) (xy 96.582992 -283.475938)
			(xy 96.597216 -283.476446) (xy 96.6216 -283.462984) (xy 96.767904 -283.210762) (xy 96.767396 -283.182822)
			(xy 96.76003 -283.170884) (xy 96.748236 -283.151149) (xy 96.72962 -283.109113) (xy 96.717007 -283.064904)
			(xy 96.71064 -283.019373) (xy 96.710246 -282.996386) (xy 96.710757 -282.970398) (xy 96.718889 -282.919063)
			(xy 96.73495 -282.869631) (xy 96.758546 -282.82332) (xy 96.789095 -282.78127) (xy 96.825846 -282.744516)
			(xy 96.867893 -282.713963) (xy 96.914201 -282.690362) (xy 96.963632 -282.674296) (xy 97.014966 -282.666159)
			(xy 97.040954 -282.665678) (xy 97.052892 -282.665932) (xy 97.067116 -282.66644) (xy 97.0915 -282.652978)
			(xy 97.237804 -282.400502) (xy 97.23755 -282.372816) (xy 97.22993 -282.360624) (xy 97.218195 -282.340904)
			(xy 97.19968 -282.298916) (xy 97.187137 -282.254775) (xy 97.180806 -282.209324) (xy 97.1804 -282.18638)
			(xy 97.180775 -282.163692) (xy 97.186978 -282.118742) (xy 97.199265 -282.075062) (xy 97.217405 -282.033469)
			(xy 97.228914 -282.013914) (xy 97.23628 -282.001976) (xy 97.236534 -281.974036) (xy 97.089468 -281.720036)
			(xy 97.065084 -281.706574) (xy 97.05086 -281.706828) (xy 97.040954 -281.707082) (xy 97.014971 -281.706569)
			(xy 96.963646 -281.698433) (xy 96.914226 -281.68237) (xy 96.867926 -281.658773) (xy 96.825888 -281.628225)
			(xy 96.789145 -281.591477) (xy 96.758603 -281.549434) (xy 96.735013 -281.503132) (xy 96.718956 -281.453709)
			(xy 96.710827 -281.402383) (xy 96.710827 -281.350417) (xy 96.718956 -281.299091) (xy 96.735013 -281.249668)
			(xy 96.758603 -281.203366) (xy 96.789145 -281.161323) (xy 96.825888 -281.124575) (xy 96.867926 -281.094027)
			(xy 96.914226 -281.07043) (xy 96.963646 -281.054367) (xy 97.014971 -281.046231) (xy 97.040954 -281.045666)
			(xy 97.052892 -281.04592) (xy 97.067116 -281.046428) (xy 97.0915 -281.032966) (xy 97.238058 -280.780744)
			(xy 97.23755 -280.752804) (xy 97.230184 -280.740612) (xy 97.218404 -280.720906) (xy 97.199805 -280.678931)
			(xy 97.18719 -280.634787) (xy 97.180803 -280.589323) (xy 97.1804 -280.566368) (xy 97.180912 -280.540383)
			(xy 97.189047 -280.489053) (xy 97.20511 -280.439627) (xy 97.228708 -280.393322) (xy 97.259259 -280.351279)
			(xy 97.29601 -280.314533) (xy 97.338056 -280.283987) (xy 97.384364 -280.260395) (xy 97.433792 -280.244337)
			(xy 97.485123 -280.236209) (xy 97.511108 -280.23566) (xy 97.522792 -280.235914) (xy 97.537016 -280.236422)
			(xy 97.5614 -280.22296) (xy 97.707958 -279.970484) (xy 97.70745 -279.942798) (xy 97.69983 -279.930606)
			(xy 97.68809 -279.910887) (xy 97.669564 -279.868901) (xy 97.65701 -279.824759) (xy 97.650668 -279.779308)
			(xy 97.6503 -279.756362) (xy 97.6503 -279.747472) (xy 97.650808 -279.733502) (xy 97.637092 -279.709118)
			(xy 96.785176 -279.21966) (xy 96.757236 -279.220168) (xy 96.745298 -279.227534) (xy 96.725578 -279.239271)
			(xy 96.683591 -279.257792) (xy 96.63945 -279.270343) (xy 96.593999 -279.276683) (xy 96.571054 -279.277064)
			(xy 96.545073 -279.276551) (xy 96.493751 -279.268415) (xy 96.444333 -279.252353) (xy 96.398036 -279.228757)
			(xy 96.356 -279.198211) (xy 96.319259 -279.161465) (xy 96.288718 -279.119425) (xy 96.26513 -279.073125)
			(xy 96.249074 -279.023705) (xy 96.240946 -278.972381) (xy 96.240946 -278.920419) (xy 96.249074 -278.869095)
			(xy 96.26513 -278.819675) (xy 96.288718 -278.773375) (xy 96.319259 -278.731335) (xy 96.356 -278.694589)
			(xy 96.398036 -278.664043) (xy 96.444333 -278.640447) (xy 96.493751 -278.624385) (xy 96.545073 -278.616249)
			(xy 96.571054 -278.615648) (xy 96.582992 -278.615902) (xy 96.597216 -278.61641) (xy 96.6216 -278.602948)
			(xy 96.767904 -278.350726) (xy 96.767396 -278.322786) (xy 96.76003 -278.310848) (xy 96.748238 -278.291113)
			(xy 96.729627 -278.249076) (xy 96.717018 -278.204866) (xy 96.710656 -278.159336) (xy 96.710246 -278.13635)
			(xy 96.710725 -278.110357) (xy 96.71885 -278.05901) (xy 96.734907 -278.009565) (xy 96.758502 -277.963242)
			(xy 96.789052 -277.92118) (xy 96.825807 -277.884415) (xy 96.86786 -277.853852) (xy 96.914177 -277.830244)
			(xy 96.963616 -277.814173) (xy 97.014961 -277.806033) (xy 97.040954 -277.805642) (xy 97.052892 -277.805896)
			(xy 97.067116 -277.806404) (xy 97.0915 -277.792942) (xy 97.237804 -277.540466) (xy 97.23755 -277.51278)
			(xy 97.22993 -277.500588) (xy 97.218191 -277.480869) (xy 97.199668 -277.438882) (xy 97.187116 -277.394741)
			(xy 97.180777 -277.34929) (xy 97.1804 -277.326344) (xy 97.180778 -277.303657) (xy 97.186985 -277.258709)
			(xy 97.199276 -277.215031) (xy 97.217419 -277.173441) (xy 97.228914 -277.153878) (xy 97.23628 -277.14194)
			(xy 97.236534 -277.114) (xy 97.089214 -276.86) (xy 97.06483 -276.846538) (xy 97.05086 -276.846792)
			(xy 97.040954 -276.847046) (xy 97.014968 -276.846533) (xy 96.963637 -276.838397) (xy 96.91421 -276.822332)
			(xy 96.867904 -276.798735) (xy 96.825859 -276.768185) (xy 96.78911 -276.731435) (xy 96.758561 -276.689389)
			(xy 96.734964 -276.643082) (xy 96.718901 -276.593655) (xy 96.710766 -276.542324) (xy 96.710246 -276.516338)
			(xy 96.710617 -276.493607) (xy 96.716843 -276.448575) (xy 96.729196 -276.404825) (xy 96.747442 -276.363186)
			(xy 96.759014 -276.343618) (xy 96.76638 -276.33168) (xy 96.766634 -276.30374) (xy 96.619568 -276.049994)
			(xy 96.595184 -276.036532) (xy 96.58096 -276.036786) (xy 96.571054 -276.03704) (xy 96.545067 -276.036527)
			(xy 96.493733 -276.02839) (xy 96.444304 -276.012323) (xy 96.397996 -275.988723) (xy 96.35595 -275.958169)
			(xy 96.319201 -275.921415) (xy 96.288653 -275.879365) (xy 96.265059 -275.833054) (xy 96.248999 -275.783622)
			(xy 96.240869 -275.732287) (xy 96.240869 -275.680313) (xy 96.248999 -275.628978) (xy 96.265059 -275.579546)
			(xy 96.288653 -275.533235) (xy 96.319201 -275.491185) (xy 96.35595 -275.454431) (xy 96.397996 -275.423877)
			(xy 96.444304 -275.400277) (xy 96.493733 -275.38421) (xy 96.545067 -275.376073) (xy 96.571054 -275.375624)
			(xy 96.582992 -275.375878) (xy 96.597216 -275.376386) (xy 96.6216 -275.362924) (xy 96.767904 -275.110702)
			(xy 96.767396 -275.082762) (xy 96.76003 -275.070824) (xy 96.748234 -275.05109) (xy 96.729612 -275.009055)
			(xy 96.716994 -274.964845) (xy 96.710621 -274.919314) (xy 96.710246 -274.896326) (xy 96.710754 -274.870336)
			(xy 96.718881 -274.818996) (xy 96.734939 -274.769559) (xy 96.758532 -274.723242) (xy 96.789081 -274.681187)
			(xy 96.825832 -274.644428) (xy 96.867881 -274.61387) (xy 96.914192 -274.590266) (xy 96.963626 -274.574197)
			(xy 97.014964 -274.566059) (xy 97.040954 -274.565618) (xy 97.052892 -274.565872) (xy 97.067116 -274.56638)
			(xy 97.0915 -274.552918) (xy 97.237804 -274.300442) (xy 97.23755 -274.272756) (xy 97.22993 -274.260564)
			(xy 97.218193 -274.240844) (xy 97.199672 -274.198857) (xy 97.187124 -274.154716) (xy 97.180788 -274.109265)
			(xy 97.1804 -274.08632) (xy 97.180772 -274.063631) (xy 97.18697 -274.018679) (xy 97.199252 -273.974996)
			(xy 97.217388 -273.9334) (xy 97.228914 -273.913854) (xy 97.23628 -273.901916) (xy 97.236534 -273.873976)
			(xy 97.089214 -273.619976) (xy 97.06483 -273.606514) (xy 97.05086 -273.606768) (xy 97.040954 -273.607022)
			(xy 97.014969 -273.606509) (xy 96.963639 -273.598373) (xy 96.914214 -273.582308) (xy 96.86791 -273.55871)
			(xy 96.825867 -273.52816) (xy 96.78912 -273.491409) (xy 96.758573 -273.449363) (xy 96.73498 -273.403057)
			(xy 96.71892 -273.35363) (xy 96.710788 -273.302299) (xy 96.710246 -273.276314) (xy 96.710619 -273.253584)
			(xy 96.716848 -273.208553) (xy 96.729204 -273.164804) (xy 96.747452 -273.123168) (xy 96.759014 -273.103594)
			(xy 96.76638 -273.091656) (xy 96.766634 -273.063716) (xy 96.619568 -272.80997) (xy 96.595184 -272.796508)
			(xy 96.58096 -272.796762) (xy 96.571054 -272.797016) (xy 96.545069 -272.796503) (xy 96.493738 -272.788367)
			(xy 96.444313 -272.772301) (xy 96.398009 -272.748702) (xy 96.355966 -272.718151) (xy 96.319219 -272.681399)
			(xy 96.288674 -272.639352) (xy 96.265081 -272.593045) (xy 96.249023 -272.543617) (xy 96.240893 -272.492286)
			(xy 96.240893 -272.440314) (xy 96.249023 -272.388983) (xy 96.265081 -272.339555) (xy 96.288674 -272.293248)
			(xy 96.319219 -272.251201) (xy 96.355966 -272.214449) (xy 96.398009 -272.183898) (xy 96.444313 -272.160299)
			(xy 96.493738 -272.144233) (xy 96.545069 -272.136097) (xy 96.571054 -272.1356) (xy 96.582992 -272.135854)
			(xy 96.597216 -272.136362) (xy 96.6216 -272.1229) (xy 96.767904 -271.870678) (xy 96.767396 -271.842738)
			(xy 96.76003 -271.8308) (xy 96.748235 -271.811066) (xy 96.729617 -271.76903) (xy 96.717002 -271.72482)
			(xy 96.710632 -271.679289) (xy 96.710246 -271.656302) (xy 96.710755 -271.630313) (xy 96.718885 -271.578976)
			(xy 96.734946 -271.529542) (xy 96.758541 -271.483229) (xy 96.78909 -271.441177) (xy 96.82584 -271.404421)
			(xy 96.867888 -271.373866) (xy 96.914198 -271.350264) (xy 96.963629 -271.334197) (xy 97.014965 -271.326059)
			(xy 97.040954 -271.325594) (xy 97.052892 -271.325848) (xy 97.067116 -271.326356) (xy 97.0915 -271.312894)
			(xy 97.237804 -271.060418) (xy 97.23755 -271.032732) (xy 97.22993 -271.02054) (xy 97.218194 -271.00082)
			(xy 97.199677 -270.958832) (xy 97.187131 -270.914691) (xy 97.180798 -270.869241) (xy 97.1804 -270.846296)
			(xy 97.180774 -270.823608) (xy 97.186975 -270.778657) (xy 97.19926 -270.734975) (xy 97.217398 -270.693382)
			(xy 97.228914 -270.67383) (xy 97.23628 -270.661892) (xy 97.236534 -270.633952) (xy 97.089214 -270.379952)
			(xy 97.06483 -270.36649) (xy 97.05086 -270.366744) (xy 97.040954 -270.366998) (xy 97.014969 -270.366485)
			(xy 96.963641 -270.358349) (xy 96.914217 -270.342283) (xy 96.867915 -270.318685) (xy 96.825874 -270.288134)
			(xy 96.789129 -270.251383) (xy 96.758586 -270.209337) (xy 96.734995 -270.163031) (xy 96.718938 -270.113604)
			(xy 96.710811 -270.062275) (xy 96.710246 -270.03629) (xy 96.710621 -270.01356) (xy 96.716853 -269.968531)
			(xy 96.729211 -269.924784) (xy 96.747462 -269.883149) (xy 96.759014 -269.86357) (xy 96.76638 -269.851632)
			(xy 96.766634 -269.823692) (xy 96.619568 -269.569946) (xy 96.595184 -269.556484) (xy 96.58096 -269.556738)
			(xy 96.571054 -269.556992) (xy 96.54507 -269.556479) (xy 96.493742 -269.548343) (xy 96.444318 -269.532277)
			(xy 96.398016 -269.508679) (xy 96.355976 -269.478128) (xy 96.319232 -269.441377) (xy 96.288689 -269.399331)
			(xy 96.265099 -269.353024) (xy 96.249043 -269.303598) (xy 96.240916 -269.252268) (xy 96.240346 -269.226284)
			(xy 96.240806 -269.201569) (xy 96.24816 -269.15269) (xy 96.262702 -269.105448) (xy 96.284108 -269.060895)
			(xy 96.311903 -269.020021) (xy 96.345468 -268.983735) (xy 96.384056 -268.952845) (xy 96.405192 -268.940026)
			(xy 96.414336 -268.934946) (xy 96.426782 -268.918436) (xy 96.449134 -268.826996) (xy 96.445832 -268.806676)
			(xy 96.440244 -268.797786) (xy 96.419109 -268.763492) (xy 96.383853 -268.691058) (xy 96.357009 -268.615103)
			(xy 96.338921 -268.536601) (xy 96.329819 -268.456558) (xy 96.329246 -268.416278) (xy 96.329735 -268.379004)
			(xy 96.337529 -268.304866) (xy 96.353029 -268.231948) (xy 96.376067 -268.161049) (xy 96.406388 -268.092947)
			(xy 96.443662 -268.028387) (xy 96.487479 -267.968077) (xy 96.53736 -267.912677) (xy 96.592758 -267.862794)
			(xy 96.653067 -267.818975) (xy 96.717626 -267.781699) (xy 96.785727 -267.751375) (xy 96.856625 -267.728336)
			(xy 96.929542 -267.712833) (xy 97.00368 -267.705036) (xy 97.040954 -267.70457) (xy 97.05481 -267.704609)
			(xy 97.082504 -267.705625) (xy 97.096326 -267.706602) (xy 97.106994 -267.707618) (xy 97.126806 -267.70076)
			(xy 97.197418 -267.635482) (xy 97.2058 -267.616432) (xy 97.2058 -267.605764) (xy 97.206311 -267.581801)
			(xy 97.213883 -267.534474) (xy 97.228758 -267.488912) (xy 97.25057 -267.446235) (xy 97.278783 -267.40749)
			(xy 97.312704 -267.373629) (xy 97.351499 -267.345485) (xy 97.394215 -267.323749) (xy 97.439804 -267.308956)
			(xy 97.487144 -267.301467) (xy 97.511108 -267.300964) (xy 97.534117 -267.301383) (xy 97.579613 -267.308294)
			(xy 97.623555 -267.321959) (xy 97.664947 -267.342067) (xy 97.70285 -267.368163) (xy 97.736405 -267.399654)
			(xy 97.76485 -267.435827) (xy 97.776538 -267.45565) (xy 97.783396 -267.467588) (xy 97.807018 -267.481304)
			(xy 98.126804 -267.481304) (xy 98.150934 -267.466572) (xy 98.157538 -267.453872) (xy 98.169884 -267.431199)
			(xy 98.20052 -267.389649) (xy 98.237236 -267.353361) (xy 98.279142 -267.323214) (xy 98.32522 -267.299939)
			(xy 98.374354 -267.284102) (xy 98.425351 -267.276086) (xy 98.476973 -267.276086) (xy 98.52797 -267.284102)
			(xy 98.577104 -267.299939) (xy 98.623182 -267.323214) (xy 98.665088 -267.353361) (xy 98.701804 -267.389649)
			(xy 98.73244 -267.431199) (xy 98.744786 -267.453872) (xy 98.75139 -267.466572) (xy 98.77552 -267.481304)
			(xy 99.095052 -267.481304) (xy 99.118674 -267.467588) (xy 99.125532 -267.45565) (xy 99.139241 -267.432638)
			(xy 99.173403 -267.391386) (xy 99.214229 -267.356716) (xy 99.260471 -267.329688) (xy 99.310714 -267.31113)
			(xy 99.363422 -267.30161) (xy 99.3902 -267.300964) (xy 99.403916 -267.300964) (xy 99.427284 -267.287502)
			(xy 99.588066 -267.010388) (xy 99.587558 -266.982702) (xy 99.579938 -266.97051) (xy 99.568198 -266.950791)
			(xy 99.549671 -266.908805) (xy 99.537116 -266.864664) (xy 99.530773 -266.819212) (xy 99.530408 -266.796266)
			(xy 99.53092 -266.770281) (xy 99.539055 -266.718952) (xy 99.555119 -266.669527) (xy 99.578717 -266.623223)
			(xy 99.609268 -266.581181) (xy 99.646019 -266.544435) (xy 99.688066 -266.513891) (xy 99.734373 -266.4903)
			(xy 99.7838 -266.474243) (xy 99.835131 -266.466116) (xy 99.861116 -266.465558) (xy 99.873054 -266.465812)
			(xy 99.887278 -266.46632) (xy 99.911662 -266.452858) (xy 100.057966 -266.200636) (xy 100.057458 -266.172696)
			(xy 100.050092 -266.160758) (xy 100.038301 -266.141023) (xy 100.01969 -266.098986) (xy 100.007082 -266.054776)
			(xy 100.000719 -266.009246) (xy 100.000308 -265.98626) (xy 100.000821 -265.960275) (xy 100.008956 -265.908947)
			(xy 100.025021 -265.859522) (xy 100.048619 -265.81322) (xy 100.07917 -265.771178) (xy 100.115921 -265.734433)
			(xy 100.157967 -265.70389) (xy 100.204274 -265.680299) (xy 100.253701 -265.664243) (xy 100.305031 -265.656116)
			(xy 100.331016 -265.655552) (xy 100.354374 -265.65596) (xy 100.400626 -265.662536) (xy 100.445496 -265.675541)
			(xy 100.488095 -265.694719) (xy 100.508054 -265.70686) (xy 100.519992 -265.71448) (xy 100.548186 -265.715242)
			(xy 101.397308 -265.227562) (xy 101.411024 -265.20267) (xy 101.410516 -265.188446) (xy 101.410262 -265.176254)
			(xy 101.410262 -265.167364) (xy 101.41077 -265.153394) (xy 101.397054 -265.12901) (xy 100.545138 -264.639552)
			(xy 100.517198 -264.64006) (xy 100.50526 -264.647426) (xy 100.48554 -264.659161) (xy 100.443552 -264.677678)
			(xy 100.399411 -264.690224) (xy 100.353961 -264.696558) (xy 100.331016 -264.696956) (xy 100.305022 -264.696474)
			(xy 100.253674 -264.688344) (xy 100.20423 -264.67228) (xy 100.157908 -264.64868) (xy 100.115848 -264.618124)
			(xy 100.079087 -264.581364) (xy 100.048528 -264.539305) (xy 100.024926 -264.492984) (xy 100.00886 -264.443541)
			(xy 100.000727 -264.392194) (xy 100.000727 -264.340206) (xy 100.00886 -264.288859) (xy 100.024926 -264.239416)
			(xy 100.048528 -264.193095) (xy 100.079087 -264.151036) (xy 100.115848 -264.114276) (xy 100.157908 -264.08372)
			(xy 100.20423 -264.06012) (xy 100.253674 -264.044056) (xy 100.305022 -264.035926) (xy 100.331016 -264.03554)
			(xy 100.354374 -264.035948) (xy 100.400626 -264.042524) (xy 100.445496 -264.055529) (xy 100.488096 -264.074705)
			(xy 100.508054 -264.086848) (xy 100.519992 -264.094468) (xy 100.54844 -264.09523) (xy 101.397308 -263.60755)
			(xy 101.411024 -263.582912) (xy 101.410516 -263.568688) (xy 101.410262 -263.556242) (xy 101.41064 -263.533555)
			(xy 101.416847 -263.488607) (xy 101.429136 -263.444928) (xy 101.447278 -263.403338) (xy 101.458776 -263.383776)
			(xy 101.466142 -263.371838) (xy 101.466396 -263.343898) (xy 101.319076 -263.089898) (xy 101.294692 -263.076436)
			(xy 101.280722 -263.07669) (xy 101.27107 -263.076944) (xy 101.245082 -263.076432) (xy 101.193745 -263.068297)
			(xy 101.144313 -263.052232) (xy 101.098003 -263.028632) (xy 101.055954 -262.998078) (xy 101.019203 -262.961323)
			(xy 100.988653 -262.919272) (xy 100.965057 -262.872959) (xy 100.948996 -262.823526) (xy 100.940866 -262.772189)
			(xy 100.940866 -262.720211) (xy 100.948996 -262.668874) (xy 100.965057 -262.619441) (xy 100.988653 -262.573128)
			(xy 101.019203 -262.531077) (xy 101.055954 -262.494322) (xy 101.098003 -262.463768) (xy 101.144313 -262.440168)
			(xy 101.193745 -262.424103) (xy 101.245082 -262.415968) (xy 101.27107 -262.415528) (xy 101.2825 -262.415782)
			(xy 101.296724 -262.41629) (xy 101.321108 -262.402828) (xy 101.467666 -262.150098) (xy 101.467158 -262.122412)
			(xy 101.459792 -262.11022) (xy 101.448063 -262.090532) (xy 101.429555 -262.048609) (xy 101.417013 -262.004531)
			(xy 101.41068 -261.959144) (xy 101.410262 -261.93623) (xy 101.410652 -261.913574) (xy 101.416871 -261.86869)
			(xy 101.429155 -261.825074) (xy 101.447276 -261.783542) (xy 101.458776 -261.764018) (xy 101.465888 -261.75208)
			(xy 101.466396 -261.72414) (xy 101.318822 -261.469886) (xy 101.294438 -261.456424) (xy 101.280468 -261.456678)
			(xy 101.27107 -261.456932) (xy 101.245082 -261.45642) (xy 101.193748 -261.448285) (xy 101.144318 -261.43222)
			(xy 101.098009 -261.408621) (xy 101.055962 -261.378069) (xy 101.019212 -261.341315) (xy 100.988663 -261.299265)
			(xy 100.965068 -261.252954) (xy 100.949008 -261.203523) (xy 100.940877 -261.152188) (xy 100.940877 -261.100212)
			(xy 100.949008 -261.048877) (xy 100.965068 -260.999446) (xy 100.988663 -260.953135) (xy 101.019212 -260.911085)
			(xy 101.055962 -260.874331) (xy 101.098009 -260.843779) (xy 101.144318 -260.82018) (xy 101.193748 -260.804115)
			(xy 101.245082 -260.79598) (xy 101.27107 -260.795516) (xy 101.300949 -260.796156) (xy 101.359734 -260.806889)
			(xy 101.38791 -260.816852) (xy 101.401372 -260.821932) (xy 101.428804 -260.816852) (xy 102.497128 -259.875782)
			(xy 102.505256 -259.847842) (xy 102.500938 -259.833364) (xy 102.494065 -259.808138) (xy 102.486667 -259.756381)
			(xy 102.486206 -259.73024) (xy 102.486655 -259.704129) (xy 102.494013 -259.652428) (xy 102.508586 -259.602281)
			(xy 102.530083 -259.554689) (xy 102.558076 -259.510604) (xy 102.592005 -259.470906) (xy 102.631192 -259.436388)
			(xy 102.674855 -259.40774) (xy 102.698296 -259.39623) (xy 102.712012 -259.38988) (xy 102.72776 -259.365242)
			(xy 102.72776 -259.195316) (xy 102.712012 -259.170678) (xy 102.698296 -259.164328) (xy 102.673305 -259.15202)
			(xy 102.627023 -259.121016) (xy 102.585927 -259.083409) (xy 102.550949 -259.040053) (xy 102.522883 -258.991933)
			(xy 102.502368 -258.940142) (xy 102.489869 -258.885856) (xy 102.48567 -258.830308) (xy 102.489867 -258.77476)
			(xy 102.502364 -258.720473) (xy 102.522877 -258.668681) (xy 102.55094 -258.62056) (xy 102.585916 -258.577202)
			(xy 102.627011 -258.539593) (xy 102.673291 -258.508588) (xy 102.698296 -258.496308) (xy 102.712012 -258.489958)
			(xy 102.72776 -258.46532) (xy 102.72776 -258.295394) (xy 102.712012 -258.270756) (xy 102.698296 -258.264406)
			(xy 102.67486 -258.25289) (xy 102.631205 -258.224237) (xy 102.592025 -258.189716) (xy 102.558102 -258.150018)
			(xy 102.530113 -258.105934) (xy 102.508618 -258.058345) (xy 102.494045 -258.008202) (xy 102.486685 -257.956505)
			(xy 102.486206 -257.930396) (xy 102.486326 -257.915279) (xy 102.488742 -257.885141) (xy 102.491032 -257.870198)
			(xy 102.493572 -257.855466) (xy 102.482142 -257.828542) (xy 101.164898 -256.922524) (xy 101.136958 -256.921)
			(xy 101.124258 -256.927604) (xy 101.100478 -256.939433) (xy 101.05008 -256.956186) (xy 100.997651 -256.964663)
			(xy 100.971096 -256.965196) (xy 100.945107 -256.964713) (xy 100.89377 -256.956581) (xy 100.844337 -256.940518)
			(xy 100.798025 -256.91692) (xy 100.755975 -256.886367) (xy 100.719222 -256.849613) (xy 100.688672 -256.807561)
			(xy 100.665076 -256.761249) (xy 100.649015 -256.711815) (xy 100.640886 -256.660477) (xy 100.640388 -256.634488)
			(xy 100.64078 -256.611573) (xy 100.647117 -256.566185) (xy 100.659668 -256.522108) (xy 100.678192 -256.480189)
			(xy 100.689918 -256.460498) (xy 100.697284 -256.44856) (xy 100.697538 -256.42062) (xy 100.55098 -256.16789)
			(xy 100.526596 -256.154428) (xy 100.512626 -256.154936) (xy 100.500942 -256.15519) (xy 100.475305 -256.154703)
			(xy 100.424647 -256.14678) (xy 100.375819 -256.131133) (xy 100.329991 -256.108137) (xy 100.288261 -256.078344)
			(xy 100.25163 -256.042466) (xy 100.220976 -256.001364) (xy 100.208588 -255.978914) (xy 100.20173 -255.966214)
			(xy 100.177854 -255.951736) (xy 99.88423 -255.951736) (xy 99.860354 -255.966214) (xy 99.853496 -255.978914)
			(xy 99.841112 -256.00137) (xy 99.810477 -256.042494) (xy 99.773854 -256.07839) (xy 99.732124 -256.108194)
			(xy 99.686289 -256.131191) (xy 99.637451 -256.146828) (xy 99.586782 -256.154729) (xy 99.561142 -256.15519)
			(xy 99.547934 -256.154936) (xy 99.533456 -256.154428) (xy 99.509072 -256.167636) (xy 99.363276 -256.419096)
			(xy 99.363784 -256.446782) (xy 99.371404 -256.458974) (xy 99.383337 -256.478795) (xy 99.402154 -256.521062)
			(xy 99.414902 -256.565538) (xy 99.421333 -256.611355) (xy 99.421696 -256.634488) (xy 99.421186 -256.660475)
			(xy 99.413056 -256.71181) (xy 99.396995 -256.76124) (xy 99.373399 -256.80755) (xy 99.342849 -256.849598)
			(xy 99.306098 -256.886349) (xy 99.26405 -256.916899) (xy 99.21774 -256.940495) (xy 99.16831 -256.956556)
			(xy 99.116975 -256.964686) (xy 99.065001 -256.964686) (xy 99.013666 -256.956556) (xy 98.964236 -256.940495)
			(xy 98.917926 -256.916899) (xy 98.875878 -256.886349) (xy 98.839127 -256.849598) (xy 98.808577 -256.80755)
			(xy 98.784981 -256.76124) (xy 98.76892 -256.71181) (xy 98.76079 -256.660475) (xy 98.76028 -256.634488)
			(xy 98.760534 -256.622804) (xy 98.761042 -256.608326) (xy 98.74758 -256.583942) (xy 97.897696 -256.095754)
			(xy 97.869756 -256.096262) (xy 97.857818 -256.104136) (xy 97.837886 -256.116245) (xy 97.795341 -256.135352)
			(xy 97.750534 -256.148292) (xy 97.704353 -256.154808) (xy 97.681034 -256.15519) (xy 97.667826 -256.154936)
			(xy 97.653602 -256.154428) (xy 97.629218 -256.16789) (xy 97.483422 -256.418842) (xy 97.48393 -256.446782)
			(xy 97.49155 -256.458974) (xy 97.503482 -256.478796) (xy 97.522296 -256.521063) (xy 97.535042 -256.565538)
			(xy 97.541472 -256.611355) (xy 97.541842 -256.634488) (xy 97.541332 -256.660475) (xy 97.533202 -256.71181)
			(xy 97.517141 -256.76124) (xy 97.493545 -256.80755) (xy 97.462995 -256.849598) (xy 97.426244 -256.886349)
			(xy 97.384196 -256.916899) (xy 97.337886 -256.940495) (xy 97.288456 -256.956556) (xy 97.237121 -256.964686)
			(xy 97.185147 -256.964686) (xy 97.133812 -256.956556) (xy 97.084382 -256.940495) (xy 97.038072 -256.916899)
			(xy 96.996024 -256.886349) (xy 96.959273 -256.849598) (xy 96.928723 -256.80755) (xy 96.905127 -256.76124)
			(xy 96.889066 -256.71181) (xy 96.880936 -256.660475) (xy 96.880426 -256.634488) (xy 96.88068 -256.622804)
			(xy 96.881188 -256.608326) (xy 96.867726 -256.583942) (xy 96.017588 -256.095754) (xy 95.989902 -256.096262)
			(xy 95.97771 -256.104136) (xy 95.957778 -256.116245) (xy 95.915233 -256.135351) (xy 95.870426 -256.148289)
			(xy 95.824245 -256.154804) (xy 95.800926 -256.15519) (xy 95.787718 -256.154936) (xy 95.773494 -256.154428)
			(xy 95.74911 -256.16789) (xy 95.588836 -256.443734) (xy 95.588836 -256.470404) (xy 95.595694 -256.482342)
			(xy 95.608443 -256.505654) (xy 95.626559 -256.555597) (xy 95.635748 -256.607924) (xy 95.636334 -256.634488)
			(xy 95.635864 -256.658481) (xy 95.62836 -256.705875) (xy 95.613534 -256.751513) (xy 95.591751 -256.794269)
			(xy 95.563549 -256.833091) (xy 95.52962 -256.867024) (xy 95.490801 -256.895231) (xy 95.448048 -256.917019)
			(xy 95.402412 -256.931851) (xy 95.355019 -256.939361) (xy 95.331026 -256.939796) (xy 95.304399 -256.939211)
			(xy 95.251955 -256.929959) (xy 95.201912 -256.911748) (xy 95.155787 -256.885132) (xy 95.114979 -256.850916)
			(xy 95.080727 -256.810139) (xy 95.066866 -256.787396) (xy 95.060008 -256.775458) (xy 95.03664 -256.761996)
			(xy 94.713806 -256.761996) (xy 94.68993 -256.776474) (xy 94.683326 -256.789174) (xy 94.670916 -256.811601)
			(xy 94.640244 -256.852665) (xy 94.603605 -256.888505) (xy 94.561875 -256.918265) (xy 94.516055 -256.941232)
			(xy 94.46724 -256.956855) (xy 94.416599 -256.964762) (xy 94.365345 -256.964762) (xy 94.314704 -256.956855)
			(xy 94.265889 -256.941232) (xy 94.220069 -256.918265) (xy 94.178339 -256.888505) (xy 94.1417 -256.852665)
			(xy 94.111028 -256.811601) (xy 94.098618 -256.789174) (xy 94.092014 -256.776474) (xy 94.068138 -256.761996)
			(xy 93.773752 -256.761996) (xy 93.749876 -256.776474) (xy 93.743272 -256.789174) (xy 93.730862 -256.811601)
			(xy 93.70019 -256.852665) (xy 93.663551 -256.888505) (xy 93.621821 -256.918265) (xy 93.576001 -256.941232)
			(xy 93.527186 -256.956855) (xy 93.476545 -256.964762) (xy 93.425291 -256.964762) (xy 93.37465 -256.956855)
			(xy 93.325835 -256.941232) (xy 93.280015 -256.918265) (xy 93.238285 -256.888505) (xy 93.201646 -256.852665)
			(xy 93.170974 -256.811601) (xy 93.158564 -256.789174) (xy 93.15196 -256.776474) (xy 93.128084 -256.761996)
			(xy 92.805504 -256.761996) (xy 92.782136 -256.775458) (xy 92.775278 -256.787396) (xy 92.762552 -256.808431)
			(xy 92.731447 -256.846501) (xy 92.69464 -256.879091) (xy 92.653084 -256.905357) (xy 92.607854 -256.924619)
			(xy 92.56012 -256.93638) (xy 92.511118 -256.940334) (xy 92.462116 -256.93638) (xy 92.414382 -256.924619)
			(xy 92.369152 -256.905357) (xy 92.327596 -256.879091) (xy 92.290789 -256.846501) (xy 92.259684 -256.808431)
			(xy 92.246958 -256.787396) (xy 92.2401 -256.775458) (xy 92.216732 -256.761996) (xy 91.893898 -256.761996)
			(xy 91.870022 -256.776474) (xy 91.863418 -256.789174) (xy 91.851008 -256.811601) (xy 91.820336 -256.852665)
			(xy 91.783697 -256.888505) (xy 91.741967 -256.918265) (xy 91.696147 -256.941232) (xy 91.647332 -256.956855)
			(xy 91.596691 -256.964762) (xy 91.545437 -256.964762) (xy 91.494796 -256.956855) (xy 91.445981 -256.941232)
			(xy 91.400161 -256.918265) (xy 91.358431 -256.888505) (xy 91.321792 -256.852665) (xy 91.29112 -256.811601)
			(xy 91.27871 -256.789174) (xy 91.272106 -256.776474) (xy 91.24823 -256.761996) (xy 90.953844 -256.761996)
			(xy 90.929968 -256.776474) (xy 90.923364 -256.789174) (xy 90.910954 -256.811601) (xy 90.880282 -256.852665)
			(xy 90.843643 -256.888505) (xy 90.801913 -256.918265) (xy 90.756093 -256.941232) (xy 90.707278 -256.956855)
			(xy 90.656637 -256.964762) (xy 90.605383 -256.964762) (xy 90.554742 -256.956855) (xy 90.505927 -256.941232)
			(xy 90.460107 -256.918265) (xy 90.418377 -256.888505) (xy 90.381738 -256.852665) (xy 90.351066 -256.811601)
			(xy 90.338656 -256.789174) (xy 90.332052 -256.776474) (xy 90.308176 -256.761996) (xy 90.01379 -256.761996)
			(xy 89.989914 -256.776474) (xy 89.98331 -256.789174) (xy 89.9709 -256.811601) (xy 89.940228 -256.852665)
			(xy 89.903589 -256.888505) (xy 89.861859 -256.918265) (xy 89.816039 -256.941232) (xy 89.767224 -256.956855)
			(xy 89.716583 -256.964762) (xy 89.665329 -256.964762) (xy 89.614688 -256.956855) (xy 89.565873 -256.941232)
			(xy 89.520053 -256.918265) (xy 89.478323 -256.888505) (xy 89.441684 -256.852665) (xy 89.411012 -256.811601)
			(xy 89.398602 -256.789174) (xy 89.391998 -256.776474) (xy 89.368122 -256.761996) (xy 88.942672 -256.761996)
			(xy 88.932707 -256.761517) (xy 88.914273 -256.753938) (xy 88.906858 -256.747264) (xy 88.321896 -256.162302)
			(xy 88.302338 -256.154682) (xy 88.291924 -256.154936) (xy 88.281002 -256.15519) (xy 88.255013 -256.154707)
			(xy 88.203675 -256.146576) (xy 88.154242 -256.130514) (xy 88.10793 -256.106916) (xy 88.065879 -256.076363)
			(xy 88.029126 -256.039609) (xy 87.998576 -255.997557) (xy 87.97498 -255.951243) (xy 87.95892 -255.901809)
			(xy 87.950792 -255.850471) (xy 87.950294 -255.824482) (xy 87.950548 -255.81356) (xy 87.950802 -255.803146)
			(xy 87.943182 -255.783588) (xy 87.39124 -255.231646) (xy 87.384544 -255.224241) (xy 87.376939 -255.205804)
			(xy 87.376508 -255.195832) (xy 87.376508 -227.29317) (xy 87.37608 -227.283102) (xy 87.368359 -227.264505)
			(xy 87.361522 -227.257102) (xy 86.908894 -226.804474) (xy 86.901499 -226.797621) (xy 86.8829 -226.789877)
			(xy 86.872826 -226.789488) (xy 86.725252 -226.789488) (xy 86.701122 -226.80422) (xy 86.694518 -226.81692)
			(xy 86.6822 -226.839594) (xy 86.651614 -226.881151) (xy 86.614941 -226.917449) (xy 86.573073 -226.947607)
			(xy 86.527026 -226.97089) (xy 86.477919 -226.986734) (xy 86.426947 -226.994754) (xy 86.375349 -226.994754)
			(xy 86.324377 -226.986734) (xy 86.27527 -226.97089) (xy 86.229223 -226.947607) (xy 86.187355 -226.917449)
			(xy 86.150682 -226.881151) (xy 86.120096 -226.839594) (xy 86.107778 -226.81692) (xy 86.101174 -226.80422)
			(xy 86.077044 -226.789488) (xy 85.785198 -226.789488) (xy 85.761068 -226.80422) (xy 85.754464 -226.81692)
			(xy 85.742146 -226.839594) (xy 85.71156 -226.881151) (xy 85.674887 -226.917449) (xy 85.633019 -226.947607)
			(xy 85.586972 -226.97089) (xy 85.537865 -226.986734) (xy 85.486893 -226.994754) (xy 85.435295 -226.994754)
			(xy 85.384323 -226.986734) (xy 85.335216 -226.97089) (xy 85.289169 -226.947607) (xy 85.247301 -226.917449)
			(xy 85.210628 -226.881151) (xy 85.180042 -226.839594) (xy 85.167724 -226.81692) (xy 85.16112 -226.80422)
			(xy 85.13699 -226.789488) (xy 84.845144 -226.789488) (xy 84.821014 -226.80422) (xy 84.81441 -226.81692)
			(xy 84.802092 -226.839594) (xy 84.771506 -226.881151) (xy 84.734833 -226.917449) (xy 84.692965 -226.947607)
			(xy 84.646918 -226.97089) (xy 84.597811 -226.986734) (xy 84.546839 -226.994754) (xy 84.495241 -226.994754)
			(xy 84.444269 -226.986734) (xy 84.395162 -226.97089) (xy 84.349115 -226.947607) (xy 84.307247 -226.917449)
			(xy 84.270574 -226.881151) (xy 84.239988 -226.839594) (xy 84.22767 -226.81692) (xy 84.221066 -226.80422)
			(xy 84.196936 -226.789488) (xy 83.90509 -226.789488) (xy 83.88096 -226.80422) (xy 83.874356 -226.81692)
			(xy 83.862038 -226.839594) (xy 83.831452 -226.881151) (xy 83.794779 -226.917449) (xy 83.752911 -226.947607)
			(xy 83.706864 -226.97089) (xy 83.657757 -226.986734) (xy 83.606785 -226.994754) (xy 83.555187 -226.994754)
			(xy 83.504215 -226.986734) (xy 83.455108 -226.97089) (xy 83.409061 -226.947607) (xy 83.367193 -226.917449)
			(xy 83.33052 -226.881151) (xy 83.299934 -226.839594) (xy 83.287616 -226.81692) (xy 83.281012 -226.80422)
			(xy 83.256882 -226.789488) (xy 82.965036 -226.789488) (xy 82.940906 -226.80422) (xy 82.934302 -226.81692)
			(xy 82.921984 -226.839594) (xy 82.891398 -226.881151) (xy 82.854725 -226.917449) (xy 82.812857 -226.947607)
			(xy 82.76681 -226.97089) (xy 82.717703 -226.986734) (xy 82.666731 -226.994754) (xy 82.615133 -226.994754)
			(xy 82.564161 -226.986734) (xy 82.515054 -226.97089) (xy 82.469007 -226.947607) (xy 82.427139 -226.917449)
			(xy 82.390466 -226.881151) (xy 82.35988 -226.839594) (xy 82.347562 -226.81692) (xy 82.340958 -226.80422)
			(xy 82.316828 -226.789488) (xy 82.025236 -226.789488) (xy 82.001106 -226.80422) (xy 81.994502 -226.81692)
			(xy 81.982184 -226.839594) (xy 81.951598 -226.881151) (xy 81.914925 -226.917449) (xy 81.873057 -226.947607)
			(xy 81.82701 -226.97089) (xy 81.777903 -226.986734) (xy 81.726931 -226.994754) (xy 81.675333 -226.994754)
			(xy 81.624361 -226.986734) (xy 81.575254 -226.97089) (xy 81.529207 -226.947607) (xy 81.487339 -226.917449)
			(xy 81.450666 -226.881151) (xy 81.42008 -226.839594) (xy 81.407762 -226.81692) (xy 81.401158 -226.80422)
			(xy 81.377028 -226.789488) (xy 81.085182 -226.789488) (xy 81.061052 -226.80422) (xy 81.054448 -226.81692)
			(xy 81.04213 -226.839594) (xy 81.011544 -226.881151) (xy 80.974871 -226.917449) (xy 80.933003 -226.947607)
			(xy 80.886956 -226.97089) (xy 80.837849 -226.986734) (xy 80.786877 -226.994754) (xy 80.735279 -226.994754)
			(xy 80.684307 -226.986734) (xy 80.6352 -226.97089) (xy 80.589153 -226.947607) (xy 80.547285 -226.917449)
			(xy 80.510612 -226.881151) (xy 80.480026 -226.839594) (xy 80.467708 -226.81692) (xy 80.461104 -226.80422)
			(xy 80.436974 -226.789488) (xy 80.145128 -226.789488) (xy 80.120998 -226.80422) (xy 80.114394 -226.81692)
			(xy 80.102076 -226.839592) (xy 80.071489 -226.881145) (xy 80.034815 -226.917437) (xy 79.992946 -226.947588)
			(xy 79.946898 -226.970863) (xy 79.897792 -226.986698) (xy 79.846822 -226.994706) (xy 79.821024 -226.995228)
			(xy 79.79393 -226.994663) (xy 79.740473 -226.98579) (xy 79.689175 -226.968326) (xy 79.641408 -226.942738)
			(xy 79.619602 -226.926648) (xy 79.612763 -226.921864) (xy 79.596954 -226.916542) (xy 79.588614 -226.916234)
			(xy 77.233526 -226.916234) (xy 77.225181 -226.916523) (xy 77.209362 -226.921836) (xy 77.202538 -226.926648)
			(xy 77.180732 -226.942739) (xy 77.132969 -226.968334) (xy 77.08167 -226.985794) (xy 77.02821 -226.994653)
			(xy 77.001116 -226.995228) (xy 76.974022 -226.994663) (xy 76.920565 -226.985788) (xy 76.869269 -226.968324)
			(xy 76.821502 -226.942735) (xy 76.799694 -226.926648) (xy 76.792854 -226.921865) (xy 76.777046 -226.916546)
			(xy 76.768706 -226.916234) (xy 23.761954 -226.916234) (xy 23.751888 -226.916666) (xy 23.733299 -226.924396)
			(xy 23.725886 -226.93122) (xy 23.423372 -227.233734) (xy 23.416523 -227.241131) (xy 23.40879 -227.25973)
			(xy 23.408386 -227.269802) (xy 23.408386 -243.86032) (xy 23.408633 -243.867501) (xy 23.41263 -243.881297)
			(xy 23.41626 -243.887498) (xy 23.429886 -243.909785) (xy 23.451412 -243.957382) (xy 23.466021 -244.007535)
			(xy 23.473424 -244.059246) (xy 23.473918 -244.085364) (xy 23.47347 -244.111487) (xy 23.466098 -244.16321)
			(xy 23.451484 -244.21337) (xy 23.42992 -244.260959) (xy 23.41626 -244.28323) (xy 23.412622 -244.289428)
			(xy 23.408617 -244.303225) (xy 23.408386 -244.310408) (xy 23.408386 -258.880356) (xy 67.312036 -258.880356)
			(xy 67.316066 -258.738021) (xy 67.328141 -258.596141) (xy 67.348224 -258.455173) (xy 67.376251 -258.315566)
			(xy 67.412131 -258.177768) (xy 67.455749 -258.042221) (xy 67.506966 -257.909359) (xy 67.565617 -257.779607)
			(xy 67.631515 -257.653381) (xy 67.704449 -257.531085) (xy 67.784186 -257.413112) (xy 67.870468 -257.299839)
			(xy 67.963021 -257.191628) (xy 68.061548 -257.088827) (xy 68.165733 -256.991765) (xy 68.275242 -256.900753)
			(xy 68.389725 -256.816081) (xy 68.508815 -256.738023) (xy 68.63213 -256.666827) (xy 68.759276 -256.602721)
			(xy 68.889845 -256.545912) (xy 69.023419 -256.49658) (xy 69.15957 -256.454884) (xy 69.297861 -256.420958)
			(xy 69.437851 -256.39491) (xy 69.57909 -256.376824) (xy 69.721126 -256.366757) (xy 69.863504 -256.364742)
			(xy 70.005768 -256.370785) (xy 70.147462 -256.384867) (xy 70.288132 -256.406943) (xy 70.427329 -256.436943)
			(xy 70.564605 -256.474769) (xy 70.699521 -256.520301) (xy 70.831645 -256.573392) (xy 70.960554 -256.633874)
			(xy 71.085835 -256.701552) (xy 71.207086 -256.776209) (xy 71.323919 -256.857607) (xy 71.43596 -256.945484)
			(xy 71.54285 -257.039559) (xy 71.644247 -257.139531) (xy 71.739825 -257.245079) (xy 71.829279 -257.355865)
			(xy 71.912321 -257.471534) (xy 71.988687 -257.591717) (xy 72.058131 -257.716027) (xy 72.120431 -257.844068)
			(xy 72.175387 -257.975427) (xy 72.222824 -258.109686) (xy 72.262588 -258.246413) (xy 72.294554 -258.385171)
			(xy 72.318619 -258.525515) (xy 72.334705 -258.666996) (xy 72.34276 -258.80916) (xy 72.343264 -258.880356)
			(xy 72.34276 -258.951552) (xy 72.334705 -259.093716) (xy 72.318619 -259.235197) (xy 72.294554 -259.375541)
			(xy 72.262588 -259.514299) (xy 72.222824 -259.651026) (xy 72.175387 -259.785285) (xy 72.120431 -259.916644)
			(xy 72.058131 -260.044685) (xy 71.988687 -260.168995) (xy 71.912321 -260.289178) (xy 71.829279 -260.404847)
			(xy 71.739825 -260.515633) (xy 71.644247 -260.621181) (xy 71.54285 -260.721153) (xy 71.43596 -260.815228)
			(xy 71.323919 -260.903105) (xy 71.207086 -260.984503) (xy 71.085835 -261.05916) (xy 70.960554 -261.126838)
			(xy 70.831645 -261.18732) (xy 70.699521 -261.240411) (xy 70.564605 -261.285943) (xy 70.427329 -261.323769)
			(xy 70.288132 -261.353769) (xy 70.147462 -261.375845) (xy 70.005768 -261.389927) (xy 69.863504 -261.39597)
			(xy 69.721126 -261.393955) (xy 69.57909 -261.383888) (xy 69.437851 -261.365802) (xy 69.297861 -261.339754)
			(xy 69.15957 -261.305828) (xy 69.023419 -261.264132) (xy 68.889845 -261.2148) (xy 68.759276 -261.157991)
			(xy 68.63213 -261.093885) (xy 68.508815 -261.022689) (xy 68.389725 -260.944631) (xy 68.275242 -260.859959)
			(xy 68.165733 -260.768947) (xy 68.061548 -260.671885) (xy 67.963021 -260.569084) (xy 67.870468 -260.460873)
			(xy 67.784186 -260.3476) (xy 67.704449 -260.229627) (xy 67.631515 -260.107331) (xy 67.565617 -259.981105)
			(xy 67.506966 -259.851353) (xy 67.455749 -259.718491) (xy 67.412131 -259.582944) (xy 67.376251 -259.445146)
			(xy 67.348224 -259.305539) (xy 67.328141 -259.164571) (xy 67.316066 -259.022691) (xy 67.312036 -258.880356)
			(xy 23.408386 -258.880356) (xy 23.408386 -334.814926) (xy 23.408813 -334.824994) (xy 23.416533 -334.843593)
			(xy 23.423372 -334.850994) (xy 23.790656 -335.218278) (xy 23.798057 -335.225118) (xy 23.816655 -335.232835)
			(xy 23.826724 -335.233264)
		)
		(stroke
			(width 0)
			(type solid)
		)
		(fill yes)
		(layer "In9.Cu")
		(net "PVDDIO_P1")
	)
	(gr_poly
		(pts
			(xy 19.971258 -195.376546) (xy 19.980677 -195.3761) (xy 19.998256 -195.369319) (xy 20.005548 -195.363338)
			(xy 20.035661 -195.336615) (xy 20.100566 -195.288972) (xy 20.170128 -195.248431) (xy 20.243574 -195.215442)
			(xy 20.320086 -195.190375) (xy 20.398813 -195.173506) (xy 20.478879 -195.165025) (xy 20.559393 -195.165025)
			(xy 20.639459 -195.173506) (xy 20.718186 -195.190375) (xy 20.794698 -195.215442) (xy 20.868144 -195.248431)
			(xy 20.937706 -195.288972) (xy 21.002611 -195.336615) (xy 21.032724 -195.363338) (xy 21.039948 -195.369431)
			(xy 21.057569 -195.376226) (xy 21.067014 -195.376546) (xy 22.125432 -195.376546) (xy 22.135421 -195.376152)
			(xy 22.153885 -195.368528) (xy 22.167993 -195.354387) (xy 22.172168 -195.345304) (xy 22.187424 -195.310196)
			(xy 22.224088 -195.242995) (xy 22.267407 -195.179877) (xy 22.316929 -195.121501) (xy 22.37214 -195.068472)
			(xy 22.432465 -195.021342) (xy 22.497277 -194.980602) (xy 22.565901 -194.946675) (xy 22.637624 -194.919914)
			(xy 22.711699 -194.900598) (xy 22.787357 -194.888927) (xy 22.86381 -194.885024) (xy 22.940263 -194.888927)
			(xy 23.015921 -194.900598) (xy 23.089996 -194.919914) (xy 23.161719 -194.946675) (xy 23.230343 -194.980602)
			(xy 23.295155 -195.021342) (xy 23.35548 -195.068472) (xy 23.410691 -195.121501) (xy 23.460213 -195.179877)
			(xy 23.503532 -195.242995) (xy 23.540196 -195.310196) (xy 23.555452 -195.345304) (xy 23.559749 -195.354298)
			(xy 23.573854 -195.368353) (xy 23.592235 -195.376014) (xy 23.602188 -195.376546) (xy 27.515312 -195.376546)
			(xy 27.524735 -195.376108) (xy 27.542324 -195.369338) (xy 27.549602 -195.363338) (xy 27.579715 -195.336615)
			(xy 27.64462 -195.288972) (xy 27.714182 -195.248431) (xy 27.787628 -195.215442) (xy 27.86414 -195.190375)
			(xy 27.942867 -195.173506) (xy 28.022933 -195.165025) (xy 28.103447 -195.165025) (xy 28.183513 -195.173506)
			(xy 28.26224 -195.190375) (xy 28.338752 -195.215442) (xy 28.412198 -195.248431) (xy 28.48176 -195.288972)
			(xy 28.546665 -195.336615) (xy 28.576778 -195.363338) (xy 28.584005 -195.369423) (xy 28.601626 -195.376198)
			(xy 28.611068 -195.376546) (xy 29.669486 -195.376546) (xy 29.679469 -195.376143) (xy 29.697916 -195.368507)
			(xy 29.712008 -195.354365) (xy 29.716222 -195.345304) (xy 29.731478 -195.310196) (xy 29.768142 -195.242995)
			(xy 29.811461 -195.179877) (xy 29.860983 -195.121501) (xy 29.916194 -195.068472) (xy 29.976519 -195.021342)
			(xy 30.041331 -194.980602) (xy 30.109955 -194.946675) (xy 30.181678 -194.919914) (xy 30.255753 -194.900598)
			(xy 30.331411 -194.888927) (xy 30.407864 -194.885024) (xy 30.484317 -194.888927) (xy 30.559975 -194.900598)
			(xy 30.63405 -194.919914) (xy 30.705773 -194.946675) (xy 30.774397 -194.980602) (xy 30.839209 -195.021342)
			(xy 30.899534 -195.068472) (xy 30.954745 -195.121501) (xy 31.004267 -195.179877) (xy 31.047586 -195.242995)
			(xy 31.08425 -195.310196) (xy 31.099506 -195.345304) (xy 31.1038 -195.354303) (xy 31.117903 -195.368371)
			(xy 31.136285 -195.376047) (xy 31.146242 -195.376546) (xy 35.049714 -195.376546) (xy 35.060134 -195.376033)
			(xy 35.079265 -195.367764) (xy 35.086798 -195.360544) (xy 35.113781 -195.33274) (xy 35.172485 -195.282167)
			(xy 35.236014 -195.237808) (xy 35.303715 -195.20012) (xy 35.374889 -195.169493) (xy 35.448802 -195.146242)
			(xy 35.524692 -195.130607) (xy 35.601776 -195.122749) (xy 35.67926 -195.122749) (xy 35.756344 -195.130607)
			(xy 35.832234 -195.146242) (xy 35.906147 -195.169493) (xy 35.977321 -195.20012) (xy 36.045022 -195.237808)
			(xy 36.108551 -195.282167) (xy 36.167255 -195.33274) (xy 36.194238 -195.360544) (xy 36.201741 -195.367803)
			(xy 36.220893 -195.376053) (xy 36.231322 -195.376546) (xy 37.213286 -195.376546) (xy 37.223269 -195.376143)
			(xy 37.241716 -195.368507) (xy 37.255808 -195.354365) (xy 37.260022 -195.345304) (xy 37.275278 -195.310196)
			(xy 37.311942 -195.242995) (xy 37.355261 -195.179877) (xy 37.404783 -195.121501) (xy 37.459994 -195.068472)
			(xy 37.520319 -195.021342) (xy 37.585131 -194.980602) (xy 37.653755 -194.946675) (xy 37.725478 -194.919914)
			(xy 37.799553 -194.900598) (xy 37.875211 -194.888927) (xy 37.951664 -194.885024) (xy 38.028117 -194.888927)
			(xy 38.103775 -194.900598) (xy 38.17785 -194.919914) (xy 38.249573 -194.946675) (xy 38.318197 -194.980602)
			(xy 38.383009 -195.021342) (xy 38.443334 -195.068472) (xy 38.498545 -195.121501) (xy 38.548067 -195.179877)
			(xy 38.591386 -195.242995) (xy 38.62805 -195.310196) (xy 38.643306 -195.345304) (xy 38.6476 -195.354303)
			(xy 38.661703 -195.368371) (xy 38.680085 -195.376047) (xy 38.690042 -195.376546) (xy 40.502586 -195.376546)
			(xy 40.512599 -195.376061) (xy 40.531103 -195.368406) (xy 40.545272 -195.354254) (xy 40.552949 -195.335758)
			(xy 40.553386 -195.325746) (xy 40.553386 -187.090304) (xy 40.553185 -187.083865) (xy 40.549985 -187.071392)
			(xy 40.547036 -187.065666) (xy 40.52714 -187.028904) (xy 40.492889 -186.952646) (xy 40.465182 -186.873774)
			(xy 40.444216 -186.792849) (xy 40.430139 -186.710446) (xy 40.423053 -186.62715) (xy 40.422576 -186.585352)
			(xy 40.423029 -186.543553) (xy 40.430111 -186.460254) (xy 40.444184 -186.377848) (xy 40.465151 -186.296921)
			(xy 40.492862 -186.218048) (xy 40.527119 -186.14179) (xy 40.547036 -186.105038) (xy 40.549997 -186.099315)
			(xy 40.553218 -186.086842) (xy 40.553386 -186.0804) (xy 40.553386 -180.71592) (xy 40.554005 -180.690966)
			(xy 40.563755 -180.64202) (xy 40.582866 -180.595917) (xy 40.610602 -180.554426) (xy 40.627808 -180.536342)
			(xy 44.933108 -176.231042) (xy 44.939944 -176.22364) (xy 44.947657 -176.205042) (xy 44.948094 -176.194974)
			(xy 44.948094 -173.55185) (xy 44.947661 -173.541784) (xy 44.939934 -173.523193) (xy 44.933108 -173.515782)
			(xy 44.085256 -172.66793) (xy 44.067998 -172.649888) (xy 44.040245 -172.608394) (xy 44.021137 -172.562276)
			(xy 44.01141 -172.513312) (xy 44.010834 -172.488352) (xy 44.010834 -169.327576) (xy 44.010463 -169.318427)
			(xy 44.004052 -169.301291) (xy 43.992024 -169.287505) (xy 43.975914 -169.278831) (xy 43.966892 -169.277284)
			(xy 43.939781 -169.27316) (xy 43.887039 -169.258146) (xy 43.836991 -169.235733) (xy 43.79067 -169.206383)
			(xy 43.749029 -169.170701) (xy 43.712928 -169.129423) (xy 43.683111 -169.083401) (xy 43.660193 -169.033582)
			(xy 43.644647 -168.980995) (xy 43.636792 -168.926723) (xy 43.636792 -168.871886) (xy 43.644645 -168.817614)
			(xy 43.66019 -168.765026) (xy 43.683107 -168.715207) (xy 43.712923 -168.669183) (xy 43.749023 -168.627905)
			(xy 43.790663 -168.592222) (xy 43.836984 -168.562871) (xy 43.887031 -168.540457) (xy 43.939773 -168.525442)
			(xy 43.966892 -168.52138) (xy 43.975895 -168.519765) (xy 43.991986 -168.511094) (xy 44.004014 -168.497332)
			(xy 44.010453 -168.480226) (xy 44.010834 -168.471088) (xy 44.010834 -156.714952) (xy 44.01141 -156.689994)
			(xy 44.021158 -156.641038) (xy 44.04027 -156.594925) (xy 44.068011 -156.553426) (xy 44.085256 -156.535374)
			(xy 47.397416 -153.223214) (xy 47.415455 -153.205949) (xy 47.456946 -153.178181) (xy 47.503064 -153.159058)
			(xy 47.552031 -153.149318) (xy 47.576994 -153.148792) (xy 50.580544 -153.148792) (xy 50.591232 -153.148331)
			(xy 50.610765 -153.139649) (xy 50.62507 -153.123765) (xy 50.628804 -153.11374) (xy 50.637444 -153.088532)
			(xy 50.660778 -153.040626) (xy 50.690556 -152.996436) (xy 50.7262 -152.956825) (xy 50.767012 -152.922564)
			(xy 50.812199 -152.894321) (xy 50.860879 -152.872647) (xy 50.912103 -152.857964) (xy 50.964872 -152.850559)
			(xy 50.991516 -152.850088) (xy 51.020432 -152.850623) (xy 51.077602 -152.859352) (xy 51.132801 -152.876607)
			(xy 51.184763 -152.901994) (xy 51.2323 -152.934931) (xy 51.274323 -152.974664) (xy 51.292506 -152.997154)
			(xy 51.300095 -153.005988) (xy 51.321004 -153.01619) (xy 51.332638 -153.016712) (xy 51.412394 -153.016712)
			(xy 51.424015 -153.016137) (xy 51.444907 -153.005949) (xy 51.452526 -152.997154) (xy 51.470714 -152.974665)
			(xy 51.512728 -152.934918) (xy 51.560261 -152.901969) (xy 51.612223 -152.876573) (xy 51.667424 -152.859313)
			(xy 51.724598 -152.850584) (xy 51.753516 -152.850088) (xy 51.783855 -152.850675) (xy 51.843767 -152.860285)
			(xy 51.901402 -152.879259) (xy 51.955306 -152.907119) (xy 52.004119 -152.943161) (xy 52.025804 -152.964388)
			(xy 52.034694 -152.973532) (xy 52.059078 -152.981152) (xy 52.167536 -152.96007) (xy 52.187348 -152.943814)
			(xy 52.192174 -152.93213) (xy 52.208306 -152.89462) (xy 52.247466 -152.822966) (xy 52.294058 -152.755907)
			(xy 52.34755 -152.694211) (xy 52.407329 -152.638584) (xy 52.472709 -152.589664) (xy 52.542943 -152.548011)
			(xy 52.617226 -152.514101) (xy 52.694707 -152.488324) (xy 52.774499 -152.470974) (xy 52.855688 -152.462249)
			(xy 52.896516 -152.461722) (xy 52.933692 -152.462183) (xy 53.00769 -152.469445) (xy 53.08063 -152.483871)
			(xy 53.151821 -152.505322) (xy 53.220588 -152.533596) (xy 53.25364 -152.550622) (xy 53.264996 -152.555931)
			(xy 53.290036 -152.555931) (xy 53.301392 -152.550622) (xy 53.334441 -152.533589) (xy 53.403203 -152.505296)
			(xy 53.474394 -152.483835) (xy 53.547337 -152.469411) (xy 53.621338 -152.46216) (xy 53.658516 -152.461722)
			(xy 53.697056 -152.462212) (xy 53.773742 -152.469998) (xy 53.849251 -152.485481) (xy 53.922814 -152.508501)
			(xy 53.993679 -152.538825) (xy 54.061124 -152.576142) (xy 54.124461 -152.620072) (xy 54.183043 -152.670166)
			(xy 54.236273 -152.725915) (xy 54.283609 -152.786748) (xy 54.324567 -152.852046) (xy 54.358729 -152.921143)
			(xy 54.385747 -152.993333) (xy 54.405345 -153.06788) (xy 54.41188 -153.105866) (xy 54.414674 -153.124408)
			(xy 54.443122 -153.148792) (xy 55.155084 -153.148792) (xy 55.181246 -153.129996) (xy 55.18658 -153.114502)
			(xy 55.199797 -153.077309) (xy 55.232869 -153.005633) (xy 55.273167 -152.937757) (xy 55.320261 -152.874407)
			(xy 55.373647 -152.816259) (xy 55.432753 -152.763937) (xy 55.496947 -152.718) (xy 55.565542 -152.678939)
			(xy 55.637806 -152.647172) (xy 55.712964 -152.62304) (xy 55.790212 -152.606799) (xy 55.868725 -152.598624)
			(xy 55.908194 -152.59812) (xy 55.945371 -152.59858) (xy 56.019369 -152.60584) (xy 56.09231 -152.620264)
			(xy 56.163502 -152.641713) (xy 56.232271 -152.669986) (xy 56.265318 -152.68702) (xy 56.276674 -152.692329)
			(xy 56.301714 -152.692329) (xy 56.31307 -152.68702) (xy 56.346119 -152.669986) (xy 56.414881 -152.641691)
			(xy 56.486072 -152.620228) (xy 56.559015 -152.605802) (xy 56.633016 -152.598549) (xy 56.670194 -152.59812)
			(xy 56.709666 -152.598613) (xy 56.788189 -152.606762) (xy 56.86545 -152.622982) (xy 56.94062 -152.647101)
			(xy 57.012895 -152.67886) (xy 57.0815 -152.717918) (xy 57.145701 -152.763858) (xy 57.20481 -152.816188)
			(xy 57.258195 -152.874346) (xy 57.305282 -152.937711) (xy 57.345568 -153.005602) (xy 57.378622 -153.077294)
			(xy 57.391808 -153.114502) (xy 57.397142 -153.129996) (xy 57.423304 -153.148792) (xy 58.940954 -153.148792)
			(xy 58.965909 -153.149409) (xy 59.014857 -153.159155) (xy 59.060964 -153.178262) (xy 59.102458 -153.205997)
			(xy 59.120532 -153.223214) (xy 60.306458 -154.40914) (xy 60.321063 -154.424358) (xy 60.345521 -154.458718)
			(xy 60.363969 -154.496645) (xy 60.375898 -154.537099) (xy 60.378848 -154.557984) (xy 60.380094 -154.565979)
			(xy 60.386952 -154.580624) (xy 60.39231 -154.586686) (xy 60.411768 -154.608044) (xy 60.444678 -154.655531)
			(xy 60.470059 -154.707433) (xy 60.487331 -154.762567) (xy 60.4961 -154.819673) (xy 60.496704 -154.84856)
			(xy 60.496197 -154.877158) (xy 60.487667 -154.933713) (xy 60.470792 -154.988362) (xy 60.445951 -155.03988)
			(xy 60.413699 -155.087115) (xy 60.394596 -155.108402) (xy 60.388316 -155.115694) (xy 60.381269 -155.133584)
			(xy 60.38088 -155.1432) (xy 60.38088 -161.494978) (xy 60.381317 -161.505042) (xy 60.389049 -161.523628)
			(xy 60.395866 -161.531046) (xy 60.778136 -161.913316) (xy 60.78855 -161.924492) (xy 60.796118 -161.932215)
			(xy 60.815848 -161.941016) (xy 60.82665 -161.94151) (xy 86.858094 -161.94151) (xy 86.863174 -161.940494)
			(xy 86.906775 -161.932248) (xy 86.995079 -161.923465) (xy 87.03945 -161.922968) (xy 87.083819 -161.923496)
			(xy 87.172121 -161.932275) (xy 87.215726 -161.940494) (xy 87.220806 -161.94151) (xy 87.493094 -161.94151)
			(xy 87.498174 -161.940494) (xy 87.541775 -161.932248) (xy 87.630079 -161.923465) (xy 87.67445 -161.922968)
			(xy 87.718819 -161.923496) (xy 87.807121 -161.932275) (xy 87.850726 -161.940494) (xy 87.855806 -161.94151)
			(xy 88.128094 -161.94151) (xy 88.133174 -161.940494) (xy 88.176775 -161.932248) (xy 88.265079 -161.923465)
			(xy 88.30945 -161.922968) (xy 88.353819 -161.923496) (xy 88.442121 -161.932275) (xy 88.485726 -161.940494)
			(xy 88.490806 -161.94151) (xy 88.763094 -161.94151) (xy 88.768174 -161.940494) (xy 88.811775 -161.932248)
			(xy 88.900079 -161.923465) (xy 88.94445 -161.922968) (xy 88.988819 -161.923496) (xy 89.077121 -161.932275)
			(xy 89.120726 -161.940494) (xy 89.125806 -161.94151) (xy 89.398094 -161.94151) (xy 89.403174 -161.940494)
			(xy 89.446775 -161.932248) (xy 89.535079 -161.923465) (xy 89.57945 -161.922968) (xy 89.623819 -161.923496)
			(xy 89.712121 -161.932275) (xy 89.755726 -161.940494) (xy 89.760806 -161.94151) (xy 90.117168 -161.94151)
			(xy 90.12047 -161.941002) (xy 90.150173 -161.937273) (xy 90.209914 -161.933329) (xy 90.23985 -161.933128)
			(xy 90.269786 -161.933336) (xy 90.329526 -161.937277) (xy 90.35923 -161.941002) (xy 90.362532 -161.94151)
			(xy 94.747588 -161.94151) (xy 94.757659 -161.94109) (xy 94.776268 -161.933379) (xy 94.783656 -161.926524)
			(xy 104.053132 -152.657048) (xy 104.071173 -152.639788) (xy 104.112667 -152.61203) (xy 104.158785 -152.592915)
			(xy 104.207749 -152.583181) (xy 104.23271 -152.582626) (xy 115.345972 -152.582626) (xy 115.37442 -152.557734)
			(xy 115.37696 -152.538684) (xy 115.383801 -152.49242) (xy 115.405943 -152.401552) (xy 115.421156 -152.357328)
			(xy 115.423799 -152.348892) (xy 115.423785 -152.331226) (xy 115.421156 -152.322784) (xy 115.40859 -152.286613)
			(xy 115.389 -152.212582) (xy 115.375855 -152.137139) (xy 115.369251 -152.060846) (xy 115.368832 -152.022556)
			(xy 115.369294 -151.981447) (xy 115.376886 -151.899581) (xy 115.392 -151.818765) (xy 115.414508 -151.739689)
			(xy 115.444217 -151.663027) (xy 115.480874 -151.589434) (xy 115.524166 -151.519537) (xy 115.573724 -151.453935)
			(xy 115.629125 -151.393185) (xy 115.689895 -151.337808) (xy 115.755516 -151.288275) (xy 115.825429 -151.245009)
			(xy 115.899036 -151.20838) (xy 115.975709 -151.1787) (xy 116.054794 -151.156223) (xy 116.135616 -151.141139)
			(xy 116.217485 -151.133579) (xy 116.258594 -151.133048) (xy 116.296909 -151.133442) (xy 116.373258 -151.139991)
			(xy 116.448762 -151.153076) (xy 116.522862 -151.172599) (xy 116.559076 -151.185118) (xy 116.567392 -151.187704)
			(xy 116.584796 -151.187704) (xy 116.593112 -151.185118) (xy 116.629318 -151.172572) (xy 116.703417 -151.15303)
			(xy 116.778924 -151.139944) (xy 116.855277 -151.133411) (xy 116.893594 -151.133048) (xy 116.933807 -151.133485)
			(xy 117.013907 -151.140719) (xy 117.093029 -151.155148) (xy 117.170526 -151.176653) (xy 117.2083 -151.190452)
			(xy 117.217087 -151.193359) (xy 117.235581 -151.193359) (xy 117.244368 -151.190452) (xy 117.282142 -151.176652)
			(xy 117.359636 -151.155127) (xy 117.438758 -151.140694) (xy 117.51886 -151.133468) (xy 117.559074 -151.133048)
			(xy 117.597389 -151.133441) (xy 117.673738 -151.139989) (xy 117.749243 -151.153072) (xy 117.823344 -151.172593)
			(xy 117.859556 -151.185118) (xy 117.867872 -151.187704) (xy 117.885276 -151.187704) (xy 117.893592 -151.185118)
			(xy 117.929798 -151.172571) (xy 118.003897 -151.153028) (xy 118.079404 -151.13994) (xy 118.155757 -151.133405)
			(xy 118.194074 -151.133048) (xy 118.232389 -151.133441) (xy 118.308738 -151.139989) (xy 118.384243 -151.153072)
			(xy 118.458344 -151.172593) (xy 118.494556 -151.185118) (xy 118.502872 -151.187704) (xy 118.520276 -151.187704)
			(xy 118.528592 -151.185118) (xy 118.564798 -151.172571) (xy 118.638897 -151.153028) (xy 118.714404 -151.13994)
			(xy 118.790757 -151.133405) (xy 118.829074 -151.133048) (xy 118.867389 -151.133441) (xy 118.943738 -151.139989)
			(xy 119.019243 -151.153072) (xy 119.093344 -151.172593) (xy 119.129556 -151.185118) (xy 119.137872 -151.187704)
			(xy 119.155276 -151.187704) (xy 119.163592 -151.185118) (xy 119.19971 -151.17261) (xy 119.27362 -151.1531)
			(xy 119.348933 -151.140013) (xy 119.425091 -151.133445) (xy 119.463312 -151.133048) (xy 119.464074 -151.133048)
			(xy 119.505181 -151.133521) (xy 119.587046 -151.141104) (xy 119.667861 -151.156206) (xy 119.746939 -151.178699)
			(xy 119.823605 -151.208392) (xy 119.897204 -151.245031) (xy 119.967109 -151.288303) (xy 120.032725 -151.33784)
			(xy 120.09349 -151.393219) (xy 120.148887 -151.453968) (xy 120.198444 -151.519568) (xy 120.241738 -151.58946)
			(xy 120.278399 -151.663048) (xy 120.308115 -151.739705) (xy 120.330632 -151.818776) (xy 120.345759 -151.899587)
			(xy 120.353366 -151.981449) (xy 120.353836 -152.022556) (xy 120.353398 -152.060844) (xy 120.34677 -152.137132)
			(xy 120.333619 -152.212571) (xy 120.314043 -152.286602) (xy 120.301512 -152.322784) (xy 120.298855 -152.331221)
			(xy 120.298841 -152.348897) (xy 120.301512 -152.357328) (xy 120.316731 -152.40155) (xy 120.338873 -152.492419)
			(xy 120.345708 -152.538684) (xy 120.348248 -152.557734) (xy 120.376696 -152.582626) (xy 127.893318 -152.582626)
			(xy 127.902304 -152.58228) (xy 127.919167 -152.57607) (xy 127.932827 -152.564392) (xy 127.937514 -152.556718)
			(xy 127.958914 -152.519592) (xy 128.007818 -152.449217) (xy 128.063266 -152.383874) (xy 128.124744 -152.324169)
			(xy 128.191681 -152.270656) (xy 128.263456 -152.223832) (xy 128.339404 -152.184131) (xy 128.418819 -152.151921)
			(xy 128.500965 -152.127502) (xy 128.585079 -152.1111) (xy 128.670381 -152.102867) (xy 128.71323 -152.102312)
			(xy 128.754841 -152.102792) (xy 128.8377 -152.110557) (xy 128.919472 -152.126024) (xy 128.999443 -152.14906)
			(xy 129.076913 -152.179462) (xy 129.151205 -152.216966) (xy 129.186686 -152.23871) (xy 129.195818 -152.243893)
			(xy 129.216543 -152.247112) (xy 129.236829 -152.24178) (xy 129.24536 -152.235662) (xy 129.279008 -152.2097)
			(xy 129.350412 -152.163595) (xy 129.425884 -152.124505) (xy 129.504737 -152.092785) (xy 129.586255 -152.068724)
			(xy 129.669695 -152.052541) (xy 129.754297 -152.044384) (xy 129.796794 -152.043892) (xy 129.838657 -152.044377)
			(xy 129.922011 -152.052254) (xy 130.004256 -152.06793) (xy 130.084664 -152.091266) (xy 130.162523 -152.122055)
			(xy 130.237144 -152.160026) (xy 130.307866 -152.20484) (xy 130.374064 -152.256103) (xy 130.435151 -152.313361)
			(xy 130.490586 -152.376105) (xy 130.53988 -152.443782) (xy 130.582595 -152.515792) (xy 130.600958 -152.553416)
			(xy 130.605419 -152.56195) (xy 130.619431 -152.575136) (xy 130.637312 -152.58224) (xy 130.646932 -152.582626)
			(xy 132.390388 -152.582626) (xy 132.40011 -152.582145) (xy 132.418133 -152.574834) (xy 132.42544 -152.568402)
			(xy 132.446907 -152.548566) (xy 132.494745 -152.514989) (xy 132.54714 -152.489094) (xy 132.602869 -152.471484)
			(xy 132.660631 -152.462572) (xy 132.689854 -152.461976) (xy 132.690108 -152.461976) (xy 132.715308 -152.462405)
			(xy 132.765265 -152.469079) (xy 132.813912 -152.482257) (xy 132.860406 -152.501712) (xy 132.882386 -152.514046)
			(xy 132.892292 -152.519888) (xy 132.914136 -152.52192) (xy 133.008878 -152.488392) (xy 133.024626 -152.472898)
			(xy 133.02869 -152.462484) (xy 133.03938 -152.435703) (xy 133.067661 -152.385451) (xy 133.103188 -152.340032)
			(xy 133.145149 -152.300481) (xy 133.192587 -152.2677) (xy 133.244422 -152.242438) (xy 133.299469 -152.225269)
			(xy 133.356475 -152.216586) (xy 133.385306 -152.216104) (xy 133.412369 -152.216569) (xy 133.465953 -152.224204)
			(xy 133.517921 -152.239334) (xy 133.567229 -152.261655) (xy 133.612889 -152.29072) (xy 133.653984 -152.325945)
			(xy 133.689688 -152.366623) (xy 133.719287 -152.411939) (xy 133.742186 -152.460982) (xy 133.757924 -152.512768)
			(xy 133.762496 -152.539446) (xy 133.764208 -152.548353) (xy 133.772977 -152.564216) (xy 133.786724 -152.57603)
			(xy 133.803725 -152.582315) (xy 133.812788 -152.582626) (xy 134.08025 -152.582626) (xy 134.092091 -152.581997)
			(xy 134.113269 -152.571393) (xy 134.12089 -152.562306) (xy 134.137621 -152.540894) (xy 134.176143 -152.502569)
			(xy 134.219713 -152.470096) (xy 134.267447 -152.444132) (xy 134.318383 -152.425202) (xy 134.371488 -152.413688)
			(xy 134.42569 -152.409824) (xy 134.479892 -152.413688) (xy 134.532997 -152.425202) (xy 134.583933 -152.444132)
			(xy 134.631667 -152.470096) (xy 134.675237 -152.502569) (xy 134.713759 -152.540894) (xy 134.73049 -152.562306)
			(xy 134.738097 -152.571403) (xy 134.759288 -152.58198) (xy 134.77113 -152.582626) (xy 134.961376 -152.582626)
			(xy 134.988554 -152.561798) (xy 134.993126 -152.545288) (xy 135.003786 -152.50867) (xy 135.031444 -152.437592)
			(xy 135.066058 -152.369629) (xy 135.10728 -152.305459) (xy 135.154701 -152.245724) (xy 135.207846 -152.191018)
			(xy 135.266185 -152.141889) (xy 135.329135 -152.098827) (xy 135.396068 -152.062262) (xy 135.466316 -152.032559)
			(xy 135.539178 -152.010015) (xy 135.613926 -151.994854) (xy 135.689813 -151.987227) (xy 135.727948 -151.986742)
			(xy 135.76788 -151.987249) (xy 135.847307 -151.995602) (xy 135.925425 -152.012212) (xy 136.00138 -152.036896)
			(xy 136.074338 -152.069385) (xy 136.1435 -152.109322) (xy 136.208109 -152.156269) (xy 136.267456 -152.209713)
			(xy 136.320893 -152.269067) (xy 136.367832 -152.333682) (xy 136.40776 -152.40285) (xy 136.440239 -152.475812)
			(xy 136.464913 -152.551769) (xy 136.481513 -152.62989) (xy 136.489856 -152.709318) (xy 136.490456 -152.74925)
			(xy 136.490456 -152.749758) (xy 136.489871 -152.791648) (xy 136.480661 -152.87492) (xy 136.462378 -152.956681)
			(xy 136.435245 -153.035946) (xy 136.399587 -153.111759) (xy 136.378188 -153.147776) (xy 136.372825 -153.157749)
			(xy 136.370481 -153.180242) (xy 136.378004 -153.201568) (xy 136.385554 -153.210006) (xy 136.577578 -153.40203)
			(xy 136.594842 -153.420069) (xy 136.622609 -153.46156) (xy 136.64173 -153.507679) (xy 136.651467 -153.556645)
			(xy 136.652 -153.581608) (xy 136.652 -167.738044) (xy 136.652496 -167.748046) (xy 136.660163 -167.766522)
			(xy 136.674314 -167.780662) (xy 136.692798 -167.788313) (xy 136.7028 -167.788844) (xy 138.924538 -167.788844)
			(xy 138.934947 -167.788357) (xy 138.95406 -167.780111) (xy 138.968325 -167.76495) (xy 138.97229 -167.755316)
			(xy 138.981545 -167.730555) (xy 139.003028 -167.682252) (xy 139.015216 -167.658796) (xy 139.020533 -167.64744)
			(xy 139.020542 -167.622395) (xy 139.015216 -167.611044) (xy 138.99815 -167.57795) (xy 138.969798 -167.509092)
			(xy 138.948286 -167.437801) (xy 138.933821 -167.364754) (xy 138.926538 -167.290645) (xy 138.926062 -167.253412)
			(xy 138.926551 -167.214741) (xy 138.934376 -167.137796) (xy 138.949945 -167.062037) (xy 138.973098 -166.988242)
			(xy 139.003598 -166.917168) (xy 139.041133 -166.849545) (xy 139.085316 -166.786065) (xy 139.135694 -166.727381)
			(xy 139.191751 -166.674095) (xy 139.252911 -166.626754) (xy 139.318547 -166.585843) (xy 139.387985 -166.551782)
			(xy 139.460512 -166.52492) (xy 139.535385 -166.505535) (xy 139.611835 -166.493823) (xy 139.689078 -166.489906)
			(xy 139.766321 -166.493823) (xy 139.842771 -166.505535) (xy 139.917644 -166.52492) (xy 139.990171 -166.551782)
			(xy 140.059609 -166.585843) (xy 140.125245 -166.626754) (xy 140.186405 -166.674095) (xy 140.242462 -166.727381)
			(xy 140.29284 -166.786065) (xy 140.337023 -166.849545) (xy 140.374558 -166.917168) (xy 140.405058 -166.988242)
			(xy 140.428211 -167.062037) (xy 140.44378 -167.137796) (xy 140.451605 -167.214741) (xy 140.452094 -167.253412)
			(xy 140.451635 -167.290646) (xy 140.444357 -167.364757) (xy 140.429892 -167.437806) (xy 140.408378 -167.509099)
			(xy 140.380018 -167.577955) (xy 140.36294 -167.611044) (xy 140.357636 -167.6224) (xy 140.357645 -167.647435)
			(xy 140.36294 -167.658796) (xy 140.375131 -167.682251) (xy 140.396617 -167.730553) (xy 140.405866 -167.755316)
			(xy 140.409872 -167.764929) (xy 140.424125 -167.780087) (xy 140.443216 -167.78836) (xy 140.453618 -167.788844)
			(xy 149.473666 -167.788844) (xy 149.498624 -167.789422) (xy 149.547577 -167.799173) (xy 149.593688 -167.818288)
			(xy 149.635183 -167.846032) (xy 149.653244 -167.863266) (xy 152.420578 -170.6306) (xy 160.67149 -170.6306)
			(xy 160.675402 -170.553457) (xy 160.687099 -170.477106) (xy 160.70646 -170.402329) (xy 160.733287 -170.329895)
			(xy 160.767305 -170.260547) (xy 160.808164 -170.194997) (xy 160.855445 -170.133916) (xy 160.908663 -170.077932)
			(xy 160.967271 -170.027619) (xy 161.03067 -169.983494) (xy 161.098207 -169.946009) (xy 161.169189 -169.91555)
			(xy 161.24289 -169.892428) (xy 161.318551 -169.876881) (xy 161.395397 -169.869068) (xy 161.434018 -169.868596)
			(xy 161.47671 -169.869176) (xy 161.561558 -169.878722) (xy 161.644811 -169.89768) (xy 161.725426 -169.925813)
			(xy 161.802397 -169.962771) (xy 161.838894 -169.984928) (xy 161.84715 -169.989642) (xy 161.865818 -169.993169)
			(xy 161.884486 -169.989642) (xy 161.892742 -169.984928) (xy 161.929245 -169.962778) (xy 162.006203 -169.925789)
			(xy 162.086816 -169.897643) (xy 162.170072 -169.878692) (xy 162.254925 -169.869175) (xy 162.297618 -169.868596)
			(xy 162.336237 -169.869094) (xy 162.413078 -169.87691) (xy 162.488734 -169.892459) (xy 162.562428 -169.915582)
			(xy 162.633406 -169.946043) (xy 162.700937 -169.983527) (xy 162.76433 -170.027651) (xy 162.822934 -170.077962)
			(xy 162.876147 -170.133944) (xy 162.923424 -170.195022) (xy 162.964279 -170.260569) (xy 162.998294 -170.329914)
			(xy 163.025118 -170.402343) (xy 163.044478 -170.477115) (xy 163.056174 -170.553462) (xy 163.060086 -170.6306)
			(xy 163.056174 -170.707738) (xy 163.044478 -170.784085) (xy 163.025118 -170.858857) (xy 162.998294 -170.931286)
			(xy 162.964279 -171.000631) (xy 162.923424 -171.066178) (xy 162.876147 -171.127256) (xy 162.822934 -171.183238)
			(xy 162.76433 -171.233549) (xy 162.700937 -171.277673) (xy 162.633406 -171.315157) (xy 162.562428 -171.345618)
			(xy 162.488734 -171.368741) (xy 162.413078 -171.38429) (xy 162.336237 -171.392106) (xy 162.297618 -171.392596)
			(xy 162.254927 -171.392) (xy 162.170079 -171.382458) (xy 162.086826 -171.363504) (xy 162.006211 -171.335374)
			(xy 161.929239 -171.298419) (xy 161.892742 -171.276264) (xy 161.884486 -171.27155) (xy 161.865818 -171.268023)
			(xy 161.84715 -171.27155) (xy 161.838894 -171.276264) (xy 161.802407 -171.29844) (xy 161.725444 -171.335424)
			(xy 161.644827 -171.363565) (xy 161.561568 -171.38251) (xy 161.476712 -171.39202) (xy 161.434018 -171.392596)
			(xy 161.395397 -171.392132) (xy 161.318551 -171.384319) (xy 161.24289 -171.368772) (xy 161.169189 -171.34565)
			(xy 161.098207 -171.315191) (xy 161.03067 -171.277706) (xy 160.967271 -171.233581) (xy 160.908663 -171.183268)
			(xy 160.855445 -171.127284) (xy 160.808164 -171.066203) (xy 160.767305 -171.000653) (xy 160.733287 -170.931305)
			(xy 160.70646 -170.858871) (xy 160.687099 -170.784094) (xy 160.675402 -170.707743) (xy 160.67149 -170.6306)
			(xy 152.420578 -170.6306) (xy 164.710364 -182.920386) (xy 164.727619 -182.938429) (xy 164.755367 -182.979924)
			(xy 164.774471 -183.026042) (xy 164.784195 -183.075004) (xy 164.784786 -183.099964) (xy 164.784786 -194.291204)
			(xy 164.785209 -194.301274) (xy 164.792923 -194.319879) (xy 164.799772 -194.327272) (xy 165.113462 -194.640962)
			(xy 165.120862 -194.647803) (xy 165.139461 -194.655521) (xy 165.14953 -194.655948) (xy 165.27145 -194.655948)
			(xy 165.282173 -194.655527) (xy 165.30177 -194.646835) (xy 165.309296 -194.639184) (xy 165.328486 -194.618593)
			(xy 165.372006 -194.582902) (xy 165.420447 -194.554243) (xy 165.472682 -194.533283) (xy 165.527496 -194.520509)
			(xy 165.583616 -194.516218) (xy 165.639736 -194.520509) (xy 165.69455 -194.533283) (xy 165.746785 -194.554243)
			(xy 165.795226 -194.582902) (xy 165.838746 -194.618593) (xy 165.857936 -194.639184) (xy 165.865536 -194.646722)
			(xy 165.885092 -194.655366) (xy 165.895782 -194.655948) (xy 166.612316 -194.655948) (xy 166.622588 -194.655476)
			(xy 166.64149 -194.647427) (xy 166.655731 -194.632619) (xy 166.659814 -194.623182) (xy 166.673896 -194.587486)
			(xy 166.708239 -194.51886) (xy 166.749301 -194.45403) (xy 166.796668 -194.393653) (xy 166.84986 -194.338339)
			(xy 166.90834 -194.288648) (xy 166.971515 -194.245082) (xy 167.038746 -194.208083) (xy 167.109354 -194.178024)
			(xy 167.182625 -194.15521) (xy 167.257816 -194.139871) (xy 167.334168 -194.132162) (xy 167.410908 -194.132162)
			(xy 167.48726 -194.139871) (xy 167.562451 -194.15521) (xy 167.635722 -194.178024) (xy 167.70633 -194.208083)
			(xy 167.773561 -194.245082) (xy 167.836736 -194.288648) (xy 167.895216 -194.338339) (xy 167.948408 -194.393653)
			(xy 167.995775 -194.45403) (xy 168.036837 -194.51886) (xy 168.07118 -194.587486) (xy 168.085262 -194.623182)
			(xy 168.089345 -194.63262) (xy 168.103581 -194.647433) (xy 168.122487 -194.655471) (xy 168.13276 -194.655948)
			(xy 168.90365 -194.655948) (xy 168.915076 -194.655307) (xy 168.935668 -194.6454) (xy 168.949948 -194.627558)
			(xy 168.95318 -194.616578) (xy 168.962376 -194.578918) (xy 168.987518 -194.50558) (xy 169.020093 -194.435228)
			(xy 169.059751 -194.368611) (xy 169.106071 -194.306442) (xy 169.158558 -194.249383) (xy 169.216651 -194.198044)
			(xy 169.279731 -194.152972) (xy 169.347124 -194.114649) (xy 169.418112 -194.083483) (xy 169.491936 -194.059807)
			(xy 169.567809 -194.043873) (xy 169.64492 -194.035853) (xy 169.683684 -194.035426) (xy 169.683938 -194.035426)
			(xy 169.723766 -194.035949) (xy 169.802975 -194.044388) (xy 169.880842 -194.061179) (xy 169.95649 -194.086131)
			(xy 170.029066 -194.118963) (xy 170.097751 -194.159305) (xy 170.161772 -194.206703) (xy 170.19143 -194.233292)
			(xy 170.198768 -194.239317) (xy 170.216488 -194.246082) (xy 170.225974 -194.2465) (xy 170.256454 -194.2465)
			(xy 170.266023 -194.246001) (xy 170.283776 -194.238827) (xy 170.290998 -194.23253) (xy 170.32138 -194.204399)
			(xy 170.387224 -194.154188) (xy 170.458122 -194.111409) (xy 170.533239 -194.076567) (xy 170.61169 -194.050072)
			(xy 170.69255 -194.032235) (xy 170.774868 -194.023268) (xy 170.81627 -194.022726) (xy 170.855792 -194.023231)
			(xy 170.934411 -194.031416) (xy 171.011762 -194.047691) (xy 171.087014 -194.071881) (xy 171.159359 -194.103727)
			(xy 171.228022 -194.142886) (xy 171.292264 -194.188939) (xy 171.351398 -194.241391) (xy 171.404787 -194.29968)
			(xy 171.45186 -194.36318) (xy 171.49211 -194.431208) (xy 171.525106 -194.503036) (xy 171.550494 -194.577893)
			(xy 171.559728 -194.616324) (xy 171.559728 -194.616578) (xy 171.562911 -194.627581) (xy 171.577199 -194.645444)
			(xy 171.59782 -194.655341) (xy 171.609258 -194.655948) (xy 172.815504 -194.655948) (xy 172.826231 -194.655536)
			(xy 172.845842 -194.646856) (xy 172.85335 -194.639184) (xy 172.87254 -194.618593) (xy 172.91606 -194.582902)
			(xy 172.964501 -194.554243) (xy 173.016736 -194.533283) (xy 173.07155 -194.520509) (xy 173.12767 -194.516218)
			(xy 173.18379 -194.520509) (xy 173.238604 -194.533283) (xy 173.290839 -194.554243) (xy 173.33928 -194.582902)
			(xy 173.3828 -194.618593) (xy 173.40199 -194.639184) (xy 173.409587 -194.646729) (xy 173.429143 -194.655391)
			(xy 173.439836 -194.655948) (xy 174.15637 -194.655948) (xy 174.166647 -194.655484) (xy 174.185564 -194.647445)
			(xy 174.19982 -194.632638) (xy 174.203868 -194.623182) (xy 174.21795 -194.587486) (xy 174.252293 -194.51886)
			(xy 174.293355 -194.45403) (xy 174.340722 -194.393653) (xy 174.393914 -194.338339) (xy 174.452394 -194.288648)
			(xy 174.515569 -194.245082) (xy 174.5828 -194.208083) (xy 174.653408 -194.178024) (xy 174.726679 -194.15521)
			(xy 174.80187 -194.139871) (xy 174.878222 -194.132162) (xy 174.954962 -194.132162) (xy 175.031314 -194.139871)
			(xy 175.106505 -194.15521) (xy 175.179776 -194.178024) (xy 175.250384 -194.208083) (xy 175.317615 -194.245082)
			(xy 175.38079 -194.288648) (xy 175.43927 -194.338339) (xy 175.492462 -194.393653) (xy 175.539829 -194.45403)
			(xy 175.580891 -194.51886) (xy 175.615234 -194.587486) (xy 175.629316 -194.623182) (xy 175.633397 -194.632625)
			(xy 175.64763 -194.64745) (xy 175.666538 -194.655506) (xy 175.676814 -194.655948) (xy 176.447704 -194.655948)
			(xy 176.459136 -194.655316) (xy 176.479746 -194.645418) (xy 176.49404 -194.627573) (xy 176.497234 -194.616578)
			(xy 176.50643 -194.578919) (xy 176.531573 -194.505584) (xy 176.564149 -194.435234) (xy 176.603808 -194.368621)
			(xy 176.650129 -194.306455) (xy 176.702616 -194.2494) (xy 176.76071 -194.198065) (xy 176.82379 -194.152997)
			(xy 176.891183 -194.114678) (xy 176.96217 -194.083517) (xy 177.035994 -194.059846) (xy 177.111865 -194.043918)
			(xy 177.188975 -194.035902) (xy 177.227738 -194.035426) (xy 177.227992 -194.035426) (xy 177.267819 -194.035952)
			(xy 177.347025 -194.044396) (xy 177.424889 -194.061191) (xy 177.500534 -194.086148) (xy 177.573106 -194.118984)
			(xy 177.641787 -194.159329) (xy 177.705804 -194.206729) (xy 177.735484 -194.233292) (xy 177.742819 -194.239324)
			(xy 177.76054 -194.246105) (xy 177.770028 -194.2465) (xy 177.800508 -194.2465) (xy 177.810073 -194.245991)
			(xy 177.827813 -194.238804) (xy 177.835052 -194.23253) (xy 177.865435 -194.204401) (xy 177.93128 -194.154195)
			(xy 178.002179 -194.111421) (xy 178.077296 -194.076584) (xy 178.155747 -194.050094) (xy 178.236607 -194.032264)
			(xy 178.318923 -194.023302) (xy 178.360324 -194.022726) (xy 178.399844 -194.023234) (xy 178.47846 -194.031424)
			(xy 178.555807 -194.047703) (xy 178.631054 -194.071896) (xy 178.703395 -194.103744) (xy 178.772052 -194.142906)
			(xy 178.83629 -194.18896) (xy 178.895419 -194.241412) (xy 178.948804 -194.299701) (xy 178.995873 -194.363199)
			(xy 179.036119 -194.431226) (xy 179.069112 -194.503052) (xy 179.094498 -194.577906) (xy 179.103782 -194.616324)
			(xy 179.103782 -194.616578) (xy 179.106871 -194.627622) (xy 179.121192 -194.645507) (xy 179.141855 -194.655404)
			(xy 179.153312 -194.655948) (xy 180.359558 -194.655948) (xy 180.37028 -194.655525) (xy 180.389875 -194.646831)
			(xy 180.397404 -194.639184) (xy 180.416594 -194.618593) (xy 180.460114 -194.582902) (xy 180.508555 -194.554243)
			(xy 180.56079 -194.533283) (xy 180.615604 -194.520509) (xy 180.671724 -194.516218) (xy 180.727844 -194.520509)
			(xy 180.782658 -194.533283) (xy 180.834893 -194.554243) (xy 180.883334 -194.582902) (xy 180.926854 -194.618593)
			(xy 180.946044 -194.639184) (xy 180.953645 -194.646721) (xy 180.9732 -194.655362) (xy 180.98389 -194.655948)
			(xy 181.700424 -194.655948) (xy 181.710695 -194.655475) (xy 181.729595 -194.647424) (xy 181.743833 -194.632616)
			(xy 181.747922 -194.623182) (xy 181.762004 -194.587486) (xy 181.796347 -194.51886) (xy 181.837409 -194.45403)
			(xy 181.884776 -194.393653) (xy 181.937968 -194.338339) (xy 181.996448 -194.288648) (xy 182.059623 -194.245082)
			(xy 182.126854 -194.208083) (xy 182.197462 -194.178024) (xy 182.270733 -194.15521) (xy 182.345924 -194.139871)
			(xy 182.422276 -194.132162) (xy 182.499016 -194.132162) (xy 182.575368 -194.139871) (xy 182.650559 -194.15521)
			(xy 182.72383 -194.178024) (xy 182.794438 -194.208083) (xy 182.861669 -194.245082) (xy 182.924844 -194.288648)
			(xy 182.983324 -194.338339) (xy 183.036516 -194.393653) (xy 183.083883 -194.45403) (xy 183.124945 -194.51886)
			(xy 183.159288 -194.587486) (xy 183.17337 -194.623182) (xy 183.177448 -194.63263) (xy 183.191679 -194.647468)
			(xy 183.210588 -194.65554) (xy 183.220868 -194.655948) (xy 183.978804 -194.655948) (xy 183.990236 -194.655316)
			(xy 184.010846 -194.645418) (xy 184.02514 -194.627573) (xy 184.028334 -194.616578) (xy 184.028334 -194.616324)
			(xy 184.037566 -194.57789) (xy 184.062936 -194.503023) (xy 184.095919 -194.431185) (xy 184.13616 -194.363147)
			(xy 184.183228 -194.299639) (xy 184.236617 -194.241344) (xy 184.295753 -194.188889) (xy 184.36 -194.142837)
			(xy 184.42867 -194.103681) (xy 184.501023 -194.071845) (xy 184.576284 -194.047668) (xy 184.653642 -194.031411)
			(xy 184.732268 -194.023249) (xy 184.771792 -194.022726) (xy 184.809567 -194.023191) (xy 184.884747 -194.030667)
			(xy 184.958819 -194.045537) (xy 185.031059 -194.067656) (xy 185.100759 -194.096806) (xy 185.167237 -194.132703)
			(xy 185.229841 -194.174995) (xy 185.259218 -194.198748) (xy 185.268539 -194.205687) (xy 185.291119 -194.211078)
			(xy 185.313775 -194.206021) (xy 185.323226 -194.199256) (xy 185.3517 -194.177069) (xy 185.412181 -194.137655)
			(xy 185.476172 -194.104238) (xy 185.543079 -194.077129) (xy 185.612282 -194.05658) (xy 185.683141 -194.04278)
			(xy 185.754999 -194.035857) (xy 185.791094 -194.035426) (xy 185.791348 -194.035426) (xy 185.830112 -194.035911)
			(xy 185.907226 -194.043908) (xy 185.983103 -194.059822) (xy 186.056932 -194.083483) (xy 186.127924 -194.114639)
			(xy 186.195321 -194.152955) (xy 186.258403 -194.198024) (xy 186.316496 -194.249363) (xy 186.36898 -194.306425)
			(xy 186.415293 -194.368599) (xy 186.454942 -194.435221) (xy 186.487502 -194.50558) (xy 186.512625 -194.578925)
			(xy 186.521852 -194.616578) (xy 186.525036 -194.627579) (xy 186.539325 -194.645434) (xy 186.559946 -194.655323)
			(xy 186.571382 -194.655948) (xy 187.903612 -194.655948) (xy 187.914338 -194.655534) (xy 187.933947 -194.646852)
			(xy 187.941458 -194.639184) (xy 187.960648 -194.618593) (xy 188.004168 -194.582902) (xy 188.052609 -194.554243)
			(xy 188.104844 -194.533283) (xy 188.159658 -194.520509) (xy 188.215778 -194.516218) (xy 188.271898 -194.520509)
			(xy 188.326712 -194.533283) (xy 188.378947 -194.554243) (xy 188.427388 -194.582902) (xy 188.470908 -194.618593)
			(xy 188.490098 -194.639184) (xy 188.497696 -194.646728) (xy 188.517251 -194.655387) (xy 188.527944 -194.655948)
			(xy 189.244224 -194.655948) (xy 189.254495 -194.655475) (xy 189.273395 -194.647424) (xy 189.287633 -194.632616)
			(xy 189.291722 -194.623182) (xy 189.305804 -194.587486) (xy 189.340147 -194.51886) (xy 189.381209 -194.45403)
			(xy 189.428576 -194.393653) (xy 189.481768 -194.338339) (xy 189.540248 -194.288648) (xy 189.603423 -194.245082)
			(xy 189.670654 -194.208083) (xy 189.741262 -194.178024) (xy 189.814533 -194.15521) (xy 189.889724 -194.139871)
			(xy 189.966076 -194.132162) (xy 190.042816 -194.132162) (xy 190.119168 -194.139871) (xy 190.194359 -194.15521)
			(xy 190.26763 -194.178024) (xy 190.338238 -194.208083) (xy 190.405469 -194.245082) (xy 190.468644 -194.288648)
			(xy 190.527124 -194.338339) (xy 190.580316 -194.393653) (xy 190.627683 -194.45403) (xy 190.668745 -194.51886)
			(xy 190.703088 -194.587486) (xy 190.71717 -194.623182) (xy 190.721248 -194.63263) (xy 190.735479 -194.647468)
			(xy 190.754388 -194.65554) (xy 190.764668 -194.655948) (xy 191.535812 -194.655948) (xy 191.547243 -194.655315)
			(xy 191.56785 -194.645414) (xy 191.582142 -194.62757) (xy 191.585342 -194.616578) (xy 191.594538 -194.578919)
			(xy 191.619682 -194.505584) (xy 191.652257 -194.435235) (xy 191.691917 -194.368623) (xy 191.738237 -194.306457)
			(xy 191.790725 -194.249403) (xy 191.848819 -194.198068) (xy 191.911899 -194.153001) (xy 191.979292 -194.114682)
			(xy 192.050279 -194.083522) (xy 192.124102 -194.059852) (xy 192.199974 -194.043924) (xy 192.277084 -194.03591)
			(xy 192.315846 -194.035426) (xy 192.3161 -194.035426) (xy 192.355927 -194.035952) (xy 192.435133 -194.044397)
			(xy 192.512996 -194.061193) (xy 192.58864 -194.08615) (xy 192.661212 -194.118987) (xy 192.729892 -194.159333)
			(xy 192.793908 -194.206733) (xy 192.823592 -194.233292) (xy 192.830928 -194.239322) (xy 192.848649 -194.2461)
			(xy 192.858136 -194.2465) (xy 192.888616 -194.2465) (xy 192.89818 -194.24599) (xy 192.915918 -194.2388)
			(xy 192.92316 -194.23253) (xy 192.953543 -194.204402) (xy 193.019388 -194.154196) (xy 193.090287 -194.111423)
			(xy 193.165405 -194.076587) (xy 193.243855 -194.050098) (xy 193.324715 -194.032268) (xy 193.407031 -194.023307)
			(xy 193.448432 -194.022726) (xy 193.487955 -194.023229) (xy 193.566577 -194.031411) (xy 193.643931 -194.047682)
			(xy 193.719186 -194.07187) (xy 193.791535 -194.103714) (xy 193.8602 -194.142872) (xy 193.924446 -194.188925)
			(xy 193.983583 -194.241377) (xy 194.036975 -194.299666) (xy 194.084051 -194.363166) (xy 194.124303 -194.431196)
			(xy 194.157302 -194.503025) (xy 194.182692 -194.577883) (xy 194.19189 -194.616324) (xy 194.19189 -194.616578)
			(xy 194.195071 -194.627585) (xy 194.209357 -194.645458) (xy 194.229979 -194.65537) (xy 194.24142 -194.655948)
			(xy 195.447666 -194.655948) (xy 195.458387 -194.655524) (xy 195.47798 -194.646828) (xy 195.485512 -194.639184)
			(xy 195.504702 -194.618593) (xy 195.548222 -194.582902) (xy 195.596663 -194.554243) (xy 195.648898 -194.533283)
			(xy 195.703712 -194.520509) (xy 195.759832 -194.516218) (xy 195.815952 -194.520509) (xy 195.870766 -194.533283)
			(xy 195.923001 -194.554243) (xy 195.971442 -194.582902) (xy 196.014962 -194.618593) (xy 196.034152 -194.639184)
			(xy 196.041747 -194.646736) (xy 196.061302 -194.655412) (xy 196.071998 -194.655948) (xy 196.788278 -194.655948)
			(xy 196.798554 -194.655483) (xy 196.817469 -194.647441) (xy 196.831722 -194.632634) (xy 196.835776 -194.623182)
			(xy 196.849858 -194.587486) (xy 196.884201 -194.51886) (xy 196.925263 -194.45403) (xy 196.97263 -194.393653)
			(xy 197.025822 -194.338339) (xy 197.084302 -194.288648) (xy 197.147477 -194.245082) (xy 197.214708 -194.208083)
			(xy 197.285316 -194.178024) (xy 197.358587 -194.15521) (xy 197.433778 -194.139871) (xy 197.51013 -194.132162)
			(xy 197.58687 -194.132162) (xy 197.663222 -194.139871) (xy 197.738413 -194.15521) (xy 197.811684 -194.178024)
			(xy 197.882292 -194.208083) (xy 197.949523 -194.245082) (xy 198.012698 -194.288648) (xy 198.071178 -194.338339)
			(xy 198.12437 -194.393653) (xy 198.171737 -194.45403) (xy 198.212799 -194.51886) (xy 198.247142 -194.587486)
			(xy 198.261224 -194.623182) (xy 198.265305 -194.632624) (xy 198.279539 -194.647447) (xy 198.298446 -194.6555)
			(xy 198.308722 -194.655948) (xy 199.079866 -194.655948) (xy 199.091289 -194.655304) (xy 199.111876 -194.645394)
			(xy 199.12615 -194.627553) (xy 199.129396 -194.616578) (xy 199.138592 -194.578918) (xy 199.163735 -194.505581)
			(xy 199.196309 -194.43523) (xy 199.235968 -194.368614) (xy 199.282288 -194.306446) (xy 199.334775 -194.249388)
			(xy 199.392869 -194.19805) (xy 199.455949 -194.15298) (xy 199.523342 -194.114658) (xy 199.594329 -194.083493)
			(xy 199.668153 -194.059818) (xy 199.744025 -194.043886) (xy 199.821137 -194.035867) (xy 199.8599 -194.035426)
			(xy 199.899727 -194.035952) (xy 199.978933 -194.044397) (xy 200.056796 -194.061193) (xy 200.13244 -194.08615)
			(xy 200.205012 -194.118987) (xy 200.273692 -194.159333) (xy 200.337708 -194.206733) (xy 200.367392 -194.233292)
			(xy 200.374728 -194.239322) (xy 200.392449 -194.2461) (xy 200.401936 -194.2465) (xy 200.432416 -194.2465)
			(xy 200.442049 -194.246033) (xy 200.459932 -194.238852) (xy 200.467214 -194.23253) (xy 200.497579 -194.204406)
			(xy 200.563387 -194.154205) (xy 200.634249 -194.111432) (xy 200.709328 -194.076592) (xy 200.787742 -194.050094)
			(xy 200.868566 -194.03225) (xy 200.950847 -194.023272) (xy 200.992232 -194.022726) (xy 201.031755 -194.023229)
			(xy 201.110377 -194.031411) (xy 201.187731 -194.047682) (xy 201.262986 -194.07187) (xy 201.335335 -194.103714)
			(xy 201.404 -194.142872) (xy 201.468246 -194.188925) (xy 201.527383 -194.241377) (xy 201.580775 -194.299666)
			(xy 201.627851 -194.363166) (xy 201.668103 -194.431196) (xy 201.701102 -194.503025) (xy 201.726492 -194.577883)
			(xy 201.73569 -194.616324) (xy 201.73569 -194.616578) (xy 201.738871 -194.627585) (xy 201.753157 -194.645458)
			(xy 201.773779 -194.65537) (xy 201.78522 -194.655948) (xy 202.991466 -194.655948) (xy 203.002187 -194.655524)
			(xy 203.02178 -194.646828) (xy 203.029312 -194.639184) (xy 203.048502 -194.618593) (xy 203.092022 -194.582902)
			(xy 203.140463 -194.554243) (xy 203.192698 -194.533283) (xy 203.247512 -194.520509) (xy 203.303632 -194.516218)
			(xy 203.359752 -194.520509) (xy 203.414566 -194.533283) (xy 203.466801 -194.554243) (xy 203.515242 -194.582902)
			(xy 203.558762 -194.618593) (xy 203.577952 -194.639184) (xy 203.585547 -194.646736) (xy 203.605102 -194.655412)
			(xy 203.615798 -194.655948) (xy 204.332332 -194.655948) (xy 204.342602 -194.655473) (xy 204.361499 -194.64742)
			(xy 204.375735 -194.632613) (xy 204.37983 -194.623182) (xy 204.393903 -194.587477) (xy 204.428231 -194.518831)
			(xy 204.469282 -194.453982) (xy 204.516642 -194.393585) (xy 204.56983 -194.338252) (xy 204.628308 -194.288544)
			(xy 204.691485 -194.244962) (xy 204.758722 -194.207949) (xy 204.829336 -194.177879) (xy 204.902615 -194.155055)
			(xy 204.977816 -194.13971) (xy 205.054179 -194.131999) (xy 205.130929 -194.131999) (xy 205.207292 -194.13971)
			(xy 205.282493 -194.155055) (xy 205.355772 -194.177879) (xy 205.426386 -194.207949) (xy 205.493623 -194.244962)
			(xy 205.5568 -194.288544) (xy 205.615278 -194.338252) (xy 205.668466 -194.393585) (xy 205.715826 -194.453982)
			(xy 205.756877 -194.518831) (xy 205.791205 -194.587477) (xy 205.805278 -194.623182) (xy 205.809357 -194.632629)
			(xy 205.823588 -194.647465) (xy 205.842497 -194.655534) (xy 205.852776 -194.655948) (xy 206.610712 -194.655948)
			(xy 206.622143 -194.655315) (xy 206.64275 -194.645414) (xy 206.657042 -194.62757) (xy 206.660242 -194.616578)
			(xy 206.660242 -194.616324) (xy 206.670057 -194.575671) (xy 206.697406 -194.496634) (xy 206.733258 -194.421073)
			(xy 206.75473 -194.385184) (xy 206.759375 -194.376943) (xy 206.762788 -194.35835) (xy 206.759193 -194.339791)
			(xy 206.754476 -194.33159) (xy 206.732894 -194.295835) (xy 206.696908 -194.220466) (xy 206.669517 -194.141565)
			(xy 206.651061 -194.060111) (xy 206.641767 -193.97711) (xy 206.641192 -193.93535) (xy 206.641647 -193.897931)
			(xy 206.649109 -193.823466) (xy 206.663955 -193.750116) (xy 206.686036 -193.67861) (xy 206.715132 -193.60966)
			(xy 206.750954 -193.543952) (xy 206.793145 -193.482142) (xy 206.841286 -193.424843) (xy 206.86776 -193.398394)
			(xy 206.875126 -193.391028) (xy 206.883 -193.372486) (xy 206.883 -193.348356) (xy 206.883616 -193.323401)
			(xy 206.893361 -193.274452) (xy 206.912467 -193.228344) (xy 206.940201 -193.186849) (xy 206.957422 -193.168778)
			(xy 207.710786 -192.415414) (xy 207.71762 -192.408011) (xy 207.725326 -192.389413) (xy 207.725772 -192.379346)
			(xy 207.725772 -187.908946) (xy 207.725338 -187.898881) (xy 207.717607 -187.880293) (xy 207.710786 -187.872878)
			(xy 205.538832 -185.700924) (xy 205.531431 -185.694086) (xy 205.512832 -185.686372) (xy 205.502764 -185.685938)
			(xy 182.457598 -185.685938) (xy 182.432641 -185.685326) (xy 182.383686 -185.67559) (xy 182.337571 -185.656491)
			(xy 182.296067 -185.628763) (xy 182.27802 -185.611516) (xy 168.733724 -172.06722) (xy 168.725616 -172.059787)
			(xy 168.705042 -172.052075) (xy 168.683131 -172.053709) (xy 168.673272 -172.058584) (xy 168.639606 -172.076426)
			(xy 168.569413 -172.106072) (xy 168.496613 -172.128573) (xy 168.421934 -172.143708) (xy 168.346119 -172.151324)
			(xy 168.30802 -172.151802) (xy 168.307512 -172.151802) (xy 168.267577 -172.151298) (xy 168.188144 -172.14295)
			(xy 168.110019 -172.126345) (xy 168.034057 -172.101665) (xy 167.961092 -172.069179) (xy 167.891922 -172.029245)
			(xy 167.827305 -171.982298) (xy 167.767949 -171.928855) (xy 167.714505 -171.8695) (xy 167.667559 -171.804884)
			(xy 167.627623 -171.735714) (xy 167.595137 -171.662748) (xy 167.570456 -171.586787) (xy 167.553851 -171.508662)
			(xy 167.545502 -171.429229) (xy 167.545004 -171.389294) (xy 167.545004 -171.388024) (xy 167.545188 -171.363828)
			(xy 167.548237 -171.315531) (xy 167.5511 -171.291504) (xy 167.551969 -171.280217) (xy 167.54498 -171.258718)
			(xy 167.529411 -171.242326) (xy 167.519096 -171.237656) (xy 167.492452 -171.226863) (xy 167.442489 -171.198435)
			(xy 167.397353 -171.162837) (xy 167.358065 -171.120874) (xy 167.325512 -171.073495) (xy 167.300431 -171.021771)
			(xy 167.283389 -170.966871) (xy 167.274771 -170.910036) (xy 167.27424 -170.881294) (xy 167.274866 -170.850302)
			(xy 167.284916 -170.789137) (xy 167.304703 -170.730395) (xy 167.31869 -170.702732) (xy 167.326564 -170.688)
			(xy 167.321738 -170.655234) (xy 138.458956 -141.792452) (xy 138.451558 -141.785607) (xy 138.432959 -141.77788)
			(xy 138.422888 -141.777466) (xy 123.385072 -141.777466) (xy 123.375005 -141.777896) (xy 123.356415 -141.785625)
			(xy 123.349004 -141.792452) (xy 121.924826 -143.21663) (xy 121.917981 -143.224029) (xy 121.910254 -143.242627)
			(xy 121.90984 -143.252698) (xy 121.90984 -146.79422) (xy 121.909267 -146.819179) (xy 121.899522 -146.868137)
			(xy 121.880412 -146.914253) (xy 121.852672 -146.955754) (xy 121.835418 -146.973798) (xy 121.352818 -147.456398)
			(xy 121.334777 -147.473657) (xy 121.293283 -147.501413) (xy 121.247165 -147.520523) (xy 121.198201 -147.53025)
			(xy 121.17324 -147.53082) (xy 115.7732 -147.53082) (xy 115.748243 -147.530209) (xy 115.699289 -147.520472)
			(xy 115.653174 -147.501372) (xy 115.611671 -147.473643) (xy 115.593622 -147.456398) (xy 114.996722 -146.859498)
			(xy 114.979463 -146.841457) (xy 114.951708 -146.799963) (xy 114.9326 -146.753845) (xy 114.922877 -146.704881)
			(xy 114.9223 -146.67992) (xy 114.9223 -144.709134) (xy 114.921865 -144.699069) (xy 114.914133 -144.680482)
			(xy 114.907314 -144.673066) (xy 113.57991 -143.345662) (xy 113.572515 -143.338807) (xy 113.553916 -143.331059)
			(xy 113.543842 -143.330676) (xy 106.982514 -143.330676) (xy 106.972464 -143.331183) (xy 106.953905 -143.338906)
			(xy 106.946446 -143.345662) (xy 104.943402 -145.348706) (xy 104.936133 -145.356738) (xy 104.928499 -145.376991)
			(xy 104.92867 -145.387822) (xy 104.92867 -145.388076) (xy 104.930702 -145.442432) (xy 104.930226 -145.481103)
			(xy 104.922394 -145.558046) (xy 104.906815 -145.633802) (xy 104.883647 -145.707591) (xy 104.853129 -145.778657)
			(xy 104.815575 -145.846268) (xy 104.77137 -145.909731) (xy 104.720969 -145.968394) (xy 104.664888 -146.021654)
			(xy 104.603705 -146.068964) (xy 104.538047 -146.109838) (xy 104.468589 -146.143856) (xy 104.396044 -146.170669)
			(xy 104.321158 -146.190001) (xy 104.283002 -146.196304) (xy 104.27081 -146.198082) (xy 104.25176 -146.211798)
			(xy 104.207564 -146.294348) (xy 104.202556 -146.305036) (xy 104.201906 -146.328601) (xy 104.206294 -146.33956)
			(xy 104.206294 -146.339814) (xy 104.223531 -146.377885) (xy 104.250535 -146.456976) (xy 104.268716 -146.538549)
			(xy 104.277855 -146.621623) (xy 104.27843 -146.66341) (xy 104.277907 -146.703344) (xy 104.269557 -146.782775)
			(xy 104.252951 -146.860897) (xy 104.22827 -146.936856) (xy 104.195785 -147.009819) (xy 104.155851 -147.078987)
			(xy 104.108906 -147.143602) (xy 104.055464 -147.202956) (xy 103.996111 -147.256398) (xy 103.931497 -147.303344)
			(xy 103.86233 -147.34328) (xy 103.789367 -147.375766) (xy 103.713409 -147.400448) (xy 103.635286 -147.417056)
			(xy 103.555856 -147.425406) (xy 103.515922 -147.425918) (xy 103.47626 -147.42541) (xy 103.397366 -147.417173)
			(xy 103.319754 -147.400786) (xy 103.244264 -147.376425) (xy 103.171712 -147.344356) (xy 103.102884 -147.304924)
			(xy 103.070406 -147.282154) (xy 103.070152 -147.2819) (xy 103.06264 -147.276987) (xy 103.045334 -147.272263)
			(xy 103.02746 -147.273793) (xy 103.011208 -147.281389) (xy 103.00462 -147.287488) (xy 99.350322 -150.941786)
			(xy 108.742233 -150.941786) (xy 108.746238 -150.836037) (xy 108.758228 -150.730894) (xy 108.778137 -150.626959)
			(xy 108.805848 -150.524827) (xy 108.841205 -150.425083) (xy 108.884003 -150.328299) (xy 108.933999 -150.235029)
			(xy 108.990906 -150.145808) (xy 109.054397 -150.061145) (xy 109.124109 -149.981527) (xy 109.199643 -149.907409)
			(xy 109.280566 -149.839216) (xy 109.366415 -149.777338) (xy 109.456698 -149.722131) (xy 109.550897 -149.673909)
			(xy 109.648474 -149.632949) (xy 109.748869 -149.599487) (xy 109.851507 -149.573713) (xy 109.9558 -149.555775)
			(xy 110.061151 -149.545776) (xy 110.166957 -149.543773) (xy 110.272611 -149.549778) (xy 110.377508 -149.563757)
			(xy 110.481048 -149.585628) (xy 110.582637 -149.615268) (xy 110.681694 -149.652506) (xy 110.777651 -149.697128)
			(xy 110.869958 -149.74888) (xy 110.958087 -149.807465) (xy 111.041533 -149.872547) (xy 111.119817 -149.943753)
			(xy 111.192492 -150.020676) (xy 111.259142 -150.102876) (xy 111.319384 -150.18988) (xy 111.372873 -150.281191)
			(xy 111.419304 -150.376286) (xy 111.458409 -150.47462) (xy 111.489966 -150.575631) (xy 111.513793 -150.678738)
			(xy 111.529754 -150.783352) (xy 111.537758 -150.888874) (xy 111.538258 -150.941786) (xy 111.537758 -150.994698)
			(xy 111.529754 -151.10022) (xy 111.513793 -151.204834) (xy 111.489966 -151.307941) (xy 111.458409 -151.408952)
			(xy 111.419304 -151.507286) (xy 111.372873 -151.602381) (xy 111.319384 -151.693692) (xy 111.259142 -151.780696)
			(xy 111.192492 -151.862896) (xy 111.119817 -151.939819) (xy 111.041533 -152.011025) (xy 110.958087 -152.076107)
			(xy 110.869958 -152.134692) (xy 110.777651 -152.186444) (xy 110.681694 -152.231066) (xy 110.582637 -152.268304)
			(xy 110.481048 -152.297944) (xy 110.377508 -152.319815) (xy 110.272611 -152.333794) (xy 110.166957 -152.339799)
			(xy 110.061151 -152.337796) (xy 109.9558 -152.327797) (xy 109.851507 -152.309859) (xy 109.748869 -152.284085)
			(xy 109.648474 -152.250623) (xy 109.550897 -152.209663) (xy 109.456698 -152.161441) (xy 109.366415 -152.106234)
			(xy 109.280566 -152.044356) (xy 109.199643 -151.976163) (xy 109.124109 -151.902045) (xy 109.054397 -151.822427)
			(xy 108.990906 -151.737764) (xy 108.933999 -151.648543) (xy 108.884003 -151.555273) (xy 108.841205 -151.458489)
			(xy 108.805848 -151.358745) (xy 108.778137 -151.256613) (xy 108.758228 -151.152678) (xy 108.746238 -151.047535)
			(xy 108.742233 -150.941786) (xy 99.350322 -150.941786) (xy 92.156534 -158.135574) (xy 92.138494 -158.152836)
			(xy 92.097002 -158.180597) (xy 92.050883 -158.199712) (xy 92.001918 -158.209442) (xy 91.976956 -158.209996)
			(xy 81.438496 -158.209996) (xy 81.413536 -158.209424) (xy 81.364574 -158.199684) (xy 81.318454 -158.18058)
			(xy 81.276947 -158.152844) (xy 81.258918 -158.135574) (xy 78.337918 -155.214574) (xy 78.331529 -155.208634)
			(xy 78.315802 -155.201118) (xy 78.298459 -155.199364) (xy 78.289912 -155.201112) (xy 78.289658 -155.201112)
			(xy 78.26716 -155.206339) (xy 78.221312 -155.211947) (xy 78.198218 -155.212288) (xy 78.19771 -155.212288)
			(xy 78.170457 -155.211825) (xy 78.116506 -155.204069) (xy 78.064208 -155.188714) (xy 78.014628 -155.166072)
			(xy 77.968775 -155.136604) (xy 77.927583 -155.10091) (xy 77.89189 -155.059717) (xy 77.862423 -155.013863)
			(xy 77.839782 -154.964282) (xy 77.824428 -154.911984) (xy 77.816674 -154.858033) (xy 77.816202 -154.83078)
			(xy 77.816202 -154.830272) (xy 77.816551 -154.807178) (xy 77.822149 -154.761329) (xy 77.827378 -154.738832)
			(xy 77.827378 -154.738578) (xy 77.82908 -154.730031) (xy 77.827288 -154.712707) (xy 77.819835 -154.696966)
			(xy 77.813916 -154.690572) (xy 76.394818 -153.271474) (xy 76.387419 -153.264632) (xy 76.368819 -153.256916)
			(xy 76.35875 -153.256488) (xy 66.872104 -153.256488) (xy 66.847151 -153.255867) (xy 66.798208 -153.246114)
			(xy 66.752107 -153.227) (xy 66.710621 -153.19926) (xy 66.692526 -153.182066) (xy 59.855862 -146.345402)
			(xy 59.848461 -146.338561) (xy 59.829863 -146.33084) (xy 59.819794 -146.330416) (xy 42.527474 -146.330416)
			(xy 42.517406 -146.330844) (xy 42.49881 -146.338567) (xy 42.491406 -146.345402) (xy 35.553396 -153.283412)
			(xy 35.546552 -153.290811) (xy 35.538822 -153.309409) (xy 35.53841 -153.31948) (xy 35.53841 -173.174406)
			(xy 35.537798 -173.199362) (xy 35.52806 -173.248316) (xy 35.508959 -173.29443) (xy 35.481228 -173.335931)
			(xy 35.463988 -173.353984) (xy 34.944304 -173.873668) (xy 34.939224 -173.905926) (xy 34.94659 -173.920658)
			(xy 34.962143 -173.952556) (xy 34.987944 -174.018671) (xy 35.00749 -174.086898) (xy 35.020612 -174.156645)
			(xy 35.027198 -174.22731) (xy 35.027616 -174.262796) (xy 35.027093 -174.30273) (xy 35.018745 -174.382161)
			(xy 35.00214 -174.460285) (xy 34.97746 -174.536244) (xy 34.944975 -174.609208) (xy 34.905041 -174.678376)
			(xy 34.858096 -174.742992) (xy 34.804654 -174.802346) (xy 34.745301 -174.855789) (xy 34.680686 -174.902735)
			(xy 34.611519 -174.94267) (xy 34.538555 -174.975156) (xy 34.462596 -174.999837) (xy 34.384473 -175.016444)
			(xy 34.305042 -175.024793) (xy 34.265108 -175.025304) (xy 34.229622 -175.024899) (xy 34.158957 -175.018308)
			(xy 34.089209 -175.005182) (xy 34.020982 -174.985635) (xy 33.954866 -174.959836) (xy 33.92297 -174.944278)
			(xy 33.908238 -174.936912) (xy 33.87598 -174.941992) (xy 24.80183 -184.016142) (xy 24.783788 -184.0334)
			(xy 24.742294 -184.061153) (xy 24.696176 -184.080262) (xy 24.647212 -184.089989) (xy 24.622252 -184.090564)
			(xy 15.765272 -184.090564) (xy 15.755205 -184.090994) (xy 15.736614 -184.098723) (xy 15.729204 -184.10555)
			(xy 13.80871 -186.026044) (xy 13.801869 -186.033444) (xy 13.794149 -186.052043) (xy 13.793724 -186.062112)
			(xy 13.793724 -194.37096) (xy 13.794159 -194.381025) (xy 13.801891 -194.399611) (xy 13.80871 -194.407028)
			(xy 14.763242 -195.36156) (xy 14.770641 -195.368404) (xy 14.789239 -195.376129) (xy 14.79931 -195.376546)
		)
		(stroke
			(width 0)
			(type solid)
		)
		(fill yes)
		(layer "In9.Cu")
		(net "P12V_MEM_CPU1")
	)
	(gr_poly
		(pts
			(xy 429.760634 -195.399406) (xy 429.772191 -195.398791) (xy 429.792949 -195.388608) (xy 429.800512 -195.379848)
			(xy 429.824565 -195.349943) (xy 429.87775 -195.29461) (xy 429.936226 -195.2449) (xy 429.999401 -195.201318)
			(xy 430.066635 -195.164304) (xy 430.137248 -195.134233) (xy 430.210525 -195.11141) (xy 430.285724 -195.096064)
			(xy 430.362085 -195.088353) (xy 430.438835 -195.088353) (xy 430.515196 -195.096064) (xy 430.590395 -195.11141)
			(xy 430.663672 -195.134233) (xy 430.734285 -195.164304) (xy 430.801519 -195.201318) (xy 430.864694 -195.2449)
			(xy 430.92317 -195.29461) (xy 430.976355 -195.349943) (xy 431.000408 -195.379848) (xy 431.007947 -195.388642)
			(xy 431.028717 -195.398841) (xy 431.040286 -195.399406) (xy 431.964338 -195.399406) (xy 431.974581 -195.398944)
			(xy 431.993451 -195.39097) (xy 432.00774 -195.376291) (xy 432.011836 -195.366894) (xy 432.026355 -195.330391)
			(xy 432.061983 -195.260371) (xy 432.104738 -195.194461) (xy 432.154152 -195.133384) (xy 432.209682 -195.077809)
			(xy 432.27072 -195.028347) (xy 432.336596 -194.985539) (xy 432.406587 -194.949856) (xy 432.479927 -194.921688)
			(xy 432.55581 -194.901344) (xy 432.633405 -194.889048) (xy 432.71186 -194.884934) (xy 432.790315 -194.889048)
			(xy 432.86791 -194.901344) (xy 432.943793 -194.921688) (xy 433.017133 -194.949856) (xy 433.087124 -194.985539)
			(xy 433.153 -195.028347) (xy 433.214038 -195.077809) (xy 433.269568 -195.133384) (xy 433.318982 -195.194461)
			(xy 433.361737 -195.260371) (xy 433.397365 -195.330391) (xy 433.411884 -195.366894) (xy 433.415986 -195.376303)
			(xy 433.430236 -195.391048) (xy 433.449127 -195.399024) (xy 433.459382 -195.399406) (xy 437.311292 -195.399406)
			(xy 437.322709 -195.398945) (xy 437.343334 -195.389159) (xy 437.350916 -195.38061) (xy 437.376437 -195.349765)
			(xy 437.43294 -195.293043) (xy 437.495075 -195.242554) (xy 437.562159 -195.198854) (xy 437.633452 -195.162424)
			(xy 437.70817 -195.133665) (xy 437.785491 -195.112894) (xy 437.864562 -195.100338) (xy 437.944514 -195.096138)
			(xy 438.024466 -195.100338) (xy 438.103537 -195.112894) (xy 438.180858 -195.133665) (xy 438.255576 -195.162424)
			(xy 438.326869 -195.198854) (xy 438.393953 -195.242554) (xy 438.456088 -195.293043) (xy 438.512591 -195.349765)
			(xy 438.538112 -195.38061) (xy 438.545782 -195.389043) (xy 438.566353 -195.398797) (xy 438.577736 -195.399406)
			(xy 439.508392 -195.399406) (xy 439.518628 -195.398934) (xy 439.537482 -195.390949) (xy 439.551754 -195.376269)
			(xy 439.55589 -195.366894) (xy 439.570409 -195.330391) (xy 439.606037 -195.260371) (xy 439.648792 -195.194461)
			(xy 439.698206 -195.133384) (xy 439.753736 -195.077809) (xy 439.814774 -195.028347) (xy 439.88065 -194.985539)
			(xy 439.950641 -194.949856) (xy 440.023981 -194.921688) (xy 440.099864 -194.901344) (xy 440.177459 -194.889048)
			(xy 440.255914 -194.884934) (xy 440.334369 -194.889048) (xy 440.411964 -194.901344) (xy 440.487847 -194.921688)
			(xy 440.561187 -194.949856) (xy 440.631178 -194.985539) (xy 440.697054 -195.028347) (xy 440.758092 -195.077809)
			(xy 440.813622 -195.133384) (xy 440.863036 -195.194461) (xy 440.905791 -195.260371) (xy 440.941419 -195.330391)
			(xy 440.955938 -195.366894) (xy 440.960042 -195.376297) (xy 440.974295 -195.391027) (xy 440.993185 -195.398983)
			(xy 441.003436 -195.399406) (xy 444.856616 -195.399406) (xy 444.867947 -195.398804) (xy 444.888401 -195.389049)
			(xy 444.895986 -195.38061) (xy 444.921516 -195.349923) (xy 444.977972 -195.293482) (xy 445.040017 -195.24325)
			(xy 445.106973 -195.199778) (xy 445.178105 -195.163541) (xy 445.252635 -195.134937) (xy 445.329745 -195.114279)
			(xy 445.408593 -195.101793) (xy 445.488314 -195.097616) (xy 445.568035 -195.101793) (xy 445.646883 -195.114279)
			(xy 445.723993 -195.134937) (xy 445.798523 -195.163541) (xy 445.869655 -195.199778) (xy 445.936611 -195.24325)
			(xy 445.998656 -195.293482) (xy 446.055112 -195.349923) (xy 446.080642 -195.38061) (xy 446.088263 -195.388998)
			(xy 446.108697 -195.398738) (xy 446.120012 -195.399406) (xy 447.052446 -195.399406) (xy 447.062688 -195.398943)
			(xy 447.081555 -195.390967) (xy 447.095842 -195.376287) (xy 447.099944 -195.366894) (xy 447.114463 -195.330391)
			(xy 447.150091 -195.260371) (xy 447.192846 -195.194461) (xy 447.24226 -195.133384) (xy 447.29779 -195.077809)
			(xy 447.358828 -195.028347) (xy 447.424704 -194.985539) (xy 447.494695 -194.949856) (xy 447.568035 -194.921688)
			(xy 447.643918 -194.901344) (xy 447.721513 -194.889048) (xy 447.799968 -194.884934) (xy 447.878423 -194.889048)
			(xy 447.956018 -194.901344) (xy 448.031901 -194.921688) (xy 448.105241 -194.949856) (xy 448.175232 -194.985539)
			(xy 448.241108 -195.028347) (xy 448.302146 -195.077809) (xy 448.357676 -195.133384) (xy 448.40709 -195.194461)
			(xy 448.449845 -195.260371) (xy 448.485473 -195.330391) (xy 448.499992 -195.366894) (xy 448.504094 -195.376302)
			(xy 448.518344 -195.391045) (xy 448.537236 -195.399018) (xy 448.54749 -195.399406) (xy 452.46036 -195.399406)
			(xy 452.470323 -195.398921) (xy 452.488749 -195.391336) (xy 452.496174 -195.384674) (xy 452.524719 -195.357139)
			(xy 452.586582 -195.307502) (xy 452.653265 -195.264557) (xy 452.724046 -195.228769) (xy 452.798162 -195.200525)
			(xy 452.874809 -195.180129) (xy 452.95316 -195.167803) (xy 453.032368 -195.163679) (xy 453.111576 -195.167803)
			(xy 453.189927 -195.180129) (xy 453.266574 -195.200525) (xy 453.34069 -195.228769) (xy 453.411471 -195.264557)
			(xy 453.478154 -195.307502) (xy 453.540017 -195.357139) (xy 453.568562 -195.384674) (xy 453.575968 -195.391367)
			(xy 453.594405 -195.398967) (xy 453.604376 -195.399406) (xy 454.596246 -195.399406) (xy 454.606488 -195.398943)
			(xy 454.625355 -195.390967) (xy 454.639642 -195.376287) (xy 454.643744 -195.366894) (xy 454.657638 -195.3319)
			(xy 454.691474 -195.264632) (xy 454.731883 -195.201097) (xy 454.778459 -195.141932) (xy 454.830732 -195.087736)
			(xy 454.888175 -195.039053) (xy 454.95021 -194.996375) (xy 455.016211 -194.960131) (xy 455.085513 -194.930687)
			(xy 455.157418 -194.90834) (xy 455.231201 -194.893314) (xy 455.306119 -194.885762) (xy 455.343768 -194.88531)
			(xy 455.344784 -194.88531) (xy 455.377331 -194.885684) (xy 455.442177 -194.891372) (xy 455.506287 -194.902656)
			(xy 455.537824 -194.91071) (xy 455.549361 -194.913247) (xy 455.572524 -194.908744) (xy 455.582274 -194.902074)
			(xy 455.645774 -194.853052) (xy 455.654641 -194.845469) (xy 455.664961 -194.82457) (xy 455.665586 -194.81292)
			(xy 455.665586 -182.640986) (xy 455.66516 -182.630917) (xy 455.65744 -182.612318) (xy 455.6506 -182.604918)
			(xy 443.527434 -170.481752) (xy 443.503812 -170.474386) (xy 443.491366 -170.476672) (xy 443.457068 -170.482622)
			(xy 443.387744 -170.48898) (xy 443.352936 -170.489372) (xy 443.313001 -170.488869) (xy 443.233567 -170.480524)
			(xy 443.155441 -170.46392) (xy 443.079479 -170.439241) (xy 443.006512 -170.406756) (xy 442.937341 -170.366822)
			(xy 442.872724 -170.319875) (xy 442.813368 -170.266432) (xy 442.759925 -170.207076) (xy 442.712978 -170.142459)
			(xy 442.673044 -170.073288) (xy 442.640559 -170.000321) (xy 442.61588 -169.924359) (xy 442.599276 -169.846233)
			(xy 442.590931 -169.766799) (xy 442.590428 -169.726864) (xy 442.590839 -169.692057) (xy 442.597196 -169.622734)
			(xy 442.603128 -169.588434) (xy 442.605414 -169.575988) (xy 442.598048 -169.552366) (xy 440.622436 -167.576754)
			(xy 440.614283 -167.569395) (xy 440.593695 -167.561809) (xy 440.571818 -167.563486) (xy 440.561984 -167.568372)
			(xy 440.528032 -167.586599) (xy 440.457176 -167.616906) (xy 440.383625 -167.639909) (xy 440.308127 -167.655374)
			(xy 440.231455 -167.663142) (xy 440.192922 -167.663622) (xy 440.152986 -167.663118) (xy 440.073552 -167.654772)
			(xy 439.995425 -167.638168) (xy 439.919461 -167.613488) (xy 439.846494 -167.581003) (xy 439.777322 -167.541069)
			(xy 439.712703 -167.494123) (xy 439.653346 -167.44068) (xy 439.5999 -167.381325) (xy 439.552951 -167.316708)
			(xy 439.513013 -167.247538) (xy 439.480525 -167.174572) (xy 439.455842 -167.09861) (xy 439.439234 -167.020484)
			(xy 439.430883 -166.94105) (xy 439.430414 -166.901114) (xy 439.430897 -166.862581) (xy 439.438666 -166.785909)
			(xy 439.454128 -166.71041) (xy 439.477124 -166.636856) (xy 439.50742 -166.565995) (xy 439.525664 -166.532052)
			(xy 439.53052 -166.522205) (xy 439.532207 -166.500336) (xy 439.52464 -166.479749) (xy 439.517282 -166.4716)
			(xy 424.576748 -151.531066) (xy 424.56935 -151.52422) (xy 424.550751 -151.516495) (xy 424.54068 -151.51608)
			(xy 388.398766 -151.51608) (xy 388.388698 -151.516509) (xy 388.370101 -151.52423) (xy 388.362698 -151.531066)
			(xy 387.161278 -152.73274) (xy 387.154301 -152.740337) (xy 387.146589 -152.759445) (xy 387.147061 -152.780046)
			(xy 387.150864 -152.789636) (xy 387.189726 -152.87625) (xy 387.194401 -152.885361) (xy 387.209487 -152.899185)
			(xy 387.22876 -152.906056) (xy 387.239002 -152.905968) (xy 387.239256 -152.905968) (xy 387.293358 -152.904444)
			(xy 387.293866 -152.904444) (xy 387.332117 -152.904855) (xy 387.408338 -152.911422) (xy 387.483715 -152.924502)
			(xy 387.557692 -152.943999) (xy 387.59384 -152.956514) (xy 387.602156 -152.9591) (xy 387.61956 -152.9591)
			(xy 387.627876 -152.956514) (xy 387.663995 -152.94401) (xy 387.737905 -152.924506) (xy 387.813218 -152.911426)
			(xy 387.889376 -152.904866) (xy 387.927596 -152.904444) (xy 387.928358 -152.904444) (xy 387.969466 -152.904917)
			(xy 388.051331 -152.912498) (xy 388.132148 -152.927599) (xy 388.211228 -152.950091) (xy 388.287895 -152.979783)
			(xy 388.361495 -153.016421) (xy 388.431402 -153.059693) (xy 388.497019 -153.10923) (xy 388.557786 -153.164609)
			(xy 388.613185 -153.225358) (xy 388.662743 -153.290958) (xy 388.706037 -153.360851) (xy 388.7427 -153.43444)
			(xy 388.772417 -153.511097) (xy 388.794935 -153.590169) (xy 388.810062 -153.670981) (xy 388.81767 -153.752844)
			(xy 388.81812 -153.793952) (xy 388.817682 -153.83224) (xy 388.811055 -153.908528) (xy 388.797904 -153.983967)
			(xy 388.778327 -154.057998) (xy 388.765796 -154.09418) (xy 388.763135 -154.102617) (xy 388.763119 -154.120294)
			(xy 388.765796 -154.128724) (xy 388.778362 -154.164895) (xy 388.797952 -154.238926) (xy 388.811098 -154.314369)
			(xy 388.817701 -154.390662) (xy 388.81812 -154.428952) (xy 388.817668 -154.468869) (xy 388.810472 -154.548377)
			(xy 388.796169 -154.626919) (xy 388.774876 -154.70386) (xy 388.761224 -154.741372) (xy 388.758387 -154.750041)
			(xy 388.75837 -154.768269) (xy 388.761224 -154.776932) (xy 388.774842 -154.814455) (xy 388.796115 -154.891398)
			(xy 388.810421 -154.969935) (xy 388.817645 -155.049438) (xy 388.81812 -155.089352) (xy 388.817682 -155.12764)
			(xy 388.811055 -155.203928) (xy 388.797904 -155.279367) (xy 388.778327 -155.353398) (xy 388.765796 -155.38958)
			(xy 388.763135 -155.398017) (xy 388.763119 -155.415694) (xy 388.765796 -155.424124) (xy 388.778362 -155.460295)
			(xy 388.797952 -155.534326) (xy 388.811098 -155.609769) (xy 388.817701 -155.686062) (xy 388.81812 -155.724352)
			(xy 388.817711 -155.763146) (xy 388.81095 -155.840438) (xy 388.797477 -155.916847) (xy 388.777393 -155.99179)
			(xy 388.764526 -156.02839) (xy 388.761869 -156.036827) (xy 388.761857 -156.054502) (xy 388.764526 -156.062934)
			(xy 388.777385 -156.099536) (xy 388.797452 -156.174482) (xy 388.810924 -156.25089) (xy 388.8177 -156.328179)
			(xy 388.81812 -156.366972) (xy 388.817686 -156.40526) (xy 388.811065 -156.481551) (xy 388.79792 -156.556992)
			(xy 388.77835 -156.631026) (xy 388.765796 -156.6672) (xy 388.763138 -156.675637) (xy 388.763129 -156.693311)
			(xy 388.765796 -156.701744) (xy 388.778365 -156.737915) (xy 388.797962 -156.811945) (xy 388.811114 -156.887387)
			(xy 388.817725 -156.963682) (xy 388.81812 -157.001972) (xy 388.817661 -157.043076) (xy 388.810078 -157.124934)
			(xy 388.794975 -157.205743) (xy 388.77248 -157.284814) (xy 388.742785 -157.361472) (xy 388.706143 -157.435063)
			(xy 388.662868 -157.504959) (xy 388.613328 -157.570564) (xy 388.557946 -157.631318) (xy 388.497194 -157.686702)
			(xy 388.431592 -157.736245) (xy 388.361698 -157.779524) (xy 388.288108 -157.816169) (xy 388.211452 -157.845867)
			(xy 388.132382 -157.868366) (xy 388.051574 -157.883473) (xy 387.969716 -157.891059) (xy 387.928612 -157.89148)
			(xy 387.92785 -157.89148) (xy 387.889599 -157.891065) (xy 387.813381 -157.88449) (xy 387.738007 -157.871402)
			(xy 387.664033 -157.851898) (xy 387.627876 -157.83941) (xy 387.61956 -157.836824) (xy 387.602156 -157.836824)
			(xy 387.59384 -157.83941) (xy 387.557721 -157.851915) (xy 387.483811 -157.871419) (xy 387.408498 -157.8845)
			(xy 387.33234 -157.891061) (xy 387.29412 -157.89148) (xy 387.293358 -157.89148) (xy 387.252252 -157.891004)
			(xy 387.170391 -157.883416) (xy 387.08958 -157.868309) (xy 387.010506 -157.845812) (xy 386.933845 -157.816116)
			(xy 386.86025 -157.779476) (xy 386.790349 -157.736202) (xy 386.724738 -157.686665) (xy 386.663976 -157.631287)
			(xy 386.608582 -157.570539) (xy 386.559028 -157.504941) (xy 386.515736 -157.435051) (xy 386.479077 -157.361466)
			(xy 386.449361 -157.284812) (xy 386.426844 -157.205744) (xy 386.411716 -157.124936) (xy 386.404107 -157.043078)
			(xy 386.403596 -157.001972) (xy 386.404033 -156.963684) (xy 386.410659 -156.887395) (xy 386.423808 -156.811956)
			(xy 386.443383 -156.737924) (xy 386.45592 -156.701744) (xy 386.458567 -156.693308) (xy 386.458558 -156.67564)
			(xy 386.45592 -156.6672) (xy 386.443353 -156.631029) (xy 386.42376 -156.556998) (xy 386.410613 -156.481556)
			(xy 386.404007 -156.405262) (xy 386.403596 -156.366972) (xy 386.404004 -156.328178) (xy 386.410763 -156.250885)
			(xy 386.424234 -156.174476) (xy 386.444317 -156.099532) (xy 386.45719 -156.062934) (xy 386.459833 -156.054497)
			(xy 386.459821 -156.036832) (xy 386.45719 -156.02839) (xy 386.444334 -155.991787) (xy 386.424273 -155.916841)
			(xy 386.410807 -155.840433) (xy 386.404038 -155.763144) (xy 386.403596 -155.724352) (xy 386.404033 -155.686064)
			(xy 386.410661 -155.609776) (xy 386.423812 -155.534337) (xy 386.443388 -155.460306) (xy 386.45592 -155.424124)
			(xy 386.458564 -155.415688) (xy 386.458548 -155.398023) (xy 386.45592 -155.38958) (xy 386.443354 -155.353409)
			(xy 386.423763 -155.279378) (xy 386.410617 -155.203936) (xy 386.404013 -155.127642) (xy 386.403596 -155.089352)
			(xy 386.404048 -155.049435) (xy 386.411244 -154.969927) (xy 386.425546 -154.891385) (xy 386.446839 -154.814444)
			(xy 386.460492 -154.776932) (xy 386.463312 -154.768263) (xy 386.463296 -154.750047) (xy 386.460492 -154.741372)
			(xy 386.446873 -154.70385) (xy 386.4256 -154.626906) (xy 386.411294 -154.548369) (xy 386.404069 -154.468866)
			(xy 386.403596 -154.428952) (xy 386.404033 -154.390664) (xy 386.410661 -154.314376) (xy 386.423812 -154.238937)
			(xy 386.443388 -154.164906) (xy 386.45592 -154.128724) (xy 386.458564 -154.120288) (xy 386.458548 -154.102623)
			(xy 386.45592 -154.09418) (xy 386.443354 -154.058009) (xy 386.423763 -153.983978) (xy 386.410617 -153.908536)
			(xy 386.404013 -153.832242) (xy 386.403596 -153.793952) (xy 386.405374 -153.740104) (xy 386.405587 -153.729805)
			(xy 386.398767 -153.710387) (xy 386.384846 -153.695228) (xy 386.375656 -153.690574) (xy 386.289042 -153.651458)
			(xy 386.279458 -153.647684) (xy 386.258882 -153.64729) (xy 386.239785 -153.65496) (xy 386.232146 -153.661872)
			(xy 382.42113 -157.472888) (xy 382.417828 -157.47873) (xy 382.397499 -157.512703) (xy 382.350838 -157.576668)
			(xy 382.297805 -157.635458) (xy 382.23897 -157.688441) (xy 382.174966 -157.735049) (xy 382.140968 -157.755336)
			(xy 382.13538 -157.758638) (xy 380.89586 -158.997904) (xy 380.87782 -159.015166) (xy 380.836328 -159.042928)
			(xy 380.790209 -159.062046) (xy 380.741244 -159.07178) (xy 380.716282 -159.072326) (xy 365.43742 -159.072326)
			(xy 365.412466 -159.071707) (xy 365.36352 -159.061957) (xy 365.317416 -159.042847) (xy 365.275924 -159.015112)
			(xy 365.257842 -158.997904) (xy 360.934 -154.674062) (xy 360.916737 -154.656022) (xy 360.888974 -154.61453)
			(xy 360.869857 -154.568412) (xy 360.860121 -154.519446) (xy 360.859578 -154.494484) (xy 360.859578 -153.646378)
			(xy 360.859061 -153.635874) (xy 360.850671 -153.616615) (xy 360.835294 -153.602302) (xy 360.825542 -153.598372)
			(xy 360.735118 -153.566876) (xy 360.725083 -153.563904) (xy 360.704231 -153.56541) (xy 360.685684 -153.57506)
			(xy 360.67873 -153.582878) (xy 360.678476 -153.583132) (xy 360.645507 -153.623747) (xy 360.57438 -153.700469)
			(xy 360.497716 -153.771659) (xy 360.415944 -153.836918) (xy 360.329522 -153.89588) (xy 360.238933 -153.948216)
			(xy 360.144686 -153.993633) (xy 360.047306 -154.031876) (xy 359.94734 -154.062731) (xy 359.845346 -154.086026)
			(xy 359.741897 -154.101631) (xy 359.63757 -154.109457) (xy 359.58526 -154.109928) (xy 359.532987 -154.109438)
			(xy 359.428735 -154.101622) (xy 359.325358 -154.086038) (xy 359.223434 -154.062772) (xy 359.123535 -154.031955)
			(xy 359.026217 -153.993758) (xy 358.932026 -153.948395) (xy 358.841488 -153.896121) (xy 358.75511 -153.837227)
			(xy 358.673375 -153.772043) (xy 358.596739 -153.700933) (xy 358.525631 -153.624295) (xy 358.460449 -153.542558)
			(xy 358.401558 -153.456178) (xy 358.349286 -153.365639) (xy 358.303926 -153.271446) (xy 358.265732 -153.174128)
			(xy 358.234918 -153.074227) (xy 358.211654 -152.972303) (xy 358.196073 -152.868925) (xy 358.188261 -152.764673)
			(xy 358.188261 -152.660127) (xy 358.196073 -152.555875) (xy 358.211654 -152.452497) (xy 358.234918 -152.350573)
			(xy 358.265732 -152.250672) (xy 358.303926 -152.153354) (xy 358.349286 -152.059161) (xy 358.401558 -151.968622)
			(xy 358.460449 -151.882242) (xy 358.525631 -151.800505) (xy 358.596739 -151.723867) (xy 358.673375 -151.652757)
			(xy 358.75511 -151.587573) (xy 358.841488 -151.528679) (xy 358.932026 -151.476405) (xy 359.026217 -151.431042)
			(xy 359.123535 -151.392845) (xy 359.223434 -151.362028) (xy 359.325358 -151.338762) (xy 359.428735 -151.323178)
			(xy 359.532987 -151.315362) (xy 359.58526 -151.314912) (xy 359.637571 -151.315388) (xy 359.741899 -151.323208)
			(xy 359.84535 -151.338807) (xy 359.947346 -151.362098) (xy 360.047314 -151.39295) (xy 360.144696 -151.431191)
			(xy 360.238946 -151.476607) (xy 360.329536 -151.528942) (xy 360.415959 -151.587905) (xy 360.497731 -151.653165)
			(xy 360.574394 -151.724357) (xy 360.64552 -151.801082) (xy 360.678476 -151.841708) (xy 360.67873 -151.841962)
			(xy 360.685686 -151.849788) (xy 360.704221 -151.859484) (xy 360.725085 -151.860964) (xy 360.735118 -151.857964)
			(xy 360.825542 -151.826468) (xy 360.835294 -151.822524) (xy 360.850704 -151.808239) (xy 360.859084 -151.78897)
			(xy 360.859578 -151.778462) (xy 360.859578 -151.095202) (xy 360.859155 -151.085132) (xy 360.851438 -151.066529)
			(xy 360.844592 -151.059134) (xy 344.769948 -134.98449) (xy 344.762551 -134.977642) (xy 344.743952 -134.969912)
			(xy 344.73388 -134.969504) (xy 331.345286 -134.969504) (xy 331.334867 -134.970018) (xy 331.315741 -134.978293)
			(xy 331.308202 -134.985506) (xy 331.288405 -135.005888) (xy 331.243854 -135.041152) (xy 331.194567 -135.069421)
			(xy 331.141634 -135.090072) (xy 331.086225 -135.102648) (xy 331.029564 -135.106871) (xy 330.972903 -135.102648)
			(xy 330.917494 -135.090072) (xy 330.864561 -135.069421) (xy 330.815274 -135.041152) (xy 330.770723 -135.005888)
			(xy 330.750926 -134.985506) (xy 330.74343 -134.978231) (xy 330.724277 -134.969949) (xy 330.713842 -134.969504)
			(xy 330.14793 -134.969504) (xy 330.137262 -134.97052) (xy 330.12634 -134.97306) (xy 330.116688 -134.976108)
			(xy 330.092725 -134.985969) (xy 330.042806 -134.999866) (xy 329.991467 -135.006889) (xy 329.965558 -135.00735)
			(xy 329.96505 -135.00735) (xy 329.938264 -135.006891) (xy 329.885219 -134.9994) (xy 329.833736 -134.984585)
			(xy 329.809094 -134.974076) (xy 329.799188 -134.969504) (xy 307.893466 -134.969504) (xy 307.883399 -134.969934)
			(xy 307.864804 -134.977657) (xy 307.857398 -134.98449) (xy 296.820844 -146.021044) (xy 296.814 -146.028443)
			(xy 296.806274 -146.047041) (xy 296.805858 -146.057112) (xy 296.805858 -146.996658) (xy 296.806133 -147.004621)
			(xy 296.811061 -147.019765) (xy 296.81551 -147.026376) (xy 296.838368 -147.058913) (xy 296.877954 -147.12788)
			(xy 296.910152 -147.200591) (xy 296.93461 -147.276257) (xy 296.951065 -147.354057) (xy 296.959336 -147.433146)
			(xy 296.959336 -147.512667) (xy 296.951063 -147.591756) (xy 296.934607 -147.669555) (xy 296.910147 -147.745221)
			(xy 296.877948 -147.817931) (xy 296.838361 -147.886898) (xy 296.81551 -147.91944) (xy 296.811101 -147.92607)
			(xy 296.806179 -147.941203) (xy 296.805858 -147.949158) (xy 296.805858 -169.490898) (xy 296.806103 -169.49808)
			(xy 296.8101 -169.511876) (xy 296.813732 -169.518076) (xy 296.834433 -169.551491) (xy 296.869612 -169.621788)
			(xy 296.897369 -169.695334) (xy 296.917408 -169.771345) (xy 296.929516 -169.849016) (xy 296.933565 -169.92752)
			(xy 296.929512 -170.006024) (xy 296.9174 -170.083694) (xy 296.897357 -170.159705) (xy 296.869596 -170.233249)
			(xy 296.834413 -170.303544) (xy 296.813732 -170.336972) (xy 296.810101 -170.343172) (xy 296.80611 -170.356969)
			(xy 296.805858 -170.36415) (xy 296.805858 -176.49063) (xy 296.805284 -176.515589) (xy 296.795538 -176.564547)
			(xy 296.776428 -176.610662) (xy 296.748688 -176.652162) (xy 296.731436 -176.670208) (xy 291.987986 -181.413658)
			(xy 291.969945 -181.430919) (xy 291.928452 -181.45868) (xy 291.882334 -181.477797) (xy 291.83337 -181.487534)
			(xy 291.808408 -181.48808) (xy 266.202922 -181.48808) (xy 266.192858 -181.488517) (xy 266.174272 -181.496249)
			(xy 266.166854 -181.503066) (xy 264.099802 -183.570118) (xy 264.092958 -183.577518) (xy 264.08523 -183.596115)
			(xy 264.084816 -183.606186) (xy 264.084816 -193.108834) (xy 264.08538 -193.12046) (xy 264.095557 -193.141368)
			(xy 264.104374 -193.148966) (xy 264.16762 -193.198242) (xy 264.177009 -193.204917) (xy 264.199493 -193.209832)
			(xy 264.2108 -193.20764) (xy 264.211054 -193.20764) (xy 264.255667 -193.19721) (xy 264.3466 -193.185998)
			(xy 264.39241 -193.185288) (xy 264.429979 -193.185743) (xy 264.50474 -193.193248) (xy 264.578376 -193.208191)
			(xy 264.650148 -193.230424) (xy 264.719337 -193.259723) (xy 264.785249 -193.295795) (xy 264.847224 -193.338277)
			(xy 264.904639 -193.386743) (xy 264.95692 -193.440709) (xy 265.003542 -193.499632) (xy 265.044037 -193.562923)
			(xy 265.078 -193.629945) (xy 265.091926 -193.66484) (xy 265.096012 -193.674201) (xy 265.110185 -193.688885)
			(xy 265.128966 -193.696867) (xy 265.13917 -193.697352) (xy 265.98372 -193.697352) (xy 265.993241 -193.696953)
			(xy 266.010966 -193.689994) (xy 266.024927 -193.677044) (xy 266.02944 -193.66865) (xy 266.046527 -193.634562)
			(xy 266.086642 -193.569712) (xy 266.133133 -193.509268) (xy 266.185519 -193.453855) (xy 266.24326 -193.404047)
			(xy 266.305758 -193.360356) (xy 266.372368 -193.323236) (xy 266.442403 -193.293069) (xy 266.515137 -193.270166)
			(xy 266.589821 -193.254765) (xy 266.665682 -193.247025) (xy 266.741938 -193.247025) (xy 266.817799 -193.254765)
			(xy 266.892483 -193.270166) (xy 266.965217 -193.293069) (xy 267.035252 -193.323236) (xy 267.101862 -193.360356)
			(xy 267.16436 -193.404047) (xy 267.222101 -193.453855) (xy 267.274487 -193.509268) (xy 267.320978 -193.569712)
			(xy 267.361093 -193.634562) (xy 267.37818 -193.66865) (xy 267.382678 -193.677055) (xy 267.396648 -193.690008)
			(xy 267.414376 -193.696982) (xy 267.4239 -193.697352) (xy 268.26083 -193.697352) (xy 268.268241 -193.697093)
			(xy 268.282435 -193.692826) (xy 268.28877 -193.68897) (xy 268.311525 -193.674442) (xy 268.360387 -193.651481)
			(xy 268.412075 -193.635896) (xy 268.465484 -193.628019) (xy 268.519472 -193.628019) (xy 268.572881 -193.635896)
			(xy 268.624569 -193.651481) (xy 268.673431 -193.674442) (xy 268.696186 -193.68897) (xy 268.702514 -193.692841)
			(xy 268.716713 -193.697114) (xy 268.724126 -193.697352) (xy 270.044418 -193.697352) (xy 270.054611 -193.696842)
			(xy 270.073362 -193.688829) (xy 270.087548 -193.674179) (xy 270.091662 -193.66484) (xy 270.105643 -193.629972)
			(xy 270.139617 -193.562965) (xy 270.180119 -193.499689) (xy 270.226743 -193.440779) (xy 270.279022 -193.386825)
			(xy 270.336432 -193.338366) (xy 270.398399 -193.295889) (xy 270.464301 -193.259818) (xy 270.533479 -193.230516)
			(xy 270.60524 -193.208276) (xy 270.678864 -193.19332) (xy 270.753614 -193.185798) (xy 270.791178 -193.185288)
			(xy 270.830686 -193.185796) (xy 270.909263 -193.194103) (xy 270.986531 -193.210626) (xy 271.061633 -193.235184)
			(xy 271.133736 -193.267503) (xy 271.202041 -193.307226) (xy 271.265789 -193.353911) (xy 271.295368 -193.380106)
			(xy 271.295622 -193.38036) (xy 271.302866 -193.386268) (xy 271.320319 -193.392922) (xy 271.329658 -193.393314)
			(xy 271.397984 -193.393314) (xy 271.407339 -193.392998) (xy 271.424818 -193.386339) (xy 271.43202 -193.38036)
			(xy 271.432274 -193.380106) (xy 271.461859 -193.35392) (xy 271.525608 -193.307239) (xy 271.593912 -193.267521)
			(xy 271.666015 -193.235206) (xy 271.741116 -193.210653) (xy 271.818382 -193.194134) (xy 271.896958 -193.185831)
			(xy 271.936464 -193.185288) (xy 271.974031 -193.185745) (xy 272.048789 -193.193255) (xy 272.122421 -193.208203)
			(xy 272.194189 -193.230439) (xy 272.263374 -193.259741) (xy 272.329282 -193.295815) (xy 272.391252 -193.338298)
			(xy 272.448663 -193.386765) (xy 272.500939 -193.440731) (xy 272.547557 -193.499654) (xy 272.588049 -193.562943)
			(xy 272.622009 -193.629965) (xy 272.63598 -193.66484) (xy 272.640064 -193.674206) (xy 272.654234 -193.688903)
			(xy 272.673017 -193.696902) (xy 272.683224 -193.697352) (xy 273.527774 -193.697352) (xy 273.5373 -193.696961)
			(xy 273.555038 -193.690012) (xy 273.569012 -193.677064) (xy 273.573494 -193.66865) (xy 273.590581 -193.634562)
			(xy 273.630696 -193.569712) (xy 273.677187 -193.509268) (xy 273.729573 -193.453855) (xy 273.787314 -193.404047)
			(xy 273.849812 -193.360356) (xy 273.916422 -193.323236) (xy 273.986457 -193.293069) (xy 274.059191 -193.270166)
			(xy 274.133875 -193.254765) (xy 274.209736 -193.247025) (xy 274.285992 -193.247025) (xy 274.361853 -193.254765)
			(xy 274.436537 -193.270166) (xy 274.509271 -193.293069) (xy 274.579306 -193.323236) (xy 274.645916 -193.360356)
			(xy 274.708414 -193.404047) (xy 274.766155 -193.453855) (xy 274.818541 -193.509268) (xy 274.865032 -193.569712)
			(xy 274.905147 -193.634562) (xy 274.922234 -193.66865) (xy 274.926735 -193.677049) (xy 274.940707 -193.689987)
			(xy 274.958433 -193.696943) (xy 274.967954 -193.697352) (xy 275.804884 -193.697352) (xy 275.812297 -193.6971)
			(xy 275.826499 -193.692843) (xy 275.832824 -193.68897) (xy 275.855579 -193.674442) (xy 275.904441 -193.651481)
			(xy 275.956129 -193.635896) (xy 276.009538 -193.628019) (xy 276.063526 -193.628019) (xy 276.116935 -193.635896)
			(xy 276.168623 -193.651481) (xy 276.217485 -193.674442) (xy 276.24024 -193.68897) (xy 276.24657 -193.692834)
			(xy 276.260768 -193.697092) (xy 276.26818 -193.697352) (xy 277.588472 -193.697352) (xy 277.598659 -193.696833)
			(xy 277.617393 -193.688808) (xy 277.631562 -193.674158) (xy 277.635716 -193.66484) (xy 277.649696 -193.629971)
			(xy 277.68367 -193.562961) (xy 277.724171 -193.499683) (xy 277.770794 -193.44077) (xy 277.823072 -193.386812)
			(xy 277.880482 -193.33835) (xy 277.942449 -193.295869) (xy 278.008351 -193.259795) (xy 278.077529 -193.230489)
			(xy 278.14929 -193.208244) (xy 278.222916 -193.193284) (xy 278.297667 -193.185757) (xy 278.335232 -193.185288)
			(xy 278.374739 -193.185798) (xy 278.453313 -193.194111) (xy 278.530578 -193.210639) (xy 278.605677 -193.235201)
			(xy 278.677776 -193.267524) (xy 278.746077 -193.307249) (xy 278.809821 -193.353937) (xy 278.839422 -193.380106)
			(xy 278.84628 -193.386456) (xy 278.86406 -193.393314) (xy 278.951436 -193.393314) (xy 278.969216 -193.386456)
			(xy 278.976074 -193.380106) (xy 279.005659 -193.35392) (xy 279.069408 -193.307239) (xy 279.137712 -193.267521)
			(xy 279.209815 -193.235206) (xy 279.284916 -193.210653) (xy 279.362182 -193.194134) (xy 279.440758 -193.185831)
			(xy 279.480264 -193.185288) (xy 279.517831 -193.185745) (xy 279.592589 -193.193255) (xy 279.666221 -193.208203)
			(xy 279.737989 -193.230439) (xy 279.807174 -193.259741) (xy 279.873082 -193.295815) (xy 279.935052 -193.338298)
			(xy 279.992463 -193.386765) (xy 280.044739 -193.440731) (xy 280.091357 -193.499654) (xy 280.131849 -193.562943)
			(xy 280.165809 -193.629965) (xy 280.17978 -193.66484) (xy 280.183864 -193.674206) (xy 280.198034 -193.688903)
			(xy 280.216817 -193.696902) (xy 280.227024 -193.697352) (xy 281.071574 -193.697352) (xy 281.0811 -193.696961)
			(xy 281.098838 -193.690012) (xy 281.112812 -193.677064) (xy 281.117294 -193.66865) (xy 281.134381 -193.634562)
			(xy 281.174496 -193.569712) (xy 281.220987 -193.509268) (xy 281.273373 -193.453855) (xy 281.331114 -193.404047)
			(xy 281.393612 -193.360356) (xy 281.460222 -193.323236) (xy 281.530257 -193.293069) (xy 281.602991 -193.270166)
			(xy 281.677675 -193.254765) (xy 281.753536 -193.247025) (xy 281.829792 -193.247025) (xy 281.905653 -193.254765)
			(xy 281.980337 -193.270166) (xy 282.053071 -193.293069) (xy 282.123106 -193.323236) (xy 282.189716 -193.360356)
			(xy 282.252214 -193.404047) (xy 282.309955 -193.453855) (xy 282.362341 -193.509268) (xy 282.408832 -193.569712)
			(xy 282.448947 -193.634562) (xy 282.466034 -193.66865) (xy 282.470535 -193.677049) (xy 282.484507 -193.689987)
			(xy 282.502233 -193.696943) (xy 282.511754 -193.697352) (xy 283.348938 -193.697352) (xy 283.356353 -193.697106)
			(xy 283.370562 -193.69286) (xy 283.376878 -193.68897) (xy 283.399633 -193.674442) (xy 283.448495 -193.651481)
			(xy 283.500183 -193.635896) (xy 283.553592 -193.628019) (xy 283.60758 -193.628019) (xy 283.660989 -193.635896)
			(xy 283.712677 -193.651481) (xy 283.761539 -193.674442) (xy 283.784294 -193.68897) (xy 283.790622 -193.69284)
			(xy 283.804821 -193.697111) (xy 283.812234 -193.697352) (xy 285.132272 -193.697352) (xy 285.142459 -193.696833)
			(xy 285.161193 -193.688808) (xy 285.175362 -193.674158) (xy 285.179516 -193.66484) (xy 285.193496 -193.629971)
			(xy 285.22747 -193.562961) (xy 285.267971 -193.499683) (xy 285.314594 -193.44077) (xy 285.366872 -193.386812)
			(xy 285.424282 -193.33835) (xy 285.486249 -193.295869) (xy 285.552151 -193.259795) (xy 285.621329 -193.230489)
			(xy 285.69309 -193.208244) (xy 285.766716 -193.193284) (xy 285.841467 -193.185757) (xy 285.879032 -193.185288)
			(xy 285.918539 -193.185798) (xy 285.997113 -193.194111) (xy 286.074378 -193.210639) (xy 286.149477 -193.235201)
			(xy 286.221576 -193.267524) (xy 286.289877 -193.307249) (xy 286.353621 -193.353937) (xy 286.383222 -193.380106)
			(xy 286.383476 -193.38036) (xy 286.390723 -193.38626) (xy 286.408176 -193.392895) (xy 286.417512 -193.393314)
			(xy 286.485838 -193.393314) (xy 286.495196 -193.393006) (xy 286.512686 -193.386359) (xy 286.519874 -193.38036)
			(xy 286.520128 -193.380106) (xy 286.549713 -193.353918) (xy 286.613461 -193.307233) (xy 286.681764 -193.267511)
			(xy 286.753866 -193.235192) (xy 286.828967 -193.210634) (xy 286.906235 -193.19411) (xy 286.984811 -193.185803)
			(xy 287.024318 -193.185288) (xy 287.061886 -193.185743) (xy 287.136647 -193.193249) (xy 287.210282 -193.208193)
			(xy 287.282054 -193.230427) (xy 287.351242 -193.259726) (xy 287.417154 -193.295798) (xy 287.479128 -193.33828)
			(xy 287.536543 -193.386747) (xy 287.588823 -193.440712) (xy 287.635444 -193.499635) (xy 287.675939 -193.562926)
			(xy 287.709902 -193.629948) (xy 287.723834 -193.66484) (xy 287.727921 -193.6742) (xy 287.742093 -193.688882)
			(xy 287.760875 -193.696861) (xy 287.771078 -193.697352) (xy 288.615628 -193.697352) (xy 288.625148 -193.696952)
			(xy 288.642871 -193.689991) (xy 288.656829 -193.67704) (xy 288.661348 -193.66865) (xy 288.678435 -193.634562)
			(xy 288.71855 -193.569712) (xy 288.765041 -193.509268) (xy 288.817427 -193.453855) (xy 288.875168 -193.404047)
			(xy 288.937666 -193.360356) (xy 289.004276 -193.323236) (xy 289.074311 -193.293069) (xy 289.147045 -193.270166)
			(xy 289.221729 -193.254765) (xy 289.29759 -193.247025) (xy 289.373846 -193.247025) (xy 289.449707 -193.254765)
			(xy 289.524391 -193.270166) (xy 289.597125 -193.293069) (xy 289.66716 -193.323236) (xy 289.73377 -193.360356)
			(xy 289.796268 -193.404047) (xy 289.854009 -193.453855) (xy 289.906395 -193.509268) (xy 289.952886 -193.569712)
			(xy 289.993001 -193.634562) (xy 290.010088 -193.66865) (xy 290.014587 -193.677054) (xy 290.028556 -193.690005)
			(xy 290.046284 -193.696977) (xy 290.055808 -193.697352) (xy 290.892992 -193.697352) (xy 290.900405 -193.697099)
			(xy 290.914605 -193.69284) (xy 290.920932 -193.68897) (xy 290.943687 -193.674442) (xy 290.992549 -193.651481)
			(xy 291.044237 -193.635896) (xy 291.097646 -193.628019) (xy 291.151634 -193.628019) (xy 291.205043 -193.635896)
			(xy 291.256731 -193.651481) (xy 291.305593 -193.674442) (xy 291.328348 -193.68897) (xy 291.334678 -193.692833)
			(xy 291.348877 -193.697088) (xy 291.356288 -193.697352) (xy 292.676326 -193.697352) (xy 292.686518 -193.696841)
			(xy 292.705267 -193.688826) (xy 292.71945 -193.674176) (xy 292.72357 -193.66484) (xy 292.737551 -193.629972)
			(xy 292.771525 -193.562965) (xy 292.812027 -193.49969) (xy 292.858651 -193.440781) (xy 292.910931 -193.386827)
			(xy 292.968341 -193.338369) (xy 293.030308 -193.295892) (xy 293.09621 -193.259823) (xy 293.165388 -193.230521)
			(xy 293.237148 -193.208281) (xy 293.310772 -193.193326) (xy 293.385522 -193.185805) (xy 293.423086 -193.185288)
			(xy 293.462593 -193.185796) (xy 293.54117 -193.194104) (xy 293.618438 -193.210628) (xy 293.693539 -193.235187)
			(xy 293.765642 -193.267506) (xy 293.833946 -193.307229) (xy 293.897694 -193.353914) (xy 293.927276 -193.380106)
			(xy 293.92753 -193.38036) (xy 293.934775 -193.386266) (xy 293.952228 -193.392917) (xy 293.961566 -193.393314)
			(xy 294.029892 -193.393314) (xy 294.039246 -193.392996) (xy 294.056723 -193.386335) (xy 294.063928 -193.38036)
			(xy 294.064182 -193.380106) (xy 294.093767 -193.35392) (xy 294.157516 -193.30724) (xy 294.225821 -193.267523)
			(xy 294.297923 -193.235209) (xy 294.373024 -193.210656) (xy 294.450291 -193.194138) (xy 294.528866 -193.185836)
			(xy 294.568372 -193.185288) (xy 294.605939 -193.185746) (xy 294.680696 -193.193256) (xy 294.754328 -193.208205)
			(xy 294.826095 -193.230442) (xy 294.895279 -193.259744) (xy 294.961186 -193.295818) (xy 295.023156 -193.338301)
			(xy 295.080566 -193.386769) (xy 295.132842 -193.440734) (xy 295.179459 -193.499657) (xy 295.219951 -193.562946)
			(xy 295.25391 -193.629967) (xy 295.267888 -193.66484) (xy 295.271973 -193.674205) (xy 295.286143 -193.6889)
			(xy 295.304926 -193.696896) (xy 295.315132 -193.697352) (xy 296.159682 -193.697352) (xy 296.169207 -193.69696)
			(xy 296.186943 -193.690009) (xy 296.200915 -193.67706) (xy 296.205402 -193.66865) (xy 296.222489 -193.634562)
			(xy 296.262604 -193.569712) (xy 296.309095 -193.509268) (xy 296.361481 -193.453855) (xy 296.419222 -193.404047)
			(xy 296.48172 -193.360356) (xy 296.54833 -193.323236) (xy 296.618365 -193.293069) (xy 296.691099 -193.270166)
			(xy 296.765783 -193.254765) (xy 296.841644 -193.247025) (xy 296.9179 -193.247025) (xy 296.993761 -193.254765)
			(xy 297.068445 -193.270166) (xy 297.141179 -193.293069) (xy 297.211214 -193.323236) (xy 297.277824 -193.360356)
			(xy 297.340322 -193.404047) (xy 297.398063 -193.453855) (xy 297.450449 -193.509268) (xy 297.49694 -193.569712)
			(xy 297.537055 -193.634562) (xy 297.554142 -193.66865) (xy 297.558643 -193.677048) (xy 297.572616 -193.689984)
			(xy 297.590342 -193.696937) (xy 297.599862 -193.697352) (xy 298.436792 -193.697352) (xy 298.444205 -193.697099)
			(xy 298.458405 -193.69284) (xy 298.464732 -193.68897) (xy 298.487487 -193.674442) (xy 298.536349 -193.651481)
			(xy 298.588037 -193.635896) (xy 298.641446 -193.628019) (xy 298.695434 -193.628019) (xy 298.748843 -193.635896)
			(xy 298.800531 -193.651481) (xy 298.849393 -193.674442) (xy 298.872148 -193.68897) (xy 298.878478 -193.692833)
			(xy 298.892677 -193.697088) (xy 298.900088 -193.697352) (xy 300.22038 -193.697352) (xy 300.230566 -193.696831)
			(xy 300.249298 -193.688805) (xy 300.263464 -193.674155) (xy 300.267624 -193.66484) (xy 300.281604 -193.629971)
			(xy 300.315578 -193.562962) (xy 300.356079 -193.499684) (xy 300.402702 -193.440771) (xy 300.454981 -193.386814)
			(xy 300.512391 -193.338353) (xy 300.574358 -193.295873) (xy 300.64026 -193.259799) (xy 300.709438 -193.230494)
			(xy 300.781199 -193.20825) (xy 300.854824 -193.19329) (xy 300.929575 -193.185764) (xy 300.96714 -193.185288)
			(xy 301.006646 -193.185799) (xy 301.085221 -193.194112) (xy 301.162485 -193.210641) (xy 301.237583 -193.235204)
			(xy 301.309682 -193.267527) (xy 301.377982 -193.307253) (xy 301.441726 -193.35394) (xy 301.47133 -193.380106)
			(xy 301.471584 -193.38036) (xy 301.478831 -193.386258) (xy 301.496284 -193.392891) (xy 301.50562 -193.393314)
			(xy 301.573946 -193.393314) (xy 301.583303 -193.393004) (xy 301.600792 -193.386355) (xy 301.607982 -193.38036)
			(xy 301.608236 -193.380106) (xy 301.637821 -193.353918) (xy 301.701569 -193.307234) (xy 301.769873 -193.267513)
			(xy 301.841975 -193.235194) (xy 301.917076 -193.210637) (xy 301.994343 -193.194114) (xy 302.072919 -193.185808)
			(xy 302.112426 -193.185288) (xy 302.149994 -193.185743) (xy 302.224754 -193.19325) (xy 302.298389 -193.208195)
			(xy 302.37016 -193.230429) (xy 302.439348 -193.259729) (xy 302.505259 -193.2958) (xy 302.567232 -193.338283)
			(xy 302.624646 -193.38675) (xy 302.676926 -193.440715) (xy 302.723546 -193.499639) (xy 302.764041 -193.562929)
			(xy 302.798003 -193.629951) (xy 302.811942 -193.66484) (xy 302.816029 -193.674199) (xy 302.830202 -193.688879)
			(xy 302.848984 -193.696856) (xy 302.859186 -193.697352) (xy 303.703736 -193.697352) (xy 303.713265 -193.696967)
			(xy 303.731014 -193.690026) (xy 303.745 -193.67708) (xy 303.749456 -193.66865) (xy 303.766543 -193.634562)
			(xy 303.806658 -193.569712) (xy 303.853149 -193.509268) (xy 303.905535 -193.453855) (xy 303.963276 -193.404047)
			(xy 304.025774 -193.360356) (xy 304.092384 -193.323236) (xy 304.162419 -193.293069) (xy 304.235153 -193.270166)
			(xy 304.309837 -193.254765) (xy 304.385698 -193.247025) (xy 304.461954 -193.247025) (xy 304.537815 -193.254765)
			(xy 304.612499 -193.270166) (xy 304.685233 -193.293069) (xy 304.755268 -193.323236) (xy 304.821878 -193.360356)
			(xy 304.884376 -193.404047) (xy 304.942117 -193.453855) (xy 304.994503 -193.509268) (xy 305.040994 -193.569712)
			(xy 305.081109 -193.634562) (xy 305.098196 -193.66865) (xy 305.102695 -193.677053) (xy 305.116665 -193.690002)
			(xy 305.134393 -193.696971) (xy 305.143916 -193.697352) (xy 305.980846 -193.697352) (xy 305.988261 -193.697105)
			(xy 306.002468 -193.692857) (xy 306.008786 -193.68897) (xy 306.031541 -193.674442) (xy 306.080403 -193.651481)
			(xy 306.132091 -193.635896) (xy 306.1855 -193.628019) (xy 306.239488 -193.628019) (xy 306.292897 -193.635896)
			(xy 306.344585 -193.651481) (xy 306.393447 -193.674442) (xy 306.416202 -193.68897) (xy 306.42253 -193.692839)
			(xy 306.436729 -193.697107) (xy 306.444142 -193.697352) (xy 307.764434 -193.697352) (xy 307.774625 -193.696839)
			(xy 307.793372 -193.688823) (xy 307.807552 -193.674173) (xy 307.811678 -193.66484) (xy 307.826282 -193.628455)
			(xy 307.862016 -193.558664) (xy 307.904837 -193.492982) (xy 307.954278 -193.432127) (xy 308.009798 -193.376763)
			(xy 308.070792 -193.327495) (xy 308.136594 -193.284859) (xy 308.206486 -193.249322) (xy 308.279704 -193.221272)
			(xy 308.355449 -193.201014) (xy 308.432894 -193.18877) (xy 308.511194 -193.184674) (xy 308.589494 -193.18877)
			(xy 308.666939 -193.201014) (xy 308.742684 -193.221272) (xy 308.815902 -193.249322) (xy 308.885794 -193.284859)
			(xy 308.951596 -193.327495) (xy 309.01259 -193.376763) (xy 309.06811 -193.432127) (xy 309.117551 -193.492982)
			(xy 309.160372 -193.558664) (xy 309.196106 -193.628455) (xy 309.21071 -193.66484) (xy 309.214795 -193.674203)
			(xy 309.228967 -193.688892) (xy 309.247749 -193.696879) (xy 309.257954 -193.697352) (xy 312.12409 -193.697352)
			(xy 312.13416 -193.696929) (xy 312.152762 -193.689212) (xy 312.160158 -193.682366) (xy 312.322972 -193.519552)
			(xy 312.329814 -193.512152) (xy 312.337535 -193.493554) (xy 312.337958 -193.483484) (xy 312.337958 -150.72995)
			(xy 312.338534 -150.704992) (xy 312.348283 -150.656037) (xy 312.367397 -150.609925) (xy 312.39514 -150.568429)
			(xy 312.41238 -150.550372) (xy 313.698382 -149.26437) (xy 313.716424 -149.247113) (xy 313.757918 -149.21936)
			(xy 313.804037 -149.200253) (xy 313.853 -149.190527) (xy 313.87796 -149.189948) (xy 332.009242 -149.189948)
			(xy 332.019285 -149.189517) (xy 332.037833 -149.181805) (xy 332.052011 -149.167576) (xy 332.056232 -149.158452)
			(xy 332.056232 -149.158198) (xy 332.067306 -149.132147) (xy 332.096025 -149.083367) (xy 332.13164 -149.039369)
			(xy 332.173368 -149.001121) (xy 332.220293 -148.969461) (xy 332.271382 -148.945087) (xy 332.325513 -148.928534)
			(xy 332.381497 -148.920165) (xy 332.438103 -148.920165) (xy 332.494087 -148.928534) (xy 332.548218 -148.945087)
			(xy 332.599307 -148.969461) (xy 332.646232 -149.001121) (xy 332.68796 -149.039369) (xy 332.723575 -149.083367)
			(xy 332.752294 -149.132147) (xy 332.763368 -149.158198) (xy 332.763368 -149.158452) (xy 332.767581 -149.167581)
			(xy 332.781762 -149.181814) (xy 332.800313 -149.189527) (xy 332.810358 -149.189948) (xy 337.382612 -149.189948)
			(xy 337.407572 -149.190521) (xy 337.456531 -149.200263) (xy 337.502648 -149.219371) (xy 337.544151 -149.247111)
			(xy 337.56219 -149.26437) (xy 338.079334 -149.781514) (xy 338.096596 -149.799554) (xy 338.12436 -149.841047)
			(xy 338.143479 -149.887165) (xy 338.153217 -149.93613) (xy 338.153756 -149.961092) (xy 338.153756 -155.952698)
			(xy 338.15418 -155.962767) (xy 338.1619 -155.981367) (xy 338.168742 -155.988766) (xy 338.502752 -156.322776)
			(xy 338.510152 -156.329617) (xy 338.528751 -156.337336) (xy 338.53882 -156.337762) (xy 348.982284 -156.337762)
			(xy 348.991332 -156.337401) (xy 349.008304 -156.331123) (xy 349.022041 -156.319343) (xy 349.026734 -156.3116)
			(xy 349.045922 -156.278073) (xy 349.090081 -156.214684) (xy 349.140423 -156.156085) (xy 349.196434 -156.102878)
			(xy 349.257537 -156.055608) (xy 349.323108 -156.014759) (xy 349.392473 -155.980751) (xy 349.464922 -155.953931)
			(xy 349.539712 -155.934576) (xy 349.616075 -155.922882) (xy 349.69323 -155.918971) (xy 349.770385 -155.922882)
			(xy 349.846748 -155.934576) (xy 349.921538 -155.953931) (xy 349.993987 -155.980751) (xy 350.063352 -156.014759)
			(xy 350.128923 -156.055608) (xy 350.190026 -156.102878) (xy 350.246037 -156.156085) (xy 350.296379 -156.214684)
			(xy 350.340538 -156.278073) (xy 350.359726 -156.3116) (xy 350.364432 -156.319333) (xy 350.37816 -156.331115)
			(xy 350.39513 -156.337384) (xy 350.404176 -156.337762) (xy 351.43567 -156.337762) (xy 351.460624 -156.33838)
			(xy 351.509572 -156.348128) (xy 351.555678 -156.367236) (xy 351.597172 -156.394969) (xy 351.615248 -156.412184)
			(xy 357.799894 -162.59683) (xy 376.471695 -162.59683) (xy 376.4757 -162.491081) (xy 376.48769 -162.385938)
			(xy 376.507599 -162.282003) (xy 376.53531 -162.179871) (xy 376.570667 -162.080127) (xy 376.613465 -161.983343)
			(xy 376.663461 -161.890073) (xy 376.720368 -161.800852) (xy 376.783859 -161.716189) (xy 376.853571 -161.636571)
			(xy 376.929105 -161.562453) (xy 377.010028 -161.49426) (xy 377.095877 -161.432382) (xy 377.18616 -161.377175)
			(xy 377.280359 -161.328953) (xy 377.377936 -161.287993) (xy 377.478331 -161.254531) (xy 377.580969 -161.228757)
			(xy 377.685262 -161.210819) (xy 377.790613 -161.20082) (xy 377.896419 -161.198817) (xy 378.002073 -161.204822)
			(xy 378.10697 -161.218801) (xy 378.21051 -161.240672) (xy 378.312099 -161.270312) (xy 378.411156 -161.30755)
			(xy 378.507113 -161.352172) (xy 378.59942 -161.403924) (xy 378.687549 -161.462509) (xy 378.770995 -161.527591)
			(xy 378.849279 -161.598797) (xy 378.921954 -161.67572) (xy 378.988604 -161.75792) (xy 379.048846 -161.844924)
			(xy 379.102335 -161.936235) (xy 379.148766 -162.03133) (xy 379.187871 -162.129664) (xy 379.219428 -162.230675)
			(xy 379.243255 -162.333782) (xy 379.259216 -162.438396) (xy 379.26722 -162.543918) (xy 379.26772 -162.59683)
			(xy 379.26722 -162.649742) (xy 379.266995 -162.65271) (xy 385.808735 -162.65271) (xy 385.81274 -162.546961)
			(xy 385.82473 -162.441818) (xy 385.844639 -162.337883) (xy 385.87235 -162.235751) (xy 385.907707 -162.136007)
			(xy 385.950505 -162.039223) (xy 386.000501 -161.945953) (xy 386.057408 -161.856732) (xy 386.120899 -161.772069)
			(xy 386.190611 -161.692451) (xy 386.266145 -161.618333) (xy 386.347068 -161.55014) (xy 386.432917 -161.488262)
			(xy 386.5232 -161.433055) (xy 386.617399 -161.384833) (xy 386.714976 -161.343873) (xy 386.815371 -161.310411)
			(xy 386.918009 -161.284637) (xy 387.022302 -161.266699) (xy 387.127653 -161.2567) (xy 387.233459 -161.254697)
			(xy 387.339113 -161.260702) (xy 387.44401 -161.274681) (xy 387.54755 -161.296552) (xy 387.649139 -161.326192)
			(xy 387.748196 -161.36343) (xy 387.844153 -161.408052) (xy 387.93646 -161.459804) (xy 388.024589 -161.518389)
			(xy 388.108035 -161.583471) (xy 388.186319 -161.654677) (xy 388.258994 -161.7316) (xy 388.325644 -161.8138)
			(xy 388.385886 -161.900804) (xy 388.439375 -161.992115) (xy 388.485806 -162.08721) (xy 388.524911 -162.185544)
			(xy 388.556468 -162.286555) (xy 388.580295 -162.389662) (xy 388.596256 -162.494276) (xy 388.60426 -162.599798)
			(xy 388.60476 -162.65271) (xy 388.60426 -162.705622) (xy 388.596256 -162.811144) (xy 388.580295 -162.915758)
			(xy 388.556468 -163.018865) (xy 388.524911 -163.119876) (xy 388.485806 -163.21821) (xy 388.439375 -163.313305)
			(xy 388.385886 -163.404616) (xy 388.325644 -163.49162) (xy 388.258994 -163.57382) (xy 388.186319 -163.650743)
			(xy 388.108035 -163.721949) (xy 388.024589 -163.787031) (xy 387.93646 -163.845616) (xy 387.844153 -163.897368)
			(xy 387.748196 -163.94199) (xy 387.649139 -163.979228) (xy 387.54755 -164.008868) (xy 387.44401 -164.030739)
			(xy 387.339113 -164.044718) (xy 387.233459 -164.050723) (xy 387.127653 -164.04872) (xy 387.022302 -164.038721)
			(xy 386.918009 -164.020783) (xy 386.815371 -163.995009) (xy 386.714976 -163.961547) (xy 386.617399 -163.920587)
			(xy 386.5232 -163.872365) (xy 386.432917 -163.817158) (xy 386.347068 -163.75528) (xy 386.266145 -163.687087)
			(xy 386.190611 -163.612969) (xy 386.120899 -163.533351) (xy 386.057408 -163.448688) (xy 386.000501 -163.359467)
			(xy 385.950505 -163.266197) (xy 385.907707 -163.169413) (xy 385.87235 -163.069669) (xy 385.844639 -162.967537)
			(xy 385.82473 -162.863602) (xy 385.81274 -162.758459) (xy 385.808735 -162.65271) (xy 379.266995 -162.65271)
			(xy 379.259216 -162.755264) (xy 379.243255 -162.859878) (xy 379.219428 -162.962985) (xy 379.187871 -163.063996)
			(xy 379.148766 -163.16233) (xy 379.102335 -163.257425) (xy 379.048846 -163.348736) (xy 378.988604 -163.43574)
			(xy 378.921954 -163.51794) (xy 378.849279 -163.594863) (xy 378.770995 -163.666069) (xy 378.687549 -163.731151)
			(xy 378.59942 -163.789736) (xy 378.507113 -163.841488) (xy 378.411156 -163.88611) (xy 378.312099 -163.923348)
			(xy 378.21051 -163.952988) (xy 378.10697 -163.974859) (xy 378.002073 -163.988838) (xy 377.896419 -163.994843)
			(xy 377.790613 -163.99284) (xy 377.685262 -163.982841) (xy 377.580969 -163.964903) (xy 377.478331 -163.939129)
			(xy 377.377936 -163.905667) (xy 377.280359 -163.864707) (xy 377.18616 -163.816485) (xy 377.095877 -163.761278)
			(xy 377.010028 -163.6994) (xy 376.929105 -163.631207) (xy 376.853571 -163.557089) (xy 376.783859 -163.477471)
			(xy 376.720368 -163.392808) (xy 376.663461 -163.303587) (xy 376.613465 -163.210317) (xy 376.570667 -163.113533)
			(xy 376.53531 -163.013789) (xy 376.507599 -162.911657) (xy 376.48769 -162.807722) (xy 376.4757 -162.702579)
			(xy 376.471695 -162.59683) (xy 357.799894 -162.59683) (xy 358.22382 -163.020756) (xy 358.231217 -163.027604)
			(xy 358.249816 -163.035338) (xy 358.259888 -163.035742) (xy 366.527588 -163.035742) (xy 366.533684 -163.034218)
			(xy 366.568113 -163.026202) (xy 366.637919 -163.015014) (xy 366.708394 -163.009408) (xy 366.743742 -163.009072)
			(xy 366.745266 -163.009072) (xy 366.780614 -163.009424) (xy 366.851086 -163.015035) (xy 366.920892 -163.026218)
			(xy 366.955324 -163.034218) (xy 366.96142 -163.035742) (xy 367.162588 -163.035742) (xy 367.168684 -163.034218)
			(xy 367.203113 -163.026202) (xy 367.272919 -163.015014) (xy 367.343394 -163.009408) (xy 367.378742 -163.009072)
			(xy 367.380266 -163.009072) (xy 367.415614 -163.009424) (xy 367.486086 -163.015035) (xy 367.555892 -163.026218)
			(xy 367.590324 -163.034218) (xy 367.59642 -163.035742) (xy 367.828068 -163.035742) (xy 367.834164 -163.034218)
			(xy 367.868593 -163.026201) (xy 367.938399 -163.015012) (xy 368.008873 -163.009404) (xy 368.044222 -163.009072)
			(xy 368.045746 -163.009072) (xy 368.081094 -163.009423) (xy 368.151567 -163.015033) (xy 368.221373 -163.026214)
			(xy 368.255804 -163.034218) (xy 368.2619 -163.035742) (xy 368.463068 -163.035742) (xy 368.469164 -163.034218)
			(xy 368.503593 -163.026201) (xy 368.573399 -163.015012) (xy 368.643873 -163.009404) (xy 368.679222 -163.009072)
			(xy 368.680746 -163.009072) (xy 368.716094 -163.009423) (xy 368.786567 -163.015033) (xy 368.856373 -163.026214)
			(xy 368.890804 -163.034218) (xy 368.8969 -163.035742) (xy 369.098068 -163.035742) (xy 369.104164 -163.034218)
			(xy 369.138593 -163.026201) (xy 369.208399 -163.015012) (xy 369.278873 -163.009404) (xy 369.314222 -163.009072)
			(xy 369.315746 -163.009072) (xy 369.351094 -163.009423) (xy 369.421567 -163.015033) (xy 369.491373 -163.026214)
			(xy 369.525804 -163.034218) (xy 369.5319 -163.035742) (xy 369.733068 -163.035742) (xy 369.739164 -163.034218)
			(xy 369.773593 -163.026201) (xy 369.843399 -163.015012) (xy 369.913873 -163.009404) (xy 369.949222 -163.009072)
			(xy 369.950746 -163.009072) (xy 369.986094 -163.009423) (xy 370.056567 -163.015033) (xy 370.126373 -163.026214)
			(xy 370.160804 -163.034218) (xy 370.1669 -163.035742) (xy 370.469668 -163.035742) (xy 370.475764 -163.034218)
			(xy 370.510193 -163.026201) (xy 370.579999 -163.015012) (xy 370.650473 -163.009404) (xy 370.685822 -163.009072)
			(xy 370.687346 -163.009072) (xy 370.722694 -163.009423) (xy 370.793167 -163.015033) (xy 370.862973 -163.026214)
			(xy 370.897404 -163.034218) (xy 370.9035 -163.035742) (xy 372.847616 -163.035742) (xy 372.872576 -163.036315)
			(xy 372.921535 -163.046058) (xy 372.967652 -163.065166) (xy 373.009154 -163.092906) (xy 373.027194 -163.110164)
			(xy 375.85523 -165.9382) (xy 375.86263 -165.945042) (xy 375.881228 -165.952765) (xy 375.891298 -165.953186)
			(xy 388.857236 -165.953186) (xy 388.867303 -165.952756) (xy 388.885897 -165.945031) (xy 388.893304 -165.9382)
			(xy 396.423134 -158.40837) (xy 396.441174 -158.391109) (xy 396.482667 -158.363349) (xy 396.528786 -158.344232)
			(xy 396.57775 -158.334498) (xy 396.602712 -158.333948) (xy 414.513268 -158.333948) (xy 414.521546 -158.333621)
			(xy 414.537222 -158.328297) (xy 414.544002 -158.323534) (xy 414.566337 -158.307007) (xy 414.614839 -158.279908)
			(xy 414.66676 -158.260131) (xy 414.721 -158.248095) (xy 414.776412 -158.244055) (xy 414.831824 -158.248095)
			(xy 414.886064 -158.260131) (xy 414.937985 -158.279908) (xy 414.986487 -158.307007) (xy 415.008822 -158.323534)
			(xy 415.015605 -158.328286) (xy 415.031281 -158.333601) (xy 415.039556 -158.333948) (xy 417.576 -158.333948)
			(xy 417.585144 -158.334202) (xy 417.594373 -158.334077) (xy 417.611814 -158.328081) (xy 417.61918 -158.322518)
			(xy 417.639733 -158.306209) (xy 417.684466 -158.278788) (xy 417.732535 -158.257757) (xy 417.783034 -158.243515)
			(xy 417.835008 -158.236328) (xy 417.861242 -158.235904) (xy 417.888491 -158.236393) (xy 417.942433 -158.244155)
			(xy 417.994722 -158.259513) (xy 418.044293 -158.282157) (xy 418.090138 -158.311625) (xy 418.131322 -158.347316)
			(xy 418.167008 -158.388506) (xy 418.196469 -158.434354) (xy 418.219105 -158.483928) (xy 418.234457 -158.536219)
			(xy 418.242211 -158.590163) (xy 418.24275 -158.617412) (xy 418.242105 -158.64888) (xy 418.231775 -158.710963)
			(xy 418.211396 -158.770509) (xy 418.19703 -158.798514) (xy 418.19229 -158.80838) (xy 418.190808 -158.830196)
			(xy 418.198506 -158.850663) (xy 418.20592 -158.858712) (xy 418.390578 -159.04337) (xy 418.407839 -159.06141)
			(xy 418.435599 -159.102903) (xy 418.454713 -159.149021) (xy 418.464443 -159.197986) (xy 418.465 -159.222948)
			(xy 418.465 -159.543242) (xy 418.465274 -159.550564) (xy 418.469407 -159.564615) (xy 418.473128 -159.570928)
			(xy 418.49441 -159.60469) (xy 418.530617 -159.675818) (xy 418.559197 -159.750338) (xy 418.579839 -159.827435)
			(xy 418.592316 -159.906266) (xy 418.596493 -159.98597) (xy 418.592323 -160.065674) (xy 418.579852 -160.144506)
			(xy 418.559216 -160.221605) (xy 418.530641 -160.296127) (xy 418.49444 -160.367258) (xy 418.473128 -160.401)
			(xy 418.469344 -160.407283) (xy 418.465229 -160.421354) (xy 418.465 -160.428686) (xy 418.465 -161.804604)
			(xy 418.465442 -161.814763) (xy 418.473292 -161.833503) (xy 418.48024 -161.840926) (xy 418.499546 -161.860583)
			(xy 418.532873 -161.904456) (xy 418.559543 -161.952666) (xy 418.579001 -162.004212) (xy 418.590841 -162.05802)
			(xy 418.594818 -162.112972) (xy 418.590849 -162.167924) (xy 418.579017 -162.221735) (xy 418.559567 -162.273283)
			(xy 418.532904 -162.321497) (xy 418.499583 -162.365375) (xy 418.48024 -162.384994) (xy 418.473288 -162.392417)
			(xy 418.465422 -162.411154) (xy 418.465 -162.421316) (xy 418.465 -162.450018) (xy 418.465444 -162.460176)
			(xy 418.473298 -162.478912) (xy 418.48024 -162.48634) (xy 418.499545 -162.505997) (xy 418.53287 -162.549869)
			(xy 418.559538 -162.598079) (xy 418.578994 -162.649624) (xy 418.590833 -162.703431) (xy 418.594808 -162.758382)
			(xy 418.590838 -162.813333) (xy 418.579004 -162.867141) (xy 418.559554 -162.918688) (xy 418.53289 -162.9669)
			(xy 418.499569 -163.010776) (xy 418.48024 -163.030408) (xy 418.47329 -163.037832) (xy 418.46543 -163.056569)
			(xy 418.465 -163.06673) (xy 418.465 -163.716716) (xy 431.458116 -163.716716) (xy 431.458593 -163.67699)
			(xy 431.46684 -163.597967) (xy 431.483247 -163.520228) (xy 431.507636 -163.444612) (xy 431.539744 -163.371936)
			(xy 431.579224 -163.302987) (xy 431.625649 -163.23851) (xy 431.678517 -163.1792) (xy 431.707544 -163.152074)
			(xy 431.714516 -163.145218) (xy 431.723062 -163.127648) (xy 431.724388 -163.108156) (xy 431.721768 -163.098734)
			(xy 431.713062 -163.070112) (xy 431.703616 -163.011041) (xy 431.702972 -162.981132) (xy 431.703431 -162.95386)
			(xy 431.71119 -162.899871) (xy 431.726554 -162.847537) (xy 431.74921 -162.797921) (xy 431.778698 -162.752036)
			(xy 431.814416 -162.710814) (xy 431.855637 -162.675097) (xy 431.901523 -162.645609) (xy 431.951138 -162.622953)
			(xy 432.003473 -162.60759) (xy 432.057462 -162.599831) (xy 432.084734 -162.59937) (xy 432.111994 -162.599792)
			(xy 432.165959 -162.607553) (xy 432.218272 -162.622911) (xy 432.267867 -162.645555) (xy 432.313737 -162.675024)
			(xy 432.354949 -162.710718) (xy 432.390663 -162.751912) (xy 432.420155 -162.797767) (xy 432.442823 -162.847352)
			(xy 432.458207 -162.899657) (xy 432.465994 -162.953618) (xy 432.466496 -162.980878) (xy 432.466496 -162.981386)
			(xy 432.466242 -162.99307) (xy 432.505612 -163.006972) (xy 432.581318 -163.042196) (xy 432.652731 -163.085464)
			(xy 432.686206 -163.110418) (xy 432.695405 -163.116761) (xy 432.717194 -163.121592) (xy 432.738983 -163.116761)
			(xy 432.748182 -163.110418) (xy 432.781656 -163.085462) (xy 432.853068 -163.042191) (xy 432.928776 -163.006973)
			(xy 432.968146 -162.99307) (xy 432.967892 -162.981386) (xy 432.967892 -162.980878) (xy 432.968471 -162.953623)
			(xy 432.976257 -162.899672) (xy 432.991638 -162.847378) (xy 433.014301 -162.797803) (xy 433.043787 -162.751956)
			(xy 433.079494 -162.710769) (xy 433.120697 -162.675081) (xy 433.166557 -162.645617) (xy 433.216143 -162.622976)
			(xy 433.268445 -162.607619) (xy 433.322399 -162.599859) (xy 433.349654 -162.59937) (xy 433.376925 -162.599844)
			(xy 433.430913 -162.607601) (xy 433.483248 -162.622963) (xy 433.532863 -162.645618) (xy 433.578749 -162.675103)
			(xy 433.61997 -162.71082) (xy 433.655688 -162.75204) (xy 433.685176 -162.797925) (xy 433.707832 -162.847539)
			(xy 433.723196 -162.899873) (xy 433.730955 -162.953861) (xy 433.731416 -162.981132) (xy 433.730789 -163.011043)
			(xy 433.721344 -163.070117) (xy 433.71262 -163.098734) (xy 433.710031 -163.108155) (xy 433.711383 -163.12763)
			(xy 433.719907 -163.145193) (xy 433.726844 -163.152074) (xy 433.755886 -163.179183) (xy 433.808744 -163.2385)
			(xy 433.855159 -163.302983) (xy 433.894631 -163.371936) (xy 433.926732 -163.444613) (xy 433.951115 -163.520229)
			(xy 433.967519 -163.597969) (xy 433.975764 -163.676991) (xy 433.976272 -163.716716) (xy 433.97577 -163.756717)
			(xy 433.967406 -163.836281) (xy 433.950771 -163.914534) (xy 433.926047 -163.99062) (xy 433.893506 -164.063705)
			(xy 433.853504 -164.132988) (xy 433.806479 -164.19771) (xy 433.752947 -164.257162) (xy 433.693493 -164.310693)
			(xy 433.628769 -164.357716) (xy 433.559485 -164.397716) (xy 433.486399 -164.430255) (xy 433.410313 -164.454976)
			(xy 433.332059 -164.471609) (xy 433.252495 -164.479971) (xy 433.212494 -164.480494) (xy 433.170888 -164.479965)
			(xy 433.08817 -164.470903) (xy 433.006928 -164.4529) (xy 432.928126 -164.426168) (xy 432.852699 -164.391024)
			(xy 432.781541 -164.347886) (xy 432.748182 -164.323014) (xy 432.738983 -164.316671) (xy 432.717194 -164.31184)
			(xy 432.695405 -164.316671) (xy 432.686206 -164.323014) (xy 432.652851 -164.347888) (xy 432.581683 -164.391001)
			(xy 432.506251 -164.426127) (xy 432.42745 -164.452851) (xy 432.346212 -164.470855) (xy 432.263498 -164.479926)
			(xy 432.221894 -164.480494) (xy 432.181894 -164.47996) (xy 432.102332 -164.471598) (xy 432.02408 -164.454964)
			(xy 431.947996 -164.430243) (xy 431.874912 -164.397704) (xy 431.80563 -164.357704) (xy 431.740908 -164.310681)
			(xy 431.681456 -164.257151) (xy 431.627925 -164.1977) (xy 431.580902 -164.132979) (xy 431.540901 -164.063697)
			(xy 431.508361 -163.990614) (xy 431.483638 -163.914529) (xy 431.467004 -163.836278) (xy 431.45864 -163.756716)
			(xy 431.458116 -163.716716) (xy 418.465 -163.716716) (xy 418.465 -174.387764) (xy 418.465413 -174.39779)
			(xy 418.473077 -174.416319) (xy 418.48725 -174.430503) (xy 418.505774 -174.43818) (xy 418.5158 -174.438564)
			(xy 425.076366 -174.438564) (xy 425.10132 -174.439182) (xy 425.150268 -174.448929) (xy 425.196375 -174.468036)
			(xy 425.237869 -174.49577) (xy 425.255944 -174.512986) (xy 425.976796 -175.233838) (xy 425.994059 -175.251878)
			(xy 426.021822 -175.29337) (xy 426.04094 -175.339488) (xy 426.050676 -175.388454) (xy 426.051218 -175.413416)
			(xy 426.051218 -191.028066) (xy 426.050621 -191.052896) (xy 426.040981 -191.101612) (xy 426.022061 -191.147528)
			(xy 426.0088 -191.168528) (xy 426.004936 -191.174858) (xy 426.000678 -191.189056) (xy 426.000418 -191.196468)
			(xy 426.000418 -195.220082) (xy 426.000857 -195.230145) (xy 426.008594 -195.248726) (xy 426.015404 -195.25615)
			(xy 426.143674 -195.38442) (xy 426.151073 -195.391263) (xy 426.169672 -195.398983) (xy 426.179742 -195.399406)
		)
		(stroke
			(width 0)
			(type solid)
		)
		(fill yes)
		(layer "In9.Cu")
		(net "P12V_MEM_CPU0")
	)
	(gr_poly
		(pts
			(xy 193.670936 -341.982552) (xy 193.681002 -341.982121) (xy 193.699593 -341.974392) (xy 193.707004 -341.967566)
			(xy 196.025008 -339.649562) (xy 196.031847 -339.642161) (xy 196.039567 -339.623563) (xy 196.039994 -339.613494)
			(xy 196.039994 -326.967342) (xy 196.03956 -326.957277) (xy 196.03183 -326.938688) (xy 196.025008 -326.931274)
			(xy 194.463924 -325.37019) (xy 194.446658 -325.352152) (xy 194.418888 -325.310661) (xy 194.399763 -325.264543)
			(xy 194.390021 -325.215575) (xy 194.389502 -325.190612) (xy 194.389502 -323.540882) (xy 194.390115 -323.515926)
			(xy 194.399856 -323.466974) (xy 194.418959 -323.420863) (xy 194.446691 -323.379364) (xy 194.463924 -323.361304)
			(xy 196.025008 -321.80022) (xy 196.031841 -321.792817) (xy 196.039545 -321.774219) (xy 196.039994 -321.764152)
			(xy 196.039994 -271.809464) (xy 196.039564 -271.799397) (xy 196.03184 -271.780802) (xy 196.025008 -271.773396)
			(xy 191.556132 -267.30452) (xy 191.548851 -267.297847) (xy 191.530684 -267.290153) (xy 191.520826 -267.289534)
			(xy 191.4398 -267.288518) (xy 191.421512 -267.29563) (xy 191.414146 -267.302742) (xy 191.393454 -267.321658)
			(xy 191.347421 -267.353654) (xy 191.297081 -267.378324) (xy 191.243589 -267.3951) (xy 191.188176 -267.403597)
			(xy 191.160146 -267.404088) (xy 191.134166 -267.40364) (xy 191.082722 -267.396342) (xy 191.032811 -267.381896)
			(xy 190.98542 -267.360589) (xy 190.941489 -267.332843) (xy 190.901886 -267.299207) (xy 190.867394 -267.260346)
			(xy 190.838697 -267.21703) (xy 190.816363 -267.170116) (xy 190.800833 -267.120531) (xy 190.796164 -267.09497)
			(xy 190.793116 -267.076428) (xy 190.764922 -267.052298) (xy 187.455302 -267.052298) (xy 187.427108 -267.076428)
			(xy 187.42406 -267.09497) (xy 187.419143 -267.12188) (xy 187.402415 -267.173963) (xy 187.378178 -267.223003)
			(xy 187.346963 -267.267926) (xy 187.309457 -267.307746) (xy 187.26648 -267.34159) (xy 187.218976 -267.368715)
			(xy 187.167987 -267.388527) (xy 187.114631 -267.40059) (xy 187.060078 -267.404641) (xy 187.005525 -267.40059)
			(xy 186.952169 -267.388527) (xy 186.90118 -267.368715) (xy 186.853676 -267.34159) (xy 186.810699 -267.307746)
			(xy 186.773193 -267.267926) (xy 186.741978 -267.223003) (xy 186.717741 -267.173963) (xy 186.701013 -267.12188)
			(xy 186.696096 -267.09497) (xy 186.693048 -267.076428) (xy 186.664854 -267.052298) (xy 184.011316 -267.052298)
			(xy 183.983122 -267.076428) (xy 183.980074 -267.09497) (xy 183.975157 -267.12188) (xy 183.958429 -267.173963)
			(xy 183.934192 -267.223003) (xy 183.902977 -267.267926) (xy 183.865471 -267.307746) (xy 183.822494 -267.34159)
			(xy 183.77499 -267.368715) (xy 183.724001 -267.388527) (xy 183.670645 -267.40059) (xy 183.616092 -267.404641)
			(xy 183.561539 -267.40059) (xy 183.508183 -267.388527) (xy 183.457194 -267.368715) (xy 183.40969 -267.34159)
			(xy 183.366713 -267.307746) (xy 183.329207 -267.267926) (xy 183.297992 -267.223003) (xy 183.273755 -267.173963)
			(xy 183.257027 -267.12188) (xy 183.25211 -267.09497) (xy 183.249062 -267.076428) (xy 183.220868 -267.052298)
			(xy 179.911248 -267.052298) (xy 179.883054 -267.076428) (xy 179.880006 -267.09497) (xy 179.875089 -267.12188)
			(xy 179.858361 -267.173963) (xy 179.834124 -267.223003) (xy 179.802909 -267.267926) (xy 179.765403 -267.307746)
			(xy 179.722426 -267.34159) (xy 179.674922 -267.368715) (xy 179.623933 -267.388527) (xy 179.570577 -267.40059)
			(xy 179.516024 -267.404641) (xy 179.461471 -267.40059) (xy 179.408115 -267.388527) (xy 179.357126 -267.368715)
			(xy 179.309622 -267.34159) (xy 179.266645 -267.307746) (xy 179.229139 -267.267926) (xy 179.197924 -267.223003)
			(xy 179.173687 -267.173963) (xy 179.156959 -267.12188) (xy 179.152042 -267.09497) (xy 179.148994 -267.076428)
			(xy 179.1208 -267.052298) (xy 176.467262 -267.052298) (xy 176.439068 -267.076428) (xy 176.43602 -267.09497)
			(xy 176.431103 -267.12188) (xy 176.414375 -267.173963) (xy 176.390138 -267.223003) (xy 176.358923 -267.267926)
			(xy 176.321417 -267.307746) (xy 176.27844 -267.34159) (xy 176.230936 -267.368715) (xy 176.179947 -267.388527)
			(xy 176.126591 -267.40059) (xy 176.072038 -267.404641) (xy 176.017485 -267.40059) (xy 175.964129 -267.388527)
			(xy 175.91314 -267.368715) (xy 175.865636 -267.34159) (xy 175.822659 -267.307746) (xy 175.785153 -267.267926)
			(xy 175.753938 -267.223003) (xy 175.729701 -267.173963) (xy 175.712973 -267.12188) (xy 175.708056 -267.09497)
			(xy 175.705008 -267.076428) (xy 175.676814 -267.052298) (xy 172.367194 -267.052298) (xy 172.339 -267.076428)
			(xy 172.335952 -267.09497) (xy 172.331035 -267.12188) (xy 172.314307 -267.173963) (xy 172.29007 -267.223003)
			(xy 172.258855 -267.267926) (xy 172.221349 -267.307746) (xy 172.178372 -267.34159) (xy 172.130868 -267.368715)
			(xy 172.079879 -267.388527) (xy 172.026523 -267.40059) (xy 171.97197 -267.404641) (xy 171.917417 -267.40059)
			(xy 171.864061 -267.388527) (xy 171.813072 -267.368715) (xy 171.765568 -267.34159) (xy 171.722591 -267.307746)
			(xy 171.685085 -267.267926) (xy 171.65387 -267.223003) (xy 171.629633 -267.173963) (xy 171.612905 -267.12188)
			(xy 171.607988 -267.09497) (xy 171.60494 -267.076428) (xy 171.576746 -267.052298) (xy 168.923208 -267.052298)
			(xy 168.895014 -267.076428) (xy 168.891966 -267.09497) (xy 168.887049 -267.12188) (xy 168.870321 -267.173963)
			(xy 168.846084 -267.223003) (xy 168.814869 -267.267926) (xy 168.777363 -267.307746) (xy 168.734386 -267.34159)
			(xy 168.686882 -267.368715) (xy 168.635893 -267.388527) (xy 168.582537 -267.40059) (xy 168.527984 -267.404641)
			(xy 168.473431 -267.40059) (xy 168.420075 -267.388527) (xy 168.369086 -267.368715) (xy 168.321582 -267.34159)
			(xy 168.278605 -267.307746) (xy 168.241099 -267.267926) (xy 168.209884 -267.223003) (xy 168.185647 -267.173963)
			(xy 168.168919 -267.12188) (xy 168.164002 -267.09497) (xy 168.160954 -267.076428) (xy 168.13276 -267.052298)
			(xy 145.690844 -267.052298) (xy 145.666798 -267.051741) (xy 145.619562 -267.042705) (xy 145.574868 -267.024946)
			(xy 145.534312 -266.999099) (xy 145.49934 -266.966085) (xy 145.48485 -266.946888) (xy 145.477233 -266.937382)
			(xy 145.45561 -266.926241) (xy 145.443448 -266.925552) (xy 144.356836 -266.925552) (xy 144.33296 -266.94003)
			(xy 144.326356 -266.952476) (xy 144.313883 -266.974725) (xy 144.283157 -267.015435) (xy 144.246548 -267.05095)
			(xy 144.204924 -267.080426) (xy 144.15927 -267.103167) (xy 144.110667 -267.118633) (xy 144.060266 -267.126459)
			(xy 144.009262 -267.126459) (xy 143.958861 -267.118633) (xy 143.910258 -267.103167) (xy 143.864604 -267.080426)
			(xy 143.82298 -267.05095) (xy 143.786371 -267.015435) (xy 143.755645 -266.974725) (xy 143.743172 -266.952476)
			(xy 143.736568 -266.94003) (xy 143.712692 -266.925552) (xy 143.416782 -266.925552) (xy 143.392906 -266.94003)
			(xy 143.386302 -266.952476) (xy 143.373826 -266.974724) (xy 143.343097 -267.015433) (xy 143.306487 -267.050947)
			(xy 143.264864 -267.080427) (xy 143.219212 -267.103174) (xy 143.170612 -267.11865) (xy 143.120212 -267.126489)
			(xy 143.09471 -267.126974) (xy 143.068721 -267.126492) (xy 143.017383 -267.118361) (xy 142.96795 -267.1023)
			(xy 142.921638 -267.078702) (xy 142.879588 -267.048149) (xy 142.842835 -267.011394) (xy 142.812286 -266.969342)
			(xy 142.788691 -266.923028) (xy 142.772633 -266.873593) (xy 142.764507 -266.822255) (xy 142.764002 -266.796266)
			(xy 142.764411 -266.772908) (xy 142.770988 -266.726657) (xy 142.783994 -266.681787) (xy 142.803171 -266.639188)
			(xy 142.81531 -266.619228) (xy 142.82293 -266.60729) (xy 142.823438 -266.579096) (xy 142.664434 -266.30503)
			(xy 142.640812 -266.291568) (xy 142.627096 -266.291568) (xy 142.62481 -266.291568) (xy 142.600817 -266.291123)
			(xy 142.553423 -266.283617) (xy 142.507787 -266.268789) (xy 142.465032 -266.247003) (xy 142.426212 -266.218797)
			(xy 142.392283 -266.184865) (xy 142.364081 -266.146042) (xy 142.3423 -266.103286) (xy 142.327476 -266.057648)
			(xy 142.319975 -266.010253) (xy 142.319502 -265.98626) (xy 142.320061 -265.959447) (xy 142.329436 -265.906648)
			(xy 142.347908 -265.856304) (xy 142.360904 -265.832844) (xy 142.367762 -265.820906) (xy 142.367762 -265.793728)
			(xy 142.208504 -265.519408) (xy 142.183866 -265.505946) (xy 142.169642 -265.506708) (xy 142.154656 -265.506962)
			(xy 142.12867 -265.506476) (xy 142.07734 -265.498339) (xy 142.027914 -265.482272) (xy 141.98161 -265.458671)
			(xy 141.939569 -265.428117) (xy 141.902824 -265.391363) (xy 141.872282 -265.349313) (xy 141.848694 -265.303003)
			(xy 141.83264 -265.253573) (xy 141.824517 -265.20224) (xy 141.823948 -265.176254) (xy 141.82437 -265.152927)
			(xy 141.83096 -265.106741) (xy 141.843962 -265.061935) (xy 141.863119 -265.019395) (xy 141.875256 -264.99947)
			(xy 141.882876 -264.987278) (xy 141.883384 -264.959084) (xy 141.73835 -264.709656) (xy 141.713712 -264.69594)
			(xy 141.699488 -264.696702) (xy 141.684756 -264.696956) (xy 141.659251 -264.696489) (xy 141.608845 -264.688666)
			(xy 141.560237 -264.673197) (xy 141.514581 -264.650449) (xy 141.472958 -264.620962) (xy 141.436356 -264.585434)
			(xy 141.405642 -264.544707) (xy 141.393164 -264.522458) (xy 141.38656 -264.510012) (xy 141.362684 -264.495788)
			(xy 141.066774 -264.495788) (xy 141.042898 -264.510012) (xy 141.036294 -264.522458) (xy 141.023821 -264.544707)
			(xy 140.993095 -264.585417) (xy 140.956486 -264.620932) (xy 140.914862 -264.650408) (xy 140.869208 -264.673149)
			(xy 140.820605 -264.688615) (xy 140.770204 -264.696441) (xy 140.7192 -264.696441) (xy 140.668799 -264.688615)
			(xy 140.620196 -264.673149) (xy 140.574542 -264.650408) (xy 140.532918 -264.620932) (xy 140.496309 -264.585417)
			(xy 140.465583 -264.544707) (xy 140.45311 -264.522458) (xy 140.446506 -264.510012) (xy 140.42263 -264.495788)
			(xy 140.12672 -264.495788) (xy 140.102844 -264.510012) (xy 140.09624 -264.522458) (xy 140.083767 -264.544707)
			(xy 140.053041 -264.585417) (xy 140.016432 -264.620932) (xy 139.974808 -264.650408) (xy 139.929154 -264.673149)
			(xy 139.880551 -264.688615) (xy 139.83015 -264.696441) (xy 139.779146 -264.696441) (xy 139.728745 -264.688615)
			(xy 139.680142 -264.673149) (xy 139.634488 -264.650408) (xy 139.592864 -264.620932) (xy 139.556255 -264.585417)
			(xy 139.525529 -264.544707) (xy 139.513056 -264.522458) (xy 139.506452 -264.510012) (xy 139.482576 -264.495788)
			(xy 139.18692 -264.495788) (xy 139.163044 -264.510012) (xy 139.15644 -264.522458) (xy 139.143967 -264.544707)
			(xy 139.113241 -264.585417) (xy 139.076632 -264.620932) (xy 139.035008 -264.650408) (xy 138.989354 -264.673149)
			(xy 138.940751 -264.688615) (xy 138.89035 -264.696441) (xy 138.839346 -264.696441) (xy 138.788945 -264.688615)
			(xy 138.740342 -264.673149) (xy 138.694688 -264.650408) (xy 138.653064 -264.620932) (xy 138.616455 -264.585417)
			(xy 138.585729 -264.544707) (xy 138.573256 -264.522458) (xy 138.566652 -264.510012) (xy 138.542776 -264.495788)
			(xy 138.246866 -264.495788) (xy 138.22299 -264.510012) (xy 138.216386 -264.522458) (xy 138.203913 -264.544707)
			(xy 138.173187 -264.585417) (xy 138.136578 -264.620932) (xy 138.094954 -264.650408) (xy 138.0493 -264.673149)
			(xy 138.000697 -264.688615) (xy 137.950296 -264.696441) (xy 137.899292 -264.696441) (xy 137.848891 -264.688615)
			(xy 137.800288 -264.673149) (xy 137.754634 -264.650408) (xy 137.71301 -264.620932) (xy 137.676401 -264.585417)
			(xy 137.645675 -264.544707) (xy 137.633202 -264.522458) (xy 137.626598 -264.510012) (xy 137.602722 -264.495788)
			(xy 137.306812 -264.495788) (xy 137.282936 -264.510012) (xy 137.276332 -264.522458) (xy 137.263858 -264.544708)
			(xy 137.23313 -264.585422) (xy 137.196522 -264.620942) (xy 137.154899 -264.650427) (xy 137.109247 -264.673179)
			(xy 137.060645 -264.688661) (xy 137.010244 -264.696505) (xy 136.98474 -264.696956) (xy 136.958749 -264.696449)
			(xy 136.907407 -264.688324) (xy 136.857968 -264.672267) (xy 136.81165 -264.648674) (xy 136.769592 -264.618126)
			(xy 136.732831 -264.581375) (xy 136.702272 -264.539325) (xy 136.678666 -264.493013) (xy 136.662596 -264.443578)
			(xy 136.654457 -264.392238) (xy 136.654032 -264.366248) (xy 136.654454 -264.342921) (xy 136.661045 -264.296735)
			(xy 136.674047 -264.251929) (xy 136.693204 -264.209389) (xy 136.70534 -264.189464) (xy 136.71296 -264.177272)
			(xy 136.713468 -264.149078) (xy 136.568688 -263.89965) (xy 136.543796 -263.885934) (xy 136.529572 -263.886696)
			(xy 136.51484 -263.88695) (xy 136.489334 -263.886482) (xy 136.438927 -263.878658) (xy 136.390318 -263.86319)
			(xy 136.344658 -263.840445) (xy 136.303031 -263.810961) (xy 136.266422 -263.775438) (xy 136.2357 -263.734716)
			(xy 136.223248 -263.712452) (xy 136.216644 -263.700006) (xy 136.192768 -263.685528) (xy 135.896858 -263.685528)
			(xy 135.872982 -263.700006) (xy 135.866378 -263.712452) (xy 135.853905 -263.734701) (xy 135.823179 -263.775411)
			(xy 135.78657 -263.810926) (xy 135.744946 -263.840402) (xy 135.699292 -263.863143) (xy 135.650689 -263.878609)
			(xy 135.600288 -263.886435) (xy 135.549284 -263.886435) (xy 135.498883 -263.878609) (xy 135.45028 -263.863143)
			(xy 135.404626 -263.840402) (xy 135.363002 -263.810926) (xy 135.326393 -263.775411) (xy 135.295667 -263.734701)
			(xy 135.283194 -263.712452) (xy 135.27659 -263.700006) (xy 135.252714 -263.685528) (xy 134.956804 -263.685528)
			(xy 134.932928 -263.700006) (xy 134.926324 -263.712452) (xy 134.913851 -263.734701) (xy 134.883125 -263.775411)
			(xy 134.846516 -263.810926) (xy 134.804892 -263.840402) (xy 134.759238 -263.863143) (xy 134.710635 -263.878609)
			(xy 134.660234 -263.886435) (xy 134.60923 -263.886435) (xy 134.558829 -263.878609) (xy 134.510226 -263.863143)
			(xy 134.464572 -263.840402) (xy 134.422948 -263.810926) (xy 134.386339 -263.775411) (xy 134.355613 -263.734701)
			(xy 134.34314 -263.712452) (xy 134.336536 -263.700006) (xy 134.31266 -263.685528) (xy 134.01675 -263.685528)
			(xy 133.992874 -263.700006) (xy 133.98627 -263.712452) (xy 133.973797 -263.734701) (xy 133.943071 -263.775411)
			(xy 133.906462 -263.810926) (xy 133.864838 -263.840402) (xy 133.819184 -263.863143) (xy 133.770581 -263.878609)
			(xy 133.72018 -263.886435) (xy 133.669176 -263.886435) (xy 133.618775 -263.878609) (xy 133.570172 -263.863143)
			(xy 133.524518 -263.840402) (xy 133.482894 -263.810926) (xy 133.446285 -263.775411) (xy 133.415559 -263.734701)
			(xy 133.403086 -263.712452) (xy 133.396482 -263.700006) (xy 133.372606 -263.685528) (xy 133.07695 -263.685528)
			(xy 133.053074 -263.700006) (xy 133.04647 -263.712452) (xy 133.033997 -263.734701) (xy 133.003271 -263.775411)
			(xy 132.966662 -263.810926) (xy 132.925038 -263.840402) (xy 132.879384 -263.863143) (xy 132.830781 -263.878609)
			(xy 132.78038 -263.886435) (xy 132.729376 -263.886435) (xy 132.678975 -263.878609) (xy 132.630372 -263.863143)
			(xy 132.584718 -263.840402) (xy 132.543094 -263.810926) (xy 132.506485 -263.775411) (xy 132.475759 -263.734701)
			(xy 132.463286 -263.712452) (xy 132.456682 -263.700006) (xy 132.432806 -263.685528) (xy 132.136896 -263.685528)
			(xy 132.11302 -263.700006) (xy 132.106416 -263.712452) (xy 132.093942 -263.734702) (xy 132.063214 -263.775415)
			(xy 132.026606 -263.810933) (xy 131.984983 -263.840417) (xy 131.93933 -263.863168) (xy 131.890728 -263.878647)
			(xy 131.840327 -263.886489) (xy 131.814824 -263.88695) (xy 131.788834 -263.886442) (xy 131.737495 -263.878315)
			(xy 131.688058 -263.862257) (xy 131.641742 -263.838663) (xy 131.599687 -263.808114) (xy 131.562929 -263.771363)
			(xy 131.532372 -263.729314) (xy 131.508769 -263.683003) (xy 131.4927 -263.63357) (xy 131.484563 -263.582232)
			(xy 131.484116 -263.556242) (xy 131.48437 -263.544812) (xy 131.484878 -263.530334) (xy 131.471162 -263.506204)
			(xy 130.621278 -263.017762) (xy 130.593592 -263.01827) (xy 130.5814 -263.02589) (xy 130.561496 -263.037985)
			(xy 130.519013 -263.057074) (xy 130.474272 -263.070013) (xy 130.428157 -263.076545) (xy 130.40487 -263.076944)
			(xy 130.379363 -263.076478) (xy 130.328953 -263.068658) (xy 130.280341 -263.053193) (xy 130.234678 -263.03045)
			(xy 130.193047 -263.000967) (xy 130.156436 -262.965444) (xy 130.125711 -262.924721) (xy 130.113278 -262.902446)
			(xy 130.106674 -262.89) (xy 130.082798 -262.875776) (xy 129.786888 -262.875776) (xy 129.763012 -262.89)
			(xy 129.756408 -262.902446) (xy 129.743935 -262.924695) (xy 129.713209 -262.965405) (xy 129.6766 -263.00092)
			(xy 129.634976 -263.030396) (xy 129.589322 -263.053137) (xy 129.540719 -263.068603) (xy 129.490318 -263.076429)
			(xy 129.439314 -263.076429) (xy 129.388913 -263.068603) (xy 129.34031 -263.053137) (xy 129.294656 -263.030396)
			(xy 129.253032 -263.00092) (xy 129.216423 -262.965405) (xy 129.185697 -262.924695) (xy 129.173224 -262.902446)
			(xy 129.16662 -262.89) (xy 129.142744 -262.875776) (xy 128.846834 -262.875776) (xy 128.822958 -262.89)
			(xy 128.816354 -262.902446) (xy 128.803881 -262.924695) (xy 128.773155 -262.965405) (xy 128.736546 -263.00092)
			(xy 128.694922 -263.030396) (xy 128.649268 -263.053137) (xy 128.600665 -263.068603) (xy 128.550264 -263.076429)
			(xy 128.49926 -263.076429) (xy 128.448859 -263.068603) (xy 128.400256 -263.053137) (xy 128.354602 -263.030396)
			(xy 128.312978 -263.00092) (xy 128.276369 -262.965405) (xy 128.245643 -262.924695) (xy 128.23317 -262.902446)
			(xy 128.226566 -262.89) (xy 128.20269 -262.875776) (xy 127.90678 -262.875776) (xy 127.882904 -262.89)
			(xy 127.8763 -262.902446) (xy 127.863826 -262.924695) (xy 127.833098 -262.965408) (xy 127.796489 -263.000925)
			(xy 127.754866 -263.030407) (xy 127.709213 -263.053156) (xy 127.660612 -263.068634) (xy 127.610211 -263.076474)
			(xy 127.584708 -263.076944) (xy 127.57531 -263.07669) (xy 127.561086 -263.076436) (xy 127.536956 -263.089898)
			(xy 127.389382 -263.343898) (xy 127.389636 -263.371838) (xy 127.397002 -263.383776) (xy 127.408518 -263.403329)
			(xy 127.426671 -263.444919) (xy 127.438963 -263.4886) (xy 127.445165 -263.533553) (xy 127.445516 -263.556242)
			(xy 127.445006 -263.582229) (xy 127.436876 -263.633564) (xy 127.420815 -263.682994) (xy 127.397219 -263.729304)
			(xy 127.366669 -263.771352) (xy 127.329918 -263.808103) (xy 127.28787 -263.838653) (xy 127.24156 -263.862249)
			(xy 127.19213 -263.87831) (xy 127.140795 -263.88644) (xy 127.088821 -263.88644) (xy 127.037486 -263.87831)
			(xy 126.988056 -263.862249) (xy 126.941746 -263.838653) (xy 126.899698 -263.808103) (xy 126.862947 -263.771352)
			(xy 126.832397 -263.729304) (xy 126.808801 -263.682994) (xy 126.79274 -263.633564) (xy 126.78461 -263.582229)
			(xy 126.7841 -263.556242) (xy 126.784354 -263.544558) (xy 126.784862 -263.530334) (xy 126.7714 -263.50595)
			(xy 125.921262 -263.017762) (xy 125.893576 -263.01827) (xy 125.881384 -263.02589) (xy 125.86148 -263.037984)
			(xy 125.818997 -263.057071) (xy 125.774255 -263.070008) (xy 125.728141 -263.076537) (xy 125.704854 -263.076944)
			(xy 125.695202 -263.07669) (xy 125.681232 -263.076436) (xy 125.656848 -263.089898) (xy 125.509528 -263.344152)
			(xy 125.509782 -263.372092) (xy 125.516894 -263.38403) (xy 125.528392 -263.403556) (xy 125.546521 -263.445084)
			(xy 125.558807 -263.4887) (xy 125.565019 -263.533586) (xy 125.565408 -263.556242) (xy 125.564898 -263.582229)
			(xy 125.556768 -263.633564) (xy 125.540707 -263.682994) (xy 125.517111 -263.729304) (xy 125.486561 -263.771352)
			(xy 125.44981 -263.808103) (xy 125.407762 -263.838653) (xy 125.361452 -263.862249) (xy 125.312022 -263.87831)
			(xy 125.260687 -263.88644) (xy 125.208713 -263.88644) (xy 125.157378 -263.87831) (xy 125.107948 -263.862249)
			(xy 125.061638 -263.838653) (xy 125.01959 -263.808103) (xy 124.982839 -263.771352) (xy 124.952289 -263.729304)
			(xy 124.928693 -263.682994) (xy 124.912632 -263.633564) (xy 124.904502 -263.582229) (xy 124.903992 -263.556242)
			(xy 124.904246 -263.544558) (xy 124.904754 -263.530334) (xy 124.891292 -263.50595) (xy 124.041154 -263.017762)
			(xy 124.013468 -263.01827) (xy 124.001276 -263.02589) (xy 123.981372 -263.037983) (xy 123.938888 -263.05707)
			(xy 123.894147 -263.070005) (xy 123.848033 -263.076533) (xy 123.824746 -263.076944) (xy 123.798753 -263.076464)
			(xy 123.747407 -263.068339) (xy 123.697964 -263.052281) (xy 123.651642 -263.028687) (xy 123.609581 -262.998136)
			(xy 123.572818 -262.961381) (xy 123.542256 -262.919328) (xy 123.51865 -262.873012) (xy 123.50258 -262.823573)
			(xy 123.494442 -262.772229) (xy 123.494038 -262.746236) (xy 123.494292 -262.734552) (xy 123.4948 -262.720328)
			(xy 123.481338 -262.695944) (xy 122.6312 -262.207756) (xy 122.603514 -262.208264) (xy 122.591322 -262.215884)
			(xy 122.571418 -262.22798) (xy 122.528936 -262.247073) (xy 122.484195 -262.260015) (xy 122.43808 -262.26655)
			(xy 122.414792 -262.266938) (xy 122.40514 -262.266684) (xy 122.39117 -262.26643) (xy 122.366786 -262.279892)
			(xy 122.219466 -262.534146) (xy 122.21972 -262.562086) (xy 122.226832 -262.574024) (xy 122.238329 -262.59355)
			(xy 122.256457 -262.635079) (xy 122.268742 -262.678695) (xy 122.274954 -262.72358) (xy 122.275346 -262.746236)
			(xy 122.274836 -262.772223) (xy 122.266706 -262.823558) (xy 122.250645 -262.872988) (xy 122.227049 -262.919298)
			(xy 122.196499 -262.961346) (xy 122.159748 -262.998097) (xy 122.1177 -263.028647) (xy 122.07139 -263.052243)
			(xy 122.02196 -263.068304) (xy 121.970625 -263.076434) (xy 121.918651 -263.076434) (xy 121.867316 -263.068304)
			(xy 121.817886 -263.052243) (xy 121.771576 -263.028647) (xy 121.729528 -262.998097) (xy 121.692777 -262.961346)
			(xy 121.662227 -262.919298) (xy 121.638631 -262.872988) (xy 121.62257 -262.823558) (xy 121.61444 -262.772223)
			(xy 121.61393 -262.746236) (xy 121.614184 -262.734552) (xy 121.614692 -262.720328) (xy 121.60123 -262.695944)
			(xy 120.46585 -262.043672) (xy 120.455182 -262.035544) (xy 120.232424 -261.812532) (xy 120.225002 -261.805747)
			(xy 120.206405 -261.79814) (xy 120.196356 -261.7978) (xy 116.513356 -261.7978) (xy 116.503289 -261.797369)
			(xy 116.484697 -261.789643) (xy 116.477288 -261.782814) (xy 116.365782 -261.671054) (xy 116.337334 -261.664704)
			(xy 116.323364 -261.670038) (xy 116.293004 -261.680242) (xy 116.22991 -261.691224) (xy 116.197888 -261.691882)
			(xy 116.171778 -261.691429) (xy 116.120079 -261.684067) (xy 116.069934 -261.669491) (xy 116.022344 -261.647992)
			(xy 115.97826 -261.62) (xy 115.938561 -261.586074) (xy 115.904041 -261.54689) (xy 115.875388 -261.503233)
			(xy 115.863878 -261.479792) (xy 115.857528 -261.466076) (xy 115.83289 -261.450328) (xy 115.612926 -261.450328)
			(xy 115.588288 -261.466076) (xy 115.581938 -261.479792) (xy 115.569632 -261.504784) (xy 115.53863 -261.551066)
			(xy 115.501025 -261.592163) (xy 115.457671 -261.627142) (xy 115.409551 -261.655208) (xy 115.357761 -261.675723)
			(xy 115.303475 -261.688222) (xy 115.247928 -261.69242) (xy 115.192381 -261.688222) (xy 115.138095 -261.675723)
			(xy 115.086305 -261.655208) (xy 115.038185 -261.627142) (xy 114.994831 -261.592163) (xy 114.957226 -261.551066)
			(xy 114.926224 -261.504784) (xy 114.913918 -261.479792) (xy 114.907568 -261.466076) (xy 114.88293 -261.450328)
			(xy 114.662966 -261.450328) (xy 114.638328 -261.466076) (xy 114.631978 -261.479792) (xy 114.619672 -261.504784)
			(xy 114.58867 -261.551066) (xy 114.551065 -261.592163) (xy 114.507711 -261.627142) (xy 114.459591 -261.655208)
			(xy 114.407801 -261.675723) (xy 114.353515 -261.688222) (xy 114.297968 -261.69242) (xy 114.242421 -261.688222)
			(xy 114.188135 -261.675723) (xy 114.136345 -261.655208) (xy 114.088225 -261.627142) (xy 114.044871 -261.592163)
			(xy 114.007266 -261.551066) (xy 113.976264 -261.504784) (xy 113.963958 -261.479792) (xy 113.957608 -261.466076)
			(xy 113.93297 -261.450328) (xy 113.713006 -261.450328) (xy 113.688368 -261.466076) (xy 113.682018 -261.479792)
			(xy 113.669712 -261.504784) (xy 113.63871 -261.551066) (xy 113.601105 -261.592163) (xy 113.557751 -261.627142)
			(xy 113.509631 -261.655208) (xy 113.457841 -261.675723) (xy 113.403555 -261.688222) (xy 113.348008 -261.69242)
			(xy 113.292461 -261.688222) (xy 113.238175 -261.675723) (xy 113.186385 -261.655208) (xy 113.138265 -261.627142)
			(xy 113.094911 -261.592163) (xy 113.057306 -261.551066) (xy 113.026304 -261.504784) (xy 113.013998 -261.479792)
			(xy 113.007648 -261.466076) (xy 112.98301 -261.450328) (xy 112.762792 -261.450328) (xy 112.738154 -261.466076)
			(xy 112.731804 -261.479792) (xy 112.719498 -261.504784) (xy 112.688496 -261.551066) (xy 112.650891 -261.592163)
			(xy 112.607537 -261.627142) (xy 112.559417 -261.655208) (xy 112.507627 -261.675723) (xy 112.453341 -261.688222)
			(xy 112.397794 -261.69242) (xy 112.342247 -261.688222) (xy 112.287961 -261.675723) (xy 112.236171 -261.655208)
			(xy 112.188051 -261.627142) (xy 112.144697 -261.592163) (xy 112.107092 -261.551066) (xy 112.07609 -261.504784)
			(xy 112.063784 -261.479792) (xy 112.057434 -261.466076) (xy 112.032796 -261.450328) (xy 111.812832 -261.450328)
			(xy 111.788194 -261.466076) (xy 111.781844 -261.479792) (xy 111.769538 -261.504784) (xy 111.738536 -261.551066)
			(xy 111.700931 -261.592163) (xy 111.657577 -261.627142) (xy 111.609457 -261.655208) (xy 111.557667 -261.675723)
			(xy 111.503381 -261.688222) (xy 111.447834 -261.69242) (xy 111.392287 -261.688222) (xy 111.338001 -261.675723)
			(xy 111.286211 -261.655208) (xy 111.238091 -261.627142) (xy 111.194737 -261.592163) (xy 111.157132 -261.551066)
			(xy 111.12613 -261.504784) (xy 111.113824 -261.479792) (xy 111.107474 -261.466076) (xy 111.082836 -261.450328)
			(xy 110.862872 -261.450328) (xy 110.838234 -261.466076) (xy 110.831884 -261.479792) (xy 110.819578 -261.504784)
			(xy 110.788576 -261.551066) (xy 110.750971 -261.592163) (xy 110.707617 -261.627142) (xy 110.659497 -261.655208)
			(xy 110.607707 -261.675723) (xy 110.553421 -261.688222) (xy 110.497874 -261.69242) (xy 110.442327 -261.688222)
			(xy 110.388041 -261.675723) (xy 110.336251 -261.655208) (xy 110.288131 -261.627142) (xy 110.244777 -261.592163)
			(xy 110.207172 -261.551066) (xy 110.17617 -261.504784) (xy 110.163864 -261.479792) (xy 110.157514 -261.466076)
			(xy 110.132876 -261.450328) (xy 109.912912 -261.450328) (xy 109.888274 -261.466076) (xy 109.881924 -261.479792)
			(xy 109.869618 -261.504784) (xy 109.838616 -261.551066) (xy 109.801011 -261.592163) (xy 109.757657 -261.627142)
			(xy 109.709537 -261.655208) (xy 109.657747 -261.675723) (xy 109.603461 -261.688222) (xy 109.547914 -261.69242)
			(xy 109.492367 -261.688222) (xy 109.438081 -261.675723) (xy 109.386291 -261.655208) (xy 109.338171 -261.627142)
			(xy 109.294817 -261.592163) (xy 109.257212 -261.551066) (xy 109.22621 -261.504784) (xy 109.213904 -261.479792)
			(xy 109.207554 -261.466076) (xy 109.182916 -261.450328) (xy 108.962952 -261.450328) (xy 108.938314 -261.466076)
			(xy 108.931964 -261.479792) (xy 108.919658 -261.504784) (xy 108.888656 -261.551066) (xy 108.851051 -261.592163)
			(xy 108.807697 -261.627142) (xy 108.759577 -261.655208) (xy 108.707787 -261.675723) (xy 108.653501 -261.688222)
			(xy 108.597954 -261.69242) (xy 108.542407 -261.688222) (xy 108.488121 -261.675723) (xy 108.436331 -261.655208)
			(xy 108.388211 -261.627142) (xy 108.344857 -261.592163) (xy 108.307252 -261.551066) (xy 108.27625 -261.504784)
			(xy 108.263944 -261.479792) (xy 108.257594 -261.466076) (xy 108.232956 -261.450328) (xy 108.012992 -261.450328)
			(xy 107.988354 -261.466076) (xy 107.982004 -261.479792) (xy 107.969698 -261.504784) (xy 107.938696 -261.551066)
			(xy 107.901091 -261.592163) (xy 107.857737 -261.627142) (xy 107.809617 -261.655208) (xy 107.757827 -261.675723)
			(xy 107.703541 -261.688222) (xy 107.647994 -261.69242) (xy 107.592447 -261.688222) (xy 107.538161 -261.675723)
			(xy 107.486371 -261.655208) (xy 107.438251 -261.627142) (xy 107.394897 -261.592163) (xy 107.357292 -261.551066)
			(xy 107.32629 -261.504784) (xy 107.313984 -261.479792) (xy 107.307634 -261.466076) (xy 107.282996 -261.450328)
			(xy 106.72572 -261.450328) (xy 106.714616 -261.450898) (xy 106.694476 -261.460261) (xy 106.686858 -261.468362)
			(xy 106.669245 -261.488471) (xy 106.629215 -261.523896) (xy 106.584492 -261.553174) (xy 106.536012 -261.575693)
			(xy 106.48479 -261.590981) (xy 106.431899 -261.598719) (xy 106.405172 -261.599172) (xy 106.379365 -261.598776)
			(xy 106.328247 -261.591635) (xy 106.303318 -261.584948) (xy 106.289856 -261.580884) (xy 106.263186 -261.587742)
			(xy 105.838752 -262.01243) (xy 105.832402 -262.040878) (xy 105.837482 -262.054848) (xy 105.847754 -262.085197)
			(xy 105.858862 -262.148292) (xy 105.85958 -262.180324) (xy 105.85913 -262.206668) (xy 105.851629 -262.258819)
			(xy 105.836782 -262.309371) (xy 105.814891 -262.357296) (xy 105.786403 -262.401618) (xy 105.751897 -262.441434)
			(xy 105.712076 -262.475934) (xy 105.66775 -262.504416) (xy 105.619822 -262.5263) (xy 105.569268 -262.54114)
			(xy 105.517116 -262.548634) (xy 105.490772 -262.549132) (xy 105.46017 -262.548528) (xy 105.399805 -262.538422)
			(xy 105.341935 -262.518494) (xy 105.31475 -262.504428) (xy 105.301542 -262.497316) (xy 105.272332 -262.499094)
			(xy 103.689912 -263.663684) (xy 103.685086 -263.666732) (xy 102.554532 -264.315956) (xy 102.54107 -264.34034)
			(xy 102.541578 -264.354564) (xy 102.541832 -264.366248) (xy 102.541322 -264.392235) (xy 102.533192 -264.44357)
			(xy 102.517131 -264.493) (xy 102.493535 -264.53931) (xy 102.462985 -264.581358) (xy 102.426234 -264.618109)
			(xy 102.384186 -264.648659) (xy 102.337876 -264.672255) (xy 102.288446 -264.688316) (xy 102.237111 -264.696446)
			(xy 102.185137 -264.696446) (xy 102.133802 -264.688316) (xy 102.084372 -264.672255) (xy 102.038062 -264.648659)
			(xy 101.996014 -264.618109) (xy 101.959263 -264.581358) (xy 101.928713 -264.53931) (xy 101.905117 -264.493)
			(xy 101.889056 -264.44357) (xy 101.880926 -264.392235) (xy 101.880416 -264.366248) (xy 101.880805 -264.343592)
			(xy 101.887022 -264.298707) (xy 101.899307 -264.255091) (xy 101.917428 -264.213559) (xy 101.92893 -264.194036)
			(xy 101.936042 -264.182098) (xy 101.93655 -264.154158) (xy 101.788976 -263.899904) (xy 101.764592 -263.886442)
			(xy 101.750622 -263.886696) (xy 101.74097 -263.88695) (xy 101.717721 -263.886579) (xy 101.671678 -263.880105)
			(xy 101.626999 -263.867233) (xy 101.584569 -263.848217) (xy 101.564694 -263.83615) (xy 101.552502 -263.828276)
			(xy 101.524562 -263.827768) (xy 100.674678 -264.315956) (xy 100.660962 -264.34034) (xy 100.66147 -264.354818)
			(xy 100.661724 -264.366248) (xy 100.66147 -264.381234) (xy 100.660708 -264.395712) (xy 100.67417 -264.42035)
			(xy 101.52126 -264.907014) (xy 101.549454 -264.906252) (xy 101.561646 -264.898378) (xy 101.581783 -264.88587)
			(xy 101.624877 -264.866122) (xy 101.670349 -264.852731) (xy 101.717268 -264.845971) (xy 101.74097 -264.845546)
			(xy 101.766964 -264.846027) (xy 101.818314 -264.854156) (xy 101.867759 -264.870217) (xy 101.914083 -264.893817)
			(xy 101.956144 -264.924373) (xy 101.992908 -264.961133) (xy 102.023467 -265.003191) (xy 102.047071 -265.049513)
			(xy 102.063137 -265.098957) (xy 102.071271 -265.150306) (xy 102.071271 -265.202294) (xy 102.063137 -265.253643)
			(xy 102.047071 -265.303087) (xy 102.023467 -265.349409) (xy 101.992908 -265.391467) (xy 101.956144 -265.428227)
			(xy 101.914083 -265.458783) (xy 101.867759 -265.482383) (xy 101.818314 -265.498444) (xy 101.766964 -265.506573)
			(xy 101.74097 -265.506962) (xy 101.717683 -265.506563) (xy 101.671571 -265.500025) (xy 101.626831 -265.487084)
			(xy 101.584349 -265.467994) (xy 101.56444 -265.455908) (xy 101.552502 -265.448288) (xy 101.524562 -265.44778)
			(xy 100.674424 -265.935968) (xy 100.660962 -265.960352) (xy 100.66147 -265.974576) (xy 100.661724 -265.98626)
			(xy 100.66147 -266.001246) (xy 100.660708 -266.015724) (xy 100.674424 -266.040362) (xy 101.52126 -266.527026)
			(xy 101.549454 -266.526264) (xy 101.561646 -266.51839) (xy 101.581783 -266.505882) (xy 101.624877 -266.486133)
			(xy 101.670349 -266.472741) (xy 101.717268 -266.465981) (xy 101.74097 -266.465558) (xy 101.76696 -266.466065)
			(xy 101.8183 -266.474192) (xy 101.867737 -266.49025) (xy 101.914053 -266.513844) (xy 101.956108 -266.544392)
			(xy 101.992866 -266.581144) (xy 102.023423 -266.623193) (xy 102.047026 -266.669504) (xy 102.063093 -266.718938)
			(xy 102.07123 -266.770276) (xy 102.071678 -266.796266) (xy 102.071199 -266.821898) (xy 102.063296 -266.872549)
			(xy 102.05593 -266.897104) (xy 102.051358 -266.911074) (xy 102.058216 -266.938506) (xy 102.31755 -267.198094)
			(xy 102.324951 -267.204933) (xy 102.343549 -267.21265) (xy 102.353618 -267.21308) (xy 102.630224 -267.21308)
			(xy 102.636891 -267.212883) (xy 102.649764 -267.209407) (xy 102.655624 -267.206222) (xy 103.27767 -266.847574)
			(xy 103.291132 -266.82319) (xy 103.290624 -266.808712) (xy 103.29037 -266.796266) (xy 103.290882 -266.77028)
			(xy 103.299017 -266.718948) (xy 103.31508 -266.669521) (xy 103.338678 -266.623214) (xy 103.369228 -266.581169)
			(xy 103.405978 -266.54442) (xy 103.448025 -266.513871) (xy 103.494332 -266.490276) (xy 103.54376 -266.474214)
			(xy 103.595092 -266.466081) (xy 103.621078 -266.465558) (xy 103.632508 -266.465812) (xy 103.646732 -266.46632)
			(xy 103.671116 -266.452858) (xy 103.817674 -266.200382) (xy 103.81742 -266.172442) (xy 103.8098 -266.160504)
			(xy 103.798061 -266.140785) (xy 103.779537 -266.098798) (xy 103.766985 -266.054657) (xy 103.760644 -266.009206)
			(xy 103.76027 -265.98626) (xy 103.76078 -265.960273) (xy 103.76891 -265.908938) (xy 103.784971 -265.859508)
			(xy 103.808567 -265.813198) (xy 103.839117 -265.77115) (xy 103.875868 -265.734399) (xy 103.917916 -265.703849)
			(xy 103.964226 -265.680253) (xy 104.013656 -265.664192) (xy 104.064991 -265.656062) (xy 104.116965 -265.656062)
			(xy 104.1683 -265.664192) (xy 104.21773 -265.680253) (xy 104.26404 -265.703849) (xy 104.306088 -265.734399)
			(xy 104.342839 -265.77115) (xy 104.373389 -265.813198) (xy 104.396985 -265.859508) (xy 104.413046 -265.908938)
			(xy 104.421176 -265.960273) (xy 104.421686 -265.98626) (xy 104.421432 -266.001246) (xy 104.42067 -266.015724)
			(xy 104.434132 -266.040362) (xy 105.281222 -266.527026) (xy 105.309416 -266.526264) (xy 105.321608 -266.51839)
			(xy 105.341744 -266.50588) (xy 105.384837 -266.486126) (xy 105.43031 -266.472729) (xy 105.477229 -266.465963)
			(xy 105.500932 -266.465558) (xy 105.526919 -266.46607) (xy 105.578251 -266.474204) (xy 105.62768 -266.490268)
			(xy 105.673987 -266.513865) (xy 105.716034 -266.544414) (xy 105.752784 -266.581165) (xy 105.783334 -266.623211)
			(xy 105.806932 -266.669519) (xy 105.822995 -266.718947) (xy 105.83113 -266.770279) (xy 105.83164 -266.796266)
			(xy 105.831205 -266.819821) (xy 105.824487 -266.86645) (xy 105.811224 -266.911655) (xy 105.791684 -266.954523)
			(xy 105.779316 -266.974574) (xy 105.771696 -266.986766) (xy 105.770934 -267.01496) (xy 105.915206 -267.263372)
			(xy 105.939844 -267.276834) (xy 105.954322 -267.276072) (xy 105.971086 -267.275564) (xy 105.994412 -267.275988)
			(xy 106.040596 -267.282584) (xy 106.085399 -267.295592) (xy 106.127935 -267.314753) (xy 106.14787 -267.326872)
			(xy 106.159808 -267.334492) (xy 106.188256 -267.335) (xy 107.037378 -266.847066) (xy 107.051094 -266.822428)
			(xy 107.050586 -266.808458) (xy 107.050332 -266.796266) (xy 107.050818 -266.77028) (xy 107.058953 -266.718948)
			(xy 107.075019 -266.66952) (xy 107.098619 -266.623215) (xy 107.129173 -266.581171) (xy 107.165927 -266.544425)
			(xy 107.207978 -266.513881) (xy 107.254289 -266.490291) (xy 107.30372 -266.474236) (xy 107.355054 -266.466112)
			(xy 107.38104 -266.465558) (xy 107.39247 -266.465812) (xy 107.406694 -266.46632) (xy 107.431078 -266.452858)
			(xy 107.577636 -266.200382) (xy 107.577382 -266.172442) (xy 107.569762 -266.160504) (xy 107.558025 -266.140784)
			(xy 107.539503 -266.098797) (xy 107.526952 -266.054656) (xy 107.520611 -266.009205) (xy 107.520232 -265.98626)
			(xy 107.520742 -265.960273) (xy 107.528872 -265.908938) (xy 107.544933 -265.859508) (xy 107.568529 -265.813198)
			(xy 107.599079 -265.77115) (xy 107.63583 -265.734399) (xy 107.677878 -265.703849) (xy 107.724188 -265.680253)
			(xy 107.773618 -265.664192) (xy 107.824953 -265.656062) (xy 107.876927 -265.656062) (xy 107.928262 -265.664192)
			(xy 107.977692 -265.680253) (xy 108.024002 -265.703849) (xy 108.06605 -265.734399) (xy 108.102801 -265.77115)
			(xy 108.133351 -265.813198) (xy 108.156947 -265.859508) (xy 108.173008 -265.908938) (xy 108.181138 -265.960273)
			(xy 108.181648 -265.98626) (xy 108.181394 -266.001246) (xy 108.180632 -266.015724) (xy 108.194094 -266.040362)
			(xy 109.041438 -266.527026) (xy 109.069632 -266.526264) (xy 109.081824 -266.51839) (xy 109.10196 -266.505881)
			(xy 109.145054 -266.486129) (xy 109.190526 -266.472734) (xy 109.237446 -266.465971) (xy 109.261148 -266.465558)
			(xy 109.287134 -266.466071) (xy 109.338464 -266.474207) (xy 109.387891 -266.490272) (xy 109.434196 -266.51387)
			(xy 109.47624 -266.54442) (xy 109.512989 -266.58117) (xy 109.543537 -266.623216) (xy 109.567133 -266.669522)
			(xy 109.583196 -266.718949) (xy 109.59133 -266.77028) (xy 109.591856 -266.796266) (xy 109.59144 -266.819853)
			(xy 109.584742 -266.86655) (xy 109.571477 -266.911821) (xy 109.551915 -266.954748) (xy 109.539532 -266.974828)
			(xy 109.531658 -266.98702) (xy 109.53115 -267.015214) (xy 109.675168 -267.263372) (xy 109.699806 -267.276834)
			(xy 109.714284 -267.276072) (xy 109.731048 -267.275564) (xy 109.754375 -267.275986) (xy 109.800561 -267.282577)
			(xy 109.845366 -267.29558) (xy 109.887906 -267.314738) (xy 109.907832 -267.326872) (xy 109.91977 -267.334492)
			(xy 109.948218 -267.335) (xy 111.09198 -266.677648) (xy 111.097855 -266.674522) (xy 111.110727 -266.671166)
			(xy 111.11738 -266.671044) (xy 111.803434 -266.671044) (xy 111.809665 -266.670834) (xy 111.821742 -266.667752)
			(xy 111.82731 -266.664948) (xy 111.853608 -266.651446) (xy 111.90879 -266.630237) (xy 111.966149 -266.615931)
			(xy 112.024827 -266.608741) (xy 112.054386 -266.608306) (xy 112.083943 -266.608754) (xy 112.142616 -266.615966)
			(xy 112.199973 -266.630271) (xy 112.25516 -266.651457) (xy 112.281462 -266.664948) (xy 112.287031 -266.667753)
			(xy 112.299107 -266.670841) (xy 112.305338 -266.671044) (xy 113.63071 -266.671044) (xy 113.65484 -266.656312)
			(xy 113.661444 -266.643612) (xy 113.673786 -266.620968) (xy 113.704407 -266.579475) (xy 113.741097 -266.543237)
			(xy 113.782966 -266.513134) (xy 113.829002 -266.489894) (xy 113.878086 -266.474081) (xy 113.92903 -266.466079)
			(xy 113.954814 -266.465558) (xy 113.978516 -266.465966) (xy 114.025434 -266.472735) (xy 114.070905 -266.486134)
			(xy 114.113997 -266.505888) (xy 114.134138 -266.51839) (xy 114.14633 -266.526264) (xy 114.174524 -266.527026)
			(xy 115.021614 -266.040362) (xy 115.035076 -266.015724) (xy 115.034314 -266.001246) (xy 115.03406 -265.98626)
			(xy 115.03457 -265.960273) (xy 115.0427 -265.908938) (xy 115.058761 -265.859508) (xy 115.082357 -265.813198)
			(xy 115.112907 -265.77115) (xy 115.149658 -265.734399) (xy 115.191706 -265.703849) (xy 115.238016 -265.680253)
			(xy 115.287446 -265.664192) (xy 115.338781 -265.656062) (xy 115.390755 -265.656062) (xy 115.44209 -265.664192)
			(xy 115.49152 -265.680253) (xy 115.53783 -265.703849) (xy 115.579878 -265.734399) (xy 115.616629 -265.77115)
			(xy 115.647179 -265.813198) (xy 115.670775 -265.859508) (xy 115.686836 -265.908938) (xy 115.694966 -265.960273)
			(xy 115.695476 -265.98626) (xy 115.695087 -266.009175) (xy 115.688756 -266.054567) (xy 115.67621 -266.098647)
			(xy 115.657689 -266.140569) (xy 115.645946 -266.16025) (xy 115.638326 -266.172442) (xy 115.638072 -266.200382)
			(xy 115.78463 -266.452858) (xy 115.809014 -266.46632) (xy 115.823238 -266.465812) (xy 115.834668 -266.465558)
			(xy 115.860658 -266.466065) (xy 115.911998 -266.474192) (xy 115.961435 -266.490249) (xy 116.007752 -266.513843)
			(xy 116.049807 -266.544391) (xy 116.086566 -266.581143) (xy 116.117123 -266.623192) (xy 116.140725 -266.669504)
			(xy 116.156793 -266.718938) (xy 116.16493 -266.770276) (xy 116.165376 -266.796266) (xy 116.165122 -266.808204)
			(xy 116.164614 -266.822682) (xy 116.178076 -266.846812) (xy 117.02796 -267.335) (xy 117.055646 -267.334492)
			(xy 117.067838 -267.326872) (xy 117.087756 -267.314718) (xy 117.130287 -267.295527) (xy 117.175097 -267.282518)
			(xy 117.221292 -267.27595) (xy 117.244622 -267.275564) (xy 117.261386 -267.276072) (xy 117.275864 -267.276834)
			(xy 117.300756 -267.263372) (xy 117.444774 -267.01496) (xy 117.444012 -266.986766) (xy 117.436392 -266.974574)
			(xy 117.424021 -266.954523) (xy 117.404465 -266.91166) (xy 117.391195 -266.866455) (xy 117.38448 -266.819822)
			(xy 117.384068 -266.796266) (xy 117.38458 -266.77028) (xy 117.392715 -266.718948) (xy 117.408778 -266.669521)
			(xy 117.432376 -266.623214) (xy 117.462926 -266.581169) (xy 117.499676 -266.544419) (xy 117.541723 -266.51387)
			(xy 117.58803 -266.490275) (xy 117.637458 -266.474212) (xy 117.68879 -266.466079) (xy 117.714776 -266.465558)
			(xy 117.738479 -266.465963) (xy 117.785399 -266.472728) (xy 117.830873 -266.486122) (xy 117.873969 -266.505872)
			(xy 117.8941 -266.51839) (xy 117.906292 -266.526264) (xy 117.934486 -266.527026) (xy 118.781576 -266.040362)
			(xy 118.795038 -266.015724) (xy 118.794276 -266.001246) (xy 118.794022 -265.98626) (xy 118.794532 -265.960273)
			(xy 118.802662 -265.908938) (xy 118.818723 -265.859508) (xy 118.842319 -265.813198) (xy 118.872869 -265.77115)
			(xy 118.90962 -265.734399) (xy 118.951668 -265.703849) (xy 118.997978 -265.680253) (xy 119.047408 -265.664192)
			(xy 119.098743 -265.656062) (xy 119.150717 -265.656062) (xy 119.202052 -265.664192) (xy 119.251482 -265.680253)
			(xy 119.297792 -265.703849) (xy 119.33984 -265.734399) (xy 119.376591 -265.77115) (xy 119.407141 -265.813198)
			(xy 119.430737 -265.859508) (xy 119.446798 -265.908938) (xy 119.454928 -265.960273) (xy 119.455438 -265.98626)
			(xy 119.455049 -266.009175) (xy 119.448717 -266.054566) (xy 119.436169 -266.098645) (xy 119.417647 -266.140566)
			(xy 119.405908 -266.16025) (xy 119.398288 -266.172442) (xy 119.398034 -266.200382) (xy 119.544592 -266.452858)
			(xy 119.568976 -266.46632) (xy 119.5832 -266.465812) (xy 119.59463 -266.465558) (xy 119.620617 -266.46607)
			(xy 119.671949 -266.474204) (xy 119.721378 -266.490267) (xy 119.767686 -266.513864) (xy 119.809733 -266.544414)
			(xy 119.846484 -266.581164) (xy 119.877034 -266.623211) (xy 119.900631 -266.669518) (xy 119.916695 -266.718947)
			(xy 119.92483 -266.770279) (xy 119.925338 -266.796266) (xy 119.925084 -266.808204) (xy 119.924576 -266.822682)
			(xy 119.938038 -266.846812) (xy 120.787668 -267.335) (xy 120.816116 -267.334492) (xy 120.828054 -267.326872)
			(xy 120.847972 -267.314719) (xy 120.890503 -267.29553) (xy 120.935313 -267.282523) (xy 120.981508 -267.275957)
			(xy 121.004838 -267.275564) (xy 121.021602 -267.276072) (xy 121.035826 -267.276834) (xy 121.060718 -267.263372)
			(xy 121.204736 -267.01496) (xy 121.203974 -266.986766) (xy 121.196354 -266.974574) (xy 121.183984 -266.954523)
			(xy 121.16443 -266.911659) (xy 121.151162 -266.866454) (xy 121.144448 -266.819822) (xy 121.14403 -266.796266)
			(xy 121.144516 -266.77028) (xy 121.152651 -266.718947) (xy 121.168717 -266.66952) (xy 121.192317 -266.623214)
			(xy 121.222871 -266.58117) (xy 121.259625 -266.544424) (xy 121.301676 -266.51388) (xy 121.347986 -266.49029)
			(xy 121.397417 -266.474235) (xy 121.448751 -266.46611) (xy 121.474738 -266.465558) (xy 121.498439 -266.465967)
			(xy 121.545356 -266.47274) (xy 121.590825 -266.486142) (xy 121.633915 -266.505898) (xy 121.654062 -266.51839)
			(xy 121.666254 -266.526264) (xy 121.694448 -266.527026) (xy 122.541538 -266.040616) (xy 122.555 -266.015724)
			(xy 122.554238 -266.001246) (xy 122.553984 -265.98626) (xy 122.554494 -265.960273) (xy 122.562624 -265.908938)
			(xy 122.578685 -265.859508) (xy 122.602281 -265.813198) (xy 122.632831 -265.77115) (xy 122.669582 -265.734399)
			(xy 122.71163 -265.703849) (xy 122.75794 -265.680253) (xy 122.80737 -265.664192) (xy 122.858705 -265.656062)
			(xy 122.910679 -265.656062) (xy 122.962014 -265.664192) (xy 123.011444 -265.680253) (xy 123.057754 -265.703849)
			(xy 123.099802 -265.734399) (xy 123.136553 -265.77115) (xy 123.167103 -265.813198) (xy 123.190699 -265.859508)
			(xy 123.20676 -265.908938) (xy 123.21489 -265.960273) (xy 123.2154 -265.98626) (xy 123.215011 -266.009176)
			(xy 123.208681 -266.054567) (xy 123.196135 -266.098647) (xy 123.177616 -266.14057) (xy 123.16587 -266.16025)
			(xy 123.158504 -266.172188) (xy 123.157996 -266.200128) (xy 123.304808 -266.452858) (xy 123.329192 -266.46632)
			(xy 123.343416 -266.465812) (xy 123.354846 -266.465558) (xy 123.380832 -266.466071) (xy 123.432163 -266.474207)
			(xy 123.481589 -266.490272) (xy 123.527895 -266.513869) (xy 123.56994 -266.544419) (xy 123.606688 -266.58117)
			(xy 123.637237 -266.623215) (xy 123.660833 -266.669522) (xy 123.676896 -266.718949) (xy 123.68503 -266.77028)
			(xy 123.685554 -266.796266) (xy 123.6853 -266.808458) (xy 123.684792 -266.822428) (xy 123.698508 -266.847066)
			(xy 124.54763 -267.335) (xy 124.576078 -267.334492) (xy 124.588016 -267.326872) (xy 124.607935 -267.314723)
			(xy 124.650468 -267.295542) (xy 124.695277 -267.282544) (xy 124.741471 -267.275986) (xy 124.7648 -267.275564)
			(xy 124.781564 -267.276072) (xy 124.796042 -267.276834) (xy 124.82068 -267.263372) (xy 124.964698 -267.015214)
			(xy 124.96419 -266.98702) (xy 124.956316 -266.974828) (xy 124.943946 -266.954742) (xy 124.924397 -266.911813)
			(xy 124.911138 -266.866544) (xy 124.904435 -266.819851) (xy 124.903992 -266.796266) (xy 124.904504 -266.770281)
			(xy 124.912639 -266.71895) (xy 124.928703 -266.669524) (xy 124.952301 -266.623219) (xy 124.982851 -266.581176)
			(xy 125.019602 -266.544429) (xy 125.061648 -266.513883) (xy 125.107956 -266.49029) (xy 125.157383 -266.474231)
			(xy 125.208715 -266.466101) (xy 125.2347 -266.465558) (xy 125.260486 -266.466052) (xy 125.311433 -266.474056)
			(xy 125.36052 -266.489872) (xy 125.406557 -266.513115) (xy 125.448429 -266.543221) (xy 125.48512 -266.579462)
			(xy 125.515742 -266.620959) (xy 125.52807 -266.643612) (xy 125.534674 -266.656312) (xy 125.558804 -266.671044)
			(xy 125.879098 -266.671044) (xy 125.902466 -266.657328) (xy 125.909324 -266.645136) (xy 125.921071 -266.625378)
			(xy 125.949569 -266.589314) (xy 125.983148 -266.557925) (xy 126.02105 -266.531921) (xy 126.06242 -266.511889)
			(xy 126.106324 -266.49828) (xy 126.151771 -266.491402) (xy 126.174754 -266.490958) (xy 126.19875 -266.491401)
			(xy 126.246154 -266.498902) (xy 126.2918 -266.513726) (xy 126.334564 -266.535508) (xy 126.373395 -266.563712)
			(xy 126.407336 -266.597644) (xy 126.43555 -266.636467) (xy 126.457344 -266.679226) (xy 126.47218 -266.724869)
			(xy 126.479693 -266.77227) (xy 126.480062 -266.796266) (xy 126.479542 -266.822534) (xy 126.4706 -266.874301)
			(xy 126.452922 -266.923771) (xy 126.440438 -266.946888) (xy 126.43358 -266.958826) (xy 126.433834 -266.985496)
			(xy 126.594616 -267.262864) (xy 126.619 -267.276326) (xy 126.633224 -267.275818) (xy 126.644654 -267.275564)
			(xy 126.670646 -267.276044) (xy 126.721992 -267.284169) (xy 126.771435 -267.300227) (xy 126.817756 -267.323822)
			(xy 126.859816 -267.354373) (xy 126.896579 -267.391127) (xy 126.92714 -267.433181) (xy 126.950745 -267.479497)
			(xy 126.966814 -267.528936) (xy 126.974951 -267.58028) (xy 126.975362 -267.606272) (xy 126.974972 -267.629187)
			(xy 126.968639 -267.674578) (xy 126.956091 -267.718656) (xy 126.937569 -267.760577) (xy 126.925832 -267.780262)
			(xy 126.918466 -267.7922) (xy 126.918212 -267.82014) (xy 127.06477 -268.07287) (xy 127.089154 -268.086332)
			(xy 127.103378 -268.085824) (xy 127.114808 -268.08557) (xy 127.140795 -268.08608) (xy 127.19213 -268.094212)
			(xy 127.241561 -268.110273) (xy 127.287871 -268.133869) (xy 127.32992 -268.164418) (xy 127.366672 -268.201169)
			(xy 127.397224 -268.243217) (xy 127.420822 -268.289526) (xy 127.436885 -268.338956) (xy 127.445019 -268.390291)
			(xy 127.445516 -268.416278) (xy 127.445126 -268.439193) (xy 127.438793 -268.484584) (xy 127.426246 -268.528663)
			(xy 127.407726 -268.570585) (xy 127.395986 -268.590268) (xy 127.38862 -268.602206) (xy 127.388112 -268.630146)
			(xy 127.53467 -268.882876) (xy 127.559054 -268.896338) (xy 127.573278 -268.89583) (xy 127.584708 -268.895576)
			(xy 127.610696 -268.896086) (xy 127.662032 -268.904218) (xy 127.711464 -268.920281) (xy 127.757775 -268.943878)
			(xy 127.799824 -268.974429) (xy 127.836576 -269.011182) (xy 127.867126 -269.053232) (xy 127.890722 -269.099544)
			(xy 127.906784 -269.148976) (xy 127.914914 -269.200312) (xy 127.914914 -269.252288) (xy 127.906784 -269.303624)
			(xy 127.890722 -269.353056) (xy 127.867126 -269.399368) (xy 127.836576 -269.441418) (xy 127.799824 -269.478171)
			(xy 127.757775 -269.508722) (xy 127.711464 -269.532319) (xy 127.662032 -269.548382) (xy 127.610696 -269.556514)
			(xy 127.584708 -269.556992) (xy 127.57531 -269.556738) (xy 127.561086 -269.556484) (xy 127.53721 -269.569946)
			(xy 127.389636 -269.8242) (xy 127.38989 -269.85214) (xy 127.397256 -269.864078) (xy 127.408712 -269.883617)
			(xy 127.426764 -269.925157) (xy 127.438984 -269.968771) (xy 127.445146 -270.013643) (xy 127.445516 -270.03629)
			(xy 127.445034 -270.06228) (xy 127.436904 -270.11362) (xy 127.420842 -270.163057) (xy 127.397245 -270.209372)
			(xy 127.366693 -270.251425) (xy 127.329939 -270.288182) (xy 127.287887 -270.318736) (xy 127.241573 -270.342336)
			(xy 127.192138 -270.358399) (xy 127.140798 -270.366532) (xy 127.114808 -270.366998) (xy 127.10541 -270.366744)
			(xy 127.09144 -270.36649) (xy 127.067056 -270.379952) (xy 126.919482 -270.63446) (xy 126.919736 -270.662146)
			(xy 126.927102 -270.674084) (xy 126.938559 -270.693622) (xy 126.956613 -270.735163) (xy 126.968834 -270.778776)
			(xy 126.974996 -270.823649) (xy 126.975362 -270.846296) (xy 126.974976 -270.869169) (xy 126.968674 -270.914479)
			(xy 126.95619 -270.958489) (xy 126.937762 -271.00036) (xy 126.926086 -271.020032) (xy 126.918466 -271.032224)
			(xy 126.918212 -271.060164) (xy 127.06477 -271.312894) (xy 127.089154 -271.326356) (xy 127.103378 -271.325848)
			(xy 127.114808 -271.325594) (xy 127.140795 -271.326104) (xy 127.192128 -271.334236) (xy 127.241557 -271.350297)
			(xy 127.287866 -271.373894) (xy 127.329913 -271.404444) (xy 127.366663 -271.441195) (xy 127.397211 -271.483243)
			(xy 127.420806 -271.529552) (xy 127.436867 -271.578982) (xy 127.444997 -271.630315) (xy 127.445516 -271.656302)
			(xy 127.445125 -271.679217) (xy 127.438789 -271.724606) (xy 127.426239 -271.768684) (xy 127.407716 -271.810603)
			(xy 127.395986 -271.830292) (xy 127.38862 -271.84223) (xy 127.388112 -271.87017) (xy 127.53467 -272.1229)
			(xy 127.559308 -272.136362) (xy 127.573278 -272.135854) (xy 127.584708 -272.1356) (xy 127.610694 -272.13611)
			(xy 127.662026 -272.144241) (xy 127.711455 -272.160303) (xy 127.757762 -272.183898) (xy 127.799808 -272.214448)
			(xy 127.836558 -272.251198) (xy 127.867106 -272.293245) (xy 127.8907 -272.339553) (xy 127.90676 -272.388981)
			(xy 127.914891 -272.440314) (xy 127.914891 -272.492286) (xy 127.90676 -272.543619) (xy 127.8907 -272.593047)
			(xy 127.867106 -272.639355) (xy 127.836558 -272.681402) (xy 127.799808 -272.718152) (xy 127.757762 -272.748702)
			(xy 127.711455 -272.772297) (xy 127.662026 -272.788359) (xy 127.610694 -272.79649) (xy 127.584708 -272.797016)
			(xy 127.57531 -272.796762) (xy 127.561086 -272.796508) (xy 127.53721 -272.80997) (xy 127.389636 -273.064224)
			(xy 127.38989 -273.092164) (xy 127.397256 -273.104102) (xy 127.408711 -273.123641) (xy 127.426759 -273.165182)
			(xy 127.438977 -273.208796) (xy 127.445135 -273.253668) (xy 127.445516 -273.276314) (xy 127.445005 -273.302301)
			(xy 127.436873 -273.353634) (xy 127.420811 -273.403063) (xy 127.397215 -273.449371) (xy 127.366665 -273.491418)
			(xy 127.329914 -273.528169) (xy 127.287866 -273.558718) (xy 127.241558 -273.582313) (xy 127.192128 -273.598375)
			(xy 127.140795 -273.606506) (xy 127.114808 -273.607022) (xy 127.10541 -273.606768) (xy 127.09144 -273.606514)
			(xy 127.067056 -273.619976) (xy 126.919482 -273.874484) (xy 126.919736 -273.90217) (xy 126.927102 -273.914108)
			(xy 126.938558 -273.933647) (xy 126.956608 -273.975187) (xy 126.968827 -274.018801) (xy 126.974985 -274.063673)
			(xy 126.975362 -274.08632) (xy 126.974974 -274.109193) (xy 126.968669 -274.154501) (xy 126.956183 -274.19851)
			(xy 126.937753 -274.240378) (xy 126.926086 -274.260056) (xy 126.918466 -274.272248) (xy 126.918212 -274.300188)
			(xy 127.06477 -274.552918) (xy 127.089154 -274.56638) (xy 127.103378 -274.565872) (xy 127.114808 -274.565618)
			(xy 127.140796 -274.566102) (xy 127.192132 -274.574234) (xy 127.241564 -274.590297) (xy 127.287874 -274.613896)
			(xy 127.329922 -274.644449) (xy 127.366673 -274.681203) (xy 127.397222 -274.723255) (xy 127.420816 -274.769567)
			(xy 127.436874 -274.819001) (xy 127.445001 -274.870338) (xy 127.445516 -274.896326) (xy 127.445123 -274.91924)
			(xy 127.438784 -274.964628) (xy 127.426232 -275.008704) (xy 127.407707 -275.050622) (xy 127.395986 -275.070316)
			(xy 127.38862 -275.082254) (xy 127.388112 -275.110194) (xy 127.53467 -275.362924) (xy 127.559308 -275.376386)
			(xy 127.573278 -275.375878) (xy 127.584708 -275.375624) (xy 127.610692 -275.376134) (xy 127.662021 -275.384265)
			(xy 127.711446 -275.400325) (xy 127.757749 -275.423919) (xy 127.799792 -275.454466) (xy 127.836539 -275.491214)
			(xy 127.867085 -275.533257) (xy 127.890678 -275.579562) (xy 127.906737 -275.628987) (xy 127.914867 -275.680316)
			(xy 127.914867 -275.732284) (xy 127.906737 -275.783613) (xy 127.890678 -275.833038) (xy 127.867085 -275.879343)
			(xy 127.836539 -275.921386) (xy 127.799792 -275.958134) (xy 127.757749 -275.988681) (xy 127.711446 -276.012275)
			(xy 127.662021 -276.028335) (xy 127.610692 -276.036466) (xy 127.584708 -276.03704) (xy 127.57531 -276.036786)
			(xy 127.561086 -276.036532) (xy 127.53721 -276.049994) (xy 127.389636 -276.304248) (xy 127.38989 -276.332188)
			(xy 127.397256 -276.344126) (xy 127.408716 -276.363664) (xy 127.426773 -276.405204) (xy 127.439001 -276.448817)
			(xy 127.445169 -276.49369) (xy 127.445516 -276.516338) (xy 127.445004 -276.542323) (xy 127.436868 -276.593654)
			(xy 127.420804 -276.64308) (xy 127.397206 -276.689385) (xy 127.366656 -276.731428) (xy 127.329905 -276.768176)
			(xy 127.287859 -276.798722) (xy 127.241552 -276.822316) (xy 127.192125 -276.838375) (xy 127.140794 -276.846506)
			(xy 127.114808 -276.847046) (xy 127.10541 -276.846792) (xy 127.09144 -276.846538) (xy 127.067056 -276.86)
			(xy 126.919482 -277.114508) (xy 126.919736 -277.142194) (xy 126.927102 -277.154132) (xy 126.938563 -277.17367)
			(xy 126.956622 -277.215209) (xy 126.968851 -277.258823) (xy 126.97502 -277.303696) (xy 126.975362 -277.326344)
			(xy 126.974979 -277.349218) (xy 126.968684 -277.394531) (xy 126.956206 -277.438545) (xy 126.937783 -277.48042)
			(xy 126.926086 -277.50008) (xy 126.918466 -277.512272) (xy 126.918212 -277.540212) (xy 127.06477 -277.792942)
			(xy 127.089154 -277.806404) (xy 127.103378 -277.805896) (xy 127.114808 -277.805642) (xy 127.140795 -277.806126)
			(xy 127.19213 -277.814258) (xy 127.24156 -277.830322) (xy 127.287869 -277.853921) (xy 127.329915 -277.884474)
			(xy 127.366664 -277.921229) (xy 127.397209 -277.963281) (xy 127.4208 -278.009593) (xy 127.436855 -278.059026)
			(xy 127.444979 -278.110362) (xy 127.445516 -278.13635) (xy 127.445128 -278.159266) (xy 127.438799 -278.204658)
			(xy 127.426255 -278.248739) (xy 127.407738 -278.290663) (xy 127.395986 -278.31034) (xy 127.38862 -278.322532)
			(xy 127.388112 -278.350218) (xy 127.53467 -278.602948) (xy 127.559054 -278.61641) (xy 127.573278 -278.615902)
			(xy 127.584708 -278.615648) (xy 127.610698 -278.616158) (xy 127.662039 -278.624291) (xy 127.711475 -278.640355)
			(xy 127.757789 -278.663954) (xy 127.799842 -278.694508) (xy 127.836597 -278.731264) (xy 127.86715 -278.773318)
			(xy 127.890748 -278.819633) (xy 127.906811 -278.869069) (xy 127.914942 -278.92041) (xy 127.914942 -278.97239)
			(xy 127.906811 -279.023731) (xy 127.890748 -279.073167) (xy 127.86715 -279.119482) (xy 127.836597 -279.161536)
			(xy 127.799842 -279.198292) (xy 127.757789 -279.228846) (xy 127.711475 -279.252445) (xy 127.662039 -279.268509)
			(xy 127.610698 -279.276642) (xy 127.584708 -279.277064) (xy 127.561835 -279.276678) (xy 127.516524 -279.270377)
			(xy 127.472514 -279.257893) (xy 127.430643 -279.239466) (xy 127.410972 -279.227788) (xy 127.399034 -279.220422)
			(xy 127.371094 -279.219914) (xy 126.51867 -279.709372) (xy 126.504954 -279.733756) (xy 126.505462 -279.747726)
			(xy 126.505462 -279.756362) (xy 126.505073 -279.779277) (xy 126.498741 -279.824668) (xy 126.486194 -279.868748)
			(xy 126.467673 -279.910669) (xy 126.455932 -279.930352) (xy 126.448566 -279.94229) (xy 126.448058 -279.97023)
			(xy 126.594616 -280.22296) (xy 126.619 -280.236422) (xy 126.633224 -280.235914) (xy 126.644654 -280.23566)
			(xy 126.670647 -280.23614) (xy 126.721993 -280.244265) (xy 126.771435 -280.260323) (xy 126.817757 -280.283918)
			(xy 126.859818 -280.314468) (xy 126.896581 -280.351223) (xy 126.927142 -280.393276) (xy 126.950747 -280.439593)
			(xy 126.966817 -280.489031) (xy 126.974954 -280.540376) (xy 126.975362 -280.566368) (xy 126.974972 -280.589283)
			(xy 126.96864 -280.634674) (xy 126.956092 -280.678753) (xy 126.93757 -280.720674) (xy 126.925832 -280.740358)
			(xy 126.918466 -280.752296) (xy 126.917958 -280.780236) (xy 127.06477 -281.032966) (xy 127.089154 -281.046428)
			(xy 127.103124 -281.04592) (xy 127.114808 -281.045666) (xy 127.140797 -281.046176) (xy 127.192134 -281.054308)
			(xy 127.241568 -281.070371) (xy 127.28788 -281.09397) (xy 127.32993 -281.124522) (xy 127.366683 -281.161276)
			(xy 127.397235 -281.203327) (xy 127.420832 -281.24964) (xy 127.436893 -281.299073) (xy 127.445024 -281.350411)
			(xy 127.445024 -281.402389) (xy 127.436893 -281.453727) (xy 127.420832 -281.50316) (xy 127.397235 -281.549473)
			(xy 127.366683 -281.591524) (xy 127.32993 -281.628278) (xy 127.28788 -281.65883) (xy 127.241568 -281.682429)
			(xy 127.192134 -281.698492) (xy 127.140797 -281.706624) (xy 127.114808 -281.707082) (xy 127.10541 -281.706828)
			(xy 127.09144 -281.706574) (xy 127.066802 -281.720036) (xy 126.919228 -281.974544) (xy 126.919736 -282.00223)
			(xy 126.927102 -282.014168) (xy 126.93856 -282.033706) (xy 126.956616 -282.075246) (xy 126.96884 -282.11886)
			(xy 126.975003 -282.163733) (xy 126.975362 -282.18638) (xy 126.974977 -282.209253) (xy 126.968677 -282.254564)
			(xy 126.956195 -282.298576) (xy 126.937769 -282.340447) (xy 126.926086 -282.360116) (xy 126.918466 -282.372308)
			(xy 126.918212 -282.400248) (xy 127.06477 -282.652978) (xy 127.089154 -282.66644) (xy 127.103378 -282.665932)
			(xy 127.114808 -282.665678) (xy 127.140795 -282.666188) (xy 127.19213 -282.67432) (xy 127.24156 -282.690381)
			(xy 127.287869 -282.713977) (xy 127.329918 -282.744527) (xy 127.366669 -282.781278) (xy 127.39722 -282.823326)
			(xy 127.420817 -282.869635) (xy 127.436879 -282.919065) (xy 127.445011 -282.970399) (xy 127.445516 -282.996386)
			(xy 127.445126 -283.019301) (xy 127.438792 -283.064691) (xy 127.426244 -283.10877) (xy 127.407723 -283.150691)
			(xy 127.395986 -283.170376) (xy 127.38862 -283.182314) (xy 127.388112 -283.210254) (xy 127.53467 -283.462984)
			(xy 127.559308 -283.476446) (xy 127.573278 -283.475938) (xy 127.584708 -283.475684) (xy 127.610695 -283.476194)
			(xy 127.66203 -283.484326) (xy 127.711461 -283.500388) (xy 127.75777 -283.523985) (xy 127.799818 -283.554535)
			(xy 127.83657 -283.591288) (xy 127.867119 -283.633336) (xy 127.890715 -283.679647) (xy 127.906776 -283.729078)
			(xy 127.914906 -283.780413) (xy 127.914906 -283.832387) (xy 127.906776 -283.883722) (xy 127.890715 -283.933153)
			(xy 127.867119 -283.979464) (xy 127.83657 -284.021512) (xy 127.799818 -284.058265) (xy 127.75777 -284.088815)
			(xy 127.711461 -284.112412) (xy 127.66203 -284.128474) (xy 127.610695 -284.136606) (xy 127.584708 -284.1371)
			(xy 127.57531 -284.136846) (xy 127.561086 -284.136592) (xy 127.53721 -284.150054) (xy 127.389636 -284.404308)
			(xy 127.38989 -284.432248) (xy 127.397256 -284.444186) (xy 127.408712 -284.463725) (xy 127.426762 -284.505266)
			(xy 127.438982 -284.548879) (xy 127.445142 -284.593751) (xy 127.445516 -284.616398) (xy 127.445007 -284.642386)
			(xy 127.436876 -284.693721) (xy 127.420816 -284.743152) (xy 127.39722 -284.789462) (xy 127.36667 -284.831511)
			(xy 127.329919 -284.868264) (xy 127.287871 -284.898815) (xy 127.241561 -284.922412) (xy 127.19213 -284.938474)
			(xy 127.140795 -284.946606) (xy 127.114808 -284.947106) (xy 127.10541 -284.946852) (xy 127.09144 -284.946598)
			(xy 127.067056 -284.96006) (xy 126.919482 -285.214568) (xy 126.919736 -285.242254) (xy 126.927102 -285.254192)
			(xy 126.938559 -285.27373) (xy 126.956611 -285.315271) (xy 126.968832 -285.358885) (xy 126.974993 -285.403757)
			(xy 126.975362 -285.426404) (xy 126.974975 -285.449277) (xy 126.968672 -285.494587) (xy 126.956188 -285.538596)
			(xy 126.937759 -285.580466) (xy 126.926086 -285.60014) (xy 126.918466 -285.612332) (xy 126.918212 -285.640272)
			(xy 127.06477 -285.893002) (xy 127.089154 -285.906464) (xy 127.103378 -285.905956) (xy 127.114808 -285.905702)
			(xy 127.140797 -285.906186) (xy 127.192134 -285.914318) (xy 127.241566 -285.930381) (xy 127.287878 -285.953979)
			(xy 127.329927 -285.984532) (xy 127.36668 -286.021286) (xy 127.39723 -286.063338) (xy 127.420826 -286.10965)
			(xy 127.436886 -286.159084) (xy 127.445016 -286.210421) (xy 127.445516 -286.23641) (xy 127.445124 -286.259325)
			(xy 127.438787 -286.304713) (xy 127.426237 -286.348791) (xy 127.407713 -286.39071) (xy 127.395986 -286.4104)
			(xy 127.38862 -286.422338) (xy 127.388112 -286.450278) (xy 127.53467 -286.702754) (xy 127.559054 -286.716216)
			(xy 127.573278 -286.715708) (xy 127.584708 -286.715454) (xy 127.610698 -286.715964) (xy 127.662037 -286.724097)
			(xy 127.711472 -286.74016) (xy 127.757786 -286.763759) (xy 127.799838 -286.794313) (xy 127.836593 -286.831068)
			(xy 127.867145 -286.873121) (xy 127.890743 -286.919435) (xy 127.906805 -286.968871) (xy 127.914936 -287.02021)
			(xy 127.914936 -287.07219) (xy 127.906805 -287.123529) (xy 127.890743 -287.172965) (xy 127.867145 -287.219279)
			(xy 127.836593 -287.261332) (xy 127.799838 -287.298087) (xy 127.757786 -287.328641) (xy 127.711472 -287.35224)
			(xy 127.662037 -287.368303) (xy 127.610698 -287.376436) (xy 127.584708 -287.37687) (xy 127.575564 -287.376616)
			(xy 127.56134 -287.376362) (xy 127.53721 -287.389824) (xy 127.389636 -287.644332) (xy 127.38989 -287.672272)
			(xy 127.397256 -287.68421) (xy 127.40871 -287.703749) (xy 127.426757 -287.745291) (xy 127.438974 -287.788904)
			(xy 127.445131 -287.833776) (xy 127.445516 -287.856422) (xy 127.445005 -287.882408) (xy 127.436872 -287.933741)
			(xy 127.420809 -287.983169) (xy 127.397212 -288.029476) (xy 127.366662 -288.071522) (xy 127.329911 -288.108271)
			(xy 127.287864 -288.138819) (xy 127.241556 -288.162414) (xy 127.192127 -288.178475) (xy 127.140794 -288.186606)
			(xy 127.114808 -288.18713) (xy 127.10541 -288.186876) (xy 127.09144 -288.186622) (xy 127.067056 -288.200084)
			(xy 126.919482 -288.454592) (xy 126.919736 -288.482024) (xy 126.927102 -288.494216) (xy 126.938553 -288.513722)
			(xy 126.956598 -288.555198) (xy 126.968815 -288.598748) (xy 126.974976 -288.643558) (xy 126.975362 -288.666174)
			(xy 126.974972 -288.689089) (xy 126.968639 -288.734479) (xy 126.95609 -288.778558) (xy 126.937568 -288.820478)
			(xy 126.925832 -288.840164) (xy 126.918466 -288.852102) (xy 126.918212 -288.880042) (xy 127.06477 -289.132772)
			(xy 127.089154 -289.146234) (xy 127.103378 -289.145726) (xy 127.114808 -289.145472) (xy 127.140795 -289.145982)
			(xy 127.19213 -289.154114) (xy 127.241561 -289.170175) (xy 127.287871 -289.193771) (xy 127.329919 -289.224321)
			(xy 127.366672 -289.261072) (xy 127.397223 -289.303119) (xy 127.42082 -289.349428) (xy 127.436884 -289.398858)
			(xy 127.445017 -289.450193) (xy 127.445516 -289.47618) (xy 127.445126 -289.499095) (xy 127.438793 -289.544486)
			(xy 127.426246 -289.588565) (xy 127.407725 -289.630486) (xy 127.395986 -289.65017) (xy 127.38862 -289.662362)
			(xy 127.388112 -289.690048) (xy 127.53467 -289.942778) (xy 127.559054 -289.95624) (xy 127.573278 -289.955732)
			(xy 127.584708 -289.955478) (xy 127.610695 -289.955988) (xy 127.66203 -289.96412) (xy 127.71146 -289.980181)
			(xy 127.757769 -290.003777) (xy 127.799818 -290.034327) (xy 127.836569 -290.071078) (xy 127.86712 -290.113126)
			(xy 127.890717 -290.159435) (xy 127.906779 -290.208865) (xy 127.914911 -290.260199) (xy 127.915416 -290.286186)
			(xy 127.915026 -290.309101) (xy 127.908692 -290.354491) (xy 127.896144 -290.39857) (xy 127.877623 -290.440491)
			(xy 127.865886 -290.460176) (xy 127.85852 -290.472114) (xy 127.858012 -290.500054) (xy 128.004824 -290.752784)
			(xy 128.029208 -290.766246) (xy 128.043432 -290.765738) (xy 128.054862 -290.765484) (xy 128.080853 -290.765964)
			(xy 128.132197 -290.774091) (xy 128.181637 -290.79015) (xy 128.227956 -290.813745) (xy 128.270014 -290.844297)
			(xy 128.306774 -290.881051) (xy 128.337331 -290.923104) (xy 128.360933 -290.96942) (xy 128.376999 -291.018858)
			(xy 128.385132 -291.070201) (xy 128.38557 -291.096192) (xy 128.385179 -291.119107) (xy 128.378843 -291.164496)
			(xy 128.366293 -291.208574) (xy 128.347769 -291.250493) (xy 128.33604 -291.270182) (xy 128.328674 -291.282374)
			(xy 128.328166 -291.31006) (xy 128.474724 -291.56279) (xy 128.499108 -291.576252) (xy 128.513332 -291.575744)
			(xy 128.524762 -291.57549) (xy 128.550753 -291.57597) (xy 128.602097 -291.584097) (xy 128.651536 -291.600156)
			(xy 128.697855 -291.623751) (xy 128.739912 -291.654303) (xy 128.776671 -291.691058) (xy 128.807228 -291.733111)
			(xy 128.830829 -291.779427) (xy 128.846894 -291.828864) (xy 128.855027 -291.880207) (xy 128.85547 -291.906198)
			(xy 128.855078 -291.929113) (xy 128.848742 -291.974502) (xy 128.836191 -292.018579) (xy 128.817667 -292.060497)
			(xy 128.80594 -292.080188) (xy 128.798574 -292.092126) (xy 128.798066 -292.120066) (xy 128.944624 -292.372796)
			(xy 128.969008 -292.386258) (xy 128.983232 -292.38575) (xy 128.994662 -292.385496) (xy 129.020653 -292.385976)
			(xy 129.071996 -292.394103) (xy 129.121435 -292.410162) (xy 129.167754 -292.433758) (xy 129.20981 -292.464309)
			(xy 129.246569 -292.501064) (xy 129.277125 -292.543117) (xy 129.300725 -292.589433) (xy 129.316789 -292.638871)
			(xy 129.324921 -292.690213) (xy 129.32537 -292.716204) (xy 129.324995 -292.739109) (xy 129.318707 -292.784484)
			(xy 129.306222 -292.828559) (xy 129.287781 -292.870491) (xy 129.276094 -292.890194) (xy 129.268474 -292.902132)
			(xy 129.26822 -292.930072) (xy 129.414778 -293.182802) (xy 129.439162 -293.196264) (xy 129.453386 -293.195756)
			(xy 129.464816 -293.195502) (xy 129.490601 -293.195997) (xy 129.541545 -293.204004) (xy 129.590628 -293.219823)
			(xy 129.636661 -293.243068) (xy 129.678528 -293.273178) (xy 129.715213 -293.309421) (xy 129.745828 -293.35092)
			(xy 129.758186 -293.373556) (xy 129.76479 -293.386256) (xy 129.78892 -293.400988) (xy 130.080766 -293.400988)
			(xy 130.104896 -293.386256) (xy 130.1115 -293.373556) (xy 130.12384 -293.350908) (xy 130.154456 -293.309405)
			(xy 130.191143 -293.273158) (xy 130.233012 -293.243045) (xy 130.279049 -293.219795) (xy 130.328135 -293.203974)
			(xy 130.379083 -293.195964) (xy 130.40487 -293.195502) (xy 130.430861 -293.195983) (xy 130.482202 -293.20411)
			(xy 130.53164 -293.22017) (xy 130.577957 -293.243767) (xy 130.620011 -293.274318) (xy 130.656769 -293.311073)
			(xy 130.687323 -293.353126) (xy 130.710922 -293.399441) (xy 130.726985 -293.448878) (xy 130.735116 -293.50022)
			(xy 130.735578 -293.52621) (xy 130.735186 -293.549124) (xy 130.728848 -293.594513) (xy 130.716297 -293.638589)
			(xy 130.697771 -293.680507) (xy 130.686048 -293.7002) (xy 130.678682 -293.712392) (xy 130.678174 -293.740332)
			(xy 130.824732 -293.992808) (xy 130.849116 -294.00627) (xy 130.86334 -294.005762) (xy 130.87477 -294.005508)
			(xy 130.90076 -294.005989) (xy 130.952102 -294.014117) (xy 131.001539 -294.030176) (xy 131.047855 -294.053773)
			(xy 131.08991 -294.084325) (xy 131.126666 -294.12108) (xy 131.15722 -294.163133) (xy 131.180818 -294.209448)
			(xy 131.19688 -294.258885) (xy 131.20501 -294.310226) (xy 131.205478 -294.336216) (xy 131.205086 -294.35913)
			(xy 131.198747 -294.404519) (xy 131.186195 -294.448595) (xy 131.167669 -294.490512) (xy 131.155948 -294.510206)
			(xy 131.148582 -294.522144) (xy 131.148328 -294.550084) (xy 131.294886 -294.802814) (xy 131.31927 -294.816276)
			(xy 131.33324 -294.815768) (xy 131.34467 -294.815514) (xy 131.37066 -294.815995) (xy 131.422001 -294.824123)
			(xy 131.471438 -294.840182) (xy 131.517754 -294.863779) (xy 131.559808 -294.894331) (xy 131.596564 -294.931086)
			(xy 131.627117 -294.973139) (xy 131.650715 -295.019454) (xy 131.666776 -295.068891) (xy 131.674904 -295.120232)
			(xy 131.675378 -295.146222) (xy 131.67499 -295.169095) (xy 131.668685 -295.214404) (xy 131.656199 -295.258412)
			(xy 131.637769 -295.300281) (xy 131.626102 -295.319958) (xy 131.618482 -295.33215) (xy 131.618228 -295.359836)
			(xy 131.780534 -295.63949) (xy 131.803648 -295.652952) (xy 131.817618 -295.652952) (xy 131.843633 -295.653399)
			(xy 131.895032 -295.66147) (xy 131.944534 -295.677489) (xy 131.990917 -295.701061) (xy 132.033038 -295.731604)
			(xy 132.069857 -295.768365) (xy 132.100466 -295.810437) (xy 132.124111 -295.856783) (xy 132.140208 -295.906259)
			(xy 132.14836 -295.957646) (xy 132.148834 -295.98366) (xy 132.148325 -296.010354) (xy 132.139749 -296.063048)
			(xy 132.122812 -296.113678) (xy 132.097956 -296.160926) (xy 132.082286 -296.182542) (xy 132.077618 -296.189283)
			(xy 132.07244 -296.204829) (xy 132.072126 -296.213022) (xy 132.072126 -304.780442) (xy 140.011662 -304.780442)
			(xy 140.015692 -304.638092) (xy 140.027769 -304.496199) (xy 140.047854 -304.355216) (xy 140.075883 -304.215595)
			(xy 140.111767 -304.077783) (xy 140.155389 -303.942222) (xy 140.206611 -303.809347) (xy 140.265269 -303.679582)
			(xy 140.331174 -303.553343) (xy 140.404115 -303.431035) (xy 140.483859 -303.31305) (xy 140.570151 -303.199765)
			(xy 140.662713 -303.091544) (xy 140.76125 -302.988732) (xy 140.865445 -302.89166) (xy 140.974966 -302.800639)
			(xy 141.08946 -302.715959) (xy 141.208562 -302.637893) (xy 141.33189 -302.566689) (xy 141.459048 -302.502577)
			(xy 141.58963 -302.445762) (xy 141.723218 -302.396425) (xy 141.859382 -302.354725) (xy 141.997688 -302.320796)
			(xy 142.137691 -302.294745) (xy 142.278945 -302.276657) (xy 142.420995 -302.266589) (xy 142.563387 -302.264574)
			(xy 142.705666 -302.270618) (xy 142.847374 -302.284701) (xy 142.988059 -302.30678) (xy 143.127269 -302.336782)
			(xy 143.264559 -302.374612) (xy 143.399489 -302.420148) (xy 143.531627 -302.473246) (xy 143.660549 -302.533733)
			(xy 143.785842 -302.601418) (xy 143.907105 -302.676083) (xy 144.02395 -302.757489) (xy 144.136003 -302.845375)
			(xy 144.242903 -302.939459) (xy 144.34431 -303.039441) (xy 144.439898 -303.144999) (xy 144.529361 -303.255797)
			(xy 144.612412 -303.371478) (xy 144.688785 -303.491673) (xy 144.758236 -303.615996) (xy 144.820542 -303.744049)
			(xy 144.875504 -303.875422) (xy 144.922945 -304.009694) (xy 144.962714 -304.146435) (xy 144.994683 -304.285207)
			(xy 145.01875 -304.425565) (xy 145.034838 -304.56706) (xy 145.042894 -304.709239) (xy 145.043398 -304.780442)
			(xy 145.042894 -304.851645) (xy 145.034838 -304.993824) (xy 145.01875 -305.135319) (xy 144.994683 -305.275677)
			(xy 144.962714 -305.414449) (xy 144.922945 -305.55119) (xy 144.875504 -305.685462) (xy 144.820542 -305.816835)
			(xy 144.758236 -305.944888) (xy 144.688785 -306.069211) (xy 144.612412 -306.189406) (xy 144.529361 -306.305087)
			(xy 144.439898 -306.415885) (xy 144.34431 -306.521443) (xy 144.242903 -306.621425) (xy 144.136003 -306.715509)
			(xy 144.02395 -306.803395) (xy 143.907105 -306.884801) (xy 143.785842 -306.959466) (xy 143.660549 -307.027151)
			(xy 143.531627 -307.087638) (xy 143.399489 -307.140736) (xy 143.264559 -307.186272) (xy 143.127269 -307.224102)
			(xy 142.988059 -307.254104) (xy 142.847374 -307.276183) (xy 142.705666 -307.290266) (xy 142.563387 -307.29631)
			(xy 142.420995 -307.294295) (xy 142.278945 -307.284227) (xy 142.137691 -307.266139) (xy 141.997688 -307.240088)
			(xy 141.859382 -307.206159) (xy 141.723218 -307.164459) (xy 141.58963 -307.115122) (xy 141.459048 -307.058307)
			(xy 141.33189 -306.994195) (xy 141.208562 -306.922991) (xy 141.08946 -306.844925) (xy 140.974966 -306.760245)
			(xy 140.865445 -306.669224) (xy 140.76125 -306.572152) (xy 140.662713 -306.46934) (xy 140.570151 -306.361119)
			(xy 140.483859 -306.247834) (xy 140.404115 -306.129849) (xy 140.331174 -306.007541) (xy 140.265269 -305.881302)
			(xy 140.206611 -305.751537) (xy 140.155389 -305.618662) (xy 140.111767 -305.483101) (xy 140.075883 -305.345289)
			(xy 140.047854 -305.205668) (xy 140.027769 -305.064685) (xy 140.015692 -304.922792) (xy 140.011662 -304.780442)
			(xy 132.072126 -304.780442) (xy 132.072126 -341.691976) (xy 132.072564 -341.702039) (xy 132.0803 -341.720621)
			(xy 132.087112 -341.728044) (xy 132.326634 -341.967566) (xy 132.334033 -341.974411) (xy 132.352631 -341.982138)
			(xy 132.362702 -341.982552)
		)
		(stroke
			(width 0)
			(type solid)
		)
		(fill yes)
		(layer "In9.Cu")
		(net "PVDD11_S3_P1")
	)
	(gr_poly
		(pts
			(xy 391.674604 -266.656566) (xy 391.681208 -266.643866) (xy 391.693531 -266.621165) (xy 391.724135 -266.579557)
			(xy 391.760835 -266.543213) (xy 391.80274 -266.513017) (xy 391.84883 -266.489703) (xy 391.897984 -266.473838)
			(xy 391.949007 -266.465808) (xy 392.000657 -266.465808) (xy 392.05168 -266.473838) (xy 392.100834 -266.489703)
			(xy 392.146924 -266.513017) (xy 392.188829 -266.543213) (xy 392.225529 -266.579557) (xy 392.256133 -266.621165)
			(xy 392.268456 -266.643866) (xy 392.27506 -266.656566) (xy 392.29919 -266.671298) (xy 393.383262 -266.671298)
			(xy 393.395402 -266.670682) (xy 393.417037 -266.65968) (xy 393.424664 -266.650216) (xy 393.439162 -266.630958)
			(xy 393.474123 -266.597782) (xy 393.514716 -266.571797) (xy 393.559482 -266.553939) (xy 393.606813 -266.544847)
			(xy 393.630912 -266.544298) (xy 425.110148 -266.544298) (xy 425.120214 -266.543866) (xy 425.138806 -266.536139)
			(xy 425.146216 -266.529312) (xy 425.477432 -266.198096) (xy 425.484285 -266.190701) (xy 425.492029 -266.172102)
			(xy 425.492418 -266.162028) (xy 425.492418 -195.452238) (xy 425.492164 -195.45173) (xy 425.492164 -191.180466)
			(xy 425.492418 -191.179196) (xy 425.492418 -191.078866) (xy 425.492983 -191.054147) (xy 425.502501 -191.005635)
			(xy 425.521229 -190.959884) (xy 425.534328 -190.938912) (xy 425.538646 -190.932562) (xy 425.542964 -190.918592)
			(xy 425.542964 -175.539908) (xy 425.542542 -175.529838) (xy 425.534825 -175.511235) (xy 425.527978 -175.50384)
			(xy 424.985942 -174.961804) (xy 424.97852 -174.955019) (xy 424.959923 -174.947409) (xy 424.949874 -174.947072)
			(xy 417.956492 -174.947072) (xy 417.956492 -174.946564) (xy 412.05277 -174.946564) (xy 412.042704 -174.946994)
			(xy 412.024113 -174.954724) (xy 412.016702 -174.96155) (xy 407.28011 -179.698142) (xy 407.262068 -179.715398)
			(xy 407.220573 -179.743148) (xy 407.174455 -179.762253) (xy 407.125492 -179.771977) (xy 407.100532 -179.772564)
			(xy 403.67077 -179.772564) (xy 403.660704 -179.772994) (xy 403.642113 -179.780724) (xy 403.634702 -179.78755)
			(xy 402.162518 -181.259734) (xy 402.155675 -181.267133) (xy 402.14795 -181.285732) (xy 402.147532 -181.295802)
			(xy 402.147532 -186.249564) (xy 402.146915 -186.274518) (xy 402.137167 -186.323466) (xy 402.11806 -186.369573)
			(xy 402.090327 -186.411068) (xy 402.07311 -186.429142) (xy 400.16811 -188.334142) (xy 400.150068 -188.351398)
			(xy 400.108573 -188.379148) (xy 400.062455 -188.398253) (xy 400.013492 -188.407977) (xy 399.988532 -188.408564)
			(xy 395.628622 -188.408564) (xy 395.620271 -188.408814) (xy 395.604442 -188.414135) (xy 395.597634 -188.418978)
			(xy 395.575289 -188.435555) (xy 395.526747 -188.462743) (xy 395.474769 -188.482586) (xy 395.420459 -188.494663)
			(xy 395.36497 -188.498717) (xy 395.309481 -188.494663) (xy 395.255171 -188.482586) (xy 395.203193 -188.462743)
			(xy 395.154651 -188.435555) (xy 395.132306 -188.418978) (xy 395.125448 -188.413898) (xy 395.109954 -188.408564)
			(xy 394.984986 -188.408564) (xy 394.969492 -188.413898) (xy 394.962634 -188.418978) (xy 394.940289 -188.435555)
			(xy 394.891747 -188.462743) (xy 394.839769 -188.482586) (xy 394.785459 -188.494663) (xy 394.72997 -188.498717)
			(xy 394.674481 -188.494663) (xy 394.620171 -188.482586) (xy 394.568193 -188.462743) (xy 394.519651 -188.435555)
			(xy 394.497306 -188.418978) (xy 394.490448 -188.413898) (xy 394.474954 -188.408564) (xy 394.39977 -188.408564)
			(xy 394.389704 -188.408994) (xy 394.371113 -188.416724) (xy 394.363702 -188.42355) (xy 393.907518 -188.879734)
			(xy 393.900675 -188.887133) (xy 393.89295 -188.905732) (xy 393.892532 -188.915802) (xy 393.892532 -207.839564)
			(xy 393.891915 -207.864518) (xy 393.882167 -207.913466) (xy 393.86306 -207.959573) (xy 393.835327 -208.001068)
			(xy 393.81811 -208.019142) (xy 391.361422 -210.47583) (xy 391.352991 -210.485282) (xy 391.345801 -210.509536)
			(xy 391.347706 -210.522058) (xy 391.367264 -210.617816) (xy 391.383774 -210.637374) (xy 391.395712 -210.6422)
			(xy 391.461617 -210.668886) (xy 391.590622 -210.72871) (xy 391.71604 -210.795728) (xy 391.837473 -210.869724)
			(xy 391.95453 -210.950463) (xy 392.066839 -211.037687) (xy 392.17404 -211.131116) (xy 392.275792 -211.230454)
			(xy 392.371768 -211.335381) (xy 392.461663 -211.445563) (xy 392.545189 -211.560648) (xy 392.62208 -211.680269)
			(xy 392.69209 -211.804042) (xy 392.754994 -211.931574) (xy 392.810593 -212.062455) (xy 392.858708 -212.196269)
			(xy 392.899186 -212.332588) (xy 392.931898 -212.470976) (xy 392.956739 -212.610991) (xy 392.973629 -212.752185)
			(xy 392.982515 -212.894109) (xy 392.983368 -213.036307) (xy 392.976186 -213.178327) (xy 392.960992 -213.319715)
			(xy 392.937833 -213.460018) (xy 392.906785 -213.598788) (xy 392.867946 -213.735583) (xy 392.82144 -213.869964)
			(xy 392.767416 -214.001504) (xy 392.706047 -214.129781) (xy 392.637528 -214.254386) (xy 392.562078 -214.374921)
			(xy 392.479939 -214.491) (xy 392.391373 -214.602253) (xy 392.296663 -214.708325) (xy 392.196111 -214.808876)
			(xy 392.090039 -214.903585) (xy 391.978785 -214.992151) (xy 391.862705 -215.074289) (xy 391.742169 -215.149737)
			(xy 391.617564 -215.218255) (xy 391.489286 -215.279624) (xy 391.357746 -215.333647) (xy 391.223364 -215.380151)
			(xy 391.08657 -215.41899) (xy 390.947799 -215.450037) (xy 390.807496 -215.473194) (xy 390.666108 -215.488388)
			(xy 390.524088 -215.495569) (xy 390.38189 -215.494714) (xy 390.239966 -215.485827) (xy 390.098772 -215.468936)
			(xy 389.958757 -215.444094) (xy 389.820369 -215.411381) (xy 389.684051 -215.370902) (xy 389.550238 -215.322786)
			(xy 389.419356 -215.267186) (xy 389.291826 -215.204281) (xy 389.168052 -215.13427) (xy 389.048433 -215.057379)
			(xy 388.933348 -214.973852) (xy 388.823166 -214.883956) (xy 388.71824 -214.787978) (xy 388.618904 -214.686226)
			(xy 388.525475 -214.579024) (xy 388.438252 -214.466715) (xy 388.357514 -214.349657) (xy 388.283518 -214.228224)
			(xy 388.216502 -214.102805) (xy 388.156678 -213.973799) (xy 388.130034 -213.907878) (xy 388.125208 -213.89594)
			(xy 388.10565 -213.87943) (xy 388.009892 -213.859618) (xy 387.997337 -213.857743) (xy 387.973064 -213.86506)
			(xy 387.963664 -213.873588) (xy 380.667006 -221.170246) (xy 380.660166 -221.177647) (xy 380.652447 -221.196245)
			(xy 380.65202 -221.206314) (xy 380.65202 -221.802452) (xy 380.651491 -221.825847) (xy 380.642932 -221.871848)
			(xy 380.626095 -221.915504) (xy 380.60155 -221.95534) (xy 380.570126 -221.990008) (xy 380.532885 -222.018335)
			(xy 380.491087 -222.039366) (xy 380.446145 -222.052387) (xy 380.422912 -222.055182) (xy 380.41072 -222.056452)
			(xy 380.390146 -222.06966) (xy 379.258322 -224.02038) (xy 379.258576 -224.04832) (xy 379.266196 -224.060512)
			(xy 379.277874 -224.080183) (xy 379.296298 -224.122055) (xy 379.308781 -224.166065) (xy 379.315086 -224.211375)
			(xy 379.315472 -224.234248) (xy 379.314959 -224.260232) (xy 379.306822 -224.311558) (xy 379.290756 -224.36098)
			(xy 379.267157 -224.40728) (xy 379.236606 -224.449319) (xy 379.199855 -224.486061) (xy 379.157809 -224.516601)
			(xy 379.111502 -224.540189) (xy 379.062076 -224.556242) (xy 379.010748 -224.564365) (xy 378.984764 -224.564956)
			(xy 378.973334 -224.564702) (xy 378.959364 -224.564194) (xy 378.93498 -224.577656) (xy 378.788422 -224.830386)
			(xy 378.788676 -224.858326) (xy 378.796042 -224.870264) (xy 378.807771 -224.889952) (xy 378.826279 -224.931876)
			(xy 378.838821 -224.975953) (xy 378.845156 -225.02134) (xy 378.845572 -225.044254) (xy 378.845092 -225.070245)
			(xy 378.836967 -225.121587) (xy 378.820908 -225.171025) (xy 378.797312 -225.217342) (xy 378.76676 -225.259397)
			(xy 378.730004 -225.296153) (xy 378.687951 -225.326707) (xy 378.641634 -225.350304) (xy 378.592196 -225.366364)
			(xy 378.540855 -225.374491) (xy 378.514864 -225.374962) (xy 378.503434 -225.374708) (xy 378.48921 -225.3742)
			(xy 378.464826 -225.387662) (xy 378.318268 -225.640392) (xy 378.318522 -225.668332) (xy 378.326142 -225.680524)
			(xy 378.337821 -225.700195) (xy 378.356246 -225.742067) (xy 378.36873 -225.786077) (xy 378.375035 -225.831387)
			(xy 378.375418 -225.85426) (xy 378.374938 -225.880252) (xy 378.366812 -225.931596) (xy 378.350753 -225.981036)
			(xy 378.327158 -226.027356) (xy 378.296606 -226.069413) (xy 378.259851 -226.106174) (xy 378.217798 -226.136731)
			(xy 378.171482 -226.160334) (xy 378.122044 -226.1764) (xy 378.070702 -226.184534) (xy 378.04471 -226.184968)
			(xy 378.033534 -226.184714) (xy 378.01931 -226.184206) (xy 377.994926 -226.197922) (xy 377.848368 -226.450398)
			(xy 377.848622 -226.478338) (xy 377.855988 -226.490276) (xy 377.867718 -226.509964) (xy 377.886228 -226.551887)
			(xy 377.89877 -226.595965) (xy 377.905105 -226.641352) (xy 377.905518 -226.664266) (xy 377.905037 -226.690257)
			(xy 377.89691 -226.741601) (xy 377.880851 -226.79104) (xy 377.857256 -226.837359) (xy 377.826704 -226.879416)
			(xy 377.789949 -226.916176) (xy 377.747897 -226.946733) (xy 377.701581 -226.970335) (xy 377.652143 -226.9864)
			(xy 377.600801 -226.994534) (xy 377.57481 -226.994974) (xy 377.56338 -226.99472) (xy 377.549156 -226.994212)
			(xy 377.524772 -227.007674) (xy 377.378214 -227.260404) (xy 377.378722 -227.288344) (xy 377.386088 -227.300282)
			(xy 377.397817 -227.31997) (xy 377.416327 -227.361893) (xy 377.428868 -227.405971) (xy 377.435202 -227.451358)
			(xy 377.435618 -227.474272) (xy 377.435137 -227.500263) (xy 377.427009 -227.551606) (xy 377.41095 -227.601044)
			(xy 377.387354 -227.647362) (xy 377.356802 -227.689418) (xy 377.320047 -227.726177) (xy 377.277995 -227.756734)
			(xy 377.23168 -227.780335) (xy 377.182243 -227.7964) (xy 377.130901 -227.804534) (xy 377.10491 -227.80498)
			(xy 377.09348 -227.804726) (xy 377.079256 -227.804218) (xy 377.054872 -227.81768) (xy 376.908314 -228.07041)
			(xy 376.908568 -228.09835) (xy 376.915934 -228.110288) (xy 376.927667 -228.129975) (xy 376.946186 -228.171897)
			(xy 376.958739 -228.215974) (xy 376.965084 -228.261363) (xy 376.965464 -228.284278) (xy 376.964982 -228.310267)
			(xy 376.956854 -228.361606) (xy 376.940793 -228.41104) (xy 376.917196 -228.457354) (xy 376.886643 -228.499404)
			(xy 376.849888 -228.536157) (xy 376.807835 -228.566707) (xy 376.76152 -228.590301) (xy 376.712084 -228.606359)
			(xy 376.660745 -228.614484) (xy 376.634756 -228.614986) (xy 376.608973 -228.614489) (xy 376.558032 -228.606478)
			(xy 376.508952 -228.590656) (xy 376.462923 -228.567408) (xy 376.421061 -228.537297) (xy 376.38438 -228.501052)
			(xy 376.35377 -228.459553) (xy 376.341386 -228.436932) (xy 376.334782 -228.424232) (xy 376.310652 -228.4095)
			(xy 376.018806 -228.4095) (xy 375.994676 -228.424232) (xy 375.988072 -228.436932) (xy 375.975732 -228.459578)
			(xy 375.945114 -228.501077) (xy 375.908425 -228.53732) (xy 375.866556 -228.567428) (xy 375.82052 -228.590673)
			(xy 375.771434 -228.606489) (xy 375.720488 -228.614494) (xy 375.668916 -228.614494) (xy 375.61797 -228.606489)
			(xy 375.568884 -228.590673) (xy 375.522848 -228.567428) (xy 375.480979 -228.53732) (xy 375.44429 -228.501077)
			(xy 375.413672 -228.459578) (xy 375.401332 -228.436932) (xy 375.394728 -228.424232) (xy 375.370598 -228.4095)
			(xy 375.079006 -228.4095) (xy 375.054876 -228.424232) (xy 375.048272 -228.436932) (xy 375.035933 -228.45958)
			(xy 375.005316 -228.501081) (xy 374.968628 -228.537327) (xy 374.926759 -228.567437) (xy 374.880722 -228.590684)
			(xy 374.831636 -228.606502) (xy 374.780688 -228.614508) (xy 374.754902 -228.614986) (xy 374.743472 -228.614732)
			(xy 374.729248 -228.614224) (xy 374.704864 -228.627686) (xy 374.558306 -228.880416) (xy 374.55856 -228.908356)
			(xy 374.56618 -228.920548) (xy 374.577856 -228.94022) (xy 374.596276 -228.982092) (xy 374.608755 -229.026102)
			(xy 374.615056 -229.071411) (xy 374.615456 -229.094284) (xy 374.615104 -229.116933) (xy 374.608957 -229.16181)
			(xy 374.596733 -229.205426) (xy 374.578664 -229.246962) (xy 374.567196 -229.266496) (xy 374.55983 -229.278434)
			(xy 374.559322 -229.30612) (xy 374.706896 -229.560374) (xy 374.73128 -229.573836) (xy 374.74525 -229.573582)
			(xy 374.754902 -229.573328) (xy 374.780886 -229.573838) (xy 374.832215 -229.581968) (xy 374.88164 -229.598027)
			(xy 374.927944 -229.62162) (xy 374.969987 -229.652167) (xy 375.006734 -229.688914) (xy 375.037281 -229.730958)
			(xy 375.060874 -229.777262) (xy 375.076933 -229.826687) (xy 375.085063 -229.878016) (xy 375.085063 -229.929984)
			(xy 375.076933 -229.981313) (xy 375.060874 -230.030738) (xy 375.037281 -230.077042) (xy 375.006734 -230.119086)
			(xy 374.969987 -230.155833) (xy 374.927944 -230.18638) (xy 374.88164 -230.209973) (xy 374.832215 -230.226032)
			(xy 374.780886 -230.234162) (xy 374.754902 -230.234744) (xy 374.743472 -230.23449) (xy 374.729248 -230.233982)
			(xy 374.704864 -230.247444) (xy 374.543828 -230.52532) (xy 374.543828 -230.55199) (xy 374.550432 -230.563928)
			(xy 374.562881 -230.587014) (xy 374.58054 -230.636397) (xy 374.589494 -230.688073) (xy 374.590056 -230.714296)
			(xy 374.58951 -230.740176) (xy 374.580779 -230.791196) (xy 374.563565 -230.84001) (xy 374.551448 -230.862886)
			(xy 374.544844 -230.874824) (xy 374.545098 -230.90124) (xy 374.706896 -231.180386) (xy 374.73128 -231.193848)
			(xy 374.74525 -231.193594) (xy 374.754902 -231.19334) (xy 374.780885 -231.19385) (xy 374.832212 -231.20198)
			(xy 374.881635 -231.218038) (xy 374.927937 -231.241631) (xy 374.969979 -231.272176) (xy 375.006725 -231.308922)
			(xy 375.03727 -231.350964) (xy 375.060862 -231.397267) (xy 375.076921 -231.44669) (xy 375.08505 -231.498017)
			(xy 375.08505 -231.549983) (xy 375.076921 -231.60131) (xy 375.060862 -231.650733) (xy 375.03727 -231.697036)
			(xy 375.006725 -231.739078) (xy 374.969979 -231.775824) (xy 374.927937 -231.806369) (xy 374.881635 -231.829962)
			(xy 374.832212 -231.84602) (xy 374.780885 -231.85415) (xy 374.754902 -231.854756) (xy 374.743472 -231.854502)
			(xy 374.729248 -231.853994) (xy 374.704864 -231.867456) (xy 374.558306 -232.12044) (xy 374.558814 -232.14838)
			(xy 374.56618 -232.160318) (xy 374.577858 -232.179989) (xy 374.596282 -232.221861) (xy 374.608765 -232.265871)
			(xy 374.61507 -232.311181) (xy 374.615456 -232.334054) (xy 374.615067 -232.35671) (xy 374.608851 -232.401596)
			(xy 374.596568 -232.445213) (xy 374.57845 -232.486747) (xy 374.566942 -232.506266) (xy 374.559576 -232.518458)
			(xy 374.559322 -232.54589) (xy 374.706896 -232.800398) (xy 374.73128 -232.81386) (xy 374.74525 -232.813606)
			(xy 374.754902 -232.813352) (xy 374.78089 -232.813862) (xy 374.832227 -232.821992) (xy 374.88166 -232.838053)
			(xy 374.927972 -232.861648) (xy 374.970023 -232.892197) (xy 375.006778 -232.928948) (xy 375.037332 -232.970996)
			(xy 375.060933 -233.017305) (xy 375.076999 -233.066736) (xy 375.085135 -233.118072) (xy 375.08561 -233.14406)
			(xy 375.085232 -233.166747) (xy 375.079024 -233.211695) (xy 375.066734 -233.255373) (xy 375.04859 -233.296962)
			(xy 375.037096 -233.316526) (xy 375.02973 -233.328464) (xy 375.029476 -233.356404) (xy 375.176796 -233.610404)
			(xy 375.20118 -233.623866) (xy 375.21515 -233.623612) (xy 375.224802 -233.623358) (xy 375.250792 -233.623868)
			(xy 375.302131 -233.631999) (xy 375.351567 -233.648062) (xy 375.397881 -233.671661) (xy 375.439933 -233.702214)
			(xy 375.476688 -233.738969) (xy 375.50724 -233.781021) (xy 375.530839 -233.827335) (xy 375.546901 -233.876771)
			(xy 375.555032 -233.92811) (xy 375.555032 -233.98009) (xy 375.546901 -234.031429) (xy 375.530839 -234.080865)
			(xy 375.50724 -234.127179) (xy 375.476688 -234.169231) (xy 375.439933 -234.205986) (xy 375.397881 -234.236539)
			(xy 375.351567 -234.260138) (xy 375.302131 -234.276201) (xy 375.250792 -234.284332) (xy 375.224802 -234.284774)
			(xy 375.213372 -234.28452) (xy 375.199148 -234.284012) (xy 375.174764 -234.297474) (xy 375.028206 -234.550204)
			(xy 375.028714 -234.578144) (xy 375.03608 -234.590082) (xy 375.047809 -234.60977) (xy 375.066319 -234.651693)
			(xy 375.078862 -234.695771) (xy 375.085195 -234.741158) (xy 375.08561 -234.764072) (xy 375.085129 -234.790063)
			(xy 375.077001 -234.841405) (xy 375.060941 -234.890843) (xy 375.037345 -234.93716) (xy 375.006794 -234.979216)
			(xy 374.970039 -235.015974) (xy 374.927986 -235.04653) (xy 374.881671 -235.07013) (xy 374.832234 -235.086194)
			(xy 374.780893 -235.094327) (xy 374.754902 -235.09478) (xy 374.743472 -235.094526) (xy 374.729248 -235.094018)
			(xy 374.704864 -235.10748) (xy 374.558306 -235.360464) (xy 374.558814 -235.388404) (xy 374.56618 -235.400342)
			(xy 374.577857 -235.420013) (xy 374.596277 -235.461886) (xy 374.608757 -235.505896) (xy 374.615059 -235.551205)
			(xy 374.615456 -235.574078) (xy 374.615066 -235.596734) (xy 374.608846 -235.641618) (xy 374.596561 -235.685233)
			(xy 374.578441 -235.726765) (xy 374.566942 -235.74629) (xy 374.559576 -235.758482) (xy 374.559322 -235.785914)
			(xy 374.706896 -236.040422) (xy 374.73128 -236.053884) (xy 374.74525 -236.05363) (xy 374.754902 -236.053376)
			(xy 374.78089 -236.053886) (xy 374.832227 -236.062017) (xy 374.88166 -236.078079) (xy 374.927971 -236.101676)
			(xy 374.970021 -236.132227) (xy 375.006774 -236.16898) (xy 375.037325 -236.211031) (xy 375.060922 -236.257342)
			(xy 375.076984 -236.306775) (xy 375.085114 -236.358112) (xy 375.085114 -236.410088) (xy 375.076984 -236.461425)
			(xy 375.060922 -236.510858) (xy 375.037325 -236.557169) (xy 375.006774 -236.59922) (xy 374.970021 -236.635973)
			(xy 374.927971 -236.666524) (xy 374.88166 -236.690121) (xy 374.832227 -236.706183) (xy 374.78089 -236.714314)
			(xy 374.754902 -236.714792) (xy 374.743472 -236.714538) (xy 374.729248 -236.71403) (xy 374.704864 -236.727492)
			(xy 374.558306 -236.980222) (xy 374.55856 -237.008162) (xy 374.56618 -237.020354) (xy 374.577856 -237.040026)
			(xy 374.596275 -237.081898) (xy 374.608754 -237.125908) (xy 374.615053 -237.171218) (xy 374.615456 -237.19409)
			(xy 374.614947 -237.220079) (xy 374.606818 -237.271418) (xy 374.590759 -237.320853) (xy 374.567164 -237.367167)
			(xy 374.536615 -237.40922) (xy 374.499865 -237.445978) (xy 374.457816 -237.476534) (xy 374.411506 -237.500137)
			(xy 374.362074 -237.516205) (xy 374.310737 -237.524343) (xy 374.284748 -237.524798) (xy 374.273572 -237.524544)
			(xy 374.259348 -237.524036) (xy 374.234964 -237.537752) (xy 374.088406 -237.790228) (xy 374.08866 -237.818168)
			(xy 374.096026 -237.830106) (xy 374.107759 -237.849793) (xy 374.126276 -237.891715) (xy 374.138826 -237.935793)
			(xy 374.145169 -237.981181) (xy 374.145556 -238.004096) (xy 374.145556 -238.012986) (xy 374.145048 -238.026956)
			(xy 374.158764 -238.05134) (xy 375.010934 -238.540798) (xy 375.038874 -238.54029) (xy 375.050812 -238.532924)
			(xy 375.070499 -238.52119) (xy 375.11242 -238.502671) (xy 375.156498 -238.49012) (xy 375.201887 -238.483776)
			(xy 375.224802 -238.483394) (xy 375.250789 -238.483904) (xy 375.302123 -238.492034) (xy 375.351553 -238.508096)
			(xy 375.397862 -238.531691) (xy 375.439909 -238.562241) (xy 375.47666 -238.598992) (xy 375.50721 -238.64104)
			(xy 375.530805 -238.687349) (xy 375.546866 -238.736779) (xy 375.554996 -238.788113) (xy 375.554996 -238.840087)
			(xy 375.546866 -238.891421) (xy 375.530805 -238.940851) (xy 375.50721 -238.98716) (xy 375.47666 -239.029208)
			(xy 375.439909 -239.065959) (xy 375.397862 -239.096509) (xy 375.351553 -239.120104) (xy 375.302123 -239.136166)
			(xy 375.250789 -239.144296) (xy 375.224802 -239.14481) (xy 375.213372 -239.144556) (xy 375.199148 -239.144048)
			(xy 375.174764 -239.15751) (xy 375.028206 -239.41024) (xy 375.028714 -239.43818) (xy 375.03608 -239.450118)
			(xy 375.047813 -239.469805) (xy 375.066331 -239.511727) (xy 375.078882 -239.555805) (xy 375.085224 -239.601193)
			(xy 375.08561 -239.624108) (xy 375.0851 -239.650095) (xy 375.076968 -239.701428) (xy 375.060907 -239.750858)
			(xy 375.03731 -239.797167) (xy 375.006761 -239.839214) (xy 374.970009 -239.875964) (xy 374.927961 -239.906514)
			(xy 374.881653 -239.930109) (xy 374.832223 -239.94617) (xy 374.780889 -239.9543) (xy 374.754902 -239.954816)
			(xy 374.743472 -239.954562) (xy 374.729502 -239.954054) (xy 374.704864 -239.967516) (xy 374.558306 -240.2205)
			(xy 374.558814 -240.24844) (xy 374.56618 -240.260378) (xy 374.577854 -240.28005) (xy 374.596271 -240.321923)
			(xy 374.608746 -240.365933) (xy 374.615042 -240.411242) (xy 374.615456 -240.434114) (xy 374.615063 -240.456769)
			(xy 374.608839 -240.501651) (xy 374.59655 -240.545264) (xy 374.578426 -240.586793) (xy 374.566942 -240.606326)
			(xy 374.559576 -240.618518) (xy 374.559322 -240.64595) (xy 374.706896 -240.900458) (xy 374.73128 -240.91392)
			(xy 374.74525 -240.913666) (xy 374.754902 -240.913412) (xy 374.780891 -240.913895) (xy 374.832228 -240.922027)
			(xy 374.881661 -240.93809) (xy 374.927972 -240.961688) (xy 374.970022 -240.99224) (xy 375.006774 -241.028995)
			(xy 375.037324 -241.071047) (xy 375.060919 -241.11736) (xy 375.076978 -241.166794) (xy 375.085106 -241.218131)
			(xy 375.08561 -241.24412) (xy 375.085235 -241.266808) (xy 375.079032 -241.311758) (xy 375.066746 -241.355439)
			(xy 375.048606 -241.397031) (xy 375.037096 -241.416586) (xy 375.02973 -241.428524) (xy 375.029476 -241.456464)
			(xy 375.176796 -241.710464) (xy 375.20118 -241.723926) (xy 375.21515 -241.723672) (xy 375.224802 -241.723418)
			(xy 375.250787 -241.723928) (xy 375.302117 -241.732058) (xy 375.351544 -241.748118) (xy 375.397849 -241.771712)
			(xy 375.439894 -241.802259) (xy 375.476642 -241.839008) (xy 375.507189 -241.881052) (xy 375.530783 -241.927358)
			(xy 375.546843 -241.976785) (xy 375.554973 -242.028115) (xy 375.554973 -242.080085) (xy 375.546843 -242.131415)
			(xy 375.530783 -242.180842) (xy 375.507189 -242.227148) (xy 375.476642 -242.269192) (xy 375.439894 -242.305941)
			(xy 375.397849 -242.336488) (xy 375.351544 -242.360082) (xy 375.302117 -242.376142) (xy 375.250787 -242.384272)
			(xy 375.224802 -242.384834) (xy 375.213372 -242.38458) (xy 375.199148 -242.384072) (xy 375.174764 -242.397534)
			(xy 375.028206 -242.650264) (xy 375.028714 -242.678204) (xy 375.03608 -242.690142) (xy 375.047812 -242.709829)
			(xy 375.066327 -242.751752) (xy 375.078874 -242.795829) (xy 375.085213 -242.841218) (xy 375.08561 -242.864132)
			(xy 375.085098 -242.890118) (xy 375.076964 -242.941448) (xy 375.0609 -242.990875) (xy 375.037302 -243.03718)
			(xy 375.006752 -243.079224) (xy 374.970001 -243.115971) (xy 374.927954 -243.146518) (xy 374.881647 -243.170111)
			(xy 374.832219 -243.186171) (xy 374.780888 -243.1943) (xy 374.754902 -243.19484) (xy 374.743472 -243.194586)
			(xy 374.729248 -243.194078) (xy 374.704864 -243.20754) (xy 374.558306 -243.460524) (xy 374.558814 -243.488464)
			(xy 374.56618 -243.500402) (xy 374.577859 -243.520073) (xy 374.596285 -243.561945) (xy 374.60877 -243.605955)
			(xy 374.615077 -243.651265) (xy 374.615456 -243.674138) (xy 374.615068 -243.696795) (xy 374.608854 -243.741681)
			(xy 374.596573 -243.785299) (xy 374.578457 -243.826834) (xy 374.566942 -243.84635) (xy 374.559576 -243.858542)
			(xy 374.559322 -243.885974) (xy 374.706896 -244.140482) (xy 374.73128 -244.153944) (xy 374.74525 -244.15369)
			(xy 374.754902 -244.153436) (xy 374.78089 -244.153919) (xy 374.832226 -244.162051) (xy 374.881657 -244.178114)
			(xy 374.927967 -244.201713) (xy 374.970014 -244.232266) (xy 375.006764 -244.269021) (xy 375.037311 -244.311072)
			(xy 375.060904 -244.357385) (xy 375.07696 -244.406819) (xy 375.085084 -244.458156) (xy 375.08561 -244.484144)
			(xy 375.085233 -244.506831) (xy 375.079028 -244.55178) (xy 375.066739 -244.595459) (xy 375.048597 -244.63705)
			(xy 375.037096 -244.65661) (xy 375.02973 -244.668548) (xy 375.029476 -244.696488) (xy 375.176796 -244.950488)
			(xy 375.20118 -244.96395) (xy 375.21515 -244.963696) (xy 375.224802 -244.963442) (xy 375.250785 -244.963952)
			(xy 375.302112 -244.972082) (xy 375.351534 -244.98814) (xy 375.397836 -245.011733) (xy 375.439878 -245.042278)
			(xy 375.476623 -245.079024) (xy 375.507168 -245.121065) (xy 375.53076 -245.167368) (xy 375.546819 -245.21679)
			(xy 375.554948 -245.268117) (xy 375.554948 -245.320083) (xy 375.546819 -245.37141) (xy 375.53076 -245.420832)
			(xy 375.507168 -245.467135) (xy 375.476623 -245.509176) (xy 375.439878 -245.545922) (xy 375.397836 -245.576467)
			(xy 375.351534 -245.60006) (xy 375.302112 -245.616118) (xy 375.250785 -245.624248) (xy 375.224802 -245.624858)
			(xy 375.213372 -245.624604) (xy 375.199148 -245.624096) (xy 375.174764 -245.637558) (xy 375.028206 -245.890288)
			(xy 375.028714 -245.918228) (xy 375.03608 -245.930166) (xy 375.04781 -245.949854) (xy 375.066322 -245.991776)
			(xy 375.078867 -246.035854) (xy 375.085202 -246.081242) (xy 375.08561 -246.104156) (xy 375.08513 -246.130148)
			(xy 375.077004 -246.181492) (xy 375.060946 -246.230932) (xy 375.037351 -246.277252) (xy 375.006799 -246.319309)
			(xy 374.970044 -246.356069) (xy 374.927991 -246.386627) (xy 374.881675 -246.410228) (xy 374.832236 -246.426294)
			(xy 374.780894 -246.434427) (xy 374.754902 -246.434864) (xy 374.743472 -246.43461) (xy 374.729248 -246.434102)
			(xy 374.704864 -246.447564) (xy 374.558306 -246.700548) (xy 374.558814 -246.728488) (xy 374.56618 -246.740426)
			(xy 374.577858 -246.760097) (xy 374.59628 -246.80197) (xy 374.608762 -246.84598) (xy 374.615066 -246.891289)
			(xy 374.615456 -246.914162) (xy 374.615067 -246.936818) (xy 374.608849 -246.981703) (xy 374.596566 -247.02532)
			(xy 374.578447 -247.066853) (xy 374.566942 -247.086374) (xy 374.559576 -247.098566) (xy 374.559322 -247.125998)
			(xy 374.706896 -247.380506) (xy 374.73128 -247.393968) (xy 374.74525 -247.393714) (xy 374.754902 -247.39346)
			(xy 374.78089 -247.39397) (xy 374.832226 -247.4021) (xy 374.881658 -247.418161) (xy 374.92797 -247.441756)
			(xy 374.970021 -247.472306) (xy 375.006775 -247.509057) (xy 375.037328 -247.551104) (xy 375.060927 -247.597414)
			(xy 375.076993 -247.646845) (xy 375.085128 -247.69818) (xy 375.08561 -247.724168) (xy 375.085232 -247.746855)
			(xy 375.079023 -247.791802) (xy 375.066731 -247.83548) (xy 375.048587 -247.877068) (xy 375.037096 -247.896634)
			(xy 375.02973 -247.908572) (xy 375.029476 -247.936512) (xy 375.176796 -248.190512) (xy 375.20118 -248.203974)
			(xy 375.21515 -248.20372) (xy 375.224802 -248.203466) (xy 375.250791 -248.203976) (xy 375.302129 -248.212107)
			(xy 375.351564 -248.22817) (xy 375.397876 -248.251767) (xy 375.439928 -248.28232) (xy 375.476682 -248.319074)
			(xy 375.507234 -248.361125) (xy 375.530831 -248.407438) (xy 375.546893 -248.456873) (xy 375.555024 -248.508211)
			(xy 375.555024 -248.560189) (xy 375.546893 -248.611527) (xy 375.530831 -248.660962) (xy 375.507234 -248.707275)
			(xy 375.476682 -248.749326) (xy 375.439928 -248.78608) (xy 375.397876 -248.816633) (xy 375.351564 -248.84023)
			(xy 375.302129 -248.856293) (xy 375.250791 -248.864424) (xy 375.224802 -248.864882) (xy 375.213372 -248.864628)
			(xy 375.199148 -248.86412) (xy 375.174764 -248.877582) (xy 375.028206 -249.130312) (xy 375.028714 -249.158252)
			(xy 375.03608 -249.17019) (xy 375.047815 -249.189876) (xy 375.066337 -249.231798) (xy 375.078891 -249.275876)
			(xy 375.085237 -249.321265) (xy 375.08561 -249.34418) (xy 375.085128 -249.37017) (xy 375.077 -249.421511)
			(xy 375.060939 -249.470949) (xy 375.037343 -249.517265) (xy 375.006791 -249.559319) (xy 374.970036 -249.596076)
			(xy 374.927984 -249.626631) (xy 374.881669 -249.650231) (xy 374.832233 -249.666294) (xy 374.780892 -249.674427)
			(xy 374.754902 -249.674888) (xy 374.743472 -249.674634) (xy 374.729248 -249.674126) (xy 374.704864 -249.687588)
			(xy 374.558306 -249.940572) (xy 374.55856 -249.968258) (xy 374.56618 -249.98045) (xy 374.577856 -250.000122)
			(xy 374.596276 -250.041994) (xy 374.608755 -250.086004) (xy 374.615055 -250.131313) (xy 374.615456 -250.154186)
			(xy 374.614948 -250.180175) (xy 374.606819 -250.231514) (xy 374.59076 -250.28095) (xy 374.567166 -250.327265)
			(xy 374.536617 -250.369319) (xy 374.499866 -250.406077) (xy 374.457818 -250.436633) (xy 374.411507 -250.460236)
			(xy 374.362075 -250.476305) (xy 374.310737 -250.484443) (xy 374.284748 -250.484894) (xy 374.26146 -250.4845)
			(xy 374.215343 -250.477971) (xy 374.170599 -250.465036) (xy 374.128113 -250.445951) (xy 374.108218 -250.43384)
			(xy 374.096026 -250.42622) (xy 374.06834 -250.425458) (xy 373.218202 -250.9139) (xy 373.20474 -250.93803)
			(xy 373.205248 -250.952508) (xy 373.205502 -250.964192) (xy 373.205019 -250.990182) (xy 373.196889 -251.041521)
			(xy 373.180828 -251.090956) (xy 373.15723 -251.13727) (xy 373.126678 -251.179322) (xy 373.089923 -251.216077)
			(xy 373.047871 -251.246629) (xy 373.001558 -251.270227) (xy 372.952123 -251.286289) (xy 372.900783 -251.294419)
			(xy 372.874794 -251.2949) (xy 372.863618 -251.294646) (xy 372.849394 -251.294138) (xy 372.82501 -251.3076)
			(xy 372.678198 -251.56033) (xy 372.678706 -251.588016) (xy 372.686072 -251.600208) (xy 372.697806 -251.619895)
			(xy 372.716326 -251.661816) (xy 372.728878 -251.705894) (xy 372.735222 -251.751283) (xy 372.735602 -251.774198)
			(xy 372.735092 -251.800185) (xy 372.726962 -251.85152) (xy 372.710901 -251.90095) (xy 372.687305 -251.94726)
			(xy 372.656755 -251.989308) (xy 372.620004 -252.026059) (xy 372.577956 -252.056609) (xy 372.531646 -252.080205)
			(xy 372.482216 -252.096266) (xy 372.430881 -252.104396) (xy 372.378907 -252.104396) (xy 372.327572 -252.096266)
			(xy 372.278142 -252.080205) (xy 372.231832 -252.056609) (xy 372.189784 -252.026059) (xy 372.153033 -251.989308)
			(xy 372.122483 -251.94726) (xy 372.098887 -251.90095) (xy 372.082826 -251.85152) (xy 372.074696 -251.800185)
			(xy 372.074186 -251.774198) (xy 372.07444 -251.759466) (xy 372.075202 -251.744988) (xy 372.061486 -251.72035)
			(xy 371.214396 -251.233432) (xy 371.186202 -251.234194) (xy 371.17401 -251.242068) (xy 371.153875 -251.254581)
			(xy 371.110782 -251.27434) (xy 371.06531 -251.287741) (xy 371.018389 -251.29451) (xy 370.994686 -251.2949)
			(xy 370.9687 -251.294389) (xy 370.917367 -251.286257) (xy 370.867939 -251.270195) (xy 370.821632 -251.246598)
			(xy 370.779587 -251.216048) (xy 370.742838 -251.179297) (xy 370.71229 -251.137249) (xy 370.688697 -251.09094)
			(xy 370.672638 -251.041511) (xy 370.664509 -250.990178) (xy 370.663978 -250.964192) (xy 370.664397 -250.940606)
			(xy 370.671101 -250.893912) (xy 370.684372 -250.848644) (xy 370.70394 -250.805722) (xy 370.716302 -250.78563)
			(xy 370.724176 -250.773438) (xy 370.724684 -250.745244) (xy 370.580666 -250.497086) (xy 370.556028 -250.483624)
			(xy 370.54155 -250.484386) (xy 370.524786 -250.484894) (xy 370.501499 -250.484496) (xy 370.455386 -250.477959)
			(xy 370.410647 -250.465017) (xy 370.368166 -250.445926) (xy 370.348256 -250.43384) (xy 370.336064 -250.42622)
			(xy 370.308124 -250.425458) (xy 369.45824 -250.913646) (xy 369.444778 -250.93803) (xy 369.445286 -250.952254)
			(xy 369.44554 -250.964192) (xy 369.445031 -250.990181) (xy 369.436902 -251.041518) (xy 369.420842 -251.090952)
			(xy 369.397247 -251.137264) (xy 369.366698 -251.179316) (xy 369.329947 -251.216072) (xy 369.287899 -251.246626)
			(xy 369.241589 -251.270227) (xy 369.192157 -251.286292) (xy 369.14082 -251.294428) (xy 369.114832 -251.2949)
			(xy 369.103402 -251.294646) (xy 369.089178 -251.294138) (xy 369.064794 -251.3076) (xy 368.918236 -251.56033)
			(xy 368.91849 -251.58827) (xy 368.92611 -251.600462) (xy 368.937784 -251.620134) (xy 368.956201 -251.662007)
			(xy 368.968677 -251.706017) (xy 368.974975 -251.751326) (xy 368.975386 -251.774198) (xy 368.974876 -251.800185)
			(xy 368.966746 -251.85152) (xy 368.950685 -251.90095) (xy 368.927089 -251.94726) (xy 368.896539 -251.989308)
			(xy 368.859788 -252.026059) (xy 368.81774 -252.056609) (xy 368.77143 -252.080205) (xy 368.722 -252.096266)
			(xy 368.670665 -252.104396) (xy 368.618691 -252.104396) (xy 368.567356 -252.096266) (xy 368.517926 -252.080205)
			(xy 368.471616 -252.056609) (xy 368.429568 -252.026059) (xy 368.392817 -251.989308) (xy 368.362267 -251.94726)
			(xy 368.338671 -251.90095) (xy 368.32261 -251.85152) (xy 368.31448 -251.800185) (xy 368.31397 -251.774198)
			(xy 368.314224 -251.759212) (xy 368.314986 -251.744988) (xy 368.30127 -251.720096) (xy 367.454434 -251.233432)
			(xy 367.42624 -251.234194) (xy 367.414048 -251.242068) (xy 367.393912 -251.254577) (xy 367.350818 -251.274328)
			(xy 367.305345 -251.28772) (xy 367.258426 -251.29448) (xy 367.234724 -251.2949) (xy 367.208734 -251.294419)
			(xy 367.157393 -251.28629) (xy 367.107956 -251.27023) (xy 367.06164 -251.246634) (xy 367.019585 -251.216082)
			(xy 366.982829 -251.179327) (xy 366.952275 -251.137274) (xy 366.928676 -251.090959) (xy 366.912613 -251.041523)
			(xy 366.904483 -250.990182) (xy 366.904016 -250.964192) (xy 366.904454 -250.940638) (xy 366.911177 -250.894011)
			(xy 366.924443 -250.848808) (xy 366.943985 -250.805943) (xy 366.95634 -250.785884) (xy 366.964214 -250.773438)
			(xy 366.964722 -250.745498) (xy 366.820704 -250.497086) (xy 366.795812 -250.483878) (xy 366.781334 -250.484386)
			(xy 366.764824 -250.484894) (xy 366.741505 -250.48451) (xy 366.695327 -250.477989) (xy 366.650523 -250.465045)
			(xy 366.607981 -250.445934) (xy 366.58804 -250.43384) (xy 366.575848 -250.425966) (xy 366.548162 -250.425458)
			(xy 365.698278 -250.913646) (xy 365.684816 -250.93803) (xy 365.685324 -250.952254) (xy 365.685578 -250.964192)
			(xy 365.685095 -250.990181) (xy 365.676965 -251.041519) (xy 365.660903 -251.090952) (xy 365.637305 -251.137264)
			(xy 365.606753 -251.179315) (xy 365.569998 -251.216067) (xy 365.527946 -251.246617) (xy 365.481632 -251.270212)
			(xy 365.432197 -251.28627) (xy 365.380859 -251.294397) (xy 365.35487 -251.2949) (xy 365.34344 -251.294646)
			(xy 365.329216 -251.294138) (xy 365.304832 -251.3076) (xy 365.158274 -251.56033) (xy 365.158528 -251.58827)
			(xy 365.166148 -251.600462) (xy 365.177824 -251.620133) (xy 365.196244 -251.662006) (xy 365.208723 -251.706016)
			(xy 365.215022 -251.751325) (xy 365.215424 -251.774198) (xy 365.214914 -251.800185) (xy 365.206784 -251.85152)
			(xy 365.190723 -251.90095) (xy 365.167127 -251.94726) (xy 365.136577 -251.989308) (xy 365.099826 -252.026059)
			(xy 365.057778 -252.056609) (xy 365.011468 -252.080205) (xy 364.962038 -252.096266) (xy 364.910703 -252.104396)
			(xy 364.858729 -252.104396) (xy 364.807394 -252.096266) (xy 364.757964 -252.080205) (xy 364.711654 -252.056609)
			(xy 364.669606 -252.026059) (xy 364.632855 -251.989308) (xy 364.602305 -251.94726) (xy 364.578709 -251.90095)
			(xy 364.562648 -251.85152) (xy 364.554518 -251.800185) (xy 364.554008 -251.774198) (xy 364.554262 -251.759212)
			(xy 364.555024 -251.744988) (xy 364.541308 -251.720096) (xy 363.694472 -251.233432) (xy 363.666278 -251.234194)
			(xy 363.654086 -251.242068) (xy 363.63395 -251.254579) (xy 363.590857 -251.274335) (xy 363.545385 -251.287733)
			(xy 363.498465 -251.294498) (xy 363.474762 -251.2949) (xy 363.448777 -251.294388) (xy 363.397448 -251.286252)
			(xy 363.348023 -251.270188) (xy 363.301719 -251.24659) (xy 363.259677 -251.216039) (xy 363.222931 -251.179288)
			(xy 363.192386 -251.137242) (xy 363.168795 -251.090935) (xy 363.152737 -251.041508) (xy 363.144609 -250.990177)
			(xy 363.144054 -250.964192) (xy 363.144492 -250.940638) (xy 363.151215 -250.894011) (xy 363.164483 -250.848809)
			(xy 363.184027 -250.805945) (xy 363.196378 -250.785884) (xy 363.204252 -250.773438) (xy 363.20476 -250.745498)
			(xy 363.060742 -250.497086) (xy 363.03585 -250.483878) (xy 363.021372 -250.484386) (xy 363.004862 -250.484894)
			(xy 362.981543 -250.484513) (xy 362.935362 -250.477997) (xy 362.890555 -250.465057) (xy 362.84801 -250.44595)
			(xy 362.828078 -250.43384) (xy 362.81614 -250.425966) (xy 362.7882 -250.425458) (xy 361.938316 -250.913646)
			(xy 361.924854 -250.93803) (xy 361.925362 -250.952508) (xy 361.925616 -250.964192) (xy 361.925107 -250.99018)
			(xy 361.916978 -251.041516) (xy 361.900917 -251.090948) (xy 361.877322 -251.137259) (xy 361.846773 -251.179309)
			(xy 361.810021 -251.216062) (xy 361.767973 -251.246614) (xy 361.721663 -251.270211) (xy 361.672231 -251.286274)
			(xy 361.620896 -251.294406) (xy 361.594908 -251.2949) (xy 361.569148 -251.294408) (xy 361.518252 -251.286417)
			(xy 361.469212 -251.270628) (xy 361.423215 -251.247423) (xy 361.381374 -251.217363) (xy 361.344702 -251.181177)
			(xy 361.314088 -251.13974) (xy 361.301792 -251.1171) (xy 361.295188 -251.1044) (xy 361.270804 -251.089668)
			(xy 358.757474 -251.089668) (xy 358.750828 -251.089485) (xy 358.737964 -251.086146) (xy 358.732074 -251.083064)
			(xy 357.587804 -250.425458) (xy 357.559864 -250.425966) (xy 357.547926 -250.43384) (xy 357.527994 -250.44595)
			(xy 357.485449 -250.465057) (xy 357.440642 -250.477998) (xy 357.394461 -250.484515) (xy 357.371142 -250.484894)
			(xy 357.354632 -250.484386) (xy 357.340154 -250.483878) (xy 357.315262 -250.497086) (xy 357.171244 -250.745498)
			(xy 357.171752 -250.773438) (xy 357.179626 -250.785884) (xy 357.191993 -250.805936) (xy 357.211541 -250.8488)
			(xy 357.224802 -250.894006) (xy 357.231508 -250.940637) (xy 357.23195 -250.964192) (xy 357.231441 -250.990181)
			(xy 357.223312 -251.041519) (xy 357.207252 -251.090953) (xy 357.183657 -251.137267) (xy 357.153108 -251.179319)
			(xy 357.116357 -251.216076) (xy 357.074309 -251.246631) (xy 357.027999 -251.270233) (xy 356.978567 -251.2863)
			(xy 356.927231 -251.294437) (xy 356.901242 -251.2949) (xy 356.877541 -251.294489) (xy 356.830625 -251.287715)
			(xy 356.785156 -251.274313) (xy 356.742066 -251.254558) (xy 356.721918 -251.242068) (xy 356.709726 -251.234194)
			(xy 356.681532 -251.233432) (xy 355.834442 -251.72035) (xy 355.820726 -251.744988) (xy 355.821488 -251.759466)
			(xy 355.821742 -251.774198) (xy 355.821232 -251.800185) (xy 355.813102 -251.85152) (xy 355.797041 -251.90095)
			(xy 355.773445 -251.94726) (xy 355.742895 -251.989308) (xy 355.706144 -252.026059) (xy 355.664096 -252.056609)
			(xy 355.617786 -252.080205) (xy 355.568356 -252.096266) (xy 355.517021 -252.104396) (xy 355.465047 -252.104396)
			(xy 355.413712 -252.096266) (xy 355.364282 -252.080205) (xy 355.317972 -252.056609) (xy 355.275924 -252.026059)
			(xy 355.239173 -251.989308) (xy 355.208623 -251.94726) (xy 355.185027 -251.90095) (xy 355.168966 -251.85152)
			(xy 355.160836 -251.800185) (xy 355.160326 -251.774198) (xy 355.160718 -251.751283) (xy 355.167055 -251.705895)
			(xy 355.179606 -251.661818) (xy 355.19813 -251.619899) (xy 355.209856 -251.600208) (xy 355.217222 -251.588016)
			(xy 355.21773 -251.560076) (xy 355.071172 -251.3076) (xy 355.046788 -251.294138) (xy 355.032564 -251.294646)
			(xy 355.021134 -251.2949) (xy 354.997431 -251.294496) (xy 354.950509 -251.287733) (xy 354.905034 -251.274342)
			(xy 354.861935 -251.254596) (xy 354.84181 -251.242068) (xy 354.829872 -251.234194) (xy 354.801678 -251.233686)
			(xy 353.954588 -251.720096) (xy 353.940872 -251.744988) (xy 353.941634 -251.759212) (xy 353.941888 -251.774198)
			(xy 353.941378 -251.800185) (xy 353.933248 -251.85152) (xy 353.917187 -251.90095) (xy 353.893591 -251.94726)
			(xy 353.863041 -251.989308) (xy 353.82629 -252.026059) (xy 353.784242 -252.056609) (xy 353.737932 -252.080205)
			(xy 353.688502 -252.096266) (xy 353.637167 -252.104396) (xy 353.585193 -252.104396) (xy 353.533858 -252.096266)
			(xy 353.484428 -252.080205) (xy 353.438118 -252.056609) (xy 353.39607 -252.026059) (xy 353.359319 -251.989308)
			(xy 353.328769 -251.94726) (xy 353.305173 -251.90095) (xy 353.289112 -251.85152) (xy 353.280982 -251.800185)
			(xy 353.280472 -251.774198) (xy 353.280859 -251.751325) (xy 353.28716 -251.706014) (xy 353.299642 -251.662004)
			(xy 353.318068 -251.620132) (xy 353.329748 -251.600462) (xy 353.337368 -251.58827) (xy 353.337622 -251.56033)
			(xy 353.191064 -251.3076) (xy 353.16668 -251.294138) (xy 353.152456 -251.294646) (xy 353.141026 -251.2949)
			(xy 353.117323 -251.294495) (xy 353.070402 -251.287732) (xy 353.024927 -251.27434) (xy 352.981829 -251.254593)
			(xy 352.961702 -251.242068) (xy 352.949764 -251.234194) (xy 352.92157 -251.233686) (xy 352.07448 -251.72035)
			(xy 352.060764 -251.744988) (xy 352.061526 -251.759466) (xy 352.06178 -251.774198) (xy 352.06127 -251.800185)
			(xy 352.05314 -251.85152) (xy 352.037079 -251.90095) (xy 352.013483 -251.94726) (xy 351.982933 -251.989308)
			(xy 351.946182 -252.026059) (xy 351.904134 -252.056609) (xy 351.857824 -252.080205) (xy 351.808394 -252.096266)
			(xy 351.757059 -252.104396) (xy 351.705085 -252.104396) (xy 351.65375 -252.096266) (xy 351.60432 -252.080205)
			(xy 351.55801 -252.056609) (xy 351.515962 -252.026059) (xy 351.479211 -251.989308) (xy 351.448661 -251.94726)
			(xy 351.425065 -251.90095) (xy 351.409004 -251.85152) (xy 351.400874 -251.800185) (xy 351.400364 -251.774198)
			(xy 351.400755 -251.751283) (xy 351.407091 -251.705894) (xy 351.41964 -251.661816) (xy 351.438162 -251.619895)
			(xy 351.449894 -251.600208) (xy 351.45726 -251.588016) (xy 351.457768 -251.56033) (xy 351.310956 -251.3076)
			(xy 351.286572 -251.294138) (xy 351.272348 -251.294646) (xy 351.261172 -251.2949) (xy 351.23747 -251.294491)
			(xy 351.190552 -251.287721) (xy 351.145081 -251.274323) (xy 351.101988 -251.254571) (xy 351.081848 -251.242068)
			(xy 351.069656 -251.234194) (xy 351.041462 -251.233432) (xy 350.194626 -251.720096) (xy 350.18091 -251.744988)
			(xy 350.181672 -251.759212) (xy 350.181926 -251.774198) (xy 350.181417 -251.800186) (xy 350.173286 -251.851522)
			(xy 350.157226 -251.900954) (xy 350.13363 -251.947265) (xy 350.103081 -251.989315) (xy 350.06633 -252.026068)
			(xy 350.024282 -252.05662) (xy 349.977972 -252.080218) (xy 349.928541 -252.096282) (xy 349.877206 -252.104415)
			(xy 349.851218 -252.104906) (xy 349.834454 -252.104398) (xy 349.819976 -252.103636) (xy 349.795084 -252.117098)
			(xy 349.651066 -252.36551) (xy 349.651828 -252.393704) (xy 349.659448 -252.405896) (xy 349.671814 -252.425949)
			(xy 349.691358 -252.468813) (xy 349.704617 -252.514019) (xy 349.711321 -252.560649) (xy 349.711772 -252.584204)
			(xy 349.711289 -252.610192) (xy 349.703157 -252.661528) (xy 349.687094 -252.71096) (xy 349.663495 -252.75727)
			(xy 349.632942 -252.799318) (xy 349.596187 -252.836068) (xy 349.554136 -252.866616) (xy 349.507823 -252.890209)
			(xy 349.458389 -252.906266) (xy 349.407052 -252.914392) (xy 349.381064 -252.914912) (xy 349.357393 -252.914491)
			(xy 349.310539 -252.907709) (xy 349.26513 -252.894316) (xy 349.222094 -252.874588) (xy 349.201994 -252.86208)
			(xy 349.189802 -252.85446) (xy 349.161608 -252.853698) (xy 348.314518 -253.340362) (xy 348.300802 -253.365)
			(xy 348.301564 -253.379478) (xy 348.301818 -253.39421) (xy 348.301564 -253.405894) (xy 348.301056 -253.420372)
			(xy 348.314518 -253.444756) (xy 349.164402 -253.932944) (xy 349.192342 -253.932182) (xy 349.204534 -253.924562)
			(xy 349.224438 -253.912465) (xy 349.26692 -253.89337) (xy 349.311661 -253.880424) (xy 349.357776 -253.873884)
			(xy 349.381064 -253.873508) (xy 349.407054 -253.873988) (xy 349.458394 -253.882115) (xy 349.507831 -253.898173)
			(xy 349.554147 -253.921768) (xy 349.596202 -253.952318) (xy 349.632959 -253.989071) (xy 349.663513 -254.031122)
			(xy 349.687113 -254.077435) (xy 349.703177 -254.126871) (xy 349.711309 -254.17821) (xy 349.711309 -254.23019)
			(xy 349.703177 -254.281529) (xy 349.687113 -254.330965) (xy 349.663513 -254.377278) (xy 349.632959 -254.419329)
			(xy 349.596202 -254.456082) (xy 349.554147 -254.486632) (xy 349.507831 -254.510227) (xy 349.458394 -254.526285)
			(xy 349.407054 -254.534412) (xy 349.381064 -254.534924) (xy 349.357393 -254.534503) (xy 349.310539 -254.527721)
			(xy 349.26513 -254.514329) (xy 349.222094 -254.494601) (xy 349.201994 -254.482092) (xy 349.189802 -254.474472)
			(xy 349.161608 -254.47371) (xy 348.314518 -254.960374) (xy 348.300802 -254.985012) (xy 348.301564 -254.99949)
			(xy 348.301818 -255.014222) (xy 348.301398 -255.037549) (xy 348.29481 -255.083737) (xy 348.281809 -255.128544)
			(xy 348.262653 -255.171085) (xy 348.25051 -255.191006) (xy 348.24289 -255.203198) (xy 348.242382 -255.231392)
			(xy 348.387162 -255.48082) (xy 348.412054 -255.494536) (xy 348.426278 -255.493774) (xy 348.44101 -255.49352)
			(xy 348.466998 -255.494004) (xy 348.518334 -255.502137) (xy 348.567765 -255.5182) (xy 348.614075 -255.541799)
			(xy 348.656123 -255.572352) (xy 348.692873 -255.609106) (xy 348.723421 -255.651158) (xy 348.747015 -255.69747)
			(xy 348.763072 -255.746903) (xy 348.771199 -255.79824) (xy 348.771718 -255.824228) (xy 348.771309 -255.847586)
			(xy 348.764731 -255.893836) (xy 348.751723 -255.938705) (xy 348.732543 -255.981302) (xy 348.72041 -256.001266)
			(xy 348.71279 -256.013204) (xy 348.712282 -256.041398) (xy 348.856808 -256.29108) (xy 348.8817 -256.304542)
			(xy 348.895924 -256.30378) (xy 348.911164 -256.303526) (xy 348.937154 -256.304006) (xy 348.988495 -256.312133)
			(xy 349.037932 -256.328193) (xy 349.084248 -256.351789) (xy 349.126302 -256.382341) (xy 349.163057 -256.419097)
			(xy 349.19361 -256.46115) (xy 349.217206 -256.507466) (xy 349.233266 -256.556903) (xy 349.241393 -256.608244)
			(xy 349.241872 -256.634234) (xy 349.241805 -256.644036) (xy 349.240659 -256.663607) (xy 349.239586 -256.67335)
			(xy 349.237808 -256.687574) (xy 349.249492 -256.713228) (xy 350.565974 -257.618738) (xy 350.595438 -257.619754)
			(xy 350.608138 -257.612134) (xy 350.629481 -257.600075) (xy 350.674673 -257.581078) (xy 350.72198 -257.568223)
			(xy 350.770571 -257.561738) (xy 350.795082 -257.561334) (xy 350.821427 -257.561781) (xy 350.873582 -257.569278)
			(xy 350.924139 -257.584121) (xy 350.972068 -257.60601) (xy 351.016394 -257.634497) (xy 351.056214 -257.669003)
			(xy 351.090718 -257.708825) (xy 351.119202 -257.753153) (xy 351.141087 -257.801084) (xy 351.155927 -257.851641)
			(xy 351.163421 -257.903797) (xy 351.16389 -257.930142) (xy 351.163434 -257.956239) (xy 351.156068 -258.00791)
			(xy 351.141487 -258.058026) (xy 351.119985 -258.105584) (xy 351.09199 -258.149635) (xy 351.058062 -258.189297)
			(xy 351.01888 -258.223779) (xy 350.975227 -258.252389) (xy 350.9518 -258.263898) (xy 350.938338 -258.270248)
			(xy 350.92259 -258.294886) (xy 350.92259 -258.46532) (xy 350.938338 -258.489958) (xy 350.9518 -258.496308)
			(xy 350.976795 -258.508589) (xy 351.023087 -258.539544) (xy 351.064197 -258.577109) (xy 351.099189 -258.620431)
			(xy 351.127267 -258.668522) (xy 351.147793 -258.720289) (xy 351.160299 -258.774555) (xy 351.164501 -258.830085)
			(xy 351.160721 -258.880102) (xy 399.452088 -258.880102) (xy 399.456118 -258.737767) (xy 399.468193 -258.595887)
			(xy 399.488276 -258.454919) (xy 399.516303 -258.315312) (xy 399.552183 -258.177514) (xy 399.595801 -258.041967)
			(xy 399.647018 -257.909105) (xy 399.705669 -257.779353) (xy 399.771567 -257.653127) (xy 399.844501 -257.530831)
			(xy 399.924238 -257.412858) (xy 400.01052 -257.299585) (xy 400.103073 -257.191374) (xy 400.2016 -257.088573)
			(xy 400.305785 -256.991511) (xy 400.415294 -256.900499) (xy 400.529777 -256.815827) (xy 400.648867 -256.737769)
			(xy 400.772182 -256.666573) (xy 400.899328 -256.602467) (xy 401.029897 -256.545658) (xy 401.163471 -256.496326)
			(xy 401.299622 -256.45463) (xy 401.437913 -256.420704) (xy 401.577903 -256.394656) (xy 401.719142 -256.37657)
			(xy 401.861178 -256.366503) (xy 402.003556 -256.364488) (xy 402.14582 -256.370531) (xy 402.287514 -256.384613)
			(xy 402.428184 -256.406689) (xy 402.567381 -256.436689) (xy 402.704657 -256.474515) (xy 402.839573 -256.520047)
			(xy 402.971697 -256.573138) (xy 403.100606 -256.63362) (xy 403.225887 -256.701298) (xy 403.347138 -256.775955)
			(xy 403.463971 -256.857353) (xy 403.576012 -256.94523) (xy 403.682902 -257.039305) (xy 403.784299 -257.139277)
			(xy 403.879877 -257.244825) (xy 403.969331 -257.355611) (xy 404.052373 -257.47128) (xy 404.128739 -257.591463)
			(xy 404.198183 -257.715773) (xy 404.260483 -257.843814) (xy 404.315439 -257.975173) (xy 404.362876 -258.109432)
			(xy 404.40264 -258.246159) (xy 404.434606 -258.384917) (xy 404.458671 -258.525261) (xy 404.474757 -258.666742)
			(xy 404.482812 -258.808906) (xy 404.483316 -258.880102) (xy 404.482812 -258.951298) (xy 404.474757 -259.093462)
			(xy 404.458671 -259.234943) (xy 404.434606 -259.375287) (xy 404.40264 -259.514045) (xy 404.362876 -259.650772)
			(xy 404.315439 -259.785031) (xy 404.260483 -259.91639) (xy 404.198183 -260.044431) (xy 404.128739 -260.168741)
			(xy 404.052373 -260.288924) (xy 403.969331 -260.404593) (xy 403.879877 -260.515379) (xy 403.784299 -260.620927)
			(xy 403.682902 -260.720899) (xy 403.576012 -260.814974) (xy 403.463971 -260.902851) (xy 403.347138 -260.984249)
			(xy 403.225887 -261.058906) (xy 403.100606 -261.126584) (xy 402.971697 -261.187066) (xy 402.839573 -261.240157)
			(xy 402.704657 -261.285689) (xy 402.567381 -261.323515) (xy 402.428184 -261.353515) (xy 402.287514 -261.375591)
			(xy 402.14582 -261.389673) (xy 402.003556 -261.395716) (xy 401.861178 -261.393701) (xy 401.719142 -261.383634)
			(xy 401.577903 -261.365548) (xy 401.437913 -261.3395) (xy 401.299622 -261.305574) (xy 401.163471 -261.263878)
			(xy 401.029897 -261.214546) (xy 400.899328 -261.157737) (xy 400.772182 -261.093631) (xy 400.648867 -261.022435)
			(xy 400.529777 -260.944377) (xy 400.415294 -260.859705) (xy 400.305785 -260.768693) (xy 400.2016 -260.671631)
			(xy 400.103073 -260.56883) (xy 400.01052 -260.460619) (xy 399.924238 -260.347346) (xy 399.844501 -260.229373)
			(xy 399.771567 -260.107077) (xy 399.705669 -259.980851) (xy 399.647018 -259.851099) (xy 399.595801 -259.718237)
			(xy 399.552183 -259.58269) (xy 399.516303 -259.444892) (xy 399.488276 -259.305285) (xy 399.468193 -259.164317)
			(xy 399.456118 -259.022437) (xy 399.452088 -258.880102) (xy 351.160721 -258.880102) (xy 351.160304 -258.885614)
			(xy 351.147802 -258.939881) (xy 351.127281 -258.99165) (xy 351.099206 -259.039744) (xy 351.064218 -259.083068)
			(xy 351.023111 -259.120637) (xy 350.976821 -259.151596) (xy 350.9518 -259.16382) (xy 350.938338 -259.17017)
			(xy 350.92259 -259.194808) (xy 350.92259 -259.365242) (xy 350.938338 -259.38988) (xy 350.9518 -259.39623)
			(xy 350.975241 -259.407715) (xy 351.018909 -259.436314) (xy 351.058102 -259.470791) (xy 351.092035 -259.510455)
			(xy 351.12003 -259.554512) (xy 351.141525 -259.60208) (xy 351.156089 -259.652206) (xy 351.163432 -259.703886)
			(xy 351.16389 -259.729986) (xy 351.163443 -259.756332) (xy 351.155946 -259.808487) (xy 351.141102 -259.859045)
			(xy 351.119214 -259.906975) (xy 351.090727 -259.951302) (xy 351.056221 -259.991124) (xy 351.016399 -260.025629)
			(xy 350.972072 -260.054116) (xy 350.924141 -260.076003) (xy 350.873583 -260.090847) (xy 350.821428 -260.098343)
			(xy 350.795082 -260.098794) (xy 350.769907 -260.098364) (xy 350.720024 -260.091512) (xy 350.671538 -260.077936)
			(xy 350.64827 -260.068314) (xy 350.634554 -260.062472) (xy 350.605852 -260.067044) (xy 349.537528 -261.00786)
			(xy 349.529146 -261.034276) (xy 349.532702 -261.0485) (xy 349.536992 -261.067579) (xy 349.541582 -261.106416)
			(xy 349.541846 -261.12597) (xy 349.541442 -261.149589) (xy 349.534758 -261.196351) (xy 349.521493 -261.241687)
			(xy 349.501916 -261.284676) (xy 349.489522 -261.304786) (xy 349.481648 -261.316978) (xy 349.480886 -261.344918)
			(xy 349.624904 -261.593076) (xy 349.649542 -261.606538) (xy 349.66402 -261.605776) (xy 349.681038 -261.605268)
			(xy 349.707025 -261.60578) (xy 349.758359 -261.613916) (xy 349.807788 -261.629982) (xy 349.854095 -261.653581)
			(xy 349.896141 -261.684134) (xy 349.932891 -261.720888) (xy 349.963438 -261.762937) (xy 349.987033 -261.809247)
			(xy 350.003093 -261.858678) (xy 350.011223 -261.910013) (xy 350.011223 -261.961987) (xy 350.003093 -262.013322)
			(xy 349.987033 -262.062753) (xy 349.963438 -262.109063) (xy 349.932891 -262.151112) (xy 349.896141 -262.187866)
			(xy 349.854095 -262.218419) (xy 349.807788 -262.242018) (xy 349.758359 -262.258084) (xy 349.707025 -262.26622)
			(xy 349.681038 -262.266684) (xy 349.66656 -262.26643) (xy 349.652336 -262.265668) (xy 349.627444 -262.279384)
			(xy 349.482664 -262.529066) (xy 349.483172 -262.557514) (xy 349.490792 -262.569452) (xy 349.50289 -262.589355)
			(xy 349.521985 -262.631837) (xy 349.53493 -262.676579) (xy 349.541469 -262.722694) (xy 349.541846 -262.745982)
			(xy 349.541429 -262.769569) (xy 349.534729 -262.816264) (xy 349.521462 -262.861534) (xy 349.501897 -262.90446)
			(xy 349.489522 -262.924544) (xy 349.481648 -262.936736) (xy 349.480886 -262.96493) (xy 349.624904 -263.213088)
			(xy 349.649542 -263.22655) (xy 349.66402 -263.225788) (xy 349.681038 -263.22528) (xy 349.707024 -263.225792)
			(xy 349.758354 -263.233928) (xy 349.80778 -263.249992) (xy 349.854085 -263.273589) (xy 349.896129 -263.30414)
			(xy 349.932877 -263.34089) (xy 349.963424 -263.382937) (xy 349.987018 -263.429244) (xy 350.003078 -263.478671)
			(xy 350.01121 -263.530002) (xy 350.011746 -263.555988) (xy 350.011328 -263.579575) (xy 350.004627 -263.62627)
			(xy 349.99136 -263.671539) (xy 349.971795 -263.714464) (xy 349.959422 -263.73455) (xy 349.951548 -263.746742)
			(xy 349.950786 -263.774936) (xy 350.094804 -264.023094) (xy 350.119442 -264.036556) (xy 350.13392 -264.035794)
			(xy 350.151192 -264.035286) (xy 350.174593 -264.035692) (xy 350.220927 -264.042293) (xy 350.265867 -264.055364)
			(xy 350.308513 -264.074645) (xy 350.328484 -264.086848) (xy 350.340422 -264.094468) (xy 350.368616 -264.094976)
			(xy 351.485962 -263.453372) (xy 351.490788 -263.45007) (xy 353.061524 -262.294624) (xy 353.072192 -262.266938)
			(xy 353.069144 -262.25246) (xy 353.065796 -262.234551) (xy 353.062233 -262.198289) (xy 353.062032 -262.18007)
			(xy 353.062482 -262.153727) (xy 353.069984 -262.101577) (xy 353.084832 -262.051026) (xy 353.106723 -262.003103)
			(xy 353.135212 -261.958783) (xy 353.169718 -261.918968) (xy 353.209539 -261.88447) (xy 353.253864 -261.85599)
			(xy 353.301792 -261.834108) (xy 353.352346 -261.81927) (xy 353.404497 -261.811777) (xy 353.43084 -261.811262)
			(xy 353.462937 -261.81195) (xy 353.526164 -261.823055) (xy 353.55657 -261.83336) (xy 353.57054 -261.83844)
			(xy 353.599496 -261.83209) (xy 354.008182 -261.42315) (xy 354.01377 -261.39267) (xy 354.00742 -261.378192)
			(xy 353.997605 -261.354753) (xy 353.983789 -261.305853) (xy 353.976835 -261.255517) (xy 353.976432 -261.23011)
			(xy 353.976879 -261.203765) (xy 353.984377 -261.151611) (xy 353.999221 -261.101055) (xy 354.02111 -261.053127)
			(xy 354.049598 -261.008802) (xy 354.084104 -260.968982) (xy 354.123926 -260.93448) (xy 354.168253 -260.905996)
			(xy 354.216183 -260.884111) (xy 354.26674 -260.869271) (xy 354.318895 -260.861777) (xy 354.34524 -260.861302)
			(xy 354.373262 -260.861826) (xy 354.428659 -260.870309) (xy 354.482136 -260.887075) (xy 354.532462 -260.911736)
			(xy 354.578479 -260.943725) (xy 354.619127 -260.982307) (xy 354.653471 -261.026594) (xy 354.680722 -261.075566)
			(xy 354.700252 -261.128097) (xy 354.706428 -261.155434) (xy 354.710238 -261.173468) (xy 354.737924 -261.196074)
			(xy 355.22281 -261.196074) (xy 355.247702 -261.180072) (xy 355.253798 -261.166864) (xy 355.266062 -261.141792)
			(xy 355.297011 -261.095346) (xy 355.334603 -261.054094) (xy 355.377982 -261.018975) (xy 355.426156 -260.990793)
			(xy 355.478027 -260.970191) (xy 355.532409 -260.957638) (xy 355.588062 -260.953422) (xy 355.643715 -260.957638)
			(xy 355.698097 -260.970191) (xy 355.749968 -260.990793) (xy 355.798142 -261.018975) (xy 355.841521 -261.054094)
			(xy 355.879113 -261.095346) (xy 355.910062 -261.141792) (xy 355.922326 -261.166864) (xy 355.928422 -261.180072)
			(xy 355.953314 -261.196074) (xy 356.17277 -261.196074) (xy 356.197662 -261.180072) (xy 356.203758 -261.166864)
			(xy 356.216022 -261.141792) (xy 356.246971 -261.095346) (xy 356.284563 -261.054094) (xy 356.327942 -261.018975)
			(xy 356.376116 -260.990793) (xy 356.427987 -260.970191) (xy 356.482369 -260.957638) (xy 356.538022 -260.953422)
			(xy 356.593675 -260.957638) (xy 356.648057 -260.970191) (xy 356.699928 -260.990793) (xy 356.748102 -261.018975)
			(xy 356.791481 -261.054094) (xy 356.829073 -261.095346) (xy 356.860022 -261.141792) (xy 356.872286 -261.166864)
			(xy 356.878382 -261.180072) (xy 356.903274 -261.196074) (xy 357.12273 -261.196074) (xy 357.147622 -261.180072)
			(xy 357.153718 -261.166864) (xy 357.165982 -261.141792) (xy 357.196931 -261.095346) (xy 357.234523 -261.054094)
			(xy 357.277902 -261.018975) (xy 357.326076 -260.990793) (xy 357.377947 -260.970191) (xy 357.432329 -260.957638)
			(xy 357.487982 -260.953422) (xy 357.543635 -260.957638) (xy 357.598017 -260.970191) (xy 357.649888 -260.990793)
			(xy 357.698062 -261.018975) (xy 357.741441 -261.054094) (xy 357.779033 -261.095346) (xy 357.809982 -261.141792)
			(xy 357.822246 -261.166864) (xy 357.828342 -261.180072) (xy 357.853234 -261.196074) (xy 358.07269 -261.196074)
			(xy 358.097582 -261.180072) (xy 358.103678 -261.166864) (xy 358.115942 -261.141792) (xy 358.146891 -261.095346)
			(xy 358.184483 -261.054094) (xy 358.227862 -261.018975) (xy 358.276036 -260.990793) (xy 358.327907 -260.970191)
			(xy 358.382289 -260.957638) (xy 358.437942 -260.953422) (xy 358.493595 -260.957638) (xy 358.547977 -260.970191)
			(xy 358.599848 -260.990793) (xy 358.648022 -261.018975) (xy 358.691401 -261.054094) (xy 358.728993 -261.095346)
			(xy 358.759942 -261.141792) (xy 358.772206 -261.166864) (xy 358.778302 -261.180072) (xy 358.803194 -261.196074)
			(xy 359.02265 -261.196074) (xy 359.047542 -261.180072) (xy 359.053638 -261.166864) (xy 359.065902 -261.141792)
			(xy 359.096851 -261.095346) (xy 359.134443 -261.054094) (xy 359.177822 -261.018975) (xy 359.225996 -260.990793)
			(xy 359.277867 -260.970191) (xy 359.332249 -260.957638) (xy 359.387902 -260.953422) (xy 359.443555 -260.957638)
			(xy 359.497937 -260.970191) (xy 359.549808 -260.990793) (xy 359.597982 -261.018975) (xy 359.641361 -261.054094)
			(xy 359.678953 -261.095346) (xy 359.709902 -261.141792) (xy 359.722166 -261.166864) (xy 359.728262 -261.180072)
			(xy 359.753154 -261.196074) (xy 359.97261 -261.196074) (xy 359.997502 -261.180072) (xy 360.003598 -261.166864)
			(xy 360.015862 -261.141792) (xy 360.046811 -261.095346) (xy 360.084403 -261.054094) (xy 360.127782 -261.018975)
			(xy 360.175956 -260.990793) (xy 360.227827 -260.970191) (xy 360.282209 -260.957638) (xy 360.337862 -260.953422)
			(xy 360.393515 -260.957638) (xy 360.447897 -260.970191) (xy 360.499768 -260.990793) (xy 360.547942 -261.018975)
			(xy 360.591321 -261.054094) (xy 360.628913 -261.095346) (xy 360.659862 -261.141792) (xy 360.672126 -261.166864)
			(xy 360.678222 -261.180072) (xy 360.703114 -261.196074) (xy 360.922824 -261.196074) (xy 360.947716 -261.180072)
			(xy 360.953812 -261.166864) (xy 360.966076 -261.141792) (xy 360.997025 -261.095346) (xy 361.034617 -261.054094)
			(xy 361.077996 -261.018975) (xy 361.12617 -260.990793) (xy 361.178041 -260.970191) (xy 361.232423 -260.957638)
			(xy 361.288076 -260.953422) (xy 361.343729 -260.957638) (xy 361.398111 -260.970191) (xy 361.449982 -260.990793)
			(xy 361.498156 -261.018975) (xy 361.541535 -261.054094) (xy 361.579127 -261.095346) (xy 361.610076 -261.141792)
			(xy 361.62234 -261.166864) (xy 361.628436 -261.180072) (xy 361.653328 -261.196074) (xy 361.872784 -261.196074)
			(xy 361.897676 -261.180072) (xy 361.903772 -261.166864) (xy 361.916036 -261.141792) (xy 361.946985 -261.095346)
			(xy 361.984577 -261.054094) (xy 362.027956 -261.018975) (xy 362.07613 -260.990793) (xy 362.128001 -260.970191)
			(xy 362.182383 -260.957638) (xy 362.238036 -260.953422) (xy 362.293689 -260.957638) (xy 362.348071 -260.970191)
			(xy 362.399942 -260.990793) (xy 362.448116 -261.018975) (xy 362.491495 -261.054094) (xy 362.529087 -261.095346)
			(xy 362.560036 -261.141792) (xy 362.5723 -261.166864) (xy 362.578396 -261.180072) (xy 362.603288 -261.196074)
			(xy 362.822744 -261.196074) (xy 362.847636 -261.180072) (xy 362.853732 -261.166864) (xy 362.865996 -261.141792)
			(xy 362.896945 -261.095346) (xy 362.934537 -261.054094) (xy 362.977916 -261.018975) (xy 363.02609 -260.990793)
			(xy 363.077961 -260.970191) (xy 363.132343 -260.957638) (xy 363.187996 -260.953422) (xy 363.243649 -260.957638)
			(xy 363.298031 -260.970191) (xy 363.349902 -260.990793) (xy 363.398076 -261.018975) (xy 363.441455 -261.054094)
			(xy 363.479047 -261.095346) (xy 363.509996 -261.141792) (xy 363.52226 -261.166864) (xy 363.528356 -261.180072)
			(xy 363.553248 -261.196074) (xy 363.772704 -261.196074) (xy 363.797596 -261.180072) (xy 363.803692 -261.166864)
			(xy 363.815164 -261.14335) (xy 363.843759 -261.099539) (xy 363.878262 -261.060211) (xy 363.917977 -261.026156)
			(xy 363.962109 -260.998057) (xy 364.009769 -260.976479) (xy 364.060002 -260.961857) (xy 364.111797 -260.954482)
			(xy 364.137956 -260.954012) (xy 364.164303 -260.954457) (xy 364.216462 -260.961951) (xy 364.267023 -260.976792)
			(xy 364.314957 -260.998678) (xy 364.359288 -261.027165) (xy 364.399113 -261.06167) (xy 364.433621 -261.101493)
			(xy 364.46211 -261.145822) (xy 364.484 -261.193755) (xy 364.498844 -261.244315) (xy 364.506341 -261.296473)
			(xy 364.506764 -261.32282) (xy 364.50609 -261.354981) (xy 364.49498 -261.418335) (xy 364.484666 -261.448804)
			(xy 364.479586 -261.46252) (xy 364.485936 -261.491476) (xy 364.522766 -261.528306) (xy 364.530168 -261.535142)
			(xy 364.548766 -261.542851) (xy 364.558834 -261.543292) (xy 368.210592 -261.543292) (xy 368.227169 -261.543852)
			(xy 368.259191 -261.552453) (xy 368.28791 -261.569022) (xy 368.3 -261.580376) (xy 368.551206 -261.831836)
			(xy 368.561874 -261.839964) (xy 369.667282 -262.474964) (xy 369.695476 -262.474456) (xy 369.707414 -262.466836)
			(xy 369.727385 -262.454634) (xy 369.770035 -262.435364) (xy 369.814974 -262.422295) (xy 369.861306 -262.415688)
			(xy 369.884706 -262.415274) (xy 369.901978 -262.415782) (xy 369.916456 -262.416544) (xy 369.941348 -262.403082)
			(xy 370.085112 -262.155178) (xy 370.084604 -262.126984) (xy 370.07673 -262.114792) (xy 370.064284 -262.094702)
			(xy 370.044634 -262.051722) (xy 370.031303 -262.006382) (xy 370.024564 -261.959605) (xy 370.024152 -261.935976)
			(xy 370.024662 -261.909989) (xy 370.032792 -261.858654) (xy 370.048853 -261.809224) (xy 370.072449 -261.762914)
			(xy 370.102999 -261.720866) (xy 370.13975 -261.684115) (xy 370.181798 -261.653565) (xy 370.228108 -261.629969)
			(xy 370.277538 -261.613908) (xy 370.328873 -261.605778) (xy 370.380847 -261.605778) (xy 370.432182 -261.613908)
			(xy 370.481612 -261.629969) (xy 370.527922 -261.653565) (xy 370.56997 -261.684115) (xy 370.606721 -261.720866)
			(xy 370.637271 -261.762914) (xy 370.660867 -261.809224) (xy 370.676928 -261.858654) (xy 370.685058 -261.909989)
			(xy 370.685568 -261.935976) (xy 370.685314 -261.948422) (xy 370.684806 -261.962646) (xy 370.698522 -261.987284)
			(xy 371.54739 -262.474964) (xy 371.575584 -262.474456) (xy 371.587522 -262.466836) (xy 371.607494 -262.454635)
			(xy 371.650143 -262.435366) (xy 371.695082 -262.422298) (xy 371.741414 -262.415692) (xy 371.764814 -262.415274)
			(xy 371.790801 -262.415785) (xy 371.842135 -262.423917) (xy 371.891565 -262.439979) (xy 371.937874 -262.463575)
			(xy 371.979921 -262.494125) (xy 372.016673 -262.530876) (xy 372.047223 -262.572923) (xy 372.07082 -262.619232)
			(xy 372.086882 -262.668661) (xy 372.095015 -262.719995) (xy 372.095522 -262.745982) (xy 372.095268 -262.758428)
			(xy 372.09476 -262.772652) (xy 372.108476 -262.79729) (xy 372.957344 -263.28497) (xy 372.985538 -263.284462)
			(xy 372.997476 -263.276842) (xy 373.017447 -263.264638) (xy 373.060095 -263.245363) (xy 373.105034 -263.232288)
			(xy 373.151367 -263.225676) (xy 373.174768 -263.22528) (xy 373.19204 -263.225788) (xy 373.206518 -263.22655)
			(xy 373.23141 -263.213088) (xy 373.375174 -262.965184) (xy 373.374666 -262.93699) (xy 373.366792 -262.924798)
			(xy 373.354343 -262.904709) (xy 373.334689 -262.861729) (xy 373.321355 -262.816389) (xy 373.314614 -262.769612)
			(xy 373.314214 -262.745982) (xy 373.314724 -262.719995) (xy 373.322854 -262.66866) (xy 373.338915 -262.61923)
			(xy 373.362511 -262.57292) (xy 373.393061 -262.530872) (xy 373.429812 -262.494121) (xy 373.47186 -262.463571)
			(xy 373.51817 -262.439975) (xy 373.5676 -262.423914) (xy 373.618935 -262.415784) (xy 373.670909 -262.415784)
			(xy 373.722244 -262.423914) (xy 373.771674 -262.439975) (xy 373.817984 -262.463571) (xy 373.860032 -262.494121)
			(xy 373.896783 -262.530872) (xy 373.927333 -262.57292) (xy 373.950929 -262.61923) (xy 373.96699 -262.66866)
			(xy 373.97512 -262.719995) (xy 373.97563 -262.745982) (xy 373.975376 -262.758428) (xy 373.974868 -262.772652)
			(xy 373.988584 -262.79729) (xy 374.837452 -263.28497) (xy 374.865646 -263.284462) (xy 374.877584 -263.276842)
			(xy 374.897555 -263.264638) (xy 374.940204 -263.245364) (xy 374.985143 -263.232291) (xy 375.031475 -263.22568)
			(xy 375.054876 -263.22528) (xy 375.072148 -263.225788) (xy 375.086626 -263.22655) (xy 375.111264 -263.213088)
			(xy 375.255028 -262.965692) (xy 375.25452 -262.93699) (xy 375.246646 -262.925052) (xy 375.234209 -262.90492)
			(xy 375.214548 -262.861879) (xy 375.201211 -262.816478) (xy 375.194468 -262.769642) (xy 375.194068 -262.745982)
			(xy 375.194579 -262.719995) (xy 375.202712 -262.668661) (xy 375.218774 -262.619232) (xy 375.24237 -262.572923)
			(xy 375.27292 -262.530875) (xy 375.309671 -262.494124) (xy 375.351718 -262.463573) (xy 375.398026 -262.439976)
			(xy 375.447456 -262.423913) (xy 375.498789 -262.415779) (xy 375.524776 -262.415274) (xy 375.550603 -262.415769)
			(xy 375.60163 -262.423796) (xy 375.650788 -262.439658) (xy 375.696883 -262.46297) (xy 375.738793 -262.493165)
			(xy 375.775499 -262.529509) (xy 375.806108 -262.571117) (xy 375.8184 -262.593836) (xy 375.825004 -262.606536)
			(xy 375.849134 -262.621268) (xy 376.140472 -262.621268) (xy 376.164602 -262.606536) (xy 376.171206 -262.593836)
			(xy 376.183529 -262.571135) (xy 376.214133 -262.529527) (xy 376.250833 -262.493183) (xy 376.292738 -262.462987)
			(xy 376.338828 -262.439673) (xy 376.387982 -262.423808) (xy 376.439005 -262.415778) (xy 376.490655 -262.415778)
			(xy 376.541678 -262.423808) (xy 376.590832 -262.439673) (xy 376.636922 -262.462987) (xy 376.678827 -262.493183)
			(xy 376.715527 -262.529527) (xy 376.746131 -262.571135) (xy 376.758454 -262.593836) (xy 376.765058 -262.606536)
			(xy 376.789188 -262.621268) (xy 377.080526 -262.621268) (xy 377.104656 -262.606536) (xy 377.11126 -262.593836)
			(xy 377.123583 -262.571135) (xy 377.154187 -262.529527) (xy 377.190887 -262.493183) (xy 377.232792 -262.462987)
			(xy 377.278882 -262.439673) (xy 377.328036 -262.423808) (xy 377.379059 -262.415778) (xy 377.430709 -262.415778)
			(xy 377.481732 -262.423808) (xy 377.530886 -262.439673) (xy 377.576976 -262.462987) (xy 377.618881 -262.493183)
			(xy 377.655581 -262.529527) (xy 377.686185 -262.571135) (xy 377.698508 -262.593836) (xy 377.705112 -262.606536)
			(xy 377.729242 -262.621268) (xy 378.02058 -262.621268) (xy 378.04471 -262.606536) (xy 378.051314 -262.593836)
			(xy 378.063636 -262.571133) (xy 378.09424 -262.529521) (xy 378.130939 -262.493172) (xy 378.172843 -262.46297)
			(xy 378.218933 -262.439649) (xy 378.268087 -262.423776) (xy 378.319111 -262.415737) (xy 378.344938 -262.415274)
			(xy 378.370924 -262.415786) (xy 378.422255 -262.423922) (xy 378.471681 -262.439986) (xy 378.517987 -262.463583)
			(xy 378.560031 -262.494133) (xy 378.59678 -262.530884) (xy 378.627327 -262.57293) (xy 378.650922 -262.619237)
			(xy 378.666983 -262.668665) (xy 378.675115 -262.719996) (xy 378.675646 -262.745982) (xy 378.675392 -262.758428)
			(xy 378.674884 -262.772652) (xy 378.6886 -262.79729) (xy 379.537214 -263.28497) (xy 379.565662 -263.284462)
			(xy 379.5776 -263.276842) (xy 379.597571 -263.264639) (xy 379.64022 -263.245367) (xy 379.685159 -263.232296)
			(xy 379.731491 -263.225687) (xy 379.754892 -263.22528) (xy 379.780718 -263.225776) (xy 379.831743 -263.233805)
			(xy 379.8809 -263.24967) (xy 379.926992 -263.272983) (xy 379.9689 -263.303179) (xy 380.005603 -263.339523)
			(xy 380.03621 -263.381131) (xy 380.048516 -263.403842) (xy 380.05512 -263.416542) (xy 380.07925 -263.431274)
			(xy 380.370588 -263.431274) (xy 380.394718 -263.416542) (xy 380.401322 -263.403842) (xy 380.413645 -263.381141)
			(xy 380.444249 -263.339533) (xy 380.480949 -263.303189) (xy 380.522854 -263.272993) (xy 380.568944 -263.249679)
			(xy 380.618098 -263.233814) (xy 380.669121 -263.225784) (xy 380.720771 -263.225784) (xy 380.771794 -263.233814)
			(xy 380.820948 -263.249679) (xy 380.867038 -263.272993) (xy 380.908943 -263.303189) (xy 380.945643 -263.339533)
			(xy 380.976247 -263.381141) (xy 380.98857 -263.403842) (xy 380.995174 -263.416542) (xy 381.019304 -263.431274)
			(xy 381.310388 -263.431274) (xy 381.334518 -263.416542) (xy 381.341122 -263.403842) (xy 381.353445 -263.381141)
			(xy 381.384049 -263.339533) (xy 381.420749 -263.303189) (xy 381.462654 -263.272993) (xy 381.508744 -263.249679)
			(xy 381.557898 -263.233814) (xy 381.608921 -263.225784) (xy 381.660571 -263.225784) (xy 381.711594 -263.233814)
			(xy 381.760748 -263.249679) (xy 381.806838 -263.272993) (xy 381.848743 -263.303189) (xy 381.885443 -263.339533)
			(xy 381.916047 -263.381141) (xy 381.92837 -263.403842) (xy 381.934974 -263.416542) (xy 381.959104 -263.431274)
			(xy 382.250442 -263.431274) (xy 382.274572 -263.416542) (xy 382.281176 -263.403842) (xy 382.293499 -263.381141)
			(xy 382.324103 -263.339533) (xy 382.360803 -263.303189) (xy 382.402708 -263.272993) (xy 382.448798 -263.249679)
			(xy 382.497952 -263.233814) (xy 382.548975 -263.225784) (xy 382.600625 -263.225784) (xy 382.651648 -263.233814)
			(xy 382.700802 -263.249679) (xy 382.746892 -263.272993) (xy 382.788797 -263.303189) (xy 382.825497 -263.339533)
			(xy 382.856101 -263.381141) (xy 382.868424 -263.403842) (xy 382.875028 -263.416542) (xy 382.899158 -263.431274)
			(xy 383.190496 -263.431274) (xy 383.214626 -263.416542) (xy 383.22123 -263.403842) (xy 383.233553 -263.381141)
			(xy 383.264157 -263.339533) (xy 383.300857 -263.303189) (xy 383.342762 -263.272993) (xy 383.388852 -263.249679)
			(xy 383.438006 -263.233814) (xy 383.489029 -263.225784) (xy 383.540679 -263.225784) (xy 383.591702 -263.233814)
			(xy 383.640856 -263.249679) (xy 383.686946 -263.272993) (xy 383.728851 -263.303189) (xy 383.765551 -263.339533)
			(xy 383.796155 -263.381141) (xy 383.808478 -263.403842) (xy 383.815082 -263.416542) (xy 383.839212 -263.431274)
			(xy 384.13055 -263.431274) (xy 384.15468 -263.416542) (xy 384.161284 -263.403842) (xy 384.173607 -263.381142)
			(xy 384.204212 -263.339536) (xy 384.240913 -263.303194) (xy 384.282818 -263.273) (xy 384.328908 -263.249688)
			(xy 384.378061 -263.233825) (xy 384.429083 -263.225796) (xy 384.454908 -263.22528) (xy 384.480895 -263.22579)
			(xy 384.532229 -263.233922) (xy 384.58166 -263.249983) (xy 384.627969 -263.273579) (xy 384.670017 -263.304129)
			(xy 384.706768 -263.34088) (xy 384.737319 -263.382928) (xy 384.760915 -263.429237) (xy 384.776977 -263.478667)
			(xy 384.78511 -263.530001) (xy 384.785616 -263.555988) (xy 384.785222 -263.578975) (xy 384.778856 -263.624506)
			(xy 384.766244 -263.668717) (xy 384.747631 -263.710754) (xy 384.735832 -263.730486) (xy 384.728212 -263.742678)
			(xy 384.727958 -263.770364) (xy 384.874262 -264.022586) (xy 384.898646 -264.036048) (xy 384.91287 -264.03554)
			(xy 384.924808 -264.035286) (xy 384.950634 -264.035783) (xy 385.001657 -264.043815) (xy 385.050811 -264.059681)
			(xy 385.096901 -264.082996) (xy 385.138806 -264.113192) (xy 385.175507 -264.149537) (xy 385.206111 -264.191145)
			(xy 385.218432 -264.213848) (xy 385.225036 -264.226548) (xy 385.249166 -264.24128) (xy 385.540504 -264.24128)
			(xy 385.564634 -264.226548) (xy 385.571238 -264.213848) (xy 385.583561 -264.191147) (xy 385.614165 -264.149539)
			(xy 385.650865 -264.113195) (xy 385.69277 -264.082999) (xy 385.73886 -264.059685) (xy 385.788014 -264.04382)
			(xy 385.839037 -264.03579) (xy 385.890687 -264.03579) (xy 385.94171 -264.04382) (xy 385.990864 -264.059685)
			(xy 386.036954 -264.082999) (xy 386.078859 -264.113195) (xy 386.115559 -264.149539) (xy 386.146163 -264.191147)
			(xy 386.158486 -264.213848) (xy 386.16509 -264.226548) (xy 386.18922 -264.24128) (xy 386.480558 -264.24128)
			(xy 386.504688 -264.226548) (xy 386.511292 -264.213848) (xy 386.523615 -264.191147) (xy 386.554219 -264.149539)
			(xy 386.590919 -264.113195) (xy 386.632824 -264.082999) (xy 386.678914 -264.059685) (xy 386.728068 -264.04382)
			(xy 386.779091 -264.03579) (xy 386.830741 -264.03579) (xy 386.881764 -264.04382) (xy 386.930918 -264.059685)
			(xy 386.977008 -264.082999) (xy 387.018913 -264.113195) (xy 387.055613 -264.149539) (xy 387.086217 -264.191147)
			(xy 387.09854 -264.213848) (xy 387.105144 -264.226548) (xy 387.129274 -264.24128) (xy 387.420358 -264.24128)
			(xy 387.444488 -264.226548) (xy 387.451092 -264.213848) (xy 387.463415 -264.191147) (xy 387.494019 -264.149539)
			(xy 387.530719 -264.113195) (xy 387.572624 -264.082999) (xy 387.618714 -264.059685) (xy 387.667868 -264.04382)
			(xy 387.718891 -264.03579) (xy 387.770541 -264.03579) (xy 387.821564 -264.04382) (xy 387.870718 -264.059685)
			(xy 387.916808 -264.082999) (xy 387.958713 -264.113195) (xy 387.995413 -264.149539) (xy 388.026017 -264.191147)
			(xy 388.03834 -264.213848) (xy 388.044944 -264.226548) (xy 388.069074 -264.24128) (xy 388.360412 -264.24128)
			(xy 388.384542 -264.226548) (xy 388.391146 -264.213848) (xy 388.403469 -264.191147) (xy 388.434073 -264.149539)
			(xy 388.470773 -264.113195) (xy 388.512678 -264.082999) (xy 388.558768 -264.059685) (xy 388.607922 -264.04382)
			(xy 388.658945 -264.03579) (xy 388.710595 -264.03579) (xy 388.761618 -264.04382) (xy 388.810772 -264.059685)
			(xy 388.856862 -264.082999) (xy 388.898767 -264.113195) (xy 388.935467 -264.149539) (xy 388.966071 -264.191147)
			(xy 388.978394 -264.213848) (xy 388.984998 -264.226548) (xy 389.009128 -264.24128) (xy 389.300466 -264.24128)
			(xy 389.324596 -264.226548) (xy 389.3312 -264.213848) (xy 389.343523 -264.191148) (xy 389.374128 -264.149543)
			(xy 389.41083 -264.113203) (xy 389.452735 -264.08301) (xy 389.498824 -264.0597) (xy 389.547978 -264.043838)
			(xy 389.598999 -264.035812) (xy 389.624824 -264.035286) (xy 389.65081 -264.035797) (xy 389.702142 -264.043931)
			(xy 389.75157 -264.059994) (xy 389.797876 -264.083591) (xy 389.839922 -264.114141) (xy 389.876671 -264.150892)
			(xy 389.907219 -264.192939) (xy 389.930813 -264.239247) (xy 389.946873 -264.288675) (xy 389.955004 -264.340008)
			(xy 389.955532 -264.365994) (xy 389.955138 -264.388981) (xy 389.948771 -264.434512) (xy 389.936159 -264.478722)
			(xy 389.917546 -264.52076) (xy 389.905748 -264.540492) (xy 389.898128 -264.552684) (xy 389.897874 -264.580624)
			(xy 390.044178 -264.832592) (xy 390.068562 -264.846054) (xy 390.082786 -264.845546) (xy 390.094724 -264.845292)
			(xy 390.12071 -264.845803) (xy 390.172042 -264.853937) (xy 390.221469 -264.87) (xy 390.267775 -264.893597)
			(xy 390.30982 -264.924147) (xy 390.346568 -264.960898) (xy 390.377115 -265.002945) (xy 390.400709 -265.049253)
			(xy 390.416769 -265.098682) (xy 390.424899 -265.150014) (xy 390.425432 -265.176) (xy 390.425037 -265.198987)
			(xy 390.41867 -265.244518) (xy 390.406058 -265.288728) (xy 390.387444 -265.330765) (xy 390.375648 -265.350498)
			(xy 390.368282 -265.362436) (xy 390.367774 -265.390376) (xy 390.528556 -265.667236) (xy 390.55167 -265.680698)
			(xy 390.565386 -265.680698) (xy 390.589352 -265.681205) (xy 390.636685 -265.688771) (xy 390.682253 -265.703642)
			(xy 390.724938 -265.725451) (xy 390.76369 -265.753663) (xy 390.797557 -265.787585) (xy 390.825707 -265.826382)
			(xy 390.847447 -265.869102) (xy 390.862244 -265.914694) (xy 390.869734 -265.962039) (xy 390.870186 -265.986006)
			(xy 390.869635 -266.012325) (xy 390.860612 -266.064184) (xy 390.842834 -266.113728) (xy 390.830308 -266.136882)
			(xy 390.82345 -266.14882) (xy 390.823704 -266.175744) (xy 390.984232 -266.452604) (xy 391.008616 -266.466066)
			(xy 391.02284 -266.465558) (xy 391.034778 -266.465304) (xy 391.060605 -266.465799) (xy 391.11163 -266.473827)
			(xy 391.160787 -266.48969) (xy 391.20688 -266.513004) (xy 391.248788 -266.5432) (xy 391.28549 -266.579545)
			(xy 391.316096 -266.621155) (xy 391.328402 -266.643866) (xy 391.335006 -266.656566) (xy 391.359136 -266.671298)
			(xy 391.650474 -266.671298)
		)
		(stroke
			(width 0)
			(type solid)
		)
		(fill yes)
		(layer "In9.Cu")
		(net "PVDDCR_SOC_P0")
	)
	(gr_poly
		(pts
			(xy 100.348542 -190.745872) (xy 100.358608 -190.745441) (xy 100.377199 -190.737712) (xy 100.38461 -190.730886)
			(xy 104.2416 -186.873896) (xy 104.259642 -186.856639) (xy 104.301136 -186.828886) (xy 104.347254 -186.80978)
			(xy 104.396218 -186.800057) (xy 104.421178 -186.799474) (xy 110.585758 -186.799474) (xy 110.59424 -186.799158)
			(xy 110.610266 -186.793593) (xy 110.623569 -186.783067) (xy 110.62843 -186.776106) (xy 110.643532 -186.753314)
			(xy 110.679223 -186.711895) (xy 110.720461 -186.675994) (xy 110.7664 -186.646346) (xy 110.8161 -186.623558)
			(xy 110.868543 -186.608096) (xy 110.922656 -186.600278) (xy 110.949994 -186.59983) (xy 110.978733 -186.600351)
			(xy 111.035561 -186.608973) (xy 111.090452 -186.626024) (xy 111.142163 -186.651116) (xy 111.189525 -186.683683)
			(xy 111.210852 -186.702954) (xy 111.217964 -186.709558) (xy 111.23549 -186.71667) (xy 111.324898 -186.71667)
			(xy 111.342424 -186.709558) (xy 111.349536 -186.702954) (xy 111.369216 -186.685119) (xy 111.412614 -186.654506)
			(xy 111.45984 -186.630209) (xy 111.509981 -186.6127) (xy 111.562065 -186.602317) (xy 111.58855 -186.600338)
			(xy 111.597948 -186.59983) (xy 111.614712 -186.592464) (xy 111.6584 -186.548776) (xy 111.665243 -186.541376)
			(xy 111.672968 -186.522778) (xy 111.673386 -186.512708) (xy 111.673386 -183.963564) (xy 111.674001 -183.938609)
			(xy 111.683744 -183.889658) (xy 111.702849 -183.843548) (xy 111.730581 -183.802051) (xy 111.747808 -183.783986)
			(xy 126.247144 -169.28465) (xy 126.265185 -169.267391) (xy 126.306679 -169.239634) (xy 126.352797 -169.220522)
			(xy 126.401761 -169.21079) (xy 126.426722 -169.210228) (xy 128.337564 -169.210228) (xy 128.347616 -169.209725)
			(xy 128.366181 -169.202008) (xy 128.373632 -169.195242) (xy 129.705608 -167.863266) (xy 129.723648 -167.846003)
			(xy 129.76514 -167.818239) (xy 129.811258 -167.799119) (xy 129.860224 -167.789379) (xy 129.885186 -167.788844)
			(xy 136.0932 -167.788844) (xy 136.103211 -167.788357) (xy 136.12171 -167.780699) (xy 136.135874 -167.766547)
			(xy 136.143548 -167.748054) (xy 136.144 -167.738044) (xy 136.144 -153.707846) (xy 136.143567 -153.69778)
			(xy 136.135839 -153.67919) (xy 136.129014 -153.671778) (xy 135.562848 -153.105612) (xy 135.555447 -153.098772)
			(xy 135.536849 -153.091055) (xy 135.52678 -153.090626) (xy 134.680198 -153.090626) (xy 134.67217 -153.090869)
			(xy 134.656891 -153.095795) (xy 134.650226 -153.100278) (xy 134.628393 -153.115636) (xy 134.581291 -153.140749)
			(xy 134.531146 -153.159046) (xy 134.478938 -153.17017) (xy 134.42569 -153.173902) (xy 134.372442 -153.17017)
			(xy 134.320234 -153.159046) (xy 134.270089 -153.140749) (xy 134.222987 -153.115636) (xy 134.201154 -153.100278)
			(xy 134.194468 -153.095836) (xy 134.179203 -153.090908) (xy 134.171182 -153.090626) (xy 133.003036 -153.090626)
			(xy 132.992702 -153.091113) (xy 132.973699 -153.099241) (xy 132.966206 -153.106374) (xy 132.946473 -153.126409)
			(xy 132.902167 -153.161038) (xy 132.853255 -153.188783) (xy 132.800798 -153.209042) (xy 132.745934 -153.221376)
			(xy 132.689854 -153.225518) (xy 132.633774 -153.221376) (xy 132.57891 -153.209042) (xy 132.526453 -153.188783)
			(xy 132.477541 -153.161038) (xy 132.433235 -153.126409) (xy 132.413502 -153.106374) (xy 132.406028 -153.09921)
			(xy 132.387014 -153.09107) (xy 132.376672 -153.090626) (xy 130.695954 -153.090626) (xy 130.668522 -153.112724)
			(xy 130.664458 -153.13025) (xy 130.655225 -153.169134) (xy 130.630677 -153.245197) (xy 130.615436 -153.282142)
			(xy 130.611863 -153.291733) (xy 130.611846 -153.312183) (xy 130.615436 -153.321766) (xy 130.631212 -153.360078)
			(xy 130.656411 -153.439014) (xy 130.674165 -153.519951) (xy 130.68432 -153.602187) (xy 130.686048 -153.643584)
			(xy 130.68684 -153.654523) (xy 130.696459 -153.674208) (xy 130.713424 -153.688072) (xy 130.723894 -153.691336)
			(xy 130.740766 -153.695835) (xy 130.774177 -153.705998) (xy 130.790696 -153.711656) (xy 130.798892 -153.714179)
			(xy 130.816028 -153.714179) (xy 130.824224 -153.711656) (xy 130.859442 -153.699704) (xy 130.931449 -153.68107)
			(xy 131.004769 -153.668566) (xy 131.078881 -153.662282) (xy 131.11607 -153.661872) (xy 131.153261 -153.662256)
			(xy 131.227377 -153.668525) (xy 131.3007 -153.681029) (xy 131.372705 -153.699678) (xy 131.407916 -153.711656)
			(xy 131.416112 -153.714179) (xy 131.433248 -153.714179) (xy 131.441444 -153.711656) (xy 131.476662 -153.699701)
			(xy 131.548668 -153.68106) (xy 131.621987 -153.66855) (xy 131.6961 -153.662259) (xy 131.73329 -153.661872)
			(xy 131.775226 -153.662355) (xy 131.858719 -153.670327) (xy 131.941076 -153.686199) (xy 132.021552 -153.709828)
			(xy 132.099416 -153.740999) (xy 132.173966 -153.779431) (xy 132.244524 -153.824776) (xy 132.310453 -153.876622)
			(xy 132.371155 -153.9345) (xy 132.42608 -153.997887) (xy 132.474731 -154.066207) (xy 132.516668 -154.138843)
			(xy 132.55151 -154.215136) (xy 132.578942 -154.294395) (xy 132.598716 -154.375904) (xy 132.610652 -154.458922)
			(xy 132.614643 -154.5427) (xy 132.610652 -154.626478) (xy 132.598716 -154.709496) (xy 132.578942 -154.791005)
			(xy 132.55151 -154.870264) (xy 132.516668 -154.946557) (xy 132.474731 -155.019193) (xy 132.42608 -155.087513)
			(xy 132.371155 -155.1509) (xy 132.310453 -155.208778) (xy 132.244524 -155.260624) (xy 132.173966 -155.305969)
			(xy 132.099416 -155.344401) (xy 132.021552 -155.375572) (xy 131.941076 -155.399201) (xy 131.858719 -155.415073)
			(xy 131.775226 -155.423045) (xy 131.73329 -155.423616) (xy 131.6961 -155.42323) (xy 131.621984 -155.416958)
			(xy 131.548663 -155.404451) (xy 131.476659 -155.385798) (xy 131.441444 -155.373832) (xy 131.433248 -155.371309)
			(xy 131.416112 -155.371309) (xy 131.407916 -155.373832) (xy 131.37458 -155.385161) (xy 131.306488 -155.403091)
			(xy 131.237181 -155.415522) (xy 131.202176 -155.419298) (xy 131.192211 -155.42073) (xy 131.174495 -155.430262)
			(xy 131.161779 -155.445852) (xy 131.158488 -155.455366) (xy 131.151037 -155.480116) (xy 131.133628 -155.528788)
			(xy 131.12369 -155.552648) (xy 131.120116 -155.562239) (xy 131.120101 -155.582688) (xy 131.12369 -155.592272)
			(xy 131.140693 -155.633685) (xy 131.167264 -155.71918) (xy 131.185107 -155.806913) (xy 131.19404 -155.895995)
			(xy 131.194556 -155.94076) (xy 131.194052 -155.983108) (xy 131.186001 -156.067422) (xy 131.169972 -156.150588)
			(xy 131.146111 -156.231855) (xy 131.114632 -156.310485) (xy 131.075821 -156.385766) (xy 131.030031 -156.457018)
			(xy 130.977675 -156.523594) (xy 130.919227 -156.584892) (xy 130.855217 -156.640357) (xy 130.786225 -156.689486)
			(xy 130.712875 -156.731835) (xy 130.635832 -156.767019) (xy 130.555793 -156.794721) (xy 130.473484 -156.814689)
			(xy 130.389649 -156.826742) (xy 130.305048 -156.830773) (xy 130.220447 -156.826742) (xy 130.136612 -156.814689)
			(xy 130.054303 -156.794721) (xy 129.974264 -156.767019) (xy 129.897221 -156.731835) (xy 129.823871 -156.689486)
			(xy 129.754879 -156.640357) (xy 129.690869 -156.584892) (xy 129.632421 -156.523594) (xy 129.580065 -156.457018)
			(xy 129.534275 -156.385766) (xy 129.495464 -156.310485) (xy 129.463985 -156.231855) (xy 129.440124 -156.150588)
			(xy 129.424095 -156.067422) (xy 129.416044 -155.983108) (xy 129.41554 -155.94076) (xy 129.41607 -155.895996)
			(xy 129.425012 -155.806917) (xy 129.442852 -155.719185) (xy 129.46941 -155.633687) (xy 129.486406 -155.592272)
			(xy 129.489964 -155.582682) (xy 129.489949 -155.562245) (xy 129.486406 -155.552648) (xy 129.471432 -155.516312)
			(xy 129.447188 -155.441549) (xy 129.429633 -155.364938) (xy 129.418904 -155.287078) (xy 129.416556 -155.247848)
			(xy 129.415794 -155.233878) (xy 129.400046 -155.210256) (xy 129.292604 -155.160472) (xy 129.264664 -155.16352)
			(xy 129.253234 -155.172156) (xy 129.22 -155.19695) (xy 129.149714 -155.240949) (xy 129.07564 -155.278222)
			(xy 128.998422 -155.308446) (xy 128.918728 -155.331358) (xy 128.837249 -155.346761) (xy 128.754691 -155.354521)
			(xy 128.71323 -155.355036) (xy 128.672115 -155.354577) (xy 128.590235 -155.346992) (xy 128.509404 -155.331884)
			(xy 128.430311 -155.309383) (xy 128.353633 -155.279679) (xy 128.280023 -155.243027) (xy 128.210108 -155.199739)
			(xy 128.144486 -155.150184) (xy 128.083717 -155.094786) (xy 128.028318 -155.034017) (xy 127.978764 -154.968395)
			(xy 127.935475 -154.898481) (xy 127.898823 -154.824871) (xy 127.869119 -154.748192) (xy 127.846617 -154.6691)
			(xy 127.831508 -154.588269) (xy 127.823923 -154.506389) (xy 127.823468 -154.465274) (xy 127.824021 -154.420503)
			(xy 127.833015 -154.331415) (xy 127.850921 -154.243682) (xy 127.877557 -154.158194) (xy 127.894588 -154.116786)
			(xy 127.89815 -154.107196) (xy 127.89814 -154.086757) (xy 127.894588 -154.077162) (xy 127.877564 -154.035751)
			(xy 127.850943 -153.95026) (xy 127.833035 -153.862529) (xy 127.824022 -153.773444) (xy 127.823468 -153.728674)
			(xy 127.824021 -153.683903) (xy 127.833015 -153.594815) (xy 127.850921 -153.507082) (xy 127.877557 -153.421594)
			(xy 127.894588 -153.380186) (xy 127.89815 -153.370596) (xy 127.89814 -153.350157) (xy 127.894588 -153.340562)
			(xy 127.880819 -153.307252) (xy 127.85808 -153.238849) (xy 127.840951 -153.16883) (xy 127.834898 -153.133298)
			(xy 127.83185 -153.114756) (xy 127.803656 -153.090626) (xy 120.270524 -153.090626) (xy 120.26177 -153.091008)
			(xy 120.245285 -153.096913) (xy 120.231718 -153.107985) (xy 120.226836 -153.115264) (xy 120.204981 -153.150744)
			(xy 120.15561 -153.217881) (xy 120.100174 -153.280104) (xy 120.03916 -153.336869) (xy 119.973104 -153.387677)
			(xy 119.902584 -153.432083) (xy 119.82822 -153.469697) (xy 119.750663 -153.500189) (xy 119.670593 -153.523293)
			(xy 119.588714 -153.538805) (xy 119.505742 -153.546589) (xy 119.464074 -153.547064) (xy 119.425791 -153.546661)
			(xy 119.349506 -153.540103) (xy 119.274066 -153.527021) (xy 119.200027 -153.50751) (xy 119.163846 -153.494994)
			(xy 119.155409 -153.492343) (xy 119.137739 -153.492343) (xy 119.129302 -153.494994) (xy 119.093126 -153.507531)
			(xy 119.01909 -153.527063) (xy 118.943648 -153.54015) (xy 118.867359 -153.546695) (xy 118.829074 -153.547064)
			(xy 118.790791 -153.546661) (xy 118.714506 -153.540103) (xy 118.639066 -153.527021) (xy 118.565027 -153.50751)
			(xy 118.528846 -153.494994) (xy 118.520409 -153.492343) (xy 118.502739 -153.492343) (xy 118.494302 -153.494994)
			(xy 118.458126 -153.507531) (xy 118.38409 -153.527063) (xy 118.308648 -153.54015) (xy 118.232359 -153.546695)
			(xy 118.194074 -153.547064) (xy 118.155791 -153.546661) (xy 118.079506 -153.540103) (xy 118.004066 -153.527021)
			(xy 117.930027 -153.50751) (xy 117.893846 -153.494994) (xy 117.885409 -153.492343) (xy 117.867739 -153.492343)
			(xy 117.859302 -153.494994) (xy 117.823126 -153.507531) (xy 117.74909 -153.527063) (xy 117.673648 -153.54015)
			(xy 117.597359 -153.546695) (xy 117.559074 -153.547064) (xy 117.518861 -153.546626) (xy 117.438762 -153.539389)
			(xy 117.359641 -153.524958) (xy 117.282145 -153.50345) (xy 117.244368 -153.48966) (xy 117.235581 -153.486753)
			(xy 117.217087 -153.486753) (xy 117.2083 -153.48966) (xy 117.170525 -153.503458) (xy 117.093031 -153.52498)
			(xy 117.01391 -153.539411) (xy 116.933808 -153.546633) (xy 116.893594 -153.547064) (xy 116.855311 -153.546662)
			(xy 116.779026 -153.540106) (xy 116.703585 -153.527025) (xy 116.629546 -153.507516) (xy 116.593366 -153.494994)
			(xy 116.584929 -153.492343) (xy 116.567259 -153.492343) (xy 116.558822 -153.494994) (xy 116.522646 -153.507528)
			(xy 116.448609 -153.527053) (xy 116.373167 -153.540133) (xy 116.296878 -153.546671) (xy 116.258594 -153.547064)
			(xy 116.216927 -153.546577) (xy 116.133958 -153.538784) (xy 116.052081 -153.523266) (xy 115.972014 -153.500158)
			(xy 115.894459 -153.469665) (xy 115.820096 -153.432053) (xy 115.749575 -153.387651) (xy 115.683516 -153.33685)
			(xy 115.622497 -153.280093) (xy 115.567053 -153.217879) (xy 115.517671 -153.150753) (xy 115.495832 -153.115264)
			(xy 115.49102 -153.107923) (xy 115.477453 -153.096807) (xy 115.460916 -153.090963) (xy 115.452144 -153.090626)
			(xy 104.358948 -153.090626) (xy 104.348883 -153.091059) (xy 104.330294 -153.09879) (xy 104.32288 -153.105612)
			(xy 95.053404 -162.375088) (xy 95.035363 -162.392347) (xy 94.993869 -162.420101) (xy 94.947751 -162.43921)
			(xy 94.898787 -162.448934) (xy 94.873826 -162.44951) (xy 91.193112 -162.44951) (xy 91.18136 -162.450113)
			(xy 91.160316 -162.460582) (xy 91.152726 -162.469576) (xy 91.096592 -162.543998) (xy 91.09202 -162.567366)
			(xy 91.095576 -162.57905) (xy 91.106407 -162.618733) (xy 91.121551 -162.699592) (xy 91.129153 -162.781504)
			(xy 91.129612 -162.822636) (xy 91.129175 -162.860924) (xy 91.122548 -162.937213) (xy 91.109399 -163.012652)
			(xy 91.089824 -163.086684) (xy 91.077288 -163.122864) (xy 91.076093 -163.126674) (xy 119.365268 -163.126674)
			(xy 119.365838 -163.081905) (xy 119.374847 -162.99282) (xy 119.392749 -162.905089) (xy 119.419366 -162.819597)
			(xy 119.436388 -162.778186) (xy 119.43997 -162.7686) (xy 119.43996 -162.748153) (xy 119.436388 -162.738562)
			(xy 119.41934 -162.69716) (xy 119.392709 -162.61167) (xy 119.374808 -162.523935) (xy 119.365818 -162.434845)
			(xy 119.365268 -162.390074) (xy 119.365838 -162.345305) (xy 119.374847 -162.25622) (xy 119.392749 -162.168489)
			(xy 119.419366 -162.082997) (xy 119.436388 -162.041586) (xy 119.43997 -162.032) (xy 119.43996 -162.011553)
			(xy 119.436388 -162.001962) (xy 119.41934 -161.96056) (xy 119.392709 -161.87507) (xy 119.374808 -161.787335)
			(xy 119.365818 -161.698245) (xy 119.365268 -161.653474) (xy 119.365674 -161.612358) (xy 119.373264 -161.530476)
			(xy 119.388376 -161.449645) (xy 119.410882 -161.370552) (xy 119.440591 -161.293873) (xy 119.477247 -161.220263)
			(xy 119.520539 -161.150349) (xy 119.570097 -161.084728) (xy 119.625499 -161.023959) (xy 119.686271 -160.968561)
			(xy 119.751895 -160.919007) (xy 119.821812 -160.87572) (xy 119.895425 -160.839068) (xy 119.972105 -160.809365)
			(xy 120.051199 -160.786863) (xy 120.132032 -160.771756) (xy 120.213914 -160.764171) (xy 120.25503 -160.763712)
			(xy 120.296646 -160.764225) (xy 120.379509 -160.772042) (xy 120.461282 -160.787558) (xy 120.54125 -160.810638)
			(xy 120.618714 -160.84108) (xy 120.693 -160.878619) (xy 120.728486 -160.900364) (xy 120.737599 -160.905467)
			(xy 120.758243 -160.908514) (xy 120.778407 -160.903135) (xy 120.786906 -160.897062) (xy 120.820569 -160.871087)
			(xy 120.891995 -160.824949) (xy 120.967499 -160.785839) (xy 121.046391 -160.754113) (xy 121.127951 -160.730062)
			(xy 121.211434 -160.713905) (xy 121.296078 -160.705788) (xy 121.338594 -160.705292) (xy 121.379707 -160.705819)
			(xy 121.461582 -160.713405) (xy 121.542407 -160.728513) (xy 121.621494 -160.751013) (xy 121.698168 -160.780715)
			(xy 121.771774 -160.817365) (xy 121.841684 -160.86065) (xy 121.907303 -160.9102) (xy 121.96807 -160.965593)
			(xy 122.023467 -161.026357) (xy 122.073021 -161.091973) (xy 122.11631 -161.161881) (xy 122.152964 -161.235485)
			(xy 122.18267 -161.312156) (xy 122.205176 -161.391242) (xy 122.220288 -161.472067) (xy 122.227879 -161.553941)
			(xy 122.228356 -161.595054) (xy 122.227793 -161.639824) (xy 122.218783 -161.728909) (xy 122.200877 -161.81664)
			(xy 122.174259 -161.902131) (xy 122.157236 -161.943542) (xy 122.153699 -161.953141) (xy 122.153682 -161.973576)
			(xy 122.157236 -161.983166) (xy 122.173031 -162.021471) (xy 122.198241 -162.100407) (xy 122.215997 -162.181345)
			(xy 122.226146 -162.263585) (xy 122.227848 -162.304984) (xy 122.228707 -162.315902) (xy 122.238347 -162.335541)
			(xy 122.255257 -162.349422) (xy 122.265694 -162.352736) (xy 122.282566 -162.357234) (xy 122.315977 -162.367397)
			(xy 122.332496 -162.373056) (xy 122.340692 -162.375579) (xy 122.357828 -162.375579) (xy 122.366024 -162.373056)
			(xy 122.40124 -162.361095) (xy 122.473244 -162.342441) (xy 122.546565 -162.329932) (xy 122.62068 -162.323659)
			(xy 122.65787 -162.323272) (xy 122.695059 -162.323671) (xy 122.769172 -162.329958) (xy 122.842492 -162.342465)
			(xy 122.914498 -162.361103) (xy 122.949716 -162.373056) (xy 122.957912 -162.375579) (xy 122.975048 -162.375579)
			(xy 122.983244 -162.373056) (xy 123.018459 -162.361089) (xy 123.090462 -162.342437) (xy 123.163784 -162.32993)
			(xy 123.2379 -162.323658) (xy 123.27509 -162.323272) (xy 123.31703 -162.323667) (xy 123.400532 -162.331639)
			(xy 123.482897 -162.347513) (xy 123.56338 -162.371144) (xy 123.641253 -162.402319) (xy 123.71581 -162.440755)
			(xy 123.786375 -162.486104) (xy 123.85231 -162.537955) (xy 123.913018 -162.595839) (xy 123.967949 -162.659232)
			(xy 124.016605 -162.727559) (xy 124.058546 -162.800202) (xy 124.093391 -162.876503) (xy 124.120826 -162.95577)
			(xy 124.140602 -163.037287) (xy 124.15254 -163.120314) (xy 124.156531 -163.2041) (xy 124.15254 -163.287886)
			(xy 124.140602 -163.370913) (xy 124.120826 -163.45243) (xy 124.093391 -163.531697) (xy 124.058546 -163.607998)
			(xy 124.016605 -163.680641) (xy 123.967949 -163.748968) (xy 123.913018 -163.812361) (xy 123.85231 -163.870245)
			(xy 123.786375 -163.922096) (xy 123.71581 -163.967445) (xy 123.641253 -164.005881) (xy 123.56338 -164.037056)
			(xy 123.482897 -164.060687) (xy 123.400532 -164.076561) (xy 123.31703 -164.084533) (xy 123.27509 -164.085016)
			(xy 123.2379 -164.084629) (xy 123.163787 -164.078339) (xy 123.090468 -164.065828) (xy 123.018462 -164.047187)
			(xy 122.983244 -164.035232) (xy 122.975048 -164.032709) (xy 122.957912 -164.032709) (xy 122.949716 -164.035232)
			(xy 122.907233 -164.049509) (xy 122.820068 -164.070379) (xy 122.775726 -164.076888) (xy 122.765804 -164.078672)
			(xy 122.748385 -164.088778) (xy 122.736231 -164.104835) (xy 122.733308 -164.11448) (xy 122.724748 -164.14638)
			(xy 122.70352 -164.20893) (xy 122.69089 -164.239448) (xy 122.687347 -164.249045) (xy 122.687332 -164.269482)
			(xy 122.69089 -164.279072) (xy 122.707886 -164.320487) (xy 122.734444 -164.405985) (xy 122.752283 -164.493717)
			(xy 122.761225 -164.582796) (xy 122.761756 -164.62756) (xy 122.761252 -164.669908) (xy 122.753201 -164.754222)
			(xy 122.737172 -164.837388) (xy 122.713311 -164.918655) (xy 122.681832 -164.997285) (xy 122.643021 -165.072566)
			(xy 122.597231 -165.143818) (xy 122.544875 -165.210394) (xy 122.486427 -165.271692) (xy 122.422417 -165.327157)
			(xy 122.353425 -165.376286) (xy 122.280075 -165.418635) (xy 122.203032 -165.453819) (xy 122.122993 -165.481521)
			(xy 122.040684 -165.501489) (xy 121.956849 -165.513542) (xy 121.872248 -165.517573) (xy 121.787647 -165.513542)
			(xy 121.703812 -165.501489) (xy 121.621503 -165.481521) (xy 121.541464 -165.453819) (xy 121.464421 -165.418635)
			(xy 121.391071 -165.376286) (xy 121.322079 -165.327157) (xy 121.258069 -165.271692) (xy 121.199621 -165.210394)
			(xy 121.147265 -165.143818) (xy 121.101475 -165.072566) (xy 121.062664 -164.997285) (xy 121.031185 -164.918655)
			(xy 121.007324 -164.837388) (xy 120.991295 -164.754222) (xy 120.983244 -164.669908) (xy 120.98274 -164.62756)
			(xy 120.983256 -164.582795) (xy 120.992189 -164.493713) (xy 121.010032 -164.40598) (xy 121.036603 -164.320485)
			(xy 121.053606 -164.279072) (xy 121.057195 -164.269488) (xy 121.057181 -164.249039) (xy 121.053606 -164.239448)
			(xy 121.036797 -164.198471) (xy 121.010427 -164.113914) (xy 120.992588 -164.027156) (xy 120.983456 -163.939054)
			(xy 120.98274 -163.89477) (xy 120.982486 -163.880038) (xy 120.966992 -163.8554) (xy 120.857264 -163.803584)
			(xy 120.828308 -163.80714) (xy 120.816878 -163.816538) (xy 120.782853 -163.843559) (xy 120.710459 -163.891613)
			(xy 120.633724 -163.93238) (xy 120.55338 -163.965469) (xy 120.470192 -163.990568) (xy 120.384953 -164.007435)
			(xy 120.298476 -164.01591) (xy 120.25503 -164.016436) (xy 120.213915 -164.015973) (xy 120.132035 -164.008388)
			(xy 120.051204 -163.99328) (xy 119.972113 -163.970779) (xy 119.895435 -163.941075) (xy 119.821825 -163.904423)
			(xy 119.751911 -163.861135) (xy 119.686289 -163.811581) (xy 119.62552 -163.756183) (xy 119.570122 -163.695414)
			(xy 119.520567 -163.629793) (xy 119.477279 -163.559879) (xy 119.440626 -163.486269) (xy 119.410922 -163.409591)
			(xy 119.38842 -163.330499) (xy 119.373312 -163.249669) (xy 119.365727 -163.167789) (xy 119.365268 -163.126674)
			(xy 91.076093 -163.126674) (xy 91.074642 -163.1313) (xy 91.074654 -163.148967) (xy 91.077288 -163.157408)
			(xy 91.089855 -163.193579) (xy 91.109446 -163.26761) (xy 91.122593 -163.343052) (xy 91.129198 -163.419346)
			(xy 91.129612 -163.457636) (xy 91.12909 -163.500411) (xy 91.120858 -163.585564) (xy 91.104502 -163.669536)
			(xy 91.080173 -163.751554) (xy 91.064588 -163.791392) (xy 91.061593 -163.799863) (xy 91.061076 -163.817812)
			(xy 91.063572 -163.826444) (xy 91.078073 -163.87193) (xy 91.098402 -163.965215) (xy 91.108643 -164.060139)
			(xy 91.109292 -164.107876) (xy 91.108833 -164.148987) (xy 91.101247 -164.230859) (xy 91.086137 -164.31168)
			(xy 91.063634 -164.390763) (xy 91.033928 -164.467431) (xy 90.997273 -164.541031) (xy 90.953982 -164.610934)
			(xy 90.904425 -164.676543) (xy 90.849025 -164.737299) (xy 90.788254 -164.792683) (xy 90.722631 -164.842222)
			(xy 90.652716 -164.885493) (xy 90.579106 -164.922127) (xy 90.50243 -164.951812) (xy 90.423341 -164.974294)
			(xy 90.342515 -164.989381) (xy 90.260641 -164.996944) (xy 90.21953 -164.997384) (xy 90.177919 -164.996915)
			(xy 90.09506 -164.989168) (xy 90.013287 -164.97371) (xy 89.933317 -164.950678) (xy 89.89441 -164.935916)
			(xy 89.885722 -164.932924) (xy 89.867362 -164.932655) (xy 89.858596 -164.935408) (xy 89.822502 -164.947871)
			(xy 89.748649 -164.967302) (xy 89.673401 -164.980325) (xy 89.597313 -164.986844) (xy 89.55913 -164.987224)
			(xy 89.520847 -164.986819) (xy 89.444563 -164.980258) (xy 89.369124 -164.967173) (xy 89.295087 -164.94766)
			(xy 89.258902 -164.935154) (xy 89.250465 -164.932503) (xy 89.232795 -164.932503) (xy 89.224358 -164.935154)
			(xy 89.188182 -164.94769) (xy 89.114146 -164.967219) (xy 89.038703 -164.980303) (xy 88.962415 -164.986844)
			(xy 88.92413 -164.987224) (xy 88.885847 -164.986819) (xy 88.809563 -164.980258) (xy 88.734124 -164.967173)
			(xy 88.660087 -164.94766) (xy 88.623902 -164.935154) (xy 88.615465 -164.932503) (xy 88.597795 -164.932503)
			(xy 88.589358 -164.935154) (xy 88.553182 -164.94769) (xy 88.479146 -164.967219) (xy 88.403703 -164.980303)
			(xy 88.327415 -164.986844) (xy 88.28913 -164.987224) (xy 88.250847 -164.986819) (xy 88.174563 -164.980258)
			(xy 88.099124 -164.967173) (xy 88.025087 -164.94766) (xy 87.988902 -164.935154) (xy 87.980465 -164.932503)
			(xy 87.962795 -164.932503) (xy 87.954358 -164.935154) (xy 87.918182 -164.94769) (xy 87.844146 -164.967219)
			(xy 87.768703 -164.980303) (xy 87.692415 -164.986844) (xy 87.65413 -164.987224) (xy 87.615847 -164.986819)
			(xy 87.539563 -164.980258) (xy 87.464124 -164.967173) (xy 87.390087 -164.94766) (xy 87.353902 -164.935154)
			(xy 87.345465 -164.932503) (xy 87.327795 -164.932503) (xy 87.319358 -164.935154) (xy 87.283182 -164.94769)
			(xy 87.209146 -164.967219) (xy 87.133703 -164.980303) (xy 87.057415 -164.986844) (xy 87.01913 -164.987224)
			(xy 86.978023 -164.986751) (xy 86.896159 -164.979169) (xy 86.815344 -164.964067) (xy 86.736267 -164.941573)
			(xy 86.659602 -164.911881) (xy 86.586004 -164.875242) (xy 86.5161 -164.831969) (xy 86.450485 -164.782432)
			(xy 86.389721 -164.727053) (xy 86.334325 -164.666304) (xy 86.28477 -164.600703) (xy 86.241478 -164.530811)
			(xy 86.204819 -164.457223) (xy 86.175105 -164.380566) (xy 86.15259 -164.301495) (xy 86.137465 -164.220684)
			(xy 86.129861 -164.138823) (xy 86.129368 -164.097716) (xy 86.129892 -164.054942) (xy 86.138129 -163.96979)
			(xy 86.154491 -163.88582) (xy 86.178826 -163.803805) (xy 86.194392 -163.76396) (xy 86.197397 -163.755489)
			(xy 86.197931 -163.737534) (xy 86.195408 -163.728908) (xy 86.180904 -163.683423) (xy 86.160567 -163.590138)
			(xy 86.15032 -163.495214) (xy 86.149688 -163.447476) (xy 86.150124 -163.409188) (xy 86.15675 -163.332899)
			(xy 86.169899 -163.25746) (xy 86.189473 -163.183427) (xy 86.202012 -163.147248) (xy 86.20466 -163.138812)
			(xy 86.204652 -163.121143) (xy 86.202012 -163.112704) (xy 86.189445 -163.076533) (xy 86.169852 -163.002502)
			(xy 86.156704 -162.92706) (xy 86.150098 -162.850766) (xy 86.149688 -162.812476) (xy 86.15012 -162.772885)
			(xy 86.157152 -162.694016) (xy 86.171157 -162.616082) (xy 86.181184 -162.57778) (xy 86.184486 -162.56635)
			(xy 86.179914 -162.543236) (xy 86.12378 -162.469576) (xy 86.116189 -162.460584) (xy 86.095145 -162.450113)
			(xy 86.083394 -162.44951) (xy 60.724796 -162.44951) (xy 60.714726 -162.449934) (xy 60.696124 -162.457651)
			(xy 60.688728 -162.464496) (xy 60.395866 -162.757358) (xy 60.389021 -162.764756) (xy 60.381298 -162.783355)
			(xy 60.38088 -162.793426) (xy 60.38088 -166.86276) (xy 61.046868 -166.86276) (xy 61.047433 -166.81799)
			(xy 61.056443 -166.728905) (xy 61.074347 -166.641174) (xy 61.100966 -166.555683) (xy 61.117988 -166.514272)
			(xy 61.121578 -166.504688) (xy 61.121563 -166.484239) (xy 61.117988 -166.474648) (xy 61.100968 -166.433235)
			(xy 61.074329 -166.347749) (xy 61.05642 -166.260018) (xy 61.047422 -166.17093) (xy 61.046868 -166.12616)
			(xy 61.047433 -166.08139) (xy 61.056443 -165.992305) (xy 61.074347 -165.904574) (xy 61.100966 -165.819083)
			(xy 61.117988 -165.777672) (xy 61.121578 -165.768088) (xy 61.121563 -165.747639) (xy 61.117988 -165.738048)
			(xy 61.100968 -165.696635) (xy 61.074329 -165.611149) (xy 61.05642 -165.523418) (xy 61.047422 -165.43433)
			(xy 61.046868 -165.38956) (xy 61.047314 -165.348449) (xy 61.054905 -165.266579) (xy 61.070019 -165.185759)
			(xy 61.092527 -165.106679) (xy 61.122236 -165.030013) (xy 61.158893 -164.956415) (xy 61.202185 -164.886514)
			(xy 61.251743 -164.820907) (xy 61.307144 -164.760153) (xy 61.367915 -164.70477) (xy 61.433537 -164.655232)
			(xy 61.503451 -164.611961) (xy 61.57706 -164.575327) (xy 61.653735 -164.545641) (xy 61.732822 -164.523157)
			(xy 61.813647 -164.508068) (xy 61.895519 -164.500502) (xy 61.93663 -164.500052) (xy 61.978242 -164.500538)
			(xy 62.061103 -164.508284) (xy 62.142878 -164.523742) (xy 62.222849 -164.546778) (xy 62.300317 -164.57719)
			(xy 62.374602 -164.61471) (xy 62.410086 -164.63645) (xy 62.419198 -164.641555) (xy 62.439843 -164.644603)
			(xy 62.460007 -164.639223) (xy 62.468506 -164.633148) (xy 62.502177 -164.607195) (xy 62.573617 -164.561104)
			(xy 62.649129 -164.522038) (xy 62.728022 -164.490352) (xy 62.809578 -164.466336) (xy 62.893052 -164.450209)
			(xy 62.977685 -164.442118) (xy 63.020194 -164.441632) (xy 63.0613 -164.442118) (xy 63.143163 -164.449702)
			(xy 63.223977 -164.464805) (xy 63.303052 -164.487299) (xy 63.379716 -164.516993) (xy 63.453313 -164.553631)
			(xy 63.523217 -164.596903) (xy 63.58883 -164.64644) (xy 63.649594 -164.701818) (xy 63.70499 -164.762565)
			(xy 63.754546 -164.828164) (xy 63.797839 -164.898054) (xy 63.8345 -164.971641) (xy 63.864216 -165.048295)
			(xy 63.886734 -165.127364) (xy 63.901861 -165.208173) (xy 63.909469 -165.290034) (xy 63.909956 -165.33114)
			(xy 63.909389 -165.375909) (xy 63.900379 -165.464994) (xy 63.882475 -165.552725) (xy 63.855858 -165.638217)
			(xy 63.838836 -165.679628) (xy 63.83525 -165.689212) (xy 63.835264 -165.709661) (xy 63.838836 -165.719252)
			(xy 63.854627 -165.757559) (xy 63.879838 -165.836494) (xy 63.897595 -165.917432) (xy 63.903105 -165.962076)
			(xy 81.591411 -165.962076) (xy 81.595416 -165.856327) (xy 81.607406 -165.751184) (xy 81.627315 -165.647249)
			(xy 81.655026 -165.545117) (xy 81.690383 -165.445373) (xy 81.733181 -165.348589) (xy 81.783177 -165.255319)
			(xy 81.840084 -165.166098) (xy 81.903575 -165.081435) (xy 81.973287 -165.001817) (xy 82.048821 -164.927699)
			(xy 82.129744 -164.859506) (xy 82.215593 -164.797628) (xy 82.305876 -164.742421) (xy 82.400075 -164.694199)
			(xy 82.497652 -164.653239) (xy 82.598047 -164.619777) (xy 82.700685 -164.594003) (xy 82.804978 -164.576065)
			(xy 82.910329 -164.566066) (xy 83.016135 -164.564063) (xy 83.121789 -164.570068) (xy 83.226686 -164.584047)
			(xy 83.330226 -164.605918) (xy 83.431815 -164.635558) (xy 83.530872 -164.672796) (xy 83.626829 -164.717418)
			(xy 83.719136 -164.76917) (xy 83.807265 -164.827755) (xy 83.890711 -164.892837) (xy 83.968995 -164.964043)
			(xy 84.04167 -165.040966) (xy 84.10832 -165.123166) (xy 84.168562 -165.21017) (xy 84.222051 -165.301481)
			(xy 84.268482 -165.396576) (xy 84.307587 -165.49491) (xy 84.339144 -165.595921) (xy 84.362971 -165.699028)
			(xy 84.378932 -165.803642) (xy 84.386936 -165.909164) (xy 84.387436 -165.962076) (xy 90.989411 -165.962076)
			(xy 90.993416 -165.856327) (xy 91.005406 -165.751184) (xy 91.025315 -165.647249) (xy 91.053026 -165.545117)
			(xy 91.088383 -165.445373) (xy 91.131181 -165.348589) (xy 91.181177 -165.255319) (xy 91.238084 -165.166098)
			(xy 91.301575 -165.081435) (xy 91.371287 -165.001817) (xy 91.446821 -164.927699) (xy 91.527744 -164.859506)
			(xy 91.613593 -164.797628) (xy 91.703876 -164.742421) (xy 91.798075 -164.694199) (xy 91.895652 -164.653239)
			(xy 91.996047 -164.619777) (xy 92.098685 -164.594003) (xy 92.202978 -164.576065) (xy 92.308329 -164.566066)
			(xy 92.414135 -164.564063) (xy 92.519789 -164.570068) (xy 92.624686 -164.584047) (xy 92.728226 -164.605918)
			(xy 92.829815 -164.635558) (xy 92.928872 -164.672796) (xy 93.024829 -164.717418) (xy 93.117136 -164.76917)
			(xy 93.205265 -164.827755) (xy 93.288711 -164.892837) (xy 93.366995 -164.964043) (xy 93.43967 -165.040966)
			(xy 93.50632 -165.123166) (xy 93.566562 -165.21017) (xy 93.620051 -165.301481) (xy 93.666482 -165.396576)
			(xy 93.705587 -165.49491) (xy 93.737144 -165.595921) (xy 93.760971 -165.699028) (xy 93.776932 -165.803642)
			(xy 93.784936 -165.909164) (xy 93.785436 -165.962076) (xy 93.784936 -166.014988) (xy 93.776932 -166.12051)
			(xy 93.760971 -166.225124) (xy 93.737144 -166.328231) (xy 93.705587 -166.429242) (xy 93.666482 -166.527576)
			(xy 93.620051 -166.622671) (xy 93.566562 -166.713982) (xy 93.50632 -166.800986) (xy 93.43967 -166.883186)
			(xy 93.366995 -166.960109) (xy 93.288711 -167.031315) (xy 93.205265 -167.096397) (xy 93.117136 -167.154982)
			(xy 93.024829 -167.206734) (xy 92.928872 -167.251356) (xy 92.829815 -167.288594) (xy 92.728226 -167.318234)
			(xy 92.624686 -167.340105) (xy 92.519789 -167.354084) (xy 92.414135 -167.360089) (xy 92.308329 -167.358086)
			(xy 92.202978 -167.348087) (xy 92.098685 -167.330149) (xy 91.996047 -167.304375) (xy 91.895652 -167.270913)
			(xy 91.798075 -167.229953) (xy 91.703876 -167.181731) (xy 91.613593 -167.126524) (xy 91.527744 -167.064646)
			(xy 91.446821 -166.996453) (xy 91.371287 -166.922335) (xy 91.301575 -166.842717) (xy 91.238084 -166.758054)
			(xy 91.181177 -166.668833) (xy 91.131181 -166.575563) (xy 91.088383 -166.478779) (xy 91.053026 -166.379035)
			(xy 91.025315 -166.276903) (xy 91.005406 -166.172968) (xy 90.993416 -166.067825) (xy 90.989411 -165.962076)
			(xy 84.387436 -165.962076) (xy 84.386936 -166.014988) (xy 84.378932 -166.12051) (xy 84.362971 -166.225124)
			(xy 84.339144 -166.328231) (xy 84.307587 -166.429242) (xy 84.268482 -166.527576) (xy 84.222051 -166.622671)
			(xy 84.168562 -166.713982) (xy 84.10832 -166.800986) (xy 84.04167 -166.883186) (xy 83.968995 -166.960109)
			(xy 83.890711 -167.031315) (xy 83.807265 -167.096397) (xy 83.719136 -167.154982) (xy 83.626829 -167.206734)
			(xy 83.530872 -167.251356) (xy 83.431815 -167.288594) (xy 83.330226 -167.318234) (xy 83.226686 -167.340105)
			(xy 83.121789 -167.354084) (xy 83.016135 -167.360089) (xy 82.910329 -167.358086) (xy 82.804978 -167.348087)
			(xy 82.700685 -167.330149) (xy 82.598047 -167.304375) (xy 82.497652 -167.270913) (xy 82.400075 -167.229953)
			(xy 82.305876 -167.181731) (xy 82.215593 -167.126524) (xy 82.129744 -167.064646) (xy 82.048821 -166.996453)
			(xy 81.973287 -166.922335) (xy 81.903575 -166.842717) (xy 81.840084 -166.758054) (xy 81.783177 -166.668833)
			(xy 81.733181 -166.575563) (xy 81.690383 -166.478779) (xy 81.655026 -166.379035) (xy 81.627315 -166.276903)
			(xy 81.607406 -166.172968) (xy 81.595416 -166.067825) (xy 81.591411 -165.962076) (xy 63.903105 -165.962076)
			(xy 63.907745 -165.999671) (xy 63.909448 -166.04107) (xy 63.910317 -166.051987) (xy 63.919952 -166.071626)
			(xy 63.936858 -166.085508) (xy 63.947294 -166.088822) (xy 63.964166 -166.09332) (xy 63.997577 -166.103483)
			(xy 64.014096 -166.109142) (xy 64.022292 -166.111665) (xy 64.039428 -166.111665) (xy 64.047624 -166.109142)
			(xy 64.082842 -166.097202) (xy 64.154852 -166.078613) (xy 64.228174 -166.066171) (xy 64.302285 -166.059965)
			(xy 64.33947 -166.059612) (xy 64.376654 -166.059989) (xy 64.450761 -166.066209) (xy 64.524081 -166.078649)
			(xy 64.596093 -166.097221) (xy 64.631316 -166.109142) (xy 64.639512 -166.111665) (xy 64.656648 -166.111665)
			(xy 64.664844 -166.109142) (xy 64.70006 -166.097196) (xy 64.772071 -166.078609) (xy 64.845393 -166.066169)
			(xy 64.919504 -166.059964) (xy 64.95669 -166.059612) (xy 64.998618 -166.060035) (xy 65.082094 -166.068005)
			(xy 65.164434 -166.083874) (xy 65.244893 -166.107498) (xy 65.322742 -166.138663) (xy 65.397276 -166.177087)
			(xy 65.46782 -166.222422) (xy 65.533735 -166.274258) (xy 65.594424 -166.332124) (xy 65.649338 -166.395498)
			(xy 65.69798 -166.463804) (xy 65.739908 -166.536425) (xy 65.774743 -166.612703) (xy 65.802169 -166.691946)
			(xy 65.821939 -166.773438) (xy 65.833873 -166.85644) (xy 65.837863 -166.9402) (xy 65.833873 -167.02396)
			(xy 65.821939 -167.106962) (xy 65.802169 -167.188454) (xy 65.774743 -167.267697) (xy 65.739908 -167.343975)
			(xy 65.69798 -167.416596) (xy 65.649338 -167.484902) (xy 65.594424 -167.548276) (xy 65.533735 -167.606142)
			(xy 65.46782 -167.657978) (xy 65.397276 -167.703313) (xy 65.322742 -167.741737) (xy 65.244893 -167.772902)
			(xy 65.164434 -167.796526) (xy 65.082094 -167.812395) (xy 64.998618 -167.820365) (xy 64.95669 -167.820848)
			(xy 64.919506 -167.820485) (xy 64.845398 -167.814262) (xy 64.772078 -167.801817) (xy 64.700067 -167.783241)
			(xy 64.664844 -167.771318) (xy 64.656648 -167.768795) (xy 64.639512 -167.768795) (xy 64.631316 -167.771318)
			(xy 64.597889 -167.782662) (xy 64.529607 -167.80059) (xy 64.494918 -167.807132) (xy 64.484907 -167.809437)
			(xy 64.467748 -167.820693) (xy 64.456372 -167.837772) (xy 64.454024 -167.847772) (xy 64.44452 -167.895628)
			(xy 64.416383 -167.989057) (xy 64.39789 -168.034208) (xy 64.394312 -168.043795) (xy 64.39432 -168.064241)
			(xy 64.39789 -168.073832) (xy 64.414873 -168.115252) (xy 64.441434 -168.200748) (xy 64.459278 -168.288478)
			(xy 64.468224 -168.377557) (xy 64.468756 -168.42232) (xy 64.468252 -168.464668) (xy 64.460201 -168.548982)
			(xy 64.444172 -168.632148) (xy 64.420311 -168.713415) (xy 64.388832 -168.792045) (xy 64.350021 -168.867326)
			(xy 64.304231 -168.938578) (xy 64.251875 -169.005154) (xy 64.193427 -169.066452) (xy 64.129417 -169.121917)
			(xy 64.060425 -169.171046) (xy 63.987075 -169.213395) (xy 63.910032 -169.248579) (xy 63.829993 -169.276281)
			(xy 63.747684 -169.296249) (xy 63.663849 -169.308302) (xy 63.579248 -169.312333) (xy 63.494647 -169.308302)
			(xy 63.410812 -169.296249) (xy 63.328503 -169.276281) (xy 63.248464 -169.248579) (xy 63.171421 -169.213395)
			(xy 63.098071 -169.171046) (xy 63.029079 -169.121917) (xy 62.965069 -169.066452) (xy 62.906621 -169.005154)
			(xy 62.854265 -168.938578) (xy 62.808475 -168.867326) (xy 62.769664 -168.792045) (xy 62.738185 -168.713415)
			(xy 62.714324 -168.632148) (xy 62.698295 -168.548982) (xy 62.690244 -168.464668) (xy 62.68974 -168.42232)
			(xy 62.690277 -168.377556) (xy 62.699204 -168.288474) (xy 62.71704 -168.200741) (xy 62.743605 -168.115246)
			(xy 62.760606 -168.073832) (xy 62.764161 -168.064238) (xy 62.764168 -168.043798) (xy 62.760606 -168.034208)
			(xy 62.743603 -167.992795) (xy 62.717048 -167.907297) (xy 62.69921 -167.819564) (xy 62.69027 -167.730484)
			(xy 62.68974 -167.68572) (xy 62.689828 -167.668048) (xy 62.691224 -167.632732) (xy 62.692534 -167.615108)
			(xy 62.69355 -167.599614) (xy 62.678564 -167.57269) (xy 62.566296 -167.516556) (xy 62.535816 -167.52062)
			(xy 62.524132 -167.53078) (xy 62.493723 -167.556945) (xy 62.428954 -167.60429) (xy 62.360182 -167.645605)
			(xy 62.287967 -167.680556) (xy 62.212896 -167.708856) (xy 62.13558 -167.730277) (xy 62.056649 -167.744645)
			(xy 61.976744 -167.751841) (xy 61.93663 -167.752268) (xy 61.895524 -167.751759) (xy 61.813662 -167.744177)
			(xy 61.732849 -167.729076) (xy 61.653773 -167.706584) (xy 61.57711 -167.676893) (xy 61.503513 -167.640256)
			(xy 61.433609 -167.596985) (xy 61.367995 -167.547451) (xy 61.307231 -167.492074) (xy 61.251835 -167.431328)
			(xy 61.202279 -167.36573) (xy 61.158986 -167.295841) (xy 61.122325 -167.222256) (xy 61.092608 -167.145602)
			(xy 61.07009 -167.066534) (xy 61.054963 -166.985725) (xy 61.047355 -166.903866) (xy 61.046868 -166.86276)
			(xy 60.38088 -166.86276) (xy 60.38088 -169.857674) (xy 111.084868 -169.857674) (xy 111.085438 -169.812905)
			(xy 111.094447 -169.72382) (xy 111.112349 -169.636089) (xy 111.138966 -169.550597) (xy 111.155988 -169.509186)
			(xy 111.15957 -169.4996) (xy 111.15956 -169.479153) (xy 111.155988 -169.469562) (xy 111.13894 -169.42816)
			(xy 111.112309 -169.34267) (xy 111.094408 -169.254935) (xy 111.085418 -169.165845) (xy 111.084868 -169.121074)
			(xy 111.085438 -169.076305) (xy 111.094447 -168.98722) (xy 111.112349 -168.899489) (xy 111.138966 -168.813997)
			(xy 111.155988 -168.772586) (xy 111.15957 -168.763) (xy 111.15956 -168.742553) (xy 111.155988 -168.732962)
			(xy 111.13894 -168.69156) (xy 111.112309 -168.60607) (xy 111.094408 -168.518335) (xy 111.085418 -168.429245)
			(xy 111.084868 -168.384474) (xy 111.085274 -168.343358) (xy 111.092864 -168.261476) (xy 111.107976 -168.180645)
			(xy 111.130482 -168.101552) (xy 111.160191 -168.024873) (xy 111.196847 -167.951263) (xy 111.240139 -167.881349)
			(xy 111.289697 -167.815728) (xy 111.345099 -167.754959) (xy 111.405871 -167.699561) (xy 111.471495 -167.650007)
			(xy 111.541412 -167.60672) (xy 111.615025 -167.570068) (xy 111.691705 -167.540365) (xy 111.770799 -167.517863)
			(xy 111.851632 -167.502756) (xy 111.933514 -167.495171) (xy 111.97463 -167.494712) (xy 112.016246 -167.495225)
			(xy 112.099109 -167.503042) (xy 112.180882 -167.518558) (xy 112.26085 -167.541638) (xy 112.338314 -167.57208)
			(xy 112.4126 -167.609619) (xy 112.448086 -167.631364) (xy 112.457199 -167.636467) (xy 112.477843 -167.639514)
			(xy 112.498007 -167.634135) (xy 112.506506 -167.628062) (xy 112.540169 -167.602087) (xy 112.611595 -167.555949)
			(xy 112.687099 -167.516839) (xy 112.765991 -167.485113) (xy 112.847551 -167.461062) (xy 112.931034 -167.444905)
			(xy 113.015678 -167.436788) (xy 113.058194 -167.436292) (xy 113.099307 -167.436819) (xy 113.181182 -167.444405)
			(xy 113.262007 -167.459513) (xy 113.341094 -167.482013) (xy 113.417768 -167.511715) (xy 113.491374 -167.548365)
			(xy 113.561284 -167.59165) (xy 113.626903 -167.6412) (xy 113.68767 -167.696593) (xy 113.743067 -167.757357)
			(xy 113.792621 -167.822973) (xy 113.83591 -167.892881) (xy 113.872564 -167.966485) (xy 113.90227 -168.043156)
			(xy 113.924776 -168.122242) (xy 113.939888 -168.203067) (xy 113.947479 -168.284941) (xy 113.947956 -168.326054)
			(xy 113.947393 -168.370824) (xy 113.938383 -168.459909) (xy 113.920477 -168.54764) (xy 113.893859 -168.633131)
			(xy 113.876836 -168.674542) (xy 113.873299 -168.684141) (xy 113.873282 -168.704576) (xy 113.876836 -168.714166)
			(xy 113.892631 -168.752471) (xy 113.917841 -168.831407) (xy 113.935597 -168.912345) (xy 113.945746 -168.994585)
			(xy 113.947448 -169.035984) (xy 113.948307 -169.046902) (xy 113.957947 -169.066541) (xy 113.974857 -169.080422)
			(xy 113.985294 -169.083736) (xy 114.002166 -169.088234) (xy 114.035577 -169.098397) (xy 114.052096 -169.104056)
			(xy 114.060292 -169.106579) (xy 114.077428 -169.106579) (xy 114.085624 -169.104056) (xy 114.12084 -169.092095)
			(xy 114.192844 -169.073441) (xy 114.266165 -169.060932) (xy 114.34028 -169.054659) (xy 114.37747 -169.054272)
			(xy 114.414659 -169.054671) (xy 114.488772 -169.060958) (xy 114.562092 -169.073465) (xy 114.634098 -169.092103)
			(xy 114.669316 -169.104056) (xy 114.677512 -169.106579) (xy 114.694648 -169.106579) (xy 114.702844 -169.104056)
			(xy 114.738059 -169.092089) (xy 114.810062 -169.073437) (xy 114.883384 -169.06093) (xy 114.9575 -169.054658)
			(xy 114.99469 -169.054272) (xy 115.03663 -169.054667) (xy 115.120132 -169.062639) (xy 115.202497 -169.078513)
			(xy 115.28298 -169.102144) (xy 115.360853 -169.133319) (xy 115.43541 -169.171755) (xy 115.505975 -169.217104)
			(xy 115.57191 -169.268955) (xy 115.632618 -169.326839) (xy 115.687549 -169.390232) (xy 115.736205 -169.458559)
			(xy 115.778146 -169.531202) (xy 115.812991 -169.607503) (xy 115.840426 -169.68677) (xy 115.860202 -169.768287)
			(xy 115.87214 -169.851314) (xy 115.876131 -169.9351) (xy 115.87214 -170.018886) (xy 115.860202 -170.101913)
			(xy 115.840426 -170.18343) (xy 115.812991 -170.262697) (xy 115.778146 -170.338998) (xy 115.736205 -170.411641)
			(xy 115.687549 -170.479968) (xy 115.632618 -170.543361) (xy 115.57191 -170.601245) (xy 115.505975 -170.653096)
			(xy 115.43541 -170.698445) (xy 115.360853 -170.736881) (xy 115.28298 -170.768056) (xy 115.202497 -170.791687)
			(xy 115.120132 -170.807561) (xy 115.03663 -170.815533) (xy 114.99469 -170.816016) (xy 114.9575 -170.815629)
			(xy 114.883387 -170.809339) (xy 114.810068 -170.796828) (xy 114.738062 -170.778187) (xy 114.702844 -170.766232)
			(xy 114.694648 -170.763709) (xy 114.677512 -170.763709) (xy 114.669316 -170.766232) (xy 114.625188 -170.781068)
			(xy 114.534574 -170.80245) (xy 114.488468 -170.808904) (xy 114.478735 -170.810567) (xy 114.461516 -170.820188)
			(xy 114.449244 -170.83563) (xy 114.44605 -170.844972) (xy 114.43848 -170.870441) (xy 114.420685 -170.920512)
			(xy 114.41049 -170.945048) (xy 114.406947 -170.954645) (xy 114.406932 -170.975082) (xy 114.41049 -170.984672)
			(xy 114.427486 -171.026087) (xy 114.454044 -171.111585) (xy 114.471883 -171.199317) (xy 114.480825 -171.288396)
			(xy 114.481356 -171.33316) (xy 114.480852 -171.375508) (xy 114.472801 -171.459822) (xy 114.456772 -171.542988)
			(xy 114.432911 -171.624255) (xy 114.401432 -171.702885) (xy 114.362621 -171.778166) (xy 114.316831 -171.849418)
			(xy 114.264475 -171.915994) (xy 114.206027 -171.977292) (xy 114.142017 -172.032757) (xy 114.073025 -172.081886)
			(xy 113.999675 -172.124235) (xy 113.922632 -172.159419) (xy 113.842593 -172.187121) (xy 113.760284 -172.207089)
			(xy 113.676449 -172.219142) (xy 113.591848 -172.223173) (xy 113.507247 -172.219142) (xy 113.423412 -172.207089)
			(xy 113.341103 -172.187121) (xy 113.261064 -172.159419) (xy 113.184021 -172.124235) (xy 113.110671 -172.081886)
			(xy 113.041679 -172.032757) (xy 112.977669 -171.977292) (xy 112.919221 -171.915994) (xy 112.866865 -171.849418)
			(xy 112.821075 -171.778166) (xy 112.782264 -171.702885) (xy 112.750785 -171.624255) (xy 112.726924 -171.542988)
			(xy 112.710895 -171.459822) (xy 112.702844 -171.375508) (xy 112.70234 -171.33316) (xy 112.702856 -171.288395)
			(xy 112.711789 -171.199313) (xy 112.729632 -171.11158) (xy 112.756203 -171.026085) (xy 112.773206 -170.984672)
			(xy 112.776795 -170.975088) (xy 112.776781 -170.954639) (xy 112.773206 -170.945048) (xy 112.757425 -170.906703)
			(xy 112.7322 -170.827708) (xy 112.714437 -170.746708) (xy 112.704291 -170.664406) (xy 112.702594 -170.622976)
			(xy 112.702086 -170.608244) (xy 112.686084 -170.584114) (xy 112.576864 -170.53433) (xy 112.548162 -170.537886)
			(xy 112.536732 -170.54703) (xy 112.50272 -170.574115) (xy 112.430302 -170.622243) (xy 112.353537 -170.663082)
			(xy 112.273156 -170.696243) (xy 112.189925 -170.72141) (xy 112.104638 -170.738343) (xy 112.018106 -170.746881)
			(xy 111.97463 -170.747436) (xy 111.933515 -170.746973) (xy 111.851635 -170.739388) (xy 111.770804 -170.72428)
			(xy 111.691713 -170.701779) (xy 111.615035 -170.672075) (xy 111.541425 -170.635423) (xy 111.471511 -170.592135)
			(xy 111.405889 -170.542581) (xy 111.34512 -170.487183) (xy 111.289722 -170.426414) (xy 111.240167 -170.360793)
			(xy 111.196879 -170.290879) (xy 111.160226 -170.217269) (xy 111.130522 -170.140591) (xy 111.10802 -170.061499)
			(xy 111.092912 -169.980669) (xy 111.085327 -169.898789) (xy 111.084868 -169.857674) (xy 60.38088 -169.857674)
			(xy 60.38088 -175.559974) (xy 69.360288 -175.559974) (xy 69.360857 -175.515205) (xy 69.369865 -175.42612)
			(xy 69.387768 -175.338388) (xy 69.414386 -175.252897) (xy 69.431408 -175.211486) (xy 69.434989 -175.2019)
			(xy 69.43498 -175.181453) (xy 69.431408 -175.171862) (xy 69.414355 -175.130462) (xy 69.387726 -175.044971)
			(xy 69.369827 -174.957236) (xy 69.360838 -174.868145) (xy 69.360288 -174.823374) (xy 69.360857 -174.778605)
			(xy 69.369865 -174.68952) (xy 69.387768 -174.601788) (xy 69.414386 -174.516297) (xy 69.431408 -174.474886)
			(xy 69.434989 -174.4653) (xy 69.43498 -174.444853) (xy 69.431408 -174.435262) (xy 69.414355 -174.393862)
			(xy 69.387726 -174.308371) (xy 69.369827 -174.220636) (xy 69.360838 -174.131545) (xy 69.360288 -174.086774)
			(xy 69.360674 -174.045657) (xy 69.368264 -173.963775) (xy 69.383377 -173.882942) (xy 69.405884 -173.803848)
			(xy 69.435593 -173.727169) (xy 69.47225 -173.653557) (xy 69.515543 -173.583643) (xy 69.565103 -173.518021)
			(xy 69.620506 -173.457252) (xy 69.681279 -173.401854) (xy 69.746905 -173.3523) (xy 69.816824 -173.309013)
			(xy 69.890438 -173.272362) (xy 69.96712 -173.24266) (xy 70.046216 -173.220159) (xy 70.12705 -173.205053)
			(xy 70.208933 -173.19747) (xy 70.25005 -173.197012) (xy 70.291666 -173.197515) (xy 70.37453 -173.205334)
			(xy 70.456303 -173.220852) (xy 70.53627 -173.243934) (xy 70.613735 -173.274378) (xy 70.68802 -173.311918)
			(xy 70.723506 -173.333664) (xy 70.732652 -173.338697) (xy 70.753275 -173.341768) (xy 70.773427 -173.336419)
			(xy 70.781926 -173.330362) (xy 70.815582 -173.304378) (xy 70.88701 -173.258241) (xy 70.962515 -173.219132)
			(xy 71.041408 -173.187407) (xy 71.122969 -173.163358) (xy 71.206453 -173.147202) (xy 71.291098 -173.139088)
			(xy 71.333614 -173.138592) (xy 71.374727 -173.139099) (xy 71.456602 -173.146687) (xy 71.537428 -173.161797)
			(xy 71.616516 -173.1843) (xy 71.693189 -173.214003) (xy 71.766795 -173.250654) (xy 71.836706 -173.29394)
			(xy 71.902324 -173.343492) (xy 71.963091 -173.398886) (xy 72.018488 -173.459651) (xy 72.068042 -173.525268)
			(xy 72.11133 -173.595177) (xy 72.147984 -173.668781) (xy 72.17769 -173.745454) (xy 72.200196 -173.82454)
			(xy 72.215308 -173.905366) (xy 72.222899 -173.987241) (xy 72.223376 -174.028354) (xy 72.22282 -174.073124)
			(xy 72.213808 -174.162209) (xy 72.195901 -174.24994) (xy 72.16928 -174.335431) (xy 72.152256 -174.376842)
			(xy 72.148718 -174.38644) (xy 72.148701 -174.406876) (xy 72.152256 -174.416466) (xy 72.16811 -174.454985)
			(xy 72.19339 -174.53436) (xy 72.211148 -174.615749) (xy 72.221227 -174.69844) (xy 72.222868 -174.740062)
			(xy 72.223665 -174.750997) (xy 72.233294 -174.770671) (xy 72.250251 -174.784536) (xy 72.260714 -174.787814)
			(xy 72.277586 -174.792311) (xy 72.310997 -174.802475) (xy 72.327516 -174.808134) (xy 72.335712 -174.810657)
			(xy 72.352848 -174.810657) (xy 72.361044 -174.808134) (xy 72.39626 -174.796188) (xy 72.46827 -174.777601)
			(xy 72.541593 -174.765161) (xy 72.615704 -174.758956) (xy 72.65289 -174.758604) (xy 72.690074 -174.75897)
			(xy 72.764182 -174.765192) (xy 72.837502 -174.777635) (xy 72.909513 -174.796211) (xy 72.944736 -174.808134)
			(xy 72.952932 -174.810657) (xy 72.970068 -174.810657) (xy 72.978264 -174.808134) (xy 73.013487 -174.79621)
			(xy 73.085495 -174.777617) (xy 73.158815 -174.76517) (xy 73.232925 -174.758959) (xy 73.27011 -174.758604)
			(xy 73.312036 -174.759059) (xy 73.395508 -174.767031) (xy 73.477845 -174.7829) (xy 73.5583 -174.806525)
			(xy 73.636145 -174.83769) (xy 73.710676 -174.876114) (xy 73.781216 -174.921448) (xy 73.847128 -174.973283)
			(xy 73.907814 -175.031148) (xy 73.962725 -175.094519) (xy 74.011364 -175.162823) (xy 74.053289 -175.235441)
			(xy 74.088123 -175.311716) (xy 74.115548 -175.390956) (xy 74.135316 -175.472444) (xy 74.14725 -175.555443)
			(xy 74.15124 -175.6392) (xy 74.14725 -175.722957) (xy 74.135316 -175.805956) (xy 74.115548 -175.887444)
			(xy 74.088123 -175.966684) (xy 74.053289 -176.042959) (xy 74.01685 -176.106074) (xy 102.855268 -176.106074)
			(xy 102.855838 -176.061305) (xy 102.864847 -175.97222) (xy 102.882749 -175.884489) (xy 102.909366 -175.798997)
			(xy 102.926388 -175.757586) (xy 102.92997 -175.748) (xy 102.92996 -175.727553) (xy 102.926388 -175.717962)
			(xy 102.90934 -175.67656) (xy 102.882709 -175.59107) (xy 102.864808 -175.503335) (xy 102.855818 -175.414245)
			(xy 102.855268 -175.369474) (xy 102.855838 -175.324705) (xy 102.864847 -175.23562) (xy 102.882749 -175.147889)
			(xy 102.909366 -175.062397) (xy 102.926388 -175.020986) (xy 102.92997 -175.0114) (xy 102.92996 -174.990953)
			(xy 102.926388 -174.981362) (xy 102.90934 -174.93996) (xy 102.882709 -174.85447) (xy 102.864808 -174.766735)
			(xy 102.855818 -174.677645) (xy 102.855268 -174.632874) (xy 102.855674 -174.591758) (xy 102.863264 -174.509876)
			(xy 102.878376 -174.429045) (xy 102.900882 -174.349952) (xy 102.930591 -174.273273) (xy 102.967247 -174.199663)
			(xy 103.010539 -174.129749) (xy 103.060097 -174.064128) (xy 103.115499 -174.003359) (xy 103.176271 -173.947961)
			(xy 103.241895 -173.898407) (xy 103.311812 -173.85512) (xy 103.385425 -173.818468) (xy 103.462105 -173.788765)
			(xy 103.541199 -173.766263) (xy 103.622032 -173.751156) (xy 103.703914 -173.743571) (xy 103.74503 -173.743112)
			(xy 103.786646 -173.743625) (xy 103.869509 -173.751442) (xy 103.951282 -173.766958) (xy 104.03125 -173.790038)
			(xy 104.108714 -173.82048) (xy 104.183 -173.858019) (xy 104.218486 -173.879764) (xy 104.227599 -173.884867)
			(xy 104.248243 -173.887914) (xy 104.268407 -173.882535) (xy 104.276906 -173.876462) (xy 104.310569 -173.850487)
			(xy 104.381995 -173.804349) (xy 104.457499 -173.765239) (xy 104.536391 -173.733513) (xy 104.617951 -173.709462)
			(xy 104.701434 -173.693305) (xy 104.786078 -173.685188) (xy 104.828594 -173.684692) (xy 104.869707 -173.685219)
			(xy 104.951582 -173.692805) (xy 105.032407 -173.707913) (xy 105.111494 -173.730413) (xy 105.188168 -173.760115)
			(xy 105.261774 -173.796765) (xy 105.331684 -173.84005) (xy 105.397303 -173.8896) (xy 105.45807 -173.944993)
			(xy 105.513467 -174.005757) (xy 105.563021 -174.071373) (xy 105.60631 -174.141281) (xy 105.642964 -174.214885)
			(xy 105.67267 -174.291556) (xy 105.695176 -174.370642) (xy 105.710288 -174.451467) (xy 105.717879 -174.533341)
			(xy 105.718356 -174.574454) (xy 105.717793 -174.619224) (xy 105.708783 -174.708309) (xy 105.690877 -174.79604)
			(xy 105.664259 -174.881531) (xy 105.647236 -174.922942) (xy 105.643699 -174.932541) (xy 105.643682 -174.952976)
			(xy 105.647236 -174.962566) (xy 105.663031 -175.000871) (xy 105.688241 -175.079807) (xy 105.705997 -175.160745)
			(xy 105.716146 -175.242985) (xy 105.717848 -175.284384) (xy 105.718707 -175.295302) (xy 105.728347 -175.314941)
			(xy 105.745257 -175.328822) (xy 105.755694 -175.332136) (xy 105.772566 -175.336634) (xy 105.805977 -175.346797)
			(xy 105.822496 -175.352456) (xy 105.830692 -175.354979) (xy 105.847828 -175.354979) (xy 105.856024 -175.352456)
			(xy 105.89124 -175.340495) (xy 105.963244 -175.321841) (xy 106.036565 -175.309332) (xy 106.11068 -175.303059)
			(xy 106.14787 -175.302672) (xy 106.185059 -175.303071) (xy 106.259172 -175.309358) (xy 106.332492 -175.321865)
			(xy 106.404498 -175.340503) (xy 106.439716 -175.352456) (xy 106.447912 -175.354979) (xy 106.465048 -175.354979)
			(xy 106.473244 -175.352456) (xy 106.508459 -175.340489) (xy 106.580462 -175.321837) (xy 106.653784 -175.30933)
			(xy 106.7279 -175.303058) (xy 106.76509 -175.302672) (xy 106.80703 -175.303067) (xy 106.890532 -175.311039)
			(xy 106.972897 -175.326913) (xy 107.05338 -175.350544) (xy 107.131253 -175.381719) (xy 107.20581 -175.420155)
			(xy 107.276375 -175.465504) (xy 107.34231 -175.517355) (xy 107.403018 -175.575239) (xy 107.457949 -175.638632)
			(xy 107.506605 -175.706959) (xy 107.548546 -175.779602) (xy 107.583391 -175.855903) (xy 107.610826 -175.93517)
			(xy 107.630602 -176.016687) (xy 107.64254 -176.099714) (xy 107.646531 -176.1835) (xy 107.64254 -176.267286)
			(xy 107.630602 -176.350313) (xy 107.610826 -176.43183) (xy 107.583391 -176.511097) (xy 107.548546 -176.587398)
			(xy 107.506605 -176.660041) (xy 107.457949 -176.728368) (xy 107.403018 -176.791761) (xy 107.34231 -176.849645)
			(xy 107.276375 -176.901496) (xy 107.20581 -176.946845) (xy 107.131253 -176.985281) (xy 107.05338 -177.016456)
			(xy 106.972897 -177.040087) (xy 106.890532 -177.055961) (xy 106.80703 -177.063933) (xy 106.76509 -177.064416)
			(xy 106.7279 -177.064029) (xy 106.653787 -177.057739) (xy 106.580468 -177.045228) (xy 106.508462 -177.026587)
			(xy 106.473244 -177.014632) (xy 106.465048 -177.012109) (xy 106.447912 -177.012109) (xy 106.439716 -177.014632)
			(xy 106.394061 -177.029945) (xy 106.300252 -177.051713) (xy 106.252518 -177.058066) (xy 106.241993 -177.059881)
			(xy 106.223638 -177.070747) (xy 106.211256 -177.088115) (xy 106.208576 -177.098452) (xy 106.19911 -177.142342)
			(xy 106.172519 -177.228104) (xy 106.15549 -177.269648) (xy 106.151947 -177.279245) (xy 106.151932 -177.299682)
			(xy 106.15549 -177.309272) (xy 106.172486 -177.350687) (xy 106.199044 -177.436185) (xy 106.216883 -177.523917)
			(xy 106.225825 -177.612996) (xy 106.226356 -177.65776) (xy 106.225852 -177.700108) (xy 106.217801 -177.784422)
			(xy 106.201772 -177.867588) (xy 106.177911 -177.948855) (xy 106.146432 -178.027485) (xy 106.107621 -178.102766)
			(xy 106.061831 -178.174018) (xy 106.009475 -178.240594) (xy 105.951027 -178.301892) (xy 105.887017 -178.357357)
			(xy 105.818025 -178.406486) (xy 105.744675 -178.448835) (xy 105.667632 -178.484019) (xy 105.587593 -178.511721)
			(xy 105.505284 -178.531689) (xy 105.421449 -178.543742) (xy 105.336848 -178.547773) (xy 105.252247 -178.543742)
			(xy 105.168412 -178.531689) (xy 105.086103 -178.511721) (xy 105.006064 -178.484019) (xy 104.929021 -178.448835)
			(xy 104.855671 -178.406486) (xy 104.786679 -178.357357) (xy 104.722669 -178.301892) (xy 104.664221 -178.240594)
			(xy 104.611865 -178.174018) (xy 104.566075 -178.102766) (xy 104.527264 -178.027485) (xy 104.495785 -177.948855)
			(xy 104.471924 -177.867588) (xy 104.455895 -177.784422) (xy 104.447844 -177.700108) (xy 104.44734 -177.65776)
			(xy 104.447856 -177.612995) (xy 104.456789 -177.523913) (xy 104.474632 -177.43618) (xy 104.501203 -177.350685)
			(xy 104.518206 -177.309272) (xy 104.521795 -177.299688) (xy 104.521781 -177.279239) (xy 104.518206 -177.269648)
			(xy 104.501216 -177.22823) (xy 104.474657 -177.142734) (xy 104.456815 -177.055003) (xy 104.447871 -176.965924)
			(xy 104.44734 -176.92116) (xy 104.447594 -176.89703) (xy 104.447848 -176.882298) (xy 104.433116 -176.857152)
			(xy 104.325166 -176.802034) (xy 104.29621 -176.804574) (xy 104.284272 -176.813464) (xy 104.251077 -176.8382)
			(xy 104.180868 -176.882074) (xy 104.106889 -176.91924) (xy 104.029779 -176.949378) (xy 103.950204 -176.972227)
			(xy 103.868852 -176.98759) (xy 103.786425 -176.995334) (xy 103.74503 -176.995836) (xy 103.703915 -176.995373)
			(xy 103.622035 -176.987788) (xy 103.541204 -176.97268) (xy 103.462113 -176.950179) (xy 103.385435 -176.920475)
			(xy 103.311825 -176.883823) (xy 103.241911 -176.840535) (xy 103.176289 -176.790981) (xy 103.11552 -176.735583)
			(xy 103.060122 -176.674814) (xy 103.010567 -176.609193) (xy 102.967279 -176.539279) (xy 102.930626 -176.465669)
			(xy 102.900922 -176.388991) (xy 102.87842 -176.309899) (xy 102.863312 -176.229069) (xy 102.855727 -176.147189)
			(xy 102.855268 -176.106074) (xy 74.01685 -176.106074) (xy 74.011364 -176.115577) (xy 73.962725 -176.183881)
			(xy 73.907814 -176.247252) (xy 73.847128 -176.305117) (xy 73.781216 -176.356952) (xy 73.710676 -176.402286)
			(xy 73.636145 -176.44071) (xy 73.5583 -176.471875) (xy 73.477845 -176.4955) (xy 73.395508 -176.511369)
			(xy 73.312036 -176.519341) (xy 73.27011 -176.51984) (xy 73.232926 -176.519472) (xy 73.158818 -176.51325)
			(xy 73.085498 -176.500807) (xy 73.013487 -176.482233) (xy 72.978264 -176.47031) (xy 72.970068 -176.467787)
			(xy 72.952932 -176.467787) (xy 72.944736 -176.47031) (xy 72.910756 -176.481853) (xy 72.841327 -176.500034)
			(xy 72.806052 -176.506632) (xy 72.796131 -176.508844) (xy 72.77908 -176.519877) (xy 72.767627 -176.53665)
			(xy 72.765158 -176.54651) (xy 72.755653 -176.591261) (xy 72.728677 -176.678684) (xy 72.71131 -176.721008)
			(xy 72.707732 -176.730595) (xy 72.707739 -176.751042) (xy 72.71131 -176.760632) (xy 72.728294 -176.802052)
			(xy 72.754855 -176.887548) (xy 72.772698 -176.975278) (xy 72.781644 -177.064356) (xy 72.782176 -177.10912)
			(xy 72.781672 -177.151468) (xy 72.773621 -177.235782) (xy 72.757592 -177.318948) (xy 72.733731 -177.400215)
			(xy 72.702252 -177.478845) (xy 72.663441 -177.554126) (xy 72.617651 -177.625378) (xy 72.565295 -177.691954)
			(xy 72.506847 -177.753252) (xy 72.442837 -177.808717) (xy 72.373845 -177.857846) (xy 72.300495 -177.900195)
			(xy 72.223452 -177.935379) (xy 72.143413 -177.963081) (xy 72.061104 -177.983049) (xy 71.977269 -177.995102)
			(xy 71.892668 -177.999133) (xy 71.808067 -177.995102) (xy 71.724232 -177.983049) (xy 71.641923 -177.963081)
			(xy 71.561884 -177.935379) (xy 71.484841 -177.900195) (xy 71.411491 -177.857846) (xy 71.342499 -177.808717)
			(xy 71.278489 -177.753252) (xy 71.220041 -177.691954) (xy 71.167685 -177.625378) (xy 71.121895 -177.554126)
			(xy 71.083084 -177.478845) (xy 71.051605 -177.400215) (xy 71.027744 -177.318948) (xy 71.011715 -177.235782)
			(xy 71.003664 -177.151468) (xy 71.00316 -177.10912) (xy 71.003695 -177.064356) (xy 71.012623 -176.975274)
			(xy 71.030459 -176.887541) (xy 71.057025 -176.802046) (xy 71.074026 -176.760632) (xy 71.07758 -176.751038)
			(xy 71.077588 -176.730598) (xy 71.074026 -176.721008) (xy 71.057024 -176.679595) (xy 71.030468 -176.594097)
			(xy 71.01263 -176.506364) (xy 71.00369 -176.417284) (xy 71.00316 -176.37252) (xy 71.003216 -176.357395)
			(xy 71.004231 -176.327162) (xy 71.005192 -176.312068) (xy 71.006208 -176.296574) (xy 70.990714 -176.269904)
			(xy 70.878954 -176.214532) (xy 70.848474 -176.218596) (xy 70.83679 -176.228756) (xy 70.806403 -176.254854)
			(xy 70.741691 -176.302073) (xy 70.672994 -176.343279) (xy 70.60087 -176.378141) (xy 70.525902 -176.406374)
			(xy 70.4487 -176.427751) (xy 70.369887 -176.442098) (xy 70.290104 -176.449298) (xy 70.25005 -176.449736)
			(xy 70.208935 -176.449254) (xy 70.127056 -176.441671) (xy 70.046226 -176.426565) (xy 69.967134 -176.404065)
			(xy 69.890456 -176.374363) (xy 69.816846 -176.337712) (xy 69.746932 -176.294426) (xy 69.68131 -176.244873)
			(xy 69.620541 -176.189476) (xy 69.565143 -176.128708) (xy 69.515588 -176.063088) (xy 69.472299 -175.993175)
			(xy 69.435647 -175.919566) (xy 69.405943 -175.842889) (xy 69.383441 -175.763798) (xy 69.368332 -175.682968)
			(xy 69.360747 -175.601089) (xy 69.360288 -175.559974) (xy 60.38088 -175.559974) (xy 60.38088 -178.798474)
			(xy 77.963268 -178.798474) (xy 77.963886 -178.752072) (xy 77.973579 -178.659774) (xy 77.992835 -178.568989)
			(xy 78.021445 -178.480704) (xy 78.039722 -178.438048) (xy 78.043541 -178.42811) (xy 78.043531 -178.406843)
			(xy 78.039722 -178.3969) (xy 78.021451 -178.354243) (xy 77.99286 -178.265953) (xy 77.973605 -178.175169)
			(xy 77.963896 -178.082875) (xy 77.963268 -178.036474) (xy 77.963674 -177.995358) (xy 77.971264 -177.913476)
			(xy 77.986376 -177.832645) (xy 78.008882 -177.753552) (xy 78.038591 -177.676873) (xy 78.075247 -177.603263)
			(xy 78.118539 -177.533349) (xy 78.168097 -177.467728) (xy 78.223499 -177.406959) (xy 78.284271 -177.351561)
			(xy 78.349895 -177.302007) (xy 78.419812 -177.25872) (xy 78.493425 -177.222068) (xy 78.570105 -177.192365)
			(xy 78.649199 -177.169863) (xy 78.730032 -177.154756) (xy 78.811914 -177.147171) (xy 78.85303 -177.146712)
			(xy 78.893848 -177.147168) (xy 78.975141 -177.154659) (xy 79.055405 -177.169568) (xy 79.133966 -177.191768)
			(xy 79.210162 -177.221072) (xy 79.283352 -177.257234) (xy 79.352922 -177.29995) (xy 79.418285 -177.348861)
			(xy 79.478892 -177.403555) (xy 79.534233 -177.463571) (xy 79.559404 -177.495708) (xy 79.565179 -177.502627)
			(xy 79.580393 -177.512264) (xy 79.589122 -177.514504) (xy 79.631283 -177.524073) (xy 79.713687 -177.550242)
			(xy 79.793163 -177.584282) (xy 79.868962 -177.625872) (xy 79.940368 -177.67462) (xy 80.006708 -177.730066)
			(xy 80.067355 -177.791686) (xy 80.121738 -177.8589) (xy 80.169343 -177.931073) (xy 80.209721 -178.007525)
			(xy 80.242492 -178.087533) (xy 80.267345 -178.170343) (xy 80.284047 -178.255173) (xy 80.29244 -178.341224)
			(xy 80.292956 -178.384454) (xy 80.292754 -178.410999) (xy 80.289578 -178.463993) (xy 80.286606 -178.490372)
			(xy 80.28578 -178.501682) (xy 80.292922 -178.523179) (xy 80.300322 -178.531774) (xy 80.329261 -178.562798)
			(xy 80.381784 -178.629432) (xy 80.427728 -178.700761) (xy 80.466676 -178.776139) (xy 80.498274 -178.854881)
			(xy 80.522235 -178.936272) (xy 80.538342 -179.019574) (xy 80.546449 -179.104032) (xy 80.546956 -179.146454)
			(xy 80.546393 -179.191224) (xy 80.537383 -179.280309) (xy 80.519477 -179.36804) (xy 80.492859 -179.453531)
			(xy 80.475836 -179.494942) (xy 80.472299 -179.504541) (xy 80.472282 -179.524976) (xy 80.475836 -179.534566)
			(xy 80.491631 -179.572871) (xy 80.516841 -179.651807) (xy 80.534597 -179.732745) (xy 80.544746 -179.814985)
			(xy 80.546448 -179.856384) (xy 80.547307 -179.867302) (xy 80.556947 -179.886941) (xy 80.573857 -179.900822)
			(xy 80.584294 -179.904136) (xy 80.601166 -179.908634) (xy 80.634577 -179.918797) (xy 80.651096 -179.924456)
			(xy 80.659292 -179.926979) (xy 80.676428 -179.926979) (xy 80.684624 -179.924456) (xy 80.71984 -179.912495)
			(xy 80.791844 -179.893841) (xy 80.865165 -179.881332) (xy 80.93928 -179.875059) (xy 80.97647 -179.874672)
			(xy 81.013659 -179.875071) (xy 81.087772 -179.881358) (xy 81.161092 -179.893865) (xy 81.233098 -179.912503)
			(xy 81.268316 -179.924456) (xy 81.276512 -179.926979) (xy 81.293648 -179.926979) (xy 81.301844 -179.924456)
			(xy 81.337059 -179.912489) (xy 81.409062 -179.893837) (xy 81.482384 -179.88133) (xy 81.5565 -179.875058)
			(xy 81.59369 -179.874672) (xy 81.63563 -179.875067) (xy 81.719132 -179.883039) (xy 81.801497 -179.898913)
			(xy 81.88198 -179.922544) (xy 81.959853 -179.953719) (xy 82.03441 -179.992155) (xy 82.104975 -180.037504)
			(xy 82.17091 -180.089355) (xy 82.231618 -180.147239) (xy 82.286549 -180.210632) (xy 82.335205 -180.278959)
			(xy 82.377146 -180.351602) (xy 82.411991 -180.427903) (xy 82.439426 -180.50717) (xy 82.459202 -180.588687)
			(xy 82.462267 -180.610002) (xy 86.081108 -180.610002) (xy 86.081685 -180.565233) (xy 86.090691 -180.476148)
			(xy 86.108592 -180.388417) (xy 86.135207 -180.302925) (xy 86.152228 -180.261514) (xy 86.155792 -180.251923)
			(xy 86.155793 -180.231481) (xy 86.152228 -180.22189) (xy 86.135186 -180.180486) (xy 86.108554 -180.094996)
			(xy 86.090651 -180.007262) (xy 86.081659 -179.918173) (xy 86.081108 -179.873402) (xy 86.081685 -179.828633)
			(xy 86.090691 -179.739548) (xy 86.108592 -179.651817) (xy 86.135207 -179.566325) (xy 86.152228 -179.524914)
			(xy 86.155792 -179.515323) (xy 86.155793 -179.494881) (xy 86.152228 -179.48529) (xy 86.135186 -179.443886)
			(xy 86.108554 -179.358396) (xy 86.090651 -179.270662) (xy 86.081659 -179.181573) (xy 86.081108 -179.136802)
			(xy 86.081615 -179.095689) (xy 86.089201 -179.013813) (xy 86.10431 -178.932986) (xy 86.126812 -178.853898)
			(xy 86.156515 -178.777224) (xy 86.193165 -178.703617) (xy 86.236451 -178.633706) (xy 86.286003 -178.568087)
			(xy 86.341397 -178.50732) (xy 86.402163 -178.451923) (xy 86.46778 -178.402369) (xy 86.537689 -178.359081)
			(xy 86.611295 -178.322428) (xy 86.687968 -178.292722) (xy 86.767055 -178.270217) (xy 86.847881 -178.255106)
			(xy 86.929757 -178.247516) (xy 86.97087 -178.24704) (xy 87.012486 -178.247545) (xy 87.095349 -178.255365)
			(xy 87.177122 -178.270883) (xy 87.257089 -178.293965) (xy 87.334554 -178.324408) (xy 87.40884 -178.361947)
			(xy 87.444326 -178.383692) (xy 87.453465 -178.388739) (xy 87.474092 -178.391802) (xy 87.494246 -178.386449)
			(xy 87.502746 -178.38039) (xy 87.536398 -178.354401) (xy 87.607826 -178.308264) (xy 87.683332 -178.269155)
			(xy 87.762226 -178.237431) (xy 87.843788 -178.213382) (xy 87.927272 -178.197227) (xy 88.011917 -178.189115)
			(xy 88.054434 -178.18862) (xy 88.095548 -178.18908) (xy 88.177426 -178.19667) (xy 88.258254 -178.211782)
			(xy 88.337343 -178.234287) (xy 88.414018 -178.263994) (xy 88.487625 -178.300648) (xy 88.557536 -178.343937)
			(xy 88.623155 -178.393491) (xy 88.683922 -178.448889) (xy 88.739319 -178.509657) (xy 88.788872 -178.575277)
			(xy 88.83216 -178.645189) (xy 88.868813 -178.718797) (xy 88.898518 -178.795473) (xy 88.921021 -178.874562)
			(xy 88.936132 -178.95539) (xy 88.94372 -179.037268) (xy 88.944196 -179.078382) (xy 88.943648 -179.123152)
			(xy 88.934633 -179.212238) (xy 88.916724 -179.299969) (xy 88.890101 -179.38546) (xy 88.873076 -179.42687)
			(xy 88.869521 -179.436464) (xy 88.869514 -179.456904) (xy 88.873076 -179.466494) (xy 88.888852 -179.504807)
			(xy 88.914067 -179.58374) (xy 88.931828 -179.664676) (xy 88.941982 -179.746913) (xy 88.943688 -179.788312)
			(xy 88.944498 -179.799238) (xy 88.954157 -179.818882) (xy 88.971088 -179.832757) (xy 88.981534 -179.836064)
			(xy 88.998407 -179.840559) (xy 89.031817 -179.850724) (xy 89.048336 -179.856384) (xy 89.056532 -179.858907)
			(xy 89.073668 -179.858907) (xy 89.081864 -179.856384) (xy 89.117077 -179.844413) (xy 89.189082 -179.825761)
			(xy 89.262404 -179.813256) (xy 89.33652 -179.806985) (xy 89.37371 -179.8066) (xy 89.4109 -179.806986)
			(xy 89.485013 -179.813277) (xy 89.558333 -179.825787) (xy 89.630338 -179.844429) (xy 89.665556 -179.856384)
			(xy 89.673752 -179.858907) (xy 89.690888 -179.858907) (xy 89.699084 -179.856384) (xy 89.734295 -179.844408)
			(xy 89.8063 -179.825757) (xy 89.879623 -179.813253) (xy 89.953739 -179.806984) (xy 89.99093 -179.8066)
			(xy 90.032865 -179.807156) (xy 90.116355 -179.815131) (xy 90.198709 -179.831006) (xy 90.279182 -179.854637)
			(xy 90.357043 -179.885811) (xy 90.431589 -179.924244) (xy 90.502144 -179.969589) (xy 90.56807 -180.021436)
			(xy 90.628768 -180.079314) (xy 90.683691 -180.1427) (xy 90.732339 -180.211019) (xy 90.774274 -180.283653)
			(xy 90.809114 -180.359944) (xy 90.836544 -180.439202) (xy 90.856317 -180.520708) (xy 90.868253 -180.603725)
			(xy 90.869375 -180.627274) (xy 94.473268 -180.627274) (xy 94.473838 -180.582505) (xy 94.482847 -180.49342)
			(xy 94.500749 -180.405689) (xy 94.527366 -180.320197) (xy 94.544388 -180.278786) (xy 94.54797 -180.2692)
			(xy 94.54796 -180.248753) (xy 94.544388 -180.239162) (xy 94.52734 -180.19776) (xy 94.500709 -180.11227)
			(xy 94.482808 -180.024535) (xy 94.473818 -179.935445) (xy 94.473268 -179.890674) (xy 94.473838 -179.845905)
			(xy 94.482847 -179.75682) (xy 94.500749 -179.669089) (xy 94.527366 -179.583597) (xy 94.544388 -179.542186)
			(xy 94.54797 -179.5326) (xy 94.54796 -179.512153) (xy 94.544388 -179.502562) (xy 94.52734 -179.46116)
			(xy 94.500709 -179.37567) (xy 94.482808 -179.287935) (xy 94.473818 -179.198845) (xy 94.473268 -179.154074)
			(xy 94.473674 -179.112958) (xy 94.481264 -179.031076) (xy 94.496376 -178.950245) (xy 94.518882 -178.871152)
			(xy 94.548591 -178.794473) (xy 94.585247 -178.720863) (xy 94.628539 -178.650949) (xy 94.678097 -178.585328)
			(xy 94.733499 -178.524559) (xy 94.794271 -178.469161) (xy 94.859895 -178.419607) (xy 94.929812 -178.37632)
			(xy 95.003425 -178.339668) (xy 95.080105 -178.309965) (xy 95.159199 -178.287463) (xy 95.240032 -178.272356)
			(xy 95.321914 -178.264771) (xy 95.36303 -178.264312) (xy 95.404646 -178.264825) (xy 95.487509 -178.272642)
			(xy 95.569282 -178.288158) (xy 95.64925 -178.311238) (xy 95.726714 -178.34168) (xy 95.801 -178.379219)
			(xy 95.836486 -178.400964) (xy 95.845599 -178.406067) (xy 95.866243 -178.409114) (xy 95.886407 -178.403735)
			(xy 95.894906 -178.397662) (xy 95.928569 -178.371687) (xy 95.999995 -178.325549) (xy 96.075499 -178.286439)
			(xy 96.154391 -178.254713) (xy 96.235951 -178.230662) (xy 96.319434 -178.214505) (xy 96.404078 -178.206388)
			(xy 96.446594 -178.205892) (xy 96.487707 -178.206419) (xy 96.569582 -178.214005) (xy 96.650407 -178.229113)
			(xy 96.729494 -178.251613) (xy 96.806168 -178.281315) (xy 96.879774 -178.317965) (xy 96.949684 -178.36125)
			(xy 97.015303 -178.4108) (xy 97.07607 -178.466193) (xy 97.131467 -178.526957) (xy 97.181021 -178.592573)
			(xy 97.22431 -178.662481) (xy 97.260964 -178.736085) (xy 97.29067 -178.812756) (xy 97.313176 -178.891842)
			(xy 97.328288 -178.972667) (xy 97.335879 -179.054541) (xy 97.336356 -179.095654) (xy 97.335793 -179.140424)
			(xy 97.326783 -179.229509) (xy 97.308877 -179.31724) (xy 97.282259 -179.402731) (xy 97.265236 -179.444142)
			(xy 97.261699 -179.453741) (xy 97.261682 -179.474176) (xy 97.265236 -179.483766) (xy 97.281031 -179.522071)
			(xy 97.306241 -179.601007) (xy 97.323997 -179.681945) (xy 97.334146 -179.764185) (xy 97.335848 -179.805584)
			(xy 97.336707 -179.816502) (xy 97.346347 -179.836141) (xy 97.363257 -179.850022) (xy 97.373694 -179.853336)
			(xy 97.390566 -179.857834) (xy 97.423977 -179.867997) (xy 97.440496 -179.873656) (xy 97.448692 -179.876179)
			(xy 97.465828 -179.876179) (xy 97.474024 -179.873656) (xy 97.50924 -179.861695) (xy 97.581244 -179.843041)
			(xy 97.654565 -179.830532) (xy 97.72868 -179.824259) (xy 97.76587 -179.823872) (xy 97.803059 -179.824271)
			(xy 97.877172 -179.830558) (xy 97.950492 -179.843065) (xy 98.022498 -179.861703) (xy 98.057716 -179.873656)
			(xy 98.065912 -179.876179) (xy 98.083048 -179.876179) (xy 98.091244 -179.873656) (xy 98.126459 -179.861689)
			(xy 98.198462 -179.843037) (xy 98.271784 -179.83053) (xy 98.3459 -179.824258) (xy 98.38309 -179.823872)
			(xy 98.42503 -179.824267) (xy 98.508532 -179.832239) (xy 98.590897 -179.848113) (xy 98.67138 -179.871744)
			(xy 98.749253 -179.902919) (xy 98.82381 -179.941355) (xy 98.894375 -179.986704) (xy 98.96031 -180.038555)
			(xy 99.021018 -180.096439) (xy 99.075949 -180.159832) (xy 99.124605 -180.228159) (xy 99.166546 -180.300802)
			(xy 99.201391 -180.377103) (xy 99.228826 -180.45637) (xy 99.248602 -180.537887) (xy 99.26054 -180.620914)
			(xy 99.264531 -180.7047) (xy 99.26054 -180.788486) (xy 99.248602 -180.871513) (xy 99.228826 -180.95303)
			(xy 99.201391 -181.032297) (xy 99.166546 -181.108598) (xy 99.124605 -181.181241) (xy 99.075949 -181.249568)
			(xy 99.021018 -181.312961) (xy 98.96031 -181.370845) (xy 98.894375 -181.422696) (xy 98.82381 -181.468045)
			(xy 98.749253 -181.506481) (xy 98.67138 -181.537656) (xy 98.590897 -181.561287) (xy 98.508532 -181.577161)
			(xy 98.42503 -181.585133) (xy 98.38309 -181.585616) (xy 98.3459 -181.585229) (xy 98.271787 -181.578939)
			(xy 98.198468 -181.566428) (xy 98.126462 -181.547787) (xy 98.091244 -181.535832) (xy 98.083048 -181.533309)
			(xy 98.065912 -181.533309) (xy 98.057716 -181.535832) (xy 98.015541 -181.55005) (xy 97.929015 -181.570917)
			(xy 97.884996 -181.577488) (xy 97.875039 -181.579265) (xy 97.857602 -181.589479) (xy 97.845472 -181.605643)
			(xy 97.842578 -181.615334) (xy 97.833867 -181.648486) (xy 97.811997 -181.713456) (xy 97.79889 -181.745128)
			(xy 97.795301 -181.754712) (xy 97.795316 -181.775161) (xy 97.79889 -181.784752) (xy 97.81588 -181.82617)
			(xy 97.842439 -181.911666) (xy 97.860281 -181.999397) (xy 97.869225 -182.088476) (xy 97.869756 -182.13324)
			(xy 97.869252 -182.175588) (xy 97.861201 -182.259902) (xy 97.845172 -182.343068) (xy 97.821311 -182.424335)
			(xy 97.789832 -182.502965) (xy 97.751021 -182.578246) (xy 97.705231 -182.649498) (xy 97.652875 -182.716074)
			(xy 97.594427 -182.777372) (xy 97.530417 -182.832837) (xy 97.461425 -182.881966) (xy 97.388075 -182.924315)
			(xy 97.311032 -182.959499) (xy 97.230993 -182.987201) (xy 97.148684 -183.007169) (xy 97.064849 -183.019222)
			(xy 96.980248 -183.023253) (xy 96.895647 -183.019222) (xy 96.811812 -183.007169) (xy 96.729503 -182.987201)
			(xy 96.649464 -182.959499) (xy 96.572421 -182.924315) (xy 96.499071 -182.881966) (xy 96.430079 -182.832837)
			(xy 96.366069 -182.777372) (xy 96.307621 -182.716074) (xy 96.255265 -182.649498) (xy 96.209475 -182.578246)
			(xy 96.170664 -182.502965) (xy 96.139185 -182.424335) (xy 96.115324 -182.343068) (xy 96.099295 -182.259902)
			(xy 96.091244 -182.175588) (xy 96.09074 -182.13324) (xy 96.091249 -182.088475) (xy 96.100185 -181.999393)
			(xy 96.118029 -181.91166) (xy 96.144602 -181.826165) (xy 96.161606 -181.784752) (xy 96.165149 -181.775155)
			(xy 96.165164 -181.754718) (xy 96.161606 -181.745128) (xy 96.14461 -181.703713) (xy 96.118052 -181.618215)
			(xy 96.100212 -181.530483) (xy 96.09127 -181.441404) (xy 96.09074 -181.39664) (xy 96.09074 -181.381146)
			(xy 96.074992 -181.356254) (xy 95.965264 -181.304184) (xy 95.936308 -181.30774) (xy 95.924878 -181.317138)
			(xy 95.890853 -181.344159) (xy 95.818459 -181.392213) (xy 95.741724 -181.43298) (xy 95.66138 -181.466069)
			(xy 95.578192 -181.491168) (xy 95.492953 -181.508035) (xy 95.406476 -181.51651) (xy 95.36303 -181.517036)
			(xy 95.321915 -181.516573) (xy 95.240035 -181.508988) (xy 95.159204 -181.49388) (xy 95.080113 -181.471379)
			(xy 95.003435 -181.441675) (xy 94.929825 -181.405023) (xy 94.859911 -181.361735) (xy 94.794289 -181.312181)
			(xy 94.73352 -181.256783) (xy 94.678122 -181.196014) (xy 94.628567 -181.130393) (xy 94.585279 -181.060479)
			(xy 94.548626 -180.986869) (xy 94.518922 -180.910191) (xy 94.49642 -180.831099) (xy 94.481312 -180.750269)
			(xy 94.473727 -180.668389) (xy 94.473268 -180.627274) (xy 90.869375 -180.627274) (xy 90.872244 -180.6875)
			(xy 90.868253 -180.771275) (xy 90.856317 -180.854292) (xy 90.836544 -180.935798) (xy 90.809114 -181.015056)
			(xy 90.774274 -181.091347) (xy 90.732339 -181.163981) (xy 90.683691 -181.2323) (xy 90.628768 -181.295686)
			(xy 90.56807 -181.353564) (xy 90.502144 -181.405411) (xy 90.431589 -181.450756) (xy 90.357043 -181.489189)
			(xy 90.279182 -181.520363) (xy 90.198709 -181.543994) (xy 90.116355 -181.559869) (xy 90.032865 -181.567844)
			(xy 89.99093 -181.568344) (xy 89.953741 -181.567944) (xy 89.879628 -181.561657) (xy 89.806308 -181.54915)
			(xy 89.734302 -181.530513) (xy 89.699084 -181.51856) (xy 89.690888 -181.516037) (xy 89.673752 -181.516037)
			(xy 89.665556 -181.51856) (xy 89.623411 -181.532721) (xy 89.536959 -181.553508) (xy 89.448856 -181.565496)
			(xy 89.404444 -181.567582) (xy 89.393451 -181.568595) (xy 89.373794 -181.578587) (xy 89.360091 -181.595863)
			(xy 89.356946 -181.606444) (xy 89.347967 -181.641899) (xy 89.324947 -181.711329) (xy 89.310972 -181.745128)
			(xy 89.307384 -181.754712) (xy 89.307399 -181.775161) (xy 89.310972 -181.784752) (xy 89.327996 -181.826163)
			(xy 89.354632 -181.91165) (xy 89.37254 -181.999382) (xy 89.381538 -182.08847) (xy 89.382092 -182.13324)
			(xy 89.381588 -182.175601) (xy 89.373535 -182.259938) (xy 89.357501 -182.343128) (xy 89.333633 -182.424418)
			(xy 89.302145 -182.50307) (xy 89.263323 -182.578373) (xy 89.21752 -182.649645) (xy 89.165149 -182.716241)
			(xy 89.106684 -182.777556) (xy 89.042656 -182.833037) (xy 88.973644 -182.88218) (xy 88.900274 -182.92454)
			(xy 88.823209 -182.959735) (xy 88.743147 -182.987444) (xy 88.660814 -183.007418) (xy 88.576955 -183.019475)
			(xy 88.49233 -183.023507) (xy 88.407705 -183.019475) (xy 88.323846 -183.007418) (xy 88.241513 -182.987444)
			(xy 88.161451 -182.959735) (xy 88.084386 -182.92454) (xy 88.011016 -182.88218) (xy 87.942004 -182.833037)
			(xy 87.877976 -182.777556) (xy 87.819511 -182.716241) (xy 87.76714 -182.649645) (xy 87.721337 -182.578373)
			(xy 87.682515 -182.50307) (xy 87.651027 -182.424418) (xy 87.627159 -182.343128) (xy 87.611125 -182.259938)
			(xy 87.603072 -182.175601) (xy 87.602568 -182.13324) (xy 87.603127 -182.08847) (xy 87.612138 -181.999385)
			(xy 87.630045 -181.911654) (xy 87.656665 -181.826163) (xy 87.673688 -181.784752) (xy 87.677232 -181.775155)
			(xy 87.677247 -181.754718) (xy 87.673688 -181.745128) (xy 87.65877 -181.708939) (xy 87.634581 -181.634489)
			(xy 87.617023 -181.558202) (xy 87.606232 -181.480668) (xy 87.603838 -181.441598) (xy 87.603076 -181.427882)
			(xy 87.588598 -181.405276) (xy 87.486236 -181.352444) (xy 87.459566 -181.353714) (xy 87.447882 -181.360826)
			(xy 87.412209 -181.38294) (xy 87.337447 -181.421096) (xy 87.259425 -181.452047) (xy 87.178837 -181.475518)
			(xy 87.096397 -181.4913) (xy 87.012838 -181.499253) (xy 86.97087 -181.499764) (xy 86.929755 -181.499316)
			(xy 86.847877 -181.491726) (xy 86.767048 -181.476614) (xy 86.687959 -181.454109) (xy 86.611283 -181.424402)
			(xy 86.537675 -181.387748) (xy 86.467763 -181.344458) (xy 86.402144 -181.294902) (xy 86.341376 -181.239504)
			(xy 86.28598 -181.178735) (xy 86.236426 -181.113114) (xy 86.193139 -181.043201) (xy 86.156487 -180.969592)
			(xy 86.126782 -180.892915) (xy 86.10428 -180.813824) (xy 86.08917 -180.732995) (xy 86.081583 -180.651117)
			(xy 86.081108 -180.610002) (xy 82.462267 -180.610002) (xy 82.47114 -180.671714) (xy 82.475131 -180.7555)
			(xy 82.47114 -180.839286) (xy 82.459202 -180.922313) (xy 82.439426 -181.00383) (xy 82.411991 -181.083097)
			(xy 82.377146 -181.159398) (xy 82.335205 -181.232041) (xy 82.286549 -181.300368) (xy 82.231618 -181.363761)
			(xy 82.17091 -181.421645) (xy 82.104975 -181.473496) (xy 82.03441 -181.518845) (xy 81.959853 -181.557281)
			(xy 81.88198 -181.588456) (xy 81.801497 -181.612087) (xy 81.719132 -181.627961) (xy 81.63563 -181.635933)
			(xy 81.59369 -181.636416) (xy 81.5565 -181.636029) (xy 81.482387 -181.629739) (xy 81.409068 -181.617228)
			(xy 81.337062 -181.598587) (xy 81.301844 -181.586632) (xy 81.293648 -181.584109) (xy 81.276512 -181.584109)
			(xy 81.268316 -181.586632) (xy 81.24011 -181.596266) (xy 81.182657 -181.612157) (xy 81.153508 -181.618382)
			(xy 81.143879 -181.620834) (xy 81.127394 -181.631892) (xy 81.116335 -181.648377) (xy 81.113884 -181.658006)
			(xy 81.104396 -181.702491) (xy 81.07755 -181.789404) (xy 81.06029 -181.831488) (xy 81.056724 -181.841078)
			(xy 81.056724 -181.861522) (xy 81.06029 -181.871112) (xy 81.077299 -181.912522) (xy 81.103853 -181.998022)
			(xy 81.121689 -182.085755) (xy 81.130627 -182.174836) (xy 81.131156 -182.2196) (xy 81.130652 -182.261948)
			(xy 81.122601 -182.346262) (xy 81.106572 -182.429428) (xy 81.082711 -182.510695) (xy 81.051232 -182.589325)
			(xy 81.012421 -182.664606) (xy 80.966631 -182.735858) (xy 80.914275 -182.802434) (xy 80.855827 -182.863732)
			(xy 80.791817 -182.919197) (xy 80.722825 -182.968326) (xy 80.649475 -183.010675) (xy 80.572432 -183.045859)
			(xy 80.492393 -183.073561) (xy 80.410084 -183.093529) (xy 80.326249 -183.105582) (xy 80.241648 -183.109613)
			(xy 80.157047 -183.105582) (xy 80.073212 -183.093529) (xy 79.990903 -183.073561) (xy 79.910864 -183.045859)
			(xy 79.833821 -183.010675) (xy 79.760471 -182.968326) (xy 79.691479 -182.919197) (xy 79.627469 -182.863732)
			(xy 79.569021 -182.802434) (xy 79.516665 -182.735858) (xy 79.470875 -182.664606) (xy 79.432064 -182.589325)
			(xy 79.400585 -182.510695) (xy 79.376724 -182.429428) (xy 79.360695 -182.346262) (xy 79.352644 -182.261948)
			(xy 79.35214 -182.2196) (xy 79.35267 -182.174836) (xy 79.361599 -182.085754) (xy 79.379438 -181.998021)
			(xy 79.406005 -181.912525) (xy 79.423006 -181.871112) (xy 79.426572 -181.861522) (xy 79.426572 -181.841078)
			(xy 79.423006 -181.831488) (xy 79.405997 -181.790078) (xy 79.379443 -181.704578) (xy 79.361607 -181.616845)
			(xy 79.352669 -181.527764) (xy 79.35214 -181.483) (xy 79.352578 -181.44277) (xy 79.359832 -181.362636)
			(xy 79.366618 -181.32298) (xy 79.368904 -181.310534) (xy 79.361792 -181.287674) (xy 79.287878 -181.210204)
			(xy 79.265272 -181.20233) (xy 79.252826 -181.203854) (xy 79.222877 -181.207733) (xy 79.162627 -181.21193)
			(xy 79.13243 -181.212236) (xy 79.091315 -181.211773) (xy 79.009435 -181.204188) (xy 78.928604 -181.18908)
			(xy 78.849513 -181.166579) (xy 78.772835 -181.136875) (xy 78.699225 -181.100223) (xy 78.629311 -181.056935)
			(xy 78.563689 -181.007381) (xy 78.50292 -180.951983) (xy 78.447522 -180.891214) (xy 78.397967 -180.825593)
			(xy 78.354679 -180.755679) (xy 78.318026 -180.682069) (xy 78.288322 -180.605391) (xy 78.26582 -180.526299)
			(xy 78.250712 -180.445469) (xy 78.243127 -180.363589) (xy 78.242668 -180.322474) (xy 78.24321 -180.279763)
			(xy 78.251472 -180.194741) (xy 78.267833 -180.1109) (xy 78.292141 -180.029009) (xy 78.307692 -179.989226)
			(xy 78.311165 -179.97915) (xy 78.310363 -179.957877) (xy 78.306168 -179.948078) (xy 78.289084 -179.911782)
			(xy 78.260766 -179.83672) (xy 78.239325 -179.759412) (xy 78.224934 -179.680487) (xy 78.21771 -179.600587)
			(xy 78.217268 -179.560474) (xy 78.217473 -179.533929) (xy 78.220647 -179.480935) (xy 78.223618 -179.454556)
			(xy 78.224421 -179.443246) (xy 78.217294 -179.421752) (xy 78.209902 -179.413154) (xy 78.180933 -179.382157)
			(xy 78.128411 -179.31552) (xy 78.082469 -179.244186) (xy 78.043525 -179.168805) (xy 78.011931 -179.090059)
			(xy 77.987974 -179.008663) (xy 77.971872 -178.925358) (xy 77.963772 -178.840898) (xy 77.963268 -178.798474)
			(xy 60.38088 -178.798474) (xy 60.38088 -179.40782) (xy 60.381306 -179.417889) (xy 60.389023 -179.43649)
			(xy 60.395866 -179.443888) (xy 60.582556 -179.630578) (xy 60.589957 -179.637418) (xy 60.608555 -179.645135)
			(xy 60.618624 -179.645564) (xy 67.985386 -179.645564) (xy 68.01034 -179.646184) (xy 68.059285 -179.655934)
			(xy 68.105389 -179.675044) (xy 68.146881 -179.702779) (xy 68.164964 -179.719986) (xy 69.815964 -181.370986)
			(xy 69.833219 -181.389029) (xy 69.860967 -181.430524) (xy 69.880071 -181.476642) (xy 69.889795 -181.525604)
			(xy 69.890386 -181.550564) (xy 69.890386 -183.85917) (xy 69.890821 -183.869235) (xy 69.898552 -183.887822)
			(xy 69.905372 -183.895238) (xy 71.920862 -185.910728) (xy 71.92826 -185.917573) (xy 71.946859 -185.925296)
			(xy 71.95693 -185.925714) (xy 73.753726 -185.925714) (xy 73.778685 -185.926288) (xy 73.827644 -185.936032)
			(xy 73.873761 -185.95514) (xy 73.915264 -185.982878) (xy 73.933304 -186.000136) (xy 78.664054 -190.730886)
			(xy 78.671455 -190.737726) (xy 78.690053 -190.745443) (xy 78.700122 -190.745872)
		)
		(stroke
			(width 0)
			(type solid)
		)
		(fill yes)
		(layer "In9.Cu")
		(net "GND")
	)
	(gr_poly
		(pts
			(xy 439.223404 -341.591138) (xy 439.233473 -341.590713) (xy 439.25207 -341.58299) (xy 439.259472 -341.576152)
			(xy 440.572652 -340.262972) (xy 440.579499 -340.255574) (xy 440.587231 -340.236976) (xy 440.587638 -340.226904)
			(xy 440.587638 -268.416786) (xy 440.587211 -268.406718) (xy 440.579486 -268.388123) (xy 440.572652 -268.380718)
			(xy 439.495946 -267.304012) (xy 439.488695 -267.297437) (xy 439.470665 -267.28986) (xy 439.460894 -267.28928)
			(xy 439.379868 -267.288264) (xy 439.36158 -267.295376) (xy 439.354214 -267.302488) (xy 439.333521 -267.3214)
			(xy 439.287486 -267.353389) (xy 439.237144 -267.378051) (xy 439.183654 -267.39482) (xy 439.128243 -267.403311)
			(xy 439.100214 -267.403834) (xy 439.074247 -267.403385) (xy 439.022828 -267.39609) (xy 438.97294 -267.381656)
			(xy 438.92557 -267.360368) (xy 438.881653 -267.332648) (xy 438.842058 -267.299042) (xy 438.807566 -267.260216)
			(xy 438.778861 -267.216936) (xy 438.756509 -267.170058) (xy 438.740952 -267.120509) (xy 438.736232 -267.09497)
			(xy 438.733184 -267.076682) (xy 438.70499 -267.052552) (xy 435.39537 -267.052552) (xy 435.367176 -267.076682)
			(xy 435.364128 -267.09497) (xy 435.359195 -267.121867) (xy 435.342442 -267.17392) (xy 435.318187 -267.222929)
			(xy 435.286964 -267.267821) (xy 435.249455 -267.307612) (xy 435.206483 -267.341429) (xy 435.15899 -267.368532)
			(xy 435.108016 -267.388327) (xy 435.054679 -267.400381) (xy 435.000146 -267.404428) (xy 434.945613 -267.400381)
			(xy 434.892276 -267.388327) (xy 434.841302 -267.368532) (xy 434.793809 -267.341429) (xy 434.750837 -267.307612)
			(xy 434.713328 -267.267821) (xy 434.682105 -267.222929) (xy 434.65785 -267.17392) (xy 434.641097 -267.121867)
			(xy 434.636164 -267.09497) (xy 434.633116 -267.076682) (xy 434.604922 -267.052552) (xy 431.951384 -267.052552)
			(xy 431.92319 -267.076682) (xy 431.920142 -267.09497) (xy 431.915209 -267.121867) (xy 431.898456 -267.17392)
			(xy 431.874201 -267.222929) (xy 431.842978 -267.267821) (xy 431.805469 -267.307612) (xy 431.762497 -267.341429)
			(xy 431.715004 -267.368532) (xy 431.66403 -267.388327) (xy 431.610693 -267.400381) (xy 431.55616 -267.404428)
			(xy 431.501627 -267.400381) (xy 431.44829 -267.388327) (xy 431.397316 -267.368532) (xy 431.349823 -267.341429)
			(xy 431.306851 -267.307612) (xy 431.269342 -267.267821) (xy 431.238119 -267.222929) (xy 431.213864 -267.17392)
			(xy 431.197111 -267.121867) (xy 431.192178 -267.09497) (xy 431.18913 -267.076682) (xy 431.160936 -267.052552)
			(xy 427.851316 -267.052552) (xy 427.823122 -267.076682) (xy 427.820074 -267.09497) (xy 427.815141 -267.121867)
			(xy 427.798388 -267.17392) (xy 427.774133 -267.222929) (xy 427.74291 -267.267821) (xy 427.705401 -267.307612)
			(xy 427.662429 -267.341429) (xy 427.614936 -267.368532) (xy 427.563962 -267.388327) (xy 427.510625 -267.400381)
			(xy 427.456092 -267.404428) (xy 427.401559 -267.400381) (xy 427.348222 -267.388327) (xy 427.297248 -267.368532)
			(xy 427.249755 -267.341429) (xy 427.206783 -267.307612) (xy 427.169274 -267.267821) (xy 427.138051 -267.222929)
			(xy 427.113796 -267.17392) (xy 427.097043 -267.121867) (xy 427.09211 -267.09497) (xy 427.089062 -267.076682)
			(xy 427.060868 -267.052552) (xy 424.40733 -267.052552) (xy 424.379136 -267.076682) (xy 424.376088 -267.09497)
			(xy 424.371155 -267.121867) (xy 424.354402 -267.17392) (xy 424.330147 -267.222929) (xy 424.298924 -267.267821)
			(xy 424.261415 -267.307612) (xy 424.218443 -267.341429) (xy 424.17095 -267.368532) (xy 424.119976 -267.388327)
			(xy 424.066639 -267.400381) (xy 424.012106 -267.404428) (xy 423.957573 -267.400381) (xy 423.904236 -267.388327)
			(xy 423.853262 -267.368532) (xy 423.805769 -267.341429) (xy 423.762797 -267.307612) (xy 423.725288 -267.267821)
			(xy 423.694065 -267.222929) (xy 423.66981 -267.17392) (xy 423.653057 -267.121867) (xy 423.648124 -267.09497)
			(xy 423.645076 -267.076682) (xy 423.616882 -267.052552) (xy 420.307262 -267.052552) (xy 420.279068 -267.076682)
			(xy 420.27602 -267.09497) (xy 420.271087 -267.121867) (xy 420.254334 -267.17392) (xy 420.230079 -267.222929)
			(xy 420.198856 -267.267821) (xy 420.161347 -267.307612) (xy 420.118375 -267.341429) (xy 420.070882 -267.368532)
			(xy 420.019908 -267.388327) (xy 419.966571 -267.400381) (xy 419.912038 -267.404428) (xy 419.857505 -267.400381)
			(xy 419.804168 -267.388327) (xy 419.753194 -267.368532) (xy 419.705701 -267.341429) (xy 419.662729 -267.307612)
			(xy 419.62522 -267.267821) (xy 419.593997 -267.222929) (xy 419.569742 -267.17392) (xy 419.552989 -267.121867)
			(xy 419.548056 -267.09497) (xy 419.545008 -267.076682) (xy 419.516814 -267.052552) (xy 416.863276 -267.052552)
			(xy 416.835082 -267.076682) (xy 416.832034 -267.09497) (xy 416.827101 -267.121867) (xy 416.810348 -267.17392)
			(xy 416.786093 -267.222929) (xy 416.75487 -267.267821) (xy 416.717361 -267.307612) (xy 416.674389 -267.341429)
			(xy 416.626896 -267.368532) (xy 416.575922 -267.388327) (xy 416.522585 -267.400381) (xy 416.468052 -267.404428)
			(xy 416.413519 -267.400381) (xy 416.360182 -267.388327) (xy 416.309208 -267.368532) (xy 416.261715 -267.341429)
			(xy 416.218743 -267.307612) (xy 416.181234 -267.267821) (xy 416.150011 -267.222929) (xy 416.125756 -267.17392)
			(xy 416.109003 -267.121867) (xy 416.10407 -267.09497) (xy 416.101022 -267.076682) (xy 416.072828 -267.052552)
			(xy 393.63142 -267.052552) (xy 393.611744 -267.052184) (xy 393.572862 -267.046114) (xy 393.535383 -267.034117)
			(xy 393.517628 -267.025628) (xy 393.499458 -267.016101) (xy 393.466191 -266.992095) (xy 393.437208 -266.963061)
			(xy 393.424918 -266.946634) (xy 393.417261 -266.9372) (xy 393.395648 -266.926177) (xy 393.383516 -266.925552)
			(xy 392.311128 -266.925552) (xy 392.301946 -266.925899) (xy 392.284734 -266.932288) (xy 392.270874 -266.94433)
			(xy 392.26617 -266.952222) (xy 392.26617 -266.952476) (xy 392.253702 -266.974698) (xy 392.222994 -267.015358)
			(xy 392.186414 -267.050827) (xy 392.144825 -267.080264) (xy 392.099214 -267.102975) (xy 392.050658 -267.118421)
			(xy 392.000308 -267.126236) (xy 391.949356 -267.126236) (xy 391.899006 -267.118421) (xy 391.85045 -267.102975)
			(xy 391.804839 -267.080264) (xy 391.76325 -267.050827) (xy 391.72667 -267.015358) (xy 391.695962 -266.974698)
			(xy 391.683494 -266.952476) (xy 391.683494 -266.952222) (xy 391.678786 -266.944335) (xy 391.664926 -266.932304)
			(xy 391.647715 -266.925927) (xy 391.638536 -266.925552) (xy 391.371074 -266.925552) (xy 391.361888 -266.925891)
			(xy 391.344663 -266.93227) (xy 391.330791 -266.944309) (xy 391.326116 -266.952222) (xy 391.326116 -266.952476)
			(xy 391.313649 -266.974701) (xy 391.282943 -267.015367) (xy 391.246364 -267.050843) (xy 391.204776 -267.08029)
			(xy 391.159165 -267.10301) (xy 391.110609 -267.118466) (xy 391.060256 -267.126293) (xy 391.034778 -267.12672)
			(xy 391.008792 -267.126209) (xy 390.957459 -267.118076) (xy 390.908031 -267.102013) (xy 390.861723 -267.078416)
			(xy 390.819677 -267.047866) (xy 390.782927 -267.011115) (xy 390.752379 -266.969068) (xy 390.728783 -266.92276)
			(xy 390.712722 -266.873331) (xy 390.70459 -266.821998) (xy 390.70407 -266.796012) (xy 390.704495 -266.772686)
			(xy 390.711091 -266.726502) (xy 390.724099 -266.6817) (xy 390.743261 -266.639164) (xy 390.755378 -266.619228)
			(xy 390.755378 -266.618974) (xy 390.759996 -266.61095) (xy 390.763708 -266.592829) (xy 390.760728 -266.574574)
			(xy 390.756394 -266.566396) (xy 390.604248 -266.304776) (xy 390.580626 -266.291314) (xy 390.564878 -266.291314)
			(xy 390.540888 -266.290842) (xy 390.493498 -266.283333) (xy 390.447867 -266.268504) (xy 390.405117 -266.246719)
			(xy 390.366301 -266.218515) (xy 390.332374 -266.184587) (xy 390.304173 -266.14577) (xy 390.28239 -266.103018)
			(xy 390.267563 -266.057386) (xy 390.260057 -266.009996) (xy 390.25957 -265.986006) (xy 390.260122 -265.959247)
			(xy 390.269435 -265.906547) (xy 390.287776 -265.856271) (xy 390.300718 -265.832844) (xy 390.305002 -265.824925)
			(xy 390.308252 -265.80723) (xy 390.305161 -265.789506) (xy 390.300972 -265.781536) (xy 390.148572 -265.519154)
			(xy 390.12368 -265.505692) (xy 390.109456 -265.506454) (xy 390.094724 -265.506708) (xy 390.068734 -265.506227)
			(xy 390.017392 -265.498098) (xy 389.967954 -265.482038) (xy 389.921638 -265.458442) (xy 389.879583 -265.42789)
			(xy 389.842826 -265.391135) (xy 389.812271 -265.349083) (xy 389.788671 -265.302768) (xy 389.772607 -265.253331)
			(xy 389.764475 -265.20199) (xy 389.764016 -265.176) (xy 389.764016 -265.175492) (xy 389.764426 -265.152236)
			(xy 389.770973 -265.106186) (xy 389.783908 -265.061508) (xy 389.802976 -265.019084) (xy 389.81507 -264.999216)
			(xy 389.82269 -264.987278) (xy 389.823198 -264.959084) (xy 389.678418 -264.709148) (xy 389.653526 -264.695686)
			(xy 389.639302 -264.696448) (xy 389.624824 -264.696702) (xy 389.599346 -264.696234) (xy 389.548992 -264.688421)
			(xy 389.500432 -264.672977) (xy 389.454816 -264.650267) (xy 389.413223 -264.620829) (xy 389.376638 -264.585359)
			(xy 389.345927 -264.544696) (xy 389.333486 -264.522458) (xy 389.328808 -264.514601) (xy 389.315032 -264.502595)
			(xy 389.297919 -264.496188) (xy 389.288782 -264.495788) (xy 389.020812 -264.495788) (xy 389.011672 -264.496167)
			(xy 388.994553 -264.502579) (xy 388.980773 -264.51459) (xy 388.976108 -264.522458) (xy 388.96364 -264.54468)
			(xy 388.932932 -264.58534) (xy 388.896352 -264.620809) (xy 388.854763 -264.650246) (xy 388.809152 -264.672957)
			(xy 388.760596 -264.688403) (xy 388.710246 -264.696218) (xy 388.659294 -264.696218) (xy 388.608944 -264.688403)
			(xy 388.560388 -264.672957) (xy 388.514777 -264.650246) (xy 388.473188 -264.620809) (xy 388.436608 -264.58534)
			(xy 388.4059 -264.54468) (xy 388.393432 -264.522458) (xy 388.388756 -264.514596) (xy 388.374982 -264.502578)
			(xy 388.357868 -264.496155) (xy 388.348728 -264.495788) (xy 388.080758 -264.495788) (xy 388.071623 -264.496176)
			(xy 388.054519 -264.502599) (xy 388.040754 -264.514614) (xy 388.036054 -264.522458) (xy 388.023586 -264.54468)
			(xy 387.992878 -264.58534) (xy 387.956298 -264.620809) (xy 387.914709 -264.650246) (xy 387.869098 -264.672957)
			(xy 387.820542 -264.688403) (xy 387.770192 -264.696218) (xy 387.71924 -264.696218) (xy 387.66889 -264.688403)
			(xy 387.620334 -264.672957) (xy 387.574723 -264.650246) (xy 387.533134 -264.620809) (xy 387.496554 -264.58534)
			(xy 387.465846 -264.54468) (xy 387.453378 -264.522458) (xy 387.448699 -264.514602) (xy 387.434923 -264.502598)
			(xy 387.41781 -264.496193) (xy 387.408674 -264.495788) (xy 387.140958 -264.495788) (xy 387.131823 -264.496176)
			(xy 387.114719 -264.502599) (xy 387.100954 -264.514614) (xy 387.096254 -264.522458) (xy 387.083786 -264.54468)
			(xy 387.053078 -264.58534) (xy 387.016498 -264.620809) (xy 386.974909 -264.650246) (xy 386.929298 -264.672957)
			(xy 386.880742 -264.688403) (xy 386.830392 -264.696218) (xy 386.77944 -264.696218) (xy 386.72909 -264.688403)
			(xy 386.680534 -264.672957) (xy 386.634923 -264.650246) (xy 386.593334 -264.620809) (xy 386.556754 -264.58534)
			(xy 386.526046 -264.54468) (xy 386.513578 -264.522458) (xy 386.508899 -264.514602) (xy 386.495123 -264.502598)
			(xy 386.47801 -264.496193) (xy 386.468874 -264.495788) (xy 386.200904 -264.495788) (xy 386.191765 -264.496169)
			(xy 386.174648 -264.502582) (xy 386.160871 -264.514594) (xy 386.1562 -264.522458) (xy 386.143732 -264.54468)
			(xy 386.113024 -264.58534) (xy 386.076444 -264.620809) (xy 386.034855 -264.650246) (xy 385.989244 -264.672957)
			(xy 385.940688 -264.688403) (xy 385.890338 -264.696218) (xy 385.839386 -264.696218) (xy 385.789036 -264.688403)
			(xy 385.74048 -264.672957) (xy 385.694869 -264.650246) (xy 385.65328 -264.620809) (xy 385.6167 -264.58534)
			(xy 385.585992 -264.54468) (xy 385.573524 -264.522458) (xy 385.568847 -264.514597) (xy 385.555073 -264.502581)
			(xy 385.537959 -264.496161) (xy 385.52882 -264.495788) (xy 385.26085 -264.495788) (xy 385.251716 -264.496178)
			(xy 385.234614 -264.502602) (xy 385.220851 -264.514617) (xy 385.216146 -264.522458) (xy 385.203679 -264.544681)
			(xy 385.172972 -264.585342) (xy 385.136391 -264.620812) (xy 385.094803 -264.650252) (xy 385.049191 -264.672964)
			(xy 385.000635 -264.688411) (xy 384.950285 -264.696228) (xy 384.924808 -264.696702) (xy 384.898818 -264.696219)
			(xy 384.847479 -264.688089) (xy 384.798044 -264.672028) (xy 384.75173 -264.64843) (xy 384.709678 -264.617878)
			(xy 384.672923 -264.581123) (xy 384.642371 -264.539071) (xy 384.618773 -264.492758) (xy 384.602711 -264.443323)
			(xy 384.594581 -264.391983) (xy 384.5941 -264.365994) (xy 384.594526 -264.342668) (xy 384.601123 -264.296485)
			(xy 384.61413 -264.251682) (xy 384.633291 -264.209146) (xy 384.645408 -264.18921) (xy 384.653028 -264.177018)
			(xy 384.653536 -264.149332) (xy 384.508756 -263.899142) (xy 384.483864 -263.88568) (xy 384.46964 -263.886442)
			(xy 384.454908 -263.886696) (xy 384.42943 -263.886227) (xy 384.379078 -263.878412) (xy 384.33052 -263.862966)
			(xy 384.284906 -263.840254) (xy 384.243316 -263.810815) (xy 384.206734 -263.775344) (xy 384.176025 -263.734682)
			(xy 384.16357 -263.712452) (xy 384.16357 -263.712198) (xy 384.158868 -263.704304) (xy 384.14501 -263.692261)
			(xy 384.127794 -263.685882) (xy 384.118612 -263.685528) (xy 383.85115 -263.685528) (xy 383.841969 -263.685873)
			(xy 383.824758 -263.692263) (xy 383.810907 -263.704312) (xy 383.806192 -263.712198) (xy 383.806192 -263.712452)
			(xy 383.793724 -263.734674) (xy 383.763016 -263.775334) (xy 383.726436 -263.810803) (xy 383.684847 -263.84024)
			(xy 383.639236 -263.862951) (xy 383.59068 -263.878397) (xy 383.54033 -263.886212) (xy 383.489378 -263.886212)
			(xy 383.439028 -263.878397) (xy 383.390472 -263.862951) (xy 383.344861 -263.84024) (xy 383.303272 -263.810803)
			(xy 383.266692 -263.775334) (xy 383.235984 -263.734674) (xy 383.223516 -263.712452) (xy 383.223516 -263.712198)
			(xy 383.218816 -263.704299) (xy 383.20496 -263.692243) (xy 383.187743 -263.685849) (xy 383.178558 -263.685528)
			(xy 382.911096 -263.685528) (xy 382.901911 -263.685865) (xy 382.884688 -263.692245) (xy 382.870823 -263.704291)
			(xy 382.866138 -263.712198) (xy 382.866138 -263.712452) (xy 382.85367 -263.734674) (xy 382.822962 -263.775334)
			(xy 382.786382 -263.810803) (xy 382.744793 -263.84024) (xy 382.699182 -263.862951) (xy 382.650626 -263.878397)
			(xy 382.600276 -263.886212) (xy 382.549324 -263.886212) (xy 382.498974 -263.878397) (xy 382.450418 -263.862951)
			(xy 382.404807 -263.84024) (xy 382.363218 -263.810803) (xy 382.326638 -263.775334) (xy 382.29593 -263.734674)
			(xy 382.283462 -263.712452) (xy 382.283462 -263.712198) (xy 382.278759 -263.704305) (xy 382.264901 -263.692264)
			(xy 382.247686 -263.685887) (xy 382.238504 -263.685528) (xy 381.971042 -263.685528) (xy 381.961862 -263.685874)
			(xy 381.944653 -263.692266) (xy 381.930804 -263.704315) (xy 381.926084 -263.712198) (xy 381.926084 -263.712452)
			(xy 381.913616 -263.734674) (xy 381.882908 -263.775334) (xy 381.846328 -263.810803) (xy 381.804739 -263.84024)
			(xy 381.759128 -263.862951) (xy 381.710572 -263.878397) (xy 381.660222 -263.886212) (xy 381.60927 -263.886212)
			(xy 381.55892 -263.878397) (xy 381.510364 -263.862951) (xy 381.464753 -263.84024) (xy 381.423164 -263.810803)
			(xy 381.386584 -263.775334) (xy 381.355876 -263.734674) (xy 381.343408 -263.712452) (xy 381.343408 -263.712198)
			(xy 381.338708 -263.7043) (xy 381.324851 -263.692246) (xy 381.307634 -263.685854) (xy 381.29845 -263.685528)
			(xy 381.031242 -263.685528) (xy 381.022062 -263.685874) (xy 381.004853 -263.692266) (xy 380.991004 -263.704315)
			(xy 380.986284 -263.712198) (xy 380.986284 -263.712452) (xy 380.973816 -263.734674) (xy 380.943108 -263.775334)
			(xy 380.906528 -263.810803) (xy 380.864939 -263.84024) (xy 380.819328 -263.862951) (xy 380.770772 -263.878397)
			(xy 380.720422 -263.886212) (xy 380.66947 -263.886212) (xy 380.61912 -263.878397) (xy 380.570564 -263.862951)
			(xy 380.524953 -263.84024) (xy 380.483364 -263.810803) (xy 380.446784 -263.775334) (xy 380.416076 -263.734674)
			(xy 380.403608 -263.712452) (xy 380.403608 -263.712198) (xy 380.398908 -263.7043) (xy 380.385051 -263.692246)
			(xy 380.367834 -263.685854) (xy 380.35865 -263.685528) (xy 380.091188 -263.685528) (xy 380.082003 -263.685866)
			(xy 380.064783 -263.692248) (xy 380.05092 -263.704295) (xy 380.04623 -263.712198) (xy 380.04623 -263.712452)
			(xy 380.033763 -263.734674) (xy 380.003055 -263.775335) (xy 379.966475 -263.810804) (xy 379.924886 -263.840242)
			(xy 379.879274 -263.862953) (xy 379.830719 -263.878398) (xy 379.780369 -263.886213) (xy 379.754892 -263.886696)
			(xy 379.728918 -263.886187) (xy 379.67761 -263.878063) (xy 379.628203 -263.862017) (xy 379.581912 -263.838442)
			(xy 379.539878 -263.80792) (xy 379.503132 -263.771201) (xy 379.47258 -263.729187) (xy 379.448973 -263.682914)
			(xy 379.432892 -263.633518) (xy 379.424732 -263.582215) (xy 379.424184 -263.556242) (xy 379.424184 -263.555734)
			(xy 379.424438 -263.544812) (xy 379.424438 -263.544558) (xy 379.424379 -263.535358) (xy 379.418498 -263.51794)
			(xy 379.406824 -263.503738) (xy 379.399038 -263.498838) (xy 378.561346 -263.017508) (xy 378.533152 -263.01827)
			(xy 378.521214 -263.02589) (xy 378.501351 -263.03791) (xy 378.458978 -263.056883) (xy 378.414372 -263.069756)
			(xy 378.368405 -263.076276) (xy 378.345192 -263.07669) (xy 378.344938 -263.07669) (xy 378.319459 -263.076223)
			(xy 378.269104 -263.068412) (xy 378.220543 -263.052969) (xy 378.174926 -263.030259) (xy 378.133333 -263.000821)
			(xy 378.096747 -262.965351) (xy 378.066036 -262.924688) (xy 378.0536 -262.902446) (xy 378.048921 -262.894589)
			(xy 378.035145 -262.882582) (xy 378.018033 -262.876172) (xy 378.008896 -262.875776) (xy 377.740926 -262.875776)
			(xy 377.731784 -262.876153) (xy 377.714661 -262.88256) (xy 377.700875 -262.894569) (xy 377.696222 -262.902446)
			(xy 377.683754 -262.924668) (xy 377.653046 -262.965328) (xy 377.616466 -263.000797) (xy 377.574877 -263.030234)
			(xy 377.529266 -263.052945) (xy 377.48071 -263.068391) (xy 377.43036 -263.076206) (xy 377.379408 -263.076206)
			(xy 377.329058 -263.068391) (xy 377.280502 -263.052945) (xy 377.234891 -263.030234) (xy 377.193302 -263.000797)
			(xy 377.156722 -262.965328) (xy 377.126014 -262.924668) (xy 377.113546 -262.902446) (xy 377.108869 -262.894584)
			(xy 377.095096 -262.882564) (xy 377.077982 -262.876139) (xy 377.068842 -262.875776) (xy 376.800872 -262.875776)
			(xy 376.791735 -262.876162) (xy 376.774626 -262.882581) (xy 376.760855 -262.894593) (xy 376.756168 -262.902446)
			(xy 376.7437 -262.924668) (xy 376.712992 -262.965328) (xy 376.676412 -263.000797) (xy 376.634823 -263.030234)
			(xy 376.589212 -263.052945) (xy 376.540656 -263.068391) (xy 376.490306 -263.076206) (xy 376.439354 -263.076206)
			(xy 376.389004 -263.068391) (xy 376.340448 -263.052945) (xy 376.294837 -263.030234) (xy 376.253248 -263.000797)
			(xy 376.216668 -262.965328) (xy 376.18596 -262.924668) (xy 376.173492 -262.902446) (xy 376.168813 -262.89459)
			(xy 376.155037 -262.882585) (xy 376.137924 -262.876177) (xy 376.128788 -262.875776) (xy 375.860818 -262.875776)
			(xy 375.851677 -262.876154) (xy 375.834556 -262.882563) (xy 375.820772 -262.894573) (xy 375.816114 -262.902446)
			(xy 375.803664 -262.924636) (xy 375.773006 -262.965244) (xy 375.736492 -263.000678) (xy 375.694983 -263.030103)
			(xy 375.649458 -263.052825) (xy 375.60099 -263.068308) (xy 375.550723 -263.076188) (xy 375.525284 -263.07669)
			(xy 375.524268 -263.07669) (xy 375.515378 -263.076436) (xy 375.501408 -263.076182) (xy 375.477278 -263.08939)
			(xy 375.336562 -263.331706) (xy 375.332277 -263.339791) (xy 375.329187 -263.357813) (xy 375.332638 -263.375769)
			(xy 375.33707 -263.383776) (xy 375.348572 -263.403301) (xy 375.366709 -263.444828) (xy 375.379003 -263.488444)
			(xy 375.385223 -263.533331) (xy 375.385584 -263.555988) (xy 375.385102 -263.581977) (xy 375.376972 -263.633316)
			(xy 375.36091 -263.68275) (xy 375.337313 -263.729064) (xy 375.30676 -263.771115) (xy 375.270006 -263.807868)
			(xy 375.227953 -263.838419) (xy 375.181639 -263.862015) (xy 375.132204 -263.878075) (xy 375.080865 -263.886203)
			(xy 375.054876 -263.886696) (xy 375.028903 -263.886186) (xy 374.977597 -263.87806) (xy 374.928192 -263.862012)
			(xy 374.881904 -263.838437) (xy 374.839871 -263.807914) (xy 374.803127 -263.771195) (xy 374.772577 -263.729183)
			(xy 374.748971 -263.68291) (xy 374.732891 -263.633516) (xy 374.724732 -263.582215) (xy 374.724168 -263.556242)
			(xy 374.724168 -263.555734) (xy 374.724422 -263.544558) (xy 374.72493 -263.530334) (xy 374.711468 -263.50595)
			(xy 373.86133 -263.017508) (xy 373.833136 -263.01827) (xy 373.821198 -263.02589) (xy 373.801335 -263.037909)
			(xy 373.758962 -263.05688) (xy 373.714355 -263.069751) (xy 373.668389 -263.076269) (xy 373.645176 -263.07669)
			(xy 373.644668 -263.07669) (xy 373.635524 -263.076436) (xy 373.626414 -263.076578) (xy 373.609204 -263.082523)
			(xy 373.595178 -263.094132) (xy 373.590312 -263.101836) (xy 373.449596 -263.344152) (xy 373.44985 -263.372092)
			(xy 373.457216 -263.383776) (xy 373.468644 -263.403294) (xy 373.486679 -263.444771) (xy 373.4989 -263.488316)
			(xy 373.50508 -263.53312) (xy 373.505476 -263.555734) (xy 373.505476 -263.555988) (xy 373.504994 -263.581977)
			(xy 373.496864 -263.633315) (xy 373.480802 -263.682749) (xy 373.457205 -263.729062) (xy 373.426652 -263.771112)
			(xy 373.389897 -263.807865) (xy 373.347845 -263.838415) (xy 373.301531 -263.86201) (xy 373.252096 -263.878068)
			(xy 373.200757 -263.886195) (xy 373.174768 -263.886696) (xy 373.148795 -263.886185) (xy 373.09749 -263.878058)
			(xy 373.048086 -263.86201) (xy 373.001799 -263.838434) (xy 372.959767 -263.807912) (xy 372.923025 -263.771192)
			(xy 372.892476 -263.72918) (xy 372.868871 -263.682908) (xy 372.852791 -263.633514) (xy 372.844632 -263.582214)
			(xy 372.84406 -263.556242) (xy 372.84406 -263.555734) (xy 372.844314 -263.544558) (xy 372.844822 -263.530334)
			(xy 372.83136 -263.50595) (xy 371.993414 -263.02462) (xy 371.985256 -263.020355) (xy 371.967103 -263.017388)
			(xy 371.94908 -263.021063) (xy 371.94109 -263.025636) (xy 371.921213 -263.037714) (xy 371.878791 -263.056781)
			(xy 371.834116 -263.069716) (xy 371.788069 -263.076263) (xy 371.764814 -263.07669) (xy 371.738839 -263.076182)
			(xy 371.687529 -263.068061) (xy 371.638119 -263.052017) (xy 371.591826 -263.028444) (xy 371.549789 -262.997922)
			(xy 371.513041 -262.961202) (xy 371.482487 -262.919187) (xy 371.458879 -262.872912) (xy 371.442797 -262.823515)
			(xy 371.434637 -262.77221) (xy 371.434106 -262.746236) (xy 371.434106 -262.745728) (xy 371.43436 -262.734552)
			(xy 371.434868 -262.720328) (xy 371.421406 -262.695944) (xy 370.571268 -262.207502) (xy 370.543074 -262.208264)
			(xy 370.531136 -262.215884) (xy 370.511274 -262.227906) (xy 370.468901 -262.246882) (xy 370.424295 -262.259758)
			(xy 370.378328 -262.266282) (xy 370.355114 -262.266684) (xy 370.354606 -262.266684) (xy 370.345462 -262.26643)
			(xy 370.336348 -262.266566) (xy 370.319128 -262.272502) (xy 370.30509 -262.284107) (xy 370.30025 -262.29183)
			(xy 370.159534 -262.534146) (xy 370.159788 -262.562086) (xy 370.167154 -262.57377) (xy 370.178581 -262.593288)
			(xy 370.196615 -262.634765) (xy 370.208835 -262.678311) (xy 370.215015 -262.723114) (xy 370.215414 -262.745728)
			(xy 370.215414 -262.745982) (xy 370.214932 -262.771972) (xy 370.206803 -262.823313) (xy 370.190743 -262.872751)
			(xy 370.167146 -262.919067) (xy 370.136594 -262.961121) (xy 370.09984 -262.997879) (xy 370.057787 -263.028433)
			(xy 370.011473 -263.052033) (xy 369.962037 -263.068098) (xy 369.910696 -263.07623) (xy 369.884706 -263.07669)
			(xy 369.858732 -263.076182) (xy 369.807422 -263.06806) (xy 369.758013 -263.052015) (xy 369.711722 -263.028441)
			(xy 369.669685 -262.997919) (xy 369.632939 -262.961199) (xy 369.602386 -262.919185) (xy 369.578778 -262.87291)
			(xy 369.562697 -262.823514) (xy 369.554537 -262.77221) (xy 369.553998 -262.746236) (xy 369.553998 -262.745728)
			(xy 369.554252 -262.734552) (xy 369.55476 -262.720328) (xy 369.541298 -262.695944) (xy 368.405918 -262.043672)
			(xy 368.39525 -262.035544) (xy 368.172492 -261.812786) (xy 368.165097 -261.805932) (xy 368.146498 -261.798186)
			(xy 368.136424 -261.7978) (xy 364.453424 -261.7978) (xy 364.44336 -261.797363) (xy 364.424776 -261.789629)
			(xy 364.417356 -261.782814) (xy 364.305596 -261.671054) (xy 364.277148 -261.664704) (xy 364.263178 -261.669784)
			(xy 364.232941 -261.679955) (xy 364.170104 -261.690938) (xy 364.13821 -261.691628) (xy 364.137956 -261.691628)
			(xy 364.111859 -261.691172) (xy 364.060187 -261.683806) (xy 364.01007 -261.669226) (xy 363.962509 -261.647725)
			(xy 363.918457 -261.619731) (xy 363.878792 -261.585805) (xy 363.844308 -261.546625) (xy 363.815693 -261.502973)
			(xy 363.8042 -261.479538) (xy 363.79785 -261.466076) (xy 363.773212 -261.450328) (xy 363.567726 -261.450328)
			(xy 363.558106 -261.450736) (xy 363.540217 -261.457819) (xy 363.526198 -261.470998) (xy 363.521752 -261.479538)
			(xy 363.509473 -261.504532) (xy 363.478521 -261.550823) (xy 363.440958 -261.591931) (xy 363.39764 -261.626922)
			(xy 363.349551 -261.654999) (xy 363.297786 -261.675523) (xy 363.243523 -261.688028) (xy 363.187996 -261.692227)
			(xy 363.132469 -261.688028) (xy 363.078206 -261.675523) (xy 363.026441 -261.654999) (xy 362.978352 -261.626922)
			(xy 362.935034 -261.591931) (xy 362.897471 -261.550823) (xy 362.866519 -261.504532) (xy 362.85424 -261.479538)
			(xy 362.84789 -261.466076) (xy 362.823252 -261.450328) (xy 362.617766 -261.450328) (xy 362.608152 -261.450746)
			(xy 362.59028 -261.457842) (xy 362.57628 -261.471023) (xy 362.571792 -261.479538) (xy 362.559513 -261.504532)
			(xy 362.528561 -261.550823) (xy 362.490998 -261.591931) (xy 362.44768 -261.626922) (xy 362.399591 -261.654999)
			(xy 362.347826 -261.675523) (xy 362.293563 -261.688028) (xy 362.238036 -261.692227) (xy 362.182509 -261.688028)
			(xy 362.128246 -261.675523) (xy 362.076481 -261.654999) (xy 362.028392 -261.626922) (xy 361.985074 -261.591931)
			(xy 361.947511 -261.550823) (xy 361.916559 -261.504532) (xy 361.90428 -261.479538) (xy 361.89793 -261.466076)
			(xy 361.873292 -261.450328) (xy 361.667806 -261.450328) (xy 361.658188 -261.45074) (xy 361.640304 -261.457827)
			(xy 361.626292 -261.471006) (xy 361.621832 -261.479538) (xy 361.609553 -261.504532) (xy 361.578601 -261.550823)
			(xy 361.541038 -261.591931) (xy 361.49772 -261.626922) (xy 361.449631 -261.654999) (xy 361.397866 -261.675523)
			(xy 361.343603 -261.688028) (xy 361.288076 -261.692227) (xy 361.232549 -261.688028) (xy 361.178286 -261.675523)
			(xy 361.126521 -261.654999) (xy 361.078432 -261.626922) (xy 361.035114 -261.591931) (xy 360.997551 -261.550823)
			(xy 360.966599 -261.504532) (xy 360.95432 -261.479538) (xy 360.94797 -261.466076) (xy 360.923332 -261.450328)
			(xy 360.717592 -261.450328) (xy 360.707975 -261.450742) (xy 360.690096 -261.457832) (xy 360.676088 -261.471012)
			(xy 360.671618 -261.479538) (xy 360.659339 -261.504532) (xy 360.628387 -261.550823) (xy 360.590824 -261.591931)
			(xy 360.547506 -261.626922) (xy 360.499417 -261.654999) (xy 360.447652 -261.675523) (xy 360.393389 -261.688028)
			(xy 360.337862 -261.692227) (xy 360.282335 -261.688028) (xy 360.228072 -261.675523) (xy 360.176307 -261.654999)
			(xy 360.128218 -261.626922) (xy 360.0849 -261.591931) (xy 360.047337 -261.550823) (xy 360.016385 -261.504532)
			(xy 360.004106 -261.479538) (xy 359.997756 -261.466076) (xy 359.973118 -261.450328) (xy 359.767632 -261.450328)
			(xy 359.758011 -261.450735) (xy 359.74012 -261.457817) (xy 359.7261 -261.470995) (xy 359.721658 -261.479538)
			(xy 359.709379 -261.504532) (xy 359.678427 -261.550823) (xy 359.640864 -261.591931) (xy 359.597546 -261.626922)
			(xy 359.549457 -261.654999) (xy 359.497692 -261.675523) (xy 359.443429 -261.688028) (xy 359.387902 -261.692227)
			(xy 359.332375 -261.688028) (xy 359.278112 -261.675523) (xy 359.226347 -261.654999) (xy 359.178258 -261.626922)
			(xy 359.13494 -261.591931) (xy 359.097377 -261.550823) (xy 359.066425 -261.504532) (xy 359.054146 -261.479538)
			(xy 359.047796 -261.466076) (xy 359.023158 -261.450328) (xy 358.817672 -261.450328) (xy 358.808057 -261.450745)
			(xy 358.790184 -261.45784) (xy 358.776181 -261.471021) (xy 358.771698 -261.479538) (xy 358.759419 -261.504532)
			(xy 358.728467 -261.550823) (xy 358.690904 -261.591931) (xy 358.647586 -261.626922) (xy 358.599497 -261.654999)
			(xy 358.547732 -261.675523) (xy 358.493469 -261.688028) (xy 358.437942 -261.692227) (xy 358.382415 -261.688028)
			(xy 358.328152 -261.675523) (xy 358.276387 -261.654999) (xy 358.228298 -261.626922) (xy 358.18498 -261.591931)
			(xy 358.147417 -261.550823) (xy 358.116465 -261.504532) (xy 358.104186 -261.479538) (xy 358.097836 -261.466076)
			(xy 358.073198 -261.450328) (xy 357.867712 -261.450328) (xy 357.858093 -261.450739) (xy 357.840208 -261.457825)
			(xy 357.826194 -261.471004) (xy 357.821738 -261.479538) (xy 357.809459 -261.504532) (xy 357.778507 -261.550823)
			(xy 357.740944 -261.591931) (xy 357.697626 -261.626922) (xy 357.649537 -261.654999) (xy 357.597772 -261.675523)
			(xy 357.543509 -261.688028) (xy 357.487982 -261.692227) (xy 357.432455 -261.688028) (xy 357.378192 -261.675523)
			(xy 357.326427 -261.654999) (xy 357.278338 -261.626922) (xy 357.23502 -261.591931) (xy 357.197457 -261.550823)
			(xy 357.166505 -261.504532) (xy 357.154226 -261.479538) (xy 357.147876 -261.466076) (xy 357.123238 -261.450328)
			(xy 356.917752 -261.450328) (xy 356.908129 -261.450732) (xy 356.890232 -261.457809) (xy 356.876206 -261.470987)
			(xy 356.871778 -261.479538) (xy 356.859499 -261.504532) (xy 356.828547 -261.550823) (xy 356.790984 -261.591931)
			(xy 356.747666 -261.626922) (xy 356.699577 -261.654999) (xy 356.647812 -261.675523) (xy 356.593549 -261.688028)
			(xy 356.538022 -261.692227) (xy 356.482495 -261.688028) (xy 356.428232 -261.675523) (xy 356.376467 -261.654999)
			(xy 356.328378 -261.626922) (xy 356.28506 -261.591931) (xy 356.247497 -261.550823) (xy 356.216545 -261.504532)
			(xy 356.204266 -261.479538) (xy 356.197916 -261.466076) (xy 356.173278 -261.450328) (xy 355.967792 -261.450328)
			(xy 355.958175 -261.450742) (xy 355.940296 -261.457832) (xy 355.926288 -261.471012) (xy 355.921818 -261.479538)
			(xy 355.909539 -261.504532) (xy 355.878587 -261.550823) (xy 355.841024 -261.591931) (xy 355.797706 -261.626922)
			(xy 355.749617 -261.654999) (xy 355.697852 -261.675523) (xy 355.643589 -261.688028) (xy 355.588062 -261.692227)
			(xy 355.532535 -261.688028) (xy 355.478272 -261.675523) (xy 355.426507 -261.654999) (xy 355.378418 -261.626922)
			(xy 355.3351 -261.591931) (xy 355.297537 -261.550823) (xy 355.266585 -261.504532) (xy 355.254306 -261.479538)
			(xy 355.247956 -261.466076) (xy 355.223318 -261.450328) (xy 354.66528 -261.450328) (xy 354.65424 -261.450937)
			(xy 354.634233 -261.460293) (xy 354.626672 -261.468362) (xy 354.609059 -261.488427) (xy 354.569045 -261.523772)
			(xy 354.524356 -261.552983) (xy 354.475924 -261.575451) (xy 354.424761 -261.590707) (xy 354.371934 -261.598433)
			(xy 354.34524 -261.598918) (xy 354.344986 -261.598918) (xy 354.319306 -261.598496) (xy 354.268444 -261.591357)
			(xy 354.24364 -261.584694) (xy 354.234784 -261.582505) (xy 354.216603 -261.583841) (xy 354.200033 -261.591442)
			(xy 354.193348 -261.597648) (xy 353.789742 -262.001508) (xy 353.783197 -262.008567) (xy 353.7755 -262.026196)
			(xy 353.774888 -262.045421) (xy 353.777804 -262.054594) (xy 353.777804 -262.054848) (xy 353.787972 -262.085085)
			(xy 353.79895 -262.147922) (xy 353.799648 -262.179816) (xy 353.799648 -262.18007) (xy 353.79918 -262.206416)
			(xy 353.791686 -262.258574) (xy 353.776845 -262.309133) (xy 353.754959 -262.357067) (xy 353.726476 -262.401397)
			(xy 353.691973 -262.441223) (xy 353.652153 -262.475734) (xy 353.607828 -262.504226) (xy 353.559899 -262.52612)
			(xy 353.509342 -262.540971) (xy 353.457186 -262.548475) (xy 353.43084 -262.548878) (xy 353.400238 -262.548271)
			(xy 353.339875 -262.538162) (xy 353.282007 -262.518232) (xy 353.254818 -262.504174) (xy 353.241864 -262.497062)
			(xy 353.212654 -262.499094) (xy 351.62998 -263.66343) (xy 351.625154 -263.666732) (xy 350.4946 -264.315956)
			(xy 350.481138 -264.34034) (xy 350.481646 -264.354564) (xy 350.4819 -264.36574) (xy 350.4819 -264.366248)
			(xy 350.481372 -264.392222) (xy 350.473211 -264.443526) (xy 350.457128 -264.492923) (xy 350.433518 -264.539198)
			(xy 350.402964 -264.581211) (xy 350.366216 -264.617931) (xy 350.324179 -264.648452) (xy 350.277886 -264.672026)
			(xy 350.228477 -264.68807) (xy 350.177167 -264.696192) (xy 350.151192 -264.696702) (xy 350.125205 -264.696192)
			(xy 350.073872 -264.68806) (xy 350.024443 -264.671998) (xy 349.978135 -264.648402) (xy 349.936089 -264.617852)
			(xy 349.899339 -264.581101) (xy 349.868791 -264.539053) (xy 349.845196 -264.492744) (xy 349.829136 -264.443314)
			(xy 349.821007 -264.391981) (xy 349.820484 -264.365994) (xy 349.820876 -264.343339) (xy 349.8271 -264.298457)
			(xy 349.83939 -264.254844) (xy 349.857514 -264.213315) (xy 349.868998 -264.193782) (xy 349.873421 -264.185775)
			(xy 349.87685 -264.167819) (xy 349.873784 -264.149797) (xy 349.869506 -264.141712) (xy 349.736156 -263.911842)
			(xy 349.731272 -263.904161) (xy 349.717234 -263.892594) (xy 349.700046 -263.886644) (xy 349.690944 -263.886442)
			(xy 349.69069 -263.886442) (xy 349.681292 -263.886696) (xy 349.680784 -263.886696) (xy 349.657642 -263.886294)
			(xy 349.611813 -263.879812) (xy 349.567336 -263.867005) (xy 349.525078 -263.848123) (xy 349.50527 -263.83615)
			(xy 349.497272 -263.831617) (xy 349.479262 -263.827997) (xy 349.461129 -263.830941) (xy 349.452946 -263.835134)
			(xy 348.614492 -264.316464) (xy 348.60103 -264.340848) (xy 348.601538 -264.355072) (xy 348.601792 -264.365994)
			(xy 348.601538 -264.381234) (xy 348.600776 -264.395458) (xy 348.614492 -264.420604) (xy 349.461328 -264.907014)
			(xy 349.489522 -264.906252) (xy 349.50146 -264.898378) (xy 349.521621 -264.885833) (xy 349.56477 -264.866012)
			(xy 349.610306 -264.852551) (xy 349.657297 -264.845725) (xy 349.681038 -264.845292) (xy 349.707023 -264.845804)
			(xy 349.758353 -264.85394) (xy 349.807779 -264.870004) (xy 349.854083 -264.893602) (xy 349.896126 -264.924152)
			(xy 349.932872 -264.960903) (xy 349.963418 -265.00295) (xy 349.987011 -265.049257) (xy 350.003069 -265.098684)
			(xy 350.011199 -265.150015) (xy 350.011199 -265.201985) (xy 350.003069 -265.253316) (xy 349.987011 -265.302743)
			(xy 349.963418 -265.34905) (xy 349.932872 -265.391097) (xy 349.896126 -265.427848) (xy 349.854083 -265.458398)
			(xy 349.807779 -265.481996) (xy 349.758353 -265.49806) (xy 349.707023 -265.506196) (xy 349.681038 -265.506708)
			(xy 349.657864 -265.506321) (xy 349.611969 -265.499857) (xy 349.567425 -265.48705) (xy 349.525106 -265.468151)
			(xy 349.50527 -265.456162) (xy 349.497272 -265.451628) (xy 349.479262 -265.448008) (xy 349.461129 -265.450952)
			(xy 349.452946 -265.455146) (xy 348.614492 -265.936476) (xy 348.60103 -265.96086) (xy 348.601538 -265.975084)
			(xy 348.601792 -265.986006) (xy 348.601538 -266.001246) (xy 348.600776 -266.01547) (xy 348.614492 -266.040616)
			(xy 349.448628 -266.51966) (xy 349.456909 -266.524031) (xy 349.475396 -266.526932) (xy 349.49368 -266.522949)
			(xy 349.501714 -266.518136) (xy 349.52185 -266.505624) (xy 349.564942 -266.485869) (xy 349.610415 -266.472471)
			(xy 349.657335 -266.465705) (xy 349.681038 -266.465304) (xy 349.707023 -266.465816) (xy 349.758352 -266.473952)
			(xy 349.807777 -266.490016) (xy 349.85408 -266.513614) (xy 349.896122 -266.544165) (xy 349.932868 -266.580916)
			(xy 349.963412 -266.622963) (xy 349.987003 -266.669269) (xy 350.00306 -266.718697) (xy 350.011188 -266.770027)
			(xy 350.011746 -266.796012) (xy 350.011263 -266.821643) (xy 350.003352 -266.872292) (xy 349.995998 -266.89685)
			(xy 349.995998 -266.897104) (xy 349.993546 -266.906071) (xy 349.994563 -266.924616) (xy 350.002156 -266.941566)
			(xy 350.008444 -266.948412) (xy 350.258126 -267.198094) (xy 350.265526 -267.204937) (xy 350.284124 -267.212663)
			(xy 350.294194 -267.21308) (xy 350.5708 -267.21308) (xy 350.577468 -267.212886) (xy 350.590344 -267.209416)
			(xy 350.5962 -267.206222) (xy 351.217738 -266.848082) (xy 351.2312 -266.823444) (xy 351.230692 -266.80922)
			(xy 351.230438 -266.796012) (xy 351.23092 -266.770023) (xy 351.23905 -266.718686) (xy 351.255112 -266.669253)
			(xy 351.27871 -266.622941) (xy 351.309263 -266.580892) (xy 351.346018 -266.544141) (xy 351.38807 -266.513592)
			(xy 351.434384 -266.489999) (xy 351.483819 -266.473942) (xy 351.535157 -266.465818) (xy 351.561146 -266.465304)
			(xy 351.573338 -266.465558) (xy 351.582506 -266.465494) (xy 351.599876 -266.459669) (xy 351.614102 -266.448125)
			(xy 351.619058 -266.440412) (xy 351.751138 -266.213082) (xy 351.755461 -266.204947) (xy 351.758543 -266.1868)
			(xy 351.754963 -266.168745) (xy 351.750376 -266.160758) (xy 351.738523 -266.141009) (xy 351.719807 -266.098925)
			(xy 351.707124 -266.054647) (xy 351.700719 -266.009035) (xy 351.700338 -265.986006) (xy 351.700821 -265.960018)
			(xy 351.708952 -265.908681) (xy 351.725014 -265.859249) (xy 351.748612 -265.812938) (xy 351.779165 -265.77089)
			(xy 351.81592 -265.734139) (xy 351.857972 -265.703591) (xy 351.904286 -265.679998) (xy 351.95372 -265.663942)
			(xy 352.005058 -265.655818) (xy 352.031046 -265.655298) (xy 352.057018 -265.65581) (xy 352.108322 -265.663938)
			(xy 352.157724 -265.679988) (xy 352.20401 -265.703564) (xy 352.24604 -265.734087) (xy 352.282781 -265.770806)
			(xy 352.31333 -265.812818) (xy 352.336934 -265.859089) (xy 352.353014 -265.908481) (xy 352.361174 -265.95978)
			(xy 352.361754 -265.985752) (xy 352.361754 -265.98626) (xy 352.3615 -266.001246) (xy 352.360738 -266.01547)
			(xy 352.374454 -266.040616) (xy 353.221036 -266.526772) (xy 353.249484 -266.52601) (xy 353.261422 -266.518136)
			(xy 353.28153 -266.50564) (xy 353.324561 -266.485904) (xy 353.369968 -266.472507) (xy 353.416821 -266.465725)
			(xy 353.440492 -266.465304) (xy 353.441 -266.465304) (xy 353.466989 -266.465787) (xy 353.518327 -266.473918)
			(xy 353.567761 -266.489981) (xy 353.614073 -266.513579) (xy 353.656123 -266.544131) (xy 353.692877 -266.580886)
			(xy 353.723427 -266.622937) (xy 353.747024 -266.669251) (xy 353.763084 -266.718685) (xy 353.771214 -266.770023)
			(xy 353.771708 -266.796012) (xy 353.771708 -266.796266) (xy 353.771295 -266.819781) (xy 353.764627 -266.866335)
			(xy 353.751421 -266.911472) (xy 353.731946 -266.954279) (xy 353.719638 -266.97432) (xy 353.712018 -266.986258)
			(xy 353.711256 -267.014706) (xy 353.848162 -267.250672) (xy 353.853192 -267.258501) (xy 353.86766 -267.270179)
			(xy 353.885341 -267.275931) (xy 353.894644 -267.275818) (xy 353.9109 -267.27531) (xy 353.911408 -267.27531)
			(xy 353.934809 -267.275717) (xy 353.981141 -267.282321) (xy 354.026079 -267.295395) (xy 354.068723 -267.314678)
			(xy 354.0887 -267.326872) (xy 354.100638 -267.334492) (xy 354.128832 -267.335254) (xy 354.9777 -266.847574)
			(xy 354.991162 -266.822936) (xy 354.990654 -266.808712) (xy 354.9904 -266.796012) (xy 354.990882 -266.770022)
			(xy 354.999012 -266.718683) (xy 355.015073 -266.669247) (xy 355.038671 -266.622933) (xy 355.069223 -266.58088)
			(xy 355.105977 -266.544125) (xy 355.148029 -266.513573) (xy 355.194343 -266.489975) (xy 355.243779 -266.473913)
			(xy 355.295118 -266.465783) (xy 355.321108 -266.465304) (xy 355.3333 -266.465558) (xy 355.342462 -266.465484)
			(xy 355.359816 -266.459644) (xy 355.374024 -266.448095) (xy 355.37902 -266.440412) (xy 355.5111 -266.213082)
			(xy 355.515419 -266.204946) (xy 355.518497 -266.1868) (xy 355.514921 -266.168746) (xy 355.510338 -266.160758)
			(xy 355.498486 -266.141009) (xy 355.479772 -266.098924) (xy 355.46709 -266.054646) (xy 355.460687 -266.009035)
			(xy 355.4603 -265.986006) (xy 355.460783 -265.960017) (xy 355.468913 -265.908678) (xy 355.484975 -265.859243)
			(xy 355.508573 -265.81293) (xy 355.539125 -265.770878) (xy 355.575879 -265.734124) (xy 355.617931 -265.703572)
			(xy 355.664245 -265.679974) (xy 355.71368 -265.663913) (xy 355.765019 -265.655783) (xy 355.791008 -265.655298)
			(xy 355.816982 -265.655807) (xy 355.868291 -265.663931) (xy 355.917698 -265.679977) (xy 355.963989 -265.703551)
			(xy 356.006024 -265.734074) (xy 356.04277 -265.770793) (xy 356.073323 -265.812806) (xy 356.096931 -265.85908)
			(xy 356.113013 -265.908476) (xy 356.121174 -265.959778) (xy 356.121716 -265.985752) (xy 356.121716 -265.98626)
			(xy 356.121462 -266.001246) (xy 356.1207 -266.01547) (xy 356.134416 -266.040616) (xy 356.968806 -266.519914)
			(xy 356.97704 -266.524139) (xy 356.995315 -266.526956) (xy 357.013389 -266.523056) (xy 357.021384 -266.51839)
			(xy 357.021638 -266.51839) (xy 357.041798 -266.505843) (xy 357.084947 -266.486019) (xy 357.130483 -266.472555)
			(xy 357.177474 -266.465725) (xy 357.201216 -266.465304) (xy 357.227202 -266.465815) (xy 357.278534 -266.473947)
			(xy 357.327962 -266.49001) (xy 357.374268 -266.513607) (xy 357.416313 -266.544157) (xy 357.453061 -266.580908)
			(xy 357.483608 -266.622956) (xy 357.507201 -266.669264) (xy 357.523259 -266.718693) (xy 357.531387 -266.770026)
			(xy 357.531924 -266.796012) (xy 357.531474 -266.819535) (xy 357.524739 -266.866098) (xy 357.511476 -266.911238)
			(xy 357.491955 -266.954044) (xy 357.4796 -266.974066) (xy 357.4796 -266.974574) (xy 357.474986 -266.982596)
			(xy 357.471284 -267.000712) (xy 357.474282 -267.018959) (xy 357.478584 -267.027152) (xy 357.608124 -267.250672)
			(xy 357.613157 -267.258494) (xy 357.627627 -267.270154) (xy 357.645305 -267.275885) (xy 357.654606 -267.275818)
			(xy 357.670862 -267.27531) (xy 357.67137 -267.27531) (xy 357.694771 -267.275714) (xy 357.741106 -267.282313)
			(xy 357.786047 -267.295383) (xy 357.828694 -267.314662) (xy 357.848662 -267.326872) (xy 357.8606 -267.334492)
			(xy 357.888794 -267.335254) (xy 359.03281 -266.677902) (xy 359.038628 -266.674782) (xy 359.05136 -266.671306)
			(xy 359.057956 -266.671044) (xy 359.74274 -266.671044) (xy 359.748971 -266.670833) (xy 359.761047 -266.66775)
			(xy 359.766616 -266.664948) (xy 359.792992 -266.651372) (xy 359.848351 -266.63005) (xy 359.905907 -266.615681)
			(xy 359.964792 -266.608482) (xy 359.994454 -266.608052) (xy 360.024114 -266.608492) (xy 360.082992 -266.615721)
			(xy 360.140545 -266.630091) (xy 360.195912 -266.651384) (xy 360.222292 -266.664948) (xy 360.227861 -266.667749)
			(xy 360.239937 -266.670831) (xy 360.246168 -266.671044) (xy 361.570524 -266.671044) (xy 361.594654 -266.656312)
			(xy 361.601258 -266.643866) (xy 361.61358 -266.621163) (xy 361.644182 -266.579552) (xy 361.680882 -266.543205)
			(xy 361.722787 -266.513005) (xy 361.768877 -266.489688) (xy 361.818032 -266.47382) (xy 361.869056 -266.465786)
			(xy 361.894882 -266.465304) (xy 361.918665 -266.465738) (xy 361.965736 -266.472595) (xy 362.011338 -266.486128)
			(xy 362.054529 -266.506057) (xy 362.074714 -266.518644) (xy 362.074968 -266.518644) (xy 362.082959 -266.52329)
			(xy 362.10103 -266.527117) (xy 362.119289 -266.524327) (xy 362.127546 -266.520168) (xy 362.961428 -266.041124)
			(xy 362.975144 -266.015978) (xy 362.974382 -266.001754) (xy 362.974128 -265.98626) (xy 362.974128 -265.985752)
			(xy 362.974656 -265.959779) (xy 362.982818 -265.908476) (xy 362.998901 -265.859081) (xy 363.022511 -265.812809)
			(xy 363.053065 -265.770797) (xy 363.089814 -265.734081) (xy 363.131851 -265.703562) (xy 363.178144 -265.679992)
			(xy 363.227553 -265.663951) (xy 363.278862 -265.655834) (xy 363.304836 -265.655298) (xy 363.330821 -265.65581)
			(xy 363.382151 -265.663945) (xy 363.431576 -265.68001) (xy 363.47788 -265.703607) (xy 363.519923 -265.734158)
			(xy 363.556669 -265.770909) (xy 363.587215 -265.812956) (xy 363.610807 -265.859263) (xy 363.626865 -265.90869)
			(xy 363.634993 -265.960021) (xy 363.635544 -265.986006) (xy 363.635152 -266.00892) (xy 363.628814 -266.054309)
			(xy 363.616262 -266.098385) (xy 363.597735 -266.140302) (xy 363.586014 -266.159996) (xy 363.578648 -266.172188)
			(xy 363.57814 -266.199874) (xy 363.71784 -266.440412) (xy 363.722785 -266.448142) (xy 363.737 -266.459725)
			(xy 363.754385 -266.465554) (xy 363.76356 -266.465558) (xy 363.774482 -266.465304) (xy 363.77499 -266.465304)
			(xy 363.800962 -266.465835) (xy 363.852261 -266.474002) (xy 363.901652 -266.490089) (xy 363.94792 -266.5137)
			(xy 363.989928 -266.544255) (xy 364.026641 -266.581002) (xy 364.057158 -266.623038) (xy 364.080727 -266.669328)
			(xy 364.096769 -266.718733) (xy 364.104889 -266.77004) (xy 364.105444 -266.796012) (xy 364.10519 -266.808204)
			(xy 364.104682 -266.822428) (xy 364.118144 -266.846812) (xy 364.96752 -267.335) (xy 364.995714 -267.334238)
			(xy 365.007652 -267.326618) (xy 365.02757 -267.314463) (xy 365.0701 -267.295272) (xy 365.11491 -267.282263)
			(xy 365.161106 -267.275695) (xy 365.184436 -267.27531) (xy 365.18469 -267.27531) (xy 365.201962 -267.275818)
			(xy 365.20247 -267.275818) (xy 365.216694 -267.27658) (xy 365.241586 -267.263118) (xy 365.385096 -267.015468)
			(xy 365.384334 -266.98702) (xy 365.376714 -266.975082) (xy 365.364298 -266.954977) (xy 365.344666 -266.911995)
			(xy 365.33134 -266.86666) (xy 365.32459 -266.819892) (xy 365.324136 -266.796266) (xy 365.324136 -266.796012)
			(xy 365.324618 -266.770023) (xy 365.332748 -266.718686) (xy 365.34881 -266.669253) (xy 365.372408 -266.622941)
			(xy 365.402961 -266.580891) (xy 365.439716 -266.54414) (xy 365.481768 -266.513591) (xy 365.528082 -266.489998)
			(xy 365.577517 -266.473941) (xy 365.628855 -266.465816) (xy 365.654844 -266.465304) (xy 365.678628 -266.465735)
			(xy 365.725701 -266.472588) (xy 365.771306 -266.486116) (xy 365.8145 -266.506041) (xy 365.834676 -266.518644)
			(xy 365.83493 -266.518644) (xy 365.842922 -266.523297) (xy 365.860996 -266.527137) (xy 365.879264 -266.524357)
			(xy 365.887508 -266.520168) (xy 366.72139 -266.041124) (xy 366.735106 -266.015978) (xy 366.734344 -266.001754)
			(xy 366.73409 -265.98626) (xy 366.73409 -265.985752) (xy 366.734618 -265.959778) (xy 366.742779 -265.908473)
			(xy 366.758862 -265.859075) (xy 366.782471 -265.8128) (xy 366.813025 -265.770786) (xy 366.849773 -265.734065)
			(xy 366.89181 -265.703542) (xy 366.938103 -265.679968) (xy 366.987512 -265.663922) (xy 367.038823 -265.655799)
			(xy 367.064798 -265.655298) (xy 367.090787 -265.655781) (xy 367.142126 -265.663912) (xy 367.19156 -265.679974)
			(xy 367.237873 -265.703572) (xy 367.279924 -265.734124) (xy 367.316678 -265.770879) (xy 367.34723 -265.81293)
			(xy 367.370827 -265.859244) (xy 367.386889 -265.908678) (xy 367.395019 -265.960017) (xy 367.395506 -265.986006)
			(xy 367.395114 -266.008921) (xy 367.388778 -266.05431) (xy 367.376227 -266.098387) (xy 367.357704 -266.140306)
			(xy 367.345976 -266.159996) (xy 367.33861 -266.172188) (xy 367.338102 -266.199874) (xy 367.477802 -266.440412)
			(xy 367.48275 -266.448134) (xy 367.496967 -266.4597) (xy 367.51435 -266.465509) (xy 367.523522 -266.465558)
			(xy 367.534444 -266.465304) (xy 367.534952 -266.465304) (xy 367.560926 -266.465832) (xy 367.612229 -266.473994)
			(xy 367.661625 -266.490078) (xy 367.707899 -266.513687) (xy 367.749912 -266.544241) (xy 367.78663 -266.580989)
			(xy 367.817151 -266.623026) (xy 367.840724 -266.669319) (xy 367.856768 -266.718728) (xy 367.864888 -266.770038)
			(xy 367.865406 -266.796012) (xy 367.865152 -266.808204) (xy 367.864644 -266.822428) (xy 367.878106 -266.846812)
			(xy 368.727736 -267.335) (xy 368.75593 -267.334238) (xy 368.767868 -267.326618) (xy 368.787786 -267.314464)
			(xy 368.830317 -267.295275) (xy 368.875127 -267.282268) (xy 368.921322 -267.275703) (xy 368.944652 -267.27531)
			(xy 368.944906 -267.27531) (xy 368.961924 -267.275818) (xy 368.962432 -267.275818) (xy 368.976656 -267.27658)
			(xy 369.001548 -267.263118) (xy 369.145058 -267.015468) (xy 369.144296 -266.98702) (xy 369.136676 -266.975082)
			(xy 369.124257 -266.954978) (xy 369.104622 -266.911996) (xy 369.091294 -266.866661) (xy 369.084542 -266.819893)
			(xy 369.084098 -266.796266) (xy 369.084098 -266.796012) (xy 369.08458 -266.770022) (xy 369.09271 -266.718683)
			(xy 369.108771 -266.669247) (xy 369.132368 -266.622932) (xy 369.162921 -266.58088) (xy 369.199675 -266.544124)
			(xy 369.241727 -266.513572) (xy 369.288041 -266.489974) (xy 369.337477 -266.473911) (xy 369.388816 -266.465781)
			(xy 369.414806 -266.465304) (xy 369.438591 -266.465732) (xy 369.485666 -266.47258) (xy 369.531274 -266.486104)
			(xy 369.574472 -266.506026) (xy 369.594638 -266.518644) (xy 369.594892 -266.518644) (xy 369.602884 -266.523304)
			(xy 369.620963 -266.527157) (xy 369.63924 -266.524388) (xy 369.64747 -266.520168) (xy 370.481352 -266.041124)
			(xy 370.495068 -266.015978) (xy 370.494306 -266.001754) (xy 370.494052 -265.98626) (xy 370.494052 -265.985752)
			(xy 370.49458 -265.959776) (xy 370.502741 -265.90847) (xy 370.518824 -265.85907) (xy 370.542432 -265.812792)
			(xy 370.572985 -265.770774) (xy 370.609732 -265.73405) (xy 370.651769 -265.703523) (xy 370.698062 -265.679944)
			(xy 370.747472 -265.663892) (xy 370.798784 -265.655764) (xy 370.82476 -265.655298) (xy 370.850751 -265.655778)
			(xy 370.902094 -265.663904) (xy 370.951534 -265.679963) (xy 370.997852 -265.703559) (xy 371.039908 -265.734111)
			(xy 371.076667 -265.770866) (xy 371.107223 -265.812919) (xy 371.130824 -265.859235) (xy 371.146888 -265.908673)
			(xy 371.155019 -265.960015) (xy 371.155468 -265.986006) (xy 371.155081 -266.008879) (xy 371.148778 -266.054189)
			(xy 371.136293 -266.098198) (xy 371.117865 -266.140068) (xy 371.106192 -266.159742) (xy 371.101715 -266.167766)
			(xy 371.098199 -266.185787) (xy 371.101215 -266.203899) (xy 371.10543 -266.212066) (xy 371.24513 -266.452604)
			(xy 371.269514 -266.466066) (xy 371.283484 -266.465558) (xy 371.29466 -266.465304) (xy 371.295168 -266.465304)
			(xy 371.321141 -266.465834) (xy 371.372442 -266.473997) (xy 371.421836 -266.490082) (xy 371.468108 -266.513692)
			(xy 371.510118 -266.544247) (xy 371.546835 -266.580995) (xy 371.577354 -266.623031) (xy 371.600925 -266.669323)
			(xy 371.616968 -266.71873) (xy 371.625089 -266.770039) (xy 371.625622 -266.796012) (xy 371.625368 -266.808204)
			(xy 371.625368 -266.808458) (xy 371.62543 -266.817657) (xy 371.631315 -266.83507) (xy 371.642991 -266.849266)
			(xy 371.650768 -266.854178) (xy 372.487698 -267.335) (xy 372.515892 -267.334238) (xy 372.52783 -267.326618)
			(xy 372.547747 -267.314462) (xy 372.590278 -267.295268) (xy 372.635088 -267.282256) (xy 372.681284 -267.275685)
			(xy 372.704614 -267.27531) (xy 372.704868 -267.27531) (xy 372.72214 -267.275818) (xy 372.722648 -267.275818)
			(xy 372.736872 -267.27658) (xy 372.761764 -267.263118) (xy 372.898162 -267.028168) (xy 372.902454 -267.019873)
			(xy 372.90538 -267.001441) (xy 372.901558 -266.983174) (xy 372.896892 -266.975082) (xy 372.884397 -266.954974)
			(xy 372.864663 -266.911942) (xy 372.851268 -266.866535) (xy 372.844486 -266.819682) (xy 372.84406 -266.796012)
			(xy 372.844569 -266.770023) (xy 372.852697 -266.718685) (xy 372.868757 -266.669251) (xy 372.892352 -266.622938)
			(xy 372.922901 -266.580885) (xy 372.959652 -266.544129) (xy 373.0017 -266.513575) (xy 373.048011 -266.489974)
			(xy 373.097443 -266.473908) (xy 373.148779 -266.465772) (xy 373.174768 -266.465304) (xy 373.200595 -266.465799)
			(xy 373.251622 -266.473825) (xy 373.30078 -266.489687) (xy 373.346874 -266.513) (xy 373.388783 -266.543196)
			(xy 373.425487 -266.579541) (xy 373.456093 -266.62115) (xy 373.468392 -266.643866) (xy 373.474996 -266.656312)
			(xy 373.499126 -266.671044) (xy 373.818912 -266.671044) (xy 373.84228 -266.657328) (xy 373.849138 -266.64539)
			(xy 373.86087 -266.625576) (xy 373.889356 -266.589399) (xy 373.922948 -266.557904) (xy 373.960883 -266.531806)
			(xy 374.002305 -266.511694) (xy 374.046275 -266.498023) (xy 374.091799 -266.491104) (xy 374.114822 -266.490704)
			(xy 374.138812 -266.491176) (xy 374.1862 -266.498685) (xy 374.23183 -266.513515) (xy 374.274579 -266.5353)
			(xy 374.313394 -266.563504) (xy 374.347319 -266.597432) (xy 374.375518 -266.63625) (xy 374.397298 -266.679001)
			(xy 374.412123 -266.724633) (xy 374.419626 -266.772022) (xy 374.42013 -266.796012) (xy 374.419586 -266.822236)
			(xy 374.410622 -266.873912) (xy 374.39296 -266.923296) (xy 374.380506 -266.94638) (xy 374.380506 -266.946634)
			(xy 374.376508 -266.954478) (xy 374.373563 -266.971821) (xy 374.376658 -266.989138) (xy 374.38076 -266.996926)
			(xy 374.527826 -267.250164) (xy 374.53276 -267.257923) (xy 374.546962 -267.269581) (xy 374.564353 -267.275509)
			(xy 374.573546 -267.275564) (xy 374.584468 -267.27531) (xy 374.584976 -267.27531) (xy 374.610948 -267.27584)
			(xy 374.662249 -267.284005) (xy 374.711641 -267.300091) (xy 374.757911 -267.323701) (xy 374.79992 -267.354256)
			(xy 374.836635 -267.391004) (xy 374.867152 -267.43304) (xy 374.890722 -267.479331) (xy 374.906764 -267.528738)
			(xy 374.914883 -267.580045) (xy 374.91543 -267.606018) (xy 374.915042 -267.628891) (xy 374.908739 -267.674201)
			(xy 374.896255 -267.71821) (xy 374.877828 -267.760081) (xy 374.866154 -267.779754) (xy 374.861663 -267.787779)
			(xy 374.858121 -267.80581) (xy 374.861111 -267.823941) (xy 374.865392 -267.832078) (xy 375.005092 -268.072616)
			(xy 375.029476 -268.086078) (xy 375.043446 -268.08557) (xy 375.054622 -268.085316) (xy 375.05513 -268.085316)
			(xy 375.081105 -268.085843) (xy 375.13241 -268.094002) (xy 375.181808 -268.110084) (xy 375.228084 -268.133692)
			(xy 375.270099 -268.164246) (xy 375.306819 -268.200995) (xy 375.337341 -268.243033) (xy 375.360914 -268.289327)
			(xy 375.376957 -268.338737) (xy 375.385077 -268.390049) (xy 375.385584 -268.416024) (xy 375.385196 -268.438897)
			(xy 375.378891 -268.484205) (xy 375.366405 -268.528214) (xy 375.347975 -268.570083) (xy 375.336308 -268.58976)
			(xy 375.331815 -268.597784) (xy 375.32827 -268.615815) (xy 375.331265 -268.633947) (xy 375.335546 -268.642084)
			(xy 375.46788 -268.870176) (xy 375.472818 -268.877927) (xy 375.487022 -268.889567) (xy 375.50441 -268.895476)
			(xy 375.5136 -268.895576) (xy 375.524522 -268.895322) (xy 375.52503 -268.895322) (xy 375.551004 -268.895849)
			(xy 375.602309 -268.904008) (xy 375.651707 -268.92009) (xy 375.697983 -268.943698) (xy 375.739997 -268.974253)
			(xy 375.776717 -269.011001) (xy 375.807238 -269.053039) (xy 375.83081 -269.099333) (xy 375.846853 -269.148744)
			(xy 375.854972 -269.200055) (xy 375.855484 -269.22603) (xy 375.854972 -269.252015) (xy 375.846838 -269.303344)
			(xy 375.830774 -269.352769) (xy 375.807176 -269.399073) (xy 375.776625 -269.441115) (xy 375.739874 -269.47786)
			(xy 375.697827 -269.508404) (xy 375.651519 -269.531995) (xy 375.602092 -269.54805) (xy 375.550761 -269.556176)
			(xy 375.524776 -269.556738) (xy 375.51614 -269.556738) (xy 375.50217 -269.55623) (xy 375.477786 -269.569692)
			(xy 375.329958 -269.824708) (xy 375.330212 -269.852648) (xy 375.337578 -269.864332) (xy 375.34896 -269.883796)
			(xy 375.366918 -269.925153) (xy 375.37908 -269.96857) (xy 375.385219 -270.013238) (xy 375.385584 -270.035782)
			(xy 375.385584 -270.036036) (xy 375.385072 -270.062021) (xy 375.376937 -270.113349) (xy 375.360872 -270.162774)
			(xy 375.337274 -270.209076) (xy 375.306723 -270.251118) (xy 375.269972 -270.287862) (xy 375.227925 -270.318405)
			(xy 375.181618 -270.341995) (xy 375.132191 -270.358051) (xy 375.080861 -270.366176) (xy 375.054876 -270.366744)
			(xy 375.04624 -270.366744) (xy 375.03227 -270.366236) (xy 375.007886 -270.379698) (xy 374.866916 -270.622776)
			(xy 374.862666 -270.630769) (xy 374.859555 -270.648588) (xy 374.862868 -270.666371) (xy 374.86717 -270.674338)
			(xy 374.867424 -270.674592) (xy 374.878804 -270.694056) (xy 374.896758 -270.735414) (xy 374.908914 -270.778831)
			(xy 374.915046 -270.823499) (xy 374.91543 -270.846042) (xy 374.915047 -270.868916) (xy 374.908754 -270.91423)
			(xy 374.896278 -270.958245) (xy 374.877859 -271.000122) (xy 374.866154 -271.019778) (xy 374.861668 -271.027803)
			(xy 374.858133 -271.045831) (xy 374.86113 -271.063957) (xy 374.865392 -271.072102) (xy 374.99798 -271.300448)
			(xy 375.00293 -271.308169) (xy 375.017148 -271.319732) (xy 375.034528 -271.325544) (xy 375.0437 -271.325594)
			(xy 375.054622 -271.32534) (xy 375.05513 -271.32534) (xy 375.081104 -271.325867) (xy 375.132408 -271.334027)
			(xy 375.181804 -271.350109) (xy 375.228078 -271.373717) (xy 375.270091 -271.404272) (xy 375.306809 -271.441021)
			(xy 375.337328 -271.483059) (xy 375.360898 -271.529353) (xy 375.376938 -271.578763) (xy 375.385055 -271.630074)
			(xy 375.385584 -271.656048) (xy 375.385201 -271.678922) (xy 375.378906 -271.724235) (xy 375.366428 -271.768249)
			(xy 375.348006 -271.810124) (xy 375.336308 -271.829784) (xy 375.331819 -271.837808) (xy 375.328282 -271.855836)
			(xy 375.331284 -271.873962) (xy 375.335546 -271.882108) (xy 375.46788 -272.1102) (xy 375.47282 -272.117948)
			(xy 375.487025 -272.129583) (xy 375.504411 -272.135488) (xy 375.5136 -272.1356) (xy 375.524522 -272.135346)
			(xy 375.52503 -272.135346) (xy 375.551007 -272.135873) (xy 375.602316 -272.144031) (xy 375.651719 -272.160112)
			(xy 375.698 -272.183719) (xy 375.74002 -272.214273) (xy 375.776747 -272.25102) (xy 375.807277 -272.293057)
			(xy 375.830858 -272.339351) (xy 375.846912 -272.388763) (xy 375.855042 -272.440077) (xy 375.855484 -272.466054)
			(xy 375.855004 -272.492045) (xy 375.846879 -272.543388) (xy 375.83082 -272.592827) (xy 375.807224 -272.639145)
			(xy 375.776673 -272.6812) (xy 375.739917 -272.717958) (xy 375.697863 -272.748513) (xy 375.651547 -272.772112)
			(xy 375.602109 -272.788173) (xy 375.550767 -272.796303) (xy 375.524776 -272.796762) (xy 375.51614 -272.796762)
			(xy 375.50217 -272.796254) (xy 375.477786 -272.809716) (xy 375.329958 -273.064732) (xy 375.330212 -273.092672)
			(xy 375.337578 -273.104356) (xy 375.348958 -273.12382) (xy 375.366914 -273.165178) (xy 375.379072 -273.208595)
			(xy 375.385209 -273.253262) (xy 375.385584 -273.275806) (xy 375.385584 -273.27606) (xy 375.385104 -273.302051)
			(xy 375.376977 -273.353393) (xy 375.360918 -273.402831) (xy 375.337322 -273.449148) (xy 375.30677 -273.491203)
			(xy 375.270015 -273.52796) (xy 375.227962 -273.558514) (xy 375.181646 -273.582112) (xy 375.132208 -273.598174)
			(xy 375.080867 -273.606303) (xy 375.054876 -273.606768) (xy 375.04624 -273.606768) (xy 375.03227 -273.60626)
			(xy 375.007886 -273.619722) (xy 374.866916 -273.8628) (xy 374.862652 -273.870793) (xy 374.859516 -273.888622)
			(xy 374.862808 -273.906424) (xy 374.86717 -273.914362) (xy 374.867424 -273.914616) (xy 374.878802 -273.93408)
			(xy 374.896753 -273.975439) (xy 374.908906 -274.018856) (xy 374.915035 -274.063523) (xy 374.91543 -274.086066)
			(xy 374.915046 -274.10894) (xy 374.908749 -274.154252) (xy 374.896271 -274.198266) (xy 374.877849 -274.240141)
			(xy 374.866154 -274.259802) (xy 374.861672 -274.267827) (xy 374.858146 -274.285852) (xy 374.861149 -274.303972)
			(xy 374.865392 -274.312126) (xy 374.99798 -274.540472) (xy 375.002924 -274.548202) (xy 375.017139 -274.559783)
			(xy 375.034525 -274.565604) (xy 375.0437 -274.565618) (xy 375.054622 -274.565364) (xy 375.05513 -274.565364)
			(xy 375.081106 -274.565891) (xy 375.132415 -274.57405) (xy 375.181816 -274.590131) (xy 375.228096 -274.613738)
			(xy 375.270115 -274.644291) (xy 375.30684 -274.681039) (xy 375.337368 -274.723077) (xy 375.360947 -274.769371)
			(xy 375.376998 -274.818782) (xy 375.385125 -274.870096) (xy 375.385584 -274.896072) (xy 375.385199 -274.918946)
			(xy 375.378901 -274.964257) (xy 375.366421 -275.008269) (xy 375.347996 -275.050142) (xy 375.336308 -275.069808)
			(xy 375.331823 -275.077832) (xy 375.328295 -275.095857) (xy 375.331303 -275.113977) (xy 375.335546 -275.122132)
			(xy 375.46788 -275.350224) (xy 375.472822 -275.357969) (xy 375.487028 -275.369598) (xy 375.504412 -275.375501)
			(xy 375.5136 -275.375624) (xy 375.524522 -275.37537) (xy 375.52503 -275.37537) (xy 375.551006 -275.375897)
			(xy 375.602314 -275.384056) (xy 375.651715 -275.400137) (xy 375.697994 -275.423744) (xy 375.740013 -275.454298)
			(xy 375.776738 -275.491045) (xy 375.807265 -275.533083) (xy 375.830843 -275.579377) (xy 375.846893 -275.628789)
			(xy 375.85502 -275.680102) (xy 375.855484 -275.706078) (xy 375.855003 -275.732068) (xy 375.846874 -275.783408)
			(xy 375.830813 -275.832843) (xy 375.807216 -275.879158) (xy 375.776664 -275.92121) (xy 375.739909 -275.957965)
			(xy 375.697856 -275.988517) (xy 375.651542 -276.012114) (xy 375.602106 -276.028174) (xy 375.550766 -276.036303)
			(xy 375.524776 -276.036786) (xy 375.51614 -276.036786) (xy 375.50217 -276.036278) (xy 375.477786 -276.04974)
			(xy 375.329958 -276.304756) (xy 375.330212 -276.332696) (xy 375.337578 -276.34438) (xy 375.348957 -276.363844)
			(xy 375.366909 -276.405203) (xy 375.379065 -276.448619) (xy 375.385198 -276.493287) (xy 375.385584 -276.51583)
			(xy 375.385584 -276.516084) (xy 375.385102 -276.542073) (xy 375.376973 -276.593413) (xy 375.360912 -276.642848)
			(xy 375.337314 -276.689161) (xy 375.306762 -276.731213) (xy 375.270007 -276.767967) (xy 375.227954 -276.798518)
			(xy 375.18164 -276.822115) (xy 375.132205 -276.838175) (xy 375.080865 -276.846303) (xy 375.054876 -276.846792)
			(xy 375.04624 -276.846792) (xy 375.03227 -276.846284) (xy 375.007886 -276.859746) (xy 374.866916 -277.102824)
			(xy 374.862657 -277.110817) (xy 374.859529 -277.128643) (xy 374.862827 -277.146439) (xy 374.86717 -277.154386)
			(xy 374.867424 -277.15464) (xy 374.878807 -277.174103) (xy 374.896767 -277.21546) (xy 374.90893 -277.258877)
			(xy 374.91507 -277.303546) (xy 374.91543 -277.32609) (xy 374.915044 -277.348963) (xy 374.908744 -277.394275)
			(xy 374.896264 -277.438286) (xy 374.877839 -277.480159) (xy 374.866154 -277.499826) (xy 374.861676 -277.507851)
			(xy 374.858158 -277.525873) (xy 374.861168 -277.543988) (xy 374.865392 -277.55215) (xy 374.99798 -277.780496)
			(xy 375.002926 -277.788223) (xy 375.017142 -277.799799) (xy 375.034526 -277.805617) (xy 375.0437 -277.805642)
			(xy 375.054622 -277.805388) (xy 375.05513 -277.805388) (xy 375.081105 -277.805915) (xy 375.132412 -277.814074)
			(xy 375.181812 -277.830155) (xy 375.22809 -277.853763) (xy 375.270107 -277.884317) (xy 375.30683 -277.921065)
			(xy 375.337355 -277.963103) (xy 375.360932 -278.009397) (xy 375.376979 -278.058808) (xy 375.385103 -278.11012)
			(xy 375.385584 -278.136096) (xy 375.385193 -278.159011) (xy 375.378857 -278.2044) (xy 375.366307 -278.248478)
			(xy 375.347784 -278.290397) (xy 375.336054 -278.310086) (xy 375.328688 -278.32177) (xy 375.328434 -278.34971)
			(xy 375.474992 -278.602694) (xy 375.499376 -278.616156) (xy 375.513346 -278.615648) (xy 375.524522 -278.615394)
			(xy 375.52503 -278.615394) (xy 375.551005 -278.615921) (xy 375.602312 -278.62408) (xy 375.651712 -278.640161)
			(xy 375.697989 -278.663769) (xy 375.740006 -278.694323) (xy 375.776728 -278.731071) (xy 375.807252 -278.773109)
			(xy 375.830828 -278.819403) (xy 375.846874 -278.868814) (xy 375.854998 -278.920126) (xy 375.855484 -278.946102)
			(xy 375.855001 -278.97209) (xy 375.846869 -279.023427) (xy 375.830806 -279.07286) (xy 375.807208 -279.119171)
			(xy 375.776655 -279.161221) (xy 375.739901 -279.197972) (xy 375.697849 -279.228522) (xy 375.651536 -279.252116)
			(xy 375.602102 -279.268175) (xy 375.550765 -279.276303) (xy 375.524776 -279.27681) (xy 375.501975 -279.276426)
			(xy 375.456805 -279.270157) (xy 375.412924 -279.257741) (xy 375.371166 -279.239414) (xy 375.351548 -279.227788)
			(xy 375.33961 -279.220422) (xy 375.311924 -279.219914) (xy 374.458992 -279.70988) (xy 374.445276 -279.734264)
			(xy 374.44553 -279.748234) (xy 374.44553 -279.756108) (xy 374.445143 -279.778981) (xy 374.438841 -279.824291)
			(xy 374.426358 -279.868302) (xy 374.407932 -279.910173) (xy 374.396254 -279.929844) (xy 374.391779 -279.937868)
			(xy 374.388267 -279.955889) (xy 374.391282 -279.973999) (xy 374.395492 -279.982168) (xy 374.527826 -280.21026)
			(xy 374.53276 -280.218019) (xy 374.546961 -280.229678) (xy 374.564353 -280.235607) (xy 374.573546 -280.23566)
			(xy 374.584468 -280.235406) (xy 374.584976 -280.235406) (xy 374.610949 -280.235936) (xy 374.662249 -280.244101)
			(xy 374.711642 -280.260187) (xy 374.757912 -280.283797) (xy 374.799921 -280.314352) (xy 374.836636 -280.3511)
			(xy 374.867155 -280.393136) (xy 374.890725 -280.439427) (xy 374.906767 -280.488833) (xy 374.914887 -280.540141)
			(xy 374.91543 -280.566114) (xy 374.915043 -280.588987) (xy 374.90874 -280.634297) (xy 374.896256 -280.678307)
			(xy 374.87783 -280.720178) (xy 374.866154 -280.73985) (xy 374.861663 -280.747875) (xy 374.858119 -280.765907)
			(xy 374.861107 -280.784039) (xy 374.865392 -280.792174) (xy 374.997726 -281.020266) (xy 375.00266 -281.028025)
			(xy 375.016862 -281.039682) (xy 375.034253 -281.04561) (xy 375.043446 -281.045666) (xy 375.054622 -281.045412)
			(xy 375.05513 -281.045412) (xy 375.081105 -281.045939) (xy 375.13241 -281.054098) (xy 375.181809 -281.07018)
			(xy 375.228085 -281.093788) (xy 375.2701 -281.124342) (xy 375.306821 -281.16109) (xy 375.337343 -281.203129)
			(xy 375.360916 -281.249422) (xy 375.376961 -281.298833) (xy 375.385081 -281.350145) (xy 375.385584 -281.37612)
			(xy 375.385099 -281.402108) (xy 375.376965 -281.453442) (xy 375.360901 -281.502873) (xy 375.337302 -281.549181)
			(xy 375.306749 -281.591228) (xy 375.269995 -281.627978) (xy 375.227944 -281.658525) (xy 375.181632 -281.682118)
			(xy 375.132199 -281.698176) (xy 375.080864 -281.706303) (xy 375.054876 -281.706828) (xy 375.045986 -281.706828)
			(xy 375.03227 -281.70632) (xy 375.007886 -281.719782) (xy 374.866916 -281.96286) (xy 374.862663 -281.970853)
			(xy 374.859547 -281.988674) (xy 374.862855 -282.006461) (xy 374.86717 -282.014422) (xy 374.867424 -282.014676)
			(xy 374.878805 -282.03414) (xy 374.896761 -282.075497) (xy 374.908919 -282.118914) (xy 374.915053 -282.163582)
			(xy 374.91543 -282.186126) (xy 374.915042 -282.208999) (xy 374.908737 -282.254308) (xy 374.896252 -282.298317)
			(xy 374.877825 -282.340187) (xy 374.866154 -282.359862) (xy 374.861665 -282.367887) (xy 374.858125 -282.385917)
			(xy 374.861117 -282.404047) (xy 374.865392 -282.412186) (xy 374.99798 -282.640532) (xy 375.002929 -282.648254)
			(xy 375.017146 -282.659822) (xy 375.034528 -282.665635) (xy 375.0437 -282.665678) (xy 375.054622 -282.665424)
			(xy 375.05513 -282.665424) (xy 375.081104 -282.665951) (xy 375.132409 -282.67411) (xy 375.181807 -282.690192)
			(xy 375.228082 -282.7138) (xy 375.270096 -282.744355) (xy 375.306816 -282.781103) (xy 375.337337 -282.823141)
			(xy 375.360909 -282.869435) (xy 375.376951 -282.918846) (xy 375.38507 -282.970157) (xy 375.385584 -282.996132)
			(xy 375.385195 -283.019005) (xy 375.378889 -283.064313) (xy 375.366402 -283.108321) (xy 375.347972 -283.150189)
			(xy 375.336308 -283.169868) (xy 375.331816 -283.177892) (xy 375.328274 -283.195922) (xy 375.331271 -283.214052)
			(xy 375.335546 -283.222192) (xy 375.46788 -283.450284) (xy 375.472819 -283.458034) (xy 375.487023 -283.469672)
			(xy 375.50441 -283.47558) (xy 375.5136 -283.475684) (xy 375.524522 -283.47543) (xy 375.52503 -283.47543)
			(xy 375.551004 -283.475957) (xy 375.602309 -283.484117) (xy 375.651706 -283.500198) (xy 375.697981 -283.523807)
			(xy 375.739994 -283.554361) (xy 375.776713 -283.59111) (xy 375.807233 -283.633148) (xy 375.830804 -283.679442)
			(xy 375.846846 -283.728852) (xy 375.854964 -283.780163) (xy 375.855484 -283.806138) (xy 375.854972 -283.832123)
			(xy 375.846836 -283.883451) (xy 375.830772 -283.932875) (xy 375.807173 -283.979177) (xy 375.776622 -284.021218)
			(xy 375.739871 -284.057963) (xy 375.697824 -284.088506) (xy 375.651518 -284.112095) (xy 375.602091 -284.128151)
			(xy 375.550761 -284.136276) (xy 375.524776 -284.136846) (xy 375.51614 -284.136846) (xy 375.50217 -284.136338)
			(xy 375.477786 -284.1498) (xy 375.329958 -284.404816) (xy 375.330212 -284.432756) (xy 375.337578 -284.44444)
			(xy 375.348959 -284.463904) (xy 375.366917 -284.505261) (xy 375.379078 -284.548678) (xy 375.385216 -284.593346)
			(xy 375.385584 -284.61589) (xy 375.385584 -284.616144) (xy 375.385071 -284.642128) (xy 375.376935 -284.693456)
			(xy 375.36087 -284.742879) (xy 375.337271 -284.789181) (xy 375.30672 -284.831221) (xy 375.269969 -284.867964)
			(xy 375.227923 -284.898507) (xy 375.181616 -284.922096) (xy 375.13219 -284.938151) (xy 375.08086 -284.946277)
			(xy 375.054876 -284.946852) (xy 375.04624 -284.946852) (xy 375.03227 -284.946344) (xy 375.007886 -284.959806)
			(xy 374.866916 -285.202884) (xy 374.86265 -285.210877) (xy 374.859508 -285.228709) (xy 374.862795 -285.246514)
			(xy 374.86717 -285.254446) (xy 374.867424 -285.2547) (xy 374.878803 -285.274164) (xy 374.896756 -285.315522)
			(xy 374.908911 -285.358939) (xy 374.915042 -285.403607) (xy 374.91543 -285.42615) (xy 374.915047 -285.449024)
			(xy 374.908752 -285.494338) (xy 374.896276 -285.538352) (xy 374.877856 -285.580228) (xy 374.866154 -285.599886)
			(xy 374.861669 -285.607911) (xy 374.858137 -285.625938) (xy 374.861136 -285.644062) (xy 374.865392 -285.65221)
			(xy 374.99798 -285.880556) (xy 375.002931 -285.888276) (xy 375.017149 -285.899838) (xy 375.034529 -285.905648)
			(xy 375.0437 -285.905702) (xy 375.054622 -285.905448) (xy 375.05513 -285.905448) (xy 375.081107 -285.905975)
			(xy 375.132416 -285.914133) (xy 375.181819 -285.930214) (xy 375.228099 -285.953822) (xy 375.27012 -285.984375)
			(xy 375.306846 -286.021122) (xy 375.337376 -286.06316) (xy 375.360957 -286.109454) (xy 375.37701 -286.158865)
			(xy 375.38514 -286.210179) (xy 375.385584 -286.236156) (xy 375.3852 -286.25903) (xy 375.378904 -286.304343)
			(xy 375.366426 -286.348356) (xy 375.348003 -286.39023) (xy 375.336308 -286.409892) (xy 375.331821 -286.417916)
			(xy 375.328287 -286.435943) (xy 375.331291 -286.454067) (xy 375.335546 -286.462216) (xy 375.46788 -286.690054)
			(xy 375.472816 -286.697808) (xy 375.487019 -286.709453) (xy 375.504409 -286.715364) (xy 375.5136 -286.715454)
			(xy 375.524522 -286.7152) (xy 375.52503 -286.7152) (xy 375.551005 -286.715727) (xy 375.602311 -286.723886)
			(xy 375.651711 -286.739967) (xy 375.697988 -286.763575) (xy 375.740004 -286.794129) (xy 375.776725 -286.830877)
			(xy 375.807249 -286.872916) (xy 375.830824 -286.91921) (xy 375.84687 -286.96862) (xy 375.854992 -287.019933)
			(xy 375.855484 -287.045908) (xy 375.855 -287.071896) (xy 375.846868 -287.123232) (xy 375.830805 -287.172664)
			(xy 375.807206 -287.218975) (xy 375.776653 -287.261023) (xy 375.739899 -287.297774) (xy 375.697847 -287.328323)
			(xy 375.651535 -287.351917) (xy 375.602101 -287.367975) (xy 375.550764 -287.376103) (xy 375.524776 -287.376616)
			(xy 375.51614 -287.376616) (xy 375.50217 -287.376362) (xy 375.47804 -287.38957) (xy 375.329958 -287.64484)
			(xy 375.330212 -287.67278) (xy 375.337578 -287.684464) (xy 375.348958 -287.703928) (xy 375.366912 -287.745286)
			(xy 375.37907 -287.788703) (xy 375.385205 -287.833371) (xy 375.385584 -287.855914) (xy 375.385584 -287.856168)
			(xy 375.385103 -287.882158) (xy 375.376976 -287.933499) (xy 375.360916 -287.982937) (xy 375.33732 -288.029252)
			(xy 375.306768 -288.071306) (xy 375.270012 -288.108062) (xy 375.227959 -288.138615) (xy 375.181644 -288.162213)
			(xy 375.132207 -288.178274) (xy 375.080866 -288.186403) (xy 375.054876 -288.186876) (xy 375.04624 -288.186876)
			(xy 375.03227 -288.186368) (xy 375.007886 -288.19983) (xy 374.860058 -288.4551) (xy 374.860312 -288.482532)
			(xy 374.867424 -288.49447) (xy 374.878805 -288.513934) (xy 374.896762 -288.555291) (xy 374.908921 -288.598708)
			(xy 374.915056 -288.643376) (xy 374.91543 -288.66592) (xy 374.915042 -288.688793) (xy 374.908739 -288.734102)
			(xy 374.896254 -288.778112) (xy 374.877827 -288.819982) (xy 374.866154 -288.839656) (xy 374.861664 -288.847681)
			(xy 374.858122 -288.865712) (xy 374.861112 -288.883843) (xy 374.865392 -288.89198) (xy 375.005092 -289.132518)
			(xy 375.029476 -289.14598) (xy 375.043446 -289.145472) (xy 375.054622 -289.145218) (xy 375.05513 -289.145218)
			(xy 375.081105 -289.145745) (xy 375.13241 -289.153904) (xy 375.181808 -289.169986) (xy 375.228084 -289.193594)
			(xy 375.270098 -289.224148) (xy 375.306818 -289.260897) (xy 375.33734 -289.302935) (xy 375.360912 -289.349229)
			(xy 375.376956 -289.39864) (xy 375.385075 -289.449951) (xy 375.385584 -289.475926) (xy 375.385196 -289.498799)
			(xy 375.378891 -289.544107) (xy 375.366404 -289.588116) (xy 375.347974 -289.629984) (xy 375.336308 -289.649662)
			(xy 375.331815 -289.657686) (xy 375.328271 -289.675717) (xy 375.331267 -289.693848) (xy 375.335546 -289.701986)
			(xy 375.46788 -289.930078) (xy 375.472818 -289.937829) (xy 375.487022 -289.949468) (xy 375.50441 -289.955377)
			(xy 375.5136 -289.955478) (xy 375.524522 -289.955224) (xy 375.52503 -289.955224) (xy 375.551004 -289.955751)
			(xy 375.602309 -289.96391) (xy 375.651707 -289.979992) (xy 375.697982 -290.0036) (xy 375.739996 -290.034155)
			(xy 375.776716 -290.070903) (xy 375.807237 -290.112941) (xy 375.830809 -290.159235) (xy 375.846851 -290.208646)
			(xy 375.85497 -290.259957) (xy 375.855484 -290.285932) (xy 375.855095 -290.308805) (xy 375.848789 -290.354113)
			(xy 375.836302 -290.398121) (xy 375.817872 -290.439989) (xy 375.806208 -290.459668) (xy 375.801716 -290.467692)
			(xy 375.798174 -290.485722) (xy 375.801171 -290.503852) (xy 375.805446 -290.511992) (xy 375.93778 -290.740084)
			(xy 375.942719 -290.747834) (xy 375.956923 -290.759472) (xy 375.97431 -290.76538) (xy 375.9835 -290.765484)
			(xy 375.994676 -290.76523) (xy 375.995184 -290.76523) (xy 376.021155 -290.765761) (xy 376.072453 -290.773927)
			(xy 376.121843 -290.790014) (xy 376.168111 -290.813625) (xy 376.210117 -290.844181) (xy 376.246829 -290.880928)
			(xy 376.277343 -290.922964) (xy 376.30091 -290.969255) (xy 376.316948 -291.01866) (xy 376.325064 -291.069966)
			(xy 376.325638 -291.095938) (xy 376.32525 -291.118854) (xy 376.318921 -291.164246) (xy 376.306376 -291.208327)
			(xy 376.287856 -291.250249) (xy 376.276108 -291.269928) (xy 376.268742 -291.281612) (xy 376.268488 -291.309552)
			(xy 376.407934 -291.55009) (xy 376.412871 -291.557845) (xy 376.427074 -291.569494) (xy 376.444463 -291.575416)
			(xy 376.453654 -291.57549) (xy 376.464576 -291.575236) (xy 376.465084 -291.575236) (xy 376.491055 -291.575767)
			(xy 376.542353 -291.583933) (xy 376.591742 -291.60002) (xy 376.638009 -291.623632) (xy 376.680015 -291.654187)
			(xy 376.716726 -291.690935) (xy 376.74724 -291.732971) (xy 376.770806 -291.779261) (xy 376.786843 -291.828667)
			(xy 376.794959 -291.879972) (xy 376.795538 -291.905944) (xy 376.795155 -291.928818) (xy 376.78886 -291.974131)
			(xy 376.776381 -292.018144) (xy 376.757957 -292.060018) (xy 376.746262 -292.07968) (xy 376.741776 -292.087705)
			(xy 376.738241 -292.105733) (xy 376.741239 -292.123858) (xy 376.7455 -292.132004) (xy 376.877834 -292.360096)
			(xy 376.882771 -292.36785) (xy 376.896975 -292.379498) (xy 376.914363 -292.385419) (xy 376.923554 -292.385496)
			(xy 376.934476 -292.385242) (xy 376.934984 -292.385242) (xy 376.960955 -292.385773) (xy 377.012252 -292.393939)
			(xy 377.061642 -292.410026) (xy 377.107908 -292.433638) (xy 377.149913 -292.464193) (xy 377.186624 -292.500941)
			(xy 377.217137 -292.542977) (xy 377.240702 -292.589267) (xy 377.256739 -292.638673) (xy 377.264853 -292.689978)
			(xy 377.265438 -292.71595) (xy 377.265055 -292.738824) (xy 377.258758 -292.784136) (xy 377.246279 -292.828149)
			(xy 377.227855 -292.870023) (xy 377.216162 -292.889686) (xy 377.211677 -292.897711) (xy 377.208144 -292.915738)
			(xy 377.211144 -292.933862) (xy 377.2154 -292.94201) (xy 377.3551 -293.182548) (xy 377.379484 -293.19601)
			(xy 377.393454 -293.195502) (xy 377.40463 -293.195248) (xy 377.405138 -293.195248) (xy 377.430945 -293.195763)
			(xy 377.481928 -293.20382) (xy 377.531039 -293.219701) (xy 377.577086 -293.24302) (xy 377.61895 -293.273212)
			(xy 377.655615 -293.309541) (xy 377.686189 -293.351127) (xy 377.698508 -293.37381) (xy 377.705112 -293.386256)
			(xy 377.729242 -293.400988) (xy 378.02058 -293.400988) (xy 378.04471 -293.386256) (xy 378.051314 -293.37381)
			(xy 378.063638 -293.351108) (xy 378.094242 -293.309499) (xy 378.130943 -293.273153) (xy 378.172847 -293.242954)
			(xy 378.218936 -293.219635) (xy 378.268089 -293.203763) (xy 378.319112 -293.195725) (xy 378.344938 -293.195248)
			(xy 378.370924 -293.19576) (xy 378.422257 -293.203895) (xy 378.471685 -293.219959) (xy 378.517993 -293.243556)
			(xy 378.560039 -293.274106) (xy 378.59679 -293.310856) (xy 378.627341 -293.352902) (xy 378.650939 -293.399209)
			(xy 378.667003 -293.448637) (xy 378.675139 -293.49997) (xy 378.675646 -293.525956) (xy 378.675257 -293.548871)
			(xy 378.668926 -293.594263) (xy 378.656379 -293.638342) (xy 378.637858 -293.680264) (xy 378.626116 -293.699946)
			(xy 378.61875 -293.712138) (xy 378.618242 -293.739824) (xy 378.757942 -293.980362) (xy 378.762892 -293.988085)
			(xy 378.777109 -293.999656) (xy 378.79449 -294.005479) (xy 378.803662 -294.005508) (xy 378.814584 -294.005254)
			(xy 378.815092 -294.005254) (xy 378.841065 -294.005785) (xy 378.892367 -294.013952) (xy 378.941761 -294.030038)
			(xy 378.988032 -294.053649) (xy 379.030044 -294.084203) (xy 379.066762 -294.12095) (xy 379.097284 -294.162985)
			(xy 379.120859 -294.209274) (xy 379.136908 -294.258681) (xy 379.145035 -294.309988) (xy 379.145546 -294.335962)
			(xy 379.145162 -294.358836) (xy 379.138864 -294.404148) (xy 379.126384 -294.44816) (xy 379.107958 -294.490033)
			(xy 379.09627 -294.509698) (xy 379.091786 -294.517722) (xy 379.088257 -294.535749) (xy 379.09126 -294.55387)
			(xy 379.095508 -294.562022) (xy 379.235208 -294.80256) (xy 379.259592 -294.816022) (xy 379.273562 -294.815514)
			(xy 379.284484 -294.81526) (xy 379.284992 -294.81526) (xy 379.310965 -294.815791) (xy 379.362266 -294.823958)
			(xy 379.41166 -294.840044) (xy 379.457931 -294.863655) (xy 379.499942 -294.894209) (xy 379.53666 -294.930956)
			(xy 379.567181 -294.972991) (xy 379.590755 -295.019281) (xy 379.606803 -295.068687) (xy 379.614929 -295.119995)
			(xy 379.615446 -295.145968) (xy 379.615062 -295.168842) (xy 379.608763 -295.214153) (xy 379.596282 -295.258165)
			(xy 379.577856 -295.300037) (xy 379.56617 -295.319704) (xy 379.558804 -295.331642) (xy 379.558296 -295.359328)
			(xy 379.713744 -295.627298) (xy 379.718522 -295.634792) (xy 379.732126 -295.646208) (xy 379.748807 -295.652301)
			(xy 379.757686 -295.652698) (xy 379.758448 -295.652698) (xy 379.784422 -295.653226) (xy 379.835726 -295.661387)
			(xy 379.885123 -295.67747) (xy 379.931398 -295.701079) (xy 379.973412 -295.731634) (xy 380.010132 -295.768381)
			(xy 380.040653 -295.810419) (xy 380.064227 -295.856712) (xy 380.080272 -295.906121) (xy 380.088394 -295.957431)
			(xy 380.088902 -295.983406) (xy 380.088369 -296.009981) (xy 380.079855 -296.062444) (xy 380.063046 -296.112866)
			(xy 380.038379 -296.159945) (xy 380.022862 -296.181526) (xy 380.018194 -296.188267) (xy 380.013014 -296.203813)
			(xy 380.012702 -296.212006) (xy 380.012702 -304.780188) (xy 387.951476 -304.780188) (xy 387.955506 -304.637824)
			(xy 387.967584 -304.495916) (xy 387.987672 -304.354919) (xy 388.015704 -304.215284) (xy 388.051591 -304.077458)
			(xy 388.095218 -303.941884) (xy 388.146445 -303.808995) (xy 388.205108 -303.679216) (xy 388.27102 -303.552965)
			(xy 388.343969 -303.430645) (xy 388.423721 -303.312648) (xy 388.510021 -303.199352) (xy 388.602593 -303.091119)
			(xy 388.701139 -302.988297) (xy 388.805345 -302.891216) (xy 388.914877 -302.800185) (xy 389.029383 -302.715497)
			(xy 389.148497 -302.637422) (xy 389.271837 -302.566212) (xy 389.399008 -302.502093) (xy 389.529604 -302.445272)
			(xy 389.663204 -302.395931) (xy 389.799383 -302.354226) (xy 389.937702 -302.320293) (xy 390.07772 -302.29424)
			(xy 390.218987 -302.27615) (xy 390.361052 -302.266081) (xy 390.503459 -302.264066) (xy 390.645752 -302.27011)
			(xy 390.787474 -302.284196) (xy 390.928173 -302.306276) (xy 391.067398 -302.336281) (xy 391.204702 -302.374115)
			(xy 391.339645 -302.419656) (xy 391.471796 -302.472759) (xy 391.600731 -302.533253) (xy 391.726037 -302.600944)
			(xy 391.847313 -302.675617) (xy 391.964169 -302.757031) (xy 392.076233 -302.844925) (xy 392.183145 -302.939019)
			(xy 392.284562 -303.039011) (xy 392.380159 -303.14458) (xy 392.469631 -303.255389) (xy 392.55269 -303.371082)
			(xy 392.629071 -303.491289) (xy 392.698529 -303.615624) (xy 392.760842 -303.74369) (xy 392.815809 -303.875077)
			(xy 392.863255 -304.009362) (xy 392.903028 -304.146117) (xy 392.935 -304.284903) (xy 392.95907 -304.425275)
			(xy 392.975159 -304.566785) (xy 392.983216 -304.708977) (xy 392.98372 -304.780188) (xy 392.983216 -304.851399)
			(xy 392.975159 -304.993591) (xy 392.95907 -305.135101) (xy 392.935 -305.275473) (xy 392.903028 -305.414259)
			(xy 392.863255 -305.551014) (xy 392.815809 -305.685299) (xy 392.760842 -305.816686) (xy 392.698529 -305.944752)
			(xy 392.629071 -306.069087) (xy 392.55269 -306.189294) (xy 392.469631 -306.304987) (xy 392.380159 -306.415796)
			(xy 392.284562 -306.521365) (xy 392.183145 -306.621357) (xy 392.076233 -306.715451) (xy 391.964169 -306.803345)
			(xy 391.847313 -306.884759) (xy 391.726037 -306.959432) (xy 391.600731 -307.027123) (xy 391.471796 -307.087617)
			(xy 391.339645 -307.14072) (xy 391.204702 -307.186261) (xy 391.067398 -307.224095) (xy 390.928173 -307.2541)
			(xy 390.787474 -307.27618) (xy 390.645752 -307.290266) (xy 390.503459 -307.29631) (xy 390.361052 -307.294295)
			(xy 390.218987 -307.284226) (xy 390.07772 -307.266136) (xy 389.937702 -307.240083) (xy 389.799383 -307.20615)
			(xy 389.663204 -307.164445) (xy 389.529604 -307.115104) (xy 389.399008 -307.058283) (xy 389.271837 -306.994164)
			(xy 389.148497 -306.922954) (xy 389.029383 -306.844879) (xy 388.914877 -306.760191) (xy 388.805345 -306.66916)
			(xy 388.701139 -306.572079) (xy 388.602593 -306.469257) (xy 388.510021 -306.361024) (xy 388.423721 -306.247728)
			(xy 388.343969 -306.129731) (xy 388.27102 -306.007411) (xy 388.205108 -305.88116) (xy 388.146445 -305.751381)
			(xy 388.095218 -305.618492) (xy 388.051591 -305.482918) (xy 388.015704 -305.345092) (xy 387.987672 -305.205457)
			(xy 387.967584 -305.06446) (xy 387.955506 -304.922552) (xy 387.951476 -304.780188) (xy 380.012702 -304.780188)
			(xy 380.012702 -327.47458) (xy 380.01314 -327.484644) (xy 380.020875 -327.503227) (xy 380.027688 -327.510648)
			(xy 391.08126 -338.56422) (xy 391.088658 -338.571066) (xy 391.107257 -338.578791) (xy 391.117328 -338.579206)
			(xy 407.750518 -338.579206) (xy 407.761731 -338.578604) (xy 407.782025 -338.569052) (xy 407.796357 -338.551799)
			(xy 407.799794 -338.541106) (xy 407.80714 -338.513876) (xy 407.825318 -338.46048) (xy 407.836116 -338.434426)
			(xy 407.839629 -338.424813) (xy 407.839503 -338.404366) (xy 407.835862 -338.394802) (xy 407.821325 -338.35936)
			(xy 407.798598 -338.2862) (xy 407.783312 -338.211132) (xy 407.77562 -338.13491) (xy 407.775156 -338.096606)
			(xy 407.775645 -338.057935) (xy 407.78347 -337.98099) (xy 407.799039 -337.905231) (xy 407.822192 -337.831436)
			(xy 407.852692 -337.760362) (xy 407.890227 -337.692739) (xy 407.93441 -337.629259) (xy 407.984788 -337.570575)
			(xy 408.040845 -337.517289) (xy 408.102005 -337.469948) (xy 408.167641 -337.429037) (xy 408.237079 -337.394976)
			(xy 408.309606 -337.368114) (xy 408.384479 -337.348729) (xy 408.460929 -337.337017) (xy 408.538172 -337.3331)
			(xy 408.615415 -337.337017) (xy 408.691865 -337.348729) (xy 408.766738 -337.368114) (xy 408.839265 -337.394976)
			(xy 408.908703 -337.429037) (xy 408.974339 -337.469948) (xy 409.035499 -337.517289) (xy 409.091556 -337.570575)
			(xy 409.141934 -337.629259) (xy 409.186117 -337.692739) (xy 409.223652 -337.760362) (xy 409.254152 -337.831436)
			(xy 409.277305 -337.905231) (xy 409.292874 -337.98099) (xy 409.300699 -338.057935) (xy 409.301188 -338.096606)
			(xy 409.300721 -338.134911) (xy 409.293047 -338.211136) (xy 409.277769 -338.286207) (xy 409.255039 -338.359368)
			(xy 409.240482 -338.394802) (xy 409.236874 -338.404372) (xy 409.236748 -338.424808) (xy 409.240228 -338.434426)
			(xy 409.251033 -338.460478) (xy 409.269211 -338.513874) (xy 409.27655 -338.541106) (xy 409.279918 -338.55183)
			(xy 409.294256 -338.569105) (xy 409.314598 -338.578601) (xy 409.325826 -338.579206) (xy 413.300418 -338.579206)
			(xy 413.325374 -338.579819) (xy 413.374326 -338.58956) (xy 413.420437 -338.608664) (xy 413.461935 -338.636396)
			(xy 413.479996 -338.653628) (xy 416.40252 -341.576152) (xy 416.409917 -341.583001) (xy 416.428516 -341.590735)
			(xy 416.438588 -341.591138)
		)
		(stroke
			(width 0)
			(type solid)
		)
		(fill yes)
		(layer "In9.Cu")
		(net "PVDD11_S3_P0")
	)
	(gr_poly
		(pts
			(xy 391.808208 -193.488564) (xy 391.816551 -193.48827) (xy 391.832363 -193.482948) (xy 391.839196 -193.47815)
			(xy 391.861462 -193.461766) (xy 391.909783 -193.434913) (xy 391.961475 -193.415319) (xy 392.015454 -193.403396)
			(xy 392.07059 -193.399394) (xy 392.125726 -193.403396) (xy 392.179705 -193.415319) (xy 392.231397 -193.434913)
			(xy 392.279718 -193.461766) (xy 392.301984 -193.47815) (xy 392.308842 -193.48323) (xy 392.324336 -193.488564)
			(xy 392.451844 -193.488564) (xy 392.467338 -193.48323) (xy 392.474196 -193.47815) (xy 392.496462 -193.461766)
			(xy 392.544783 -193.434913) (xy 392.596475 -193.415319) (xy 392.650454 -193.403396) (xy 392.70559 -193.399394)
			(xy 392.760726 -193.403396) (xy 392.814705 -193.415319) (xy 392.866397 -193.434913) (xy 392.914718 -193.461766)
			(xy 392.936984 -193.47815) (xy 392.943827 -193.482922) (xy 392.959635 -193.488218) (xy 392.967972 -193.488564)
			(xy 393.120372 -193.488564) (xy 393.130436 -193.488127) (xy 393.149018 -193.48039) (xy 393.15644 -193.473578)
			(xy 393.369546 -193.260472) (xy 393.376394 -193.253074) (xy 393.384126 -193.234476) (xy 393.384532 -193.224404)
			(xy 393.384532 -188.789564) (xy 393.385107 -188.764605) (xy 393.394853 -188.715648) (xy 393.413963 -188.669533)
			(xy 393.441703 -188.628033) (xy 393.458954 -188.609986) (xy 394.093954 -187.974986) (xy 394.111994 -187.957725)
			(xy 394.153488 -187.929967) (xy 394.199606 -187.910853) (xy 394.248571 -187.901121) (xy 394.273532 -187.900564)
			(xy 394.389864 -187.900564) (xy 394.401462 -187.90006) (xy 394.42236 -187.890005) (xy 394.429996 -187.88126)
			(xy 394.448176 -187.858929) (xy 394.490116 -187.819475) (xy 394.537511 -187.786774) (xy 394.589283 -187.76157)
			(xy 394.644256 -187.744436) (xy 394.70118 -187.73576) (xy 394.72997 -187.73521) (xy 394.757338 -187.735687)
			(xy 394.811511 -187.74352) (xy 394.864009 -187.759015) (xy 394.913753 -187.781854) (xy 394.959722 -187.811568)
			(xy 394.980668 -187.82919) (xy 394.98778 -187.835286) (xy 395.004798 -187.841636) (xy 395.090142 -187.841636)
			(xy 395.10716 -187.835286) (xy 395.114272 -187.82919) (xy 395.135203 -187.811547) (xy 395.181169 -187.781818)
			(xy 395.230916 -187.758972) (xy 395.283419 -187.743478) (xy 395.337599 -187.735656) (xy 395.36497 -187.73521)
			(xy 395.39376 -187.735755) (xy 395.450681 -187.744444) (xy 395.505651 -187.761585) (xy 395.557423 -187.786788)
			(xy 395.604822 -187.819481) (xy 395.646772 -187.858924) (xy 395.664944 -187.88126) (xy 395.672572 -187.890016)
			(xy 395.693474 -187.900076) (xy 395.705076 -187.900564) (xy 399.862294 -187.900564) (xy 399.872364 -187.900141)
			(xy 399.890967 -187.892424) (xy 399.898362 -187.885578) (xy 401.624546 -186.159394) (xy 401.631397 -186.151998)
			(xy 401.639138 -186.133399) (xy 401.639532 -186.123326) (xy 401.639532 -181.169564) (xy 401.640107 -181.144605)
			(xy 401.649853 -181.095648) (xy 401.668963 -181.049533) (xy 401.696703 -181.008033) (xy 401.713954 -180.989986)
			(xy 403.364954 -179.338986) (xy 403.382994 -179.321725) (xy 403.424488 -179.293967) (xy 403.470606 -179.274853)
			(xy 403.519571 -179.265121) (xy 403.544532 -179.264564) (xy 406.974294 -179.264564) (xy 406.984364 -179.264141)
			(xy 407.002967 -179.256424) (xy 407.010362 -179.249578) (xy 411.746954 -174.512986) (xy 411.764994 -174.495725)
			(xy 411.806488 -174.467967) (xy 411.852606 -174.448853) (xy 411.901571 -174.439121) (xy 411.926532 -174.438564)
			(xy 417.9062 -174.438564) (xy 417.916219 -174.438144) (xy 417.934729 -174.430473) (xy 417.948893 -174.416299)
			(xy 417.956551 -174.397783) (xy 417.957 -174.387764) (xy 417.957 -163.063174) (xy 417.956521 -163.053209)
			(xy 417.948944 -163.034774) (xy 417.942268 -163.02736) (xy 417.923466 -163.007768) (xy 417.891029 -162.964221)
			(xy 417.865095 -162.916515) (xy 417.846188 -162.865613) (xy 417.83469 -162.812544) (xy 417.830833 -162.758382)
			(xy 417.834695 -162.704219) (xy 417.846199 -162.651152) (xy 417.865111 -162.600252) (xy 417.891049 -162.552548)
			(xy 417.92349 -162.509004) (xy 417.942268 -162.489388) (xy 417.94938 -162.482022) (xy 417.957 -162.463988)
			(xy 417.957 -162.407346) (xy 417.94938 -162.389312) (xy 417.942268 -162.381946) (xy 417.923467 -162.362354)
			(xy 417.891032 -162.318808) (xy 417.8651 -162.271102) (xy 417.846195 -162.220201) (xy 417.834698 -162.167133)
			(xy 417.830843 -162.112972) (xy 417.834706 -162.058811) (xy 417.846211 -162.005745) (xy 417.865124 -161.954847)
			(xy 417.891063 -161.907145) (xy 417.923504 -161.863603) (xy 417.942268 -161.843974) (xy 417.949009 -161.836603)
			(xy 417.956597 -161.818141) (xy 417.957 -161.80816) (xy 417.957 -159.349186) (xy 417.956574 -159.339117)
			(xy 417.948856 -159.320516) (xy 417.942014 -159.313118) (xy 417.48583 -158.856934) (xy 417.478429 -158.850095)
			(xy 417.459831 -158.842381) (xy 417.449762 -158.841948) (xy 415.116772 -158.841948) (xy 415.105146 -158.842512)
			(xy 415.08424 -158.852692) (xy 415.07664 -158.861506) (xy 415.059866 -158.882147) (xy 415.021549 -158.919035)
			(xy 414.978479 -158.950242) (xy 414.931493 -158.975166) (xy 414.8815 -158.993321) (xy 414.82947 -159.004357)
			(xy 414.776412 -159.00806) (xy 414.723354 -159.004357) (xy 414.671324 -158.993321) (xy 414.621331 -158.975166)
			(xy 414.574345 -158.950242) (xy 414.531275 -158.919035) (xy 414.492958 -158.882147) (xy 414.476184 -158.861506)
			(xy 414.468599 -158.852665) (xy 414.447688 -158.842455) (xy 414.436052 -158.841948) (xy 396.72895 -158.841948)
			(xy 396.718885 -158.842382) (xy 396.700298 -158.850114) (xy 396.692882 -158.856934) (xy 393.847828 -161.701988)
			(xy 409.929076 -161.701988) (xy 409.92965 -161.657219) (xy 409.938657 -161.568134) (xy 409.956559 -161.480403)
			(xy 409.983175 -161.394911) (xy 410.000196 -161.3535) (xy 410.00377 -161.343912) (xy 410.003765 -161.323466)
			(xy 410.000196 -161.313876) (xy 409.983153 -161.272472) (xy 409.956521 -161.186983) (xy 409.938618 -161.099248)
			(xy 409.929627 -161.010159) (xy 409.929076 -160.965388) (xy 409.92965 -160.920619) (xy 409.938657 -160.831534)
			(xy 409.956559 -160.743803) (xy 409.983175 -160.658311) (xy 410.000196 -160.6169) (xy 410.00377 -160.607312)
			(xy 410.003765 -160.586866) (xy 410.000196 -160.577276) (xy 409.983153 -160.535872) (xy 409.956521 -160.450383)
			(xy 409.938618 -160.362648) (xy 409.929627 -160.273559) (xy 409.929076 -160.228788) (xy 409.929541 -160.187678)
			(xy 409.93713 -160.105808) (xy 409.952241 -160.024988) (xy 409.974747 -159.945907) (xy 410.004454 -159.869241)
			(xy 410.041109 -159.795643) (xy 410.0844 -159.725742) (xy 410.133957 -159.660134) (xy 410.189357 -159.59938)
			(xy 410.250127 -159.543997) (xy 410.315748 -159.494459) (xy 410.385662 -159.451187) (xy 410.45927 -159.414553)
			(xy 410.535944 -159.384867) (xy 410.615031 -159.362384) (xy 410.695856 -159.347295) (xy 410.777728 -159.339729)
			(xy 410.818838 -159.33928) (xy 410.86045 -159.339758) (xy 410.943312 -159.347505) (xy 411.025087 -159.362965)
			(xy 411.105058 -159.386002) (xy 411.182525 -159.416415) (xy 411.25681 -159.453937) (xy 411.292294 -159.475678)
			(xy 411.301404 -159.480786) (xy 411.32205 -159.48383) (xy 411.342214 -159.478449) (xy 411.350714 -159.472376)
			(xy 411.384386 -159.446424) (xy 411.455825 -159.400332) (xy 411.531336 -159.361265) (xy 411.610229 -159.329579)
			(xy 411.691785 -159.305563) (xy 411.77526 -159.289436) (xy 411.859893 -159.281346) (xy 411.902402 -159.28086)
			(xy 411.943509 -159.281311) (xy 412.025374 -159.288895) (xy 412.106189 -159.304) (xy 412.185267 -159.326496)
			(xy 412.261931 -159.356191) (xy 412.33553 -159.392831) (xy 412.405434 -159.436106) (xy 412.471048 -159.485644)
			(xy 412.531813 -159.541025) (xy 412.587209 -159.601775) (xy 412.636764 -159.667376) (xy 412.680057 -159.737269)
			(xy 412.716716 -159.810858) (xy 412.746431 -159.887515) (xy 412.768947 -159.966587) (xy 412.784073 -160.047398)
			(xy 412.791679 -160.129261) (xy 412.792164 -160.170368) (xy 412.791606 -160.215138) (xy 412.782594 -160.304223)
			(xy 412.764688 -160.391954) (xy 412.738068 -160.477445) (xy 412.721044 -160.518856) (xy 412.717498 -160.528452)
			(xy 412.717487 -160.548889) (xy 412.721044 -160.55848) (xy 412.736814 -160.596795) (xy 412.762031 -160.675727)
			(xy 412.779794 -160.756662) (xy 412.78995 -160.8389) (xy 412.791656 -160.880298) (xy 412.792499 -160.891219)
			(xy 412.802145 -160.910859) (xy 412.819062 -160.924738) (xy 412.829502 -160.92805) (xy 412.846374 -160.932547)
			(xy 412.879785 -160.942711) (xy 412.896304 -160.94837) (xy 412.9045 -160.950893) (xy 412.921636 -160.950893)
			(xy 412.929832 -160.94837) (xy 412.96505 -160.936429) (xy 413.037059 -160.91784) (xy 413.110382 -160.905398)
			(xy 413.184492 -160.899192) (xy 413.221678 -160.89884) (xy 413.258862 -160.899213) (xy 413.33297 -160.905434)
			(xy 413.40629 -160.917875) (xy 413.478301 -160.936448) (xy 413.513524 -160.94837) (xy 413.52172 -160.950893)
			(xy 413.538856 -160.950893) (xy 413.547052 -160.94837) (xy 413.582277 -160.936451) (xy 413.654284 -160.917856)
			(xy 413.727604 -160.905408) (xy 413.801713 -160.899196) (xy 413.838898 -160.89884) (xy 413.880822 -160.899407)
			(xy 413.964291 -160.907377) (xy 414.046623 -160.923245) (xy 414.127075 -160.946868) (xy 414.204917 -160.978031)
			(xy 414.279444 -161.016452) (xy 414.349982 -161.061784) (xy 414.415891 -161.113615) (xy 414.476575 -161.171477)
			(xy 414.531484 -161.234845) (xy 414.580121 -161.303146) (xy 414.622045 -161.37576) (xy 414.656876 -161.452031)
			(xy 414.684301 -161.531268) (xy 414.704068 -161.612752) (xy 414.716001 -161.695747) (xy 414.719991 -161.7795)
			(xy 414.716001 -161.863253) (xy 414.704068 -161.946248) (xy 414.684301 -162.027732) (xy 414.656876 -162.106969)
			(xy 414.622045 -162.18324) (xy 414.580121 -162.255854) (xy 414.531484 -162.324155) (xy 414.476575 -162.387523)
			(xy 414.415891 -162.445385) (xy 414.349982 -162.497216) (xy 414.279444 -162.542548) (xy 414.204917 -162.580969)
			(xy 414.127075 -162.612132) (xy 414.046623 -162.635755) (xy 413.964291 -162.651623) (xy 413.880822 -162.659593)
			(xy 413.838898 -162.660076) (xy 413.801714 -162.659709) (xy 413.727606 -162.653487) (xy 413.654286 -162.641044)
			(xy 413.582275 -162.622469) (xy 413.547052 -162.610546) (xy 413.538856 -162.608023) (xy 413.52172 -162.608023)
			(xy 413.513524 -162.610546) (xy 413.484703 -162.620382) (xy 413.425976 -162.636526) (xy 413.396176 -162.642804)
			(xy 413.386613 -162.645219) (xy 413.370195 -162.656115) (xy 413.359083 -162.672387) (xy 413.356552 -162.68192)
			(xy 413.346352 -162.726278) (xy 413.318104 -162.812809) (xy 413.300164 -162.85464) (xy 413.296347 -162.864579)
			(xy 413.296353 -162.885846) (xy 413.300164 -162.895788) (xy 413.318411 -162.938449) (xy 413.346955 -163.026742)
			(xy 413.366147 -163.117527) (xy 413.37578 -163.209818) (xy 413.376364 -163.256214) (xy 413.37586 -163.298562)
			(xy 413.367809 -163.382876) (xy 413.35178 -163.466042) (xy 413.327919 -163.547309) (xy 413.29644 -163.625939)
			(xy 413.257629 -163.70122) (xy 413.211839 -163.772472) (xy 413.159483 -163.839048) (xy 413.101035 -163.900346)
			(xy 413.037025 -163.955811) (xy 412.968033 -164.00494) (xy 412.894683 -164.047289) (xy 412.81764 -164.082473)
			(xy 412.737601 -164.110175) (xy 412.655292 -164.130143) (xy 412.571457 -164.142196) (xy 412.486856 -164.146227)
			(xy 412.402255 -164.142196) (xy 412.31842 -164.130143) (xy 412.236111 -164.110175) (xy 412.156072 -164.082473)
			(xy 412.079029 -164.047289) (xy 412.005679 -164.00494) (xy 411.936687 -163.955811) (xy 411.872677 -163.900346)
			(xy 411.814229 -163.839048) (xy 411.761873 -163.772472) (xy 411.716083 -163.70122) (xy 411.677272 -163.625939)
			(xy 411.645793 -163.547309) (xy 411.621932 -163.466042) (xy 411.605903 -163.382876) (xy 411.597852 -163.298562)
			(xy 411.597348 -163.256214) (xy 411.597931 -163.209818) (xy 411.607575 -163.11753) (xy 411.626771 -163.026746)
			(xy 411.65531 -162.938453) (xy 411.673548 -162.895788) (xy 411.677348 -162.885844) (xy 411.677353 -162.864582)
			(xy 411.673548 -162.85464) (xy 411.655311 -162.811974) (xy 411.626764 -162.723684) (xy 411.607569 -162.632899)
			(xy 411.597934 -162.54061) (xy 411.597348 -162.494214) (xy 411.597953 -162.446404) (xy 411.608131 -162.351329)
			(xy 411.617668 -162.304476) (xy 411.61964 -162.292071) (xy 411.612727 -162.267957) (xy 411.60446 -162.258502)
			(xy 411.56382 -162.216338) (xy 411.560264 -162.2171) (xy 411.551448 -162.219368) (xy 411.536098 -162.229138)
			(xy 411.530292 -162.23615) (xy 411.505142 -162.268826) (xy 411.44974 -162.329904) (xy 411.388921 -162.38559)
			(xy 411.323208 -162.435407) (xy 411.253166 -162.478927) (xy 411.179396 -162.515776) (xy 411.102531 -162.545637)
			(xy 411.023231 -162.568254) (xy 410.942179 -162.583432) (xy 410.860069 -162.591042) (xy 410.818838 -162.591496)
			(xy 410.777733 -162.590951) (xy 410.695873 -162.583371) (xy 410.615061 -162.568271) (xy 410.535987 -162.54578)
			(xy 410.459325 -162.516091) (xy 410.385729 -162.479456) (xy 410.315826 -162.436187) (xy 410.250213 -162.386655)
			(xy 410.18945 -162.331281) (xy 410.134053 -162.270538) (xy 410.084497 -162.204943) (xy 410.041203 -162.135056)
			(xy 410.004541 -162.061473) (xy 409.974824 -161.984822) (xy 409.952304 -161.905756) (xy 409.937174 -161.82495)
			(xy 409.929564 -161.743093) (xy 409.929076 -161.701988) (xy 393.847828 -161.701988) (xy 389.163052 -166.386764)
			(xy 389.14501 -166.404022) (xy 389.103516 -166.431776) (xy 389.057398 -166.450887) (xy 389.008435 -166.460618)
			(xy 388.983474 -166.461186) (xy 375.76506 -166.461186) (xy 375.740105 -166.460571) (xy 375.691156 -166.450826)
			(xy 375.645048 -166.431719) (xy 375.603553 -166.403984) (xy 375.585482 -166.386764) (xy 372.757446 -163.558728)
			(xy 372.750046 -163.551887) (xy 372.731447 -163.544168) (xy 372.721378 -163.543742) (xy 371.644926 -163.543742)
			(xy 371.633257 -163.544309) (xy 371.612329 -163.554628) (xy 371.604794 -163.563554) (xy 371.548152 -163.63696)
			(xy 371.54358 -163.659566) (xy 371.546628 -163.67125) (xy 371.556021 -163.708401) (xy 371.569135 -163.783907)
			(xy 371.575699 -163.860262) (xy 371.576092 -163.89858) (xy 371.575687 -163.936863) (xy 371.569125 -164.013146)
			(xy 371.556038 -164.088585) (xy 371.536524 -164.162622) (xy 371.524022 -164.198808) (xy 371.521369 -164.207245)
			(xy 371.521362 -164.224918) (xy 371.524022 -164.233352) (xy 371.536558 -164.269528) (xy 371.556087 -164.343564)
			(xy 371.56917 -164.419007) (xy 371.575711 -164.495295) (xy 371.576092 -164.53358) (xy 371.575689 -164.571359)
			(xy 371.569283 -164.646646) (xy 371.556523 -164.721119) (xy 371.537501 -164.794244) (xy 371.525292 -164.829998)
			(xy 371.522635 -164.838727) (xy 371.523012 -164.856957) (xy 371.526054 -164.865558) (xy 371.541111 -164.904826)
			(xy 371.564617 -164.98558) (xy 371.580393 -165.068193) (xy 371.588299 -165.151927) (xy 371.588792 -165.19398)
			(xy 371.588333 -165.235083) (xy 371.580749 -165.31694) (xy 371.565645 -165.397747) (xy 371.543149 -165.476817)
			(xy 371.513454 -165.553473) (xy 371.476812 -165.627062) (xy 371.433536 -165.696956) (xy 371.383996 -165.762559)
			(xy 371.328613 -165.823311) (xy 371.267862 -165.878693) (xy 371.202259 -165.928234) (xy 371.132365 -165.97151)
			(xy 371.058776 -166.008152) (xy 370.98212 -166.037848) (xy 370.903051 -166.060344) (xy 370.822244 -166.075449)
			(xy 370.740387 -166.083033) (xy 370.699284 -166.083488) (xy 370.65452 -166.082959) (xy 370.565439 -166.074019)
			(xy 370.477706 -166.056182) (xy 370.392207 -166.029628) (xy 370.350796 -166.012622) (xy 370.341205 -166.009057)
			(xy 370.320763 -166.009057) (xy 370.311172 -166.012622) (xy 370.269758 -166.029622) (xy 370.184263 -166.056187)
			(xy 370.09653 -166.074023) (xy 370.007448 -166.08295) (xy 369.962684 -166.083488) (xy 369.924401 -166.083086)
			(xy 369.848116 -166.076529) (xy 369.772675 -166.063447) (xy 369.698636 -166.043938) (xy 369.662456 -166.031418)
			(xy 369.654019 -166.028767) (xy 369.636349 -166.028767) (xy 369.627912 -166.031418) (xy 369.591737 -166.043957)
			(xy 369.517701 -166.063491) (xy 369.442258 -166.07658) (xy 369.365969 -166.083126) (xy 369.327684 -166.083488)
			(xy 369.289401 -166.083086) (xy 369.213116 -166.076529) (xy 369.137675 -166.063447) (xy 369.063636 -166.043938)
			(xy 369.027456 -166.031418) (xy 369.019019 -166.028767) (xy 369.001349 -166.028767) (xy 368.992912 -166.031418)
			(xy 368.956737 -166.043957) (xy 368.882701 -166.063491) (xy 368.807258 -166.07658) (xy 368.730969 -166.083126)
			(xy 368.692684 -166.083488) (xy 368.654401 -166.083086) (xy 368.578116 -166.076529) (xy 368.502675 -166.063447)
			(xy 368.428636 -166.043938) (xy 368.392456 -166.031418) (xy 368.384019 -166.028767) (xy 368.366349 -166.028767)
			(xy 368.357912 -166.031418) (xy 368.321737 -166.043957) (xy 368.247701 -166.063491) (xy 368.172258 -166.07658)
			(xy 368.095969 -166.083126) (xy 368.057684 -166.083488) (xy 368.017471 -166.08305) (xy 367.937372 -166.075813)
			(xy 367.858251 -166.061382) (xy 367.780755 -166.039874) (xy 367.742978 -166.026084) (xy 367.734191 -166.023177)
			(xy 367.715697 -166.023177) (xy 367.70691 -166.026084) (xy 367.669135 -166.039882) (xy 367.591641 -166.061404)
			(xy 367.51252 -166.075836) (xy 367.432418 -166.083058) (xy 367.392204 -166.083488) (xy 367.353921 -166.083082)
			(xy 367.277638 -166.076519) (xy 367.2022 -166.063431) (xy 367.128164 -166.043916) (xy 367.091976 -166.031418)
			(xy 367.083539 -166.028767) (xy 367.065869 -166.028767) (xy 367.057432 -166.031418) (xy 367.021256 -166.043953)
			(xy 366.94722 -166.063481) (xy 366.871777 -166.076563) (xy 366.795488 -166.083103) (xy 366.757204 -166.083488)
			(xy 366.716101 -166.083028) (xy 366.634246 -166.075443) (xy 366.55344 -166.060338) (xy 366.474372 -166.037841)
			(xy 366.397717 -166.008145) (xy 366.32413 -165.971502) (xy 366.254237 -165.928226) (xy 366.188636 -165.878686)
			(xy 366.127885 -165.823303) (xy 366.072504 -165.762552) (xy 366.022965 -165.69695) (xy 365.97969 -165.627056)
			(xy 365.943049 -165.553468) (xy 365.913354 -165.476813) (xy 365.890858 -165.397745) (xy 365.875755 -165.316938)
			(xy 365.868171 -165.235083) (xy 365.867696 -165.19398) (xy 365.868101 -165.156201) (xy 365.87451 -165.080916)
			(xy 365.887273 -165.006443) (xy 365.906298 -164.93332) (xy 365.918496 -164.897562) (xy 365.921146 -164.888833)
			(xy 365.920756 -164.870609) (xy 365.917734 -164.862002) (xy 365.902673 -164.822735) (xy 365.879159 -164.741981)
			(xy 365.863376 -164.659368) (xy 365.855464 -164.575634) (xy 365.854996 -164.53358) (xy 365.855398 -164.495297)
			(xy 365.861956 -164.419012) (xy 365.875037 -164.343571) (xy 365.894546 -164.269532) (xy 365.907066 -164.233352)
			(xy 365.909713 -164.224915) (xy 365.909706 -164.207247) (xy 365.907066 -164.198808) (xy 365.894528 -164.162632)
			(xy 365.874994 -164.088597) (xy 365.861906 -164.013154) (xy 365.85536 -163.936865) (xy 365.854996 -163.89858)
			(xy 365.855389 -163.860262) (xy 365.861963 -163.783909) (xy 365.875078 -163.708404) (xy 365.88446 -163.67125)
			(xy 365.887508 -163.659566) (xy 365.882936 -163.63696) (xy 365.826294 -163.563554) (xy 365.818709 -163.554693)
			(xy 365.797809 -163.54439) (xy 365.786162 -163.543742) (xy 358.13365 -163.543742) (xy 358.108692 -163.543166)
			(xy 358.059737 -163.533417) (xy 358.013625 -163.514303) (xy 357.972129 -163.48656) (xy 357.954072 -163.46932)
			(xy 351.3455 -156.860748) (xy 351.338104 -156.853896) (xy 351.319505 -156.846154) (xy 351.309432 -156.845762)
			(xy 350.068388 -156.845762) (xy 350.05949 -156.846201) (xy 350.042798 -156.852382) (xy 350.02922 -156.863893)
			(xy 350.024446 -156.871416) (xy 350.010761 -156.894401) (xy 349.977951 -156.936651) (xy 349.939563 -156.973906)
			(xy 349.896349 -157.005437) (xy 349.849157 -157.030625) (xy 349.79891 -157.048978) (xy 349.746593 -157.060135)
			(xy 349.69323 -157.063879) (xy 349.639867 -157.060135) (xy 349.58755 -157.048978) (xy 349.537303 -157.030625)
			(xy 349.490111 -157.005437) (xy 349.446897 -156.973906) (xy 349.408509 -156.936651) (xy 349.375699 -156.894401)
			(xy 349.362014 -156.871416) (xy 349.357317 -156.863824) (xy 349.343727 -156.852265) (xy 349.326992 -156.846078)
			(xy 349.318072 -156.845762) (xy 348.206314 -156.845762) (xy 348.178628 -156.86786) (xy 348.174818 -156.885132)
			(xy 348.168301 -156.911353) (xy 348.148875 -156.961769) (xy 348.122532 -157.008941) (xy 348.089797 -157.051926)
			(xy 348.051327 -157.089863) (xy 348.00789 -157.121994) (xy 347.960355 -157.147677) (xy 347.909673 -157.166398)
			(xy 347.856856 -157.177782) (xy 347.802962 -157.181602) (xy 347.749068 -157.177782) (xy 347.696251 -157.166398)
			(xy 347.645569 -157.147677) (xy 347.598034 -157.121994) (xy 347.554597 -157.089863) (xy 347.516127 -157.051926)
			(xy 347.483392 -157.008941) (xy 347.457049 -156.961769) (xy 347.437623 -156.911353) (xy 347.431106 -156.885132)
			(xy 347.427296 -156.86786) (xy 347.39961 -156.845762) (xy 345.89339 -156.845762) (xy 345.883962 -156.846142)
			(xy 345.866385 -156.852966) (xy 345.852467 -156.865686) (xy 345.847924 -156.873956) (xy 345.800934 -156.96819)
			(xy 345.803474 -156.996638) (xy 345.81211 -157.008322) (xy 345.836277 -157.041312) (xy 345.879146 -157.110962)
			(xy 345.915445 -157.184251) (xy 345.944869 -157.26056) (xy 345.967169 -157.339247) (xy 345.982157 -157.419647)
			(xy 345.989707 -157.501084) (xy 345.990164 -157.541976) (xy 345.989614 -157.586747) (xy 345.980624 -157.675837)
			(xy 345.962723 -157.763572) (xy 345.936093 -157.849063) (xy 345.919044 -157.890464) (xy 345.915475 -157.900055)
			(xy 345.915466 -157.920501) (xy 345.919044 -157.930088) (xy 345.934825 -157.968399) (xy 345.960034 -158.047334)
			(xy 345.977796 -158.12827) (xy 345.98796 -158.210507) (xy 345.989656 -158.251906) (xy 345.990452 -158.262842)
			(xy 346.000076 -158.282517) (xy 346.01704 -158.296372) (xy 346.027502 -158.299658) (xy 346.044374 -158.304158)
			(xy 346.077785 -158.314321) (xy 346.094304 -158.319978) (xy 346.1025 -158.322501) (xy 346.119636 -158.322501)
			(xy 346.127832 -158.319978) (xy 346.163055 -158.308054) (xy 346.235066 -158.289477) (xy 346.308386 -158.277032)
			(xy 346.382493 -158.270808) (xy 346.419678 -158.270448) (xy 346.456863 -158.270803) (xy 346.530973 -158.277013)
			(xy 346.604294 -158.289457) (xy 346.676303 -158.308048) (xy 346.711524 -158.319978) (xy 346.71972 -158.322501)
			(xy 346.736856 -158.322501) (xy 346.745052 -158.319978) (xy 346.780275 -158.308055) (xy 346.852286 -158.28948)
			(xy 346.925606 -158.277036) (xy 346.999714 -158.270814) (xy 347.036898 -158.270448) (xy 347.078826 -158.270931)
			(xy 347.162301 -158.278902) (xy 347.244641 -158.294771) (xy 347.3251 -158.318396) (xy 347.402949 -158.349562)
			(xy 347.477482 -158.387986) (xy 347.548026 -158.433322) (xy 347.613941 -158.485158) (xy 347.67463 -158.543024)
			(xy 347.729544 -158.606398) (xy 347.778184 -158.674705) (xy 347.820112 -158.747325) (xy 347.854947 -158.823603)
			(xy 347.882373 -158.902846) (xy 347.902143 -158.984338) (xy 347.914077 -159.06734) (xy 347.918067 -159.1511)
			(xy 347.914077 -159.23486) (xy 347.902143 -159.317862) (xy 347.882373 -159.399354) (xy 347.854947 -159.478597)
			(xy 347.820112 -159.554875) (xy 347.778184 -159.627495) (xy 347.729544 -159.695802) (xy 347.67463 -159.759176)
			(xy 347.613941 -159.817042) (xy 347.548026 -159.868878) (xy 347.477482 -159.914214) (xy 347.402949 -159.952638)
			(xy 347.3251 -159.983804) (xy 347.244641 -160.007429) (xy 347.162301 -160.023298) (xy 347.078826 -160.031269)
			(xy 347.036898 -160.031684) (xy 346.999713 -160.031328) (xy 346.925604 -160.025116) (xy 346.852284 -160.012668)
			(xy 346.780277 -159.994074) (xy 346.745052 -159.982154) (xy 346.736856 -159.979631) (xy 346.71972 -159.979631)
			(xy 346.711524 -159.982154) (xy 346.684116 -159.9915) (xy 346.628318 -160.007005) (xy 346.600018 -160.013142)
			(xy 346.590236 -160.015623) (xy 346.573599 -160.02702) (xy 346.562627 -160.04394) (xy 346.560394 -160.053782)
			(xy 346.550931 -160.102889) (xy 346.522415 -160.198749) (xy 346.503498 -160.245044) (xy 346.499922 -160.254635)
			(xy 346.499906 -160.275085) (xy 346.503498 -160.284668) (xy 346.520501 -160.326081) (xy 346.547073 -160.411576)
			(xy 346.564915 -160.499309) (xy 346.573849 -160.588391) (xy 346.574364 -160.633156) (xy 346.57386 -160.675504)
			(xy 346.565809 -160.759818) (xy 346.54978 -160.842984) (xy 346.525919 -160.924251) (xy 346.49444 -161.002881)
			(xy 346.455629 -161.078162) (xy 346.409839 -161.149414) (xy 346.357483 -161.21599) (xy 346.299035 -161.277288)
			(xy 346.235025 -161.332753) (xy 346.166033 -161.381882) (xy 346.092683 -161.424231) (xy 346.01564 -161.459415)
			(xy 345.935601 -161.487117) (xy 345.853292 -161.507085) (xy 345.769457 -161.519138) (xy 345.684856 -161.523169)
			(xy 345.600255 -161.519138) (xy 345.51642 -161.507085) (xy 345.434111 -161.487117) (xy 345.354072 -161.459415)
			(xy 345.277029 -161.424231) (xy 345.203679 -161.381882) (xy 345.134687 -161.332753) (xy 345.070677 -161.277288)
			(xy 345.012229 -161.21599) (xy 344.959873 -161.149414) (xy 344.914083 -161.078162) (xy 344.875272 -161.002881)
			(xy 344.843793 -160.924251) (xy 344.819932 -160.842984) (xy 344.803903 -160.759818) (xy 344.795852 -160.675504)
			(xy 344.795348 -160.633156) (xy 344.795879 -160.588392) (xy 344.804821 -160.499313) (xy 344.822661 -160.411581)
			(xy 344.849219 -160.326084) (xy 344.866214 -160.284668) (xy 344.869771 -160.275078) (xy 344.869755 -160.254642)
			(xy 344.866214 -160.245044) (xy 344.84921 -160.203631) (xy 344.822637 -160.118136) (xy 344.804793 -160.030403)
			(xy 344.795858 -159.941321) (xy 344.795348 -159.896556) (xy 344.795687 -159.859467) (xy 344.801777 -159.785539)
			(xy 344.814004 -159.712376) (xy 344.82278 -159.676338) (xy 344.82455 -159.668013) (xy 344.823085 -159.651066)
			(xy 344.816159 -159.635529) (xy 344.810588 -159.629094) (xy 344.78976 -159.606742) (xy 344.783674 -159.600773)
			(xy 344.768557 -159.592916) (xy 344.7517 -159.590446) (xy 344.743278 -159.591756) (xy 344.739468 -159.592518)
			(xy 344.71446 -159.626484) (xy 344.658986 -159.690029) (xy 344.597746 -159.748037) (xy 344.53129 -159.799988)
			(xy 344.460215 -159.845416) (xy 344.385159 -159.883912) (xy 344.306796 -159.915131) (xy 344.22583 -159.938792)
			(xy 344.142988 -159.954683) (xy 344.059014 -159.962662) (xy 344.016838 -159.963104) (xy 343.975729 -159.962631)
			(xy 343.893863 -159.95505) (xy 343.813044 -159.939949) (xy 343.733963 -159.917456) (xy 343.657295 -159.887765)
			(xy 343.583692 -159.851127) (xy 343.513784 -159.807855) (xy 343.448165 -159.758319) (xy 343.387396 -159.70294)
			(xy 343.331995 -159.642192) (xy 343.282434 -159.576592) (xy 343.239136 -159.5067) (xy 343.20247 -159.433111)
			(xy 343.17275 -159.356453) (xy 343.150228 -159.277381) (xy 343.135096 -159.196568) (xy 343.127484 -159.114704)
			(xy 343.127076 -159.073596) (xy 343.127628 -159.028825) (xy 343.13662 -158.939736) (xy 343.154524 -158.852003)
			(xy 343.181158 -158.766514) (xy 343.198196 -158.725108) (xy 343.201762 -158.715518) (xy 343.20176 -158.695075)
			(xy 343.198196 -158.685484) (xy 343.181175 -158.644073) (xy 343.154561 -158.558581) (xy 343.136661 -158.47085)
			(xy 343.127656 -158.381765) (xy 343.127076 -158.336996) (xy 343.127628 -158.292225) (xy 343.13662 -158.203136)
			(xy 343.154524 -158.115403) (xy 343.181158 -158.029914) (xy 343.198196 -157.988508) (xy 343.201762 -157.978918)
			(xy 343.20176 -157.958475) (xy 343.198196 -157.948884) (xy 343.181175 -157.907473) (xy 343.154561 -157.821981)
			(xy 343.136661 -157.73425) (xy 343.127656 -157.645165) (xy 343.127076 -157.600396) (xy 343.127514 -157.560386)
			(xy 343.1347 -157.48069) (xy 343.149014 -157.401962) (xy 343.17034 -157.324836) (xy 343.198505 -157.249938)
			(xy 343.233283 -157.177871) (xy 343.274391 -157.109218) (xy 343.321499 -157.044535) (xy 343.347548 -157.014164)
			(xy 343.357454 -157.002988) (xy 343.361772 -156.973524) (xy 343.317322 -156.87548) (xy 343.312906 -156.866812)
			(xy 343.298853 -156.853386) (xy 343.280812 -156.846154) (xy 343.271094 -156.845762) (xy 338.569808 -156.845762)
			(xy 338.559738 -156.846185) (xy 338.541138 -156.853905) (xy 338.53374 -156.860748) (xy 338.168742 -157.225746)
			(xy 338.161898 -157.233145) (xy 338.154174 -157.251744) (xy 338.153756 -157.261814) (xy 338.153756 -167.430196)
			(xy 351.432876 -167.430196) (xy 351.433453 -167.385427) (xy 351.442459 -167.296342) (xy 351.46036 -167.208611)
			(xy 351.486975 -167.123119) (xy 351.503996 -167.081708) (xy 351.507565 -167.072118) (xy 351.507564 -167.051674)
			(xy 351.503996 -167.042084) (xy 351.486956 -167.000679) (xy 351.460322 -166.91519) (xy 351.442419 -166.827456)
			(xy 351.433427 -166.738367) (xy 351.432876 -166.693596) (xy 351.433453 -166.648827) (xy 351.442459 -166.559742)
			(xy 351.46036 -166.472011) (xy 351.486975 -166.386519) (xy 351.503996 -166.345108) (xy 351.507565 -166.335518)
			(xy 351.507564 -166.315074) (xy 351.503996 -166.305484) (xy 351.486956 -166.264079) (xy 351.460322 -166.17859)
			(xy 351.442419 -166.090856) (xy 351.433427 -166.001767) (xy 351.432876 -165.956996) (xy 351.433349 -165.915886)
			(xy 351.440937 -165.834016) (xy 351.456047 -165.753196) (xy 351.478552 -165.674116) (xy 351.508259 -165.597449)
			(xy 351.544914 -165.523852) (xy 351.588204 -165.453951) (xy 351.63776 -165.388343) (xy 351.693159 -165.327588)
			(xy 351.753929 -165.272205) (xy 351.81955 -165.222667) (xy 351.889463 -165.179396) (xy 351.963071 -165.142761)
			(xy 352.039745 -165.113075) (xy 352.118832 -165.090592) (xy 352.199656 -165.075503) (xy 352.281528 -165.067937)
			(xy 352.322638 -165.067488) (xy 352.364249 -165.06798) (xy 352.447111 -165.075726) (xy 352.528885 -165.091184)
			(xy 352.608856 -165.114219) (xy 352.686324 -165.144629) (xy 352.760609 -165.182147) (xy 352.796094 -165.203886)
			(xy 352.805204 -165.208993) (xy 352.82585 -165.212036) (xy 352.846014 -165.206657) (xy 352.854514 -165.200584)
			(xy 352.888186 -165.174633) (xy 352.959626 -165.128541) (xy 353.035137 -165.089474) (xy 353.11403 -165.057787)
			(xy 353.195586 -165.033771) (xy 353.27906 -165.017645) (xy 353.363693 -165.009554) (xy 353.406202 -165.009068)
			(xy 353.44731 -165.009511) (xy 353.529174 -165.017096) (xy 353.60999 -165.0322) (xy 353.689068 -165.054696)
			(xy 353.765733 -165.084391) (xy 353.839332 -165.121033) (xy 353.909237 -165.164307) (xy 353.974851 -165.213846)
			(xy 354.035616 -165.269227) (xy 354.091012 -165.329978) (xy 354.140567 -165.39558) (xy 354.183859 -165.465474)
			(xy 354.220519 -165.539063) (xy 354.250233 -165.615721) (xy 354.272749 -165.694793) (xy 354.287874 -165.775606)
			(xy 354.295479 -165.857468) (xy 354.295964 -165.898576) (xy 354.295409 -165.943346) (xy 354.286396 -166.032431)
			(xy 354.268489 -166.120162) (xy 354.241868 -166.205653) (xy 354.224844 -166.247064) (xy 354.221294 -166.256659)
			(xy 354.221285 -166.277097) (xy 354.224844 -166.286688) (xy 354.240617 -166.325002) (xy 354.265832 -166.403934)
			(xy 354.283595 -166.48487) (xy 354.288919 -166.527988) (xy 401.547076 -166.527988) (xy 401.54765 -166.483219)
			(xy 401.556657 -166.394134) (xy 401.574559 -166.306403) (xy 401.601175 -166.220911) (xy 401.618196 -166.1795)
			(xy 401.62177 -166.169912) (xy 401.621765 -166.149466) (xy 401.618196 -166.139876) (xy 401.601153 -166.098472)
			(xy 401.574521 -166.012983) (xy 401.556618 -165.925248) (xy 401.547627 -165.836159) (xy 401.547076 -165.791388)
			(xy 401.54765 -165.746619) (xy 401.556657 -165.657534) (xy 401.574559 -165.569803) (xy 401.601175 -165.484311)
			(xy 401.618196 -165.4429) (xy 401.62177 -165.433312) (xy 401.621765 -165.412866) (xy 401.618196 -165.403276)
			(xy 401.601153 -165.361872) (xy 401.574521 -165.276383) (xy 401.556618 -165.188648) (xy 401.547627 -165.099559)
			(xy 401.547076 -165.054788) (xy 401.547541 -165.013678) (xy 401.55513 -164.931808) (xy 401.570241 -164.850988)
			(xy 401.592747 -164.771907) (xy 401.622454 -164.695241) (xy 401.659109 -164.621643) (xy 401.7024 -164.551742)
			(xy 401.751957 -164.486134) (xy 401.807357 -164.42538) (xy 401.868127 -164.369997) (xy 401.933748 -164.320459)
			(xy 402.003662 -164.277187) (xy 402.07727 -164.240553) (xy 402.153944 -164.210867) (xy 402.233031 -164.188384)
			(xy 402.313856 -164.173295) (xy 402.395728 -164.165729) (xy 402.436838 -164.16528) (xy 402.47845 -164.165758)
			(xy 402.561312 -164.173505) (xy 402.643087 -164.188965) (xy 402.723058 -164.212002) (xy 402.800525 -164.242415)
			(xy 402.87481 -164.279937) (xy 402.910294 -164.301678) (xy 402.919404 -164.306786) (xy 402.94005 -164.30983)
			(xy 402.960214 -164.304449) (xy 402.968714 -164.298376) (xy 403.002386 -164.272424) (xy 403.073825 -164.226332)
			(xy 403.149336 -164.187265) (xy 403.228229 -164.155579) (xy 403.309785 -164.131563) (xy 403.39326 -164.115436)
			(xy 403.477893 -164.107346) (xy 403.520402 -164.10686) (xy 403.561509 -164.107311) (xy 403.643374 -164.114895)
			(xy 403.724189 -164.13) (xy 403.803267 -164.152496) (xy 403.879931 -164.182191) (xy 403.95353 -164.218831)
			(xy 404.023434 -164.262106) (xy 404.089048 -164.311644) (xy 404.149813 -164.367025) (xy 404.205209 -164.427775)
			(xy 404.254764 -164.493376) (xy 404.298057 -164.563269) (xy 404.334716 -164.636858) (xy 404.364431 -164.713515)
			(xy 404.386947 -164.792587) (xy 404.402073 -164.873398) (xy 404.409679 -164.955261) (xy 404.410164 -164.996368)
			(xy 404.409606 -165.041138) (xy 404.400594 -165.130223) (xy 404.382688 -165.217954) (xy 404.356068 -165.303445)
			(xy 404.339044 -165.344856) (xy 404.335498 -165.354452) (xy 404.335487 -165.374889) (xy 404.339044 -165.38448)
			(xy 404.354814 -165.422795) (xy 404.380031 -165.501727) (xy 404.397794 -165.582662) (xy 404.40795 -165.6649)
			(xy 404.409656 -165.706298) (xy 404.410499 -165.717219) (xy 404.420145 -165.736859) (xy 404.437062 -165.750738)
			(xy 404.447502 -165.75405) (xy 404.464374 -165.758547) (xy 404.497785 -165.768711) (xy 404.514304 -165.77437)
			(xy 404.5225 -165.776893) (xy 404.539636 -165.776893) (xy 404.547832 -165.77437) (xy 404.58305 -165.762429)
			(xy 404.655059 -165.74384) (xy 404.728382 -165.731398) (xy 404.802492 -165.725192) (xy 404.839678 -165.72484)
			(xy 404.876862 -165.725213) (xy 404.95097 -165.731434) (xy 405.02429 -165.743875) (xy 405.096301 -165.762448)
			(xy 405.131524 -165.77437) (xy 405.13972 -165.776893) (xy 405.156856 -165.776893) (xy 405.165052 -165.77437)
			(xy 405.200277 -165.762451) (xy 405.272284 -165.743856) (xy 405.345604 -165.731408) (xy 405.419713 -165.725196)
			(xy 405.456898 -165.72484) (xy 405.498822 -165.725407) (xy 405.582291 -165.733377) (xy 405.664623 -165.749245)
			(xy 405.745075 -165.772868) (xy 405.822917 -165.804031) (xy 405.897444 -165.842452) (xy 405.967982 -165.887784)
			(xy 406.033891 -165.939615) (xy 406.094575 -165.997477) (xy 406.149484 -166.060845) (xy 406.198121 -166.129146)
			(xy 406.240045 -166.20176) (xy 406.274876 -166.278031) (xy 406.302301 -166.357268) (xy 406.322068 -166.438752)
			(xy 406.334001 -166.521747) (xy 406.337991 -166.6055) (xy 406.334001 -166.689253) (xy 406.322068 -166.772248)
			(xy 406.302301 -166.853732) (xy 406.274876 -166.932969) (xy 406.240045 -167.00924) (xy 406.198121 -167.081854)
			(xy 406.149484 -167.150155) (xy 406.094575 -167.213523) (xy 406.033891 -167.271385) (xy 405.967982 -167.323216)
			(xy 405.897444 -167.368548) (xy 405.822917 -167.406969) (xy 405.745075 -167.438132) (xy 405.664623 -167.461755)
			(xy 405.582291 -167.477623) (xy 405.498822 -167.485593) (xy 405.456898 -167.486076) (xy 405.419714 -167.485709)
			(xy 405.345606 -167.479487) (xy 405.272286 -167.467044) (xy 405.200275 -167.448469) (xy 405.165052 -167.436546)
			(xy 405.156856 -167.434023) (xy 405.13972 -167.434023) (xy 405.131524 -167.436546) (xy 405.102703 -167.446382)
			(xy 405.043976 -167.462526) (xy 405.014176 -167.468804) (xy 405.004613 -167.471219) (xy 404.988195 -167.482115)
			(xy 404.977083 -167.498387) (xy 404.974552 -167.50792) (xy 404.964352 -167.552278) (xy 404.936104 -167.638809)
			(xy 404.918164 -167.68064) (xy 404.914347 -167.690579) (xy 404.914353 -167.711846) (xy 404.918164 -167.721788)
			(xy 404.936411 -167.764449) (xy 404.964955 -167.852742) (xy 404.984147 -167.943527) (xy 404.99378 -168.035818)
			(xy 404.994364 -168.082214) (xy 404.99386 -168.124562) (xy 404.985809 -168.208876) (xy 404.96978 -168.292042)
			(xy 404.945919 -168.373309) (xy 404.91444 -168.451939) (xy 404.875629 -168.52722) (xy 404.829839 -168.598472)
			(xy 404.777483 -168.665048) (xy 404.719035 -168.726346) (xy 404.655025 -168.781811) (xy 404.586033 -168.83094)
			(xy 404.512683 -168.873289) (xy 404.43564 -168.908473) (xy 404.355601 -168.936175) (xy 404.273292 -168.956143)
			(xy 404.189457 -168.968196) (xy 404.104856 -168.972227) (xy 404.020255 -168.968196) (xy 403.93642 -168.956143)
			(xy 403.854111 -168.936175) (xy 403.774072 -168.908473) (xy 403.697029 -168.873289) (xy 403.623679 -168.83094)
			(xy 403.554687 -168.781811) (xy 403.490677 -168.726346) (xy 403.432229 -168.665048) (xy 403.379873 -168.598472)
			(xy 403.334083 -168.52722) (xy 403.295272 -168.451939) (xy 403.263793 -168.373309) (xy 403.239932 -168.292042)
			(xy 403.223903 -168.208876) (xy 403.215852 -168.124562) (xy 403.215348 -168.082214) (xy 403.215931 -168.035818)
			(xy 403.225575 -167.94353) (xy 403.244771 -167.852746) (xy 403.27331 -167.764453) (xy 403.291548 -167.721788)
			(xy 403.295348 -167.711844) (xy 403.295353 -167.690582) (xy 403.291548 -167.68064) (xy 403.273311 -167.637974)
			(xy 403.244764 -167.549684) (xy 403.225569 -167.458899) (xy 403.215934 -167.36661) (xy 403.215348 -167.320214)
			(xy 403.215953 -167.272404) (xy 403.226131 -167.177329) (xy 403.235668 -167.130476) (xy 403.23764 -167.118071)
			(xy 403.230727 -167.093957) (xy 403.22246 -167.084502) (xy 403.18182 -167.042338) (xy 403.178264 -167.0431)
			(xy 403.169448 -167.045368) (xy 403.154098 -167.055138) (xy 403.148292 -167.06215) (xy 403.123142 -167.094826)
			(xy 403.06774 -167.155904) (xy 403.006921 -167.21159) (xy 402.941208 -167.261407) (xy 402.871166 -167.304927)
			(xy 402.797396 -167.341776) (xy 402.720531 -167.371637) (xy 402.641231 -167.394254) (xy 402.560179 -167.409432)
			(xy 402.478069 -167.417042) (xy 402.436838 -167.417496) (xy 402.395733 -167.416951) (xy 402.313873 -167.409371)
			(xy 402.233061 -167.394271) (xy 402.153987 -167.37178) (xy 402.077325 -167.342091) (xy 402.003729 -167.305456)
			(xy 401.933826 -167.262187) (xy 401.868213 -167.212655) (xy 401.80745 -167.157281) (xy 401.752053 -167.096538)
			(xy 401.702497 -167.030943) (xy 401.659203 -166.961056) (xy 401.622541 -166.887473) (xy 401.592824 -166.810822)
			(xy 401.570304 -166.731756) (xy 401.555174 -166.65095) (xy 401.547564 -166.569093) (xy 401.547076 -166.527988)
			(xy 354.288919 -166.527988) (xy 354.29375 -166.567107) (xy 354.295456 -166.608506) (xy 354.296293 -166.619427)
			(xy 354.305942 -166.639068) (xy 354.322861 -166.652946) (xy 354.333302 -166.656258) (xy 354.350174 -166.660755)
			(xy 354.383585 -166.670919) (xy 354.400104 -166.676578) (xy 354.4083 -166.679101) (xy 354.425436 -166.679101)
			(xy 354.433632 -166.676578) (xy 354.468848 -166.664633) (xy 354.540859 -166.646046) (xy 354.614181 -166.633606)
			(xy 354.688292 -166.6274) (xy 354.725478 -166.627048) (xy 354.762662 -166.62742) (xy 354.83677 -166.633641)
			(xy 354.91009 -166.646083) (xy 354.982101 -166.664656) (xy 355.017324 -166.676578) (xy 355.02552 -166.679101)
			(xy 355.042656 -166.679101) (xy 355.050852 -166.676578) (xy 355.086076 -166.664655) (xy 355.158083 -166.646062)
			(xy 355.231404 -166.633616) (xy 355.305513 -166.627404) (xy 355.342698 -166.627048) (xy 355.384622 -166.627599)
			(xy 355.468092 -166.635569) (xy 355.550425 -166.651437) (xy 355.630878 -166.67506) (xy 355.70872 -166.706224)
			(xy 355.783248 -166.744645) (xy 355.853787 -166.789977) (xy 355.919696 -166.841809) (xy 355.980381 -166.899671)
			(xy 356.03529 -166.96304) (xy 356.083927 -167.031341) (xy 356.125852 -167.103957) (xy 356.160684 -167.180228)
			(xy 356.188108 -167.259465) (xy 356.207876 -167.340951) (xy 356.219809 -167.423946) (xy 356.223799 -167.5077)
			(xy 356.219809 -167.591454) (xy 356.207876 -167.674449) (xy 356.188108 -167.755935) (xy 356.160684 -167.835172)
			(xy 356.125852 -167.911443) (xy 356.083927 -167.984059) (xy 356.03529 -168.05236) (xy 355.980381 -168.115729)
			(xy 355.919696 -168.173591) (xy 355.853787 -168.225423) (xy 355.783248 -168.270755) (xy 355.70872 -168.309176)
			(xy 355.630878 -168.34034) (xy 355.550425 -168.363963) (xy 355.468092 -168.379831) (xy 355.384622 -168.387801)
			(xy 355.342698 -168.388284) (xy 355.305514 -168.387917) (xy 355.231406 -168.381694) (xy 355.158086 -168.369251)
			(xy 355.086075 -168.350676) (xy 355.050852 -168.338754) (xy 355.042656 -168.336231) (xy 355.02552 -168.336231)
			(xy 355.017324 -168.338754) (xy 354.989608 -168.348198) (xy 354.933173 -168.363832) (xy 354.904548 -168.369996)
			(xy 354.894796 -168.372455) (xy 354.878183 -168.383762) (xy 354.867189 -168.400583) (xy 354.864924 -168.410382)
			(xy 354.855394 -168.457508) (xy 354.827522 -168.549531) (xy 354.809298 -168.594024) (xy 354.805711 -168.603608)
			(xy 354.805724 -168.624057) (xy 354.809298 -168.633648) (xy 354.826287 -168.675066) (xy 354.852846 -168.760563)
			(xy 354.870688 -168.848293) (xy 354.879632 -168.937372) (xy 354.880164 -168.982136) (xy 354.87966 -169.024484)
			(xy 354.871609 -169.108798) (xy 354.85558 -169.191964) (xy 354.831719 -169.273231) (xy 354.80024 -169.351861)
			(xy 354.761429 -169.427142) (xy 354.715639 -169.498394) (xy 354.663283 -169.56497) (xy 354.604835 -169.626268)
			(xy 354.540825 -169.681733) (xy 354.471833 -169.730862) (xy 354.398483 -169.773211) (xy 354.32144 -169.808395)
			(xy 354.241401 -169.836097) (xy 354.159092 -169.856065) (xy 354.075257 -169.868118) (xy 353.990656 -169.872149)
			(xy 353.906055 -169.868118) (xy 353.82222 -169.856065) (xy 353.739911 -169.836097) (xy 353.659872 -169.808395)
			(xy 353.582829 -169.773211) (xy 353.509479 -169.730862) (xy 353.440487 -169.681733) (xy 353.376477 -169.626268)
			(xy 353.318029 -169.56497) (xy 353.265673 -169.498394) (xy 353.219883 -169.427142) (xy 353.181072 -169.351861)
			(xy 353.149593 -169.273231) (xy 353.125732 -169.191964) (xy 353.109703 -169.108798) (xy 353.101652 -169.024484)
			(xy 353.101148 -168.982136) (xy 353.101655 -168.937371) (xy 353.110591 -168.848289) (xy 353.128436 -168.760556)
			(xy 353.155009 -168.675061) (xy 353.172014 -168.633648) (xy 353.175559 -168.624052) (xy 353.175573 -168.603614)
			(xy 353.172014 -168.594024) (xy 353.155017 -168.552609) (xy 353.12846 -168.467112) (xy 353.11062 -168.37938)
			(xy 353.101678 -168.2903) (xy 353.101148 -168.245536) (xy 353.10149 -168.209754) (xy 353.107197 -168.138419)
			(xy 353.118619 -168.067773) (xy 353.126802 -168.032938) (xy 353.12847 -168.024629) (xy 353.126899 -168.007765)
			(xy 353.119933 -167.992328) (xy 353.114356 -167.985948) (xy 353.07397 -167.943276) (xy 353.064064 -167.945308)
			(xy 353.055257 -167.947603) (xy 353.039905 -167.957355) (xy 353.034092 -167.964358) (xy 353.008944 -167.997035)
			(xy 352.953542 -168.058113) (xy 352.892723 -168.113799) (xy 352.82701 -168.163616) (xy 352.756967 -168.207136)
			(xy 352.683196 -168.243984) (xy 352.606331 -168.273845) (xy 352.527031 -168.296462) (xy 352.445979 -168.31164)
			(xy 352.363869 -168.31925) (xy 352.322638 -168.319704) (xy 352.281533 -168.319151) (xy 352.199674 -168.311571)
			(xy 352.118862 -168.296471) (xy 352.039789 -168.273981) (xy 351.963127 -168.244292) (xy 351.889531 -168.207657)
			(xy 351.819629 -168.164389) (xy 351.754016 -168.114857) (xy 351.693252 -168.059484) (xy 351.637856 -167.998741)
			(xy 351.5883 -167.933147) (xy 351.545006 -167.863261) (xy 351.508343 -167.789678) (xy 351.478626 -167.713028)
			(xy 351.456106 -167.633963) (xy 351.440975 -167.553157) (xy 351.433364 -167.471301) (xy 351.432876 -167.430196)
			(xy 338.153756 -167.430196) (xy 338.153756 -171.66717) (xy 338.154193 -171.677233) (xy 338.161932 -171.695814)
			(xy 338.168742 -171.703238) (xy 338.349082 -171.883578) (xy 338.356484 -171.890414) (xy 338.375082 -171.898122)
			(xy 338.38515 -171.898564) (xy 340.118446 -171.898564) (xy 340.128512 -171.898132) (xy 340.147101 -171.890402)
			(xy 340.154514 -171.883578) (xy 340.174138 -171.864476) (xy 340.217877 -171.831523) (xy 340.265878 -171.805163)
			(xy 340.317156 -171.785937) (xy 340.370656 -171.774241) (xy 340.425278 -171.770316) (xy 340.4799 -171.774241)
			(xy 340.5334 -171.785937) (xy 340.584678 -171.805163) (xy 340.632679 -171.831523) (xy 340.676418 -171.864476)
			(xy 340.696042 -171.883578) (xy 340.703442 -171.89042) (xy 340.72204 -171.898143) (xy 340.73211 -171.898564)
			(xy 351.093532 -171.898564) (xy 351.118488 -171.899178) (xy 351.167439 -171.90892) (xy 351.21355 -171.928023)
			(xy 351.25505 -171.955753) (xy 351.27311 -171.972986) (xy 352.03511 -172.734986) (xy 352.052368 -172.753027)
			(xy 352.080122 -172.794521) (xy 352.09923 -172.84064) (xy 352.108956 -172.889604) (xy 352.109532 -172.914564)
			(xy 352.109532 -173.21911) (xy 393.739116 -173.21911) (xy 393.739743 -173.172708) (xy 393.749432 -173.08041)
			(xy 393.768686 -172.989625) (xy 393.797294 -172.90134) (xy 393.81557 -172.858684) (xy 393.819371 -172.84874)
			(xy 393.819374 -172.827478) (xy 393.81557 -172.817536) (xy 393.797307 -172.774875) (xy 393.768715 -172.686587)
			(xy 393.749458 -172.595804) (xy 393.739745 -172.503511) (xy 393.739116 -172.45711) (xy 393.739622 -172.415997)
			(xy 393.747208 -172.33412) (xy 393.762316 -172.253293) (xy 393.784818 -172.174205) (xy 393.81452 -172.097531)
			(xy 393.851171 -172.023924) (xy 393.894457 -171.954012) (xy 393.944008 -171.888393) (xy 393.999403 -171.827626)
			(xy 394.060168 -171.772229) (xy 394.125786 -171.722675) (xy 394.195696 -171.679387) (xy 394.269301 -171.642733)
			(xy 394.345975 -171.613028) (xy 394.425062 -171.590524) (xy 394.505889 -171.575413) (xy 394.587765 -171.567824)
			(xy 394.628878 -171.567348) (xy 394.670013 -171.567796) (xy 394.75193 -171.575416) (xy 394.832794 -171.590566)
			(xy 394.911913 -171.613115) (xy 394.988614 -171.642872) (xy 395.06224 -171.679583) (xy 395.132163 -171.722933)
			(xy 395.197785 -171.772553) (xy 395.258547 -171.828019) (xy 395.313929 -171.888856) (xy 395.339062 -171.921424)
			(xy 395.345281 -171.928954) (xy 395.36201 -171.939002) (xy 395.371574 -171.940982) (xy 395.41286 -171.948033)
			(xy 395.493962 -171.968978) (xy 395.572736 -171.997455) (xy 395.648484 -172.033212) (xy 395.720535 -172.075931)
			(xy 395.78825 -172.125234) (xy 395.851031 -172.180685) (xy 395.908321 -172.241793) (xy 395.959613 -172.308015)
			(xy 396.004452 -172.378766) (xy 396.042441 -172.453419) (xy 396.073244 -172.531313) (xy 396.096588 -172.611757)
			(xy 396.112266 -172.69404) (xy 396.120139 -172.777432) (xy 396.12062 -172.819314) (xy 396.120152 -172.860082)
			(xy 396.112652 -172.941273) (xy 396.097752 -173.021436) (xy 396.075577 -173.099899) (xy 396.046313 -173.176003)
			(xy 396.028672 -173.21276) (xy 396.024359 -173.222451) (xy 396.023438 -173.243625) (xy 396.026894 -173.253654)
			(xy 396.041217 -173.292003) (xy 396.063564 -173.370761) (xy 396.07857 -173.451241) (xy 396.086111 -173.53276)
			(xy 396.086584 -173.573694) (xy 396.086007 -173.618463) (xy 396.077001 -173.707548) (xy 396.0591 -173.795279)
			(xy 396.032485 -173.880771) (xy 396.015464 -173.922182) (xy 396.011903 -173.931774) (xy 396.0119 -173.952215)
			(xy 396.015464 -173.961806) (xy 396.031243 -174.000118) (xy 396.056457 -174.079051) (xy 396.074218 -174.159987)
			(xy 396.084371 -174.242225) (xy 396.086076 -174.283624) (xy 396.086886 -174.29455) (xy 396.096546 -174.314192)
			(xy 396.113476 -174.328068) (xy 396.123922 -174.331376) (xy 396.140795 -174.335871) (xy 396.174205 -174.346036)
			(xy 396.190724 -174.351696) (xy 396.19892 -174.354219) (xy 396.216056 -174.354219) (xy 396.224252 -174.351696)
			(xy 396.259466 -174.339729) (xy 396.33147 -174.321076) (xy 396.404792 -174.308569) (xy 396.478908 -174.302297)
			(xy 396.516098 -174.301912) (xy 396.553288 -174.302301) (xy 396.627401 -174.30859) (xy 396.70072 -174.3211)
			(xy 396.772726 -174.339741) (xy 396.807944 -174.351696) (xy 396.81614 -174.354219) (xy 396.833276 -174.354219)
			(xy 396.841472 -174.351696) (xy 396.876685 -174.339723) (xy 396.948689 -174.321072) (xy 397.022011 -174.308567)
			(xy 397.096127 -174.302297) (xy 397.133318 -174.301912) (xy 397.175254 -174.302444) (xy 397.258746 -174.310418)
			(xy 397.341102 -174.326292) (xy 397.421577 -174.349923) (xy 397.49944 -174.381096) (xy 397.573988 -174.41953)
			(xy 397.644545 -174.464875) (xy 397.710473 -174.516722) (xy 397.771173 -174.574601) (xy 397.826097 -174.637988)
			(xy 397.874747 -174.706309) (xy 397.916683 -174.778944) (xy 397.951524 -174.855237) (xy 397.978955 -174.934497)
			(xy 397.998729 -175.016005) (xy 398.010665 -175.099023) (xy 398.014656 -175.1828) (xy 398.010665 -175.266577)
			(xy 397.998729 -175.349595) (xy 397.978955 -175.431103) (xy 397.951524 -175.510363) (xy 397.916683 -175.586656)
			(xy 397.874747 -175.659291) (xy 397.826097 -175.727612) (xy 397.771173 -175.790999) (xy 397.710473 -175.848878)
			(xy 397.644545 -175.900725) (xy 397.573988 -175.94607) (xy 397.49944 -175.984504) (xy 397.421577 -176.015677)
			(xy 397.341102 -176.039308) (xy 397.258746 -176.055182) (xy 397.175254 -176.063156) (xy 397.133318 -176.063656)
			(xy 397.096129 -176.063259) (xy 397.022016 -176.056971) (xy 396.948696 -176.044464) (xy 396.87669 -176.025825)
			(xy 396.841472 -176.013872) (xy 396.833276 -176.011349) (xy 396.81614 -176.011349) (xy 396.807944 -176.013872)
			(xy 396.778999 -176.023726) (xy 396.720017 -176.039869) (xy 396.690088 -176.04613) (xy 396.680526 -176.048543)
			(xy 396.664116 -176.059448) (xy 396.653002 -176.075716) (xy 396.650464 -176.085246) (xy 396.640294 -176.12901)
			(xy 396.612299 -176.21439) (xy 396.594584 -176.25568) (xy 396.590807 -176.265631) (xy 396.590789 -176.286886)
			(xy 396.594584 -176.296828) (xy 396.612812 -176.339497) (xy 396.641361 -176.427787) (xy 396.660559 -176.51857)
			(xy 396.670197 -176.610859) (xy 396.670784 -176.657254) (xy 396.67028 -176.699602) (xy 396.662229 -176.783916)
			(xy 396.6462 -176.867082) (xy 396.622339 -176.948349) (xy 396.59086 -177.026979) (xy 396.552049 -177.10226)
			(xy 396.506259 -177.173512) (xy 396.453903 -177.240088) (xy 396.395455 -177.301386) (xy 396.331445 -177.356851)
			(xy 396.262453 -177.40598) (xy 396.189103 -177.448329) (xy 396.11206 -177.483513) (xy 396.032021 -177.511215)
			(xy 395.949712 -177.531183) (xy 395.865877 -177.543236) (xy 395.781276 -177.547267) (xy 395.696675 -177.543236)
			(xy 395.61284 -177.531183) (xy 395.530531 -177.511215) (xy 395.450492 -177.483513) (xy 395.373449 -177.448329)
			(xy 395.300099 -177.40598) (xy 395.231107 -177.356851) (xy 395.167097 -177.301386) (xy 395.108649 -177.240088)
			(xy 395.056293 -177.173512) (xy 395.010503 -177.10226) (xy 394.971692 -177.026979) (xy 394.940213 -176.948349)
			(xy 394.916352 -176.867082) (xy 394.900323 -176.783916) (xy 394.892272 -176.699602) (xy 394.891768 -176.657254)
			(xy 394.892372 -176.610859) (xy 394.902011 -176.518571) (xy 394.921201 -176.427788) (xy 394.949733 -176.339493)
			(xy 394.967968 -176.296828) (xy 394.971802 -176.286894) (xy 394.971784 -176.265622) (xy 394.967968 -176.25568)
			(xy 394.949707 -176.213025) (xy 394.921167 -176.12473) (xy 394.901979 -176.033943) (xy 394.89235 -175.941651)
			(xy 394.891768 -175.895254) (xy 394.89209 -175.858508) (xy 394.898067 -175.785262) (xy 394.903706 -175.74895)
			(xy 394.905738 -175.737012) (xy 394.898626 -175.713898) (xy 394.824966 -175.637698) (xy 394.802106 -175.629824)
			(xy 394.790168 -175.631602) (xy 394.760779 -175.635286) (xy 394.701676 -175.63923) (xy 394.672058 -175.639476)
			(xy 394.630944 -175.639027) (xy 394.549066 -175.631436) (xy 394.468237 -175.616324) (xy 394.389148 -175.593818)
			(xy 394.312473 -175.564111) (xy 394.238865 -175.527456) (xy 394.168954 -175.484166) (xy 394.103335 -175.434611)
			(xy 394.042568 -175.379212) (xy 393.987171 -175.318444) (xy 393.937618 -175.252823) (xy 393.89433 -175.18291)
			(xy 393.857678 -175.109302) (xy 393.827973 -175.032625) (xy 393.80547 -174.953535) (xy 393.79036 -174.872707)
			(xy 393.782772 -174.790829) (xy 393.782296 -174.749714) (xy 393.782849 -174.707004) (xy 393.791108 -174.621982)
			(xy 393.807465 -174.53814) (xy 393.831771 -174.456249) (xy 393.84732 -174.416466) (xy 393.850767 -174.406384)
			(xy 393.849981 -174.385117) (xy 393.845796 -174.375318) (xy 393.828728 -174.339015) (xy 393.800407 -174.263955)
			(xy 393.778962 -174.186649) (xy 393.764567 -174.107726) (xy 393.75734 -174.027827) (xy 393.756896 -173.987714)
			(xy 393.757452 -173.943459) (xy 393.766275 -173.855391) (xy 393.783795 -173.768633) (xy 393.809839 -173.684042)
			(xy 393.826492 -173.643036) (xy 393.830085 -173.632871) (xy 393.829579 -173.611348) (xy 393.825476 -173.60138)
			(xy 393.808875 -173.565511) (xy 393.781358 -173.491412) (xy 393.760529 -173.415162) (xy 393.746554 -173.337364)
			(xy 393.739543 -173.258632) (xy 393.739116 -173.21911) (xy 352.109532 -173.21911) (xy 352.109532 -175.705516)
			(xy 359.713276 -175.705516) (xy 359.713826 -175.660746) (xy 359.72284 -175.571661) (xy 359.740749 -175.48393)
			(xy 359.767371 -175.398439) (xy 359.784396 -175.357028) (xy 359.787954 -175.347435) (xy 359.78796 -175.326994)
			(xy 359.784396 -175.317404) (xy 359.767362 -175.275997) (xy 359.740727 -175.190508) (xy 359.722822 -175.102775)
			(xy 359.713828 -175.013687) (xy 359.713276 -174.968916) (xy 359.713826 -174.924146) (xy 359.72284 -174.835061)
			(xy 359.740749 -174.74733) (xy 359.767371 -174.661839) (xy 359.784396 -174.620428) (xy 359.787954 -174.610835)
			(xy 359.78796 -174.590394) (xy 359.784396 -174.580804) (xy 359.767362 -174.539397) (xy 359.740727 -174.453908)
			(xy 359.722822 -174.366175) (xy 359.713828 -174.277087) (xy 359.713276 -174.232316) (xy 359.713768 -174.191206)
			(xy 359.721354 -174.109337) (xy 359.736463 -174.028517) (xy 359.758966 -173.949437) (xy 359.788671 -173.872771)
			(xy 359.825324 -173.799173) (xy 359.868613 -173.729272) (xy 359.918168 -173.663664) (xy 359.973567 -173.602909)
			(xy 360.034335 -173.547526) (xy 360.099955 -173.497988) (xy 360.169867 -173.454716) (xy 360.243474 -173.418081)
			(xy 360.320148 -173.388396) (xy 360.399234 -173.365912) (xy 360.480057 -173.350823) (xy 360.561928 -173.343257)
			(xy 360.603038 -173.342808) (xy 360.64465 -173.343297) (xy 360.727511 -173.351043) (xy 360.809285 -173.366502)
			(xy 360.889257 -173.389537) (xy 360.966724 -173.419948) (xy 361.041009 -173.457467) (xy 361.076494 -173.479206)
			(xy 361.085605 -173.48431) (xy 361.10625 -173.487353) (xy 361.126414 -173.481975) (xy 361.134914 -173.475904)
			(xy 361.168589 -173.449956) (xy 361.240028 -173.403863) (xy 361.315538 -173.364795) (xy 361.39443 -173.333108)
			(xy 361.475986 -173.309092) (xy 361.55946 -173.292965) (xy 361.644093 -173.284874) (xy 361.686602 -173.284388)
			(xy 361.72771 -173.284811) (xy 361.809576 -173.292396) (xy 361.890393 -173.307501) (xy 361.969472 -173.329998)
			(xy 362.046138 -173.359694) (xy 362.119738 -173.396336) (xy 362.189643 -173.439612) (xy 362.255258 -173.489152)
			(xy 362.316023 -173.544534) (xy 362.371419 -173.605287) (xy 362.420974 -173.67089) (xy 362.464266 -173.740786)
			(xy 362.500925 -173.814377) (xy 362.530638 -173.891036) (xy 362.553153 -173.97011) (xy 362.568276 -174.050924)
			(xy 362.57588 -174.132788) (xy 362.576364 -174.173896) (xy 362.575781 -174.218665) (xy 362.566776 -174.307749)
			(xy 362.548877 -174.395481) (xy 362.522264 -174.480972) (xy 362.505244 -174.522384) (xy 362.501683 -174.531976)
			(xy 362.501681 -174.552417) (xy 362.505244 -174.562008) (xy 362.522284 -174.603413) (xy 362.548917 -174.688902)
			(xy 362.56682 -174.776636) (xy 362.575812 -174.865725) (xy 362.576364 -174.910496) (xy 362.575094 -174.95393)
			(xy 362.575081 -174.965654) (xy 362.584392 -174.987145) (xy 362.602236 -175.002315) (xy 362.613448 -175.005746)
			(xy 362.632326 -175.010612) (xy 362.669677 -175.021792) (xy 362.688124 -175.028098) (xy 362.69632 -175.030621)
			(xy 362.713456 -175.030621) (xy 362.721652 -175.028098) (xy 362.756876 -175.016176) (xy 362.828883 -174.997583)
			(xy 362.902204 -174.985136) (xy 362.976313 -174.978924) (xy 363.013498 -174.978568) (xy 363.050682 -174.978934)
			(xy 363.12479 -174.985156) (xy 363.19811 -174.997599) (xy 363.270121 -175.016175) (xy 363.305344 -175.028098)
			(xy 363.31354 -175.030621) (xy 363.330676 -175.030621) (xy 363.338872 -175.028098) (xy 363.374094 -175.01617)
			(xy 363.446102 -174.997579) (xy 363.519423 -174.985133) (xy 363.593533 -174.978923) (xy 363.630718 -174.978568)
			(xy 363.672642 -174.979095) (xy 363.75611 -174.987067) (xy 363.838443 -175.002937) (xy 363.918894 -175.026561)
			(xy 363.996736 -175.057726) (xy 364.071262 -175.096148) (xy 364.141799 -175.141481) (xy 364.207708 -175.193313)
			(xy 364.268391 -175.251175) (xy 364.323299 -175.314544) (xy 364.371935 -175.382845) (xy 364.413859 -175.45546)
			(xy 364.44869 -175.531731) (xy 364.476114 -175.610968) (xy 364.495881 -175.692452) (xy 364.507814 -175.775447)
			(xy 364.511804 -175.8592) (xy 364.507814 -175.942953) (xy 364.495881 -176.025948) (xy 364.476114 -176.107432)
			(xy 364.44869 -176.186669) (xy 364.413859 -176.26294) (xy 364.371935 -176.335555) (xy 364.323299 -176.403856)
			(xy 364.268391 -176.467225) (xy 364.207708 -176.525087) (xy 364.141799 -176.576919) (xy 364.071262 -176.622252)
			(xy 363.996736 -176.660674) (xy 363.918894 -176.691839) (xy 363.838443 -176.715463) (xy 363.75611 -176.731333)
			(xy 363.672642 -176.739305) (xy 363.630718 -176.739804) (xy 363.593534 -176.739435) (xy 363.519426 -176.733214)
			(xy 363.446106 -176.720772) (xy 363.374095 -176.702197) (xy 363.338872 -176.690274) (xy 363.330676 -176.687751)
			(xy 363.31354 -176.687751) (xy 363.305344 -176.690274) (xy 363.271301 -176.701822) (xy 363.201745 -176.720004)
			(xy 363.166406 -176.726596) (xy 363.157145 -176.728648) (xy 363.140992 -176.738571) (xy 363.129516 -176.75366)
			(xy 363.126528 -176.762664) (xy 363.118751 -176.789183) (xy 363.100323 -176.841292) (xy 363.089698 -176.866804)
			(xy 363.086123 -176.876392) (xy 363.086128 -176.896837) (xy 363.089698 -176.906428) (xy 363.10668 -176.947849)
			(xy 363.133241 -177.033344) (xy 363.151085 -177.121074) (xy 363.160031 -177.210153) (xy 363.160564 -177.254916)
			(xy 363.16006 -177.297264) (xy 363.152009 -177.381578) (xy 363.13598 -177.464744) (xy 363.112119 -177.546011)
			(xy 363.08064 -177.624641) (xy 363.041829 -177.699922) (xy 362.996039 -177.771174) (xy 362.943683 -177.83775)
			(xy 362.885235 -177.899048) (xy 362.821225 -177.954513) (xy 362.752233 -178.003642) (xy 362.678883 -178.045991)
			(xy 362.60184 -178.081175) (xy 362.521801 -178.108877) (xy 362.439492 -178.128845) (xy 362.355657 -178.140898)
			(xy 362.271056 -178.144929) (xy 362.186455 -178.140898) (xy 362.10262 -178.128845) (xy 362.020311 -178.108877)
			(xy 361.940272 -178.081175) (xy 361.863229 -178.045991) (xy 361.789879 -178.003642) (xy 361.720887 -177.954513)
			(xy 361.656877 -177.899048) (xy 361.598429 -177.83775) (xy 361.546073 -177.771174) (xy 361.500283 -177.699922)
			(xy 361.461472 -177.624641) (xy 361.429993 -177.546011) (xy 361.406132 -177.464744) (xy 361.390103 -177.381578)
			(xy 361.382052 -177.297264) (xy 361.381548 -177.254916) (xy 361.382083 -177.210152) (xy 361.39101 -177.12107)
			(xy 361.408847 -177.033337) (xy 361.435413 -176.947842) (xy 361.452414 -176.906428) (xy 361.455971 -176.896835)
			(xy 361.455977 -176.876394) (xy 361.452414 -176.866804) (xy 361.435411 -176.825392) (xy 361.408855 -176.739893)
			(xy 361.391017 -176.65216) (xy 361.382077 -176.56308) (xy 361.381548 -176.518316) (xy 361.381877 -176.482967)
			(xy 361.387485 -176.412493) (xy 361.398676 -176.342687) (xy 361.406694 -176.308258) (xy 361.408272 -176.299927)
			(xy 361.406606 -176.283067) (xy 361.399568 -176.267656) (xy 361.393994 -176.261268) (xy 361.353608 -176.218596)
			(xy 361.344464 -176.220628) (xy 361.335655 -176.222917) (xy 361.320303 -176.232673) (xy 361.314492 -176.239678)
			(xy 361.289321 -176.272337) (xy 361.233923 -176.333418) (xy 361.173108 -176.389107) (xy 361.107398 -176.438926)
			(xy 361.037358 -176.482448) (xy 360.96359 -176.519299) (xy 360.886727 -176.549162) (xy 360.807429 -176.57178)
			(xy 360.726377 -176.586959) (xy 360.644268 -176.594569) (xy 360.603038 -176.595024) (xy 360.561931 -176.594551)
			(xy 360.480067 -176.58697) (xy 360.399251 -176.571868) (xy 360.320173 -176.549375) (xy 360.243508 -176.519683)
			(xy 360.169909 -176.483044) (xy 360.100004 -176.439772) (xy 360.034389 -176.390235) (xy 359.973624 -176.334856)
			(xy 359.918228 -176.274107) (xy 359.868672 -176.208506) (xy 359.825379 -176.138613) (xy 359.78872 -176.065025)
			(xy 359.759005 -175.988368) (xy 359.73649 -175.909296) (xy 359.721365 -175.828485) (xy 359.713761 -175.746623)
			(xy 359.713276 -175.705516) (xy 352.109532 -175.705516) (xy 352.109532 -178.503326) (xy 352.109961 -178.513393)
			(xy 352.117685 -178.531988) (xy 352.124518 -178.539394) (xy 352.789998 -179.204874) (xy 368.074448 -179.204874)
			(xy 368.074947 -179.16192) (xy 368.083214 -179.076411) (xy 368.099688 -178.992098) (xy 368.124215 -178.909766)
			(xy 368.156566 -178.830183) (xy 368.196441 -178.75409) (xy 368.243467 -178.682196) (xy 368.297207 -178.615173)
			(xy 368.357158 -178.553643) (xy 368.422764 -178.498181) (xy 368.493412 -178.449303) (xy 368.568443 -178.407466)
			(xy 368.607594 -178.389788) (xy 368.616013 -178.385775) (xy 368.629319 -178.372724) (xy 368.633502 -178.364388)
			(xy 368.645948 -178.33721) (xy 368.64947 -178.328554) (xy 368.650638 -178.309919) (xy 368.648234 -178.300888)
			(xy 368.635415 -178.257999) (xy 368.617464 -178.170297) (xy 368.608423 -178.081234) (xy 368.607848 -178.036474)
			(xy 368.608352 -177.994113) (xy 368.616405 -177.909776) (xy 368.632439 -177.826586) (xy 368.656307 -177.745296)
			(xy 368.687795 -177.666644) (xy 368.726617 -177.591341) (xy 368.77242 -177.520069) (xy 368.824791 -177.453473)
			(xy 368.883256 -177.392158) (xy 368.947284 -177.336677) (xy 369.016296 -177.287534) (xy 369.089666 -177.245174)
			(xy 369.166731 -177.209979) (xy 369.246793 -177.18227) (xy 369.329126 -177.162296) (xy 369.412985 -177.150239)
			(xy 369.49761 -177.146208) (xy 369.582235 -177.150239) (xy 369.666094 -177.162296) (xy 369.748427 -177.18227)
			(xy 369.828489 -177.209979) (xy 369.905554 -177.245174) (xy 369.978924 -177.287534) (xy 370.047936 -177.336677)
			(xy 370.111964 -177.392158) (xy 370.170429 -177.453473) (xy 370.2228 -177.520069) (xy 370.268603 -177.591341)
			(xy 370.307425 -177.666644) (xy 370.338913 -177.745296) (xy 370.362781 -177.826586) (xy 370.378815 -177.909776)
			(xy 370.386868 -177.994113) (xy 370.387372 -178.036474) (xy 370.386957 -178.074882) (xy 370.380322 -178.151412)
			(xy 370.367108 -178.227083) (xy 370.357654 -178.264312) (xy 370.35562 -178.273261) (xy 370.357441 -178.291512)
			(xy 370.365595 -178.307941) (xy 370.37903 -178.320427) (xy 370.387372 -178.324256) (xy 370.427603 -178.341379)
			(xy 370.50477 -178.382506) (xy 370.577528 -178.431007) (xy 370.645175 -178.486413) (xy 370.707059 -178.548191)
			(xy 370.762582 -178.615743) (xy 370.811207 -178.688417) (xy 370.852467 -178.765513) (xy 370.885962 -178.846285)
			(xy 370.911369 -178.929954) (xy 370.928442 -179.015713) (xy 370.937018 -179.102733) (xy 370.937536 -179.146454)
			(xy 370.936975 -179.191224) (xy 370.927964 -179.280309) (xy 370.910058 -179.36804) (xy 370.883439 -179.453531)
			(xy 370.866416 -179.494942) (xy 370.86288 -179.504541) (xy 370.862862 -179.524975) (xy 370.866416 -179.534566)
			(xy 370.883441 -179.575977) (xy 370.910078 -179.661464) (xy 370.927986 -179.749196) (xy 370.936982 -179.838284)
			(xy 370.937536 -179.883054) (xy 370.937282 -179.904136) (xy 370.937602 -179.915409) (xy 370.946803 -179.935973)
			(xy 370.963911 -179.950631) (xy 370.97462 -179.954174) (xy 370.989618 -179.95835) (xy 371.019344 -179.967623)
			(xy 371.034056 -179.972716) (xy 371.042252 -179.975239) (xy 371.059388 -179.975239) (xy 371.067584 -179.972716)
			(xy 371.102796 -179.960741) (xy 371.174801 -179.94209) (xy 371.248123 -179.929585) (xy 371.322239 -179.923316)
			(xy 371.35943 -179.922932) (xy 371.396619 -179.923339) (xy 371.470732 -179.929623) (xy 371.544052 -179.942128)
			(xy 371.616058 -179.960764) (xy 371.651276 -179.972716) (xy 371.659472 -179.975239) (xy 371.676608 -179.975239)
			(xy 371.684804 -179.972716) (xy 371.720023 -179.960763) (xy 371.792025 -179.942106) (xy 371.865345 -179.929595)
			(xy 371.93946 -179.923319) (xy 371.97665 -179.922932) (xy 372.01859 -179.923405) (xy 372.10209 -179.931374)
			(xy 372.184455 -179.947244) (xy 372.264938 -179.970872) (xy 372.34281 -180.002043) (xy 372.417367 -180.040476)
			(xy 372.487932 -180.085822) (xy 372.553868 -180.137671) (xy 372.614576 -180.195553) (xy 372.669507 -180.258944)
			(xy 372.718163 -180.327269) (xy 372.760105 -180.39991) (xy 372.794951 -180.476209) (xy 372.822386 -180.555475)
			(xy 372.842162 -180.63699) (xy 372.848069 -180.678074) (xy 376.477276 -180.678074) (xy 376.477846 -180.633305)
			(xy 376.486854 -180.54422) (xy 376.504757 -180.456489) (xy 376.531374 -180.370997) (xy 376.548396 -180.329586)
			(xy 376.551978 -180.32) (xy 376.551968 -180.299553) (xy 376.548396 -180.289962) (xy 376.531349 -180.24856)
			(xy 376.504717 -180.16307) (xy 376.486816 -180.075335) (xy 376.477826 -179.986245) (xy 376.477276 -179.941474)
			(xy 376.477846 -179.896705) (xy 376.486854 -179.80762) (xy 376.504757 -179.719889) (xy 376.531374 -179.634397)
			(xy 376.548396 -179.592986) (xy 376.551978 -179.5834) (xy 376.551968 -179.562953) (xy 376.548396 -179.553362)
			(xy 376.531349 -179.51196) (xy 376.504717 -179.42647) (xy 376.486816 -179.338735) (xy 376.477826 -179.249645)
			(xy 376.477276 -179.204874) (xy 376.477674 -179.163758) (xy 376.485264 -179.081876) (xy 376.500376 -179.001043)
			(xy 376.522883 -178.92195) (xy 376.552591 -178.845272) (xy 376.589248 -178.771661) (xy 376.632541 -178.701747)
			(xy 376.682099 -178.636125) (xy 376.737501 -178.575356) (xy 376.798274 -178.519958) (xy 376.863899 -178.470404)
			(xy 376.933817 -178.427117) (xy 377.00743 -178.390466) (xy 377.084111 -178.360763) (xy 377.163206 -178.338262)
			(xy 377.244039 -178.323155) (xy 377.325922 -178.315571) (xy 377.367038 -178.315112) (xy 377.408654 -178.315621)
			(xy 377.491518 -178.323439) (xy 377.57329 -178.338956) (xy 377.653258 -178.362036) (xy 377.730723 -178.392479)
			(xy 377.805008 -178.430018) (xy 377.840494 -178.451764) (xy 377.849603 -178.456874) (xy 377.87025 -178.459919)
			(xy 377.890415 -178.454537) (xy 377.898914 -178.448462) (xy 377.932574 -178.422483) (xy 378.004001 -178.376346)
			(xy 378.079506 -178.337236) (xy 378.158398 -178.305511) (xy 378.239958 -178.28146) (xy 378.323442 -178.265303)
			(xy 378.408086 -178.257188) (xy 378.450602 -178.256692) (xy 378.491715 -178.257211) (xy 378.57359 -178.264798)
			(xy 378.654416 -178.279906) (xy 378.733503 -178.302408) (xy 378.810176 -178.33211) (xy 378.883782 -178.368761)
			(xy 378.953693 -178.412046) (xy 379.019312 -178.461597) (xy 379.080078 -178.51699) (xy 379.135475 -178.577755)
			(xy 379.185029 -178.643371) (xy 379.228318 -178.713279) (xy 379.264972 -178.786883) (xy 379.294678 -178.863555)
			(xy 379.317184 -178.942641) (xy 379.332296 -179.023466) (xy 379.339887 -179.105341) (xy 379.340364 -179.146454)
			(xy 379.339801 -179.191224) (xy 379.330791 -179.280309) (xy 379.312886 -179.36804) (xy 379.286267 -179.453531)
			(xy 379.269244 -179.494942) (xy 379.265706 -179.50454) (xy 379.265689 -179.524976) (xy 379.269244 -179.534566)
			(xy 379.28504 -179.572871) (xy 379.310249 -179.651807) (xy 379.328005 -179.732745) (xy 379.338154 -179.814985)
			(xy 379.339856 -179.856384) (xy 379.340709 -179.867303) (xy 379.350351 -179.886943) (xy 379.367263 -179.900823)
			(xy 379.377702 -179.904136) (xy 379.394574 -179.908633) (xy 379.427985 -179.918797) (xy 379.444504 -179.924456)
			(xy 379.4527 -179.926979) (xy 379.469836 -179.926979) (xy 379.478032 -179.924456) (xy 379.513248 -179.912493)
			(xy 379.585251 -179.893839) (xy 379.658572 -179.881331) (xy 379.732688 -179.875058) (xy 379.769878 -179.874672)
			(xy 379.807067 -179.875069) (xy 379.88118 -179.881356) (xy 379.9545 -179.893864) (xy 380.026506 -179.912502)
			(xy 380.061724 -179.924456) (xy 380.06992 -179.926979) (xy 380.087056 -179.926979) (xy 380.095252 -179.924456)
			(xy 380.130466 -179.912487) (xy 380.20247 -179.893835) (xy 380.275792 -179.881329) (xy 380.349908 -179.875057)
			(xy 380.387098 -179.874672) (xy 380.429038 -179.875067) (xy 380.512539 -179.88304) (xy 380.594904 -179.898915)
			(xy 380.675386 -179.922546) (xy 380.753258 -179.953722) (xy 380.827814 -179.992158) (xy 380.898379 -180.037507)
			(xy 380.964314 -180.089358) (xy 381.025021 -180.147242) (xy 381.079951 -180.210635) (xy 381.128607 -180.278962)
			(xy 381.170547 -180.351604) (xy 381.205392 -180.427905) (xy 381.232827 -180.507172) (xy 381.252602 -180.588688)
			(xy 381.26454 -180.671715) (xy 381.264843 -180.678074) (xy 384.808476 -180.678074) (xy 384.809046 -180.633305)
			(xy 384.818054 -180.54422) (xy 384.835957 -180.456489) (xy 384.862574 -180.370997) (xy 384.879596 -180.329586)
			(xy 384.883178 -180.32) (xy 384.883168 -180.299553) (xy 384.879596 -180.289962) (xy 384.862549 -180.24856)
			(xy 384.835917 -180.16307) (xy 384.818016 -180.075335) (xy 384.809026 -179.986245) (xy 384.808476 -179.941474)
			(xy 384.809046 -179.896705) (xy 384.818054 -179.80762) (xy 384.835957 -179.719889) (xy 384.862574 -179.634397)
			(xy 384.879596 -179.592986) (xy 384.883178 -179.5834) (xy 384.883168 -179.562953) (xy 384.879596 -179.553362)
			(xy 384.862549 -179.51196) (xy 384.835917 -179.42647) (xy 384.818016 -179.338735) (xy 384.809026 -179.249645)
			(xy 384.808476 -179.204874) (xy 384.808874 -179.163758) (xy 384.816464 -179.081876) (xy 384.831576 -179.001043)
			(xy 384.854083 -178.92195) (xy 384.883791 -178.845272) (xy 384.920448 -178.771661) (xy 384.963741 -178.701747)
			(xy 385.013299 -178.636125) (xy 385.068701 -178.575356) (xy 385.129474 -178.519958) (xy 385.195099 -178.470404)
			(xy 385.265017 -178.427117) (xy 385.33863 -178.390466) (xy 385.415311 -178.360763) (xy 385.494406 -178.338262)
			(xy 385.575239 -178.323155) (xy 385.657122 -178.315571) (xy 385.698238 -178.315112) (xy 385.739854 -178.315621)
			(xy 385.822718 -178.323439) (xy 385.90449 -178.338956) (xy 385.984458 -178.362036) (xy 386.061923 -178.392479)
			(xy 386.136208 -178.430018) (xy 386.171694 -178.451764) (xy 386.180803 -178.456874) (xy 386.20145 -178.459919)
			(xy 386.221615 -178.454537) (xy 386.230114 -178.448462) (xy 386.263774 -178.422483) (xy 386.335201 -178.376346)
			(xy 386.410706 -178.337236) (xy 386.489598 -178.305511) (xy 386.571158 -178.28146) (xy 386.654642 -178.265303)
			(xy 386.739286 -178.257188) (xy 386.781802 -178.256692) (xy 386.822915 -178.257211) (xy 386.90479 -178.264798)
			(xy 386.985616 -178.279906) (xy 387.064703 -178.302408) (xy 387.141376 -178.33211) (xy 387.214982 -178.368761)
			(xy 387.284893 -178.412046) (xy 387.350512 -178.461597) (xy 387.411278 -178.51699) (xy 387.466675 -178.577755)
			(xy 387.516229 -178.643371) (xy 387.559518 -178.713279) (xy 387.596172 -178.786883) (xy 387.625878 -178.863555)
			(xy 387.648384 -178.942641) (xy 387.663496 -179.023466) (xy 387.671087 -179.105341) (xy 387.671564 -179.146454)
			(xy 387.671001 -179.191224) (xy 387.661991 -179.280309) (xy 387.644086 -179.36804) (xy 387.617467 -179.453531)
			(xy 387.600444 -179.494942) (xy 387.596906 -179.50454) (xy 387.596889 -179.524976) (xy 387.600444 -179.534566)
			(xy 387.61624 -179.572871) (xy 387.641449 -179.651807) (xy 387.659205 -179.732745) (xy 387.669354 -179.814985)
			(xy 387.671056 -179.856384) (xy 387.671909 -179.867303) (xy 387.681551 -179.886943) (xy 387.698463 -179.900823)
			(xy 387.708902 -179.904136) (xy 387.725774 -179.908633) (xy 387.759185 -179.918797) (xy 387.775704 -179.924456)
			(xy 387.7839 -179.926979) (xy 387.801036 -179.926979) (xy 387.809232 -179.924456) (xy 387.844448 -179.912493)
			(xy 387.916451 -179.893839) (xy 387.989772 -179.881331) (xy 388.063888 -179.875058) (xy 388.101078 -179.874672)
			(xy 388.138267 -179.875069) (xy 388.21238 -179.881356) (xy 388.2857 -179.893864) (xy 388.357706 -179.912502)
			(xy 388.392924 -179.924456) (xy 388.40112 -179.926979) (xy 388.418256 -179.926979) (xy 388.426452 -179.924456)
			(xy 388.461666 -179.912487) (xy 388.53367 -179.893835) (xy 388.606992 -179.881329) (xy 388.681108 -179.875057)
			(xy 388.718298 -179.874672) (xy 388.760238 -179.875067) (xy 388.843739 -179.88304) (xy 388.926104 -179.898915)
			(xy 389.006586 -179.922546) (xy 389.084458 -179.953722) (xy 389.159014 -179.992158) (xy 389.229579 -180.037507)
			(xy 389.295514 -180.089358) (xy 389.356221 -180.147242) (xy 389.411151 -180.210635) (xy 389.459807 -180.278962)
			(xy 389.501747 -180.351604) (xy 389.536592 -180.427905) (xy 389.564027 -180.507172) (xy 389.583802 -180.588688)
			(xy 389.59574 -180.671715) (xy 389.599731 -180.7555) (xy 389.59574 -180.839285) (xy 389.583802 -180.922312)
			(xy 389.564027 -181.003828) (xy 389.536592 -181.083095) (xy 389.501747 -181.159396) (xy 389.459807 -181.232038)
			(xy 389.411151 -181.300365) (xy 389.356221 -181.363758) (xy 389.295514 -181.421642) (xy 389.229579 -181.473493)
			(xy 389.159014 -181.518842) (xy 389.084458 -181.557278) (xy 389.006586 -181.588454) (xy 388.926104 -181.612085)
			(xy 388.843739 -181.62796) (xy 388.760238 -181.635933) (xy 388.718298 -181.636416) (xy 388.681108 -181.636027)
			(xy 388.606996 -181.629737) (xy 388.533676 -181.617227) (xy 388.46167 -181.598587) (xy 388.426452 -181.586632)
			(xy 388.418256 -181.584109) (xy 388.40112 -181.584109) (xy 388.392924 -181.586632) (xy 388.365208 -181.596078)
			(xy 388.308773 -181.611711) (xy 388.280148 -181.617874) (xy 388.270401 -181.620348) (xy 388.25379 -181.63165)
			(xy 388.242792 -181.648464) (xy 388.240524 -181.65826) (xy 388.231054 -181.705587) (xy 388.203179 -181.797995)
			(xy 388.184898 -181.842664) (xy 388.181345 -181.852258) (xy 388.181336 -181.872698) (xy 388.184898 -181.882288)
			(xy 388.2019 -181.923701) (xy 388.228456 -182.009199) (xy 388.246294 -182.096932) (xy 388.255234 -182.186012)
			(xy 388.255764 -182.230776) (xy 388.25526 -182.273124) (xy 388.247209 -182.357438) (xy 388.23118 -182.440604)
			(xy 388.207319 -182.521871) (xy 388.17584 -182.600501) (xy 388.137029 -182.675782) (xy 388.091239 -182.747034)
			(xy 388.038883 -182.81361) (xy 387.980435 -182.874908) (xy 387.916425 -182.930373) (xy 387.847433 -182.979502)
			(xy 387.774083 -183.021851) (xy 387.69704 -183.057035) (xy 387.617001 -183.084737) (xy 387.534692 -183.104705)
			(xy 387.450857 -183.116758) (xy 387.366256 -183.120789) (xy 387.281655 -183.116758) (xy 387.19782 -183.104705)
			(xy 387.115511 -183.084737) (xy 387.035472 -183.057035) (xy 386.958429 -183.021851) (xy 386.885079 -182.979502)
			(xy 386.816087 -182.930373) (xy 386.752077 -182.874908) (xy 386.693629 -182.81361) (xy 386.641273 -182.747034)
			(xy 386.595483 -182.675782) (xy 386.556672 -182.600501) (xy 386.525193 -182.521871) (xy 386.501332 -182.440604)
			(xy 386.485303 -182.357438) (xy 386.477252 -182.273124) (xy 386.476748 -182.230776) (xy 386.477269 -182.186011)
			(xy 386.486201 -182.096929) (xy 386.504042 -182.009196) (xy 386.530611 -181.923701) (xy 386.547614 -181.882288)
			(xy 386.551194 -181.872702) (xy 386.551185 -181.852255) (xy 386.547614 -181.842664) (xy 386.53063 -181.801244)
			(xy 386.504069 -181.715748) (xy 386.486226 -181.628018) (xy 386.47728 -181.53894) (xy 386.476748 -181.494176)
			(xy 386.477087 -181.458262) (xy 386.482864 -181.386666) (xy 386.494395 -181.315769) (xy 386.502656 -181.280816)
			(xy 386.504286 -181.272505) (xy 386.502711 -181.255655) (xy 386.495751 -181.24023) (xy 386.49021 -181.233826)
			(xy 386.44957 -181.1909) (xy 386.439664 -181.193186) (xy 386.430849 -181.195458) (xy 386.415499 -181.205225)
			(xy 386.409692 -181.212236) (xy 386.384552 -181.244927) (xy 386.329156 -181.306026) (xy 386.268343 -181.361734)
			(xy 386.202634 -181.411575) (xy 386.132593 -181.455119) (xy 386.058822 -181.491993) (xy 385.981955 -181.521881)
			(xy 385.902652 -181.544524) (xy 385.821593 -181.55973) (xy 385.739474 -181.567368) (xy 385.698238 -181.567836)
			(xy 385.657123 -181.567365) (xy 385.575243 -181.559781) (xy 385.494413 -181.544674) (xy 385.415321 -181.522173)
			(xy 385.338643 -181.49247) (xy 385.265033 -181.455819) (xy 385.195119 -181.412532) (xy 385.129497 -181.362978)
			(xy 385.068728 -181.30758) (xy 385.01333 -181.246812) (xy 384.963775 -181.181191) (xy 384.920487 -181.111277)
			(xy 384.883834 -181.037668) (xy 384.854131 -180.96099) (xy 384.831629 -180.881899) (xy 384.81652 -180.801068)
			(xy 384.808935 -180.719189) (xy 384.808476 -180.678074) (xy 381.264843 -180.678074) (xy 381.268531 -180.7555)
			(xy 381.26454 -180.839285) (xy 381.252602 -180.922312) (xy 381.232827 -181.003828) (xy 381.205392 -181.083095)
			(xy 381.170547 -181.159396) (xy 381.128607 -181.232038) (xy 381.079951 -181.300365) (xy 381.025021 -181.363758)
			(xy 380.964314 -181.421642) (xy 380.898379 -181.473493) (xy 380.827814 -181.518842) (xy 380.753258 -181.557278)
			(xy 380.675386 -181.588454) (xy 380.594904 -181.612085) (xy 380.512539 -181.62796) (xy 380.429038 -181.635933)
			(xy 380.387098 -181.636416) (xy 380.349908 -181.636027) (xy 380.275796 -181.629737) (xy 380.202476 -181.617227)
			(xy 380.13047 -181.598587) (xy 380.095252 -181.586632) (xy 380.087056 -181.584109) (xy 380.06992 -181.584109)
			(xy 380.061724 -181.586632) (xy 380.034008 -181.596078) (xy 379.977573 -181.611711) (xy 379.948948 -181.617874)
			(xy 379.939201 -181.620348) (xy 379.92259 -181.63165) (xy 379.911592 -181.648464) (xy 379.909324 -181.65826)
			(xy 379.899854 -181.705587) (xy 379.871979 -181.797995) (xy 379.853698 -181.842664) (xy 379.850145 -181.852258)
			(xy 379.850136 -181.872698) (xy 379.853698 -181.882288) (xy 379.8707 -181.923701) (xy 379.897256 -182.009199)
			(xy 379.915094 -182.096932) (xy 379.924034 -182.186012) (xy 379.924564 -182.230776) (xy 379.92406 -182.273124)
			(xy 379.916009 -182.357438) (xy 379.89998 -182.440604) (xy 379.876119 -182.521871) (xy 379.84464 -182.600501)
			(xy 379.805829 -182.675782) (xy 379.760039 -182.747034) (xy 379.707683 -182.81361) (xy 379.649235 -182.874908)
			(xy 379.585225 -182.930373) (xy 379.516233 -182.979502) (xy 379.442883 -183.021851) (xy 379.36584 -183.057035)
			(xy 379.285801 -183.084737) (xy 379.203492 -183.104705) (xy 379.119657 -183.116758) (xy 379.035056 -183.120789)
			(xy 378.950455 -183.116758) (xy 378.86662 -183.104705) (xy 378.784311 -183.084737) (xy 378.704272 -183.057035)
			(xy 378.627229 -183.021851) (xy 378.553879 -182.979502) (xy 378.484887 -182.930373) (xy 378.420877 -182.874908)
			(xy 378.362429 -182.81361) (xy 378.310073 -182.747034) (xy 378.264283 -182.675782) (xy 378.225472 -182.600501)
			(xy 378.193993 -182.521871) (xy 378.170132 -182.440604) (xy 378.154103 -182.357438) (xy 378.146052 -182.273124)
			(xy 378.145548 -182.230776) (xy 378.146069 -182.186011) (xy 378.155001 -182.096929) (xy 378.172842 -182.009196)
			(xy 378.199411 -181.923701) (xy 378.216414 -181.882288) (xy 378.219994 -181.872702) (xy 378.219985 -181.852255)
			(xy 378.216414 -181.842664) (xy 378.19943 -181.801244) (xy 378.172869 -181.715748) (xy 378.155026 -181.628018)
			(xy 378.14608 -181.53894) (xy 378.145548 -181.494176) (xy 378.145887 -181.458262) (xy 378.151664 -181.386666)
			(xy 378.163195 -181.315769) (xy 378.171456 -181.280816) (xy 378.173086 -181.272505) (xy 378.171511 -181.255655)
			(xy 378.164551 -181.24023) (xy 378.15901 -181.233826) (xy 378.11837 -181.1909) (xy 378.108464 -181.193186)
			(xy 378.099649 -181.195458) (xy 378.084299 -181.205225) (xy 378.078492 -181.212236) (xy 378.053352 -181.244927)
			(xy 377.997956 -181.306026) (xy 377.937143 -181.361734) (xy 377.871434 -181.411575) (xy 377.801393 -181.455119)
			(xy 377.727622 -181.491993) (xy 377.650755 -181.521881) (xy 377.571452 -181.544524) (xy 377.490393 -181.55973)
			(xy 377.408274 -181.567368) (xy 377.367038 -181.567836) (xy 377.325923 -181.567365) (xy 377.244043 -181.559781)
			(xy 377.163213 -181.544674) (xy 377.084121 -181.522173) (xy 377.007443 -181.49247) (xy 376.933833 -181.455819)
			(xy 376.863919 -181.412532) (xy 376.798297 -181.362978) (xy 376.737528 -181.30758) (xy 376.68213 -181.246812)
			(xy 376.632575 -181.181191) (xy 376.589287 -181.111277) (xy 376.552634 -181.037668) (xy 376.522931 -180.96099)
			(xy 376.500429 -180.881899) (xy 376.48532 -180.801068) (xy 376.477735 -180.719189) (xy 376.477276 -180.678074)
			(xy 372.848069 -180.678074) (xy 372.8541 -180.720015) (xy 372.858091 -180.8038) (xy 372.8541 -180.887585)
			(xy 372.842162 -180.97061) (xy 372.822386 -181.052125) (xy 372.794951 -181.131391) (xy 372.760105 -181.20769)
			(xy 372.718163 -181.280331) (xy 372.669507 -181.348656) (xy 372.614576 -181.412047) (xy 372.553868 -181.469929)
			(xy 372.487932 -181.521778) (xy 372.417367 -181.567124) (xy 372.34281 -181.605557) (xy 372.264938 -181.636728)
			(xy 372.184455 -181.660356) (xy 372.10209 -181.676226) (xy 372.01859 -181.684195) (xy 371.97665 -181.684676)
			(xy 371.939461 -181.684274) (xy 371.865348 -181.677988) (xy 371.792028 -181.665482) (xy 371.720022 -181.646845)
			(xy 371.684804 -181.634892) (xy 371.676608 -181.632369) (xy 371.659472 -181.632369) (xy 371.651276 -181.634892)
			(xy 371.611916 -181.648156) (xy 371.531285 -181.66812) (xy 371.449135 -181.680416) (xy 371.40769 -181.683152)
			(xy 371.397914 -181.684226) (xy 371.380178 -181.69268) (xy 371.366873 -181.707139) (xy 371.362986 -181.716172)
			(xy 371.348 -181.753764) (xy 371.344447 -181.763358) (xy 371.344438 -181.783798) (xy 371.348 -181.793388)
			(xy 371.365037 -181.834794) (xy 371.39167 -181.920283) (xy 371.409574 -182.008016) (xy 371.418568 -182.097105)
			(xy 371.41912 -182.141876) (xy 371.418616 -182.184237) (xy 371.410563 -182.268574) (xy 371.394529 -182.351764)
			(xy 371.370661 -182.433054) (xy 371.339173 -182.511706) (xy 371.300351 -182.587009) (xy 371.254548 -182.658281)
			(xy 371.202177 -182.724877) (xy 371.143712 -182.786192) (xy 371.079684 -182.841673) (xy 371.010672 -182.890816)
			(xy 370.937302 -182.933176) (xy 370.860237 -182.968371) (xy 370.780175 -182.99608) (xy 370.697842 -183.016054)
			(xy 370.613983 -183.028111) (xy 370.529358 -183.032143) (xy 370.444733 -183.028111) (xy 370.360874 -183.016054)
			(xy 370.278541 -182.99608) (xy 370.198479 -182.968371) (xy 370.121414 -182.933176) (xy 370.048044 -182.890816)
			(xy 369.979032 -182.841673) (xy 369.915004 -182.786192) (xy 369.856539 -182.724877) (xy 369.804168 -182.658281)
			(xy 369.758365 -182.587009) (xy 369.719543 -182.511706) (xy 369.688055 -182.433054) (xy 369.664187 -182.351764)
			(xy 369.648153 -182.268574) (xy 369.6401 -182.184237) (xy 369.639596 -182.141876) (xy 369.640165 -182.097107)
			(xy 369.649173 -182.008022) (xy 369.667076 -181.92029) (xy 369.693694 -181.834799) (xy 369.710716 -181.793388)
			(xy 369.714296 -181.783802) (xy 369.714287 -181.763355) (xy 369.710716 -181.753764) (xy 369.693665 -181.712364)
			(xy 369.667035 -181.626872) (xy 369.649135 -181.539137) (xy 369.640146 -181.450047) (xy 369.639596 -181.405276)
			(xy 369.639771 -181.384669) (xy 369.641804 -181.343504) (xy 369.64366 -181.32298) (xy 369.644676 -181.311804)
			(xy 369.637818 -181.291738) (xy 369.571016 -181.22011) (xy 369.551458 -181.211728) (xy 369.540282 -181.211982)
			(xy 369.52301 -181.212236) (xy 369.481895 -181.211792) (xy 369.400014 -181.204205) (xy 369.319183 -181.189096)
			(xy 369.240091 -181.166593) (xy 369.163413 -181.136888) (xy 369.089803 -181.100234) (xy 369.019889 -181.056945)
			(xy 368.954268 -181.007389) (xy 368.893499 -180.95199) (xy 368.838101 -180.89122) (xy 368.788546 -180.825598)
			(xy 368.745258 -180.755683) (xy 368.708606 -180.682072) (xy 368.678902 -180.605393) (xy 368.6564 -180.526301)
			(xy 368.641292 -180.44547) (xy 368.633707 -180.36359) (xy 368.633248 -180.322474) (xy 368.6337 -180.283493)
			(xy 368.640575 -180.205835) (xy 368.654226 -180.129077) (xy 368.663982 -180.091334) (xy 368.666037 -180.082278)
			(xy 368.664208 -180.063813) (xy 368.655908 -180.047218) (xy 368.642231 -180.034679) (xy 368.633756 -180.030882)
			(xy 368.596114 -180.015301) (xy 368.523548 -179.97826) (xy 368.454673 -179.934739) (xy 368.390066 -179.885102)
			(xy 368.330268 -179.829767) (xy 368.27578 -179.769195) (xy 368.227059 -179.703896) (xy 368.184512 -179.634415)
			(xy 368.148496 -179.561335) (xy 368.119314 -179.485268) (xy 368.097208 -179.406851) (xy 368.082365 -179.326741)
			(xy 368.074909 -179.24561) (xy 368.074448 -179.204874) (xy 352.789998 -179.204874) (xy 353.723702 -180.138578)
			(xy 353.7311 -180.145426) (xy 353.749698 -180.153164) (xy 353.75977 -180.153564) (xy 359.221532 -180.153564)
			(xy 359.246488 -180.154178) (xy 359.295439 -180.16392) (xy 359.34155 -180.183023) (xy 359.38305 -180.210753)
			(xy 359.40111 -180.227986) (xy 360.41711 -181.243986) (xy 360.434368 -181.262027) (xy 360.462122 -181.303521)
			(xy 360.48123 -181.34964) (xy 360.490956 -181.398604) (xy 360.491532 -181.423564) (xy 360.491532 -186.885326)
			(xy 360.491961 -186.895393) (xy 360.499685 -186.913988) (xy 360.506518 -186.921394) (xy 362.105702 -188.520578)
			(xy 362.1131 -188.527426) (xy 362.131698 -188.535164) (xy 362.14177 -188.535564) (xy 366.907318 -188.535564)
			(xy 366.932274 -188.536177) (xy 366.981227 -188.545917) (xy 367.02734 -188.565018) (xy 367.068842 -188.592747)
			(xy 367.086896 -188.609986) (xy 371.950488 -193.473578) (xy 371.957885 -193.480429) (xy 371.976483 -193.488171)
			(xy 371.986556 -193.488564)
		)
		(stroke
			(width 0)
			(type solid)
		)
		(fill yes)
		(layer "In9.Cu")
		(net "GND")
	)
	(gr_poly
		(pts
			(xy 372.218458 -251.50064) (xy 372.23065 -251.493274) (xy 372.250358 -251.481499) (xy 372.292333 -251.462908)
			(xy 372.336477 -251.450302) (xy 372.38194 -251.443923) (xy 372.404894 -251.44349) (xy 372.420134 -251.443744)
			(xy 372.434358 -251.444506) (xy 372.45925 -251.431044) (xy 372.603776 -251.18187) (xy 372.603268 -251.153676)
			(xy 372.595648 -251.141484) (xy 372.583446 -251.121513) (xy 372.564176 -251.078863) (xy 372.551107 -251.033924)
			(xy 372.5445 -250.987592) (xy 372.544086 -250.964192) (xy 372.544596 -250.938205) (xy 372.552728 -250.886871)
			(xy 372.568789 -250.837441) (xy 372.592385 -250.791133) (xy 372.622935 -250.749085) (xy 372.659686 -250.712334)
			(xy 372.701734 -250.681784) (xy 372.748043 -250.658188) (xy 372.797473 -250.642127) (xy 372.848807 -250.633996)
			(xy 372.874794 -250.633484) (xy 372.898153 -250.63389) (xy 372.944405 -250.640464) (xy 372.989276 -250.653468)
			(xy 373.031876 -250.672645) (xy 373.051832 -250.684792) (xy 373.06377 -250.692412) (xy 373.091964 -250.69292)
			(xy 373.941086 -250.20524) (xy 373.954802 -250.180602) (xy 373.954294 -250.166378) (xy 373.95404 -250.154186)
			(xy 373.954524 -250.128199) (xy 373.962657 -250.076865) (xy 373.978722 -250.027435) (xy 374.002321 -249.981127)
			(xy 374.032874 -249.939082) (xy 374.069629 -249.902334) (xy 374.11168 -249.871788) (xy 374.157993 -249.848198)
			(xy 374.207425 -249.832143) (xy 374.258761 -249.824019) (xy 374.284748 -249.823478) (xy 374.300242 -249.823732)
			(xy 374.314466 -249.824494) (xy 374.339358 -249.811032) (xy 374.483884 -249.561604) (xy 374.483376 -249.53341)
			(xy 374.475756 -249.521472) (xy 374.463555 -249.501501) (xy 374.444285 -249.458851) (xy 374.431217 -249.413912)
			(xy 374.424612 -249.36758) (xy 374.424194 -249.34418) (xy 374.424705 -249.318194) (xy 374.432838 -249.266862)
			(xy 374.448901 -249.217434) (xy 374.472498 -249.171128) (xy 374.503048 -249.129082) (xy 374.539799 -249.092334)
			(xy 374.581846 -249.061786) (xy 374.628155 -249.038192) (xy 374.677583 -249.022133) (xy 374.728916 -249.014003)
			(xy 374.754902 -249.013472) (xy 374.770142 -249.013726) (xy 374.784366 -249.014488) (xy 374.809258 -249.001026)
			(xy 374.953784 -248.751598) (xy 374.953276 -248.723404) (xy 374.945656 -248.711466) (xy 374.933455 -248.691494)
			(xy 374.914186 -248.648845) (xy 374.901119 -248.603906) (xy 374.894515 -248.557574) (xy 374.894094 -248.534174)
			(xy 374.894507 -248.510586) (xy 374.901201 -248.463888) (xy 374.914463 -248.418614) (xy 374.934024 -248.375685)
			(xy 374.946418 -248.355612) (xy 374.954292 -248.343166) (xy 374.955054 -248.315226) (xy 374.811036 -248.067068)
			(xy 374.786398 -248.053606) (xy 374.77192 -248.054368) (xy 374.754902 -248.054876) (xy 374.728914 -248.054393)
			(xy 374.677577 -248.046262) (xy 374.628144 -248.030199) (xy 374.581833 -248.006601) (xy 374.539784 -247.976048)
			(xy 374.503032 -247.939294) (xy 374.472483 -247.897242) (xy 374.448889 -247.850928) (xy 374.432831 -247.801494)
			(xy 374.424705 -247.750156) (xy 374.424194 -247.724168) (xy 374.424592 -247.700537) (xy 374.431319 -247.653755)
			(xy 374.444645 -247.60841) (xy 374.464298 -247.565427) (xy 374.476772 -247.545352) (xy 374.484392 -247.53316)
			(xy 374.485154 -247.504966) (xy 374.34139 -247.257062) (xy 374.316498 -247.2436) (xy 374.30202 -247.244362)
			(xy 374.284748 -247.24487) (xy 374.258759 -247.244391) (xy 374.207421 -247.236266) (xy 374.157986 -247.22021)
			(xy 374.111671 -247.196618) (xy 374.069618 -247.16607) (xy 374.032862 -247.129319) (xy 374.002308 -247.08727)
			(xy 373.978708 -247.040959) (xy 373.962645 -246.991526) (xy 373.954513 -246.940189) (xy 373.954513 -246.888211)
			(xy 373.962645 -246.836874) (xy 373.978708 -246.787441) (xy 374.002308 -246.74113) (xy 374.032862 -246.699081)
			(xy 374.069618 -246.66233) (xy 374.111671 -246.631782) (xy 374.157985 -246.60819) (xy 374.207421 -246.592134)
			(xy 374.258759 -246.584009) (xy 374.284748 -246.583454) (xy 374.300242 -246.583708) (xy 374.31472 -246.58447)
			(xy 374.339358 -246.571008) (xy 374.483884 -246.321834) (xy 374.483376 -246.293386) (xy 374.475756 -246.281448)
			(xy 374.463556 -246.261476) (xy 374.44429 -246.218826) (xy 374.431225 -246.173887) (xy 374.424623 -246.127556)
			(xy 374.424194 -246.104156) (xy 374.424707 -246.078171) (xy 374.432843 -246.026842) (xy 374.448908 -245.977418)
			(xy 374.472506 -245.931114) (xy 374.503057 -245.889072) (xy 374.539807 -245.852327) (xy 374.581854 -245.821782)
			(xy 374.62816 -245.79819) (xy 374.677587 -245.782132) (xy 374.728917 -245.774003) (xy 374.754902 -245.773448)
			(xy 374.770142 -245.773702) (xy 374.784366 -245.774464) (xy 374.809258 -245.761002) (xy 374.953784 -245.511574)
			(xy 374.953276 -245.48338) (xy 374.945656 -245.471442) (xy 374.933456 -245.45147) (xy 374.914191 -245.40882)
			(xy 374.901127 -245.363881) (xy 374.894526 -245.31755) (xy 374.894094 -245.29415) (xy 374.894509 -245.270563)
			(xy 374.901206 -245.223866) (xy 374.91447 -245.178594) (xy 374.934034 -245.135667) (xy 374.946418 -245.115588)
			(xy 374.954292 -245.103142) (xy 374.955054 -245.075202) (xy 374.811036 -244.827044) (xy 374.786398 -244.813582)
			(xy 374.77192 -244.814344) (xy 374.754902 -244.814852) (xy 374.728913 -244.814343) (xy 374.677576 -244.806213)
			(xy 374.628143 -244.790152) (xy 374.58183 -244.766557) (xy 374.539777 -244.736008) (xy 374.503022 -244.699258)
			(xy 374.472467 -244.65721) (xy 374.448865 -244.6109) (xy 374.432798 -244.561469) (xy 374.424661 -244.510132)
			(xy 374.424194 -244.484144) (xy 374.424594 -244.460513) (xy 374.431324 -244.413733) (xy 374.444653 -244.368389)
			(xy 374.464308 -244.325409) (xy 374.476772 -244.305328) (xy 374.484392 -244.293136) (xy 374.485154 -244.264942)
			(xy 374.34139 -244.017038) (xy 374.316498 -244.003576) (xy 374.30202 -244.004338) (xy 374.284748 -244.004846)
			(xy 374.258753 -244.004366) (xy 374.207403 -243.99624) (xy 374.157956 -243.98018) (xy 374.111631 -243.956582)
			(xy 374.069568 -243.926028) (xy 374.032804 -243.889268) (xy 374.002243 -243.84721) (xy 373.978638 -243.800888)
			(xy 373.962571 -243.751444) (xy 373.954437 -243.700095) (xy 373.954437 -243.648105) (xy 373.962571 -243.596756)
			(xy 373.978638 -243.547312) (xy 374.002243 -243.50099) (xy 374.032804 -243.458932) (xy 374.069568 -243.422172)
			(xy 374.111631 -243.391618) (xy 374.157956 -243.36802) (xy 374.207403 -243.35196) (xy 374.258753 -243.343834)
			(xy 374.284748 -243.34343) (xy 374.300242 -243.343684) (xy 374.31472 -243.344446) (xy 374.339358 -243.330984)
			(xy 374.483884 -243.08181) (xy 374.483376 -243.053362) (xy 374.475756 -243.041424) (xy 374.463551 -243.021453)
			(xy 374.444275 -242.978805) (xy 374.4312 -242.933866) (xy 374.424588 -242.887533) (xy 374.424194 -242.864132)
			(xy 374.424675 -242.838141) (xy 374.432802 -242.786799) (xy 374.448861 -242.73736) (xy 374.472458 -242.691043)
			(xy 374.503009 -242.648987) (xy 374.539764 -242.612229) (xy 374.581817 -242.581673) (xy 374.628132 -242.558073)
			(xy 374.67757 -242.542009) (xy 374.728911 -242.533877) (xy 374.754902 -242.533424) (xy 374.770142 -242.533678)
			(xy 374.784366 -242.53444) (xy 374.809258 -242.520978) (xy 374.953784 -242.27155) (xy 374.953276 -242.243356)
			(xy 374.945656 -242.231418) (xy 374.933452 -242.211447) (xy 374.914176 -242.168799) (xy 374.901102 -242.12386)
			(xy 374.894491 -242.077527) (xy 374.894094 -242.054126) (xy 374.894511 -242.030539) (xy 374.901211 -241.983843)
			(xy 374.914478 -241.938574) (xy 374.934044 -241.895649) (xy 374.946418 -241.875564) (xy 374.954292 -241.863118)
			(xy 374.955054 -241.835178) (xy 374.811036 -241.58702) (xy 374.786398 -241.573558) (xy 374.77192 -241.57432)
			(xy 374.754902 -241.574828) (xy 374.728914 -241.574319) (xy 374.677578 -241.566188) (xy 374.628146 -241.550128)
			(xy 374.581835 -241.526532) (xy 374.539785 -241.495983) (xy 374.503031 -241.459232) (xy 374.472479 -241.417184)
			(xy 374.448881 -241.370874) (xy 374.432817 -241.321443) (xy 374.424683 -241.270108) (xy 374.424194 -241.24412)
			(xy 374.424596 -241.22049) (xy 374.431329 -241.173711) (xy 374.44466 -241.128369) (xy 374.464318 -241.08539)
			(xy 374.476772 -241.065304) (xy 374.484392 -241.053112) (xy 374.485154 -241.024918) (xy 374.34139 -240.777014)
			(xy 374.316498 -240.763552) (xy 374.30202 -240.764314) (xy 374.284748 -240.764822) (xy 374.258755 -240.764342)
			(xy 374.207409 -240.756217) (xy 374.157966 -240.740158) (xy 374.111644 -240.716562) (xy 374.069584 -240.686009)
			(xy 374.032822 -240.649253) (xy 374.002263 -240.607197) (xy 373.97866 -240.560879) (xy 373.962594 -240.511438)
			(xy 373.954461 -240.460093) (xy 373.954461 -240.408107) (xy 373.962594 -240.356762) (xy 373.97866 -240.307321)
			(xy 374.002263 -240.261003) (xy 374.032822 -240.218947) (xy 374.069584 -240.182191) (xy 374.111644 -240.151638)
			(xy 374.157966 -240.128042) (xy 374.207409 -240.111983) (xy 374.258755 -240.103858) (xy 374.284748 -240.103406)
			(xy 374.300242 -240.10366) (xy 374.31472 -240.104422) (xy 374.339358 -240.09096) (xy 374.483884 -239.841786)
			(xy 374.483376 -239.813592) (xy 374.475756 -239.8014) (xy 374.463553 -239.781429) (xy 374.44428 -239.73878)
			(xy 374.431208 -239.693841) (xy 374.424599 -239.647509) (xy 374.424194 -239.624108) (xy 374.424677 -239.598118)
			(xy 374.432807 -239.546779) (xy 374.448868 -239.497343) (xy 374.472466 -239.451029) (xy 374.503018 -239.408977)
			(xy 374.539772 -239.372222) (xy 374.581824 -239.341669) (xy 374.628138 -239.318071) (xy 374.677573 -239.302008)
			(xy 374.728912 -239.293877) (xy 374.754902 -239.2934) (xy 374.770142 -239.293654) (xy 374.784366 -239.294416)
			(xy 374.809258 -239.280954) (xy 374.953784 -239.03178) (xy 374.953276 -239.003332) (xy 374.945656 -238.991394)
			(xy 374.933453 -238.971423) (xy 374.914181 -238.928774) (xy 374.90111 -238.883835) (xy 374.894502 -238.837503)
			(xy 374.894094 -238.814102) (xy 374.894348 -238.798862) (xy 374.89511 -238.784384) (xy 374.881648 -238.759746)
			(xy 374.034558 -238.273336) (xy 374.006364 -238.274098) (xy 373.994172 -238.281972) (xy 373.974036 -238.294482)
			(xy 373.930943 -238.314236) (xy 373.88547 -238.327632) (xy 373.83855 -238.334395) (xy 373.814848 -238.334804)
			(xy 373.788857 -238.334324) (xy 373.737513 -238.326199) (xy 373.688072 -238.310142) (xy 373.641753 -238.286547)
			(xy 373.599696 -238.255996) (xy 373.562936 -238.219241) (xy 373.532379 -238.177188) (xy 373.508777 -238.130872)
			(xy 373.492712 -238.081434) (xy 373.484579 -238.030091) (xy 373.484579 -237.978109) (xy 373.492712 -237.926766)
			(xy 373.508777 -237.877328) (xy 373.532379 -237.831012) (xy 373.562936 -237.788959) (xy 373.599696 -237.752204)
			(xy 373.641753 -237.721653) (xy 373.688072 -237.698058) (xy 373.737513 -237.682001) (xy 373.788857 -237.673876)
			(xy 373.814848 -237.673388) (xy 373.830088 -237.673642) (xy 373.844566 -237.674404) (xy 373.869204 -237.660942)
			(xy 374.01373 -237.411768) (xy 374.013222 -237.383574) (xy 374.005602 -237.371382) (xy 373.993402 -237.35141)
			(xy 373.974134 -237.30876) (xy 373.961067 -237.263821) (xy 373.954462 -237.21749) (xy 373.95404 -237.19409)
			(xy 373.954524 -237.168103) (xy 373.962657 -237.116768) (xy 373.97872 -237.067338) (xy 374.002319 -237.02103)
			(xy 374.032873 -236.978983) (xy 374.069628 -236.942235) (xy 374.111679 -236.911689) (xy 374.157992 -236.888098)
			(xy 374.207425 -236.872043) (xy 374.258761 -236.863919) (xy 374.284748 -236.863382) (xy 374.300242 -236.863636)
			(xy 374.314466 -236.864398) (xy 374.339358 -236.850936) (xy 374.483884 -236.601508) (xy 374.483376 -236.573314)
			(xy 374.475756 -236.561376) (xy 374.463554 -236.541405) (xy 374.444284 -236.498755) (xy 374.431216 -236.453816)
			(xy 374.42461 -236.407484) (xy 374.424194 -236.384084) (xy 374.4246 -236.360466) (xy 374.431289 -236.313706)
			(xy 374.444558 -236.268372) (xy 374.464136 -236.225385) (xy 374.476518 -236.205268) (xy 374.484392 -236.193076)
			(xy 374.485154 -236.164882) (xy 374.34139 -235.916978) (xy 374.316498 -235.903516) (xy 374.30202 -235.904278)
			(xy 374.284748 -235.904786) (xy 374.258758 -235.904307) (xy 374.207417 -235.896182) (xy 374.157979 -235.880125)
			(xy 374.111663 -235.856531) (xy 374.069607 -235.825982) (xy 374.032849 -235.789229) (xy 374.002294 -235.747178)
			(xy 373.978694 -235.700865) (xy 373.962629 -235.65143) (xy 373.954497 -235.60009) (xy 373.954497 -235.54811)
			(xy 373.962629 -235.49677) (xy 373.978694 -235.447335) (xy 374.002294 -235.401022) (xy 374.032849 -235.358971)
			(xy 374.069607 -235.322218) (xy 374.111663 -235.291669) (xy 374.157979 -235.268075) (xy 374.207417 -235.252018)
			(xy 374.258758 -235.243893) (xy 374.284748 -235.24337) (xy 374.300242 -235.243624) (xy 374.31472 -235.244386)
			(xy 374.339358 -235.230924) (xy 374.483884 -234.98175) (xy 374.483376 -234.953302) (xy 374.475756 -234.941364)
			(xy 374.463555 -234.921392) (xy 374.444287 -234.878743) (xy 374.43122 -234.833804) (xy 374.424616 -234.787472)
			(xy 374.424194 -234.764072) (xy 374.424706 -234.738086) (xy 374.43284 -234.686755) (xy 374.448903 -234.637329)
			(xy 374.472501 -234.591023) (xy 374.503051 -234.548979) (xy 374.539802 -234.512231) (xy 374.581849 -234.481685)
			(xy 374.628156 -234.458092) (xy 374.677585 -234.442033) (xy 374.728916 -234.433903) (xy 374.754902 -234.433364)
			(xy 374.770142 -234.433618) (xy 374.784366 -234.43438) (xy 374.809258 -234.420918) (xy 374.953784 -234.17149)
			(xy 374.953276 -234.143296) (xy 374.945656 -234.131358) (xy 374.933455 -234.111386) (xy 374.914188 -234.068737)
			(xy 374.901122 -234.023798) (xy 374.894518 -233.977466) (xy 374.894094 -233.954066) (xy 374.894508 -233.930478)
			(xy 374.901203 -233.88378) (xy 374.914465 -233.838508) (xy 374.934027 -233.795579) (xy 374.946418 -233.775504)
			(xy 374.954292 -233.763058) (xy 374.955054 -233.735118) (xy 374.811036 -233.48696) (xy 374.786398 -233.473498)
			(xy 374.77192 -233.47426) (xy 374.754902 -233.474768) (xy 374.728914 -233.474285) (xy 374.677577 -233.466154)
			(xy 374.628145 -233.450091) (xy 374.581834 -233.426493) (xy 374.539786 -233.39594) (xy 374.503035 -233.359185)
			(xy 374.472487 -233.317133) (xy 374.448894 -233.27082) (xy 374.432837 -233.221386) (xy 374.424712 -233.170048)
			(xy 374.424194 -233.14406) (xy 374.424593 -233.120429) (xy 374.431321 -233.073647) (xy 374.444648 -233.028303)
			(xy 374.464302 -232.985321) (xy 374.476772 -232.965244) (xy 374.484392 -232.953052) (xy 374.485154 -232.924858)
			(xy 374.34139 -232.676954) (xy 374.316498 -232.663492) (xy 374.30202 -232.664254) (xy 374.284748 -232.664762)
			(xy 374.25876 -232.664283) (xy 374.207423 -232.656158) (xy 374.157989 -232.640103) (xy 374.111675 -232.616511)
			(xy 374.069623 -232.585964) (xy 374.032868 -232.549214) (xy 374.002314 -232.507166) (xy 373.978716 -232.460856)
			(xy 373.962653 -232.411424) (xy 373.954521 -232.360088) (xy 373.954521 -232.308112) (xy 373.962653 -232.256776)
			(xy 373.978716 -232.207344) (xy 374.002314 -232.161034) (xy 374.032868 -232.118986) (xy 374.069623 -232.082236)
			(xy 374.111675 -232.051689) (xy 374.157989 -232.028097) (xy 374.207423 -232.012042) (xy 374.25876 -232.003917)
			(xy 374.284748 -232.003346) (xy 374.300242 -232.0036) (xy 374.314466 -232.004362) (xy 374.339358 -231.9909)
			(xy 374.483884 -231.741472) (xy 374.483376 -231.713278) (xy 374.475756 -231.70134) (xy 374.46355 -231.68137)
			(xy 374.444272 -231.638721) (xy 374.431195 -231.593782) (xy 374.42458 -231.547449) (xy 374.424194 -231.524048)
			(xy 374.424596 -231.500429) (xy 374.431277 -231.453665) (xy 374.444538 -231.408326) (xy 374.46411 -231.365333)
			(xy 374.476518 -231.345232) (xy 374.484392 -231.33304) (xy 374.485154 -231.304846) (xy 374.341644 -231.05745)
			(xy 374.316498 -231.043734) (xy 374.30202 -231.044496) (xy 374.284748 -231.045004) (xy 374.258757 -231.044524)
			(xy 374.207413 -231.036399) (xy 374.157972 -231.020342) (xy 374.111653 -230.996747) (xy 374.069596 -230.966196)
			(xy 374.032836 -230.929441) (xy 374.002279 -230.887388) (xy 373.978677 -230.841072) (xy 373.962612 -230.791634)
			(xy 373.954479 -230.740291) (xy 373.954479 -230.688309) (xy 373.962612 -230.636966) (xy 373.978677 -230.587528)
			(xy 374.002279 -230.541212) (xy 374.032836 -230.499159) (xy 374.069596 -230.462404) (xy 374.111653 -230.431853)
			(xy 374.157972 -230.408258) (xy 374.207413 -230.392201) (xy 374.258757 -230.384076) (xy 374.284748 -230.383588)
			(xy 374.299988 -230.383842) (xy 374.314466 -230.384604) (xy 374.339104 -230.371142) (xy 374.483884 -230.12146)
			(xy 374.483376 -230.093266) (xy 374.475756 -230.081328) (xy 374.463551 -230.061357) (xy 374.444275 -230.018709)
			(xy 374.431199 -229.97377) (xy 374.424586 -229.927437) (xy 374.424194 -229.904036) (xy 374.424597 -229.880417)
			(xy 374.431279 -229.833654) (xy 374.444542 -229.788316) (xy 374.464115 -229.745324) (xy 374.476518 -229.72522)
			(xy 374.484392 -229.713028) (xy 374.485154 -229.684834) (xy 374.341644 -229.437438) (xy 374.316498 -229.423722)
			(xy 374.30202 -229.424484) (xy 374.284748 -229.424992) (xy 374.258758 -229.424513) (xy 374.207416 -229.416388)
			(xy 374.157977 -229.40033) (xy 374.111659 -229.376736) (xy 374.069603 -229.346186) (xy 374.032845 -229.309433)
			(xy 374.002289 -229.267382) (xy 373.978688 -229.221067) (xy 373.962624 -229.171631) (xy 373.954491 -229.12029)
			(xy 373.954491 -229.06831) (xy 373.962624 -229.016969) (xy 373.978688 -228.967533) (xy 374.002289 -228.921218)
			(xy 374.032845 -228.879167) (xy 374.069603 -228.842414) (xy 374.111659 -228.811864) (xy 374.157977 -228.78827)
			(xy 374.207416 -228.772212) (xy 374.258758 -228.764087) (xy 374.284748 -228.763576) (xy 374.300242 -228.76383)
			(xy 374.314466 -228.764592) (xy 374.339358 -228.75113) (xy 374.483884 -228.501702) (xy 374.483376 -228.473508)
			(xy 374.475756 -228.46157) (xy 374.463555 -228.441599) (xy 374.444286 -228.398949) (xy 374.431218 -228.35401)
			(xy 374.424613 -228.307678) (xy 374.424194 -228.284278) (xy 374.424705 -228.258292) (xy 374.432839 -228.20696)
			(xy 374.448901 -228.157533) (xy 374.472499 -228.111227) (xy 374.503049 -228.069182) (xy 374.5398 -228.032433)
			(xy 374.581847 -228.001886) (xy 374.628155 -227.978292) (xy 374.677584 -227.962233) (xy 374.728916 -227.954103)
			(xy 374.754902 -227.95357) (xy 374.780419 -227.954044) (xy 374.830846 -227.961886) (xy 374.87947 -227.977383)
			(xy 374.925135 -228.000167) (xy 374.966756 -228.029698) (xy 375.003346 -228.065273) (xy 375.034035 -228.106048)
			(xy 375.046494 -228.128322) (xy 375.053352 -228.141022) (xy 375.077228 -228.155246) (xy 375.372376 -228.155246)
			(xy 375.396252 -228.141022) (xy 375.40311 -228.128322) (xy 375.415561 -228.106045) (xy 375.446256 -228.065278)
			(xy 375.48285 -228.02971) (xy 375.524473 -228.000185) (xy 375.570138 -227.977406) (xy 375.618761 -227.961913)
			(xy 375.669186 -227.954073) (xy 375.720218 -227.954073) (xy 375.770643 -227.961913) (xy 375.819266 -227.977406)
			(xy 375.864931 -228.000185) (xy 375.906554 -228.02971) (xy 375.943148 -228.065278) (xy 375.973843 -228.106045)
			(xy 375.986294 -228.128322) (xy 375.993152 -228.141022) (xy 376.017028 -228.155246) (xy 376.31243 -228.155246)
			(xy 376.336306 -228.141022) (xy 376.343164 -228.128322) (xy 376.355619 -228.10605) (xy 376.386321 -228.065292)
			(xy 376.422917 -228.029731) (xy 376.46454 -228.000213) (xy 376.510203 -227.977437) (xy 376.558821 -227.961944)
			(xy 376.609242 -227.954101) (xy 376.634756 -227.95357) (xy 376.649996 -227.953824) (xy 376.664474 -227.954586)
			(xy 376.689112 -227.941124) (xy 376.833892 -227.691696) (xy 376.833384 -227.663502) (xy 376.825764 -227.65131)
			(xy 376.813575 -227.631367) (xy 376.794318 -227.58878) (xy 376.781246 -227.543907) (xy 376.774617 -227.497641)
			(xy 376.774202 -227.474272) (xy 376.774714 -227.448287) (xy 376.782848 -227.396956) (xy 376.798911 -227.34753)
			(xy 376.822509 -227.301225) (xy 376.853059 -227.259181) (xy 376.88981 -227.222435) (xy 376.931857 -227.191889)
			(xy 376.978165 -227.168297) (xy 377.027593 -227.152239) (xy 377.078924 -227.144111) (xy 377.10491 -227.143564)
			(xy 377.12015 -227.143818) (xy 377.134374 -227.14458) (xy 377.159266 -227.131118) (xy 377.303792 -226.88169)
			(xy 377.303284 -226.853496) (xy 377.295664 -226.841558) (xy 377.283463 -226.821586) (xy 377.264195 -226.778937)
			(xy 377.251129 -226.733998) (xy 377.244525 -226.687666) (xy 377.244102 -226.664266) (xy 377.244614 -226.638281)
			(xy 377.252749 -226.586951) (xy 377.268813 -226.537526) (xy 377.292411 -226.491222) (xy 377.322961 -226.449179)
			(xy 377.359712 -226.412433) (xy 377.401759 -226.381888) (xy 377.448066 -226.358296) (xy 377.497494 -226.342239)
			(xy 377.548825 -226.334111) (xy 377.57481 -226.333558) (xy 377.59005 -226.333812) (xy 377.604528 -226.334574)
			(xy 377.629166 -226.321112) (xy 377.773692 -226.071938) (xy 377.773184 -226.043744) (xy 377.765564 -226.031552)
			(xy 377.753363 -226.01158) (xy 377.734096 -225.968931) (xy 377.721031 -225.923992) (xy 377.714428 -225.87766)
			(xy 377.714002 -225.85426) (xy 377.714515 -225.828275) (xy 377.72265 -225.776946) (xy 377.738715 -225.727522)
			(xy 377.762313 -225.681218) (xy 377.792864 -225.639176) (xy 377.829615 -225.602431) (xy 377.871661 -225.571887)
			(xy 377.917968 -225.548296) (xy 377.967395 -225.532238) (xy 378.018725 -225.524111) (xy 378.04471 -225.523552)
			(xy 378.060204 -225.523806) (xy 378.074428 -225.524568) (xy 378.09932 -225.511106) (xy 378.243846 -225.261678)
			(xy 378.243338 -225.233484) (xy 378.235718 -225.221546) (xy 378.223519 -225.201574) (xy 378.204256 -225.158923)
			(xy 378.191193 -225.113984) (xy 378.184592 -225.067653) (xy 378.184156 -225.044254) (xy 378.184669 -225.018268)
			(xy 378.192805 -224.966937) (xy 378.20887 -224.91751) (xy 378.232467 -224.871205) (xy 378.263017 -224.82916)
			(xy 378.299767 -224.792411) (xy 378.341813 -224.761862) (xy 378.38812 -224.738266) (xy 378.437547 -224.722203)
			(xy 378.488878 -224.714068) (xy 378.514864 -224.713546) (xy 378.530104 -224.7138) (xy 378.544582 -224.714562)
			(xy 378.56922 -224.7011) (xy 378.713746 -224.451926) (xy 378.713238 -224.423732) (xy 378.705618 -224.41154)
			(xy 378.693414 -224.391569) (xy 378.674138 -224.348921) (xy 378.661062 -224.303982) (xy 378.654448 -224.257649)
			(xy 378.654056 -224.234248) (xy 378.654536 -224.208255) (xy 378.662661 -224.156909) (xy 378.678718 -224.107466)
			(xy 378.702313 -224.061143) (xy 378.732863 -224.019082) (xy 378.769618 -223.982318) (xy 378.811671 -223.951757)
			(xy 378.857988 -223.92815) (xy 378.907427 -223.91208) (xy 378.958771 -223.903942) (xy 378.984764 -223.90354)
			(xy 379.000258 -223.903794) (xy 379.014482 -223.904556) (xy 379.039374 -223.891094) (xy 380.170182 -221.942152)
			(xy 380.171452 -221.917768) (xy 380.166372 -221.906592) (xy 380.155966 -221.881825) (xy 380.1447 -221.829308)
			(xy 380.14402 -221.802452) (xy 380.14402 -221.080076) (xy 380.144594 -221.055117) (xy 380.154337 -221.006158)
			(xy 380.173445 -220.960041) (xy 380.201184 -220.918538) (xy 380.218442 -220.900498) (xy 387.950456 -213.168484)
			(xy 387.958076 -213.148164) (xy 387.957568 -213.137242) (xy 387.953632 -213.066255) (xy 387.952792 -212.92407)
			(xy 387.959985 -212.782064) (xy 387.975189 -212.640691) (xy 387.998356 -212.500403) (xy 388.02941 -212.361648)
			(xy 388.068254 -212.224868) (xy 388.114763 -212.090502) (xy 388.168788 -211.958977) (xy 388.230156 -211.830715)
			(xy 388.298673 -211.706124) (xy 388.374119 -211.585603) (xy 388.456253 -211.469536) (xy 388.544812 -211.358295)
			(xy 388.639514 -211.252234) (xy 388.740057 -211.151693) (xy 388.846119 -211.056992) (xy 388.957362 -210.968433)
			(xy 389.073429 -210.886301) (xy 389.193951 -210.810857) (xy 389.318543 -210.742342) (xy 389.446806 -210.680975)
			(xy 389.578332 -210.626951) (xy 389.712699 -210.580444) (xy 389.849479 -210.541603) (xy 389.988234 -210.51055)
			(xy 390.128523 -210.487385) (xy 390.269896 -210.472183) (xy 390.411902 -210.464991) (xy 390.554087 -210.465833)
			(xy 390.625076 -210.469734) (xy 390.635998 -210.470242) (xy 390.656318 -210.462622) (xy 393.369546 -207.749394)
			(xy 393.376397 -207.741998) (xy 393.384138 -207.723399) (xy 393.384532 -207.713326) (xy 393.384532 -194.232276)
			(xy 393.384105 -194.222207) (xy 393.376388 -194.203606) (xy 393.369546 -194.196208) (xy 393.184888 -194.01155)
			(xy 393.177491 -194.0047) (xy 393.158893 -193.996962) (xy 393.14882 -193.996564) (xy 393.046458 -193.996564)
			(xy 393.034831 -193.997128) (xy 393.013918 -194.0073) (xy 393.006326 -194.016122) (xy 392.988134 -194.038563)
			(xy 392.946131 -194.078223) (xy 392.898631 -194.111098) (xy 392.846718 -194.136439) (xy 392.791579 -194.153667)
			(xy 392.734474 -194.162387) (xy 392.70559 -194.162934) (xy 392.678221 -194.162461) (xy 392.624044 -194.154635)
			(xy 392.571543 -194.139145) (xy 392.521795 -194.116309) (xy 392.475822 -194.086596) (xy 392.454892 -194.068954)
			(xy 392.44778 -194.062858) (xy 392.430762 -194.056508) (xy 392.345418 -194.056508) (xy 392.3284 -194.062858)
			(xy 392.321288 -194.068954) (xy 392.300357 -194.086597) (xy 392.254392 -194.116325) (xy 392.204645 -194.13917)
			(xy 392.152141 -194.15466) (xy 392.097961 -194.162478) (xy 392.07059 -194.162934) (xy 392.041706 -194.1624)
			(xy 391.984599 -194.153686) (xy 391.92946 -194.136457) (xy 391.877551 -194.111108) (xy 391.830058 -194.07822)
			(xy 391.78807 -194.038545) (xy 391.769854 -194.016122) (xy 391.762268 -194.007284) (xy 391.741357 -193.997082)
			(xy 391.729722 -193.996564) (xy 371.860318 -193.996564) (xy 371.835361 -193.995985) (xy 371.786409 -193.986231)
			(xy 371.7403 -193.967115) (xy 371.698807 -193.93937) (xy 371.68074 -193.922142) (xy 366.817148 -189.05855)
			(xy 366.809749 -189.051706) (xy 366.79115 -189.043983) (xy 366.78108 -189.043564) (xy 362.015532 -189.043564)
			(xy 361.990574 -189.042986) (xy 361.941621 -189.033235) (xy 361.89551 -189.01412) (xy 361.854015 -188.986377)
			(xy 361.835954 -188.969142) (xy 360.057954 -187.191142) (xy 360.040696 -187.1731) (xy 360.012941 -187.131606)
			(xy 359.99383 -187.085488) (xy 359.984101 -187.036525) (xy 359.983532 -187.011564) (xy 359.983532 -181.549802)
			(xy 359.98311 -181.539731) (xy 359.9754 -181.521123) (xy 359.968546 -181.513734) (xy 359.131362 -180.67655)
			(xy 359.123964 -180.669704) (xy 359.105365 -180.661976) (xy 359.095294 -180.661564) (xy 353.633532 -180.661564)
			(xy 353.608574 -180.660986) (xy 353.559621 -180.651235) (xy 353.51351 -180.63212) (xy 353.472015 -180.604377)
			(xy 353.453954 -180.587142) (xy 351.675954 -178.809142) (xy 351.658696 -178.7911) (xy 351.630941 -178.749606)
			(xy 351.61183 -178.703488) (xy 351.602101 -178.654525) (xy 351.601532 -178.629564) (xy 351.601532 -173.040802)
			(xy 351.60111 -173.030731) (xy 351.5934 -173.012123) (xy 351.586546 -173.004734) (xy 351.003362 -172.42155)
			(xy 350.995964 -172.414704) (xy 350.977365 -172.406976) (xy 350.967294 -172.406564) (xy 341.17915 -172.406564)
			(xy 341.169072 -172.406993) (xy 341.150476 -172.414769) (xy 341.136334 -172.42913) (xy 341.13216 -172.438314)
			(xy 341.116949 -172.474599) (xy 341.080083 -172.544112) (xy 341.036256 -172.609458) (xy 340.985933 -172.669944)
			(xy 340.929648 -172.724927) (xy 340.868001 -172.773821) (xy 340.801646 -172.816107) (xy 340.73129 -172.851335)
			(xy 340.65768 -172.879131) (xy 340.581599 -172.899199) (xy 340.503856 -172.911326) (xy 340.425278 -172.915382)
			(xy 340.3467 -172.911326) (xy 340.268957 -172.899199) (xy 340.192876 -172.879131) (xy 340.119266 -172.851335)
			(xy 340.04891 -172.816107) (xy 339.982555 -172.773821) (xy 339.920908 -172.724927) (xy 339.864623 -172.669944)
			(xy 339.8143 -172.609458) (xy 339.770473 -172.544112) (xy 339.733607 -172.474599) (xy 339.718396 -172.438314)
			(xy 339.714209 -172.429144) (xy 339.700048 -172.414819) (xy 339.681476 -172.40702) (xy 339.671406 -172.406564)
			(xy 337.660996 -172.406564) (xy 337.653122 -172.406856) (xy 337.638118 -172.411638) (xy 337.631532 -172.415962)
			(xy 337.609767 -172.430685) (xy 337.56165 -172.451774) (xy 337.510227 -172.462534) (xy 337.483958 -172.463206)
			(xy 333.800196 -172.463206) (xy 333.790126 -172.46363) (xy 333.771523 -172.471346) (xy 333.764128 -172.478192)
			(xy 333.434944 -172.807376) (xy 333.428105 -172.814776) (xy 333.420391 -172.833375) (xy 333.419958 -172.843444)
			(xy 333.419958 -214.864188) (xy 333.42038 -214.874258) (xy 333.428098 -214.89286) (xy 333.434944 -214.900256)
			(xy 336.083262 -217.548574) (xy 338.152884 -217.548574) (xy 338.152884 -217.494026) (xy 338.160647 -217.440032)
			(xy 338.176017 -217.387693) (xy 338.198679 -217.338074) (xy 338.228172 -217.292186) (xy 338.263897 -217.250963)
			(xy 338.305125 -217.215244) (xy 338.351016 -217.185756) (xy 338.400638 -217.1631) (xy 338.452979 -217.147737)
			(xy 338.506973 -217.13998) (xy 338.534248 -217.13952) (xy 339.550248 -217.13952) (xy 339.577514 -217.140046)
			(xy 339.63149 -217.147813) (xy 339.683811 -217.163181) (xy 339.733413 -217.185839) (xy 339.779286 -217.215325)
			(xy 339.820495 -217.251039) (xy 339.856204 -217.292253) (xy 339.885684 -217.338129) (xy 339.908336 -217.387734)
			(xy 339.923698 -217.440057) (xy 339.931458 -217.494034) (xy 339.931458 -217.548566) (xy 339.923698 -217.602543)
			(xy 339.908336 -217.654866) (xy 339.885684 -217.704471) (xy 339.856204 -217.750347) (xy 339.820495 -217.791561)
			(xy 339.779286 -217.827275) (xy 339.733413 -217.856761) (xy 339.683811 -217.879419) (xy 339.63149 -217.894787)
			(xy 339.577514 -217.902554) (xy 339.550248 -217.903044) (xy 338.534248 -217.903044) (xy 338.506973 -217.90262)
			(xy 338.452979 -217.894863) (xy 338.400638 -217.8795) (xy 338.351016 -217.856844) (xy 338.305125 -217.827356)
			(xy 338.263897 -217.791637) (xy 338.228172 -217.750414) (xy 338.198679 -217.704526) (xy 338.176017 -217.654907)
			(xy 338.160647 -217.602568) (xy 338.152884 -217.548574) (xy 336.083262 -217.548574) (xy 338.659978 -220.12529)
			(xy 338.6963 -220.128846) (xy 338.71154 -220.118178) (xy 338.733862 -220.103534) (xy 338.78196 -220.080375)
			(xy 338.832973 -220.064644) (xy 338.885762 -220.056694) (xy 338.912454 -220.056202) (xy 338.940441 -220.056719)
			(xy 338.995728 -220.065469) (xy 339.048965 -220.082761) (xy 339.098841 -220.108169) (xy 339.144127 -220.141067)
			(xy 339.183709 -220.180645) (xy 339.216612 -220.225929) (xy 339.242025 -220.275802) (xy 339.259322 -220.329037)
			(xy 339.268078 -220.384323) (xy 339.268562 -220.41231) (xy 339.268105 -220.439004) (xy 339.260166 -220.491799)
			(xy 339.244423 -220.542813) (xy 339.22123 -220.5909) (xy 339.206586 -220.613224) (xy 339.195918 -220.628464)
			(xy 339.199474 -220.664786) (xy 340.157562 -221.622874) (xy 340.174818 -221.640916) (xy 340.202569 -221.682412)
			(xy 340.221675 -221.72853) (xy 340.231401 -221.777492) (xy 340.231984 -221.802452) (xy 340.231306 -221.829307)
			(xy 340.220025 -221.881819) (xy 340.209632 -221.906592) (xy 340.204552 -221.917768) (xy 340.205822 -221.942152)
			(xy 340.396576 -222.271082) (xy 340.421468 -222.284544) (xy 340.435692 -222.283782) (xy 340.451186 -222.283528)
			(xy 340.477175 -222.28401) (xy 340.528513 -222.29214) (xy 340.577947 -222.308201) (xy 340.62426 -222.331799)
			(xy 340.66631 -222.362351) (xy 340.703063 -222.399107) (xy 340.733613 -222.441159) (xy 340.757207 -222.487473)
			(xy 340.773265 -222.536908) (xy 340.781392 -222.588247) (xy 340.781894 -222.614236) (xy 340.781492 -222.637638)
			(xy 340.774898 -222.683975) (xy 340.761832 -222.728918) (xy 340.742556 -222.771569) (xy 340.730332 -222.791528)
			(xy 340.722712 -222.80372) (xy 340.72195 -222.831914) (xy 341.33663 -223.891094) (xy 341.361268 -223.904556)
			(xy 341.375746 -223.903794) (xy 341.390986 -223.90354) (xy 341.416975 -223.904022) (xy 341.468312 -223.912152)
			(xy 341.517745 -223.928214) (xy 341.564057 -223.951811) (xy 341.606106 -223.982364) (xy 341.642858 -224.019119)
			(xy 341.673406 -224.061172) (xy 341.697 -224.107486) (xy 341.713056 -224.156921) (xy 341.721181 -224.208259)
			(xy 341.721694 -224.234248) (xy 341.721291 -224.25765) (xy 341.714695 -224.303986) (xy 341.701628 -224.348929)
			(xy 341.682351 -224.391578) (xy 341.670132 -224.41154) (xy 341.662512 -224.423478) (xy 341.662004 -224.451926)
			(xy 341.80653 -224.7011) (xy 341.831422 -224.714562) (xy 341.845646 -224.7138) (xy 341.86114 -224.713546)
			(xy 341.887126 -224.714058) (xy 341.938459 -224.722194) (xy 341.987887 -224.738258) (xy 342.034194 -224.761855)
			(xy 342.076241 -224.792405) (xy 342.112992 -224.829155) (xy 342.143542 -224.871201) (xy 342.16714 -224.917508)
			(xy 342.183205 -224.966935) (xy 342.191341 -225.018268) (xy 342.191848 -225.044254) (xy 342.191445 -225.067656)
			(xy 342.184847 -225.113991) (xy 342.171778 -225.158932) (xy 342.152498 -225.20158) (xy 342.140286 -225.221546)
			(xy 342.132666 -225.233738) (xy 342.132158 -225.261932) (xy 342.276684 -225.511106) (xy 342.301322 -225.524568)
			(xy 342.3158 -225.523806) (xy 342.33104 -225.523552) (xy 342.357026 -225.524064) (xy 342.408358 -225.5322)
			(xy 342.457786 -225.548264) (xy 342.504093 -225.571861) (xy 342.546139 -225.602411) (xy 342.582889 -225.639161)
			(xy 342.613439 -225.681207) (xy 342.637036 -225.727514) (xy 342.6531 -225.776942) (xy 342.661236 -225.828274)
			(xy 342.661748 -225.85426) (xy 342.661344 -225.877661) (xy 342.654746 -225.923997) (xy 342.641676 -225.968937)
			(xy 342.622396 -226.011584) (xy 342.610186 -226.031552) (xy 342.602566 -226.04349) (xy 342.602058 -226.071684)
			(xy 342.746584 -226.321112) (xy 342.771476 -226.334574) (xy 342.7857 -226.333812) (xy 342.801194 -226.333558)
			(xy 342.827182 -226.334067) (xy 342.87852 -226.342197) (xy 342.927953 -226.358257) (xy 342.974266 -226.381852)
			(xy 343.016318 -226.412401) (xy 343.053073 -226.449152) (xy 343.083627 -226.4912) (xy 343.107228 -226.53751)
			(xy 343.123294 -226.586941) (xy 343.13143 -226.638278) (xy 343.131902 -226.664266) (xy 343.131498 -226.687667)
			(xy 343.1249 -226.734003) (xy 343.111831 -226.778944) (xy 343.092553 -226.821592) (xy 343.08034 -226.841558)
			(xy 343.07272 -226.85375) (xy 343.072212 -226.881944) (xy 343.216738 -227.131118) (xy 343.24163 -227.14458)
			(xy 343.255854 -227.143818) (xy 343.271094 -227.143564) (xy 343.297082 -227.144073) (xy 343.348419 -227.152203)
			(xy 343.397852 -227.168263) (xy 343.444165 -227.191858) (xy 343.486216 -227.222407) (xy 343.522971 -227.259158)
			(xy 343.553524 -227.301206) (xy 343.577124 -227.347516) (xy 343.593189 -227.396948) (xy 343.601324 -227.448284)
			(xy 343.601802 -227.474272) (xy 343.601386 -227.497642) (xy 343.594776 -227.543914) (xy 343.581713 -227.588793)
			(xy 343.562457 -227.631384) (xy 343.55024 -227.65131) (xy 343.54262 -227.663502) (xy 343.542112 -227.691696)
			(xy 343.686892 -227.941124) (xy 343.71153 -227.954586) (xy 343.725754 -227.953824) (xy 343.740994 -227.95357)
			(xy 343.766511 -227.954043) (xy 343.816939 -227.961884) (xy 343.865564 -227.97738) (xy 343.91123 -228.000164)
			(xy 343.952852 -228.029695) (xy 343.989443 -228.06527) (xy 344.020133 -228.106045) (xy 344.032586 -228.128322)
			(xy 344.039444 -228.141022) (xy 344.06332 -228.155246) (xy 344.358722 -228.155246) (xy 344.382598 -228.141022)
			(xy 344.389456 -228.128322) (xy 344.401911 -228.10605) (xy 344.432612 -228.06529) (xy 344.469208 -228.029729)
			(xy 344.510831 -228.00021) (xy 344.556494 -227.977433) (xy 344.605113 -227.961939) (xy 344.655534 -227.954095)
			(xy 344.681048 -227.95357) (xy 344.707033 -227.954083) (xy 344.758363 -227.962219) (xy 344.807789 -227.978284)
			(xy 344.854093 -228.001882) (xy 344.896137 -228.032433) (xy 344.932884 -228.069183) (xy 344.963431 -228.111229)
			(xy 344.987026 -228.157535) (xy 345.003087 -228.206962) (xy 345.011219 -228.258293) (xy 345.011756 -228.284278)
			(xy 345.011351 -228.307679) (xy 345.004751 -228.354013) (xy 344.991679 -228.398953) (xy 344.972397 -228.441598)
			(xy 344.960194 -228.46157) (xy 344.952574 -228.473508) (xy 344.952066 -228.501702) (xy 345.096592 -228.75113)
			(xy 345.121484 -228.764592) (xy 345.135708 -228.76383) (xy 345.151202 -228.763576) (xy 345.17719 -228.764086)
			(xy 345.228527 -228.772217) (xy 345.27796 -228.788279) (xy 345.324271 -228.811876) (xy 345.366321 -228.842427)
			(xy 345.403074 -228.87918) (xy 345.433625 -228.921231) (xy 345.457222 -228.967542) (xy 345.473284 -229.016975)
			(xy 345.481414 -229.068312) (xy 345.481414 -229.120288) (xy 345.473284 -229.171625) (xy 345.457222 -229.221058)
			(xy 345.433625 -229.267369) (xy 345.403074 -229.30942) (xy 345.366321 -229.346173) (xy 345.324271 -229.376724)
			(xy 345.27796 -229.400321) (xy 345.228527 -229.416383) (xy 345.17719 -229.424514) (xy 345.151202 -229.424992)
			(xy 345.13393 -229.424484) (xy 345.119452 -229.423722) (xy 345.094306 -229.437438) (xy 344.950796 -229.684834)
			(xy 344.951558 -229.713028) (xy 344.959432 -229.72522) (xy 344.971851 -229.745317) (xy 344.991444 -229.788306)
			(xy 345.004715 -229.833646) (xy 345.011395 -229.880414) (xy 345.011756 -229.904036) (xy 345.011354 -229.927438)
			(xy 345.004759 -229.973775) (xy 344.991692 -230.018717) (xy 344.972414 -230.061366) (xy 344.960194 -230.081328)
			(xy 344.952574 -230.093266) (xy 344.952066 -230.12146) (xy 345.096846 -230.371142) (xy 345.121484 -230.384604)
			(xy 345.135962 -230.383842) (xy 345.151202 -230.383588) (xy 345.177189 -230.384098) (xy 345.228524 -230.392229)
			(xy 345.277955 -230.40829) (xy 345.324265 -230.431886) (xy 345.366313 -230.462436) (xy 345.403065 -230.499188)
			(xy 345.433615 -230.541237) (xy 345.457211 -230.587547) (xy 345.473272 -230.636978) (xy 345.481402 -230.688313)
			(xy 345.481402 -230.740287) (xy 345.473272 -230.791622) (xy 345.457211 -230.841053) (xy 345.433615 -230.887363)
			(xy 345.403065 -230.929412) (xy 345.366313 -230.966164) (xy 345.324265 -230.996714) (xy 345.277955 -231.02031)
			(xy 345.228524 -231.036371) (xy 345.177189 -231.044502) (xy 345.151202 -231.045004) (xy 345.13393 -231.044496)
			(xy 345.119452 -231.043734) (xy 345.094306 -231.05745) (xy 344.950796 -231.304846) (xy 344.951558 -231.33304)
			(xy 344.959432 -231.345232) (xy 344.97185 -231.36533) (xy 344.991441 -231.408318) (xy 345.004711 -231.453659)
			(xy 345.011389 -231.500426) (xy 345.011756 -231.524048) (xy 345.011353 -231.54745) (xy 345.004757 -231.593786)
			(xy 344.991688 -231.638727) (xy 344.972409 -231.681376) (xy 344.960194 -231.70134) (xy 344.952574 -231.713278)
			(xy 344.952066 -231.741472) (xy 345.096592 -231.9909) (xy 345.121484 -232.004362) (xy 345.135708 -232.0036)
			(xy 345.151202 -232.003346) (xy 345.177193 -232.003856) (xy 345.228534 -232.011988) (xy 345.277971 -232.028051)
			(xy 345.324287 -232.05165) (xy 345.366341 -232.082204) (xy 345.403097 -232.118961) (xy 345.433651 -232.161015)
			(xy 345.45725 -232.207331) (xy 345.473313 -232.256768) (xy 345.481444 -232.308109) (xy 345.481444 -232.360091)
			(xy 345.473313 -232.411432) (xy 345.45725 -232.460869) (xy 345.433651 -232.507185) (xy 345.403097 -232.549239)
			(xy 345.366341 -232.585996) (xy 345.324287 -232.61655) (xy 345.277971 -232.640149) (xy 345.228534 -232.656212)
			(xy 345.177193 -232.664344) (xy 345.151202 -232.664762) (xy 345.13393 -232.664254) (xy 345.119452 -232.663492)
			(xy 345.09456 -232.676954) (xy 344.950796 -232.924858) (xy 344.951304 -232.953052) (xy 344.959178 -232.965244)
			(xy 344.971622 -232.985335) (xy 344.991267 -233.028316) (xy 345.004592 -233.073656) (xy 345.011326 -233.120431)
			(xy 345.011756 -233.14406) (xy 345.011249 -233.170051) (xy 345.003124 -233.221393) (xy 344.987067 -233.270832)
			(xy 344.963474 -233.31715) (xy 344.932926 -233.359208) (xy 344.896175 -233.395969) (xy 344.854125 -233.426528)
			(xy 344.807813 -233.450134) (xy 344.758378 -233.466204) (xy 344.707038 -233.474343) (xy 344.681048 -233.474768)
			(xy 344.66403 -233.47426) (xy 344.649298 -233.473498) (xy 344.62466 -233.48696) (xy 344.480896 -233.734864)
			(xy 344.481404 -233.763058) (xy 344.489278 -233.77525) (xy 344.501721 -233.795341) (xy 344.521365 -233.838322)
			(xy 344.53469 -233.883662) (xy 344.541423 -233.930437) (xy 344.541856 -233.954066) (xy 344.541452 -233.977467)
			(xy 344.534853 -234.023802) (xy 344.521783 -234.068743) (xy 344.502502 -234.111389) (xy 344.490294 -234.131358)
			(xy 344.482674 -234.14355) (xy 344.481912 -234.171744) (xy 344.626438 -234.420918) (xy 344.65133 -234.43438)
			(xy 344.665554 -234.433618) (xy 344.681048 -234.433364) (xy 344.707034 -234.433877) (xy 344.758364 -234.442013)
			(xy 344.80779 -234.458078) (xy 344.854095 -234.481676) (xy 344.896139 -234.512226) (xy 344.932887 -234.548977)
			(xy 344.963434 -234.591022) (xy 344.987029 -234.637329) (xy 345.003091 -234.686756) (xy 345.011224 -234.738086)
			(xy 345.011756 -234.764072) (xy 345.011351 -234.787473) (xy 345.004752 -234.833808) (xy 344.991681 -234.878748)
			(xy 344.972399 -234.921394) (xy 344.960194 -234.941364) (xy 344.952574 -234.953556) (xy 344.952066 -234.98175)
			(xy 345.096592 -235.230924) (xy 345.12123 -235.244386) (xy 345.135708 -235.243624) (xy 345.151202 -235.24337)
			(xy 345.177191 -235.24388) (xy 345.228528 -235.252011) (xy 345.277962 -235.268073) (xy 345.324274 -235.291671)
			(xy 345.366325 -235.322223) (xy 345.403079 -235.358977) (xy 345.43363 -235.401027) (xy 345.457227 -235.44734)
			(xy 345.473289 -235.496773) (xy 345.48142 -235.548111) (xy 345.48142 -235.600089) (xy 345.473289 -235.651427)
			(xy 345.457227 -235.70086) (xy 345.43363 -235.747173) (xy 345.403079 -235.789223) (xy 345.366325 -235.825977)
			(xy 345.324274 -235.856529) (xy 345.277962 -235.880127) (xy 345.228528 -235.896189) (xy 345.177191 -235.90432)
			(xy 345.151202 -235.904786) (xy 345.13393 -235.904278) (xy 345.119452 -235.903516) (xy 345.09456 -235.916978)
			(xy 344.950796 -236.164882) (xy 344.951558 -236.193076) (xy 344.959432 -236.205268) (xy 344.971848 -236.225366)
			(xy 344.991434 -236.268355) (xy 345.004699 -236.313696) (xy 345.011372 -236.360463) (xy 345.011756 -236.384084)
			(xy 345.011351 -236.407485) (xy 345.004749 -236.453819) (xy 344.991677 -236.498758) (xy 344.972395 -236.541403)
			(xy 344.960194 -236.561376) (xy 344.952574 -236.573314) (xy 344.952066 -236.601508) (xy 345.096592 -236.850936)
			(xy 345.121484 -236.864398) (xy 345.135708 -236.863636) (xy 345.151202 -236.863382) (xy 345.177189 -236.863892)
			(xy 345.228524 -236.872022) (xy 345.277955 -236.888083) (xy 345.324265 -236.911679) (xy 345.366314 -236.942229)
			(xy 345.403066 -236.97898) (xy 345.433617 -237.021028) (xy 345.457213 -237.067337) (xy 345.473276 -237.116768)
			(xy 345.481408 -237.168103) (xy 345.48191 -237.19409) (xy 345.481504 -237.217491) (xy 345.474903 -237.263825)
			(xy 345.461832 -237.308765) (xy 345.442552 -237.351411) (xy 345.430348 -237.371382) (xy 345.422728 -237.383574)
			(xy 345.42222 -237.411768) (xy 345.566746 -237.660942) (xy 345.591384 -237.674404) (xy 345.605862 -237.673642)
			(xy 345.621102 -237.673388) (xy 345.647089 -237.673898) (xy 345.698424 -237.682029) (xy 345.747855 -237.69809)
			(xy 345.794165 -237.721686) (xy 345.836213 -237.752236) (xy 345.872965 -237.788988) (xy 345.903515 -237.831037)
			(xy 345.927111 -237.877347) (xy 345.943172 -237.926778) (xy 345.951302 -237.978113) (xy 345.951302 -238.030087)
			(xy 345.943172 -238.081422) (xy 345.927111 -238.130853) (xy 345.903515 -238.177163) (xy 345.872965 -238.219212)
			(xy 345.836213 -238.255964) (xy 345.794165 -238.286514) (xy 345.747855 -238.31011) (xy 345.698424 -238.326171)
			(xy 345.647089 -238.334302) (xy 345.621102 -238.334804) (xy 345.597399 -238.334398) (xy 345.55048 -238.327631)
			(xy 345.505006 -238.314236) (xy 345.461911 -238.294488) (xy 345.441778 -238.281972) (xy 345.429586 -238.274098)
			(xy 345.401392 -238.273336) (xy 344.554302 -238.759746) (xy 344.54084 -238.784384) (xy 344.541602 -238.798862)
			(xy 344.541856 -238.814102) (xy 344.541449 -238.837503) (xy 344.534846 -238.883835) (xy 344.521771 -238.928773)
			(xy 344.502487 -238.971417) (xy 344.490294 -238.991394) (xy 344.482674 -239.003332) (xy 344.482166 -239.03178)
			(xy 344.626692 -239.280954) (xy 344.651584 -239.294416) (xy 344.665808 -239.293654) (xy 344.681048 -239.2934)
			(xy 344.707032 -239.293913) (xy 344.758361 -239.30205) (xy 344.807784 -239.318115) (xy 344.854087 -239.341714)
			(xy 344.896128 -239.372264) (xy 344.932872 -239.409015) (xy 344.963416 -239.451061) (xy 344.987006 -239.497367)
			(xy 345.003063 -239.546794) (xy 345.011191 -239.598123) (xy 345.011756 -239.624108) (xy 345.011349 -239.647508)
			(xy 345.004745 -239.693841) (xy 344.991669 -239.738778) (xy 344.972385 -239.781421) (xy 344.960194 -239.8014)
			(xy 344.952574 -239.813592) (xy 344.952066 -239.841786) (xy 345.096592 -240.09096) (xy 345.12123 -240.104422)
			(xy 345.135708 -240.10366) (xy 345.151202 -240.103406) (xy 345.177188 -240.103916) (xy 345.22852 -240.112046)
			(xy 345.277948 -240.128107) (xy 345.324256 -240.151702) (xy 345.366302 -240.18225) (xy 345.403051 -240.219)
			(xy 345.433599 -240.261046) (xy 345.457194 -240.307354) (xy 345.473254 -240.356782) (xy 345.481385 -240.408114)
			(xy 345.481385 -240.460086) (xy 345.473254 -240.511418) (xy 345.457194 -240.560846) (xy 345.433599 -240.607154)
			(xy 345.403051 -240.6492) (xy 345.366302 -240.68595) (xy 345.324256 -240.716498) (xy 345.277948 -240.740093)
			(xy 345.22852 -240.756154) (xy 345.177188 -240.764284) (xy 345.151202 -240.764822) (xy 345.13393 -240.764314)
			(xy 345.119452 -240.763552) (xy 345.09456 -240.777014) (xy 344.950796 -241.024918) (xy 344.951304 -241.053112)
			(xy 344.959178 -241.065304) (xy 344.971624 -241.085394) (xy 344.991274 -241.128374) (xy 345.004605 -241.173714)
			(xy 345.011345 -241.220491) (xy 345.011756 -241.24412) (xy 345.011245 -241.270108) (xy 345.003112 -241.321442)
			(xy 344.98705 -241.370873) (xy 344.963454 -241.417184) (xy 344.932905 -241.459233) (xy 344.896154 -241.495986)
			(xy 344.854107 -241.526539) (xy 344.807799 -241.550139) (xy 344.75837 -241.566206) (xy 344.707035 -241.574343)
			(xy 344.681048 -241.574828) (xy 344.66403 -241.57432) (xy 344.649298 -241.573558) (xy 344.62466 -241.58702)
			(xy 344.480896 -241.834924) (xy 344.481404 -241.863118) (xy 344.489278 -241.87531) (xy 344.501724 -241.8954)
			(xy 344.521373 -241.938381) (xy 344.534703 -241.983721) (xy 344.541442 -242.030497) (xy 344.541856 -242.054126)
			(xy 344.541455 -242.077528) (xy 344.534861 -242.123865) (xy 344.521795 -242.168809) (xy 344.502518 -242.211459)
			(xy 344.490294 -242.231418) (xy 344.482674 -242.24361) (xy 344.481912 -242.271804) (xy 344.626438 -242.520978)
			(xy 344.65133 -242.53444) (xy 344.665554 -242.533678) (xy 344.681048 -242.533424) (xy 344.707032 -242.533937)
			(xy 344.758359 -242.542074) (xy 344.807781 -242.55814) (xy 344.854081 -242.581738) (xy 344.89612 -242.61229)
			(xy 344.932862 -242.649041) (xy 344.963403 -242.691087) (xy 344.986991 -242.737393) (xy 345.003045 -242.786819)
			(xy 345.011169 -242.838148) (xy 345.011756 -242.864132) (xy 345.011354 -242.887534) (xy 345.00476 -242.933871)
			(xy 344.991693 -242.978814) (xy 344.972416 -243.021463) (xy 344.960194 -243.041424) (xy 344.952574 -243.053616)
			(xy 344.952066 -243.08181) (xy 345.096592 -243.330984) (xy 345.12123 -243.344446) (xy 345.135708 -243.343684)
			(xy 345.151202 -243.34343) (xy 345.177186 -243.34394) (xy 345.228514 -243.35207) (xy 345.277939 -243.368129)
			(xy 345.324243 -243.391722) (xy 345.366286 -243.422269) (xy 345.403033 -243.459016) (xy 345.433579 -243.501059)
			(xy 345.457172 -243.547363) (xy 345.473231 -243.596788) (xy 345.48136 -243.648116) (xy 345.48136 -243.6741)
			(xy 361.758723 -243.6741) (xy 361.762898 -243.623721) (xy 361.775308 -243.574716) (xy 361.795615 -243.528421)
			(xy 361.823265 -243.486101) (xy 361.857503 -243.448909) (xy 361.897396 -243.41786) (xy 361.941856 -243.393801)
			(xy 361.989669 -243.377388) (xy 362.039532 -243.369068) (xy 362.064808 -243.368576) (xy 363.004862 -243.368576)
			(xy 363.030146 -243.36899) (xy 363.080025 -243.377308) (xy 363.127854 -243.393722) (xy 363.172329 -243.417786)
			(xy 363.212237 -243.448843) (xy 363.246487 -243.486045) (xy 363.274147 -243.528377) (xy 363.294462 -243.574685)
			(xy 363.306876 -243.623705) (xy 363.311053 -243.6741) (xy 363.306876 -243.724495) (xy 363.294462 -243.773515)
			(xy 363.274147 -243.819823) (xy 363.246487 -243.862155) (xy 363.212237 -243.899357) (xy 363.172329 -243.930414)
			(xy 363.127854 -243.954478) (xy 363.080025 -243.970892) (xy 363.030146 -243.97921) (xy 363.004862 -243.9797)
			(xy 362.064808 -243.9797) (xy 362.039532 -243.979132) (xy 361.989669 -243.970812) (xy 361.941856 -243.954399)
			(xy 361.897396 -243.93034) (xy 361.857503 -243.899291) (xy 361.823265 -243.862099) (xy 361.795615 -243.819779)
			(xy 361.775308 -243.773484) (xy 361.762898 -243.724479) (xy 361.758723 -243.6741) (xy 345.48136 -243.6741)
			(xy 345.48136 -243.700084) (xy 345.473231 -243.751412) (xy 345.457172 -243.800837) (xy 345.433579 -243.847141)
			(xy 345.403033 -243.889184) (xy 345.366286 -243.925931) (xy 345.324243 -243.956478) (xy 345.277939 -243.980071)
			(xy 345.228514 -243.99613) (xy 345.177186 -244.00426) (xy 345.151202 -244.004846) (xy 345.13393 -244.004338)
			(xy 345.119452 -244.003576) (xy 345.09456 -244.017038) (xy 344.950796 -244.264942) (xy 344.951304 -244.293136)
			(xy 344.959178 -244.305328) (xy 344.971623 -244.325418) (xy 344.99127 -244.368399) (xy 345.004597 -244.413739)
			(xy 345.011333 -244.460515) (xy 345.011755 -244.4841) (xy 364.108984 -244.4841) (xy 364.113155 -244.433763)
			(xy 364.125555 -244.384799) (xy 364.145845 -244.338543) (xy 364.173472 -244.296259) (xy 364.207683 -244.259098)
			(xy 364.247543 -244.228076) (xy 364.291966 -244.204037) (xy 364.33974 -244.187639) (xy 364.389561 -244.179327)
			(xy 364.414816 -244.178836) (xy 365.35487 -244.178836) (xy 365.380133 -244.179238) (xy 365.42997 -244.18755)
			(xy 365.47776 -244.203952) (xy 365.522198 -244.227997) (xy 365.562072 -244.259028) (xy 365.596293 -244.2962)
			(xy 365.62393 -244.338497) (xy 365.644227 -244.384767) (xy 365.656631 -244.433747) (xy 365.660804 -244.4841)
			(xy 366.928884 -244.4841) (xy 366.933055 -244.433762) (xy 366.945456 -244.384797) (xy 366.965746 -244.338541)
			(xy 366.993374 -244.296256) (xy 367.027586 -244.259095) (xy 367.067447 -244.228073) (xy 367.111871 -244.204035)
			(xy 367.159646 -244.187637) (xy 367.209469 -244.179327) (xy 367.234724 -244.178836) (xy 368.174778 -244.178836)
			(xy 368.200041 -244.179239) (xy 368.249877 -244.187552) (xy 368.297665 -244.203955) (xy 368.342102 -244.228)
			(xy 368.381975 -244.259031) (xy 368.416196 -244.296203) (xy 368.443831 -244.3385) (xy 368.464128 -244.384769)
			(xy 368.476531 -244.433748) (xy 368.480704 -244.4841) (xy 369.749113 -244.4841) (xy 369.753283 -244.433771)
			(xy 369.76568 -244.384814) (xy 369.785966 -244.338565) (xy 369.813587 -244.296286) (xy 369.847791 -244.25913)
			(xy 369.887643 -244.22811) (xy 369.932057 -244.204073) (xy 369.979822 -244.187673) (xy 370.029635 -244.179359)
			(xy 370.054886 -244.178836) (xy 370.99494 -244.178836) (xy 371.020197 -244.179272) (xy 371.070021 -244.187592)
			(xy 371.117796 -244.203999) (xy 371.162219 -244.228045) (xy 371.202079 -244.259074) (xy 371.236289 -244.296241)
			(xy 371.263916 -244.33853) (xy 371.284205 -244.38479) (xy 371.296604 -244.433759) (xy 371.300776 -244.4841)
			(xy 372.569013 -244.4841) (xy 372.573183 -244.43377) (xy 372.585581 -244.384812) (xy 372.605867 -244.338563)
			(xy 372.63349 -244.296284) (xy 372.667694 -244.259127) (xy 372.707547 -244.228107) (xy 372.751963 -244.20407)
			(xy 372.799729 -244.187671) (xy 372.849543 -244.179358) (xy 372.874794 -244.178836) (xy 373.814848 -244.178836)
			(xy 373.840104 -244.179273) (xy 373.889927 -244.187594) (xy 373.937701 -244.204002) (xy 373.982123 -244.228048)
			(xy 374.021982 -244.259077) (xy 374.056191 -244.296243) (xy 374.083817 -244.338533) (xy 374.104106 -244.384792)
			(xy 374.116505 -244.43376) (xy 374.120676 -244.4841) (xy 374.116505 -244.53444) (xy 374.104106 -244.583408)
			(xy 374.083817 -244.629667) (xy 374.056191 -244.671957) (xy 374.021982 -244.709123) (xy 373.982123 -244.740152)
			(xy 373.937701 -244.764198) (xy 373.889927 -244.780606) (xy 373.840104 -244.788927) (xy 373.814848 -244.789452)
			(xy 372.874794 -244.789452) (xy 372.849543 -244.788842) (xy 372.799729 -244.780529) (xy 372.751963 -244.76413)
			(xy 372.707547 -244.740093) (xy 372.667694 -244.709073) (xy 372.63349 -244.671916) (xy 372.605867 -244.629637)
			(xy 372.585581 -244.583388) (xy 372.573183 -244.53443) (xy 372.569013 -244.4841) (xy 371.300776 -244.4841)
			(xy 371.296604 -244.534441) (xy 371.284205 -244.58341) (xy 371.263915 -244.62967) (xy 371.236289 -244.671959)
			(xy 371.202079 -244.709126) (xy 371.162219 -244.740155) (xy 371.117796 -244.764201) (xy 371.070021 -244.780608)
			(xy 371.020197 -244.788928) (xy 370.99494 -244.789452) (xy 370.054886 -244.789452) (xy 370.029635 -244.788841)
			(xy 369.979822 -244.780527) (xy 369.932057 -244.764127) (xy 369.887643 -244.74009) (xy 369.847791 -244.70907)
			(xy 369.813587 -244.671914) (xy 369.785966 -244.629635) (xy 369.76568 -244.583386) (xy 369.753283 -244.534429)
			(xy 369.749113 -244.4841) (xy 368.480704 -244.4841) (xy 368.476531 -244.534452) (xy 368.464128 -244.583431)
			(xy 368.443831 -244.6297) (xy 368.416196 -244.671997) (xy 368.381975 -244.709169) (xy 368.342102 -244.7402)
			(xy 368.297665 -244.764245) (xy 368.249877 -244.780648) (xy 368.200041 -244.788961) (xy 368.174778 -244.789452)
			(xy 367.234724 -244.789452) (xy 367.209469 -244.788873) (xy 367.159646 -244.780563) (xy 367.111871 -244.764165)
			(xy 367.067447 -244.740127) (xy 367.027586 -244.709105) (xy 366.993374 -244.671944) (xy 366.965746 -244.629659)
			(xy 366.945456 -244.583403) (xy 366.933055 -244.534438) (xy 366.928884 -244.4841) (xy 365.660804 -244.4841)
			(xy 365.656631 -244.534453) (xy 365.644227 -244.583433) (xy 365.62393 -244.629703) (xy 365.596293 -244.672)
			(xy 365.562072 -244.709172) (xy 365.522198 -244.740203) (xy 365.47776 -244.764248) (xy 365.42997 -244.78065)
			(xy 365.380133 -244.788962) (xy 365.35487 -244.789452) (xy 364.414816 -244.789452) (xy 364.389561 -244.788873)
			(xy 364.33974 -244.780561) (xy 364.291966 -244.764163) (xy 364.247543 -244.740124) (xy 364.207683 -244.709102)
			(xy 364.173472 -244.671941) (xy 364.145845 -244.629657) (xy 364.125555 -244.583401) (xy 364.113155 -244.534437)
			(xy 364.108984 -244.4841) (xy 345.011755 -244.4841) (xy 345.011756 -244.484144) (xy 345.011243 -244.51013)
			(xy 345.003107 -244.561462) (xy 344.987043 -244.61089) (xy 344.963446 -244.657197) (xy 344.932896 -244.699243)
			(xy 344.896146 -244.735993) (xy 344.8541 -244.766544) (xy 344.807794 -244.790142) (xy 344.758366 -244.806207)
			(xy 344.707034 -244.814343) (xy 344.681048 -244.814852) (xy 344.66403 -244.814344) (xy 344.649298 -244.813582)
			(xy 344.62466 -244.827044) (xy 344.480896 -245.074948) (xy 344.481404 -245.103142) (xy 344.489278 -245.115334)
			(xy 344.501722 -245.135425) (xy 344.521369 -245.178405) (xy 344.534695 -245.223745) (xy 344.541431 -245.270521)
			(xy 344.541855 -245.2941) (xy 361.758735 -245.2941) (xy 361.76291 -245.243723) (xy 361.775319 -245.194719)
			(xy 361.795626 -245.148427) (xy 361.823274 -245.106109) (xy 361.857511 -245.068918) (xy 361.897403 -245.03787)
			(xy 361.941861 -245.013812) (xy 361.989672 -244.997399) (xy 362.039533 -244.98908) (xy 362.064808 -244.988588)
			(xy 363.004862 -244.988588) (xy 363.030147 -244.988978) (xy 363.080028 -244.997296) (xy 363.127859 -245.013711)
			(xy 363.172336 -245.037776) (xy 363.212245 -245.068834) (xy 363.246497 -245.106037) (xy 363.274158 -245.148371)
			(xy 363.294473 -245.194681) (xy 363.306888 -245.243703) (xy 363.311065 -245.2941) (xy 363.306888 -245.344497)
			(xy 363.294473 -245.393519) (xy 363.274158 -245.439829) (xy 363.246497 -245.482163) (xy 363.212245 -245.519366)
			(xy 363.172336 -245.550424) (xy 363.127859 -245.574489) (xy 363.080028 -245.590904) (xy 363.030147 -245.599222)
			(xy 363.004862 -245.599712) (xy 362.064808 -245.599712) (xy 362.039533 -245.59912) (xy 361.989672 -245.590801)
			(xy 361.941861 -245.574388) (xy 361.897403 -245.55033) (xy 361.857511 -245.519282) (xy 361.823274 -245.482091)
			(xy 361.795626 -245.439773) (xy 361.775319 -245.393481) (xy 361.76291 -245.344477) (xy 361.758735 -245.2941)
			(xy 344.541855 -245.2941) (xy 344.541856 -245.29415) (xy 344.541453 -245.317552) (xy 344.534856 -245.363888)
			(xy 344.521788 -245.408829) (xy 344.502509 -245.451477) (xy 344.490294 -245.471442) (xy 344.482674 -245.483634)
			(xy 344.481912 -245.511828) (xy 344.626438 -245.761002) (xy 344.65133 -245.774464) (xy 344.665554 -245.773702)
			(xy 344.681048 -245.773448) (xy 344.707034 -245.773961) (xy 344.758365 -245.782097) (xy 344.807792 -245.798162)
			(xy 344.854098 -245.82176) (xy 344.896143 -245.85231) (xy 344.932893 -245.88906) (xy 344.963442 -245.931105)
			(xy 344.98704 -245.977412) (xy 345.003104 -246.026839) (xy 345.011239 -246.07817) (xy 345.011756 -246.104156)
			(xy 345.011755 -246.1042) (xy 364.108896 -246.1042) (xy 364.113068 -246.053848) (xy 364.125472 -246.00487)
			(xy 364.145768 -245.958601) (xy 364.173403 -245.916305) (xy 364.207623 -245.879133) (xy 364.247495 -245.848102)
			(xy 364.291931 -245.824057) (xy 364.339718 -245.807653) (xy 364.389554 -245.79934) (xy 364.414816 -245.798848)
			(xy 365.35487 -245.798848) (xy 365.380126 -245.799426) (xy 365.429949 -245.807736) (xy 365.477725 -245.824133)
			(xy 365.52215 -245.848171) (xy 365.562012 -245.879193) (xy 365.596224 -245.916354) (xy 365.623853 -245.958639)
			(xy 365.644144 -246.004896) (xy 365.656545 -246.053861) (xy 365.660716 -246.1042) (xy 366.928796 -246.1042)
			(xy 366.932969 -246.053847) (xy 366.945372 -246.004868) (xy 366.965669 -245.958599) (xy 366.993305 -245.916302)
			(xy 367.027526 -245.879131) (xy 367.067399 -245.848099) (xy 367.111836 -245.824054) (xy 367.159625 -245.807652)
			(xy 367.209461 -245.799339) (xy 367.234724 -245.798848) (xy 368.174778 -245.798848) (xy 368.200033 -245.799427)
			(xy 368.249855 -245.807737) (xy 368.29763 -245.824135) (xy 368.342054 -245.848173) (xy 368.381915 -245.879196)
			(xy 368.416126 -245.916357) (xy 368.443754 -245.958642) (xy 368.464045 -246.004897) (xy 368.476445 -246.053862)
			(xy 368.480616 -246.1042) (xy 369.749024 -246.1042) (xy 369.753196 -246.053856) (xy 369.765597 -246.004885)
			(xy 369.785888 -245.958623) (xy 369.813518 -245.916332) (xy 369.847731 -245.879165) (xy 369.887595 -245.848136)
			(xy 369.932022 -245.824092) (xy 369.979801 -245.807687) (xy 370.029628 -245.79937) (xy 370.054886 -245.798848)
			(xy 370.99494 -245.798848) (xy 371.02019 -245.799461) (xy 371.069999 -245.807778) (xy 371.11776 -245.82418)
			(xy 371.162171 -245.848219) (xy 371.202019 -245.879239) (xy 371.236219 -245.916395) (xy 371.263838 -245.958673)
			(xy 371.284121 -246.004919) (xy 371.296517 -246.053873) (xy 371.300687 -246.1042) (xy 372.568924 -246.1042)
			(xy 372.573096 -246.053855) (xy 372.585497 -246.004884) (xy 372.60579 -245.958621) (xy 372.63342 -245.916329)
			(xy 372.667634 -245.879162) (xy 372.707499 -245.848133) (xy 372.751927 -245.824089) (xy 372.799707 -245.807685)
			(xy 372.849535 -245.79937) (xy 372.874794 -245.798848) (xy 373.814848 -245.798848) (xy 373.840097 -245.799461)
			(xy 373.889906 -245.80778) (xy 373.937666 -245.824183) (xy 373.982075 -245.848222) (xy 374.021923 -245.879242)
			(xy 374.056121 -245.916398) (xy 374.083739 -245.958675) (xy 374.104022 -246.004921) (xy 374.116417 -246.053874)
			(xy 374.120587 -246.1042) (xy 374.116417 -246.154526) (xy 374.104022 -246.203479) (xy 374.083739 -246.249725)
			(xy 374.056121 -246.292002) (xy 374.021923 -246.329158) (xy 373.982075 -246.360178) (xy 373.937666 -246.384217)
			(xy 373.889906 -246.40062) (xy 373.840097 -246.408939) (xy 373.814848 -246.409464) (xy 372.874794 -246.409464)
			(xy 372.849535 -246.40903) (xy 372.799707 -246.400715) (xy 372.751927 -246.384311) (xy 372.707499 -246.360267)
			(xy 372.667634 -246.329238) (xy 372.63342 -246.292071) (xy 372.60579 -246.249779) (xy 372.585497 -246.203516)
			(xy 372.573096 -246.154545) (xy 372.568924 -246.1042) (xy 371.300687 -246.1042) (xy 371.296517 -246.154527)
			(xy 371.284121 -246.203481) (xy 371.263838 -246.249727) (xy 371.236219 -246.292005) (xy 371.202019 -246.329161)
			(xy 371.162171 -246.360181) (xy 371.11776 -246.38422) (xy 371.069999 -246.400622) (xy 371.02019 -246.408939)
			(xy 370.99494 -246.409464) (xy 370.054886 -246.409464) (xy 370.029628 -246.40903) (xy 369.979801 -246.400713)
			(xy 369.932022 -246.384308) (xy 369.887595 -246.360264) (xy 369.847731 -246.329235) (xy 369.813518 -246.292068)
			(xy 369.785888 -246.249777) (xy 369.765597 -246.203515) (xy 369.753196 -246.154544) (xy 369.749024 -246.1042)
			(xy 368.480616 -246.1042) (xy 368.476445 -246.154538) (xy 368.464045 -246.203503) (xy 368.443754 -246.249758)
			(xy 368.416126 -246.292043) (xy 368.381915 -246.329204) (xy 368.342054 -246.360227) (xy 368.29763 -246.384265)
			(xy 368.249855 -246.400663) (xy 368.200033 -246.408973) (xy 368.174778 -246.409464) (xy 367.234724 -246.409464)
			(xy 367.209461 -246.409061) (xy 367.159625 -246.400748) (xy 367.111836 -246.384346) (xy 367.067399 -246.360301)
			(xy 367.027526 -246.329269) (xy 366.993305 -246.292098) (xy 366.965669 -246.249801) (xy 366.945372 -246.203532)
			(xy 366.932969 -246.154553) (xy 366.928796 -246.1042) (xy 365.660716 -246.1042) (xy 365.656545 -246.154539)
			(xy 365.644144 -246.203504) (xy 365.623853 -246.249761) (xy 365.596224 -246.292046) (xy 365.562012 -246.329207)
			(xy 365.52215 -246.360229) (xy 365.477725 -246.384267) (xy 365.429949 -246.400664) (xy 365.380126 -246.408974)
			(xy 365.35487 -246.409464) (xy 364.414816 -246.409464) (xy 364.389554 -246.40906) (xy 364.339718 -246.400747)
			(xy 364.291931 -246.384343) (xy 364.247495 -246.360298) (xy 364.207623 -246.329267) (xy 364.173403 -246.292095)
			(xy 364.145768 -246.249799) (xy 364.125472 -246.20353) (xy 364.113068 -246.154552) (xy 364.108896 -246.1042)
			(xy 345.011755 -246.1042) (xy 345.011353 -246.127558) (xy 345.004755 -246.173893) (xy 344.991686 -246.218834)
			(xy 344.972406 -246.261482) (xy 344.960194 -246.281448) (xy 344.952574 -246.29364) (xy 344.952066 -246.321834)
			(xy 345.096592 -246.571008) (xy 345.12123 -246.58447) (xy 345.135708 -246.583708) (xy 345.151202 -246.583454)
			(xy 345.177192 -246.583964) (xy 345.228532 -246.592096) (xy 345.277968 -246.608159) (xy 345.324283 -246.631757)
			(xy 345.366335 -246.662311) (xy 345.403091 -246.699066) (xy 345.433644 -246.741119) (xy 345.457242 -246.787434)
			(xy 345.473305 -246.83687) (xy 345.481436 -246.88821) (xy 345.481436 -246.9142) (xy 361.758647 -246.9142)
			(xy 361.762823 -246.863808) (xy 361.775236 -246.814791) (xy 361.795548 -246.768485) (xy 361.823205 -246.726155)
			(xy 361.857452 -246.688953) (xy 361.897355 -246.657897) (xy 361.941825 -246.633831) (xy 361.989651 -246.617414)
			(xy 362.039526 -246.609093) (xy 362.064808 -246.6086) (xy 363.004862 -246.6086) (xy 363.03014 -246.609166)
			(xy 363.080006 -246.617481) (xy 363.127824 -246.633892) (xy 363.172288 -246.65795) (xy 363.212185 -246.688999)
			(xy 363.246428 -246.726191) (xy 363.274081 -246.768513) (xy 363.29439 -246.81481) (xy 363.306801 -246.863818)
			(xy 363.310977 -246.9142) (xy 363.306801 -246.964582) (xy 363.29439 -247.01359) (xy 363.274081 -247.059887)
			(xy 363.246428 -247.102209) (xy 363.212185 -247.139401) (xy 363.172288 -247.17045) (xy 363.127824 -247.194508)
			(xy 363.080006 -247.210919) (xy 363.03014 -247.219234) (xy 363.004862 -247.219724) (xy 362.064808 -247.219724)
			(xy 362.039526 -247.219307) (xy 361.989651 -247.210986) (xy 361.941825 -247.194569) (xy 361.897355 -247.170503)
			(xy 361.857452 -247.139447) (xy 361.823205 -247.102245) (xy 361.795548 -247.059915) (xy 361.775236 -247.013609)
			(xy 361.762823 -246.964592) (xy 361.758647 -246.9142) (xy 345.481436 -246.9142) (xy 345.481436 -246.94019)
			(xy 345.473305 -246.99153) (xy 345.457242 -247.040966) (xy 345.433644 -247.087281) (xy 345.403091 -247.129334)
			(xy 345.366335 -247.166089) (xy 345.324283 -247.196643) (xy 345.277968 -247.220241) (xy 345.228532 -247.236304)
			(xy 345.177192 -247.244436) (xy 345.151202 -247.24487) (xy 345.13393 -247.244362) (xy 345.119452 -247.2436)
			(xy 345.09456 -247.257062) (xy 344.950796 -247.504966) (xy 344.951558 -247.53316) (xy 344.959178 -247.545352)
			(xy 344.971621 -247.565443) (xy 344.991265 -247.608424) (xy 345.004589 -247.653764) (xy 345.011322 -247.700539)
			(xy 345.011756 -247.724168) (xy 345.011755 -247.7242) (xy 364.108908 -247.7242) (xy 364.11308 -247.67385)
			(xy 364.125483 -247.624874) (xy 364.145778 -247.578607) (xy 364.173412 -247.536312) (xy 364.207631 -247.499142)
			(xy 364.247501 -247.468112) (xy 364.291935 -247.444068) (xy 364.339721 -247.427665) (xy 364.389555 -247.419352)
			(xy 364.414816 -247.41886) (xy 365.35487 -247.41886) (xy 365.380127 -247.419414) (xy 365.429952 -247.427724)
			(xy 365.477729 -247.444122) (xy 365.522156 -247.468161) (xy 365.56202 -247.499184) (xy 365.596233 -247.536347)
			(xy 365.623863 -247.578634) (xy 365.644155 -247.624892) (xy 365.656556 -247.673859) (xy 365.660728 -247.7242)
			(xy 366.928808 -247.7242) (xy 366.93298 -247.673849) (xy 366.945384 -247.624872) (xy 366.96568 -247.578605)
			(xy 366.993314 -247.536309) (xy 367.027534 -247.499139) (xy 367.067406 -247.468109) (xy 367.111841 -247.444065)
			(xy 367.159628 -247.427663) (xy 367.209462 -247.419351) (xy 367.234724 -247.41886) (xy 368.174778 -247.41886)
			(xy 368.200034 -247.419415) (xy 368.249858 -247.427726) (xy 368.297635 -247.444124) (xy 368.34206 -247.468163)
			(xy 368.381923 -247.499187) (xy 368.416136 -247.536349) (xy 368.443764 -247.578636) (xy 368.464056 -247.624893)
			(xy 368.476457 -247.67386) (xy 368.480628 -247.7242) (xy 369.749037 -247.7242) (xy 369.753208 -247.673858)
			(xy 369.765609 -247.624889) (xy 369.785899 -247.578629) (xy 369.813527 -247.53634) (xy 369.847739 -247.499174)
			(xy 369.887601 -247.468147) (xy 369.932027 -247.444103) (xy 369.979804 -247.427699) (xy 370.029629 -247.419383)
			(xy 370.054886 -247.41886) (xy 370.99494 -247.41886) (xy 371.020191 -247.419449) (xy 371.070002 -247.427767)
			(xy 371.117765 -247.444169) (xy 371.162177 -247.468209) (xy 371.202028 -247.499231) (xy 371.236229 -247.536388)
			(xy 371.263848 -247.578667) (xy 371.284133 -247.624915) (xy 371.296529 -247.673871) (xy 371.300699 -247.7242)
			(xy 372.568937 -247.7242) (xy 372.573108 -247.673857) (xy 372.585509 -247.624888) (xy 372.605801 -247.578627)
			(xy 372.63343 -247.536337) (xy 372.667642 -247.499171) (xy 372.707506 -247.468144) (xy 372.751932 -247.444101)
			(xy 372.79971 -247.427698) (xy 372.849536 -247.419382) (xy 372.874794 -247.41886) (xy 373.814848 -247.41886)
			(xy 373.840098 -247.419449) (xy 373.889908 -247.427768) (xy 373.93767 -247.444172) (xy 373.982082 -247.468212)
			(xy 374.021931 -247.499233) (xy 374.056131 -247.53639) (xy 374.083749 -247.578669) (xy 374.104033 -247.624917)
			(xy 374.116429 -247.673872) (xy 374.120599 -247.7242) (xy 374.116429 -247.774528) (xy 374.104033 -247.823483)
			(xy 374.083749 -247.869731) (xy 374.056131 -247.91201) (xy 374.021931 -247.949166) (xy 373.982082 -247.980188)
			(xy 373.937671 -248.004228) (xy 373.889908 -248.020632) (xy 373.840098 -248.028951) (xy 373.814848 -248.029476)
			(xy 372.874794 -248.029476) (xy 372.849536 -248.029018) (xy 372.79971 -248.020702) (xy 372.751932 -248.004299)
			(xy 372.707506 -247.980256) (xy 372.667642 -247.949229) (xy 372.63343 -247.912063) (xy 372.605801 -247.869773)
			(xy 372.585509 -247.823512) (xy 372.573108 -247.774543) (xy 372.568937 -247.7242) (xy 371.300699 -247.7242)
			(xy 371.296529 -247.774529) (xy 371.284133 -247.823485) (xy 371.263848 -247.869733) (xy 371.236229 -247.912012)
			(xy 371.202028 -247.949169) (xy 371.162177 -247.980191) (xy 371.117765 -248.004231) (xy 371.070002 -248.020633)
			(xy 371.020191 -248.028951) (xy 370.99494 -248.029476) (xy 370.054886 -248.029476) (xy 370.029629 -248.029017)
			(xy 369.979804 -248.020701) (xy 369.932027 -248.004297) (xy 369.887601 -247.980253) (xy 369.847739 -247.949226)
			(xy 369.813527 -247.91206) (xy 369.785899 -247.869771) (xy 369.765609 -247.823511) (xy 369.753208 -247.774542)
			(xy 369.749037 -247.7242) (xy 368.480628 -247.7242) (xy 368.476457 -247.77454) (xy 368.464056 -247.823507)
			(xy 368.443764 -247.869764) (xy 368.416136 -247.912051) (xy 368.381923 -247.949213) (xy 368.34206 -247.980237)
			(xy 368.297635 -248.004276) (xy 368.249858 -248.020674) (xy 368.200034 -248.028985) (xy 368.174778 -248.029476)
			(xy 367.234724 -248.029476) (xy 367.209462 -248.029049) (xy 367.159628 -248.020737) (xy 367.111841 -248.004335)
			(xy 367.067406 -247.980291) (xy 367.027534 -247.949261) (xy 366.993314 -247.912091) (xy 366.96568 -247.869795)
			(xy 366.945384 -247.823528) (xy 366.93298 -247.774551) (xy 366.928808 -247.7242) (xy 365.660728 -247.7242)
			(xy 365.656556 -247.774541) (xy 365.644155 -247.823508) (xy 365.623863 -247.869766) (xy 365.596233 -247.912053)
			(xy 365.56202 -247.949216) (xy 365.522156 -247.980239) (xy 365.477729 -248.004278) (xy 365.429952 -248.020676)
			(xy 365.380127 -248.028986) (xy 365.35487 -248.029476) (xy 364.414816 -248.029476) (xy 364.389555 -248.029048)
			(xy 364.339721 -248.020735) (xy 364.291935 -248.004332) (xy 364.247501 -247.980288) (xy 364.207631 -247.949258)
			(xy 364.173412 -247.912088) (xy 364.145778 -247.869793) (xy 364.125483 -247.823526) (xy 364.11308 -247.77455)
			(xy 364.108908 -247.7242) (xy 345.011755 -247.7242) (xy 345.011249 -247.750158) (xy 345.003123 -247.801499)
			(xy 344.987065 -247.850937) (xy 344.963472 -247.897255) (xy 344.932923 -247.939311) (xy 344.896172 -247.976071)
			(xy 344.854123 -248.00663) (xy 344.807811 -248.030234) (xy 344.758377 -248.046304) (xy 344.707038 -248.054443)
			(xy 344.681048 -248.054876) (xy 344.66403 -248.054368) (xy 344.649552 -248.053606) (xy 344.62466 -248.067068)
			(xy 344.480896 -248.314972) (xy 344.481658 -248.343166) (xy 344.489532 -248.355358) (xy 344.501949 -248.375456)
			(xy 344.521536 -248.418445) (xy 344.534803 -248.463785) (xy 344.541477 -248.510553) (xy 344.541856 -248.534174)
			(xy 344.541602 -248.546366) (xy 344.541094 -248.56059) (xy 344.55481 -248.585228) (xy 345.404186 -249.073162)
			(xy 345.432126 -249.0724) (xy 345.444318 -249.06478) (xy 345.464237 -249.05263) (xy 345.506769 -249.03345)
			(xy 345.551579 -249.020451) (xy 345.597773 -249.013894) (xy 345.621102 -249.013472) (xy 345.644058 -249.013879)
			(xy 345.689525 -249.020257) (xy 345.733673 -249.032863) (xy 345.775653 -249.051454) (xy 345.795346 -249.063256)
			(xy 345.807284 -249.070622) (xy 345.835224 -249.07113) (xy 346.68714 -248.581672) (xy 346.700856 -248.557288)
			(xy 346.700348 -248.543318) (xy 346.700348 -248.534174) (xy 346.700858 -248.508187) (xy 346.708988 -248.456852)
			(xy 346.725049 -248.407422) (xy 346.748645 -248.361112) (xy 346.779195 -248.319064) (xy 346.815946 -248.282313)
			(xy 346.857994 -248.251763) (xy 346.904304 -248.228167) (xy 346.953734 -248.212106) (xy 347.005069 -248.203976)
			(xy 347.057043 -248.203976) (xy 347.108378 -248.212106) (xy 347.157808 -248.228167) (xy 347.204118 -248.251763)
			(xy 347.246166 -248.282313) (xy 347.282917 -248.319064) (xy 347.313467 -248.361112) (xy 347.337063 -248.407422)
			(xy 347.353124 -248.456852) (xy 347.361254 -248.508187) (xy 347.361764 -248.534174) (xy 347.361764 -248.5342)
			(xy 361.758659 -248.5342) (xy 361.762835 -248.48381) (xy 361.775248 -248.434795) (xy 361.795559 -248.388491)
			(xy 361.823214 -248.346162) (xy 361.85746 -248.308962) (xy 361.897361 -248.277907) (xy 361.94183 -248.253842)
			(xy 361.989653 -248.237426) (xy 362.039527 -248.229104) (xy 362.064808 -248.228612) (xy 363.004862 -248.228612)
			(xy 363.030141 -248.229154) (xy 363.080009 -248.23747) (xy 363.127829 -248.253881) (xy 363.172294 -248.27794)
			(xy 363.212193 -248.30899) (xy 363.246437 -248.346184) (xy 363.274091 -248.388507) (xy 363.294401 -248.434806)
			(xy 363.306813 -248.483816) (xy 363.310989 -248.5342) (xy 363.306813 -248.584584) (xy 363.294401 -248.633594)
			(xy 363.274091 -248.679893) (xy 363.246437 -248.722216) (xy 363.212193 -248.75941) (xy 363.172294 -248.79046)
			(xy 363.127829 -248.814519) (xy 363.080009 -248.83093) (xy 363.030141 -248.839246) (xy 363.004862 -248.839736)
			(xy 362.064808 -248.839736) (xy 362.039527 -248.839296) (xy 361.989653 -248.830974) (xy 361.94183 -248.814558)
			(xy 361.897361 -248.790493) (xy 361.85746 -248.759438) (xy 361.823214 -248.722238) (xy 361.795559 -248.679909)
			(xy 361.775248 -248.633605) (xy 361.762835 -248.58459) (xy 361.758659 -248.5342) (xy 347.361764 -248.5342)
			(xy 347.361359 -248.557575) (xy 347.35476 -248.60391) (xy 347.341688 -248.64885) (xy 347.322407 -248.691496)
			(xy 347.310202 -248.711466) (xy 347.302582 -248.723404) (xy 347.302074 -248.751852) (xy 347.4466 -249.001026)
			(xy 347.471492 -249.014488) (xy 347.485716 -249.013726) (xy 347.50121 -249.013472) (xy 347.527197 -249.013982)
			(xy 347.578532 -249.022114) (xy 347.627962 -249.038176) (xy 347.674272 -249.061772) (xy 347.71632 -249.092321)
			(xy 347.753072 -249.129072) (xy 347.783623 -249.17112) (xy 347.807221 -249.217429) (xy 347.823284 -249.266859)
			(xy 347.831417 -249.318193) (xy 347.831918 -249.34418) (xy 347.831513 -249.367581) (xy 347.824911 -249.413915)
			(xy 347.811838 -249.458853) (xy 347.792554 -249.501498) (xy 347.780356 -249.521472) (xy 347.772736 -249.533664)
			(xy 347.772228 -249.561858) (xy 347.916754 -249.811032) (xy 347.941392 -249.824494) (xy 347.95587 -249.823732)
			(xy 347.97111 -249.823478) (xy 347.997097 -249.823988) (xy 348.048431 -249.83212) (xy 348.097861 -249.848182)
			(xy 348.14417 -249.871778) (xy 348.186218 -249.902328) (xy 348.22297 -249.939079) (xy 348.25352 -249.981126)
			(xy 348.277117 -250.027435) (xy 348.293179 -250.076865) (xy 348.301311 -250.128199) (xy 348.301818 -250.154186)
			(xy 348.301564 -250.166378) (xy 348.301056 -250.180348) (xy 348.314772 -250.204986) (xy 349.164148 -250.69292)
			(xy 349.192088 -250.692412) (xy 349.20428 -250.684792) (xy 349.224198 -250.67264) (xy 349.26673 -250.653454)
			(xy 349.31154 -250.640449) (xy 349.357735 -250.633886) (xy 349.381064 -250.633484) (xy 349.407055 -250.633964)
			(xy 349.458399 -250.642091) (xy 349.507839 -250.65815) (xy 349.554157 -250.681746) (xy 349.596214 -250.712297)
			(xy 349.632974 -250.749052) (xy 349.663531 -250.791105) (xy 349.687133 -250.837421) (xy 349.703199 -250.886858)
			(xy 349.711332 -250.938201) (xy 349.711772 -250.964192) (xy 349.711366 -250.987593) (xy 349.704764 -251.033926)
			(xy 349.691691 -251.078865) (xy 349.672409 -251.12151) (xy 349.66021 -251.141484) (xy 349.65259 -251.153422)
			(xy 349.652082 -251.181616) (xy 349.796862 -251.431044) (xy 349.8215 -251.444506) (xy 349.835978 -251.443744)
			(xy 349.851218 -251.44349) (xy 349.874166 -251.443858) (xy 349.919626 -251.450165) (xy 349.963774 -251.462711)
			(xy 350.005757 -251.481253) (xy 350.025462 -251.49302) (xy 350.0374 -251.50064) (xy 350.06534 -251.500894)
			(xy 350.917256 -251.011436) (xy 350.930972 -250.987052) (xy 350.930464 -250.973082) (xy 350.930464 -250.964192)
			(xy 350.930974 -250.938205) (xy 350.939104 -250.88687) (xy 350.955165 -250.83744) (xy 350.978761 -250.79113)
			(xy 351.009311 -250.749082) (xy 351.046062 -250.712331) (xy 351.08811 -250.681781) (xy 351.13442 -250.658185)
			(xy 351.18385 -250.642124) (xy 351.235185 -250.633994) (xy 351.287159 -250.633994) (xy 351.338494 -250.642124)
			(xy 351.387924 -250.658185) (xy 351.434234 -250.681781) (xy 351.476282 -250.712331) (xy 351.513033 -250.749082)
			(xy 351.543583 -250.79113) (xy 351.567179 -250.83744) (xy 351.58324 -250.88687) (xy 351.59137 -250.938205)
			(xy 351.59188 -250.964192) (xy 351.591474 -250.987593) (xy 351.584872 -251.033927) (xy 351.5718 -251.078865)
			(xy 351.552518 -251.121511) (xy 351.540318 -251.141484) (xy 351.532698 -251.153676) (xy 351.53219 -251.18187)
			(xy 351.676716 -251.431044) (xy 351.701608 -251.444506) (xy 351.715832 -251.443744) (xy 351.731072 -251.44349)
			(xy 351.754026 -251.443902) (xy 351.799489 -251.450289) (xy 351.843632 -251.462903) (xy 351.885605 -251.481502)
			(xy 351.905316 -251.493274) (xy 351.917254 -251.50064) (xy 351.945194 -251.501148) (xy 352.79711 -251.01169)
			(xy 352.810826 -250.987306) (xy 352.810318 -250.973336) (xy 352.810318 -250.964192) (xy 352.810828 -250.938205)
			(xy 352.818958 -250.88687) (xy 352.835019 -250.83744) (xy 352.858615 -250.79113) (xy 352.889165 -250.749082)
			(xy 352.925916 -250.712331) (xy 352.967964 -250.681781) (xy 353.014274 -250.658185) (xy 353.063704 -250.642124)
			(xy 353.115039 -250.633994) (xy 353.167013 -250.633994) (xy 353.218348 -250.642124) (xy 353.267778 -250.658185)
			(xy 353.314088 -250.681781) (xy 353.356136 -250.712331) (xy 353.392887 -250.749082) (xy 353.423437 -250.79113)
			(xy 353.447033 -250.83744) (xy 353.463094 -250.88687) (xy 353.471224 -250.938205) (xy 353.471734 -250.964192)
			(xy 353.471328 -250.987593) (xy 353.464725 -251.033926) (xy 353.451651 -251.078864) (xy 353.432367 -251.121508)
			(xy 353.420172 -251.141484) (xy 353.412552 -251.153422) (xy 353.412044 -251.181616) (xy 353.556824 -251.431044)
			(xy 353.581462 -251.444506) (xy 353.59594 -251.443744) (xy 353.61118 -251.44349) (xy 353.634127 -251.443863)
			(xy 353.679584 -251.450177) (xy 353.723727 -251.46273) (xy 353.765705 -251.481278) (xy 353.785424 -251.49302)
			(xy 353.797362 -251.50064) (xy 353.825302 -251.500894) (xy 354.677218 -251.01169) (xy 354.690934 -250.987306)
			(xy 354.690426 -250.973082) (xy 354.690426 -250.964192) (xy 354.690936 -250.938205) (xy 354.699066 -250.88687)
			(xy 354.715127 -250.83744) (xy 354.738723 -250.79113) (xy 354.769273 -250.749082) (xy 354.806024 -250.712331)
			(xy 354.848072 -250.681781) (xy 354.894382 -250.658185) (xy 354.943812 -250.642124) (xy 354.995147 -250.633994)
			(xy 355.047121 -250.633994) (xy 355.098456 -250.642124) (xy 355.147886 -250.658185) (xy 355.194196 -250.681781)
			(xy 355.236244 -250.712331) (xy 355.272995 -250.749082) (xy 355.303545 -250.79113) (xy 355.327141 -250.83744)
			(xy 355.343202 -250.88687) (xy 355.351332 -250.938205) (xy 355.351842 -250.964192) (xy 355.351436 -250.987593)
			(xy 355.344834 -251.033926) (xy 355.33176 -251.078864) (xy 355.312476 -251.121508) (xy 355.30028 -251.141484)
			(xy 355.29266 -251.153422) (xy 355.292152 -251.181616) (xy 355.436932 -251.431044) (xy 355.46157 -251.444506)
			(xy 355.475794 -251.443744) (xy 355.491034 -251.44349) (xy 355.513989 -251.443899) (xy 355.559454 -251.450282)
			(xy 355.603599 -251.462892) (xy 355.645576 -251.481487) (xy 355.665278 -251.493274) (xy 355.67747 -251.50064)
			(xy 355.705156 -251.501148) (xy 356.557326 -251.01169) (xy 356.571042 -250.987306) (xy 356.570534 -250.973082)
			(xy 356.570534 -250.964192) (xy 356.571018 -250.938204) (xy 356.57915 -250.886869) (xy 356.595214 -250.837438)
			(xy 356.618813 -250.791129) (xy 356.649366 -250.749082) (xy 356.686121 -250.712333) (xy 356.728172 -250.681786)
			(xy 356.774485 -250.658195) (xy 356.823918 -250.642139) (xy 356.875254 -250.634014) (xy 356.901242 -250.633484)
			(xy 356.911148 -250.633738) (xy 356.925118 -250.633992) (xy 356.949502 -250.62053) (xy 357.096822 -250.366784)
			(xy 357.096568 -250.338844) (xy 357.089202 -250.326906) (xy 357.077655 -250.307326) (xy 357.059443 -250.265679)
			(xy 357.04709 -250.221935) (xy 357.040828 -250.176913) (xy 357.040434 -250.154186) (xy 357.040944 -250.128199)
			(xy 357.049074 -250.076864) (xy 357.065135 -250.027434) (xy 357.088731 -249.981124) (xy 357.119281 -249.939076)
			(xy 357.156032 -249.902325) (xy 357.19808 -249.871775) (xy 357.24439 -249.848179) (xy 357.29382 -249.832118)
			(xy 357.345155 -249.823988) (xy 357.397129 -249.823988) (xy 357.448464 -249.832118) (xy 357.497894 -249.848179)
			(xy 357.544204 -249.871775) (xy 357.586252 -249.902325) (xy 357.623003 -249.939076) (xy 357.653553 -249.981124)
			(xy 357.677149 -250.027434) (xy 357.69321 -250.076864) (xy 357.70134 -250.128199) (xy 357.70185 -250.154186)
			(xy 357.701596 -250.166124) (xy 357.701088 -250.180602) (xy 357.71455 -250.204986) (xy 358.800146 -250.828556)
			(xy 358.805965 -250.831674) (xy 358.818696 -250.835145) (xy 358.825292 -250.835414) (xy 361.272582 -250.835414)
			(xy 361.296458 -250.82119) (xy 361.303062 -250.80849) (xy 361.315521 -250.786186) (xy 361.346238 -250.745366)
			(xy 361.38286 -250.709747) (xy 361.424517 -250.680176) (xy 361.470222 -250.657352) (xy 361.518889 -250.641819)
			(xy 361.569365 -250.633944) (xy 361.594908 -250.633484) (xy 361.618266 -250.633891) (xy 361.664518 -250.640467)
			(xy 361.709388 -250.653473) (xy 361.751987 -250.672651) (xy 361.771946 -250.684792) (xy 361.783884 -250.692412)
			(xy 361.812078 -250.69292) (xy 362.661454 -250.204986) (xy 362.674916 -250.180602) (xy 362.674408 -250.166124)
			(xy 362.674154 -250.154186) (xy 362.674664 -250.128199) (xy 362.682794 -250.076864) (xy 362.698855 -250.027434)
			(xy 362.722451 -249.981124) (xy 362.753001 -249.939076) (xy 362.789752 -249.902325) (xy 362.8318 -249.871775)
			(xy 362.87811 -249.848179) (xy 362.92754 -249.832118) (xy 362.978875 -249.823988) (xy 363.030849 -249.823988)
			(xy 363.082184 -249.832118) (xy 363.131614 -249.848179) (xy 363.177924 -249.871775) (xy 363.219972 -249.902325)
			(xy 363.256723 -249.939076) (xy 363.287273 -249.981124) (xy 363.310869 -250.027434) (xy 363.32693 -250.076864)
			(xy 363.33506 -250.128199) (xy 363.33557 -250.154186) (xy 363.335197 -250.176916) (xy 363.328968 -250.221947)
			(xy 363.316613 -250.265696) (xy 363.298366 -250.307333) (xy 363.286802 -250.326906) (xy 363.279436 -250.338844)
			(xy 363.279182 -250.366784) (xy 363.426502 -250.62053) (xy 363.450886 -250.633992) (xy 363.464856 -250.633738)
			(xy 363.474762 -250.633484) (xy 363.500753 -250.633964) (xy 363.552097 -250.642091) (xy 363.601537 -250.65815)
			(xy 363.647856 -250.681745) (xy 363.689914 -250.712297) (xy 363.726674 -250.749051) (xy 363.757231 -250.791104)
			(xy 363.780833 -250.83742) (xy 363.796899 -250.886858) (xy 363.805032 -250.938201) (xy 363.80547 -250.964192)
			(xy 363.80547 -250.973082) (xy 363.804962 -250.987306) (xy 363.818678 -251.01169) (xy 364.670594 -251.500894)
			(xy 364.698534 -251.50064) (xy 364.710472 -251.49302) (xy 364.730192 -251.481285) (xy 364.77218 -251.46277)
			(xy 364.816321 -251.450227) (xy 364.861772 -251.443895) (xy 364.884716 -251.44349) (xy 364.899956 -251.443744)
			(xy 364.914434 -251.444506) (xy 364.939072 -251.431044) (xy 365.083852 -251.181616) (xy 365.083344 -251.153422)
			(xy 365.075724 -251.141484) (xy 365.063523 -251.121512) (xy 365.044254 -251.078863) (xy 365.031186 -251.033924)
			(xy 365.024579 -250.987592) (xy 365.024162 -250.964192) (xy 365.024672 -250.938204) (xy 365.032803 -250.886869)
			(xy 365.048865 -250.837438) (xy 365.072461 -250.791127) (xy 365.10301 -250.749078) (xy 365.139761 -250.712324)
			(xy 365.181808 -250.681772) (xy 365.228117 -250.658173) (xy 365.277548 -250.642109) (xy 365.328882 -250.633974)
			(xy 365.35487 -250.633484) (xy 365.378196 -250.633907) (xy 365.424381 -250.640502) (xy 365.469184 -250.653508)
			(xy 365.511721 -250.672669) (xy 365.531654 -250.684792) (xy 365.543846 -250.692412) (xy 365.571786 -250.69292)
			(xy 366.421416 -250.204986) (xy 366.434878 -250.180602) (xy 366.43437 -250.166124) (xy 366.434116 -250.154186)
			(xy 366.434626 -250.128199) (xy 366.442756 -250.076864) (xy 366.458817 -250.027434) (xy 366.482413 -249.981124)
			(xy 366.512963 -249.939076) (xy 366.549714 -249.902325) (xy 366.591762 -249.871775) (xy 366.638072 -249.848179)
			(xy 366.687502 -249.832118) (xy 366.738837 -249.823988) (xy 366.790811 -249.823988) (xy 366.842146 -249.832118)
			(xy 366.891576 -249.848179) (xy 366.937886 -249.871775) (xy 366.979934 -249.902325) (xy 367.016685 -249.939076)
			(xy 367.047235 -249.981124) (xy 367.070831 -250.027434) (xy 367.086892 -250.076864) (xy 367.095022 -250.128199)
			(xy 367.095532 -250.154186) (xy 367.095159 -250.176916) (xy 367.088931 -250.221948) (xy 367.076578 -250.265698)
			(xy 367.058334 -250.307337) (xy 367.046764 -250.326906) (xy 367.039398 -250.338844) (xy 367.039144 -250.366784)
			(xy 367.186464 -250.62053) (xy 367.210848 -250.633992) (xy 367.224818 -250.633738) (xy 367.234724 -250.633484)
			(xy 367.26071 -250.633995) (xy 367.312042 -250.642129) (xy 367.36147 -250.658192) (xy 367.407777 -250.681789)
			(xy 367.449822 -250.712339) (xy 367.486572 -250.74909) (xy 367.51712 -250.791137) (xy 367.540714 -250.837445)
			(xy 367.556775 -250.886873) (xy 367.564906 -250.938206) (xy 367.565432 -250.964192) (xy 367.565432 -250.973082)
			(xy 367.564924 -250.987306) (xy 367.57864 -251.01169) (xy 368.430556 -251.500894) (xy 368.458496 -251.50064)
			(xy 368.470434 -251.49302) (xy 368.490154 -251.481283) (xy 368.532141 -251.462763) (xy 368.576282 -251.450214)
			(xy 368.621733 -251.443878) (xy 368.644678 -251.44349) (xy 368.659918 -251.443744) (xy 368.674396 -251.444506)
			(xy 368.699034 -251.431044) (xy 368.843814 -251.181616) (xy 368.843306 -251.153422) (xy 368.835686 -251.141484)
			(xy 368.823483 -251.121513) (xy 368.80421 -251.078864) (xy 368.791139 -251.033925) (xy 368.784532 -250.987593)
			(xy 368.784124 -250.964192) (xy 368.784608 -250.938204) (xy 368.79274 -250.886868) (xy 368.808804 -250.837437)
			(xy 368.832402 -250.791127) (xy 368.862955 -250.749079) (xy 368.89971 -250.712329) (xy 368.941761 -250.681781)
			(xy 368.988074 -250.658188) (xy 369.037507 -250.642131) (xy 369.088844 -250.634005) (xy 369.114832 -250.633484)
			(xy 369.138159 -250.633905) (xy 369.184346 -250.640494) (xy 369.229152 -250.653496) (xy 369.271692 -250.672653)
			(xy 369.291616 -250.684792) (xy 369.303808 -250.692412) (xy 369.331748 -250.69292) (xy 370.181124 -250.20524)
			(xy 370.19484 -250.180348) (xy 370.194332 -250.166378) (xy 370.194078 -250.154186) (xy 370.194588 -250.128199)
			(xy 370.202718 -250.076864) (xy 370.218779 -250.027434) (xy 370.242375 -249.981124) (xy 370.272925 -249.939076)
			(xy 370.309676 -249.902325) (xy 370.351724 -249.871775) (xy 370.398034 -249.848179) (xy 370.447464 -249.832118)
			(xy 370.498799 -249.823988) (xy 370.550773 -249.823988) (xy 370.602108 -249.832118) (xy 370.651538 -249.848179)
			(xy 370.697848 -249.871775) (xy 370.739896 -249.902325) (xy 370.776647 -249.939076) (xy 370.807197 -249.981124)
			(xy 370.830793 -250.027434) (xy 370.846854 -250.076864) (xy 370.854984 -250.128199) (xy 370.855494 -250.154186)
			(xy 370.855121 -250.176916) (xy 370.848893 -250.221948) (xy 370.836538 -250.265697) (xy 370.818292 -250.307335)
			(xy 370.806726 -250.326906) (xy 370.799614 -250.338844) (xy 370.799106 -250.366784) (xy 370.946426 -250.62053)
			(xy 370.97081 -250.633992) (xy 370.98478 -250.633738) (xy 370.994686 -250.633484) (xy 371.020676 -250.633966)
			(xy 371.072017 -250.642096) (xy 371.121454 -250.658156) (xy 371.16777 -250.681753) (xy 371.209824 -250.712305)
			(xy 371.246581 -250.74906) (xy 371.277135 -250.791112) (xy 371.300735 -250.837426) (xy 371.316799 -250.886862)
			(xy 371.324932 -250.938202) (xy 371.325394 -250.964192) (xy 371.325394 -250.973082) (xy 371.324886 -250.987306)
			(xy 371.338602 -251.01169) (xy 372.190772 -251.501148)
		)
		(stroke
			(width 0)
			(type solid)
		)
		(fill yes)
		(layer "In9.Cu")
		(net "PVDDCR_CPU0_P0")
	)
	(gr_poly
		(pts
			(xy 162.954716 -127.702056) (xy 162.95751 -127.683006) (xy 162.961665 -127.655922) (xy 162.976729 -127.603241)
			(xy 162.999176 -127.553257) (xy 163.028545 -127.507) (xy 163.064231 -127.465421) (xy 163.105499 -127.429377)
			(xy 163.1515 -127.399609) (xy 163.201288 -127.376729) (xy 163.253837 -127.36121) (xy 163.308066 -127.353369)
			(xy 163.362858 -127.353369) (xy 163.417087 -127.36121) (xy 163.469636 -127.376729) (xy 163.519424 -127.399609)
			(xy 163.565425 -127.429377) (xy 163.606693 -127.465421) (xy 163.642379 -127.507) (xy 163.671748 -127.553257)
			(xy 163.694195 -127.603241) (xy 163.709259 -127.655922) (xy 163.713414 -127.683006) (xy 163.716208 -127.702056)
			(xy 163.744656 -127.726948) (xy 190.944754 -127.726948) (xy 190.951858 -127.726752) (xy 190.965525 -127.722884)
			(xy 190.971678 -127.719328) (xy 190.99448 -127.705591) (xy 191.043106 -127.683925) (xy 191.094276 -127.669243)
			(xy 191.146991 -127.66183) (xy 191.173608 -127.661416) (xy 191.200221 -127.661897) (xy 191.252926 -127.669324)
			(xy 191.304092 -127.68399) (xy 191.352728 -127.705612) (xy 191.375538 -127.719328) (xy 191.381701 -127.722862)
			(xy 191.395362 -127.72674) (xy 191.402462 -127.726948) (xy 203.152502 -127.726948) (xy 203.159232 -127.726772)
			(xy 203.17223 -127.723287) (xy 203.178156 -127.72009) (xy 203.20019 -127.70762) (xy 203.24685 -127.687967)
			(xy 203.2957 -127.674661) (xy 203.345881 -127.667936) (xy 203.371196 -127.667512) (xy 203.39651 -127.667944)
			(xy 203.446688 -127.674676) (xy 203.495536 -127.687983) (xy 203.542196 -127.707631) (xy 203.564236 -127.72009)
			(xy 203.570173 -127.723256) (xy 203.583165 -127.726729) (xy 203.58989 -127.726948) (xy 206.107792 -127.726948)
			(xy 206.11631 -127.726631) (xy 206.132409 -127.721059) (xy 206.139288 -127.716026) (xy 206.161813 -127.698976)
			(xy 206.210892 -127.671005) (xy 206.26356 -127.650577) (xy 206.318664 -127.638139) (xy 206.375 -127.633962)
			(xy 206.431336 -127.638139) (xy 206.48644 -127.650577) (xy 206.539108 -127.671005) (xy 206.588187 -127.698976)
			(xy 206.610712 -127.716026) (xy 206.617596 -127.72105) (xy 206.633691 -127.726622) (xy 206.642208 -127.726948)
			(xy 211.23529 -127.726948) (xy 211.243926 -127.726604) (xy 211.26021 -127.720847) (xy 211.273642 -127.709987)
			(xy 211.27847 -127.702818) (xy 211.29245 -127.680927) (xy 211.325751 -127.641068) (xy 211.36449 -127.60647)
			(xy 211.407845 -127.577867) (xy 211.454895 -127.555867) (xy 211.504642 -127.540935) (xy 211.55603 -127.533389)
			(xy 211.60797 -127.533389) (xy 211.659358 -127.540935) (xy 211.709105 -127.555867) (xy 211.756155 -127.577867)
			(xy 211.79951 -127.60647) (xy 211.838249 -127.641068) (xy 211.87155 -127.680927) (xy 211.88553 -127.702818)
			(xy 211.890364 -127.709975) (xy 211.903808 -127.7208) (xy 211.920081 -127.726553) (xy 211.92871 -127.726948)
			(xy 215.033098 -127.726948) (xy 215.058244 -127.710184) (xy 215.06434 -127.695706) (xy 215.07557 -127.669964)
			(xy 215.104481 -127.621817) (xy 215.140138 -127.578429) (xy 215.181772 -127.540738) (xy 215.228482 -127.509558)
			(xy 215.279258 -127.485564) (xy 215.333004 -127.469273) (xy 215.388558 -127.461039) (xy 215.444718 -127.461039)
			(xy 215.500272 -127.469273) (xy 215.554018 -127.485564) (xy 215.604794 -127.509558) (xy 215.651504 -127.540738)
			(xy 215.693138 -127.578429) (xy 215.728795 -127.621817) (xy 215.757706 -127.669964) (xy 215.768936 -127.695706)
			(xy 215.775032 -127.710184) (xy 215.800178 -127.726948) (xy 218.129612 -127.726948) (xy 218.156536 -127.707136)
			(xy 218.161362 -127.69088) (xy 218.169644 -127.665079) (xy 218.192483 -127.615941) (xy 218.222044 -127.570528)
			(xy 218.257734 -127.529755) (xy 218.298833 -127.494441) (xy 218.344516 -127.465298) (xy 218.393862 -127.442911)
			(xy 218.445879 -127.427732) (xy 218.499521 -127.420065) (xy 218.553707 -127.420065) (xy 218.607349 -127.427732)
			(xy 218.659366 -127.442911) (xy 218.708712 -127.465298) (xy 218.754395 -127.494441) (xy 218.795494 -127.529755)
			(xy 218.831184 -127.570528) (xy 218.860745 -127.615941) (xy 218.883584 -127.665079) (xy 218.891866 -127.69088)
			(xy 218.896692 -127.707136) (xy 218.923616 -127.726948) (xy 233.68127 -127.726948) (xy 233.7054 -127.712216)
			(xy 233.712004 -127.69977) (xy 233.724418 -127.67713) (xy 233.754782 -127.635369) (xy 233.79086 -127.598432)
			(xy 233.831894 -127.567094) (xy 233.877024 -127.54201) (xy 233.925304 -127.523708) (xy 233.975721 -127.51257)
			(xy 234.027218 -127.508832) (xy 234.078715 -127.51257) (xy 234.129132 -127.523708) (xy 234.177412 -127.54201)
			(xy 234.222542 -127.567094) (xy 234.263576 -127.598432) (xy 234.299654 -127.635369) (xy 234.330018 -127.67713)
			(xy 234.342432 -127.69977) (xy 234.349036 -127.712216) (xy 234.373166 -127.726948) (xy 234.44327 -127.726948)
			(xy 234.4674 -127.712216) (xy 234.474004 -127.69977) (xy 234.486418 -127.67713) (xy 234.516782 -127.635369)
			(xy 234.55286 -127.598432) (xy 234.593894 -127.567094) (xy 234.639024 -127.54201) (xy 234.687304 -127.523708)
			(xy 234.737721 -127.51257) (xy 234.789218 -127.508832) (xy 234.840715 -127.51257) (xy 234.891132 -127.523708)
			(xy 234.939412 -127.54201) (xy 234.984542 -127.567094) (xy 235.025576 -127.598432) (xy 235.061654 -127.635369)
			(xy 235.092018 -127.67713) (xy 235.104432 -127.69977) (xy 235.111036 -127.712216) (xy 235.135166 -127.726948)
			(xy 274.749006 -127.726948) (xy 274.759075 -127.726522) (xy 274.777673 -127.718801) (xy 274.785074 -127.711962)
			(xy 278.118316 -124.37872) (xy 278.125936 -124.35713) (xy 278.124666 -124.3457) (xy 278.123688 -124.335633)
			(xy 278.12267 -124.315429) (xy 278.122634 -124.305314) (xy 278.123096 -124.278062) (xy 278.130852 -124.224111)
			(xy 278.146207 -124.171814) (xy 278.16885 -124.122235) (xy 278.198318 -124.076383) (xy 278.234012 -124.035192)
			(xy 278.275206 -123.999501) (xy 278.32106 -123.970036) (xy 278.370641 -123.947397) (xy 278.422939 -123.932046)
			(xy 278.47689 -123.924294) (xy 278.504142 -123.923806) (xy 278.514257 -123.923846) (xy 278.53446 -123.924865)
			(xy 278.544528 -123.925838) (xy 278.555958 -123.927108) (xy 278.577548 -123.919488) (xy 303.84369 -98.653346)
			(xy 303.861733 -98.63609) (xy 303.903228 -98.608342) (xy 303.949346 -98.589238) (xy 303.998308 -98.579515)
			(xy 304.023268 -98.578924) (xy 319.85712 -98.578924) (xy 319.86347 -98.5774) (xy 319.885554 -98.571977)
			(xy 319.93065 -98.566123) (xy 319.953386 -98.565716) (xy 319.976123 -98.566109) (xy 320.021218 -98.571974)
			(xy 320.043302 -98.5774) (xy 320.049652 -98.578924) (xy 328.96683 -98.578924) (xy 328.972672 -98.5774)
			(xy 328.994631 -98.57249) (xy 329.039326 -98.567268) (xy 329.061826 -98.566986) (xy 329.084325 -98.567287)
			(xy 329.129017 -98.57251) (xy 329.15098 -98.5774) (xy 329.156822 -98.578924) (xy 329.725782 -98.578924)
			(xy 329.732823 -98.578705) (xy 329.746365 -98.574848) (xy 329.752452 -98.571304) (xy 329.775114 -98.557855)
			(xy 329.823353 -98.536646) (xy 329.874057 -98.522292) (xy 329.926256 -98.515067) (xy 329.952604 -98.514662)
			(xy 329.978949 -98.51511) (xy 330.031137 -98.522359) (xy 330.081836 -98.536706) (xy 330.130085 -98.557878)
			(xy 330.152756 -98.571304) (xy 330.158871 -98.574785) (xy 330.172395 -98.57865) (xy 330.179426 -98.578924)
			(xy 330.538582 -98.578924) (xy 330.545623 -98.578705) (xy 330.559165 -98.574848) (xy 330.565252 -98.571304)
			(xy 330.587914 -98.557855) (xy 330.636153 -98.536646) (xy 330.686857 -98.522292) (xy 330.739056 -98.515067)
			(xy 330.765404 -98.514662) (xy 330.791749 -98.51511) (xy 330.843937 -98.522359) (xy 330.894636 -98.536706)
			(xy 330.942885 -98.557878) (xy 330.965556 -98.571304) (xy 330.971671 -98.574785) (xy 330.985195 -98.57865)
			(xy 330.992226 -98.578924) (xy 331.351382 -98.578924) (xy 331.358423 -98.578705) (xy 331.371965 -98.574848)
			(xy 331.378052 -98.571304) (xy 331.400714 -98.557855) (xy 331.448953 -98.536646) (xy 331.499657 -98.522292)
			(xy 331.551856 -98.515067) (xy 331.578204 -98.514662) (xy 331.604549 -98.51511) (xy 331.656737 -98.522359)
			(xy 331.707436 -98.536706) (xy 331.755685 -98.557878) (xy 331.778356 -98.571304) (xy 331.784471 -98.574785)
			(xy 331.797995 -98.57865) (xy 331.805026 -98.578924) (xy 434.901594 -98.578924) (xy 434.930042 -98.55454)
			(xy 434.93309 -98.535998) (xy 434.93765 -98.509829) (xy 434.953507 -98.459133) (xy 434.97672 -98.411356)
			(xy 435.006775 -98.367558) (xy 435.043004 -98.328712) (xy 435.084602 -98.29568) (xy 435.130647 -98.269196)
			(xy 435.180115 -98.249847) (xy 435.23191 -98.238064) (xy 435.28488 -98.234106) (xy 435.33785 -98.238064)
			(xy 435.389645 -98.249847) (xy 435.439113 -98.269196) (xy 435.485158 -98.29568) (xy 435.526756 -98.328712)
			(xy 435.562985 -98.367558) (xy 435.59304 -98.411356) (xy 435.616253 -98.459133) (xy 435.63211 -98.509829)
			(xy 435.63667 -98.535998) (xy 435.639718 -98.55454) (xy 435.668166 -98.578924) (xy 435.790594 -98.578924)
			(xy 435.819042 -98.55454) (xy 435.82209 -98.535998) (xy 435.82665 -98.509829) (xy 435.842507 -98.459133)
			(xy 435.86572 -98.411356) (xy 435.895775 -98.367558) (xy 435.932004 -98.328712) (xy 435.973602 -98.29568)
			(xy 436.019647 -98.269196) (xy 436.069115 -98.249847) (xy 436.12091 -98.238064) (xy 436.17388 -98.234106)
			(xy 436.22685 -98.238064) (xy 436.278645 -98.249847) (xy 436.328113 -98.269196) (xy 436.374158 -98.29568)
			(xy 436.415756 -98.328712) (xy 436.451985 -98.367558) (xy 436.48204 -98.411356) (xy 436.505253 -98.459133)
			(xy 436.52111 -98.509829) (xy 436.52567 -98.535998) (xy 436.528718 -98.55454) (xy 436.557166 -98.578924)
			(xy 449.12407 -98.578924) (xy 449.134135 -98.578489) (xy 449.152723 -98.570759) (xy 449.160138 -98.563938)
			(xy 452.022972 -95.701104) (xy 452.029822 -95.693707) (xy 452.037562 -95.675109) (xy 452.037958 -95.665036)
			(xy 452.037958 -74.851768) (xy 452.038532 -74.826809) (xy 452.048279 -74.777852) (xy 452.06739 -74.731738)
			(xy 452.095132 -74.690239) (xy 452.11238 -74.67219) (xy 453.087486 -73.697084) (xy 453.105528 -73.679826)
			(xy 453.147022 -73.652073) (xy 453.19314 -73.632965) (xy 453.242104 -73.62324) (xy 453.267064 -73.622662)
			(xy 457.412344 -73.622662) (xy 457.42241 -73.62223) (xy 457.440999 -73.6145) (xy 457.448412 -73.607676)
			(xy 459.405228 -71.65086) (xy 459.412076 -71.643463) (xy 459.419807 -71.624864) (xy 459.420214 -71.614792)
			(xy 459.420214 -63.811404) (xy 459.419792 -63.801333) (xy 459.41208 -63.782726) (xy 459.405228 -63.775336)
			(xy 457.727558 -62.097666) (xy 457.72016 -62.090819) (xy 457.701561 -62.083089) (xy 457.69149 -62.08268)
			(xy 449.739258 -62.08268) (xy 449.714299 -62.082105) (xy 449.665342 -62.072358) (xy 449.619228 -62.053248)
			(xy 449.577727 -62.025508) (xy 449.55968 -62.008258) (xy 442.522356 -54.970934) (xy 442.514957 -54.964091)
			(xy 442.496358 -54.956367) (xy 442.486288 -54.955948) (xy 422.81602 -54.955948) (xy 422.804687 -54.956545)
			(xy 422.784228 -54.966298) (xy 422.77665 -54.974744) (xy 422.758432 -54.996324) (xy 422.716721 -55.034394)
			(xy 422.669852 -55.065899) (xy 422.618851 -55.090151) (xy 422.564833 -55.106619) (xy 422.508977 -55.114944)
			(xy 422.452503 -55.114944) (xy 422.396647 -55.106619) (xy 422.342629 -55.090151) (xy 422.291628 -55.065899)
			(xy 422.244759 -55.034394) (xy 422.203048 -54.996324) (xy 422.18483 -54.974744) (xy 422.177211 -54.966353)
			(xy 422.156776 -54.956614) (xy 422.14546 -54.955948) (xy 271.882108 -54.955948) (xy 271.876526 -54.956094)
			(xy 271.865631 -54.95853) (xy 271.860518 -54.960774) (xy 271.831548 -54.973762) (xy 271.771125 -54.993252)
			(xy 271.708745 -55.005069) (xy 271.64538 -55.009028) (xy 271.582015 -55.005069) (xy 271.519635 -54.993252)
			(xy 271.459212 -54.973762) (xy 271.430242 -54.960774) (xy 271.425128 -54.958534) (xy 271.414233 -54.9561)
			(xy 271.408652 -54.955948) (xy 270.06042 -54.955948) (xy 270.050006 -54.960774) (xy 269.97693 -54.9949)
			(xy 269.827974 -55.056784) (xy 269.676152 -55.111262) (xy 269.521834 -55.158203) (xy 269.365393 -55.197494)
			(xy 269.207207 -55.229037) (xy 269.047661 -55.252759) (xy 268.887141 -55.2686) (xy 268.726036 -55.276522)
			(xy 268.645386 -55.277004) (xy 268.564737 -55.276511) (xy 268.403634 -55.268572) (xy 268.243117 -55.25272)
			(xy 268.083573 -55.228992) (xy 267.92539 -55.197446) (xy 267.76895 -55.158158) (xy 267.614631 -55.111224)
			(xy 267.462807 -55.056757) (xy 267.313846 -54.994889) (xy 267.240766 -54.960774) (xy 267.230352 -54.955948)
			(xy 265.88212 -54.955948) (xy 265.876538 -54.956093) (xy 265.865642 -54.958527) (xy 265.86053 -54.960774)
			(xy 265.83156 -54.973762) (xy 265.771137 -54.993252) (xy 265.708757 -55.005069) (xy 265.645392 -55.009028)
			(xy 265.582027 -55.005069) (xy 265.519647 -54.993252) (xy 265.459224 -54.973762) (xy 265.430254 -54.960774)
			(xy 265.42514 -54.958533) (xy 265.414246 -54.956096) (xy 265.408664 -54.955948) (xy 257.139694 -54.955948)
			(xy 257.133683 -54.956109) (xy 257.121994 -54.958921) (xy 257.11658 -54.961536) (xy 257.08441 -54.977442)
			(xy 257.017665 -55.003829) (xy 256.948734 -55.023819) (xy 256.878228 -55.037236) (xy 256.806772 -55.043959)
			(xy 256.770886 -55.04434) (xy 256.735003 -55.043924) (xy 256.663553 -55.037179) (xy 256.593053 -55.023757)
			(xy 256.524122 -55.003779) (xy 256.457371 -54.977419) (xy 256.425192 -54.961536) (xy 256.419766 -54.958947)
			(xy 256.408087 -54.956114) (xy 256.402078 -54.955948) (xy 255.4732 -54.955948) (xy 255.470406 -54.956202)
			(xy 255.461037 -54.957151) (xy 255.442231 -54.95817) (xy 255.432814 -54.958234) (xy 255.395222 -54.956202)
			(xy 255.392428 -54.955948) (xy 254.342138 -54.955948) (xy 254.330962 -54.958488) (xy 254.325628 -54.961282)
			(xy 254.296918 -54.97489) (xy 254.236145 -54.993403) (xy 254.204724 -54.998112) (xy 254.196342 -54.999382)
			(xy 254.18161 -55.006494) (xy 253.417578 -55.770526) (xy 253.399538 -55.787788) (xy 253.358045 -55.815551)
			(xy 253.311927 -55.83467) (xy 253.262962 -55.844407) (xy 253.238 -55.844948) (xy 249.699272 -55.844948)
			(xy 249.686721 -55.845598) (xy 249.664603 -55.857465) (xy 249.657108 -55.867554) (xy 249.634801 -55.900043)
			(xy 249.584484 -55.960705) (xy 249.528179 -56.015853) (xy 249.466485 -56.064899) (xy 249.400061 -56.10732)
			(xy 249.329616 -56.142663) (xy 249.2559 -56.17055) (xy 249.179702 -56.190685) (xy 249.101833 -56.202853)
			(xy 249.023124 -56.206923) (xy 248.944415 -56.202853) (xy 248.866546 -56.190685) (xy 248.790348 -56.17055)
			(xy 248.716632 -56.142663) (xy 248.646187 -56.10732) (xy 248.579763 -56.064899) (xy 248.518069 -56.015853)
			(xy 248.461764 -55.960705) (xy 248.411447 -55.900043) (xy 248.38914 -55.867554) (xy 248.381626 -55.857486)
			(xy 248.359519 -55.845613) (xy 248.346976 -55.844948) (xy 247.08104 -55.844948) (xy 247.054116 -55.865268)
			(xy 247.04929 -55.881524) (xy 247.041247 -55.907662) (xy 247.018716 -55.957491) (xy 246.989302 -56.003593)
			(xy 246.953606 -56.045022) (xy 246.91236 -56.08093) (xy 246.866409 -56.11058) (xy 246.816696 -56.133366)
			(xy 246.764238 -56.148819) (xy 246.710111 -56.156623) (xy 246.682768 -56.157114) (xy 246.655399 -56.15664)
			(xy 246.601222 -56.148812) (xy 246.548721 -56.133322) (xy 246.498973 -56.110488) (xy 246.452998 -56.080778)
			(xy 246.43207 -56.063134) (xy 246.424958 -56.057038) (xy 246.40794 -56.050688) (xy 246.322596 -56.050688)
			(xy 246.305578 -56.057038) (xy 246.298466 -56.063134) (xy 246.277533 -56.080773) (xy 246.231565 -56.110492)
			(xy 246.181818 -56.133329) (xy 246.129315 -56.148813) (xy 246.075137 -56.156626) (xy 246.047768 -56.157114)
			(xy 246.020426 -56.156642) (xy 245.966302 -56.14883) (xy 245.913848 -56.13337) (xy 245.864139 -56.110579)
			(xy 245.818193 -56.080925) (xy 245.776952 -56.045014) (xy 245.741261 -56.003583) (xy 245.711851 -55.95748)
			(xy 245.689324 -55.907651) (xy 245.681246 -55.881524) (xy 245.67642 -55.865268) (xy 245.649496 -55.844948)
			(xy 202.819 -55.844948) (xy 202.79404 -55.844377) (xy 202.745079 -55.834636) (xy 202.698961 -55.815529)
			(xy 202.657457 -55.78779) (xy 202.639422 -55.770526) (xy 201.851768 -54.982872) (xy 201.823828 -54.976522)
			(xy 201.809858 -54.981094) (xy 201.783299 -54.989792) (xy 201.72876 -55.001995) (xy 201.67321 -55.008132)
			(xy 201.645266 -55.008526) (xy 201.614536 -55.00806) (xy 201.553524 -55.000648) (xy 201.493851 -54.985937)
			(xy 201.436386 -54.96414) (xy 201.381966 -54.935576) (xy 201.331386 -54.900662) (xy 201.285384 -54.859905)
			(xy 201.244629 -54.813901) (xy 201.209715 -54.76332) (xy 201.181153 -54.7089) (xy 201.159359 -54.651434)
			(xy 201.144649 -54.59176) (xy 201.137239 -54.530748) (xy 201.136758 -54.500018) (xy 201.137158 -54.472075)
			(xy 201.143315 -54.416529) (xy 201.155514 -54.361991) (xy 201.16419 -54.335426) (xy 201.168762 -54.321456)
			(xy 201.162412 -54.293516) (xy 194.541394 -47.672498) (xy 194.507104 -47.66818) (xy 194.491864 -47.67707)
			(xy 194.471153 -47.688951) (xy 194.427227 -47.707665) (xy 194.381191 -47.720332) (xy 194.333873 -47.726723)
			(xy 194.31 -47.727108) (xy 194.282017 -47.726559) (xy 194.22674 -47.717804) (xy 194.173513 -47.700509)
			(xy 194.123646 -47.675101) (xy 194.078369 -47.642205) (xy 194.038795 -47.602631) (xy 194.005899 -47.557354)
			(xy 193.980491 -47.507487) (xy 193.963196 -47.45426) (xy 193.954441 -47.398983) (xy 193.953892 -47.371)
			(xy 193.954294 -47.347128) (xy 193.960702 -47.299816) (xy 193.973364 -47.253782) (xy 193.992054 -47.209848)
			(xy 194.00393 -47.189136) (xy 194.01282 -47.173896) (xy 194.008502 -47.139606) (xy 181.833774 -34.964878)
			(xy 181.828694 -34.96183) (xy 181.798524 -34.942783) (xy 181.741507 -34.899881) (xy 181.688748 -34.85184)
			(xy 181.640708 -34.79908) (xy 181.597808 -34.742063) (xy 181.578758 -34.711894) (xy 181.57571 -34.706814)
			(xy 179.117752 -32.248856) (xy 179.092606 -32.241744) (xy 179.079652 -32.245046) (xy 179.059071 -32.249675)
			(xy 179.017179 -32.254636) (xy 178.996086 -32.254952) (xy 178.968102 -32.254402) (xy 178.912824 -32.245646)
			(xy 178.859596 -32.22835) (xy 178.809729 -32.202942) (xy 178.764449 -32.170047) (xy 178.724873 -32.130473)
			(xy 178.691974 -32.085197) (xy 178.666561 -32.035331) (xy 178.649261 -31.982105) (xy 178.6405 -31.926828)
			(xy 178.639978 -31.898844) (xy 178.640261 -31.877749) (xy 178.645227 -31.835854) (xy 178.649884 -31.815278)
			(xy 178.653186 -31.802324) (xy 178.646074 -31.777178) (xy 177.07483 -30.205934) (xy 177.067429 -30.199095)
			(xy 177.048831 -30.191381) (xy 177.038762 -30.190948) (xy 172.484034 -30.190948) (xy 172.458888 -30.207712)
			(xy 172.452792 -30.22219) (xy 172.441562 -30.247932) (xy 172.412651 -30.296079) (xy 172.376994 -30.339467)
			(xy 172.33536 -30.377158) (xy 172.28865 -30.408338) (xy 172.237874 -30.432332) (xy 172.184128 -30.448623)
			(xy 172.128574 -30.456857) (xy 172.072414 -30.456857) (xy 172.01686 -30.448623) (xy 171.963114 -30.432332)
			(xy 171.912338 -30.408338) (xy 171.865628 -30.377158) (xy 171.823994 -30.339467) (xy 171.788337 -30.296079)
			(xy 171.759426 -30.247932) (xy 171.748196 -30.22219) (xy 171.7421 -30.207712) (xy 171.716954 -30.190948)
			(xy 145.371566 -30.190948) (xy 145.347182 -30.206188) (xy 145.340578 -30.219396) (xy 145.327453 -30.244847)
			(xy 145.294738 -30.291845) (xy 145.255374 -30.333433) (xy 145.233136 -30.351476) (xy 145.223738 -30.358842)
			(xy 145.213578 -30.37967) (xy 145.213578 -30.483556) (xy 145.223738 -30.504384) (xy 145.233136 -30.51175)
			(xy 145.255594 -30.529956) (xy 145.295279 -30.571994) (xy 145.328169 -30.619536) (xy 145.353514 -30.671495)
			(xy 145.370732 -30.726682) (xy 145.37943 -30.783834) (xy 145.379948 -30.81274) (xy 145.379948 -31.67634)
			(xy 145.379462 -31.703591) (xy 145.371706 -31.757539) (xy 145.356351 -31.809834) (xy 145.333709 -31.859411)
			(xy 145.304243 -31.905261) (xy 145.268552 -31.946452) (xy 145.227361 -31.982143) (xy 145.181511 -32.011609)
			(xy 145.131934 -32.034251) (xy 145.079639 -32.049606) (xy 145.025691 -32.057362) (xy 144.971189 -32.057362)
			(xy 144.917241 -32.049606) (xy 144.864946 -32.034251) (xy 144.815369 -32.011609) (xy 144.769519 -31.982143)
			(xy 144.728328 -31.946452) (xy 144.692637 -31.905261) (xy 144.663171 -31.859411) (xy 144.640529 -31.809834)
			(xy 144.625174 -31.757539) (xy 144.617418 -31.703591) (xy 144.616932 -31.67634) (xy 144.616932 -30.81274)
			(xy 144.617448 -30.783834) (xy 144.626138 -30.72668) (xy 144.643354 -30.671493) (xy 144.668702 -30.619536)
			(xy 144.701602 -30.572) (xy 144.7413 -30.529974) (xy 144.763744 -30.51175) (xy 144.773142 -30.504384)
			(xy 144.783302 -30.483556) (xy 144.783302 -30.37967) (xy 144.773142 -30.358842) (xy 144.763744 -30.351476)
			(xy 144.741481 -30.33346) (xy 144.702103 -30.291877) (xy 144.669393 -30.244868) (xy 144.656302 -30.219396)
			(xy 144.649698 -30.206188) (xy 144.625314 -30.190948) (xy 141.066266 -30.190948) (xy 141.038326 -30.214062)
			(xy 141.03477 -30.232096) (xy 141.029627 -30.256703) (xy 141.013719 -30.304391) (xy 140.991673 -30.349571)
			(xy 140.963873 -30.391456) (xy 140.947648 -30.410658) (xy 140.941552 -30.41777) (xy 140.935202 -30.434534)
			(xy 140.935202 -30.520132) (xy 140.941552 -30.53715) (xy 140.947648 -30.544008) (xy 140.96529 -30.564968)
			(xy 140.995011 -30.610991) (xy 141.017848 -30.660789) (xy 141.03333 -30.713342) (xy 141.04114 -30.767567)
			(xy 141.041628 -30.79496) (xy 141.041628 -31.65856) (xy 141.041142 -31.685811) (xy 141.033386 -31.739759)
			(xy 141.018031 -31.792054) (xy 140.995389 -31.841631) (xy 140.965923 -31.887481) (xy 140.930232 -31.928672)
			(xy 140.889041 -31.964363) (xy 140.843191 -31.993829) (xy 140.793614 -32.016471) (xy 140.741319 -32.031826)
			(xy 140.687371 -32.039582) (xy 140.632869 -32.039582) (xy 140.578921 -32.031826) (xy 140.526626 -32.016471)
			(xy 140.477049 -31.993829) (xy 140.431199 -31.964363) (xy 140.390008 -31.928672) (xy 140.354317 -31.887481)
			(xy 140.324851 -31.841631) (xy 140.302209 -31.792054) (xy 140.286854 -31.739759) (xy 140.279098 -31.685811)
			(xy 140.278612 -31.65856) (xy 140.278612 -30.79496) (xy 140.279068 -30.767566) (xy 140.286874 -30.713338)
			(xy 140.302364 -30.660785) (xy 140.325218 -30.610992) (xy 140.354966 -30.564984) (xy 140.372592 -30.544008)
			(xy 140.378688 -30.53715) (xy 140.385038 -30.520132) (xy 140.385038 -30.434534) (xy 140.378688 -30.41777)
			(xy 140.372592 -30.410658) (xy 140.35638 -30.391448) (xy 140.328606 -30.34955) (xy 140.306564 -30.304373)
			(xy 140.290632 -30.256697) (xy 140.28547 -30.232096) (xy 140.281914 -30.214062) (xy 140.253974 -30.190948)
			(xy 136.16686 -30.190948) (xy 136.159588 -30.191172) (xy 136.145642 -30.195293) (xy 136.139428 -30.199076)
			(xy 136.116233 -30.213377) (xy 136.066651 -30.235976) (xy 136.014362 -30.251301) (xy 135.960425 -30.25904)
			(xy 135.93318 -30.259528) (xy 135.90593 -30.25909) (xy 135.85198 -30.251377) (xy 135.799679 -30.236054)
			(xy 135.750096 -30.213434) (xy 135.726932 -30.199076) (xy 135.720683 -30.19537) (xy 135.706759 -30.191241)
			(xy 135.6995 -30.190948) (xy 69.056758 -30.190948) (xy 69.031104 -30.20822) (xy 69.025262 -30.222444)
			(xy 69.014087 -30.248301) (xy 68.985241 -30.296684) (xy 68.949594 -30.340298) (xy 68.90792 -30.378196)
			(xy 68.861126 -30.409553) (xy 68.810229 -30.433688) (xy 68.756337 -30.450075) (xy 68.70062 -30.458359)
			(xy 68.644292 -30.458359) (xy 68.588575 -30.450075) (xy 68.534683 -30.433688) (xy 68.483786 -30.409553)
			(xy 68.436992 -30.378196) (xy 68.395318 -30.340298) (xy 68.359671 -30.296684) (xy 68.330825 -30.248301)
			(xy 68.31965 -30.222444) (xy 68.313808 -30.20822) (xy 68.288154 -30.190948) (xy 66.421 -30.190948)
			(xy 66.39604 -30.190377) (xy 66.347079 -30.180636) (xy 66.300961 -30.161529) (xy 66.259457 -30.13379)
			(xy 66.241422 -30.116526) (xy 64.04483 -27.919934) (xy 64.037429 -27.913095) (xy 64.018831 -27.905381)
			(xy 64.008762 -27.904948) (xy 60.070238 -27.904948) (xy 60.060174 -27.905384) (xy 60.04159 -27.913119)
			(xy 60.03417 -27.919934) (xy 57.672986 -30.281118) (xy 57.666133 -30.288513) (xy 57.658392 -30.307112)
			(xy 57.658 -30.317186) (xy 57.658 -32.94761) (xy 102.642416 -32.94761) (xy 102.642416 -31.95701)
			(xy 102.642902 -31.929759) (xy 102.650658 -31.875811) (xy 102.666013 -31.823516) (xy 102.688655 -31.773939)
			(xy 102.718121 -31.728089) (xy 102.753812 -31.686898) (xy 102.795003 -31.651207) (xy 102.840853 -31.621741)
			(xy 102.89043 -31.599099) (xy 102.942725 -31.583744) (xy 102.996673 -31.575988) (xy 103.051175 -31.575988)
			(xy 103.105123 -31.583744) (xy 103.157418 -31.599099) (xy 103.206995 -31.621741) (xy 103.252845 -31.651207)
			(xy 103.294036 -31.686898) (xy 103.329727 -31.728089) (xy 103.359193 -31.773939) (xy 103.381835 -31.823516)
			(xy 103.39719 -31.875811) (xy 103.404946 -31.929759) (xy 103.405432 -31.95701) (xy 103.405432 -32.405066)
			(xy 105.659936 -32.405066) (xy 105.659936 -31.541466) (xy 105.660422 -31.514215) (xy 105.668178 -31.460267)
			(xy 105.683533 -31.407972) (xy 105.706175 -31.358395) (xy 105.735641 -31.312545) (xy 105.771332 -31.271354)
			(xy 105.812523 -31.235663) (xy 105.858373 -31.206197) (xy 105.90795 -31.183555) (xy 105.960245 -31.1682)
			(xy 106.014193 -31.160444) (xy 106.068695 -31.160444) (xy 106.122643 -31.1682) (xy 106.174938 -31.183555)
			(xy 106.224515 -31.206197) (xy 106.270365 -31.235663) (xy 106.311556 -31.271354) (xy 106.347247 -31.312545)
			(xy 106.376713 -31.358395) (xy 106.399355 -31.407972) (xy 106.41471 -31.460267) (xy 106.422466 -31.514215)
			(xy 106.422952 -31.541466) (xy 106.422952 -32.405066) (xy 106.422466 -32.432317) (xy 106.41471 -32.486265)
			(xy 106.399355 -32.53856) (xy 106.376713 -32.588137) (xy 106.347247 -32.633987) (xy 106.311556 -32.675178)
			(xy 106.270365 -32.710869) (xy 106.224515 -32.740335) (xy 106.174938 -32.762977) (xy 106.122643 -32.778332)
			(xy 106.068695 -32.786088) (xy 106.014193 -32.786088) (xy 105.960245 -32.778332) (xy 105.90795 -32.762977)
			(xy 105.858373 -32.740335) (xy 105.812523 -32.710869) (xy 105.771332 -32.675178) (xy 105.735641 -32.633987)
			(xy 105.706175 -32.588137) (xy 105.683533 -32.53856) (xy 105.668178 -32.486265) (xy 105.660422 -32.432317)
			(xy 105.659936 -32.405066) (xy 103.405432 -32.405066) (xy 103.405432 -32.94761) (xy 103.404946 -32.974861)
			(xy 103.39719 -33.028809) (xy 103.390276 -33.052356) (xy 119.734235 -33.052356) (xy 119.734235 -32.997844)
			(xy 119.741993 -32.943888) (xy 119.757352 -32.891585) (xy 119.779997 -32.842) (xy 119.80947 -32.796143)
			(xy 119.845169 -32.754947) (xy 119.886367 -32.719252) (xy 119.932226 -32.689783) (xy 119.981813 -32.667141)
			(xy 120.034117 -32.651787) (xy 120.088074 -32.644033) (xy 120.11533 -32.643572) (xy 120.97893 -32.643572)
			(xy 121.006178 -32.6441) (xy 121.06012 -32.65186) (xy 121.112408 -32.667217) (xy 121.161979 -32.689858)
			(xy 121.207823 -32.719324) (xy 121.249008 -32.755014) (xy 121.284694 -32.796201) (xy 121.314156 -32.842047)
			(xy 121.336794 -32.89162) (xy 121.352147 -32.943909) (xy 121.359902 -32.997852) (xy 121.359902 -33.052348)
			(xy 121.352147 -33.106291) (xy 121.336794 -33.15858) (xy 121.314156 -33.208153) (xy 121.284694 -33.253999)
			(xy 121.249008 -33.295186) (xy 121.207823 -33.330876) (xy 121.161979 -33.360342) (xy 121.112408 -33.382983)
			(xy 121.06012 -33.39834) (xy 121.006178 -33.4061) (xy 120.97893 -33.406588) (xy 120.11533 -33.406588)
			(xy 120.088074 -33.406167) (xy 120.034117 -33.398413) (xy 119.981813 -33.383059) (xy 119.932226 -33.360417)
			(xy 119.886367 -33.330948) (xy 119.845169 -33.295253) (xy 119.80947 -33.254057) (xy 119.779997 -33.2082)
			(xy 119.757352 -33.158615) (xy 119.741993 -33.106312) (xy 119.734235 -33.052356) (xy 103.390276 -33.052356)
			(xy 103.381835 -33.081104) (xy 103.359193 -33.130681) (xy 103.329727 -33.176531) (xy 103.294036 -33.217722)
			(xy 103.252845 -33.253413) (xy 103.206995 -33.282879) (xy 103.157418 -33.305521) (xy 103.105123 -33.320876)
			(xy 103.051175 -33.328632) (xy 102.996673 -33.328632) (xy 102.942725 -33.320876) (xy 102.89043 -33.305521)
			(xy 102.840853 -33.282879) (xy 102.795003 -33.253413) (xy 102.753812 -33.217722) (xy 102.718121 -33.176531)
			(xy 102.688655 -33.130681) (xy 102.666013 -33.081104) (xy 102.650658 -33.028809) (xy 102.642902 -32.974861)
			(xy 102.642416 -32.94761) (xy 57.658 -32.94761) (xy 57.658 -33.838388) (xy 122.111008 -33.838388)
			(xy 122.111008 -32.974788) (xy 122.111494 -32.947519) (xy 122.119256 -32.893535) (xy 122.134621 -32.841205)
			(xy 122.157278 -32.791595) (xy 122.186764 -32.745714) (xy 122.222479 -32.704497) (xy 122.263696 -32.668782)
			(xy 122.309577 -32.639296) (xy 122.359187 -32.616639) (xy 122.411517 -32.601274) (xy 122.465501 -32.593512)
			(xy 122.520039 -32.593512) (xy 122.574023 -32.601274) (xy 122.626353 -32.616639) (xy 122.675963 -32.639296)
			(xy 122.721844 -32.668782) (xy 122.763061 -32.704497) (xy 122.798776 -32.745714) (xy 122.828262 -32.791595)
			(xy 122.850919 -32.841205) (xy 122.866284 -32.893535) (xy 122.874046 -32.947519) (xy 122.874532 -32.974788)
			(xy 122.874532 -33.413556) (xy 124.175423 -33.413556) (xy 124.175423 -33.359044) (xy 124.183181 -33.305087)
			(xy 124.198539 -33.252783) (xy 124.221185 -33.203197) (xy 124.250658 -33.157339) (xy 124.286357 -33.116142)
			(xy 124.327555 -33.080446) (xy 124.373415 -33.050976) (xy 124.423002 -33.028332) (xy 124.475306 -33.012977)
			(xy 124.529264 -33.005222) (xy 124.55652 -33.00476) (xy 125.42012 -33.00476) (xy 125.447368 -33.005312)
			(xy 125.501309 -33.01307) (xy 125.553597 -33.028425) (xy 125.603167 -33.051066) (xy 125.649011 -33.08053)
			(xy 125.690196 -33.116218) (xy 125.725882 -33.157405) (xy 125.755344 -33.20325) (xy 125.777982 -33.252822)
			(xy 125.793335 -33.305111) (xy 125.80109 -33.359052) (xy 125.80109 -33.413548) (xy 125.793335 -33.467489)
			(xy 125.777982 -33.519778) (xy 125.755344 -33.56935) (xy 125.725882 -33.615195) (xy 125.690196 -33.656382)
			(xy 125.649011 -33.69207) (xy 125.603167 -33.721534) (xy 125.553597 -33.744175) (xy 125.501309 -33.75953)
			(xy 125.447368 -33.767288) (xy 125.42012 -33.767776) (xy 124.55652 -33.767776) (xy 124.529264 -33.767378)
			(xy 124.475306 -33.759623) (xy 124.423002 -33.744268) (xy 124.373415 -33.721624) (xy 124.327555 -33.692154)
			(xy 124.286357 -33.656458) (xy 124.250658 -33.615261) (xy 124.221185 -33.569403) (xy 124.198539 -33.519817)
			(xy 124.183181 -33.467513) (xy 124.175423 -33.413556) (xy 122.874532 -33.413556) (xy 122.874532 -33.838388)
			(xy 122.874046 -33.865657) (xy 122.866284 -33.919641) (xy 122.850919 -33.971971) (xy 122.828262 -34.021581)
			(xy 122.798776 -34.067462) (xy 122.763061 -34.108679) (xy 122.721844 -34.144394) (xy 122.675963 -34.17388)
			(xy 122.626353 -34.196537) (xy 122.574023 -34.211902) (xy 122.520039 -34.219664) (xy 122.465501 -34.219664)
			(xy 122.411517 -34.211902) (xy 122.359187 -34.196537) (xy 122.309577 -34.17388) (xy 122.263696 -34.144394)
			(xy 122.222479 -34.108679) (xy 122.186764 -34.067462) (xy 122.157278 -34.021581) (xy 122.134621 -33.971971)
			(xy 122.119256 -33.919641) (xy 122.111494 -33.865657) (xy 122.111008 -33.838388) (xy 57.658 -33.838388)
			(xy 57.658 -36.080556) (xy 122.143423 -36.080556) (xy 122.143423 -36.026044) (xy 122.151181 -35.972087)
			(xy 122.166539 -35.919783) (xy 122.189185 -35.870197) (xy 122.218658 -35.824339) (xy 122.254357 -35.783142)
			(xy 122.295555 -35.747446) (xy 122.341415 -35.717976) (xy 122.391002 -35.695332) (xy 122.443306 -35.679977)
			(xy 122.497264 -35.672222) (xy 122.52452 -35.67176) (xy 123.38812 -35.67176) (xy 123.415368 -35.672312)
			(xy 123.469309 -35.68007) (xy 123.521597 -35.695425) (xy 123.571167 -35.718066) (xy 123.617011 -35.74753)
			(xy 123.658196 -35.783218) (xy 123.693882 -35.824405) (xy 123.723344 -35.87025) (xy 123.745982 -35.919822)
			(xy 123.761335 -35.972111) (xy 123.76909 -36.026052) (xy 123.76909 -36.080548) (xy 123.761335 -36.134489)
			(xy 123.745982 -36.186778) (xy 123.723344 -36.23635) (xy 123.693882 -36.282195) (xy 123.658196 -36.323382)
			(xy 123.617011 -36.35907) (xy 123.571167 -36.388534) (xy 123.521597 -36.411175) (xy 123.469309 -36.42653)
			(xy 123.415368 -36.434288) (xy 123.38812 -36.434776) (xy 122.52452 -36.434776) (xy 122.497264 -36.434378)
			(xy 122.443306 -36.426623) (xy 122.391002 -36.411268) (xy 122.341415 -36.388624) (xy 122.295555 -36.359154)
			(xy 122.254357 -36.323458) (xy 122.218658 -36.282261) (xy 122.189185 -36.236403) (xy 122.166539 -36.186817)
			(xy 122.151181 -36.134513) (xy 122.143423 -36.080556) (xy 57.658 -36.080556) (xy 57.658 -37.099618)
			(xy 170.601124 -37.099618) (xy 170.601124 -37.00031) (xy 170.609115 -36.901323) (xy 170.625045 -36.8033)
			(xy 170.648811 -36.706877) (xy 170.680259 -36.612679) (xy 170.719185 -36.521316) (xy 170.765336 -36.433383)
			(xy 170.818413 -36.349448) (xy 170.878072 -36.270056) (xy 170.943926 -36.195722) (xy 171.015548 -36.126929)
			(xy 171.092473 -36.064121) (xy 171.174203 -36.007707) (xy 171.260207 -35.958053) (xy 171.349927 -35.91548)
			(xy 171.442783 -35.880264) (xy 171.538171 -35.852635) (xy 171.635473 -35.832771) (xy 171.734058 -35.8208)
			(xy 171.833286 -35.816802) (xy 171.932514 -35.8208) (xy 172.031099 -35.832771) (xy 172.128401 -35.852635)
			(xy 172.223789 -35.880264) (xy 172.316645 -35.91548) (xy 172.406365 -35.958053) (xy 172.492369 -36.007707)
			(xy 172.574099 -36.064121) (xy 172.651024 -36.126929) (xy 172.722646 -36.195722) (xy 172.7885 -36.270056)
			(xy 172.848159 -36.349448) (xy 172.901236 -36.433383) (xy 172.947387 -36.521316) (xy 172.986313 -36.612679)
			(xy 173.017761 -36.706877) (xy 173.041527 -36.8033) (xy 173.057457 -36.901323) (xy 173.065448 -37.00031)
			(xy 173.065948 -37.049964) (xy 173.065448 -37.099618) (xy 173.057457 -37.198605) (xy 173.041527 -37.296628)
			(xy 173.017761 -37.393051) (xy 172.986313 -37.487249) (xy 172.947387 -37.578612) (xy 172.901236 -37.666545)
			(xy 172.848159 -37.75048) (xy 172.7885 -37.829872) (xy 172.722646 -37.904206) (xy 172.651024 -37.972999)
			(xy 172.574099 -38.035807) (xy 172.492369 -38.092221) (xy 172.406365 -38.141875) (xy 172.316645 -38.184448)
			(xy 172.223789 -38.219664) (xy 172.128401 -38.247293) (xy 172.031099 -38.267157) (xy 171.932514 -38.279128)
			(xy 171.833286 -38.283127) (xy 171.734058 -38.279128) (xy 171.635473 -38.267157) (xy 171.538171 -38.247293)
			(xy 171.442783 -38.219664) (xy 171.349927 -38.184448) (xy 171.260207 -38.141875) (xy 171.174203 -38.092221)
			(xy 171.092473 -38.035807) (xy 171.015548 -37.972999) (xy 170.943926 -37.904206) (xy 170.878072 -37.829872)
			(xy 170.818413 -37.75048) (xy 170.765336 -37.666545) (xy 170.719185 -37.578612) (xy 170.680259 -37.487249)
			(xy 170.648811 -37.393051) (xy 170.625045 -37.296628) (xy 170.609115 -37.198605) (xy 170.601124 -37.099618)
			(xy 57.658 -37.099618) (xy 57.658 -43.481752) (xy 178.630072 -43.481752) (xy 178.630072 -42.618152)
			(xy 178.630558 -42.590883) (xy 178.63832 -42.536899) (xy 178.653685 -42.484569) (xy 178.676342 -42.434959)
			(xy 178.705828 -42.389078) (xy 178.741543 -42.347861) (xy 178.78276 -42.312146) (xy 178.828641 -42.28266)
			(xy 178.878251 -42.260003) (xy 178.930581 -42.244638) (xy 178.984565 -42.236876) (xy 179.039103 -42.236876)
			(xy 179.093087 -42.244638) (xy 179.145417 -42.260003) (xy 179.195027 -42.28266) (xy 179.240908 -42.312146)
			(xy 179.282125 -42.347861) (xy 179.31784 -42.389078) (xy 179.347326 -42.434959) (xy 179.369983 -42.484569)
			(xy 179.385348 -42.536899) (xy 179.39311 -42.590883) (xy 179.393596 -42.618152) (xy 179.393596 -43.481752)
			(xy 179.39311 -43.509021) (xy 179.385348 -43.563005) (xy 179.369983 -43.615335) (xy 179.347326 -43.664945)
			(xy 179.31784 -43.710826) (xy 179.282125 -43.752043) (xy 179.240908 -43.787758) (xy 179.195027 -43.817244)
			(xy 179.145417 -43.839901) (xy 179.093087 -43.855266) (xy 179.039103 -43.863028) (xy 178.984565 -43.863028)
			(xy 178.930581 -43.855266) (xy 178.878251 -43.839901) (xy 178.828641 -43.817244) (xy 178.78276 -43.787758)
			(xy 178.741543 -43.752043) (xy 178.705828 -43.710826) (xy 178.676342 -43.664945) (xy 178.653685 -43.615335)
			(xy 178.63832 -43.563005) (xy 178.630558 -43.509021) (xy 178.630072 -43.481752) (xy 57.658 -43.481752)
			(xy 57.658 -47.04994) (xy 59.582066 -47.04994) (xy 59.586045 -46.890389) (xy 59.597972 -46.731234)
			(xy 59.617818 -46.572872) (xy 59.645532 -46.415696) (xy 59.681047 -46.260096) (xy 59.724273 -46.10646)
			(xy 59.775104 -45.95517) (xy 59.833413 -45.806602) (xy 59.899054 -45.661125) (xy 59.971866 -45.519101)
			(xy 60.051666 -45.380882) (xy 60.138257 -45.246813) (xy 60.231423 -45.117227) (xy 60.330933 -44.992446)
			(xy 60.436538 -44.87278) (xy 60.547978 -44.758527) (xy 60.664973 -44.649971) (xy 60.787235 -44.547381)
			(xy 60.914458 -44.451014) (xy 61.046326 -44.361107) (xy 61.182512 -44.277886) (xy 61.322677 -44.201556)
			(xy 61.466472 -44.132307) (xy 61.613541 -44.070313) (xy 61.763517 -44.015726) (xy 61.916027 -43.968683)
			(xy 62.070693 -43.9293) (xy 62.227129 -43.897676) (xy 62.384947 -43.873888) (xy 62.543755 -43.857997)
			(xy 62.703158 -43.850041) (xy 62.782958 -43.849544) (xy 64.382904 -43.849544) (xy 64.462705 -43.850033)
			(xy 64.622107 -43.857989) (xy 64.780916 -43.87388) (xy 64.938734 -43.897668) (xy 65.095171 -43.929293)
			(xy 65.249837 -43.968675) (xy 65.402347 -44.015719) (xy 65.552323 -44.070306) (xy 65.699392 -44.132301)
			(xy 65.843188 -44.201549) (xy 65.983353 -44.277879) (xy 66.119539 -44.361101) (xy 66.251408 -44.451008)
			(xy 66.378631 -44.547376) (xy 66.500893 -44.649966) (xy 66.617889 -44.758522) (xy 66.729328 -44.872775)
			(xy 66.834934 -44.992442) (xy 66.934444 -45.117223) (xy 67.02761 -45.246809) (xy 67.114201 -45.380878)
			(xy 67.194001 -45.519097) (xy 67.266813 -45.661122) (xy 67.332455 -45.806599) (xy 67.390764 -45.955168)
			(xy 67.441595 -46.106458) (xy 67.484821 -46.260094) (xy 67.520336 -46.415694) (xy 67.54805 -46.572871)
			(xy 67.567896 -46.731233) (xy 67.579823 -46.890388) (xy 67.583802 -47.04994) (xy 89.78165 -47.04994)
			(xy 89.78563 -46.895439) (xy 89.797557 -46.741349) (xy 89.817402 -46.588076) (xy 89.84511 -46.436028)
			(xy 89.880608 -46.285609) (xy 89.923803 -46.137216) (xy 89.97458 -45.991243) (xy 90.032804 -45.848078)
			(xy 90.098321 -45.708101) (xy 90.170957 -45.571681) (xy 90.250519 -45.439181) (xy 90.336796 -45.310953)
			(xy 90.42956 -45.187337) (xy 90.528565 -45.068659) (xy 90.633548 -44.955236) (xy 90.74423 -44.847368)
			(xy 90.860319 -44.74534) (xy 90.981506 -44.649424) (xy 91.10747 -44.559873) (xy 91.237877 -44.476926)
			(xy 91.372381 -44.400801) (xy 91.510626 -44.331702) (xy 91.652244 -44.269811) (xy 91.796861 -44.215293)
			(xy 91.944092 -44.168291) (xy 92.093548 -44.128931) (xy 92.244832 -44.097317) (xy 92.397543 -44.073533)
			(xy 92.551275 -44.057642) (xy 92.705622 -44.049686) (xy 92.782898 -44.049188) (xy 94.383098 -44.049188)
			(xy 94.460374 -44.049669) (xy 94.614722 -44.057625) (xy 94.768456 -44.073516) (xy 94.921168 -44.0973)
			(xy 95.072452 -44.128914) (xy 95.221909 -44.168274) (xy 95.369142 -44.215276) (xy 95.513759 -44.269795)
			(xy 95.655379 -44.331686) (xy 95.793624 -44.400785) (xy 95.928129 -44.47691) (xy 96.058537 -44.559858)
			(xy 96.184502 -44.649409) (xy 96.30569 -44.745326) (xy 96.421779 -44.847354) (xy 96.532463 -44.955223)
			(xy 96.555487 -44.980098) (xy 181.659784 -44.980098) (xy 181.659784 -44.116498) (xy 181.66027 -44.089229)
			(xy 181.668032 -44.035245) (xy 181.683397 -43.982915) (xy 181.706054 -43.933305) (xy 181.73554 -43.887424)
			(xy 181.771255 -43.846207) (xy 181.812472 -43.810492) (xy 181.858353 -43.781006) (xy 181.907963 -43.758349)
			(xy 181.960293 -43.742984) (xy 182.014277 -43.735222) (xy 182.068815 -43.735222) (xy 182.122799 -43.742984)
			(xy 182.175129 -43.758349) (xy 182.224739 -43.781006) (xy 182.27062 -43.810492) (xy 182.311837 -43.846207)
			(xy 182.347552 -43.887424) (xy 182.377038 -43.933305) (xy 182.399695 -43.982915) (xy 182.41506 -44.035245)
			(xy 182.422822 -44.089229) (xy 182.423308 -44.116498) (xy 182.423308 -44.980098) (xy 182.422822 -45.007367)
			(xy 182.41506 -45.061351) (xy 182.399695 -45.113681) (xy 182.377038 -45.163291) (xy 182.347552 -45.209172)
			(xy 182.311837 -45.250389) (xy 182.27062 -45.286104) (xy 182.224739 -45.31559) (xy 182.175129 -45.338247)
			(xy 182.122799 -45.353612) (xy 182.068815 -45.361374) (xy 182.014277 -45.361374) (xy 181.960293 -45.353612)
			(xy 181.907963 -45.338247) (xy 181.858353 -45.31559) (xy 181.812472 -45.286104) (xy 181.771255 -45.250389)
			(xy 181.73554 -45.209172) (xy 181.706054 -45.163291) (xy 181.683397 -45.113681) (xy 181.668032 -45.061351)
			(xy 181.66027 -45.007367) (xy 181.659784 -44.980098) (xy 96.555487 -44.980098) (xy 96.637446 -45.068647)
			(xy 96.736452 -45.187325) (xy 96.829216 -45.310943) (xy 96.915495 -45.439171) (xy 96.995057 -45.571672)
			(xy 97.067693 -45.708092) (xy 97.133211 -45.848071) (xy 97.191435 -45.991237) (xy 97.242212 -46.13721)
			(xy 97.285407 -46.285604) (xy 97.320906 -46.436025) (xy 97.329238 -46.481746) (xy 178.630072 -46.481746)
			(xy 178.630072 -45.618146) (xy 178.630558 -45.590877) (xy 178.63832 -45.536893) (xy 178.653685 -45.484563)
			(xy 178.676342 -45.434953) (xy 178.705828 -45.389072) (xy 178.741543 -45.347855) (xy 178.78276 -45.31214)
			(xy 178.828641 -45.282654) (xy 178.878251 -45.259997) (xy 178.930581 -45.244632) (xy 178.984565 -45.23687)
			(xy 179.039103 -45.23687) (xy 179.093087 -45.244632) (xy 179.145417 -45.259997) (xy 179.195027 -45.282654)
			(xy 179.240908 -45.31214) (xy 179.282125 -45.347855) (xy 179.31784 -45.389072) (xy 179.347326 -45.434953)
			(xy 179.369983 -45.484563) (xy 179.385348 -45.536893) (xy 179.39311 -45.590877) (xy 179.393596 -45.618146)
			(xy 179.393596 -46.481746) (xy 179.39311 -46.509015) (xy 179.385348 -46.562999) (xy 179.369983 -46.615329)
			(xy 179.347326 -46.664939) (xy 179.31784 -46.71082) (xy 179.282125 -46.752037) (xy 179.240908 -46.787752)
			(xy 179.195027 -46.817238) (xy 179.145417 -46.839895) (xy 179.093087 -46.85526) (xy 179.039103 -46.863022)
			(xy 178.984565 -46.863022) (xy 178.930581 -46.85526) (xy 178.878251 -46.839895) (xy 178.828641 -46.817238)
			(xy 178.78276 -46.787752) (xy 178.741543 -46.752037) (xy 178.705828 -46.71082) (xy 178.676342 -46.664939)
			(xy 178.653685 -46.615329) (xy 178.63832 -46.562999) (xy 178.630558 -46.509015) (xy 178.630072 -46.481746)
			(xy 97.329238 -46.481746) (xy 97.348615 -46.588073) (xy 97.368459 -46.741347) (xy 97.380387 -46.895438)
			(xy 97.384366 -47.04994) (xy 97.380387 -47.204442) (xy 97.368459 -47.358533) (xy 97.348615 -47.511807)
			(xy 97.320906 -47.663855) (xy 97.285407 -47.814276) (xy 97.242212 -47.96267) (xy 97.219453 -48.028098)
			(xy 181.659784 -48.028098) (xy 181.659784 -47.164498) (xy 181.66027 -47.137229) (xy 181.668032 -47.083245)
			(xy 181.683397 -47.030915) (xy 181.706054 -46.981305) (xy 181.73554 -46.935424) (xy 181.771255 -46.894207)
			(xy 181.812472 -46.858492) (xy 181.858353 -46.829006) (xy 181.907963 -46.806349) (xy 181.960293 -46.790984)
			(xy 182.014277 -46.783222) (xy 182.068815 -46.783222) (xy 182.122799 -46.790984) (xy 182.175129 -46.806349)
			(xy 182.224739 -46.829006) (xy 182.27062 -46.858492) (xy 182.311837 -46.894207) (xy 182.347552 -46.935424)
			(xy 182.377038 -46.981305) (xy 182.399695 -47.030915) (xy 182.41506 -47.083245) (xy 182.422822 -47.137229)
			(xy 182.423308 -47.164498) (xy 182.423308 -48.028098) (xy 182.422822 -48.055367) (xy 182.41506 -48.109351)
			(xy 182.399695 -48.161681) (xy 182.377038 -48.211291) (xy 182.347552 -48.257172) (xy 182.311837 -48.298389)
			(xy 182.27062 -48.334104) (xy 182.224739 -48.36359) (xy 182.175129 -48.386247) (xy 182.122799 -48.401612)
			(xy 182.068815 -48.409374) (xy 182.014277 -48.409374) (xy 181.960293 -48.401612) (xy 181.907963 -48.386247)
			(xy 181.858353 -48.36359) (xy 181.812472 -48.334104) (xy 181.771255 -48.298389) (xy 181.73554 -48.257172)
			(xy 181.706054 -48.211291) (xy 181.683397 -48.161681) (xy 181.668032 -48.109351) (xy 181.66027 -48.055367)
			(xy 181.659784 -48.028098) (xy 97.219453 -48.028098) (xy 97.191435 -48.108643) (xy 97.133211 -48.251809)
			(xy 97.067693 -48.391788) (xy 96.995057 -48.528208) (xy 96.915495 -48.660709) (xy 96.829216 -48.788937)
			(xy 96.736452 -48.912555) (xy 96.637446 -49.031233) (xy 96.532463 -49.144657) (xy 96.421779 -49.252526)
			(xy 96.30569 -49.354554) (xy 96.184502 -49.450471) (xy 96.140518 -49.48174) (xy 178.630072 -49.48174)
			(xy 178.630072 -48.61814) (xy 178.630558 -48.590871) (xy 178.63832 -48.536887) (xy 178.653685 -48.484557)
			(xy 178.676342 -48.434947) (xy 178.705828 -48.389066) (xy 178.741543 -48.347849) (xy 178.78276 -48.312134)
			(xy 178.828641 -48.282648) (xy 178.878251 -48.259991) (xy 178.930581 -48.244626) (xy 178.984565 -48.236864)
			(xy 179.039103 -48.236864) (xy 179.093087 -48.244626) (xy 179.145417 -48.259991) (xy 179.195027 -48.282648)
			(xy 179.240908 -48.312134) (xy 179.282125 -48.347849) (xy 179.31784 -48.389066) (xy 179.347326 -48.434947)
			(xy 179.369983 -48.484557) (xy 179.385348 -48.536887) (xy 179.39311 -48.590871) (xy 179.393596 -48.61814)
			(xy 179.393596 -49.48174) (xy 179.39311 -49.509009) (xy 179.385348 -49.562993) (xy 179.369983 -49.615323)
			(xy 179.347326 -49.664933) (xy 179.31784 -49.710814) (xy 179.282125 -49.752031) (xy 179.240908 -49.787746)
			(xy 179.195027 -49.817232) (xy 179.145417 -49.839889) (xy 179.093087 -49.855254) (xy 179.039103 -49.863016)
			(xy 178.984565 -49.863016) (xy 178.930581 -49.855254) (xy 178.878251 -49.839889) (xy 178.828641 -49.817232)
			(xy 178.78276 -49.787746) (xy 178.741543 -49.752031) (xy 178.705828 -49.710814) (xy 178.676342 -49.664933)
			(xy 178.653685 -49.615323) (xy 178.63832 -49.562993) (xy 178.630558 -49.509009) (xy 178.630072 -49.48174)
			(xy 96.140518 -49.48174) (xy 96.058537 -49.540022) (xy 95.928129 -49.62297) (xy 95.793624 -49.699095)
			(xy 95.655379 -49.768194) (xy 95.513759 -49.830085) (xy 95.369142 -49.884604) (xy 95.221909 -49.931606)
			(xy 95.072452 -49.970966) (xy 94.921168 -50.00258) (xy 94.768456 -50.026364) (xy 94.614722 -50.042255)
			(xy 94.460374 -50.050211) (xy 94.383098 -50.0507) (xy 92.782898 -50.0507) (xy 92.705622 -50.050194)
			(xy 92.551275 -50.042238) (xy 92.397543 -50.026347) (xy 92.244832 -50.002563) (xy 92.093548 -49.970949)
			(xy 91.944092 -49.931589) (xy 91.796861 -49.884587) (xy 91.652244 -49.830069) (xy 91.510626 -49.768178)
			(xy 91.372381 -49.699079) (xy 91.237877 -49.622954) (xy 91.10747 -49.540007) (xy 90.981506 -49.450456)
			(xy 90.860319 -49.35454) (xy 90.74423 -49.252512) (xy 90.633548 -49.144644) (xy 90.528565 -49.031221)
			(xy 90.42956 -48.912543) (xy 90.336796 -48.788927) (xy 90.250519 -48.660699) (xy 90.170957 -48.528199)
			(xy 90.098321 -48.391779) (xy 90.032804 -48.251802) (xy 89.97458 -48.108637) (xy 89.923803 -47.962664)
			(xy 89.880608 -47.814271) (xy 89.84511 -47.663852) (xy 89.817402 -47.511804) (xy 89.797557 -47.358531)
			(xy 89.78563 -47.204441) (xy 89.78165 -47.04994) (xy 67.583802 -47.04994) (xy 67.579823 -47.209492)
			(xy 67.567896 -47.368647) (xy 67.54805 -47.527009) (xy 67.520336 -47.684186) (xy 67.484821 -47.839786)
			(xy 67.441595 -47.993422) (xy 67.390764 -48.144712) (xy 67.332455 -48.293281) (xy 67.266813 -48.438758)
			(xy 67.194001 -48.580783) (xy 67.114201 -48.719002) (xy 67.02761 -48.853071) (xy 66.934444 -48.982657)
			(xy 66.834934 -49.107438) (xy 66.729328 -49.227105) (xy 66.617889 -49.341358) (xy 66.500893 -49.449914)
			(xy 66.378631 -49.552504) (xy 66.251408 -49.648872) (xy 66.119539 -49.738779) (xy 65.983353 -49.822001)
			(xy 65.843188 -49.898331) (xy 65.699392 -49.967579) (xy 65.552323 -50.029574) (xy 65.402347 -50.084161)
			(xy 65.249837 -50.131205) (xy 65.095171 -50.170587) (xy 64.938734 -50.202212) (xy 64.780916 -50.226)
			(xy 64.622107 -50.241891) (xy 64.462705 -50.249847) (xy 64.382904 -50.250344) (xy 62.782958 -50.250344)
			(xy 62.703158 -50.249839) (xy 62.543755 -50.241883) (xy 62.384947 -50.225992) (xy 62.227129 -50.202204)
			(xy 62.070693 -50.17058) (xy 61.916027 -50.131197) (xy 61.763517 -50.084154) (xy 61.613541 -50.029567)
			(xy 61.466472 -49.967573) (xy 61.322677 -49.898324) (xy 61.182512 -49.821994) (xy 61.046326 -49.738773)
			(xy 60.914458 -49.648866) (xy 60.787235 -49.552499) (xy 60.664973 -49.449909) (xy 60.547978 -49.341353)
			(xy 60.436538 -49.2271) (xy 60.330933 -49.107434) (xy 60.231423 -48.982653) (xy 60.138257 -48.853067)
			(xy 60.051666 -48.718998) (xy 59.971866 -48.580779) (xy 59.899054 -48.438755) (xy 59.833413 -48.293278)
			(xy 59.775104 -48.14471) (xy 59.724273 -47.99342) (xy 59.681047 -47.839784) (xy 59.645532 -47.684184)
			(xy 59.617818 -47.527008) (xy 59.597972 -47.368646) (xy 59.586045 -47.209491) (xy 59.582066 -47.04994)
			(xy 57.658 -47.04994) (xy 57.658 -50.949098) (xy 181.659784 -50.949098) (xy 181.659784 -50.085498)
			(xy 181.66027 -50.058229) (xy 181.668032 -50.004245) (xy 181.683397 -49.951915) (xy 181.706054 -49.902305)
			(xy 181.73554 -49.856424) (xy 181.771255 -49.815207) (xy 181.812472 -49.779492) (xy 181.858353 -49.750006)
			(xy 181.907963 -49.727349) (xy 181.960293 -49.711984) (xy 182.014277 -49.704222) (xy 182.068815 -49.704222)
			(xy 182.122799 -49.711984) (xy 182.175129 -49.727349) (xy 182.224739 -49.750006) (xy 182.27062 -49.779492)
			(xy 182.311837 -49.815207) (xy 182.347552 -49.856424) (xy 182.377038 -49.902305) (xy 182.399695 -49.951915)
			(xy 182.41506 -50.004245) (xy 182.422822 -50.058229) (xy 182.423308 -50.085498) (xy 182.423308 -50.949098)
			(xy 182.422822 -50.976367) (xy 182.41506 -51.030351) (xy 182.399695 -51.082681) (xy 182.377038 -51.132291)
			(xy 182.347552 -51.178172) (xy 182.311837 -51.219389) (xy 182.27062 -51.255104) (xy 182.224739 -51.28459)
			(xy 182.175129 -51.307247) (xy 182.122799 -51.322612) (xy 182.068815 -51.330374) (xy 182.014277 -51.330374)
			(xy 181.960293 -51.322612) (xy 181.907963 -51.307247) (xy 181.858353 -51.28459) (xy 181.812472 -51.255104)
			(xy 181.771255 -51.219389) (xy 181.73554 -51.178172) (xy 181.706054 -51.132291) (xy 181.683397 -51.082681)
			(xy 181.668032 -51.030351) (xy 181.66027 -50.976367) (xy 181.659784 -50.949098) (xy 57.658 -50.949098)
			(xy 57.658 -52.481734) (xy 178.630072 -52.481734) (xy 178.630072 -51.618134) (xy 178.630558 -51.590865)
			(xy 178.63832 -51.536881) (xy 178.653685 -51.484551) (xy 178.676342 -51.434941) (xy 178.705828 -51.38906)
			(xy 178.741543 -51.347843) (xy 178.78276 -51.312128) (xy 178.828641 -51.282642) (xy 178.878251 -51.259985)
			(xy 178.930581 -51.24462) (xy 178.984565 -51.236858) (xy 179.039103 -51.236858) (xy 179.093087 -51.24462)
			(xy 179.145417 -51.259985) (xy 179.195027 -51.282642) (xy 179.240908 -51.312128) (xy 179.282125 -51.347843)
			(xy 179.31784 -51.38906) (xy 179.347326 -51.434941) (xy 179.369983 -51.484551) (xy 179.385348 -51.536881)
			(xy 179.39311 -51.590865) (xy 179.393596 -51.618134) (xy 179.393596 -52.481734) (xy 179.39311 -52.509003)
			(xy 179.385348 -52.562987) (xy 179.369983 -52.615317) (xy 179.347326 -52.664927) (xy 179.31784 -52.710808)
			(xy 179.282125 -52.752025) (xy 179.240908 -52.78774) (xy 179.195027 -52.817226) (xy 179.145417 -52.839883)
			(xy 179.093087 -52.855248) (xy 179.039103 -52.86301) (xy 178.984565 -52.86301) (xy 178.930581 -52.855248)
			(xy 178.878251 -52.839883) (xy 178.828641 -52.817226) (xy 178.78276 -52.78774) (xy 178.741543 -52.752025)
			(xy 178.705828 -52.710808) (xy 178.676342 -52.664927) (xy 178.653685 -52.615317) (xy 178.63832 -52.562987)
			(xy 178.630558 -52.509003) (xy 178.630072 -52.481734) (xy 57.658 -52.481734) (xy 57.658 -53.954934)
			(xy 181.659784 -53.954934) (xy 181.659784 -53.091334) (xy 181.66027 -53.064065) (xy 181.668032 -53.010081)
			(xy 181.683397 -52.957751) (xy 181.706054 -52.908141) (xy 181.73554 -52.86226) (xy 181.771255 -52.821043)
			(xy 181.812472 -52.785328) (xy 181.858353 -52.755842) (xy 181.907963 -52.733185) (xy 181.960293 -52.71782)
			(xy 182.014277 -52.710058) (xy 182.068815 -52.710058) (xy 182.122799 -52.71782) (xy 182.175129 -52.733185)
			(xy 182.224739 -52.755842) (xy 182.27062 -52.785328) (xy 182.311837 -52.821043) (xy 182.347552 -52.86226)
			(xy 182.377038 -52.908141) (xy 182.399695 -52.957751) (xy 182.41506 -53.010081) (xy 182.422822 -53.064065)
			(xy 182.423308 -53.091334) (xy 182.423308 -53.954934) (xy 182.422822 -53.982203) (xy 182.41506 -54.036187)
			(xy 182.399695 -54.088517) (xy 182.377038 -54.138127) (xy 182.347552 -54.184008) (xy 182.311837 -54.225225)
			(xy 182.27062 -54.26094) (xy 182.224739 -54.290426) (xy 182.175129 -54.313083) (xy 182.122799 -54.328448)
			(xy 182.068815 -54.33621) (xy 182.014277 -54.33621) (xy 181.960293 -54.328448) (xy 181.907963 -54.313083)
			(xy 181.858353 -54.290426) (xy 181.812472 -54.26094) (xy 181.771255 -54.225225) (xy 181.73554 -54.184008)
			(xy 181.706054 -54.138127) (xy 181.683397 -54.088517) (xy 181.668032 -54.036187) (xy 181.66027 -53.982203)
			(xy 181.659784 -53.954934) (xy 57.658 -53.954934) (xy 57.658 -55.481728) (xy 178.630072 -55.481728)
			(xy 178.630072 -54.618128) (xy 178.630558 -54.590859) (xy 178.63832 -54.536875) (xy 178.653685 -54.484545)
			(xy 178.676342 -54.434935) (xy 178.705828 -54.389054) (xy 178.741543 -54.347837) (xy 178.78276 -54.312122)
			(xy 178.828641 -54.282636) (xy 178.878251 -54.259979) (xy 178.930581 -54.244614) (xy 178.984565 -54.236852)
			(xy 179.039103 -54.236852) (xy 179.093087 -54.244614) (xy 179.145417 -54.259979) (xy 179.195027 -54.282636)
			(xy 179.240908 -54.312122) (xy 179.282125 -54.347837) (xy 179.31784 -54.389054) (xy 179.347326 -54.434935)
			(xy 179.369983 -54.484545) (xy 179.385348 -54.536875) (xy 179.39311 -54.590859) (xy 179.393596 -54.618128)
			(xy 179.393596 -55.481728) (xy 179.39311 -55.508997) (xy 179.385348 -55.562981) (xy 179.369983 -55.615311)
			(xy 179.347326 -55.664921) (xy 179.31784 -55.710802) (xy 179.282125 -55.752019) (xy 179.240908 -55.787734)
			(xy 179.195027 -55.81722) (xy 179.145417 -55.839877) (xy 179.093087 -55.855242) (xy 179.039103 -55.863004)
			(xy 178.984565 -55.863004) (xy 178.930581 -55.855242) (xy 178.878251 -55.839877) (xy 178.828641 -55.81722)
			(xy 178.78276 -55.787734) (xy 178.741543 -55.752019) (xy 178.705828 -55.710802) (xy 178.676342 -55.664921)
			(xy 178.653685 -55.615311) (xy 178.63832 -55.562981) (xy 178.630558 -55.508997) (xy 178.630072 -55.481728)
			(xy 57.658 -55.481728) (xy 57.658 -57.094424) (xy 170.842423 -57.094424) (xy 170.842423 -57.005424)
			(xy 170.850401 -56.916783) (xy 170.866293 -56.829214) (xy 170.88997 -56.743422) (xy 170.921242 -56.660098)
			(xy 170.959857 -56.579912) (xy 171.005505 -56.50351) (xy 171.057817 -56.431508) (xy 171.116374 -56.364486)
			(xy 171.180702 -56.302981) (xy 171.250284 -56.247491) (xy 171.324561 -56.198462) (xy 171.402933 -56.156288)
			(xy 171.484771 -56.121309) (xy 171.569414 -56.093806) (xy 171.656182 -56.074002) (xy 171.744376 -56.062055)
			(xy 171.833286 -56.058063) (xy 171.922196 -56.062055) (xy 172.01039 -56.074002) (xy 172.097158 -56.093806)
			(xy 172.181801 -56.121309) (xy 172.263639 -56.156288) (xy 172.342011 -56.198462) (xy 172.416288 -56.247491)
			(xy 172.48587 -56.302981) (xy 172.550198 -56.364486) (xy 172.608755 -56.431508) (xy 172.661067 -56.50351)
			(xy 172.706715 -56.579912) (xy 172.74533 -56.660098) (xy 172.776602 -56.743422) (xy 172.800279 -56.829214)
			(xy 172.816171 -56.916783) (xy 172.824149 -57.005424) (xy 172.824648 -57.049924) (xy 172.824149 -57.094424)
			(xy 172.816171 -57.183065) (xy 172.800279 -57.270634) (xy 172.776602 -57.356426) (xy 172.74533 -57.43975)
			(xy 172.706715 -57.519936) (xy 172.661067 -57.596338) (xy 172.608755 -57.66834) (xy 172.550198 -57.735362)
			(xy 172.48587 -57.796867) (xy 172.416288 -57.852357) (xy 172.342011 -57.901386) (xy 172.263639 -57.94356)
			(xy 172.181801 -57.978539) (xy 172.097158 -58.006042) (xy 172.01039 -58.025846) (xy 171.922196 -58.037793)
			(xy 171.833286 -58.041786) (xy 171.744376 -58.037793) (xy 171.656182 -58.025846) (xy 171.569414 -58.006042)
			(xy 171.484771 -57.978539) (xy 171.402933 -57.94356) (xy 171.324561 -57.901386) (xy 171.250284 -57.852357)
			(xy 171.180702 -57.796867) (xy 171.116374 -57.735362) (xy 171.057817 -57.66834) (xy 171.005505 -57.596338)
			(xy 170.959857 -57.519936) (xy 170.921242 -57.43975) (xy 170.88997 -57.356426) (xy 170.866293 -57.270634)
			(xy 170.850401 -57.183065) (xy 170.842423 -57.094424) (xy 57.658 -57.094424) (xy 57.658 -60.375038)
			(xy 233.333551 -60.375038) (xy 233.337555 -60.287153) (xy 233.349535 -60.199996) (xy 233.36939 -60.114289)
			(xy 233.396957 -60.030744) (xy 233.432007 -59.950051) (xy 233.474249 -59.872879) (xy 233.523334 -59.799869)
			(xy 233.578855 -59.731625) (xy 233.640352 -59.668712) (xy 233.707314 -59.611652) (xy 233.779188 -59.560918)
			(xy 233.855378 -59.51693) (xy 233.935252 -59.480052) (xy 234.018149 -59.450591) (xy 234.103381 -59.428789)
			(xy 234.190243 -59.414829) (xy 234.278014 -59.408825) (xy 234.365968 -59.410828) (xy 234.453375 -59.42082)
			(xy 234.539511 -59.43872) (xy 234.623663 -59.464378) (xy 234.705133 -59.497582) (xy 234.783246 -59.538056)
			(xy 234.857354 -59.585467) (xy 234.926845 -59.63942) (xy 234.991141 -59.699468) (xy 235.04971 -59.765115)
			(xy 235.102067 -59.835815) (xy 235.147779 -59.910984) (xy 235.186465 -59.989998) (xy 235.217806 -60.072203)
			(xy 235.241541 -60.156917) (xy 235.257475 -60.243438) (xy 235.265475 -60.33105) (xy 235.265976 -60.375038)
			(xy 235.265475 -60.419026) (xy 235.257475 -60.506638) (xy 235.241541 -60.593159) (xy 235.217806 -60.677873)
			(xy 235.186465 -60.760078) (xy 235.147779 -60.839092) (xy 235.102067 -60.914261) (xy 235.04971 -60.984961)
			(xy 234.991141 -61.050608) (xy 234.926845 -61.110656) (xy 234.857354 -61.164609) (xy 234.783246 -61.21202)
			(xy 234.705133 -61.252494) (xy 234.623663 -61.285698) (xy 234.539511 -61.311356) (xy 234.453375 -61.329256)
			(xy 234.365968 -61.339248) (xy 234.278014 -61.341251) (xy 234.190243 -61.335247) (xy 234.103381 -61.321287)
			(xy 234.018149 -61.299485) (xy 233.935252 -61.270024) (xy 233.855378 -61.233146) (xy 233.779188 -61.189158)
			(xy 233.707314 -61.138424) (xy 233.640352 -61.081364) (xy 233.578855 -61.018451) (xy 233.523334 -60.950207)
			(xy 233.474249 -60.877197) (xy 233.432007 -60.800025) (xy 233.396957 -60.719332) (xy 233.36939 -60.635787)
			(xy 233.349535 -60.55008) (xy 233.337555 -60.462923) (xy 233.333551 -60.375038) (xy 57.658 -60.375038)
			(xy 57.658 -74.767948) (xy 173.354492 -74.767948) (xy 173.354492 -66.06794) (xy 173.354997 -65.962416)
			(xy 173.363081 -65.751522) (xy 173.379237 -65.541093) (xy 173.40344 -65.331436) (xy 173.435657 -65.122861)
			(xy 173.475839 -64.915673) (xy 173.523927 -64.710176) (xy 173.579851 -64.506672) (xy 173.643528 -64.305459)
			(xy 173.714866 -64.106832) (xy 173.79376 -63.911084) (xy 173.880093 -63.718502) (xy 173.97374 -63.529367)
			(xy 174.074562 -63.343958) (xy 174.182412 -63.162547) (xy 174.297131 -62.9854) (xy 174.418551 -62.812778)
			(xy 174.546494 -62.644932) (xy 174.680772 -62.48211) (xy 174.821188 -62.324551) (xy 174.967536 -62.172486)
			(xy 175.119601 -62.026138) (xy 175.27716 -61.885722) (xy 175.439982 -61.751444) (xy 175.607828 -61.623501)
			(xy 175.78045 -61.502081) (xy 175.957597 -61.387362) (xy 176.139008 -61.279512) (xy 176.324417 -61.17869)
			(xy 176.513552 -61.085043) (xy 176.706134 -60.99871) (xy 176.901882 -60.919816) (xy 177.100509 -60.848478)
			(xy 177.301722 -60.784801) (xy 177.505226 -60.728877) (xy 177.710723 -60.680789) (xy 177.917911 -60.640607)
			(xy 178.126486 -60.60839) (xy 178.336143 -60.584187) (xy 178.546572 -60.568031) (xy 178.757466 -60.559947)
			(xy 178.968514 -60.559947) (xy 179.179408 -60.568031) (xy 179.389837 -60.584187) (xy 179.599494 -60.60839)
			(xy 179.808069 -60.640607) (xy 180.015257 -60.680789) (xy 180.220754 -60.728877) (xy 180.424258 -60.784801)
			(xy 180.625471 -60.848478) (xy 180.824098 -60.919816) (xy 181.019846 -60.99871) (xy 181.212428 -61.085043)
			(xy 181.401563 -61.17869) (xy 181.586972 -61.279512) (xy 181.768383 -61.387362) (xy 181.94553 -61.502081)
			(xy 182.118152 -61.623501) (xy 182.285998 -61.751444) (xy 182.44882 -61.885722) (xy 182.606379 -62.026138)
			(xy 182.758444 -62.172486) (xy 182.904792 -62.324551) (xy 183.045208 -62.48211) (xy 183.179486 -62.644932)
			(xy 183.307429 -62.812778) (xy 183.428849 -62.9854) (xy 183.543568 -63.162547) (xy 183.651418 -63.343958)
			(xy 183.75224 -63.529367) (xy 183.845887 -63.718502) (xy 183.93222 -63.911084) (xy 184.011114 -64.106832)
			(xy 184.082452 -64.305459) (xy 184.146129 -64.506672) (xy 184.202053 -64.710176) (xy 184.250141 -64.915673)
			(xy 184.290323 -65.122861) (xy 184.32254 -65.331436) (xy 184.346743 -65.541093) (xy 184.362899 -65.751522)
			(xy 184.370983 -65.962416) (xy 184.371488 -66.06794) (xy 184.371488 -74.760836) (xy 287.494472 -74.760836)
			(xy 287.494472 -66.060828) (xy 287.494977 -65.955304) (xy 287.503061 -65.74441) (xy 287.519217 -65.533981)
			(xy 287.54342 -65.324324) (xy 287.575637 -65.115749) (xy 287.615819 -64.908561) (xy 287.663907 -64.703064)
			(xy 287.719831 -64.49956) (xy 287.783508 -64.298347) (xy 287.854846 -64.09972) (xy 287.93374 -63.903972)
			(xy 288.020073 -63.71139) (xy 288.11372 -63.522255) (xy 288.214542 -63.336846) (xy 288.322392 -63.155435)
			(xy 288.437111 -62.978288) (xy 288.558531 -62.805666) (xy 288.686474 -62.63782) (xy 288.820752 -62.474998)
			(xy 288.961168 -62.317439) (xy 289.107516 -62.165374) (xy 289.259581 -62.019026) (xy 289.41714 -61.87861)
			(xy 289.579962 -61.744332) (xy 289.747808 -61.616389) (xy 289.92043 -61.494969) (xy 290.097577 -61.38025)
			(xy 290.278988 -61.2724) (xy 290.464397 -61.171578) (xy 290.653532 -61.077931) (xy 290.846114 -60.991598)
			(xy 291.041862 -60.912704) (xy 291.240489 -60.841366) (xy 291.441702 -60.777689) (xy 291.645206 -60.721765)
			(xy 291.850703 -60.673677) (xy 292.057891 -60.633495) (xy 292.266466 -60.601278) (xy 292.476123 -60.577075)
			(xy 292.686552 -60.560919) (xy 292.897446 -60.552835) (xy 293.108494 -60.552835) (xy 293.319388 -60.560919)
			(xy 293.529817 -60.577075) (xy 293.739474 -60.601278) (xy 293.948049 -60.633495) (xy 294.155237 -60.673677)
			(xy 294.360734 -60.721765) (xy 294.564238 -60.777689) (xy 294.765451 -60.841366) (xy 294.964078 -60.912704)
			(xy 295.159826 -60.991598) (xy 295.352408 -61.077931) (xy 295.541543 -61.171578) (xy 295.726952 -61.2724)
			(xy 295.908363 -61.38025) (xy 296.08551 -61.494969) (xy 296.258132 -61.616389) (xy 296.425978 -61.744332)
			(xy 296.5888 -61.87861) (xy 296.746359 -62.019026) (xy 296.898424 -62.165374) (xy 297.044772 -62.317439)
			(xy 297.185188 -62.474998) (xy 297.319466 -62.63782) (xy 297.447409 -62.805666) (xy 297.568829 -62.978288)
			(xy 297.683548 -63.155435) (xy 297.791398 -63.336846) (xy 297.89222 -63.522255) (xy 297.985867 -63.71139)
			(xy 298.0722 -63.903972) (xy 298.151094 -64.09972) (xy 298.222432 -64.298347) (xy 298.286109 -64.49956)
			(xy 298.342033 -64.703064) (xy 298.390121 -64.908561) (xy 298.430303 -65.115749) (xy 298.46252 -65.324324)
			(xy 298.486723 -65.533981) (xy 298.502879 -65.74441) (xy 298.510963 -65.955304) (xy 298.511468 -66.060828)
			(xy 298.511468 -74.760836) (xy 298.511434 -74.767948) (xy 421.29456 -74.767948) (xy 421.29456 -66.06794)
			(xy 421.295065 -65.962416) (xy 421.303149 -65.751522) (xy 421.319305 -65.541093) (xy 421.343508 -65.331436)
			(xy 421.375725 -65.122861) (xy 421.415907 -64.915673) (xy 421.463995 -64.710176) (xy 421.519919 -64.506672)
			(xy 421.583596 -64.305459) (xy 421.654934 -64.106832) (xy 421.733828 -63.911084) (xy 421.820161 -63.718502)
			(xy 421.913808 -63.529367) (xy 422.01463 -63.343958) (xy 422.12248 -63.162547) (xy 422.237199 -62.9854)
			(xy 422.358619 -62.812778) (xy 422.486562 -62.644932) (xy 422.62084 -62.48211) (xy 422.761256 -62.324551)
			(xy 422.907604 -62.172486) (xy 423.059669 -62.026138) (xy 423.217228 -61.885722) (xy 423.38005 -61.751444)
			(xy 423.547896 -61.623501) (xy 423.720518 -61.502081) (xy 423.897665 -61.387362) (xy 424.079076 -61.279512)
			(xy 424.264485 -61.17869) (xy 424.45362 -61.085043) (xy 424.646202 -60.99871) (xy 424.84195 -60.919816)
			(xy 425.040577 -60.848478) (xy 425.24179 -60.784801) (xy 425.445294 -60.728877) (xy 425.650791 -60.680789)
			(xy 425.857979 -60.640607) (xy 426.066554 -60.60839) (xy 426.276211 -60.584187) (xy 426.48664 -60.568031)
			(xy 426.697534 -60.559947) (xy 426.908582 -60.559947) (xy 427.119476 -60.568031) (xy 427.329905 -60.584187)
			(xy 427.539562 -60.60839) (xy 427.748137 -60.640607) (xy 427.955325 -60.680789) (xy 428.160822 -60.728877)
			(xy 428.364326 -60.784801) (xy 428.565539 -60.848478) (xy 428.764166 -60.919816) (xy 428.959914 -60.99871)
			(xy 429.152496 -61.085043) (xy 429.341631 -61.17869) (xy 429.52704 -61.279512) (xy 429.708451 -61.387362)
			(xy 429.885598 -61.502081) (xy 430.05822 -61.623501) (xy 430.226066 -61.751444) (xy 430.388888 -61.885722)
			(xy 430.546447 -62.026138) (xy 430.698512 -62.172486) (xy 430.84486 -62.324551) (xy 430.985276 -62.48211)
			(xy 431.119554 -62.644932) (xy 431.247497 -62.812778) (xy 431.368917 -62.9854) (xy 431.483636 -63.162547)
			(xy 431.591486 -63.343958) (xy 431.692308 -63.529367) (xy 431.785955 -63.718502) (xy 431.872288 -63.911084)
			(xy 431.951182 -64.106832) (xy 432.02252 -64.305459) (xy 432.086197 -64.506672) (xy 432.142121 -64.710176)
			(xy 432.190209 -64.915673) (xy 432.230391 -65.122861) (xy 432.262608 -65.331436) (xy 432.286811 -65.541093)
			(xy 432.302967 -65.751522) (xy 432.311051 -65.962416) (xy 432.311556 -66.06794) (xy 432.311556 -74.767948)
			(xy 432.311051 -74.873472) (xy 432.302967 -75.084366) (xy 432.286811 -75.294795) (xy 432.262608 -75.504452)
			(xy 432.230391 -75.713027) (xy 432.190209 -75.920215) (xy 432.142121 -76.125712) (xy 432.086197 -76.329216)
			(xy 432.02252 -76.530429) (xy 431.951182 -76.729056) (xy 431.872288 -76.924804) (xy 431.785955 -77.117386)
			(xy 431.692308 -77.306521) (xy 431.591486 -77.49193) (xy 431.483636 -77.673341) (xy 431.368917 -77.850488)
			(xy 431.247497 -78.02311) (xy 431.119554 -78.190956) (xy 430.985276 -78.353778) (xy 430.84486 -78.511337)
			(xy 430.698512 -78.663402) (xy 430.546447 -78.80975) (xy 430.388888 -78.950166) (xy 430.226066 -79.084444)
			(xy 430.05822 -79.212387) (xy 429.885598 -79.333807) (xy 429.708451 -79.448526) (xy 429.52704 -79.556376)
			(xy 429.341631 -79.657198) (xy 429.152496 -79.750845) (xy 428.959914 -79.837178) (xy 428.764166 -79.916072)
			(xy 428.565539 -79.98741) (xy 428.364326 -80.051087) (xy 428.160822 -80.107011) (xy 427.955325 -80.155099)
			(xy 427.748137 -80.195281) (xy 427.539562 -80.227498) (xy 427.329905 -80.251701) (xy 427.119476 -80.267857)
			(xy 426.908582 -80.275941) (xy 426.697534 -80.275941) (xy 426.48664 -80.267857) (xy 426.276211 -80.251701)
			(xy 426.066554 -80.227498) (xy 425.857979 -80.195281) (xy 425.650791 -80.155099) (xy 425.445294 -80.107011)
			(xy 425.24179 -80.051087) (xy 425.040577 -79.98741) (xy 424.84195 -79.916072) (xy 424.646202 -79.837178)
			(xy 424.45362 -79.750845) (xy 424.264485 -79.657198) (xy 424.079076 -79.556376) (xy 423.897665 -79.448526)
			(xy 423.720518 -79.333807) (xy 423.547896 -79.212387) (xy 423.38005 -79.084444) (xy 423.217228 -78.950166)
			(xy 423.059669 -78.80975) (xy 422.907604 -78.663402) (xy 422.761256 -78.511337) (xy 422.62084 -78.353778)
			(xy 422.486562 -78.190956) (xy 422.358619 -78.02311) (xy 422.237199 -77.850488) (xy 422.12248 -77.673341)
			(xy 422.01463 -77.49193) (xy 421.913808 -77.306521) (xy 421.820161 -77.117386) (xy 421.733828 -76.924804)
			(xy 421.654934 -76.729056) (xy 421.583596 -76.530429) (xy 421.519919 -76.329216) (xy 421.463995 -76.125712)
			(xy 421.415907 -75.920215) (xy 421.375725 -75.713027) (xy 421.343508 -75.504452) (xy 421.319305 -75.294795)
			(xy 421.303149 -75.084366) (xy 421.295065 -74.873472) (xy 421.29456 -74.767948) (xy 298.511434 -74.767948)
			(xy 298.510963 -74.86636) (xy 298.502879 -75.077254) (xy 298.486723 -75.287683) (xy 298.46252 -75.49734)
			(xy 298.430303 -75.705915) (xy 298.390121 -75.913103) (xy 298.342033 -76.1186) (xy 298.286109 -76.322104)
			(xy 298.222432 -76.523317) (xy 298.151094 -76.721944) (xy 298.0722 -76.917692) (xy 297.985867 -77.110274)
			(xy 297.89222 -77.299409) (xy 297.791398 -77.484818) (xy 297.683548 -77.666229) (xy 297.568829 -77.843376)
			(xy 297.447409 -78.015998) (xy 297.319466 -78.183844) (xy 297.185188 -78.346666) (xy 297.044772 -78.504225)
			(xy 296.898424 -78.65629) (xy 296.746359 -78.802638) (xy 296.5888 -78.943054) (xy 296.425978 -79.077332)
			(xy 296.258132 -79.205275) (xy 296.08551 -79.326695) (xy 295.908363 -79.441414) (xy 295.726952 -79.549264)
			(xy 295.541543 -79.650086) (xy 295.352408 -79.743733) (xy 295.159826 -79.830066) (xy 294.964078 -79.90896)
			(xy 294.765451 -79.980298) (xy 294.564238 -80.043975) (xy 294.360734 -80.099899) (xy 294.155237 -80.147987)
			(xy 293.948049 -80.188169) (xy 293.739474 -80.220386) (xy 293.529817 -80.244589) (xy 293.319388 -80.260745)
			(xy 293.108494 -80.268829) (xy 292.897446 -80.268829) (xy 292.686552 -80.260745) (xy 292.476123 -80.244589)
			(xy 292.266466 -80.220386) (xy 292.057891 -80.188169) (xy 291.850703 -80.147987) (xy 291.645206 -80.099899)
			(xy 291.441702 -80.043975) (xy 291.240489 -79.980298) (xy 291.041862 -79.90896) (xy 290.846114 -79.830066)
			(xy 290.653532 -79.743733) (xy 290.464397 -79.650086) (xy 290.278988 -79.549264) (xy 290.097577 -79.441414)
			(xy 289.92043 -79.326695) (xy 289.747808 -79.205275) (xy 289.579962 -79.077332) (xy 289.41714 -78.943054)
			(xy 289.259581 -78.802638) (xy 289.107516 -78.65629) (xy 288.961168 -78.504225) (xy 288.820752 -78.346666)
			(xy 288.686474 -78.183844) (xy 288.558531 -78.015998) (xy 288.437111 -77.843376) (xy 288.322392 -77.666229)
			(xy 288.214542 -77.484818) (xy 288.11372 -77.299409) (xy 288.020073 -77.110274) (xy 287.93374 -76.917692)
			(xy 287.854846 -76.721944) (xy 287.783508 -76.523317) (xy 287.719831 -76.322104) (xy 287.663907 -76.1186)
			(xy 287.615819 -75.913103) (xy 287.575637 -75.705915) (xy 287.54342 -75.49734) (xy 287.519217 -75.287683)
			(xy 287.503061 -75.077254) (xy 287.494977 -74.86636) (xy 287.494472 -74.760836) (xy 184.371488 -74.760836)
			(xy 184.371488 -74.767948) (xy 184.370983 -74.873472) (xy 184.362899 -75.084366) (xy 184.346743 -75.294795)
			(xy 184.32254 -75.504452) (xy 184.290323 -75.713027) (xy 184.250141 -75.920215) (xy 184.202053 -76.125712)
			(xy 184.146129 -76.329216) (xy 184.082452 -76.530429) (xy 184.011114 -76.729056) (xy 183.93222 -76.924804)
			(xy 183.845887 -77.117386) (xy 183.75224 -77.306521) (xy 183.651418 -77.49193) (xy 183.543568 -77.673341)
			(xy 183.428849 -77.850488) (xy 183.307429 -78.02311) (xy 183.179486 -78.190956) (xy 183.045208 -78.353778)
			(xy 182.904792 -78.511337) (xy 182.758444 -78.663402) (xy 182.606379 -78.80975) (xy 182.44882 -78.950166)
			(xy 182.285998 -79.084444) (xy 182.118152 -79.212387) (xy 181.94553 -79.333807) (xy 181.768383 -79.448526)
			(xy 181.586972 -79.556376) (xy 181.401563 -79.657198) (xy 181.212428 -79.750845) (xy 181.019846 -79.837178)
			(xy 180.824098 -79.916072) (xy 180.625471 -79.98741) (xy 180.424258 -80.051087) (xy 180.220754 -80.107011)
			(xy 180.015257 -80.155099) (xy 179.808069 -80.195281) (xy 179.599494 -80.227498) (xy 179.389837 -80.251701)
			(xy 179.179408 -80.267857) (xy 178.968514 -80.275941) (xy 178.757466 -80.275941) (xy 178.546572 -80.267857)
			(xy 178.336143 -80.251701) (xy 178.126486 -80.227498) (xy 177.917911 -80.195281) (xy 177.710723 -80.155099)
			(xy 177.505226 -80.107011) (xy 177.301722 -80.051087) (xy 177.100509 -79.98741) (xy 176.901882 -79.916072)
			(xy 176.706134 -79.837178) (xy 176.513552 -79.750845) (xy 176.324417 -79.657198) (xy 176.139008 -79.556376)
			(xy 175.957597 -79.448526) (xy 175.78045 -79.333807) (xy 175.607828 -79.212387) (xy 175.439982 -79.084444)
			(xy 175.27716 -78.950166) (xy 175.119601 -78.80975) (xy 174.967536 -78.663402) (xy 174.821188 -78.511337)
			(xy 174.680772 -78.353778) (xy 174.546494 -78.190956) (xy 174.418551 -78.02311) (xy 174.297131 -77.850488)
			(xy 174.182412 -77.673341) (xy 174.074562 -77.49193) (xy 173.97374 -77.306521) (xy 173.880093 -77.117386)
			(xy 173.79376 -76.924804) (xy 173.714866 -76.729056) (xy 173.643528 -76.530429) (xy 173.579851 -76.329216)
			(xy 173.523927 -76.125712) (xy 173.475839 -75.920215) (xy 173.435657 -75.713027) (xy 173.40344 -75.504452)
			(xy 173.379237 -75.294795) (xy 173.363081 -75.084366) (xy 173.354997 -74.873472) (xy 173.354492 -74.767948)
			(xy 57.658 -74.767948) (xy 57.658 -81.70037) (xy 230.62845 -81.70037) (xy 230.632464 -81.494686)
			(xy 230.6445 -81.289316) (xy 230.664539 -81.084572) (xy 230.692552 -80.880765) (xy 230.728495 -80.678206)
			(xy 230.772314 -80.477204) (xy 230.823941 -80.278065) (xy 230.883299 -80.081092) (xy 230.950297 -79.886584)
			(xy 231.024833 -79.694839) (xy 231.106793 -79.506148) (xy 231.196053 -79.320798) (xy 231.292476 -79.139072)
			(xy 231.395917 -78.961246) (xy 231.506216 -78.787592) (xy 231.623207 -78.618373) (xy 231.746711 -78.453847)
			(xy 231.87654 -78.294266) (xy 232.012497 -78.139871) (xy 232.154374 -77.990899) (xy 232.301955 -77.847575)
			(xy 232.455016 -77.710119) (xy 232.613323 -77.578739) (xy 232.776636 -77.453636) (xy 232.944705 -77.334999)
			(xy 233.117275 -77.223011) (xy 233.294083 -77.11784) (xy 233.47486 -77.019649) (xy 233.65933 -76.928585)
			(xy 233.847212 -76.844788) (xy 234.038222 -76.768385) (xy 234.232066 -76.699492) (xy 234.428451 -76.638215)
			(xy 234.627077 -76.584647) (xy 234.827642 -76.53887) (xy 235.02984 -76.500952) (xy 235.233364 -76.470953)
			(xy 235.437903 -76.448916) (xy 235.643146 -76.434877) (xy 235.848781 -76.428857) (xy 236.054494 -76.430864)
			(xy 236.259972 -76.440896) (xy 236.464902 -76.458937) (xy 236.668972 -76.48496) (xy 236.871872 -76.518925)
			(xy 237.073292 -76.56078) (xy 237.272925 -76.610462) (xy 237.470468 -76.667896) (xy 237.66562 -76.732993)
			(xy 237.858084 -76.805654) (xy 238.047566 -76.88577) (xy 238.233777 -76.973217) (xy 238.416436 -77.067863)
			(xy 238.595262 -77.169563) (xy 238.769984 -77.278163) (xy 238.940337 -77.393498) (xy 239.106059 -77.515391)
			(xy 239.2669 -77.643657) (xy 239.422613 -77.7781) (xy 239.572963 -77.918517) (xy 239.71772 -78.064693)
			(xy 239.856663 -78.216405) (xy 239.989581 -78.373423) (xy 240.116272 -78.535508) (xy 240.236542 -78.702411)
			(xy 240.350209 -78.873881) (xy 240.457099 -79.049654) (xy 240.55705 -79.229464) (xy 240.649909 -79.413037)
			(xy 240.735536 -79.600093) (xy 240.813798 -79.790348) (xy 240.884579 -79.983511) (xy 240.947769 -80.179289)
			(xy 241.003272 -80.377383) (xy 241.051004 -80.577492) (xy 241.090893 -80.77931) (xy 241.122877 -80.982532)
			(xy 241.135929 -81.093507) (xy 398.275806 -81.093507) (xy 398.275806 -81.008785) (xy 398.283859 -80.924448)
			(xy 398.299893 -80.841258) (xy 398.323761 -80.759968) (xy 398.355249 -80.681316) (xy 398.394071 -80.606013)
			(xy 398.439874 -80.534741) (xy 398.492245 -80.468145) (xy 398.55071 -80.40683) (xy 398.614738 -80.351349)
			(xy 398.68375 -80.302206) (xy 398.75712 -80.259846) (xy 398.834185 -80.224651) (xy 398.914247 -80.196942)
			(xy 398.99658 -80.176968) (xy 399.080439 -80.164911) (xy 399.165064 -80.16088) (xy 399.249689 -80.164911)
			(xy 399.333548 -80.176968) (xy 399.415881 -80.196942) (xy 399.495943 -80.224651) (xy 399.573008 -80.259846)
			(xy 399.646378 -80.302206) (xy 399.71539 -80.351349) (xy 399.779418 -80.40683) (xy 399.837883 -80.468145)
			(xy 399.890254 -80.534741) (xy 399.936057 -80.606013) (xy 399.974879 -80.681316) (xy 400.006367 -80.759968)
			(xy 400.030235 -80.841258) (xy 400.046269 -80.924448) (xy 400.054322 -81.008785) (xy 400.054826 -81.051146)
			(xy 400.054322 -81.093507) (xy 400.046269 -81.177844) (xy 400.030235 -81.261034) (xy 400.006367 -81.342324)
			(xy 399.974879 -81.420976) (xy 399.936057 -81.496279) (xy 399.890254 -81.567551) (xy 399.837883 -81.634147)
			(xy 399.779418 -81.695462) (xy 399.71539 -81.750943) (xy 399.646378 -81.800086) (xy 399.573008 -81.842446)
			(xy 399.495943 -81.877641) (xy 399.415881 -81.90535) (xy 399.333548 -81.925324) (xy 399.249689 -81.937381)
			(xy 399.165064 -81.941413) (xy 399.080439 -81.937381) (xy 398.99658 -81.925324) (xy 398.914247 -81.90535)
			(xy 398.834185 -81.877641) (xy 398.75712 -81.842446) (xy 398.68375 -81.800086) (xy 398.614738 -81.750943)
			(xy 398.55071 -81.695462) (xy 398.492245 -81.634147) (xy 398.439874 -81.567551) (xy 398.394071 -81.496279)
			(xy 398.355249 -81.420976) (xy 398.323761 -81.342324) (xy 398.299893 -81.261034) (xy 398.283859 -81.177844)
			(xy 398.275806 -81.093507) (xy 241.135929 -81.093507) (xy 241.146907 -81.186846) (xy 241.162948 -81.391942)
			(xy 241.170974 -81.597509) (xy 241.171476 -81.70037) (xy 241.170974 -81.803231) (xy 241.162948 -82.008798)
			(xy 241.146907 -82.213894) (xy 241.122877 -82.418208) (xy 241.090893 -82.62143) (xy 241.051004 -82.823248)
			(xy 241.003272 -83.023357) (xy 240.947769 -83.221451) (xy 240.884579 -83.417229) (xy 240.813798 -83.610392)
			(xy 240.735536 -83.800647) (xy 240.649909 -83.987703) (xy 240.55705 -84.171276) (xy 240.457099 -84.351086)
			(xy 240.350209 -84.526859) (xy 240.236542 -84.698329) (xy 240.116272 -84.865232) (xy 239.989581 -85.027317)
			(xy 239.856663 -85.184335) (xy 239.71772 -85.336047) (xy 239.572963 -85.482223) (xy 239.422613 -85.62264)
			(xy 239.2669 -85.757083) (xy 239.106059 -85.885349) (xy 238.940337 -86.007242) (xy 238.769984 -86.122577)
			(xy 238.595262 -86.231177) (xy 238.416436 -86.332877) (xy 238.233777 -86.427523) (xy 238.047566 -86.51497)
			(xy 237.858084 -86.595086) (xy 237.66562 -86.667747) (xy 237.470468 -86.732844) (xy 237.272925 -86.790278)
			(xy 237.073292 -86.83996) (xy 236.871872 -86.881815) (xy 236.668972 -86.91578) (xy 236.464902 -86.941803)
			(xy 236.259972 -86.959844) (xy 236.054494 -86.969876) (xy 235.848781 -86.971883) (xy 235.643146 -86.965863)
			(xy 235.437903 -86.951824) (xy 235.233364 -86.929787) (xy 235.02984 -86.899788) (xy 234.827642 -86.86187)
			(xy 234.627077 -86.816093) (xy 234.428451 -86.762525) (xy 234.232066 -86.701248) (xy 234.038222 -86.632355)
			(xy 233.847212 -86.555952) (xy 233.65933 -86.472155) (xy 233.47486 -86.381091) (xy 233.294083 -86.2829)
			(xy 233.117275 -86.177729) (xy 232.944705 -86.065741) (xy 232.776636 -85.947104) (xy 232.613323 -85.822001)
			(xy 232.455016 -85.690621) (xy 232.301955 -85.553165) (xy 232.154374 -85.409841) (xy 232.012497 -85.260869)
			(xy 231.87654 -85.106474) (xy 231.746711 -84.946893) (xy 231.623207 -84.782367) (xy 231.506216 -84.613148)
			(xy 231.395917 -84.439494) (xy 231.292476 -84.261668) (xy 231.196053 -84.079942) (xy 231.106793 -83.894592)
			(xy 231.024833 -83.705901) (xy 230.950297 -83.514156) (xy 230.883299 -83.319648) (xy 230.823941 -83.122675)
			(xy 230.772314 -82.923536) (xy 230.728495 -82.722534) (xy 230.692552 -82.519975) (xy 230.664539 -82.316168)
			(xy 230.6445 -82.111424) (xy 230.632464 -81.906054) (xy 230.62845 -81.70037) (xy 57.658 -81.70037)
			(xy 57.658 -84.065147) (xy 218.29831 -84.065147) (xy 218.29831 -84.010653) (xy 218.306065 -83.956712)
			(xy 218.321417 -83.904424) (xy 218.344054 -83.854854) (xy 218.373515 -83.809009) (xy 218.4092 -83.767823)
			(xy 218.450383 -83.732134) (xy 218.496225 -83.70267) (xy 218.545794 -83.680029) (xy 218.598081 -83.664672)
			(xy 218.652021 -83.656912) (xy 218.679268 -83.656424) (xy 219.542868 -83.656424) (xy 219.570125 -83.656821)
			(xy 219.624084 -83.664575) (xy 219.67639 -83.679929) (xy 219.725978 -83.702572) (xy 219.771839 -83.732041)
			(xy 219.813039 -83.767738) (xy 219.848739 -83.808935) (xy 219.878213 -83.854794) (xy 219.90086 -83.90438)
			(xy 219.916219 -83.956685) (xy 219.923977 -84.010643) (xy 219.923977 -84.065157) (xy 219.916219 -84.119115)
			(xy 219.90086 -84.17142) (xy 219.878213 -84.221006) (xy 219.848739 -84.266865) (xy 219.813039 -84.308062)
			(xy 219.771839 -84.343759) (xy 219.725978 -84.373228) (xy 219.67639 -84.395871) (xy 219.624084 -84.411225)
			(xy 219.570125 -84.418979) (xy 219.542868 -84.41944) (xy 218.679268 -84.41944) (xy 218.652021 -84.418888)
			(xy 218.598081 -84.411128) (xy 218.545794 -84.395771) (xy 218.496225 -84.37313) (xy 218.450383 -84.343666)
			(xy 218.4092 -84.307977) (xy 218.373515 -84.266791) (xy 218.344054 -84.220946) (xy 218.321417 -84.171376)
			(xy 218.306065 -84.119088) (xy 218.29831 -84.065147) (xy 57.658 -84.065147) (xy 57.658 -86.948548)
			(xy 217.344518 -86.948548) (xy 217.344518 -86.894052) (xy 217.352274 -86.84011) (xy 217.367627 -86.787821)
			(xy 217.390266 -86.738249) (xy 217.419729 -86.692404) (xy 217.455416 -86.651218) (xy 217.496602 -86.61553)
			(xy 217.542447 -86.586067) (xy 217.592019 -86.563428) (xy 217.644308 -86.548074) (xy 217.69825 -86.540318)
			(xy 217.725498 -86.539832) (xy 218.589098 -86.539832) (xy 218.616354 -86.540215) (xy 218.670311 -86.547972)
			(xy 218.722614 -86.56333) (xy 218.7722 -86.585975) (xy 218.818058 -86.615446) (xy 218.859255 -86.651143)
			(xy 218.894953 -86.69234) (xy 218.924424 -86.738198) (xy 218.947069 -86.787784) (xy 218.962427 -86.840087)
			(xy 218.970185 -86.894044) (xy 218.970185 -86.948556) (xy 218.962427 -87.002513) (xy 218.947069 -87.054816)
			(xy 218.924424 -87.104402) (xy 218.894953 -87.15026) (xy 218.859255 -87.191457) (xy 218.818058 -87.227154)
			(xy 218.7722 -87.256625) (xy 218.722614 -87.27927) (xy 218.670311 -87.294628) (xy 218.616354 -87.302385)
			(xy 218.589098 -87.302848) (xy 217.725498 -87.302848) (xy 217.69825 -87.302282) (xy 217.644308 -87.294526)
			(xy 217.592019 -87.279172) (xy 217.542447 -87.256533) (xy 217.496602 -87.22707) (xy 217.455416 -87.191382)
			(xy 217.419729 -87.150196) (xy 217.390266 -87.104351) (xy 217.367627 -87.054779) (xy 217.352274 -87.00249)
			(xy 217.344518 -86.948548) (xy 57.658 -86.948548) (xy 57.658 -90.64371) (xy 57.658425 -90.653779)
			(xy 57.666142 -90.672381) (xy 57.672986 -90.679778) (xy 62.76848 -95.775272) (xy 62.79515 -95.78213)
			(xy 62.808612 -95.77832) (xy 62.834465 -95.771319) (xy 62.887496 -95.763797) (xy 62.914276 -95.763334)
			(xy 62.945012 -95.76395) (xy 63.00569 -95.773804) (xy 63.064003 -95.793262) (xy 63.11844 -95.821819)
			(xy 63.143384 -95.839788) (xy 63.149988 -95.844868) (xy 63.165482 -95.849948) (xy 63.29807 -95.849948)
			(xy 63.313564 -95.844868) (xy 63.320168 -95.839788) (xy 63.342294 -95.823756) (xy 63.390217 -95.797512)
			(xy 63.441394 -95.778373) (xy 63.494777 -95.766731) (xy 63.549276 -95.762824) (xy 63.603775 -95.766731)
			(xy 63.657158 -95.778373) (xy 63.708335 -95.797512) (xy 63.756258 -95.823756) (xy 63.778384 -95.839788)
			(xy 63.785124 -95.844458) (xy 63.80067 -95.849646) (xy 63.808864 -95.849948) (xy 64.432688 -95.849948)
			(xy 64.440883 -95.849641) (xy 64.456434 -95.844466) (xy 64.463168 -95.839788) (xy 64.485294 -95.823756)
			(xy 64.533217 -95.797512) (xy 64.584394 -95.778373) (xy 64.637777 -95.766731) (xy 64.692276 -95.762824)
			(xy 64.746775 -95.766731) (xy 64.800158 -95.778373) (xy 64.851335 -95.797512) (xy 64.899258 -95.823756)
			(xy 64.921384 -95.839788) (xy 64.928124 -95.844458) (xy 64.94367 -95.849646) (xy 64.951864 -95.849948)
			(xy 103.886 -95.849948) (xy 103.91096 -95.850519) (xy 103.959921 -95.86026) (xy 104.00604 -95.879367)
			(xy 104.047544 -95.907105) (xy 104.065578 -95.92437) (xy 130.506216 -122.365008) (xy 130.513616 -122.371851)
			(xy 130.532214 -122.379579) (xy 130.542284 -122.379994) (xy 141.43101 -122.379994) (xy 141.45768 -122.359928)
			(xy 141.462506 -122.343672) (xy 141.470712 -122.31775) (xy 141.493445 -122.268358) (xy 141.522958 -122.222693)
			(xy 141.558654 -122.18168) (xy 141.599811 -122.14615) (xy 141.645595 -122.116821) (xy 141.695078 -122.094289)
			(xy 141.747259 -122.079009) (xy 141.80108 -122.071291) (xy 141.855452 -122.071291) (xy 141.909273 -122.079009)
			(xy 141.961454 -122.094289) (xy 142.010937 -122.116821) (xy 142.056721 -122.14615) (xy 142.097878 -122.18168)
			(xy 142.133574 -122.222693) (xy 142.163087 -122.268358) (xy 142.18582 -122.31775) (xy 142.194026 -122.343672)
			(xy 142.198852 -122.359928) (xy 142.225522 -122.379994) (xy 156.121862 -122.379994) (xy 156.146816 -122.380611)
			(xy 156.195764 -122.390359) (xy 156.24187 -122.409467) (xy 156.283362 -122.437203) (xy 156.30144 -122.454416)
			(xy 161.558986 -127.711962) (xy 161.566387 -127.718799) (xy 161.584986 -127.726508) (xy 161.595054 -127.726948)
			(xy 162.926268 -127.726948)
		)
		(stroke
			(width 0)
			(type solid)
		)
		(fill yes)
		(layer "In9.Cu")
		(net "P3V3_AUX")
	)
	(gr_poly
		(pts
			(xy 124.278644 -251.50064) (xy 124.290582 -251.493274) (xy 124.310303 -251.481541) (xy 124.352291 -251.46303)
			(xy 124.396433 -251.45049) (xy 124.441882 -251.444161) (xy 124.464826 -251.443744) (xy 124.479812 -251.443998)
			(xy 124.49429 -251.44476) (xy 124.518928 -251.431298) (xy 124.663708 -251.18187) (xy 124.6632 -251.153676)
			(xy 124.65558 -251.141738) (xy 124.643374 -251.121768) (xy 124.624094 -251.07912) (xy 124.611017 -251.034181)
			(xy 124.604402 -250.987847) (xy 124.604018 -250.964446) (xy 124.604498 -250.938455) (xy 124.612623 -250.887113)
			(xy 124.628682 -250.837674) (xy 124.652278 -250.791356) (xy 124.682829 -250.7493) (xy 124.719585 -250.712542)
			(xy 124.761639 -250.681988) (xy 124.807955 -250.65839) (xy 124.857393 -250.642328) (xy 124.908735 -250.634199)
			(xy 124.934726 -250.633738) (xy 124.958053 -250.634158) (xy 125.004241 -250.640746) (xy 125.049048 -250.653746)
			(xy 125.09159 -250.6729) (xy 125.11151 -250.685046) (xy 125.123702 -250.692666) (xy 125.151388 -250.693174)
			(xy 126.001272 -250.20524) (xy 126.014734 -250.180856) (xy 126.014226 -250.166378) (xy 126.013972 -250.15444)
			(xy 126.014452 -250.128448) (xy 126.022578 -250.077104) (xy 126.038637 -250.027662) (xy 126.062232 -249.981342)
			(xy 126.092783 -249.939284) (xy 126.129538 -249.902522) (xy 126.171591 -249.871963) (xy 126.217907 -249.84836)
			(xy 126.267345 -249.832292) (xy 126.318688 -249.824157) (xy 126.34468 -249.823732) (xy 126.35992 -249.823986)
			(xy 126.374398 -249.824748) (xy 126.399036 -249.811286) (xy 126.543816 -249.561858) (xy 126.543308 -249.533664)
			(xy 126.535434 -249.521472) (xy 126.523262 -249.501527) (xy 126.504049 -249.458935) (xy 126.491035 -249.414059)
			(xy 126.484482 -249.367797) (xy 126.484126 -249.344434) (xy 126.484607 -249.318444) (xy 126.492734 -249.267103)
			(xy 126.508793 -249.217666) (xy 126.53239 -249.171351) (xy 126.562942 -249.129298) (xy 126.599698 -249.092542)
			(xy 126.641751 -249.06199) (xy 126.688066 -249.038393) (xy 126.737503 -249.022334) (xy 126.788844 -249.014207)
			(xy 126.814834 -249.013726) (xy 126.82982 -249.01398) (xy 126.844298 -249.014742) (xy 126.868936 -249.00128)
			(xy 127.013716 -248.751852) (xy 127.013208 -248.723658) (xy 127.005334 -248.711466) (xy 126.993162 -248.691521)
			(xy 126.97395 -248.648929) (xy 126.960937 -248.604053) (xy 126.954385 -248.557791) (xy 126.954026 -248.534428)
			(xy 126.954428 -248.510798) (xy 126.96116 -248.464019) (xy 126.974492 -248.418677) (xy 126.994151 -248.375699)
			(xy 127.006604 -248.355612) (xy 127.014478 -248.34342) (xy 127.014986 -248.315226) (xy 126.871222 -248.067322)
			(xy 126.84633 -248.05386) (xy 126.831852 -248.054622) (xy 126.814834 -248.05513) (xy 126.788842 -248.054649)
			(xy 126.737498 -248.046523) (xy 126.688058 -248.030464) (xy 126.641738 -248.006868) (xy 126.59968 -247.976317)
			(xy 126.56292 -247.939562) (xy 126.532361 -247.897509) (xy 126.508758 -247.851194) (xy 126.492691 -247.801756)
			(xy 126.484555 -247.750414) (xy 126.484126 -247.724422) (xy 126.484528 -247.700792) (xy 126.491262 -247.654013)
			(xy 126.504594 -247.608672) (xy 126.524253 -247.565694) (xy 126.536704 -247.545606) (xy 126.544578 -247.533414)
			(xy 126.545086 -247.50522) (xy 126.401576 -247.25757) (xy 126.37643 -247.243854) (xy 126.361952 -247.244616)
			(xy 126.34468 -247.245124) (xy 126.318693 -247.244613) (xy 126.267358 -247.236479) (xy 126.217928 -247.220416)
			(xy 126.171619 -247.196818) (xy 126.129571 -247.166266) (xy 126.092821 -247.129513) (xy 126.062272 -247.087464)
			(xy 126.038676 -247.041154) (xy 126.022616 -246.991722) (xy 126.014486 -246.940387) (xy 126.014486 -246.888413)
			(xy 126.022616 -246.837078) (xy 126.038676 -246.787646) (xy 126.062272 -246.741336) (xy 126.092821 -246.699287)
			(xy 126.129571 -246.662534) (xy 126.171619 -246.631982) (xy 126.217928 -246.608384) (xy 126.267358 -246.592321)
			(xy 126.318693 -246.584187) (xy 126.34468 -246.583708) (xy 126.360174 -246.583962) (xy 126.374398 -246.584724)
			(xy 126.39929 -246.571262) (xy 126.543816 -246.321834) (xy 126.543308 -246.29364) (xy 126.535688 -246.281448)
			(xy 126.523505 -246.261503) (xy 126.504261 -246.218914) (xy 126.4912 -246.174041) (xy 126.484581 -246.127777)
			(xy 126.484126 -246.10441) (xy 126.484608 -246.078421) (xy 126.492739 -246.027083) (xy 126.5088 -245.97765)
			(xy 126.532398 -245.931338) (xy 126.562951 -245.889288) (xy 126.599706 -245.852535) (xy 126.641758 -245.821986)
			(xy 126.688072 -245.798391) (xy 126.737507 -245.782333) (xy 126.788845 -245.774207) (xy 126.814834 -245.773702)
			(xy 126.830074 -245.773956) (xy 126.844298 -245.774718) (xy 126.868936 -245.761256) (xy 127.013716 -245.511828)
			(xy 127.013208 -245.483634) (xy 127.005334 -245.471442) (xy 126.993164 -245.451496) (xy 126.973955 -245.408904)
			(xy 126.960945 -245.364028) (xy 126.954396 -245.317766) (xy 126.954026 -245.294404) (xy 126.954429 -245.270774)
			(xy 126.961165 -245.223997) (xy 126.9745 -245.178657) (xy 126.994161 -245.135681) (xy 127.006604 -245.115588)
			(xy 127.014478 -245.103396) (xy 127.014986 -245.075202) (xy 126.871222 -244.827298) (xy 126.84633 -244.813836)
			(xy 126.831852 -244.814598) (xy 126.814834 -244.815106) (xy 126.788843 -244.814625) (xy 126.7375 -244.806498)
			(xy 126.688062 -244.790439) (xy 126.641744 -244.766843) (xy 126.599688 -244.736291) (xy 126.562929 -244.699537)
			(xy 126.532374 -244.657484) (xy 126.508773 -244.611168) (xy 126.492709 -244.561731) (xy 126.484577 -244.510389)
			(xy 126.484126 -244.484398) (xy 126.48453 -244.460768) (xy 126.491266 -244.413991) (xy 126.504602 -244.368652)
			(xy 126.524263 -244.325676) (xy 126.536704 -244.305582) (xy 126.544578 -244.29339) (xy 126.545086 -244.265196)
			(xy 126.401576 -244.017546) (xy 126.37643 -244.00383) (xy 126.361952 -244.004592) (xy 126.34468 -244.0051)
			(xy 126.318694 -244.004589) (xy 126.267364 -243.996456) (xy 126.217937 -243.980394) (xy 126.171631 -243.956797)
			(xy 126.129587 -243.926248) (xy 126.092839 -243.889498) (xy 126.062292 -243.847452) (xy 126.038699 -243.801145)
			(xy 126.022639 -243.751717) (xy 126.014509 -243.700386) (xy 126.014509 -243.648414) (xy 126.022639 -243.597083)
			(xy 126.038699 -243.547655) (xy 126.062292 -243.501348) (xy 126.092839 -243.459302) (xy 126.129587 -243.422552)
			(xy 126.171631 -243.392003) (xy 126.217937 -243.368406) (xy 126.267364 -243.352344) (xy 126.318694 -243.344211)
			(xy 126.34468 -243.343684) (xy 126.360174 -243.343938) (xy 126.374398 -243.3447) (xy 126.39929 -243.331238)
			(xy 126.543816 -243.08181) (xy 126.543308 -243.053616) (xy 126.535688 -243.041424) (xy 126.523501 -243.02148)
			(xy 126.504247 -242.978893) (xy 126.491175 -242.93402) (xy 126.484546 -242.887755) (xy 126.484126 -242.864386)
			(xy 126.48461 -242.838398) (xy 126.492743 -242.787064) (xy 126.508807 -242.737633) (xy 126.532406 -242.691324)
			(xy 126.562959 -242.649277) (xy 126.599714 -242.612528) (xy 126.641765 -242.581981) (xy 126.688077 -242.558389)
			(xy 126.73751 -242.542332) (xy 126.788846 -242.534206) (xy 126.814834 -242.533678) (xy 126.830074 -242.533932)
			(xy 126.844298 -242.534694) (xy 126.868936 -242.521232) (xy 127.013716 -242.271804) (xy 127.013208 -242.24361)
			(xy 127.005334 -242.231418) (xy 126.993165 -242.211472) (xy 126.973959 -242.16888) (xy 126.960953 -242.124004)
			(xy 126.954407 -242.077742) (xy 126.954026 -242.05438) (xy 126.954431 -242.030751) (xy 126.96117 -241.983974)
			(xy 126.974507 -241.938636) (xy 126.994171 -241.895662) (xy 127.006604 -241.875564) (xy 127.014478 -241.863372)
			(xy 127.014986 -241.835178) (xy 126.871222 -241.587274) (xy 126.84633 -241.573812) (xy 126.831852 -241.574574)
			(xy 126.814834 -241.575082) (xy 126.788844 -241.574601) (xy 126.737503 -241.566474) (xy 126.688065 -241.550415)
			(xy 126.641749 -241.526818) (xy 126.599695 -241.496266) (xy 126.562939 -241.459511) (xy 126.532386 -241.417458)
			(xy 126.508788 -241.371142) (xy 126.492728 -241.321705) (xy 126.484599 -241.270364) (xy 126.484126 -241.244374)
			(xy 126.484532 -241.220745) (xy 126.491271 -241.173969) (xy 126.504609 -241.128631) (xy 126.524273 -241.085658)
			(xy 126.536704 -241.065558) (xy 126.544578 -241.053366) (xy 126.545086 -241.025172) (xy 126.401576 -240.777522)
			(xy 126.37643 -240.763806) (xy 126.361952 -240.764568) (xy 126.34468 -240.765076) (xy 126.318696 -240.764565)
			(xy 126.267369 -240.756433) (xy 126.217946 -240.740372) (xy 126.171644 -240.716777) (xy 126.129603 -240.68623)
			(xy 126.092857 -240.649482) (xy 126.062313 -240.607439) (xy 126.038721 -240.561135) (xy 126.022663 -240.511711)
			(xy 126.014533 -240.460384) (xy 126.014533 -240.408416) (xy 126.022663 -240.357089) (xy 126.038721 -240.307665)
			(xy 126.062313 -240.261361) (xy 126.092857 -240.219318) (xy 126.129603 -240.18257) (xy 126.171644 -240.152023)
			(xy 126.217946 -240.128428) (xy 126.267369 -240.112367) (xy 126.318696 -240.104235) (xy 126.34468 -240.10366)
			(xy 126.360174 -240.103914) (xy 126.374398 -240.104676) (xy 126.39929 -240.091214) (xy 126.543816 -239.841786)
			(xy 126.543308 -239.813592) (xy 126.535688 -239.8014) (xy 126.523502 -239.781456) (xy 126.504251 -239.738868)
			(xy 126.491183 -239.693995) (xy 126.484557 -239.64773) (xy 126.484126 -239.624362) (xy 126.484638 -239.598378)
			(xy 126.492774 -239.54705) (xy 126.508839 -239.497627) (xy 126.532437 -239.451325) (xy 126.562988 -239.409285)
			(xy 126.599739 -239.372541) (xy 126.641786 -239.341999) (xy 126.688093 -239.318411) (xy 126.73752 -239.302357)
			(xy 126.78885 -239.294233) (xy 126.814834 -239.293654) (xy 126.830074 -239.293908) (xy 126.844298 -239.29467)
			(xy 126.868936 -239.281208) (xy 127.013716 -239.03178) (xy 127.013208 -239.003586) (xy 127.005588 -238.991394)
			(xy 126.993403 -238.97145) (xy 126.974152 -238.928862) (xy 126.961085 -238.883989) (xy 126.95446 -238.837724)
			(xy 126.954026 -238.814356) (xy 126.95428 -238.798862) (xy 126.955042 -238.784384) (xy 126.94158 -238.759746)
			(xy 126.094744 -238.273336) (xy 126.06655 -238.274098) (xy 126.054358 -238.281972) (xy 126.034198 -238.29452)
			(xy 125.99105 -238.314346) (xy 125.945514 -238.327811) (xy 125.898522 -238.334641) (xy 125.87478 -238.335058)
			(xy 125.84879 -238.334547) (xy 125.79745 -238.326413) (xy 125.748015 -238.310347) (xy 125.701701 -238.286747)
			(xy 125.659649 -238.256192) (xy 125.622895 -238.219435) (xy 125.592343 -238.177382) (xy 125.568745 -238.131067)
			(xy 125.552683 -238.08163) (xy 125.544552 -238.03029) (xy 125.544552 -237.97831) (xy 125.552683 -237.92697)
			(xy 125.568745 -237.877533) (xy 125.592343 -237.831218) (xy 125.622895 -237.789165) (xy 125.659649 -237.752408)
			(xy 125.701701 -237.721853) (xy 125.748015 -237.698253) (xy 125.79745 -237.682187) (xy 125.84879 -237.674053)
			(xy 125.87478 -237.673642) (xy 125.89002 -237.673896) (xy 125.904244 -237.674658) (xy 125.929136 -237.661196)
			(xy 126.073662 -237.411768) (xy 126.073154 -237.383574) (xy 126.065534 -237.371636) (xy 126.053329 -237.351665)
			(xy 126.034053 -237.309017) (xy 126.020977 -237.264078) (xy 126.014364 -237.217745) (xy 126.013972 -237.194344)
			(xy 126.014452 -237.168352) (xy 126.022577 -237.117007) (xy 126.038636 -237.067565) (xy 126.062231 -237.021244)
			(xy 126.092782 -236.979185) (xy 126.129536 -236.942423) (xy 126.17159 -236.911864) (xy 126.217906 -236.88826)
			(xy 126.267344 -236.872192) (xy 126.318688 -236.864057) (xy 126.34468 -236.863636) (xy 126.35992 -236.86389)
			(xy 126.374144 -236.864652) (xy 126.399036 -236.85119) (xy 126.543816 -236.601762) (xy 126.543308 -236.573568)
			(xy 126.535434 -236.561376) (xy 126.523262 -236.541431) (xy 126.504048 -236.498839) (xy 126.491034 -236.453964)
			(xy 126.48448 -236.407701) (xy 126.484126 -236.384338) (xy 126.484527 -236.360707) (xy 126.491258 -236.313928)
			(xy 126.504589 -236.268585) (xy 126.524247 -236.225606) (xy 126.536704 -236.205522) (xy 126.544578 -236.19333)
			(xy 126.545086 -236.165136) (xy 126.401576 -235.917486) (xy 126.37643 -235.90377) (xy 126.361952 -235.904532)
			(xy 126.34468 -235.90504) (xy 126.318691 -235.904529) (xy 126.267354 -235.896395) (xy 126.217922 -235.880331)
			(xy 126.17161 -235.856732) (xy 126.129561 -235.826178) (xy 126.092809 -235.789424) (xy 126.062258 -235.747372)
			(xy 126.038662 -235.70106) (xy 126.0226 -235.651626) (xy 126.01447 -235.600289) (xy 126.01447 -235.548311)
			(xy 126.0226 -235.496974) (xy 126.038662 -235.44754) (xy 126.062258 -235.401228) (xy 126.092809 -235.359176)
			(xy 126.129561 -235.322422) (xy 126.17161 -235.291868) (xy 126.217922 -235.268269) (xy 126.267354 -235.252205)
			(xy 126.318691 -235.244071) (xy 126.34468 -235.243624) (xy 126.360174 -235.243878) (xy 126.374398 -235.24464)
			(xy 126.39929 -235.231178) (xy 126.543816 -234.98175) (xy 126.543308 -234.953556) (xy 126.535688 -234.941364)
			(xy 126.523504 -234.92142) (xy 126.504258 -234.878831) (xy 126.491194 -234.833958) (xy 126.484574 -234.787693)
			(xy 126.484126 -234.764326) (xy 126.484607 -234.738336) (xy 126.492735 -234.686997) (xy 126.508796 -234.637561)
			(xy 126.532393 -234.591246) (xy 126.562945 -234.549194) (xy 126.5997 -234.51244) (xy 126.641753 -234.481889)
			(xy 126.688068 -234.458293) (xy 126.737504 -234.442234) (xy 126.788844 -234.434107) (xy 126.814834 -234.433618)
			(xy 126.830074 -234.433872) (xy 126.844298 -234.434634) (xy 126.868936 -234.421172) (xy 127.013716 -234.171744)
			(xy 127.013208 -234.14355) (xy 127.005334 -234.131358) (xy 126.993163 -234.111413) (xy 126.973951 -234.068821)
			(xy 126.96094 -234.023945) (xy 126.954389 -233.977682) (xy 126.954026 -233.95432) (xy 126.954428 -233.93069)
			(xy 126.961162 -233.883911) (xy 126.974495 -233.83857) (xy 126.994154 -233.795593) (xy 127.006604 -233.775504)
			(xy 127.014478 -233.763312) (xy 127.014986 -233.735118) (xy 126.871222 -233.487214) (xy 126.84633 -233.473752)
			(xy 126.831852 -233.474514) (xy 126.814834 -233.475022) (xy 126.788843 -233.474541) (xy 126.737499 -233.466415)
			(xy 126.688059 -233.450355) (xy 126.64174 -233.42676) (xy 126.599683 -233.396208) (xy 126.562923 -233.359454)
			(xy 126.532365 -233.317401) (xy 126.508763 -233.271085) (xy 126.492697 -233.221648) (xy 126.484562 -233.170305)
			(xy 126.484126 -233.144314) (xy 126.484529 -233.120684) (xy 126.491263 -233.073906) (xy 126.504597 -233.028565)
			(xy 126.524256 -232.985588) (xy 126.536704 -232.965498) (xy 126.544578 -232.953306) (xy 126.545086 -232.925112)
			(xy 126.401576 -232.677462) (xy 126.37643 -232.663746) (xy 126.361952 -232.664508) (xy 126.34468 -232.665016)
			(xy 126.318693 -232.664505) (xy 126.26736 -232.656372) (xy 126.217931 -232.640309) (xy 126.171623 -232.616711)
			(xy 126.129577 -232.58616) (xy 126.092827 -232.549408) (xy 126.062278 -232.50736) (xy 126.038684 -232.461051)
			(xy 126.022624 -232.411621) (xy 126.014493 -232.360287) (xy 126.014493 -232.308313) (xy 126.022624 -232.256979)
			(xy 126.038684 -232.207549) (xy 126.062278 -232.16124) (xy 126.092827 -232.119192) (xy 126.129577 -232.08244)
			(xy 126.171623 -232.051889) (xy 126.217931 -232.028291) (xy 126.26736 -232.012228) (xy 126.318693 -232.004095)
			(xy 126.34468 -232.0036) (xy 126.35992 -232.003854) (xy 126.374398 -232.004616) (xy 126.399036 -231.991154)
			(xy 126.543816 -231.741726) (xy 126.543308 -231.713532) (xy 126.535434 -231.70134) (xy 126.523264 -231.681394)
			(xy 126.504055 -231.638802) (xy 126.491046 -231.593926) (xy 126.484497 -231.547664) (xy 126.484126 -231.524302)
			(xy 126.48453 -231.500672) (xy 126.491266 -231.453895) (xy 126.5046 -231.408555) (xy 126.524261 -231.365579)
			(xy 126.536704 -231.345486) (xy 126.544578 -231.333294) (xy 126.545086 -231.3051) (xy 126.401576 -231.057704)
			(xy 126.37643 -231.043988) (xy 126.362206 -231.04475) (xy 126.34468 -231.045258) (xy 126.31869 -231.044747)
			(xy 126.26735 -231.036613) (xy 126.217915 -231.020547) (xy 126.171601 -230.996947) (xy 126.129549 -230.966392)
			(xy 126.092795 -230.929635) (xy 126.062243 -230.887582) (xy 126.038645 -230.841267) (xy 126.022583 -230.79183)
			(xy 126.014452 -230.74049) (xy 126.014452 -230.68851) (xy 126.022583 -230.63717) (xy 126.038645 -230.587733)
			(xy 126.062243 -230.541418) (xy 126.092795 -230.499365) (xy 126.129549 -230.462608) (xy 126.171601 -230.432053)
			(xy 126.217915 -230.408453) (xy 126.26735 -230.392387) (xy 126.31869 -230.384253) (xy 126.34468 -230.383842)
			(xy 126.35992 -230.384096) (xy 126.374144 -230.384858) (xy 126.399036 -230.371396) (xy 126.543816 -230.121714)
			(xy 126.543308 -230.09352) (xy 126.535434 -230.081328) (xy 126.523265 -230.061382) (xy 126.504057 -230.01879)
			(xy 126.49105 -229.973914) (xy 126.484503 -229.927652) (xy 126.484126 -229.90429) (xy 126.48453 -229.88066)
			(xy 126.491268 -229.833884) (xy 126.504604 -229.788545) (xy 126.524266 -229.74557) (xy 126.536704 -229.725474)
			(xy 126.544578 -229.713282) (xy 126.545086 -229.685088) (xy 126.401576 -229.437692) (xy 126.37643 -229.423976)
			(xy 126.362206 -229.424738) (xy 126.34468 -229.425246) (xy 126.318691 -229.424735) (xy 126.267353 -229.416601)
			(xy 126.217919 -229.400536) (xy 126.171607 -229.376937) (xy 126.129557 -229.346383) (xy 126.092804 -229.309628)
			(xy 126.062253 -229.267576) (xy 126.038656 -229.221262) (xy 126.022594 -229.171828) (xy 126.014464 -229.120489)
			(xy 126.014464 -229.068511) (xy 126.022594 -229.017172) (xy 126.038656 -228.967738) (xy 126.062253 -228.921424)
			(xy 126.092804 -228.879372) (xy 126.129557 -228.842617) (xy 126.171607 -228.812063) (xy 126.217919 -228.788464)
			(xy 126.267353 -228.772399) (xy 126.318691 -228.764265) (xy 126.34468 -228.76383) (xy 126.35992 -228.764084)
			(xy 126.374144 -228.764846) (xy 126.399036 -228.751384) (xy 126.543816 -228.501956) (xy 126.543308 -228.473762)
			(xy 126.535434 -228.46157) (xy 126.523262 -228.441625) (xy 126.504049 -228.399033) (xy 126.491036 -228.354157)
			(xy 126.484483 -228.307895) (xy 126.484126 -228.284532) (xy 126.484607 -228.258542) (xy 126.492734 -228.207202)
			(xy 126.508794 -228.157765) (xy 126.532391 -228.11145) (xy 126.562943 -228.069397) (xy 126.599698 -228.032642)
			(xy 126.641752 -228.00209) (xy 126.688067 -227.978493) (xy 126.737504 -227.962434) (xy 126.788844 -227.954307)
			(xy 126.814834 -227.953824) (xy 126.84034 -227.954291) (xy 126.890747 -227.962112) (xy 126.939357 -227.977579)
			(xy 126.985015 -228.000325) (xy 127.026641 -228.029811) (xy 127.063246 -228.065338) (xy 127.093963 -228.106064)
			(xy 127.106426 -228.128322) (xy 127.11303 -228.141022) (xy 127.136906 -228.155246) (xy 127.432562 -228.155246)
			(xy 127.456438 -228.141022) (xy 127.463042 -228.128322) (xy 127.475515 -228.106073) (xy 127.506241 -228.065363)
			(xy 127.54285 -228.029848) (xy 127.584474 -228.000372) (xy 127.630128 -227.977631) (xy 127.678731 -227.962165)
			(xy 127.729132 -227.954339) (xy 127.780136 -227.954339) (xy 127.830537 -227.962165) (xy 127.87914 -227.977631)
			(xy 127.924794 -228.000372) (xy 127.966418 -228.029848) (xy 128.003027 -228.065363) (xy 128.033753 -228.106073)
			(xy 128.046226 -228.128322) (xy 128.05283 -228.141022) (xy 128.076706 -228.155246) (xy 128.372616 -228.155246)
			(xy 128.396492 -228.141022) (xy 128.403096 -228.128322) (xy 128.415572 -228.106074) (xy 128.446301 -228.065365)
			(xy 128.482911 -228.029851) (xy 128.524534 -228.000371) (xy 128.570186 -227.977624) (xy 128.618786 -227.962148)
			(xy 128.669186 -227.954308) (xy 128.694688 -227.953824) (xy 128.709928 -227.954078) (xy 128.724152 -227.95484)
			(xy 128.749044 -227.941378) (xy 128.893824 -227.69195) (xy 128.893062 -227.663756) (xy 128.885442 -227.651564)
			(xy 128.873274 -227.631618) (xy 128.854067 -227.589025) (xy 128.841058 -227.544149) (xy 128.834508 -227.497888)
			(xy 128.834134 -227.474526) (xy 128.834615 -227.448537) (xy 128.842743 -227.397197) (xy 128.858804 -227.347762)
			(xy 128.882401 -227.301448) (xy 128.912953 -227.259397) (xy 128.949709 -227.222643) (xy 128.991762 -227.192093)
			(xy 129.038077 -227.168498) (xy 129.087513 -227.15244) (xy 129.138853 -227.144314) (xy 129.164842 -227.143818)
			(xy 129.179828 -227.144072) (xy 129.194306 -227.144834) (xy 129.218944 -227.131372) (xy 129.363724 -226.881944)
			(xy 129.363216 -226.85375) (xy 129.355342 -226.841558) (xy 129.343174 -226.821612) (xy 129.323968 -226.779019)
			(xy 129.31096 -226.734143) (xy 129.304411 -226.687882) (xy 129.304034 -226.66452) (xy 129.304516 -226.638531)
			(xy 129.312645 -226.587192) (xy 129.328706 -226.537758) (xy 129.352303 -226.491445) (xy 129.382856 -226.449394)
			(xy 129.419611 -226.412641) (xy 129.461664 -226.382092) (xy 129.507978 -226.358497) (xy 129.557414 -226.34244)
			(xy 129.608753 -226.334314) (xy 129.634742 -226.333812) (xy 129.649982 -226.334066) (xy 129.664206 -226.334828)
			(xy 129.689098 -226.321366) (xy 129.833624 -226.071938) (xy 129.833116 -226.043744) (xy 129.825496 -226.031806)
			(xy 129.813295 -226.011834) (xy 129.794024 -225.969185) (xy 129.780954 -225.924246) (xy 129.774345 -225.877914)
			(xy 129.773934 -225.854514) (xy 129.774416 -225.828525) (xy 129.782546 -225.777187) (xy 129.798607 -225.727754)
			(xy 129.822205 -225.681442) (xy 129.852758 -225.639392) (xy 129.889513 -225.60264) (xy 129.931566 -225.57209)
			(xy 129.97788 -225.548497) (xy 130.027315 -225.532439) (xy 130.078653 -225.524314) (xy 130.104642 -225.523806)
			(xy 130.119882 -225.52406) (xy 130.134106 -225.524822) (xy 130.158998 -225.51136) (xy 130.303778 -225.261932)
			(xy 130.303016 -225.233738) (xy 130.295396 -225.221546) (xy 130.283227 -225.2016) (xy 130.264019 -225.159008)
			(xy 130.251011 -225.114132) (xy 130.244462 -225.06787) (xy 130.244088 -225.044508) (xy 130.244571 -225.018518)
			(xy 130.252701 -224.967178) (xy 130.268762 -224.917743) (xy 130.292359 -224.871428) (xy 130.322911 -224.829375)
			(xy 130.359666 -224.792619) (xy 130.401718 -224.762066) (xy 130.448031 -224.738467) (xy 130.497467 -224.722404)
			(xy 130.548806 -224.714271) (xy 130.574796 -224.7138) (xy 130.589782 -224.714054) (xy 130.60426 -224.714816)
			(xy 130.628898 -224.701354) (xy 130.773678 -224.451926) (xy 130.77317 -224.423732) (xy 130.76555 -224.41154)
			(xy 130.75336 -224.391598) (xy 130.7341 -224.349011) (xy 130.721024 -224.304138) (xy 130.714391 -224.257871)
			(xy 130.713988 -224.234502) (xy 130.714497 -224.208515) (xy 130.722628 -224.15718) (xy 130.738688 -224.107749)
			(xy 130.762284 -224.061439) (xy 130.792834 -224.01939) (xy 130.829585 -223.982638) (xy 130.871633 -223.952087)
			(xy 130.917943 -223.928491) (xy 130.967374 -223.912429) (xy 131.018709 -223.904298) (xy 131.044696 -223.903794)
			(xy 131.059936 -223.904048) (xy 131.07416 -223.90481) (xy 131.099052 -223.891348) (xy 131.243832 -223.64192)
			(xy 131.24307 -223.613726) (xy 131.23545 -223.601534) (xy 131.223283 -223.581587) (xy 131.20408 -223.538994)
			(xy 131.191075 -223.494119) (xy 131.184529 -223.447857) (xy 131.184142 -223.424496) (xy 131.184645 -223.398617)
			(xy 131.192714 -223.347493) (xy 131.208656 -223.298252) (xy 131.232079 -223.252098) (xy 131.262412 -223.21016)
			(xy 131.298911 -223.173464) (xy 131.340686 -223.142907) (xy 131.363466 -223.130618) (xy 131.376166 -223.124014)
			(xy 131.390898 -223.099884) (xy 131.390898 -222.129096) (xy 131.376166 -222.104966) (xy 131.363466 -222.098362)
			(xy 131.340682 -222.086079) (xy 131.298909 -222.055521) (xy 131.26241 -222.018824) (xy 131.232079 -221.976885)
			(xy 131.208658 -221.93073) (xy 131.192719 -221.881488) (xy 131.184652 -221.830363) (xy 131.184142 -221.804484)
			(xy 131.184669 -221.777238) (xy 131.193557 -221.723477) (xy 131.211155 -221.671905) (xy 131.236984 -221.623925)
			(xy 131.25323 -221.602046) (xy 131.258139 -221.595259) (xy 131.26358 -221.579428) (xy 131.263898 -221.571058)
			(xy 131.263898 -217.924888) (xy 131.24307 -217.897456) (xy 131.22656 -217.892884) (xy 131.200314 -217.885224)
			(xy 131.150376 -217.862969) (xy 131.104429 -217.833339) (xy 131.063554 -217.797029) (xy 131.028713 -217.754896)
			(xy 131.000726 -217.707929) (xy 130.980252 -217.657235) (xy 130.967772 -217.604005) (xy 130.96358 -217.549494)
			(xy 130.967774 -217.494982) (xy 130.980256 -217.441753) (xy 131.000732 -217.39106) (xy 131.02872 -217.344094)
			(xy 131.063563 -217.301962) (xy 131.104439 -217.265654) (xy 131.150387 -217.236025) (xy 131.200326 -217.213772)
			(xy 131.22656 -217.206068) (xy 131.24307 -217.201496) (xy 131.263898 -217.174064) (xy 131.263898 -211.935314)
			(xy 131.263459 -211.925251) (xy 131.255722 -211.906669) (xy 131.248912 -211.899246) (xy 111.747808 -192.398142)
			(xy 111.730547 -192.380102) (xy 111.702786 -192.338609) (xy 111.683672 -192.292491) (xy 111.67394 -192.243526)
			(xy 111.673386 -192.218564) (xy 111.673386 -187.59424) (xy 111.672952 -187.584175) (xy 111.66522 -187.565588)
			(xy 111.6584 -187.558172) (xy 111.422688 -187.32246) (xy 111.415292 -187.315609) (xy 111.396693 -187.307869)
			(xy 111.38662 -187.307474) (xy 111.161576 -187.307474) (xy 111.155059 -187.307705) (xy 111.142456 -187.311042)
			(xy 111.136684 -187.314078) (xy 111.112118 -187.327269) (xy 111.060032 -187.347172) (xy 111.005604 -187.359285)
			(xy 110.949994 -187.363352) (xy 110.894384 -187.359285) (xy 110.839956 -187.347172) (xy 110.78787 -187.327269)
			(xy 110.763304 -187.314078) (xy 110.75754 -187.311019) (xy 110.744934 -187.307666) (xy 110.738412 -187.307474)
			(xy 104.547416 -187.307474) (xy 104.537366 -187.30798) (xy 104.518806 -187.315703) (xy 104.511348 -187.32246)
			(xy 100.654358 -191.17945) (xy 100.636317 -191.196709) (xy 100.594823 -191.224466) (xy 100.548705 -191.243579)
			(xy 100.499741 -191.253312) (xy 100.47478 -191.253872) (xy 78.573884 -191.253872) (xy 78.548924 -191.253299)
			(xy 78.499965 -191.243557) (xy 78.453847 -191.224449) (xy 78.412344 -191.196711) (xy 78.394306 -191.17945)
			(xy 73.663556 -186.4487) (xy 73.656155 -186.44186) (xy 73.637557 -186.434142) (xy 73.627488 -186.433714)
			(xy 71.830692 -186.433714) (xy 71.805736 -186.433102) (xy 71.756782 -186.423363) (xy 71.710669 -186.404262)
			(xy 71.669167 -186.376532) (xy 71.651114 -186.359292) (xy 69.456808 -184.164986) (xy 69.439543 -184.146947)
			(xy 69.411775 -184.105456) (xy 69.392653 -184.059337) (xy 69.382913 -184.010371) (xy 69.382386 -183.985408)
			(xy 69.382386 -181.676802) (xy 69.381963 -181.666732) (xy 69.374247 -181.648128) (xy 69.3674 -181.640734)
			(xy 67.895216 -180.16855) (xy 67.887816 -180.161711) (xy 67.869217 -180.153999) (xy 67.859148 -180.153564)
			(xy 60.618624 -180.153564) (xy 60.608561 -180.154003) (xy 60.589983 -180.161744) (xy 60.582556 -180.16855)
			(xy 60.395866 -180.35524) (xy 60.389019 -180.362637) (xy 60.381288 -180.381236) (xy 60.38088 -180.391308)
			(xy 60.38088 -202.52182) (xy 60.381306 -202.531889) (xy 60.389023 -202.55049) (xy 60.395866 -202.557888)
			(xy 65.337436 -207.499458) (xy 97.408492 -207.499458) (xy 97.408492 -206.635858) (xy 97.408978 -206.608589)
			(xy 97.41674 -206.554605) (xy 97.432105 -206.502275) (xy 97.454762 -206.452665) (xy 97.484248 -206.406784)
			(xy 97.519963 -206.365567) (xy 97.56118 -206.329852) (xy 97.607061 -206.300366) (xy 97.656671 -206.277709)
			(xy 97.709001 -206.262344) (xy 97.762985 -206.254582) (xy 97.817523 -206.254582) (xy 97.871507 -206.262344)
			(xy 97.923837 -206.277709) (xy 97.973447 -206.300366) (xy 98.019328 -206.329852) (xy 98.060545 -206.365567)
			(xy 98.09626 -206.406784) (xy 98.125746 -206.452665) (xy 98.148403 -206.502275) (xy 98.163768 -206.554605)
			(xy 98.17153 -206.608589) (xy 98.172016 -206.635858) (xy 98.172016 -207.499458) (xy 98.17153 -207.526727)
			(xy 98.163768 -207.580711) (xy 98.148403 -207.633041) (xy 98.125746 -207.682651) (xy 98.09626 -207.728532)
			(xy 98.060545 -207.769749) (xy 98.019328 -207.805464) (xy 97.973447 -207.83495) (xy 97.923837 -207.857607)
			(xy 97.871507 -207.872972) (xy 97.817523 -207.880734) (xy 97.762985 -207.880734) (xy 97.709001 -207.872972)
			(xy 97.656671 -207.857607) (xy 97.607061 -207.83495) (xy 97.56118 -207.805464) (xy 97.519963 -207.769749)
			(xy 97.484248 -207.728532) (xy 97.454762 -207.682651) (xy 97.432105 -207.633041) (xy 97.41674 -207.580711)
			(xy 97.408978 -207.526727) (xy 97.408492 -207.499458) (xy 65.337436 -207.499458) (xy 66.861436 -209.023458)
			(xy 94.105984 -209.023458) (xy 94.105984 -208.159858) (xy 94.10647 -208.132589) (xy 94.114232 -208.078605)
			(xy 94.129597 -208.026275) (xy 94.152254 -207.976665) (xy 94.18174 -207.930784) (xy 94.217455 -207.889567)
			(xy 94.258672 -207.853852) (xy 94.304553 -207.824366) (xy 94.354163 -207.801709) (xy 94.406493 -207.786344)
			(xy 94.460477 -207.778582) (xy 94.515015 -207.778582) (xy 94.568999 -207.786344) (xy 94.621329 -207.801709)
			(xy 94.670939 -207.824366) (xy 94.71682 -207.853852) (xy 94.758037 -207.889567) (xy 94.793752 -207.930784)
			(xy 94.823238 -207.976665) (xy 94.845895 -208.026275) (xy 94.86126 -208.078605) (xy 94.869022 -208.132589)
			(xy 94.869508 -208.159858) (xy 94.869508 -209.023458) (xy 94.869022 -209.050727) (xy 94.86126 -209.104711)
			(xy 94.845895 -209.157041) (xy 94.823238 -209.206651) (xy 94.793752 -209.252532) (xy 94.758037 -209.293749)
			(xy 94.71682 -209.329464) (xy 94.670939 -209.35895) (xy 94.621329 -209.381607) (xy 94.568999 -209.396972)
			(xy 94.515015 -209.404734) (xy 94.460477 -209.404734) (xy 94.406493 -209.396972) (xy 94.354163 -209.381607)
			(xy 94.304553 -209.35895) (xy 94.258672 -209.329464) (xy 94.217455 -209.293749) (xy 94.18174 -209.252532)
			(xy 94.152254 -209.206651) (xy 94.129597 -209.157041) (xy 94.114232 -209.104711) (xy 94.10647 -209.050727)
			(xy 94.105984 -209.023458) (xy 66.861436 -209.023458) (xy 70.818248 -212.98027) (xy 78.812394 -212.98027)
			(xy 78.816423 -212.837949) (xy 78.828498 -212.696084) (xy 78.848579 -212.55513) (xy 78.876602 -212.415537)
			(xy 78.912478 -212.277753) (xy 78.956092 -212.14222) (xy 79.007304 -212.009371) (xy 79.06595 -211.879632)
			(xy 79.131841 -211.753419) (xy 79.204768 -211.631136) (xy 79.284496 -211.513174) (xy 79.37077 -211.399912)
			(xy 79.463314 -211.291713) (xy 79.56183 -211.188922) (xy 79.666005 -211.09187) (xy 79.775503 -211.000866)
			(xy 79.889974 -210.916204) (xy 80.009052 -210.838153) (xy 80.132355 -210.766964) (xy 80.259488 -210.702865)
			(xy 80.390044 -210.646061) (xy 80.523604 -210.596735) (xy 80.659741 -210.555043) (xy 80.798019 -210.52112)
			(xy 80.937994 -210.495075) (xy 81.079219 -210.47699) (xy 81.22124 -210.466925) (xy 81.363604 -210.46491)
			(xy 81.505854 -210.470953) (xy 81.647534 -210.485033) (xy 81.78819 -210.507107) (xy 81.927372 -210.537103)
			(xy 82.064634 -210.574925) (xy 82.199537 -210.620453) (xy 82.331648 -210.673539) (xy 82.460544 -210.734015)
			(xy 82.585812 -210.801686) (xy 82.707051 -210.876336) (xy 82.823872 -210.957725) (xy 82.935902 -211.045593)
			(xy 83.042781 -211.139659) (xy 83.144167 -211.23962) (xy 83.239736 -211.345158) (xy 83.329181 -211.455933)
			(xy 83.412215 -211.571591) (xy 83.488573 -211.691761) (xy 83.55801 -211.816059) (xy 83.620303 -211.944086)
			(xy 83.675254 -212.075433) (xy 83.698081 -212.140038) (xy 94.106492 -212.140038) (xy 94.106492 -211.276438)
			(xy 94.106978 -211.249187) (xy 94.114734 -211.195239) (xy 94.130089 -211.142944) (xy 94.152731 -211.093367)
			(xy 94.182197 -211.047517) (xy 94.217888 -211.006326) (xy 94.259079 -210.970635) (xy 94.304929 -210.941169)
			(xy 94.354506 -210.918527) (xy 94.406801 -210.903172) (xy 94.460749 -210.895416) (xy 94.515251 -210.895416)
			(xy 94.569199 -210.903172) (xy 94.621494 -210.918527) (xy 94.671071 -210.941169) (xy 94.716921 -210.970635)
			(xy 94.758112 -211.006326) (xy 94.793803 -211.047517) (xy 94.823269 -211.093367) (xy 94.845911 -211.142944)
			(xy 94.861266 -211.195239) (xy 94.869022 -211.249187) (xy 94.869508 -211.276438) (xy 94.869508 -212.140038)
			(xy 94.869022 -212.167289) (xy 94.861266 -212.221237) (xy 94.845911 -212.273532) (xy 94.823269 -212.323109)
			(xy 94.793803 -212.368959) (xy 94.758112 -212.41015) (xy 94.716921 -212.445841) (xy 94.671071 -212.475307)
			(xy 94.621494 -212.497949) (xy 94.569199 -212.513304) (xy 94.515251 -212.52106) (xy 94.460749 -212.52106)
			(xy 94.406801 -212.513304) (xy 94.354506 -212.497949) (xy 94.304929 -212.475307) (xy 94.259079 -212.445841)
			(xy 94.217888 -212.41015) (xy 94.182197 -212.368959) (xy 94.152731 -212.323109) (xy 94.130089 -212.273532)
			(xy 94.114734 -212.221237) (xy 94.106978 -212.167289) (xy 94.106492 -212.140038) (xy 83.698081 -212.140038)
			(xy 83.722686 -212.209678) (xy 83.762447 -212.346391) (xy 83.794409 -212.485135) (xy 83.818471 -212.625465)
			(xy 83.834555 -212.766931) (xy 83.842611 -212.909081) (xy 83.843114 -212.98027) (xy 83.842611 -213.051459)
			(xy 83.834555 -213.193609) (xy 83.818471 -213.335075) (xy 83.794409 -213.475405) (xy 83.762447 -213.614149)
			(xy 83.722686 -213.750862) (xy 83.675254 -213.885107) (xy 83.620303 -214.016454) (xy 83.55801 -214.144481)
			(xy 83.488573 -214.268779) (xy 83.412215 -214.388949) (xy 83.329181 -214.504607) (xy 83.239736 -214.615382)
			(xy 83.144167 -214.72092) (xy 83.042781 -214.820881) (xy 82.935902 -214.914947) (xy 82.837077 -214.992458)
			(xy 94.106492 -214.992458) (xy 94.106492 -214.128858) (xy 94.106978 -214.101607) (xy 94.114734 -214.047659)
			(xy 94.130089 -213.995364) (xy 94.152731 -213.945787) (xy 94.182197 -213.899937) (xy 94.217888 -213.858746)
			(xy 94.259079 -213.823055) (xy 94.304929 -213.793589) (xy 94.354506 -213.770947) (xy 94.406801 -213.755592)
			(xy 94.460749 -213.747836) (xy 94.515251 -213.747836) (xy 94.569199 -213.755592) (xy 94.621494 -213.770947)
			(xy 94.671071 -213.793589) (xy 94.716921 -213.823055) (xy 94.758112 -213.858746) (xy 94.793803 -213.899937)
			(xy 94.823269 -213.945787) (xy 94.845911 -213.995364) (xy 94.861266 -214.047659) (xy 94.869022 -214.101607)
			(xy 94.869508 -214.128858) (xy 94.869508 -214.992458) (xy 94.869022 -215.019709) (xy 94.861266 -215.073657)
			(xy 94.845911 -215.125952) (xy 94.823269 -215.175529) (xy 94.793803 -215.221379) (xy 94.758112 -215.26257)
			(xy 94.716921 -215.298261) (xy 94.671071 -215.327727) (xy 94.621494 -215.350369) (xy 94.569199 -215.365724)
			(xy 94.515251 -215.37348) (xy 94.460749 -215.37348) (xy 94.406801 -215.365724) (xy 94.354506 -215.350369)
			(xy 94.304929 -215.327727) (xy 94.259079 -215.298261) (xy 94.217888 -215.26257) (xy 94.182197 -215.221379)
			(xy 94.152731 -215.175529) (xy 94.130089 -215.125952) (xy 94.114734 -215.073657) (xy 94.106978 -215.019709)
			(xy 94.106492 -214.992458) (xy 82.837077 -214.992458) (xy 82.823872 -215.002815) (xy 82.707051 -215.084204)
			(xy 82.585812 -215.158854) (xy 82.460544 -215.226525) (xy 82.331648 -215.287001) (xy 82.199537 -215.340087)
			(xy 82.064634 -215.385615) (xy 81.927372 -215.423437) (xy 81.78819 -215.453433) (xy 81.647534 -215.475507)
			(xy 81.505854 -215.489587) (xy 81.363604 -215.49563) (xy 81.22124 -215.493615) (xy 81.079219 -215.48355)
			(xy 80.937994 -215.465465) (xy 80.798019 -215.43942) (xy 80.659741 -215.405497) (xy 80.523604 -215.363805)
			(xy 80.390044 -215.314479) (xy 80.259488 -215.257675) (xy 80.132355 -215.193576) (xy 80.009052 -215.122387)
			(xy 79.889974 -215.044336) (xy 79.775503 -214.959674) (xy 79.666005 -214.86867) (xy 79.56183 -214.771618)
			(xy 79.463314 -214.668827) (xy 79.37077 -214.560628) (xy 79.284496 -214.447366) (xy 79.204768 -214.329404)
			(xy 79.131841 -214.207121) (xy 79.06595 -214.080908) (xy 79.007304 -213.951169) (xy 78.956092 -213.81832)
			(xy 78.912478 -213.682787) (xy 78.876602 -213.545003) (xy 78.848579 -213.40541) (xy 78.828498 -213.264456)
			(xy 78.816423 -213.122591) (xy 78.812394 -212.98027) (xy 70.818248 -212.98027) (xy 76.838556 -219.000578)
			(xy 76.845957 -219.007418) (xy 76.864555 -219.015135) (xy 76.874624 -219.015564) (xy 84.622386 -219.015564)
			(xy 84.646483 -219.01613) (xy 84.693813 -219.02522) (xy 84.738578 -219.043075) (xy 84.779171 -219.069055)
			(xy 84.814134 -219.102227) (xy 84.828634 -219.121482) (xy 84.836296 -219.130904) (xy 84.857909 -219.141902)
			(xy 84.870036 -219.142564) (xy 92.496894 -219.142564) (xy 92.51347 -219.143126) (xy 92.545488 -219.15173)
			(xy 92.574201 -219.168306) (xy 92.586302 -219.179648) (xy 93.221302 -219.814648) (xy 93.226655 -219.820372)
			(xy 129.049982 -219.820372) (xy 129.049982 -219.765828) (xy 129.057745 -219.71184) (xy 129.073111 -219.659505)
			(xy 129.095769 -219.609891) (xy 129.125257 -219.564005) (xy 129.160975 -219.522783) (xy 129.202196 -219.487064)
			(xy 129.24808 -219.457575) (xy 129.297694 -219.434915) (xy 129.350028 -219.419547) (xy 129.404016 -219.411783)
			(xy 129.431288 -219.411296) (xy 130.447288 -219.411296) (xy 130.474557 -219.411843) (xy 130.528539 -219.419602)
			(xy 130.580867 -219.434966) (xy 130.630476 -219.45762) (xy 130.676357 -219.487104) (xy 130.717574 -219.522818)
			(xy 130.753288 -219.564034) (xy 130.782774 -219.609913) (xy 130.80543 -219.659522) (xy 130.820795 -219.711849)
			(xy 130.828557 -219.765831) (xy 130.828557 -219.820369) (xy 130.820795 -219.874351) (xy 130.80543 -219.926678)
			(xy 130.782774 -219.976287) (xy 130.753288 -220.022166) (xy 130.717574 -220.063382) (xy 130.676357 -220.099096)
			(xy 130.630476 -220.12858) (xy 130.580867 -220.151234) (xy 130.528539 -220.166598) (xy 130.474557 -220.174357)
			(xy 130.447288 -220.17482) (xy 129.431288 -220.17482) (xy 129.404016 -220.174417) (xy 129.350028 -220.166653)
			(xy 129.297694 -220.151285) (xy 129.24808 -220.128625) (xy 129.202196 -220.099136) (xy 129.160975 -220.063417)
			(xy 129.125257 -220.022195) (xy 129.095769 -219.976309) (xy 129.073111 -219.926695) (xy 129.057745 -219.87436)
			(xy 129.049982 -219.820372) (xy 93.226655 -219.820372) (xy 93.23263 -219.826761) (xy 93.249205 -219.855471)
			(xy 93.257828 -219.887482) (xy 93.258386 -219.904056) (xy 93.258386 -222.191072) (xy 93.257816 -222.207645)
			(xy 93.249198 -222.239653) (xy 93.232616 -222.268356) (xy 93.221302 -222.28048) (xy 93.146372 -222.355156)
			(xy 93.139526 -222.362554) (xy 93.131801 -222.381153) (xy 93.131386 -222.391224) (xy 93.131386 -223.678496)
			(xy 93.131808 -223.688567) (xy 93.13952 -223.707174) (xy 93.146372 -223.714564) (xy 93.200728 -223.768666)
			(xy 93.20911 -223.778064) (xy 93.318076 -223.91116) (xy 93.347032 -223.920304) (xy 93.36151 -223.915986)
			(xy 93.383419 -223.910277) (xy 93.42828 -223.904161) (xy 93.450918 -223.903794) (xy 93.476904 -223.904305)
			(xy 93.528236 -223.912438) (xy 93.577664 -223.9285) (xy 93.623971 -223.952097) (xy 93.666017 -223.982647)
			(xy 93.702766 -224.019398) (xy 93.733313 -224.061446) (xy 93.756907 -224.107754) (xy 93.772967 -224.157183)
			(xy 93.781097 -224.208516) (xy 93.781626 -224.234502) (xy 93.781142 -224.260488) (xy 93.773005 -224.311821)
			(xy 93.756932 -224.361246) (xy 93.745558 -224.384616) (xy 93.7387 -224.398078) (xy 93.742002 -224.42805)
			(xy 93.97492 -224.712022) (xy 93.98889 -224.720658) (xy 93.997018 -224.72269) (xy 94.02315 -224.729403)
			(xy 94.072952 -224.750151) (xy 94.118725 -224.77871) (xy 94.159254 -224.81432) (xy 94.193464 -224.856038)
			(xy 94.220447 -224.902756) (xy 94.239488 -224.953235) (xy 94.250081 -225.006136) (xy 94.251526 -225.033078)
			(xy 94.25178 -225.04146) (xy 94.257622 -225.056954) (xy 96.633284 -227.954078) (xy 96.659954 -227.963476)
			(xy 96.673924 -227.960682) (xy 96.690501 -227.957465) (xy 96.724095 -227.95403) (xy 96.74098 -227.953824)
			(xy 96.766969 -227.954306) (xy 96.818308 -227.962435) (xy 96.867744 -227.978495) (xy 96.914057 -228.002093)
			(xy 96.956109 -228.032645) (xy 96.992863 -228.0694) (xy 97.023414 -228.111453) (xy 97.047009 -228.157767)
			(xy 97.063068 -228.207203) (xy 97.071195 -228.258543) (xy 97.071688 -228.284532) (xy 97.071279 -228.30789)
			(xy 97.064702 -228.354141) (xy 97.051696 -228.399011) (xy 97.032519 -228.44161) (xy 97.02038 -228.46157)
			(xy 97.012506 -228.473762) (xy 97.011998 -228.501956) (xy 97.156778 -228.751384) (xy 97.18167 -228.764846)
			(xy 97.195894 -228.764084) (xy 97.211134 -228.76383) (xy 97.237116 -228.764342) (xy 97.288441 -228.772476)
			(xy 97.337861 -228.788538) (xy 97.38416 -228.812133) (xy 97.426199 -228.84268) (xy 97.462942 -228.879427)
			(xy 97.493484 -228.921469) (xy 97.517075 -228.96777) (xy 97.533132 -229.017192) (xy 97.54126 -229.068518)
			(xy 97.54126 -229.120482) (xy 97.533132 -229.171808) (xy 97.517075 -229.22123) (xy 97.493484 -229.267531)
			(xy 97.462942 -229.309573) (xy 97.426199 -229.34632) (xy 97.38416 -229.376867) (xy 97.337861 -229.400462)
			(xy 97.288441 -229.416524) (xy 97.237116 -229.424658) (xy 97.211134 -229.425246) (xy 97.193608 -229.424738)
			(xy 97.179384 -229.423976) (xy 97.154238 -229.437692) (xy 97.010728 -229.685088) (xy 97.011236 -229.713282)
			(xy 97.01911 -229.725474) (xy 97.03156 -229.745563) (xy 97.051218 -229.788542) (xy 97.064556 -229.833882)
			(xy 97.071301 -229.880659) (xy 97.071688 -229.90429) (xy 97.071282 -229.927649) (xy 97.06471 -229.973902)
			(xy 97.051709 -230.018775) (xy 97.032536 -230.061378) (xy 97.02038 -230.081328) (xy 97.012506 -230.09352)
			(xy 97.011998 -230.121714) (xy 97.156778 -230.371396) (xy 97.18167 -230.384858) (xy 97.195894 -230.384096)
			(xy 97.211134 -230.383842) (xy 97.237115 -230.384354) (xy 97.288438 -230.392488) (xy 97.337856 -230.40855)
			(xy 97.384154 -230.432144) (xy 97.426191 -230.462689) (xy 97.462933 -230.499435) (xy 97.493474 -230.541475)
			(xy 97.517064 -230.587775) (xy 97.53312 -230.637195) (xy 97.541248 -230.688518) (xy 97.541248 -230.740482)
			(xy 97.53312 -230.791805) (xy 97.517064 -230.841225) (xy 97.493474 -230.887525) (xy 97.462933 -230.929565)
			(xy 97.426191 -230.966311) (xy 97.384154 -230.996856) (xy 97.337856 -231.02045) (xy 97.288438 -231.036512)
			(xy 97.237115 -231.044646) (xy 97.211134 -231.045258) (xy 97.193608 -231.04475) (xy 97.179384 -231.043988)
			(xy 97.154238 -231.057704) (xy 97.010728 -231.3051) (xy 97.011236 -231.333294) (xy 97.01911 -231.345486)
			(xy 97.03156 -231.365575) (xy 97.051216 -231.408554) (xy 97.064552 -231.453894) (xy 97.071296 -231.500672)
			(xy 97.071688 -231.524302) (xy 97.071281 -231.547661) (xy 97.064708 -231.593913) (xy 97.051705 -231.638785)
			(xy 97.032531 -231.681387) (xy 97.02038 -231.70134) (xy 97.012506 -231.713532) (xy 97.011998 -231.741726)
			(xy 97.156778 -231.991154) (xy 97.181416 -232.004616) (xy 97.195894 -232.003854) (xy 97.211134 -232.0036)
			(xy 97.237119 -232.004112) (xy 97.288448 -232.012247) (xy 97.337873 -232.02831) (xy 97.384176 -232.051907)
			(xy 97.426219 -232.082457) (xy 97.462965 -232.119207) (xy 97.49351 -232.161253) (xy 97.517103 -232.207559)
			(xy 97.533161 -232.256985) (xy 97.541291 -232.308315) (xy 97.541291 -232.360285) (xy 97.533161 -232.411615)
			(xy 97.517103 -232.461041) (xy 97.49351 -232.507347) (xy 97.462965 -232.549393) (xy 97.426219 -232.586143)
			(xy 97.384176 -232.616693) (xy 97.337873 -232.64029) (xy 97.288448 -232.656353) (xy 97.237119 -232.664488)
			(xy 97.211134 -232.665016) (xy 97.193608 -232.664508) (xy 97.179384 -232.663746) (xy 97.154238 -232.677462)
			(xy 97.010728 -232.925112) (xy 97.011236 -232.953306) (xy 97.01911 -232.965498) (xy 97.031559 -232.985587)
			(xy 97.051214 -233.028567) (xy 97.064548 -233.073907) (xy 97.07129 -233.120684) (xy 97.071688 -233.144314)
			(xy 97.071204 -233.170302) (xy 97.063071 -233.221638) (xy 97.047007 -233.271069) (xy 97.023408 -233.317379)
			(xy 96.992855 -233.359427) (xy 96.956101 -233.396177) (xy 96.91405 -233.426726) (xy 96.867738 -233.45032)
			(xy 96.818305 -233.466379) (xy 96.766968 -233.474506) (xy 96.74098 -233.475022) (xy 96.723708 -233.474514)
			(xy 96.70923 -233.473752) (xy 96.684338 -233.487214) (xy 96.540574 -233.734864) (xy 96.541336 -233.763058)
			(xy 96.54921 -233.775504) (xy 96.561659 -233.795593) (xy 96.581313 -233.838573) (xy 96.594646 -233.883913)
			(xy 96.601387 -233.93069) (xy 96.601788 -233.95432) (xy 96.601387 -233.977722) (xy 96.594795 -234.02406)
			(xy 96.581731 -234.069005) (xy 96.562456 -234.111656) (xy 96.550226 -234.131612) (xy 96.542606 -234.143804)
			(xy 96.542098 -234.171998) (xy 96.686624 -234.421172) (xy 96.711516 -234.434634) (xy 96.72574 -234.433872)
			(xy 96.74098 -234.433618) (xy 96.76697 -234.4341) (xy 96.818309 -234.442229) (xy 96.867745 -234.458289)
			(xy 96.914059 -234.481886) (xy 96.956111 -234.512439) (xy 96.992865 -234.549194) (xy 97.023417 -234.591246)
			(xy 97.047013 -234.637561) (xy 97.063073 -234.686997) (xy 97.071201 -234.738336) (xy 97.071688 -234.764326)
			(xy 97.071287 -234.787728) (xy 97.064694 -234.834066) (xy 97.051629 -234.87901) (xy 97.032354 -234.921661)
			(xy 97.020126 -234.941618) (xy 97.012506 -234.953556) (xy 97.011998 -234.98175) (xy 97.156524 -235.231178)
			(xy 97.181416 -235.24464) (xy 97.19564 -235.243878) (xy 97.211134 -235.243624) (xy 97.237117 -235.244136)
			(xy 97.288442 -235.25227) (xy 97.337864 -235.268332) (xy 97.384164 -235.291928) (xy 97.426203 -235.322475)
			(xy 97.462947 -235.359223) (xy 97.49349 -235.401265) (xy 97.517081 -235.447568) (xy 97.533138 -235.496991)
			(xy 97.541267 -235.548317) (xy 97.541267 -235.600283) (xy 97.533138 -235.651609) (xy 97.517081 -235.701032)
			(xy 97.49349 -235.747335) (xy 97.462947 -235.789377) (xy 97.426203 -235.826125) (xy 97.384164 -235.856672)
			(xy 97.337864 -235.880268) (xy 97.288442 -235.89633) (xy 97.237117 -235.904464) (xy 97.211134 -235.90504)
			(xy 97.193862 -235.904532) (xy 97.179384 -235.90377) (xy 97.154238 -235.917486) (xy 97.010728 -236.165136)
			(xy 97.011236 -236.19333) (xy 97.01911 -236.205522) (xy 97.031557 -236.225611) (xy 97.051209 -236.268591)
			(xy 97.06454 -236.313932) (xy 97.071279 -236.360708) (xy 97.071688 -236.384338) (xy 97.071279 -236.407696)
			(xy 97.064701 -236.453947) (xy 97.051694 -236.498816) (xy 97.032517 -236.541414) (xy 97.02038 -236.561376)
			(xy 97.012506 -236.573568) (xy 97.011998 -236.601762) (xy 97.156778 -236.85119) (xy 97.18167 -236.864652)
			(xy 97.195894 -236.86389) (xy 97.211134 -236.863636) (xy 97.23712 -236.864122) (xy 97.288452 -236.872257)
			(xy 97.337879 -236.888323) (xy 97.384185 -236.911923) (xy 97.426228 -236.942477) (xy 97.462974 -236.979232)
			(xy 97.493517 -237.021282) (xy 97.517107 -237.067593) (xy 97.533161 -237.117024) (xy 97.541284 -237.168358)
			(xy 97.541842 -237.194344) (xy 97.541439 -237.217746) (xy 97.534843 -237.264082) (xy 97.521775 -237.309024)
			(xy 97.502496 -237.351672) (xy 97.49028 -237.371636) (xy 97.48266 -237.383574) (xy 97.482152 -237.411768)
			(xy 97.626678 -237.661196) (xy 97.65157 -237.674658) (xy 97.665794 -237.673896) (xy 97.681034 -237.673642)
			(xy 97.707015 -237.674154) (xy 97.758338 -237.682288) (xy 97.807756 -237.69835) (xy 97.854054 -237.721944)
			(xy 97.896091 -237.752489) (xy 97.932833 -237.789235) (xy 97.963374 -237.831275) (xy 97.986964 -237.877575)
			(xy 98.00302 -237.926995) (xy 98.011148 -237.978318) (xy 98.011148 -238.030282) (xy 98.00302 -238.081605)
			(xy 97.986964 -238.131025) (xy 97.963374 -238.177325) (xy 97.932833 -238.219365) (xy 97.896091 -238.256111)
			(xy 97.854054 -238.286656) (xy 97.807756 -238.31025) (xy 97.758338 -238.326312) (xy 97.707015 -238.334446)
			(xy 97.681034 -238.335058) (xy 97.657289 -238.334654) (xy 97.610286 -238.327863) (xy 97.564744 -238.314401)
			(xy 97.521602 -238.294547) (xy 97.501456 -238.281972) (xy 97.489264 -238.274098) (xy 97.46107 -238.273336)
			(xy 96.614234 -238.759746) (xy 96.600772 -238.784384) (xy 96.601534 -238.798862) (xy 96.601788 -238.814356)
			(xy 96.601366 -238.837725) (xy 96.594745 -238.883991) (xy 96.581672 -238.928864) (xy 96.562407 -238.971447)
			(xy 96.550226 -238.991394) (xy 96.542606 -239.003586) (xy 96.542098 -239.03178) (xy 96.686878 -239.281208)
			(xy 96.711516 -239.29467) (xy 96.72574 -239.293908) (xy 96.74098 -239.293654) (xy 96.766969 -239.294162)
			(xy 96.818308 -239.30229) (xy 96.867744 -239.318349) (xy 96.914059 -239.341943) (xy 96.956113 -239.372492)
			(xy 96.992871 -239.409243) (xy 97.023427 -239.451291) (xy 97.047029 -239.497602) (xy 97.063097 -239.547035)
			(xy 97.071233 -239.598373) (xy 97.071688 -239.624362) (xy 97.071265 -239.647731) (xy 97.064644 -239.693997)
			(xy 97.05157 -239.738869) (xy 97.032305 -239.781451) (xy 97.020126 -239.8014) (xy 97.012506 -239.813592)
			(xy 97.011998 -239.841786) (xy 97.156524 -240.091214) (xy 97.181416 -240.104676) (xy 97.19564 -240.103914)
			(xy 97.211134 -240.10366) (xy 97.237122 -240.104172) (xy 97.288457 -240.112308) (xy 97.337888 -240.128373)
			(xy 97.384197 -240.151973) (xy 97.426245 -240.182527) (xy 97.462996 -240.219281) (xy 97.493545 -240.261332)
			(xy 97.51714 -240.307643) (xy 97.5332 -240.357076) (xy 97.54133 -240.408412) (xy 97.54133 -240.460388)
			(xy 97.5332 -240.511724) (xy 97.51714 -240.561157) (xy 97.493545 -240.607468) (xy 97.462996 -240.649519)
			(xy 97.426245 -240.686273) (xy 97.384197 -240.716827) (xy 97.337888 -240.740427) (xy 97.288457 -240.756492)
			(xy 97.237122 -240.764628) (xy 97.211134 -240.765076) (xy 97.193608 -240.764568) (xy 97.179384 -240.763806)
			(xy 97.154238 -240.777522) (xy 97.010728 -241.025172) (xy 97.011236 -241.053366) (xy 97.01911 -241.065558)
			(xy 97.031561 -241.085646) (xy 97.051221 -241.128625) (xy 97.064561 -241.173965) (xy 97.071309 -241.220743)
			(xy 97.071688 -241.244374) (xy 97.071207 -241.270364) (xy 97.063079 -241.321705) (xy 97.047018 -241.371141)
			(xy 97.023422 -241.417457) (xy 96.99287 -241.45951) (xy 96.956115 -241.496266) (xy 96.914062 -241.526819)
			(xy 96.867747 -241.550416) (xy 96.81831 -241.566477) (xy 96.76697 -241.574606) (xy 96.74098 -241.575082)
			(xy 96.723708 -241.574574) (xy 96.70923 -241.573812) (xy 96.684338 -241.587274) (xy 96.540574 -241.834924)
			(xy 96.541336 -241.863118) (xy 96.54921 -241.875564) (xy 96.561661 -241.895653) (xy 96.58132 -241.938631)
			(xy 96.594659 -241.983972) (xy 96.601406 -242.030749) (xy 96.601788 -242.05438) (xy 96.601383 -242.077781)
			(xy 96.594783 -242.124116) (xy 96.581712 -242.169056) (xy 96.562431 -242.211702) (xy 96.550226 -242.231672)
			(xy 96.542606 -242.243864) (xy 96.542098 -242.272058) (xy 96.686624 -242.521232) (xy 96.711516 -242.534694)
			(xy 96.72574 -242.533932) (xy 96.74098 -242.533678) (xy 96.766971 -242.53416) (xy 96.818313 -242.542288)
			(xy 96.867751 -242.558349) (xy 96.914068 -242.581945) (xy 96.956123 -242.612497) (xy 96.992881 -242.649251)
			(xy 97.023437 -242.691303) (xy 97.047038 -242.737618) (xy 97.063104 -242.787054) (xy 97.071238 -242.838395)
			(xy 97.071688 -242.864386) (xy 97.071283 -242.887787) (xy 97.064682 -242.934121) (xy 97.05161 -242.979061)
			(xy 97.032329 -243.021706) (xy 97.020126 -243.041678) (xy 97.012506 -243.053616) (xy 97.011998 -243.08181)
			(xy 97.156524 -243.331238) (xy 97.181416 -243.3447) (xy 97.19564 -243.343938) (xy 97.211134 -243.343684)
			(xy 97.23712 -243.344196) (xy 97.288452 -243.352331) (xy 97.337879 -243.368395) (xy 97.384185 -243.391994)
			(xy 97.426229 -243.422545) (xy 97.462977 -243.459297) (xy 97.493524 -243.501344) (xy 97.517118 -243.547653)
			(xy 97.533177 -243.597081) (xy 97.541307 -243.648414) (xy 97.541307 -243.6744) (xy 108.185132 -243.6744)
			(xy 108.189304 -243.624054) (xy 108.201706 -243.575081) (xy 108.222 -243.528817) (xy 108.249632 -243.486525)
			(xy 108.283849 -243.449358) (xy 108.323717 -243.418331) (xy 108.368148 -243.394288) (xy 108.41593 -243.377887)
			(xy 108.465761 -243.369575) (xy 108.49102 -243.369084) (xy 109.431074 -243.369084) (xy 109.456332 -243.369591)
			(xy 109.506161 -243.377902) (xy 109.553942 -243.394301) (xy 109.598371 -243.418342) (xy 109.638238 -243.449368)
			(xy 109.672453 -243.486533) (xy 109.700085 -243.528823) (xy 109.720378 -243.575085) (xy 109.73278 -243.624056)
			(xy 109.736952 -243.6744) (xy 109.73278 -243.724744) (xy 109.720378 -243.773715) (xy 109.700085 -243.819977)
			(xy 109.672453 -243.862267) (xy 109.638238 -243.899432) (xy 109.598371 -243.930458) (xy 109.553942 -243.954499)
			(xy 109.506161 -243.970898) (xy 109.456332 -243.979209) (xy 109.431074 -243.9797) (xy 108.49102 -243.9797)
			(xy 108.465761 -243.979225) (xy 108.41593 -243.970913) (xy 108.368148 -243.954512) (xy 108.323717 -243.930469)
			(xy 108.283849 -243.899442) (xy 108.249632 -243.862275) (xy 108.222 -243.819983) (xy 108.201706 -243.773719)
			(xy 108.189304 -243.724746) (xy 108.185132 -243.6744) (xy 97.541307 -243.6744) (xy 97.541307 -243.700386)
			(xy 97.533177 -243.751719) (xy 97.517118 -243.801147) (xy 97.493524 -243.847456) (xy 97.462977 -243.889503)
			(xy 97.426229 -243.926255) (xy 97.384185 -243.956806) (xy 97.337879 -243.980405) (xy 97.288452 -243.996469)
			(xy 97.23712 -244.004604) (xy 97.211134 -244.0051) (xy 97.193608 -244.004592) (xy 97.179384 -244.00383)
			(xy 97.154238 -244.017546) (xy 97.010728 -244.265196) (xy 97.011236 -244.29339) (xy 97.01911 -244.305582)
			(xy 97.03156 -244.325671) (xy 97.051217 -244.36865) (xy 97.064553 -244.41399) (xy 97.071298 -244.460768)
			(xy 97.071688 -244.484398) (xy 97.071688 -244.4844) (xy 97.374883 -244.4844) (xy 97.379059 -244.434011)
			(xy 97.391472 -244.384997) (xy 97.411784 -244.338695) (xy 97.43944 -244.296368) (xy 97.473686 -244.259171)
			(xy 97.513588 -244.228118) (xy 97.558057 -244.204057) (xy 97.605881 -244.187644) (xy 97.655753 -244.179326)
			(xy 97.681034 -244.178836) (xy 98.621088 -244.178836) (xy 98.646367 -244.179332) (xy 98.696236 -244.187652)
			(xy 98.744056 -244.204067) (xy 98.788521 -244.228129) (xy 98.82842 -244.259181) (xy 98.862663 -244.296378)
			(xy 98.890316 -244.338703) (xy 98.910626 -244.385003) (xy 98.923037 -244.434014) (xy 98.927213 -244.4844)
			(xy 100.194783 -244.4844) (xy 100.198959 -244.434011) (xy 100.211373 -244.384996) (xy 100.231685 -244.338693)
			(xy 100.259342 -244.296365) (xy 100.293589 -244.259168) (xy 100.333492 -244.228115) (xy 100.377963 -244.204054)
			(xy 100.425787 -244.187642) (xy 100.475661 -244.179326) (xy 100.500942 -244.178836) (xy 101.440996 -244.178836)
			(xy 101.466275 -244.179333) (xy 101.516143 -244.187654) (xy 101.563961 -244.204069) (xy 101.608426 -244.228131)
			(xy 101.648323 -244.259184) (xy 101.682565 -244.29638) (xy 101.710217 -244.338705) (xy 101.730526 -244.385005)
			(xy 101.742937 -244.434015) (xy 101.747113 -244.4844) (xy 103.014983 -244.4844) (xy 103.019159 -244.434014)
			(xy 103.03157 -244.385003) (xy 103.051879 -244.338704) (xy 103.079532 -244.296378) (xy 103.113774 -244.259181)
			(xy 103.153672 -244.228128) (xy 103.198137 -244.204065) (xy 103.245956 -244.18765) (xy 103.295825 -244.179329)
			(xy 103.321104 -244.178836) (xy 104.261158 -244.178836) (xy 104.286439 -244.17933) (xy 104.336312 -244.187646)
			(xy 104.384136 -244.204058) (xy 104.428605 -244.228118) (xy 104.468508 -244.259171) (xy 104.502755 -244.296368)
			(xy 104.530412 -244.338695) (xy 104.550724 -244.384997) (xy 104.563137 -244.434011) (xy 104.567313 -244.4844)
			(xy 105.834883 -244.4844) (xy 105.839059 -244.434014) (xy 105.851471 -244.385002) (xy 105.87178 -244.338701)
			(xy 105.899434 -244.296375) (xy 105.933678 -244.259178) (xy 105.973577 -244.228125) (xy 106.018043 -244.204063)
			(xy 106.065863 -244.187648) (xy 106.115732 -244.179328) (xy 106.141012 -244.178836) (xy 107.081066 -244.178836)
			(xy 107.106346 -244.17933) (xy 107.156218 -244.187647) (xy 107.204041 -244.20406) (xy 107.24851 -244.228121)
			(xy 107.288411 -244.259174) (xy 107.322657 -244.29637) (xy 107.350313 -244.338697) (xy 107.370624 -244.384999)
			(xy 107.383037 -244.434012) (xy 107.387213 -244.4844) (xy 107.383037 -244.534788) (xy 107.370624 -244.583801)
			(xy 107.350313 -244.630103) (xy 107.322657 -244.67243) (xy 107.288411 -244.709626) (xy 107.24851 -244.740679)
			(xy 107.204041 -244.76474) (xy 107.156218 -244.781153) (xy 107.106346 -244.78947) (xy 107.081066 -244.78996)
			(xy 106.141012 -244.78996) (xy 106.115732 -244.789472) (xy 106.065863 -244.781152) (xy 106.018043 -244.764737)
			(xy 105.973577 -244.740675) (xy 105.933678 -244.709622) (xy 105.899434 -244.672425) (xy 105.87178 -244.630099)
			(xy 105.851471 -244.583798) (xy 105.839059 -244.534786) (xy 105.834883 -244.4844) (xy 104.567313 -244.4844)
			(xy 104.563137 -244.534789) (xy 104.550724 -244.583803) (xy 104.530412 -244.630105) (xy 104.502755 -244.672432)
			(xy 104.468508 -244.709629) (xy 104.428605 -244.740682) (xy 104.384136 -244.764742) (xy 104.336312 -244.781154)
			(xy 104.286439 -244.78947) (xy 104.261158 -244.78996) (xy 103.321104 -244.78996) (xy 103.295825 -244.789471)
			(xy 103.245956 -244.78115) (xy 103.198137 -244.764735) (xy 103.153672 -244.740672) (xy 103.113774 -244.709619)
			(xy 103.079532 -244.672422) (xy 103.051879 -244.630096) (xy 103.03157 -244.583797) (xy 103.019159 -244.534786)
			(xy 103.014983 -244.4844) (xy 101.747113 -244.4844) (xy 101.742937 -244.534785) (xy 101.730526 -244.583795)
			(xy 101.710217 -244.630095) (xy 101.682565 -244.67242) (xy 101.648323 -244.709616) (xy 101.608426 -244.740669)
			(xy 101.563961 -244.764731) (xy 101.516143 -244.781146) (xy 101.466275 -244.789467) (xy 101.440996 -244.78996)
			(xy 100.500942 -244.78996) (xy 100.475661 -244.789474) (xy 100.425787 -244.781158) (xy 100.377963 -244.764746)
			(xy 100.333492 -244.740685) (xy 100.293589 -244.709632) (xy 100.259342 -244.672435) (xy 100.231685 -244.630107)
			(xy 100.211373 -244.583804) (xy 100.198959 -244.534789) (xy 100.194783 -244.4844) (xy 98.927213 -244.4844)
			(xy 98.923037 -244.534786) (xy 98.910626 -244.583797) (xy 98.890316 -244.630097) (xy 98.862663 -244.672422)
			(xy 98.82842 -244.709619) (xy 98.788521 -244.740671) (xy 98.744056 -244.764733) (xy 98.696236 -244.781148)
			(xy 98.646367 -244.789468) (xy 98.621088 -244.78996) (xy 97.681034 -244.78996) (xy 97.655753 -244.789474)
			(xy 97.605881 -244.781156) (xy 97.558057 -244.764743) (xy 97.513588 -244.740682) (xy 97.473686 -244.709629)
			(xy 97.43944 -244.672432) (xy 97.411784 -244.630105) (xy 97.391472 -244.583803) (xy 97.379059 -244.534789)
			(xy 97.374883 -244.4844) (xy 97.071688 -244.4844) (xy 97.071205 -244.510387) (xy 97.063074 -244.561724)
			(xy 97.047012 -244.611158) (xy 97.023414 -244.65747) (xy 96.992861 -244.69952) (xy 96.956106 -244.736273)
			(xy 96.914055 -244.766823) (xy 96.867741 -244.790418) (xy 96.818307 -244.806478) (xy 96.766969 -244.814606)
			(xy 96.74098 -244.815106) (xy 96.723708 -244.814598) (xy 96.70923 -244.813836) (xy 96.684338 -244.827298)
			(xy 96.540574 -245.074948) (xy 96.541336 -245.103142) (xy 96.54921 -245.115588) (xy 96.56166 -245.135677)
			(xy 96.581316 -245.178656) (xy 96.594651 -245.223997) (xy 96.601395 -245.270774) (xy 96.601788 -245.2944)
			(xy 108.185144 -245.2944) (xy 108.189316 -245.244056) (xy 108.201717 -245.195085) (xy 108.222011 -245.148823)
			(xy 108.249642 -245.106533) (xy 108.283857 -245.069367) (xy 108.323723 -245.038341) (xy 108.368153 -245.014299)
			(xy 108.415933 -244.997899) (xy 108.465762 -244.989587) (xy 108.49102 -244.989096) (xy 109.431074 -244.989096)
			(xy 109.456333 -244.989579) (xy 109.506164 -244.99789) (xy 109.553947 -245.01429) (xy 109.598378 -245.038332)
			(xy 109.638246 -245.069359) (xy 109.672463 -245.106526) (xy 109.700095 -245.148818) (xy 109.72039 -245.195081)
			(xy 109.732792 -245.244054) (xy 109.736964 -245.2944) (xy 109.732792 -245.344746) (xy 109.72039 -245.393719)
			(xy 109.700095 -245.439982) (xy 109.672463 -245.482274) (xy 109.638246 -245.519441) (xy 109.598378 -245.550468)
			(xy 109.553947 -245.57451) (xy 109.506164 -245.59091) (xy 109.456333 -245.599221) (xy 109.431074 -245.599712)
			(xy 108.49102 -245.599712) (xy 108.465762 -245.599213) (xy 108.415933 -245.590901) (xy 108.368153 -245.574501)
			(xy 108.323723 -245.550459) (xy 108.283857 -245.519433) (xy 108.249642 -245.482267) (xy 108.222011 -245.439977)
			(xy 108.201717 -245.393715) (xy 108.189316 -245.344744) (xy 108.185144 -245.2944) (xy 96.601788 -245.2944)
			(xy 96.601788 -245.294404) (xy 96.601381 -245.317805) (xy 96.594778 -245.364138) (xy 96.581704 -245.409076)
			(xy 96.562422 -245.45172) (xy 96.550226 -245.471696) (xy 96.542606 -245.483888) (xy 96.542098 -245.512082)
			(xy 96.686624 -245.761256) (xy 96.711516 -245.774718) (xy 96.72574 -245.773956) (xy 96.74098 -245.773702)
			(xy 96.76697 -245.774184) (xy 96.81831 -245.782312) (xy 96.867747 -245.798373) (xy 96.914062 -245.82197)
			(xy 96.956116 -245.852522) (xy 96.992872 -245.889277) (xy 97.023425 -245.931329) (xy 97.047023 -245.977644)
			(xy 97.063085 -246.02708) (xy 97.071216 -246.07842) (xy 97.071688 -246.1044) (xy 97.374895 -246.1044)
			(xy 97.379071 -246.054013) (xy 97.391483 -246.005001) (xy 97.411794 -245.958701) (xy 97.439449 -245.916375)
			(xy 97.473694 -245.879179) (xy 97.513595 -245.848128) (xy 97.558062 -245.824068) (xy 97.605884 -245.807655)
			(xy 97.655754 -245.799338) (xy 97.681034 -245.798848) (xy 98.621088 -245.798848) (xy 98.646368 -245.79932)
			(xy 98.696239 -245.80764) (xy 98.744061 -245.824056) (xy 98.788528 -245.848119) (xy 98.828428 -245.879173)
			(xy 98.862672 -245.91637) (xy 98.890327 -245.958698) (xy 98.910637 -246.004999) (xy 98.923049 -246.054012)
			(xy 98.927225 -246.1044) (xy 100.194795 -246.1044) (xy 100.198971 -246.054012) (xy 100.211384 -246.005)
			(xy 100.231695 -245.958699) (xy 100.259351 -245.916373) (xy 100.293597 -245.879177) (xy 100.333499 -245.848125)
			(xy 100.377968 -245.824065) (xy 100.42579 -245.807654) (xy 100.475662 -245.799338) (xy 100.500942 -245.798848)
			(xy 101.440996 -245.798848) (xy 101.466276 -245.799321) (xy 101.516146 -245.807642) (xy 101.563966 -245.824058)
			(xy 101.608432 -245.848121) (xy 101.648331 -245.879175) (xy 101.682574 -245.916373) (xy 101.710228 -245.9587)
			(xy 101.730538 -246.005001) (xy 101.742949 -246.054013) (xy 101.747125 -246.1044) (xy 103.014995 -246.1044)
			(xy 103.01917 -246.054016) (xy 103.031581 -246.005007) (xy 103.05189 -245.958709) (xy 103.079542 -245.916385)
			(xy 103.113783 -245.87919) (xy 103.153679 -245.848138) (xy 103.198142 -245.824076) (xy 103.245959 -245.807661)
			(xy 103.295826 -245.799341) (xy 103.321104 -245.798848) (xy 104.261158 -245.798848) (xy 104.28644 -245.799318)
			(xy 104.336315 -245.807634) (xy 104.38414 -245.824047) (xy 104.428612 -245.848108) (xy 104.468516 -245.879162)
			(xy 104.502764 -245.91636) (xy 104.530422 -245.958689) (xy 104.550735 -246.004993) (xy 104.563149 -246.054009)
			(xy 104.567325 -246.1044) (xy 105.834895 -246.1044) (xy 105.839071 -246.054016) (xy 105.851482 -246.005006)
			(xy 105.871791 -245.958707) (xy 105.899444 -245.916383) (xy 105.933686 -245.879187) (xy 105.973583 -245.848135)
			(xy 106.018047 -245.824074) (xy 106.065866 -245.80766) (xy 106.115733 -245.79934) (xy 106.141012 -245.798848)
			(xy 107.081066 -245.798848) (xy 107.106347 -245.799318) (xy 107.156221 -245.807636) (xy 107.204046 -245.824049)
			(xy 107.248516 -245.848111) (xy 107.288419 -245.879165) (xy 107.322666 -245.916363) (xy 107.350323 -245.958691)
			(xy 107.370636 -246.004995) (xy 107.383049 -246.05401) (xy 107.387225 -246.1044) (xy 107.383049 -246.15479)
			(xy 107.370636 -246.203805) (xy 107.350323 -246.250109) (xy 107.322666 -246.292437) (xy 107.288419 -246.329635)
			(xy 107.248516 -246.360689) (xy 107.204046 -246.384751) (xy 107.156221 -246.401164) (xy 107.106347 -246.409482)
			(xy 107.081066 -246.409972) (xy 106.141012 -246.409972) (xy 106.115733 -246.40946) (xy 106.065866 -246.40114)
			(xy 106.018047 -246.384726) (xy 105.973583 -246.360665) (xy 105.933686 -246.329613) (xy 105.899444 -246.292417)
			(xy 105.871791 -246.250093) (xy 105.851482 -246.203794) (xy 105.839071 -246.154784) (xy 105.834895 -246.1044)
			(xy 104.567325 -246.1044) (xy 104.563149 -246.154791) (xy 104.550735 -246.203807) (xy 104.530422 -246.250111)
			(xy 104.502764 -246.29244) (xy 104.468516 -246.329638) (xy 104.428612 -246.360692) (xy 104.38414 -246.384753)
			(xy 104.336315 -246.401166) (xy 104.28644 -246.409482) (xy 104.261158 -246.409972) (xy 103.321104 -246.409972)
			(xy 103.295826 -246.409459) (xy 103.245959 -246.401139) (xy 103.198142 -246.384724) (xy 103.153679 -246.360662)
			(xy 103.113783 -246.32961) (xy 103.079542 -246.292415) (xy 103.05189 -246.250091) (xy 103.031581 -246.203793)
			(xy 103.01917 -246.154784) (xy 103.014995 -246.1044) (xy 101.747125 -246.1044) (xy 101.742949 -246.154787)
			(xy 101.730538 -246.203799) (xy 101.710228 -246.2501) (xy 101.682574 -246.292427) (xy 101.648331 -246.329625)
			(xy 101.608432 -246.360679) (xy 101.563966 -246.384742) (xy 101.516146 -246.401158) (xy 101.466276 -246.409479)
			(xy 101.440996 -246.409972) (xy 100.500942 -246.409972) (xy 100.475662 -246.409462) (xy 100.42579 -246.401146)
			(xy 100.377968 -246.384735) (xy 100.333499 -246.360675) (xy 100.293597 -246.329623) (xy 100.259351 -246.292427)
			(xy 100.231695 -246.250101) (xy 100.211384 -246.2038) (xy 100.198971 -246.154788) (xy 100.194795 -246.1044)
			(xy 98.927225 -246.1044) (xy 98.923049 -246.154788) (xy 98.910637 -246.203801) (xy 98.890327 -246.250102)
			(xy 98.862672 -246.29243) (xy 98.828428 -246.329627) (xy 98.788528 -246.360681) (xy 98.744061 -246.384744)
			(xy 98.696239 -246.40116) (xy 98.646368 -246.40948) (xy 98.621088 -246.409972) (xy 97.681034 -246.409972)
			(xy 97.655754 -246.409462) (xy 97.605884 -246.401145) (xy 97.558062 -246.384732) (xy 97.513595 -246.360672)
			(xy 97.473694 -246.329621) (xy 97.439449 -246.292425) (xy 97.411794 -246.250099) (xy 97.391483 -246.203799)
			(xy 97.379071 -246.154787) (xy 97.374895 -246.1044) (xy 97.071688 -246.1044) (xy 97.071688 -246.10441)
			(xy 97.071281 -246.127811) (xy 97.064677 -246.174143) (xy 97.051602 -246.219081) (xy 97.032319 -246.261725)
			(xy 97.020126 -246.281702) (xy 97.012506 -246.29364) (xy 97.011998 -246.321834) (xy 97.156524 -246.571262)
			(xy 97.181416 -246.584724) (xy 97.19564 -246.583962) (xy 97.211134 -246.583708) (xy 97.237118 -246.58422)
			(xy 97.288446 -246.592354) (xy 97.33787 -246.608418) (xy 97.384172 -246.632014) (xy 97.426214 -246.662563)
			(xy 97.462959 -246.699312) (xy 97.493504 -246.741357) (xy 97.517095 -246.787662) (xy 97.533154 -246.837087)
			(xy 97.541283 -246.888416) (xy 97.541283 -246.9144) (xy 108.185156 -246.9144) (xy 108.189328 -246.864058)
			(xy 108.201729 -246.815089) (xy 108.222021 -246.768829) (xy 108.249651 -246.72654) (xy 108.283865 -246.689376)
			(xy 108.32373 -246.658351) (xy 108.368157 -246.63431) (xy 108.415936 -246.617911) (xy 108.465763 -246.609599)
			(xy 108.49102 -246.609108) (xy 109.431074 -246.609108) (xy 109.456334 -246.609567) (xy 109.506167 -246.617878)
			(xy 109.553951 -246.634279) (xy 109.598385 -246.658322) (xy 109.638254 -246.68935) (xy 109.672472 -246.726518)
			(xy 109.700106 -246.768812) (xy 109.720401 -246.815077) (xy 109.732804 -246.864052) (xy 109.736976 -246.9144)
			(xy 109.732804 -246.964748) (xy 109.720401 -247.013723) (xy 109.700106 -247.059988) (xy 109.672472 -247.102282)
			(xy 109.638254 -247.13945) (xy 109.598385 -247.170478) (xy 109.553951 -247.194521) (xy 109.506167 -247.210922)
			(xy 109.456334 -247.219233) (xy 109.431074 -247.219724) (xy 108.49102 -247.219724) (xy 108.465763 -247.219201)
			(xy 108.415936 -247.210889) (xy 108.368157 -247.19449) (xy 108.32373 -247.170449) (xy 108.283865 -247.139424)
			(xy 108.249651 -247.10226) (xy 108.222021 -247.059971) (xy 108.201729 -247.013711) (xy 108.189328 -246.964742)
			(xy 108.185156 -246.9144) (xy 97.541283 -246.9144) (xy 97.541283 -246.940384) (xy 97.533154 -246.991713)
			(xy 97.517095 -247.041138) (xy 97.493504 -247.087443) (xy 97.462959 -247.129488) (xy 97.426214 -247.166237)
			(xy 97.384172 -247.196786) (xy 97.33787 -247.220382) (xy 97.288446 -247.236446) (xy 97.237118 -247.24458)
			(xy 97.211134 -247.245124) (xy 97.193862 -247.244616) (xy 97.179384 -247.243854) (xy 97.154238 -247.25757)
			(xy 97.010728 -247.50522) (xy 97.011236 -247.533414) (xy 97.01911 -247.545606) (xy 97.031558 -247.565695)
			(xy 97.051212 -247.608675) (xy 97.064545 -247.654015) (xy 97.071286 -247.700792) (xy 97.071688 -247.7244)
			(xy 97.374907 -247.7244) (xy 97.379083 -247.674015) (xy 97.391495 -247.625005) (xy 97.411805 -247.578707)
			(xy 97.439459 -247.536383) (xy 97.473702 -247.499188) (xy 97.513601 -247.468138) (xy 97.558067 -247.444079)
			(xy 97.605887 -247.427667) (xy 97.655755 -247.41935) (xy 97.681034 -247.41886) (xy 98.621088 -247.41886)
			(xy 98.646369 -247.419308) (xy 98.696242 -247.427629) (xy 98.744066 -247.444045) (xy 98.788534 -247.468109)
			(xy 98.828436 -247.499164) (xy 98.862682 -247.536363) (xy 98.890337 -247.578692) (xy 98.910648 -247.624995)
			(xy 98.923061 -247.67401) (xy 98.927237 -247.7244) (xy 100.194807 -247.7244) (xy 100.198983 -247.674014)
			(xy 100.211395 -247.625004) (xy 100.231706 -247.578704) (xy 100.259361 -247.53638) (xy 100.293605 -247.499185)
			(xy 100.333506 -247.468135) (xy 100.377972 -247.444076) (xy 100.425793 -247.427665) (xy 100.475663 -247.41935)
			(xy 100.500942 -247.41886) (xy 101.440996 -247.41886) (xy 101.466277 -247.419309) (xy 101.516149 -247.42763)
			(xy 101.563971 -247.444047) (xy 101.608439 -247.468111) (xy 101.648339 -247.499167) (xy 101.682584 -247.536366)
			(xy 101.710238 -247.578694) (xy 101.730549 -247.624997) (xy 101.742961 -247.674011) (xy 101.747137 -247.7244)
			(xy 103.015007 -247.7244) (xy 103.019182 -247.674018) (xy 103.031593 -247.625011) (xy 103.0519 -247.578715)
			(xy 103.079551 -247.536393) (xy 103.113791 -247.499199) (xy 103.153685 -247.468148) (xy 103.198147 -247.444087)
			(xy 103.245962 -247.427673) (xy 103.295827 -247.419353) (xy 103.321104 -247.41886) (xy 104.261158 -247.41886)
			(xy 104.286441 -247.419306) (xy 104.336318 -247.427622) (xy 104.384145 -247.444036) (xy 104.428619 -247.468098)
			(xy 104.468524 -247.499153) (xy 104.502774 -247.536353) (xy 104.530433 -247.578683) (xy 104.550746 -247.624989)
			(xy 104.56316 -247.674007) (xy 104.567337 -247.7244) (xy 105.834907 -247.7244) (xy 105.839082 -247.674018)
			(xy 105.851493 -247.62501) (xy 105.871801 -247.578713) (xy 105.899453 -247.53639) (xy 105.933694 -247.499196)
			(xy 105.97359 -247.468145) (xy 106.018052 -247.444085) (xy 106.065869 -247.427671) (xy 106.115734 -247.419352)
			(xy 106.141012 -247.41886) (xy 107.081066 -247.41886) (xy 107.106348 -247.419306) (xy 107.156224 -247.427624)
			(xy 107.204051 -247.444038) (xy 107.248523 -247.468101) (xy 107.288427 -247.499156) (xy 107.322676 -247.536356)
			(xy 107.350334 -247.578686) (xy 107.370647 -247.624991) (xy 107.383061 -247.674008) (xy 107.387237 -247.7244)
			(xy 107.383061 -247.774792) (xy 107.370647 -247.823809) (xy 107.350334 -247.870114) (xy 107.322676 -247.912444)
			(xy 107.288427 -247.949644) (xy 107.248523 -247.980699) (xy 107.204051 -248.004762) (xy 107.156224 -248.021176)
			(xy 107.106348 -248.029494) (xy 107.081066 -248.029984) (xy 106.141012 -248.029984) (xy 106.115734 -248.029448)
			(xy 106.065869 -248.021129) (xy 106.018052 -248.004715) (xy 105.97359 -247.980655) (xy 105.933694 -247.949604)
			(xy 105.899453 -247.91241) (xy 105.871801 -247.870087) (xy 105.851493 -247.82379) (xy 105.839082 -247.774782)
			(xy 105.834907 -247.7244) (xy 104.567337 -247.7244) (xy 104.56316 -247.774793) (xy 104.550746 -247.823811)
			(xy 104.530433 -247.870117) (xy 104.502774 -247.912447) (xy 104.468524 -247.949647) (xy 104.428619 -247.980702)
			(xy 104.384145 -248.004764) (xy 104.336318 -248.021178) (xy 104.286441 -248.029494) (xy 104.261158 -248.029984)
			(xy 103.321104 -248.029984) (xy 103.295827 -248.029447) (xy 103.245962 -248.021127) (xy 103.198147 -248.004713)
			(xy 103.153685 -247.980652) (xy 103.113791 -247.949601) (xy 103.079551 -247.912407) (xy 103.0519 -247.870085)
			(xy 103.031593 -247.823789) (xy 103.019182 -247.774782) (xy 103.015007 -247.7244) (xy 101.747137 -247.7244)
			(xy 101.742961 -247.774789) (xy 101.730549 -247.823803) (xy 101.710238 -247.870106) (xy 101.682584 -247.912434)
			(xy 101.648339 -247.949633) (xy 101.608439 -247.980689) (xy 101.563971 -248.004753) (xy 101.516149 -248.02117)
			(xy 101.466277 -248.029491) (xy 101.440996 -248.029984) (xy 100.500942 -248.029984) (xy 100.475663 -248.02945)
			(xy 100.425793 -248.021135) (xy 100.377972 -248.004724) (xy 100.333506 -247.980665) (xy 100.293605 -247.949615)
			(xy 100.259361 -247.91242) (xy 100.231706 -247.870096) (xy 100.211395 -247.823796) (xy 100.198983 -247.774786)
			(xy 100.194807 -247.7244) (xy 98.927237 -247.7244) (xy 98.923061 -247.77479) (xy 98.910648 -247.823805)
			(xy 98.890337 -247.870108) (xy 98.862682 -247.912437) (xy 98.828436 -247.949636) (xy 98.788534 -247.980691)
			(xy 98.744066 -248.004755) (xy 98.696242 -248.021171) (xy 98.646369 -248.029492) (xy 98.621088 -248.029984)
			(xy 97.681034 -248.029984) (xy 97.655755 -248.02945) (xy 97.605887 -248.021133) (xy 97.558067 -248.004721)
			(xy 97.513601 -247.980662) (xy 97.473702 -247.949612) (xy 97.439459 -247.912417) (xy 97.411805 -247.870093)
			(xy 97.391495 -247.823795) (xy 97.379083 -247.774785) (xy 97.374907 -247.7244) (xy 97.071688 -247.7244)
			(xy 97.071688 -247.724422) (xy 97.071177 -247.750407) (xy 97.063043 -247.801738) (xy 97.04698 -247.851164)
			(xy 97.023383 -247.897469) (xy 96.992832 -247.939513) (xy 96.956081 -247.97626) (xy 96.914034 -248.006805)
			(xy 96.867726 -248.030396) (xy 96.818297 -248.046453) (xy 96.766966 -248.05458) (xy 96.74098 -248.05513)
			(xy 96.723962 -248.054622) (xy 96.70923 -248.05386) (xy 96.684592 -248.067322) (xy 96.540828 -248.315226)
			(xy 96.541336 -248.34342) (xy 96.54921 -248.355612) (xy 96.561658 -248.375701) (xy 96.581311 -248.418681)
			(xy 96.594643 -248.464021) (xy 96.601383 -248.510798) (xy 96.601788 -248.534428) (xy 96.601534 -248.546366)
			(xy 96.601026 -248.56059) (xy 96.614742 -248.585228) (xy 97.464372 -249.073162) (xy 97.492312 -249.072654)
			(xy 97.50425 -249.06478) (xy 97.524182 -249.052668) (xy 97.566725 -249.033556) (xy 97.611533 -249.020612)
			(xy 97.657714 -249.014091) (xy 97.681034 -249.013726) (xy 97.703982 -249.014095) (xy 97.749442 -249.020403)
			(xy 97.793589 -249.032948) (xy 97.835573 -249.051489) (xy 97.855278 -249.063256) (xy 97.867216 -249.070622)
			(xy 97.895156 -249.07113) (xy 98.747072 -248.581672) (xy 98.760788 -248.557288) (xy 98.76028 -248.543318)
			(xy 98.76028 -248.534428) (xy 98.76079 -248.508441) (xy 98.76892 -248.457106) (xy 98.784981 -248.407676)
			(xy 98.808577 -248.361366) (xy 98.839127 -248.319318) (xy 98.875878 -248.282567) (xy 98.917926 -248.252017)
			(xy 98.964236 -248.228421) (xy 99.013666 -248.21236) (xy 99.065001 -248.20423) (xy 99.116975 -248.20423)
			(xy 99.16831 -248.21236) (xy 99.21774 -248.228421) (xy 99.26405 -248.252017) (xy 99.306098 -248.282567)
			(xy 99.342849 -248.319318) (xy 99.373399 -248.361366) (xy 99.396995 -248.407676) (xy 99.413056 -248.457106)
			(xy 99.421186 -248.508441) (xy 99.421695 -248.5344) (xy 108.185168 -248.5344) (xy 108.189339 -248.48406)
			(xy 108.20174 -248.435093) (xy 108.222032 -248.388834) (xy 108.249661 -248.346547) (xy 108.283873 -248.309385)
			(xy 108.323736 -248.278361) (xy 108.368162 -248.254321) (xy 108.415939 -248.237922) (xy 108.465764 -248.229611)
			(xy 108.49102 -248.22912) (xy 109.431074 -248.22912) (xy 109.456335 -248.229555) (xy 109.50617 -248.237867)
			(xy 109.553956 -248.254268) (xy 109.598391 -248.278312) (xy 109.638262 -248.309342) (xy 109.672482 -248.346511)
			(xy 109.700117 -248.388806) (xy 109.720412 -248.435073) (xy 109.732816 -248.48405) (xy 109.736988 -248.5344)
			(xy 109.732816 -248.58475) (xy 109.720412 -248.633727) (xy 109.700117 -248.679994) (xy 109.672482 -248.722289)
			(xy 109.638262 -248.759458) (xy 109.598391 -248.790488) (xy 109.553956 -248.814532) (xy 109.50617 -248.830933)
			(xy 109.456335 -248.839245) (xy 109.431074 -248.839736) (xy 108.49102 -248.839736) (xy 108.465764 -248.839189)
			(xy 108.415939 -248.830878) (xy 108.368162 -248.814479) (xy 108.323736 -248.790439) (xy 108.283873 -248.759415)
			(xy 108.249661 -248.722253) (xy 108.222032 -248.679966) (xy 108.20174 -248.633707) (xy 108.189339 -248.58474)
			(xy 108.185168 -248.5344) (xy 99.421695 -248.5344) (xy 99.421696 -248.534428) (xy 99.421276 -248.557797)
			(xy 99.414659 -248.604066) (xy 99.401589 -248.64894) (xy 99.382328 -248.691526) (xy 99.370134 -248.711466)
			(xy 99.362514 -248.723658) (xy 99.362006 -248.751852) (xy 99.506786 -249.00128) (xy 99.531424 -249.014742)
			(xy 99.545902 -249.01398) (xy 99.561142 -249.013726) (xy 99.587126 -249.014239) (xy 99.638453 -249.022375)
			(xy 99.687876 -249.03844) (xy 99.734177 -249.062038) (xy 99.776217 -249.09259) (xy 99.81296 -249.129341)
			(xy 99.843501 -249.171387) (xy 99.867089 -249.217694) (xy 99.883143 -249.267121) (xy 99.891267 -249.31845)
			(xy 99.89185 -249.344434) (xy 99.891448 -249.367836) (xy 99.884853 -249.414173) (xy 99.871786 -249.459115)
			(xy 99.852508 -249.501765) (xy 99.840288 -249.521726) (xy 99.832668 -249.533664) (xy 99.83216 -249.561858)
			(xy 99.976686 -249.811286) (xy 100.001578 -249.824748) (xy 100.015802 -249.823986) (xy 100.031042 -249.823732)
			(xy 100.057026 -249.824245) (xy 100.108353 -249.832381) (xy 100.157775 -249.848446) (xy 100.204076 -249.872045)
			(xy 100.246115 -249.902596) (xy 100.282857 -249.939348) (xy 100.313398 -249.981394) (xy 100.336985 -250.027701)
			(xy 100.353038 -250.077127) (xy 100.361161 -250.128456) (xy 100.36175 -250.15444) (xy 100.361496 -250.166378)
			(xy 100.360988 -250.180602) (xy 100.37445 -250.204986) (xy 101.224334 -250.693174) (xy 101.252274 -250.692666)
			(xy 101.264212 -250.684792) (xy 101.284144 -250.672683) (xy 101.326689 -250.653579) (xy 101.371496 -250.640642)
			(xy 101.417677 -250.63413) (xy 101.440996 -250.633738) (xy 101.466984 -250.634221) (xy 101.518321 -250.642352)
			(xy 101.567753 -250.658414) (xy 101.614063 -250.682013) (xy 101.656111 -250.712566) (xy 101.692862 -250.749321)
			(xy 101.723409 -250.791373) (xy 101.747002 -250.837686) (xy 101.763058 -250.88712) (xy 101.771182 -250.938458)
			(xy 101.771704 -250.964446) (xy 101.771294 -250.987804) (xy 101.764715 -251.034054) (xy 101.751708 -251.078923)
			(xy 101.732531 -251.121521) (xy 101.720396 -251.141484) (xy 101.712522 -251.153676) (xy 101.712014 -251.18187)
			(xy 101.856794 -251.431298) (xy 101.881686 -251.44476) (xy 101.89591 -251.443998) (xy 101.91115 -251.443744)
			(xy 101.934066 -251.444133) (xy 101.979457 -251.450463) (xy 102.023537 -251.463009) (xy 102.06546 -251.481529)
			(xy 102.08514 -251.493274) (xy 102.097078 -251.50064) (xy 102.125018 -251.501148) (xy 102.977188 -251.011436)
			(xy 102.990904 -250.987052) (xy 102.990396 -250.973082) (xy 102.990396 -250.964446) (xy 102.990906 -250.938459)
			(xy 102.999036 -250.887124) (xy 103.015097 -250.837694) (xy 103.038693 -250.791384) (xy 103.069243 -250.749336)
			(xy 103.105994 -250.712585) (xy 103.148042 -250.682035) (xy 103.194352 -250.658439) (xy 103.243782 -250.642378)
			(xy 103.295117 -250.634248) (xy 103.347091 -250.634248) (xy 103.398426 -250.642378) (xy 103.447856 -250.658439)
			(xy 103.494166 -250.682035) (xy 103.536214 -250.712585) (xy 103.572965 -250.749336) (xy 103.603515 -250.791384)
			(xy 103.627111 -250.837694) (xy 103.643172 -250.887124) (xy 103.651302 -250.938459) (xy 103.651812 -250.964446)
			(xy 103.651409 -250.987848) (xy 103.644814 -251.034185) (xy 103.631748 -251.079127) (xy 103.612472 -251.121777)
			(xy 103.60025 -251.141738) (xy 103.59263 -251.153676) (xy 103.592122 -251.18187) (xy 103.736902 -251.431298)
			(xy 103.76154 -251.44476) (xy 103.776018 -251.443998) (xy 103.791004 -251.443744) (xy 103.813953 -251.444111)
			(xy 103.859414 -251.450416) (xy 103.903563 -251.462958) (xy 103.945549 -251.481496) (xy 103.965248 -251.493274)
			(xy 103.977186 -251.50064) (xy 104.005126 -251.501148) (xy 104.857042 -251.01169) (xy 104.870758 -250.987306)
			(xy 104.87025 -250.973336) (xy 104.87025 -250.964446) (xy 104.87076 -250.938459) (xy 104.87889 -250.887124)
			(xy 104.894951 -250.837694) (xy 104.918547 -250.791384) (xy 104.949097 -250.749336) (xy 104.985848 -250.712585)
			(xy 105.027896 -250.682035) (xy 105.074206 -250.658439) (xy 105.123636 -250.642378) (xy 105.174971 -250.634248)
			(xy 105.226945 -250.634248) (xy 105.27828 -250.642378) (xy 105.32771 -250.658439) (xy 105.37402 -250.682035)
			(xy 105.416068 -250.712585) (xy 105.452819 -250.749336) (xy 105.483369 -250.791384) (xy 105.506965 -250.837694)
			(xy 105.523026 -250.887124) (xy 105.531156 -250.938459) (xy 105.531666 -250.964446) (xy 105.531256 -250.987804)
			(xy 105.524677 -251.034054) (xy 105.511668 -251.078922) (xy 105.492489 -251.121519) (xy 105.480358 -251.141484)
			(xy 105.472484 -251.153676) (xy 105.471976 -251.18187) (xy 105.616756 -251.431298) (xy 105.641648 -251.44476)
			(xy 105.655872 -251.443998) (xy 105.671112 -251.443744) (xy 105.694026 -251.444137) (xy 105.739414 -251.450475)
			(xy 105.78349 -251.463028) (xy 105.825407 -251.481554) (xy 105.845102 -251.493274) (xy 105.85704 -251.50064)
			(xy 105.88498 -251.501148) (xy 106.73715 -251.01169) (xy 106.750866 -250.987306) (xy 106.750358 -250.973336)
			(xy 106.750358 -250.964446) (xy 106.750868 -250.938459) (xy 106.758998 -250.887124) (xy 106.775059 -250.837694)
			(xy 106.798655 -250.791384) (xy 106.829205 -250.749336) (xy 106.865956 -250.712585) (xy 106.908004 -250.682035)
			(xy 106.954314 -250.658439) (xy 107.003744 -250.642378) (xy 107.055079 -250.634248) (xy 107.107053 -250.634248)
			(xy 107.158388 -250.642378) (xy 107.207818 -250.658439) (xy 107.254128 -250.682035) (xy 107.296176 -250.712585)
			(xy 107.332927 -250.749336) (xy 107.363477 -250.791384) (xy 107.387073 -250.837694) (xy 107.403134 -250.887124)
			(xy 107.411264 -250.938459) (xy 107.411774 -250.964446) (xy 107.411364 -250.987804) (xy 107.404785 -251.034054)
			(xy 107.391777 -251.078922) (xy 107.372598 -251.121519) (xy 107.360466 -251.141484) (xy 107.352592 -251.153676)
			(xy 107.352084 -251.18187) (xy 107.496864 -251.431298) (xy 107.521756 -251.44476) (xy 107.53598 -251.443998)
			(xy 107.550966 -251.443744) (xy 107.573913 -251.444115) (xy 107.619371 -251.450428) (xy 107.663516 -251.462977)
			(xy 107.705497 -251.481522) (xy 107.72521 -251.493274) (xy 107.737148 -251.50064) (xy 107.765088 -251.501148)
			(xy 108.617258 -251.01169) (xy 108.630974 -250.987306) (xy 108.630466 -250.973082) (xy 108.630466 -250.964446)
			(xy 108.630946 -250.938454) (xy 108.639071 -250.887108) (xy 108.655129 -250.837666) (xy 108.678724 -250.791344)
			(xy 108.709275 -250.749284) (xy 108.746029 -250.712522) (xy 108.788083 -250.681961) (xy 108.834399 -250.658356)
			(xy 108.883838 -250.642288) (xy 108.935182 -250.634151) (xy 108.961174 -250.633738) (xy 108.97108 -250.633992)
			(xy 108.98505 -250.634246) (xy 109.009434 -250.620784) (xy 109.156754 -250.367038) (xy 109.156246 -250.339098)
			(xy 109.149134 -250.32716) (xy 109.137589 -250.30758) (xy 109.11938 -250.265933) (xy 109.107032 -250.222188)
			(xy 109.100776 -250.177167) (xy 109.100366 -250.15444) (xy 109.100876 -250.128453) (xy 109.109006 -250.077118)
			(xy 109.125067 -250.027688) (xy 109.148663 -249.981378) (xy 109.179213 -249.93933) (xy 109.215964 -249.902579)
			(xy 109.258012 -249.872029) (xy 109.304322 -249.848433) (xy 109.353752 -249.832372) (xy 109.405087 -249.824242)
			(xy 109.457061 -249.824242) (xy 109.508396 -249.832372) (xy 109.557826 -249.848433) (xy 109.604136 -249.872029)
			(xy 109.646184 -249.902579) (xy 109.682935 -249.93933) (xy 109.713485 -249.981378) (xy 109.737081 -250.027688)
			(xy 109.753142 -250.077118) (xy 109.761272 -250.128453) (xy 109.761782 -250.15444) (xy 109.761528 -250.166378)
			(xy 109.76102 -250.180602) (xy 109.774482 -250.204986) (xy 110.860078 -250.828556) (xy 110.865897 -250.83167)
			(xy 110.878629 -250.835133) (xy 110.885224 -250.835414) (xy 113.332514 -250.835414) (xy 113.35639 -250.82119)
			(xy 113.363248 -250.80849) (xy 113.3757 -250.786214) (xy 113.406397 -250.745446) (xy 113.44299 -250.709877)
			(xy 113.484613 -250.68035) (xy 113.530277 -250.657567) (xy 113.578899 -250.642068) (xy 113.629324 -250.634221)
			(xy 113.65484 -250.633738) (xy 113.678167 -250.634159) (xy 113.724354 -250.640749) (xy 113.76916 -250.65375)
			(xy 113.811701 -250.672906) (xy 113.831624 -250.685046) (xy 113.843816 -250.692666) (xy 113.871502 -250.693174)
			(xy 114.721386 -250.204986) (xy 114.734848 -250.180602) (xy 114.73434 -250.166378) (xy 114.734086 -250.15444)
			(xy 114.734596 -250.128453) (xy 114.742726 -250.077118) (xy 114.758787 -250.027688) (xy 114.782383 -249.981378)
			(xy 114.812933 -249.93933) (xy 114.849684 -249.902579) (xy 114.891732 -249.872029) (xy 114.938042 -249.848433)
			(xy 114.987472 -249.832372) (xy 115.038807 -249.824242) (xy 115.090781 -249.824242) (xy 115.142116 -249.832372)
			(xy 115.191546 -249.848433) (xy 115.237856 -249.872029) (xy 115.279904 -249.902579) (xy 115.316655 -249.93933)
			(xy 115.347205 -249.981378) (xy 115.370801 -250.027688) (xy 115.386862 -250.077118) (xy 115.394992 -250.128453)
			(xy 115.395502 -250.15444) (xy 115.395132 -250.177171) (xy 115.38891 -250.222205) (xy 115.376561 -250.265958)
			(xy 115.358319 -250.3076) (xy 115.346734 -250.32716) (xy 115.339622 -250.339098) (xy 115.339114 -250.367038)
			(xy 115.486434 -250.620784) (xy 115.510818 -250.634246) (xy 115.524788 -250.633992) (xy 115.534694 -250.633738)
			(xy 115.560682 -250.634221) (xy 115.612019 -250.642352) (xy 115.661451 -250.658414) (xy 115.707762 -250.682012)
			(xy 115.74981 -250.712565) (xy 115.786561 -250.74932) (xy 115.817109 -250.791372) (xy 115.840702 -250.837686)
			(xy 115.856758 -250.88712) (xy 115.864882 -250.938458) (xy 115.865402 -250.964446) (xy 115.865402 -250.973082)
			(xy 115.864894 -250.987306) (xy 115.87861 -251.01169) (xy 116.73078 -251.501148) (xy 116.75872 -251.50064)
			(xy 116.770658 -251.493274) (xy 116.790346 -251.481545) (xy 116.832269 -251.463034) (xy 116.876347 -251.450491)
			(xy 116.921734 -251.444155) (xy 116.944648 -251.443744) (xy 116.959888 -251.443998) (xy 116.974112 -251.44476)
			(xy 116.999004 -251.431298) (xy 117.143784 -251.18187) (xy 117.143276 -251.153676) (xy 117.135402 -251.141484)
			(xy 117.123236 -251.121537) (xy 117.104036 -251.078944) (xy 117.091036 -251.034068) (xy 117.084496 -250.987807)
			(xy 117.084094 -250.964446) (xy 117.084574 -250.938454) (xy 117.092699 -250.88711) (xy 117.108757 -250.83767)
			(xy 117.132353 -250.79135) (xy 117.162904 -250.749293) (xy 117.199659 -250.712533) (xy 117.241713 -250.681976)
			(xy 117.288029 -250.658374) (xy 117.337468 -250.64231) (xy 117.38881 -250.634177) (xy 117.414802 -250.633738)
			(xy 117.438122 -250.634117) (xy 117.484306 -250.640627) (xy 117.529117 -250.65356) (xy 117.571666 -250.672661)
			(xy 117.591586 -250.684792) (xy 117.603524 -250.692666) (xy 117.631464 -250.693174) (xy 118.481348 -250.204986)
			(xy 118.49481 -250.180602) (xy 118.494302 -250.166124) (xy 118.494048 -250.15444) (xy 118.494558 -250.128453)
			(xy 118.502688 -250.077118) (xy 118.518749 -250.027688) (xy 118.542345 -249.981378) (xy 118.572895 -249.93933)
			(xy 118.609646 -249.902579) (xy 118.651694 -249.872029) (xy 118.698004 -249.848433) (xy 118.747434 -249.832372)
			(xy 118.798769 -249.824242) (xy 118.850743 -249.824242) (xy 118.902078 -249.832372) (xy 118.951508 -249.848433)
			(xy 118.997818 -249.872029) (xy 119.039866 -249.902579) (xy 119.076617 -249.93933) (xy 119.107167 -249.981378)
			(xy 119.130763 -250.027688) (xy 119.146824 -250.077118) (xy 119.154954 -250.128453) (xy 119.155464 -250.15444)
			(xy 119.155094 -250.177171) (xy 119.148871 -250.222205) (xy 119.136521 -250.265957) (xy 119.118278 -250.307598)
			(xy 119.106696 -250.32716) (xy 119.099584 -250.339098) (xy 119.099076 -250.367038) (xy 119.246396 -250.620784)
			(xy 119.27078 -250.634246) (xy 119.28475 -250.633992) (xy 119.294656 -250.633738) (xy 119.320646 -250.634218)
			(xy 119.371987 -250.642344) (xy 119.421425 -250.658403) (xy 119.467741 -250.681999) (xy 119.509795 -250.712551)
			(xy 119.54655 -250.749307) (xy 119.577102 -250.791361) (xy 119.600698 -250.837677) (xy 119.616757 -250.887115)
			(xy 119.624882 -250.938456) (xy 119.625364 -250.964446) (xy 119.625364 -250.973082) (xy 119.624856 -250.987306)
			(xy 119.638572 -251.01169) (xy 120.490742 -251.501148) (xy 120.518682 -251.50064) (xy 120.53062 -251.493274)
			(xy 120.550307 -251.481542) (xy 120.59223 -251.463027) (xy 120.636307 -251.450479) (xy 120.681696 -251.444137)
			(xy 120.70461 -251.443744) (xy 120.71985 -251.443998) (xy 120.734074 -251.44476) (xy 120.758966 -251.431298)
			(xy 120.903746 -251.18187) (xy 120.903238 -251.153676) (xy 120.895364 -251.141484) (xy 120.8832 -251.121537)
			(xy 120.864002 -251.078943) (xy 120.851003 -251.034067) (xy 120.844464 -250.987807) (xy 120.844056 -250.964446)
			(xy 120.844536 -250.938453) (xy 120.852661 -250.887107) (xy 120.868719 -250.837664) (xy 120.892313 -250.791342)
			(xy 120.922864 -250.749281) (xy 120.959619 -250.712518) (xy 121.001672 -250.681956) (xy 121.047988 -250.65835)
			(xy 121.097427 -250.64228) (xy 121.148771 -250.634142) (xy 121.174764 -250.633738) (xy 121.198083 -250.634121)
			(xy 121.244263 -250.640639) (xy 121.289069 -250.65358) (xy 121.331614 -250.672686) (xy 121.351548 -250.684792)
			(xy 121.363486 -250.692666) (xy 121.391426 -250.693174) (xy 122.24131 -250.204986) (xy 122.254772 -250.180602)
			(xy 122.254264 -250.166378) (xy 122.25401 -250.15444) (xy 122.25452 -250.128453) (xy 122.26265 -250.077118)
			(xy 122.278711 -250.027688) (xy 122.302307 -249.981378) (xy 122.332857 -249.93933) (xy 122.369608 -249.902579)
			(xy 122.411656 -249.872029) (xy 122.457966 -249.848433) (xy 122.507396 -249.832372) (xy 122.558731 -249.824242)
			(xy 122.610705 -249.824242) (xy 122.66204 -249.832372) (xy 122.71147 -249.848433) (xy 122.75778 -249.872029)
			(xy 122.799828 -249.902579) (xy 122.836579 -249.93933) (xy 122.867129 -249.981378) (xy 122.890725 -250.027688)
			(xy 122.906786 -250.077118) (xy 122.914916 -250.128453) (xy 122.915426 -250.15444) (xy 122.91505 -250.177128)
			(xy 122.908845 -250.222077) (xy 122.896557 -250.265756) (xy 122.878416 -250.307348) (xy 122.866912 -250.326906)
			(xy 122.859546 -250.338844) (xy 122.859292 -250.366784) (xy 123.006358 -250.620784) (xy 123.030742 -250.634246)
			(xy 123.044966 -250.633992) (xy 123.054618 -250.633738) (xy 123.080605 -250.634223) (xy 123.131939 -250.642356)
			(xy 123.181368 -250.658421) (xy 123.227675 -250.68202) (xy 123.26972 -250.712573) (xy 123.306468 -250.749328)
			(xy 123.337013 -250.791379) (xy 123.360604 -250.837691) (xy 123.376659 -250.887124) (xy 123.384783 -250.938459)
			(xy 123.385326 -250.964446) (xy 123.385326 -250.973082) (xy 123.384818 -250.987306) (xy 123.398534 -251.01169)
			(xy 124.250704 -251.501148)
		)
		(stroke
			(width 0)
			(type solid)
		)
		(fill yes)
		(layer "In9.Cu")
		(net "PVDDCR_CPU0_P1")
	)
	(gr_poly
		(pts
			(xy 181.346602 -389.076692) (xy 181.356672 -389.076268) (xy 181.375275 -389.068552) (xy 181.38267 -389.061706)
			(xy 184.122822 -386.321554) (xy 184.12967 -386.314157) (xy 184.1374 -386.295558) (xy 184.137808 -386.285486)
			(xy 184.137808 -369.556284) (xy 184.137382 -369.546215) (xy 184.129665 -369.527614) (xy 184.122822 -369.520216)
			(xy 181.865778 -367.263172) (xy 181.858382 -367.256321) (xy 181.839783 -367.248583) (xy 181.82971 -367.248186)
			(xy 70.670674 -367.248186) (xy 70.660606 -367.248613) (xy 70.642007 -367.256333) (xy 70.634606 -367.263172)
			(xy 69.858382 -368.039396) (xy 69.851526 -368.04679) (xy 69.843777 -368.065389) (xy 69.843396 -368.075464)
			(xy 69.843396 -368.086894) (xy 69.850508 -368.104674) (xy 69.857366 -368.11204) (xy 69.875234 -368.131454)
			(xy 69.906 -368.174318) (xy 69.93056 -368.221016) (xy 69.948445 -368.270654) (xy 69.959314 -368.322285)
			(xy 69.962958 -368.374922) (xy 69.959308 -368.427558) (xy 69.948434 -368.479187) (xy 69.930543 -368.528824)
			(xy 69.905977 -368.575519) (xy 69.875206 -368.618379) (xy 69.857366 -368.63782) (xy 69.850981 -368.64514)
			(xy 69.843793 -368.663167) (xy 69.843396 -368.672872) (xy 69.843396 -369.062569) (xy 76.863431 -369.062569)
			(xy 76.863431 -369.008031) (xy 76.871193 -368.954048) (xy 76.886558 -368.90172) (xy 76.909214 -368.85211)
			(xy 76.9387 -368.80623) (xy 76.974414 -368.765013) (xy 77.015632 -368.729298) (xy 77.061512 -368.699813)
			(xy 77.111121 -368.677157) (xy 77.16345 -368.661793) (xy 77.217433 -368.654031) (xy 77.244702 -368.653568)
			(xy 78.108302 -368.653568) (xy 78.135573 -368.653995) (xy 78.189561 -368.661757) (xy 78.241894 -368.677124)
			(xy 78.291508 -368.699782) (xy 78.337393 -368.72927) (xy 78.378613 -368.764988) (xy 78.414331 -368.806209)
			(xy 78.443819 -368.852093) (xy 78.466477 -368.901707) (xy 78.481843 -368.954041) (xy 78.489606 -369.008029)
			(xy 78.489606 -369.062569) (xy 83.670631 -369.062569) (xy 83.670631 -369.008031) (xy 83.678393 -368.954048)
			(xy 83.693758 -368.90172) (xy 83.716414 -368.85211) (xy 83.7459 -368.80623) (xy 83.781614 -368.765013)
			(xy 83.822832 -368.729298) (xy 83.868712 -368.699813) (xy 83.918321 -368.677157) (xy 83.97065 -368.661793)
			(xy 84.024633 -368.654031) (xy 84.051902 -368.653568) (xy 84.915502 -368.653568) (xy 84.942773 -368.653995)
			(xy 84.996761 -368.661757) (xy 85.049094 -368.677124) (xy 85.098708 -368.699782) (xy 85.144593 -368.72927)
			(xy 85.185813 -368.764988) (xy 85.221531 -368.806209) (xy 85.251019 -368.852093) (xy 85.273677 -368.901707)
			(xy 85.289043 -368.954041) (xy 85.296806 -369.008029) (xy 85.296806 -369.062569) (xy 90.477831 -369.062569)
			(xy 90.477831 -369.008031) (xy 90.485593 -368.954048) (xy 90.500958 -368.90172) (xy 90.523614 -368.85211)
			(xy 90.5531 -368.80623) (xy 90.588814 -368.765013) (xy 90.630032 -368.729298) (xy 90.675912 -368.699813)
			(xy 90.725521 -368.677157) (xy 90.77785 -368.661793) (xy 90.831833 -368.654031) (xy 90.859102 -368.653568)
			(xy 91.722702 -368.653568) (xy 91.749973 -368.653995) (xy 91.803961 -368.661757) (xy 91.856294 -368.677124)
			(xy 91.905908 -368.699782) (xy 91.951793 -368.72927) (xy 91.993013 -368.764988) (xy 92.028731 -368.806209)
			(xy 92.058219 -368.852093) (xy 92.080877 -368.901707) (xy 92.096243 -368.954041) (xy 92.104006 -369.008029)
			(xy 92.104006 -369.062569) (xy 97.285031 -369.062569) (xy 97.285031 -369.008031) (xy 97.292793 -368.954048)
			(xy 97.308158 -368.90172) (xy 97.330814 -368.85211) (xy 97.3603 -368.80623) (xy 97.396014 -368.765013)
			(xy 97.437232 -368.729298) (xy 97.483112 -368.699813) (xy 97.532721 -368.677157) (xy 97.58505 -368.661793)
			(xy 97.639033 -368.654031) (xy 97.666302 -368.653568) (xy 98.529902 -368.653568) (xy 98.557173 -368.653995)
			(xy 98.611161 -368.661757) (xy 98.663494 -368.677124) (xy 98.713108 -368.699782) (xy 98.758993 -368.72927)
			(xy 98.800213 -368.764988) (xy 98.835931 -368.806209) (xy 98.865419 -368.852093) (xy 98.888077 -368.901707)
			(xy 98.903443 -368.954041) (xy 98.911206 -369.008029) (xy 98.911206 -369.062569) (xy 100.688631 -369.062569)
			(xy 100.688631 -369.008031) (xy 100.696393 -368.954048) (xy 100.711758 -368.90172) (xy 100.734414 -368.85211)
			(xy 100.7639 -368.80623) (xy 100.799614 -368.765013) (xy 100.840832 -368.729298) (xy 100.886712 -368.699813)
			(xy 100.936321 -368.677157) (xy 100.98865 -368.661793) (xy 101.042633 -368.654031) (xy 101.069902 -368.653568)
			(xy 101.933502 -368.653568) (xy 101.960773 -368.653995) (xy 102.014761 -368.661757) (xy 102.067094 -368.677124)
			(xy 102.116708 -368.699782) (xy 102.162593 -368.72927) (xy 102.203813 -368.764988) (xy 102.239531 -368.806209)
			(xy 102.269019 -368.852093) (xy 102.291677 -368.901707) (xy 102.307043 -368.954041) (xy 102.314806 -369.008029)
			(xy 102.314806 -369.062567) (xy 111.435654 -369.062567) (xy 111.435654 -369.008033) (xy 111.443415 -368.954054)
			(xy 111.458779 -368.901729) (xy 111.481433 -368.852123) (xy 111.510917 -368.806246) (xy 111.546629 -368.765031)
			(xy 111.587842 -368.729319) (xy 111.633719 -368.699835) (xy 111.683325 -368.677181) (xy 111.73565 -368.661816)
			(xy 111.789629 -368.654055) (xy 111.816896 -368.653568) (xy 112.680496 -368.653568) (xy 112.707769 -368.653971)
			(xy 112.761761 -368.661734) (xy 112.814098 -368.677101) (xy 112.863716 -368.69976) (xy 112.909603 -368.72925)
			(xy 112.950827 -368.76497) (xy 112.986548 -368.806193) (xy 113.016038 -368.852081) (xy 113.038698 -368.901698)
			(xy 113.054066 -368.954035) (xy 113.061828 -369.008027) (xy 113.061828 -369.062567) (xy 118.242854 -369.062567)
			(xy 118.242854 -369.008033) (xy 118.250615 -368.954054) (xy 118.265979 -368.901729) (xy 118.288633 -368.852123)
			(xy 118.318117 -368.806246) (xy 118.353829 -368.765031) (xy 118.395042 -368.729319) (xy 118.440919 -368.699835)
			(xy 118.490525 -368.677181) (xy 118.54285 -368.661816) (xy 118.596829 -368.654055) (xy 118.624096 -368.653568)
			(xy 119.487696 -368.653568) (xy 119.514969 -368.653971) (xy 119.568961 -368.661734) (xy 119.621298 -368.677101)
			(xy 119.670916 -368.69976) (xy 119.716803 -368.72925) (xy 119.758027 -368.76497) (xy 119.793748 -368.806193)
			(xy 119.823238 -368.852081) (xy 119.845898 -368.901698) (xy 119.861266 -368.954035) (xy 119.869028 -369.008027)
			(xy 119.869028 -369.062567) (xy 125.050054 -369.062567) (xy 125.050054 -369.008033) (xy 125.057815 -368.954054)
			(xy 125.073179 -368.901729) (xy 125.095833 -368.852123) (xy 125.125317 -368.806246) (xy 125.161029 -368.765031)
			(xy 125.202242 -368.729319) (xy 125.248119 -368.699835) (xy 125.297725 -368.677181) (xy 125.35005 -368.661816)
			(xy 125.404029 -368.654055) (xy 125.431296 -368.653568) (xy 126.294896 -368.653568) (xy 126.322169 -368.653971)
			(xy 126.376161 -368.661734) (xy 126.428498 -368.677101) (xy 126.478116 -368.69976) (xy 126.524003 -368.72925)
			(xy 126.565227 -368.76497) (xy 126.600948 -368.806193) (xy 126.630438 -368.852081) (xy 126.653098 -368.901698)
			(xy 126.668466 -368.954035) (xy 126.676228 -369.008027) (xy 126.676228 -369.062567) (xy 131.857254 -369.062567)
			(xy 131.857254 -369.008033) (xy 131.865015 -368.954054) (xy 131.880379 -368.901729) (xy 131.903033 -368.852123)
			(xy 131.932517 -368.806246) (xy 131.968229 -368.765031) (xy 132.009442 -368.729319) (xy 132.055319 -368.699835)
			(xy 132.104925 -368.677181) (xy 132.15725 -368.661816) (xy 132.211229 -368.654055) (xy 132.238496 -368.653568)
			(xy 133.102096 -368.653568) (xy 133.129369 -368.653971) (xy 133.183361 -368.661734) (xy 133.235698 -368.677101)
			(xy 133.285316 -368.69976) (xy 133.331203 -368.72925) (xy 133.372427 -368.76497) (xy 133.408148 -368.806193)
			(xy 133.437638 -368.852081) (xy 133.460298 -368.901698) (xy 133.475666 -368.954035) (xy 133.483428 -369.008027)
			(xy 133.483428 -369.062567) (xy 135.260854 -369.062567) (xy 135.260854 -369.008033) (xy 135.268615 -368.954054)
			(xy 135.283979 -368.901729) (xy 135.306633 -368.852123) (xy 135.336117 -368.806246) (xy 135.371829 -368.765031)
			(xy 135.413042 -368.729319) (xy 135.458919 -368.699835) (xy 135.508525 -368.677181) (xy 135.56085 -368.661816)
			(xy 135.614829 -368.654055) (xy 135.642096 -368.653568) (xy 136.505696 -368.653568) (xy 136.532969 -368.653971)
			(xy 136.586961 -368.661734) (xy 136.639298 -368.677101) (xy 136.688916 -368.69976) (xy 136.734803 -368.72925)
			(xy 136.776027 -368.76497) (xy 136.811748 -368.806193) (xy 136.841238 -368.852081) (xy 136.863898 -368.901698)
			(xy 136.879266 -368.954035) (xy 136.887028 -369.008027) (xy 136.887028 -369.062573) (xy 136.879266 -369.116565)
			(xy 136.863898 -369.168902) (xy 136.841238 -369.218519) (xy 136.811748 -369.264407) (xy 136.776027 -369.30563)
			(xy 136.734803 -369.34135) (xy 136.688916 -369.37084) (xy 136.639298 -369.393499) (xy 136.586961 -369.408866)
			(xy 136.532969 -369.416629) (xy 136.505696 -369.417092) (xy 135.642096 -369.417092) (xy 135.614829 -369.416545)
			(xy 135.56085 -369.408784) (xy 135.508525 -369.393419) (xy 135.458919 -369.370765) (xy 135.413042 -369.341281)
			(xy 135.371829 -369.305569) (xy 135.336117 -369.264354) (xy 135.306633 -369.218477) (xy 135.283979 -369.168871)
			(xy 135.268615 -369.116546) (xy 135.260854 -369.062567) (xy 133.483428 -369.062567) (xy 133.483428 -369.062573)
			(xy 133.475666 -369.116565) (xy 133.460298 -369.168902) (xy 133.437638 -369.218519) (xy 133.408148 -369.264407)
			(xy 133.372427 -369.30563) (xy 133.331203 -369.34135) (xy 133.285316 -369.37084) (xy 133.235698 -369.393499)
			(xy 133.183361 -369.408866) (xy 133.129369 -369.416629) (xy 133.102096 -369.417092) (xy 132.238496 -369.417092)
			(xy 132.211229 -369.416545) (xy 132.15725 -369.408784) (xy 132.104925 -369.393419) (xy 132.055319 -369.370765)
			(xy 132.009442 -369.341281) (xy 131.968229 -369.305569) (xy 131.932517 -369.264354) (xy 131.903033 -369.218477)
			(xy 131.880379 -369.168871) (xy 131.865015 -369.116546) (xy 131.857254 -369.062567) (xy 126.676228 -369.062567)
			(xy 126.676228 -369.062573) (xy 126.668466 -369.116565) (xy 126.653098 -369.168902) (xy 126.630438 -369.218519)
			(xy 126.600948 -369.264407) (xy 126.565227 -369.30563) (xy 126.524003 -369.34135) (xy 126.478116 -369.37084)
			(xy 126.428498 -369.393499) (xy 126.376161 -369.408866) (xy 126.322169 -369.416629) (xy 126.294896 -369.417092)
			(xy 125.431296 -369.417092) (xy 125.404029 -369.416545) (xy 125.35005 -369.408784) (xy 125.297725 -369.393419)
			(xy 125.248119 -369.370765) (xy 125.202242 -369.341281) (xy 125.161029 -369.305569) (xy 125.125317 -369.264354)
			(xy 125.095833 -369.218477) (xy 125.073179 -369.168871) (xy 125.057815 -369.116546) (xy 125.050054 -369.062567)
			(xy 119.869028 -369.062567) (xy 119.869028 -369.062573) (xy 119.861266 -369.116565) (xy 119.845898 -369.168902)
			(xy 119.823238 -369.218519) (xy 119.793748 -369.264407) (xy 119.758027 -369.30563) (xy 119.716803 -369.34135)
			(xy 119.670916 -369.37084) (xy 119.621298 -369.393499) (xy 119.568961 -369.408866) (xy 119.514969 -369.416629)
			(xy 119.487696 -369.417092) (xy 118.624096 -369.417092) (xy 118.596829 -369.416545) (xy 118.54285 -369.408784)
			(xy 118.490525 -369.393419) (xy 118.440919 -369.370765) (xy 118.395042 -369.341281) (xy 118.353829 -369.305569)
			(xy 118.318117 -369.264354) (xy 118.288633 -369.218477) (xy 118.265979 -369.168871) (xy 118.250615 -369.116546)
			(xy 118.242854 -369.062567) (xy 113.061828 -369.062567) (xy 113.061828 -369.062573) (xy 113.054066 -369.116565)
			(xy 113.038698 -369.168902) (xy 113.016038 -369.218519) (xy 112.986548 -369.264407) (xy 112.950827 -369.30563)
			(xy 112.909603 -369.34135) (xy 112.863716 -369.37084) (xy 112.814098 -369.393499) (xy 112.761761 -369.408866)
			(xy 112.707769 -369.416629) (xy 112.680496 -369.417092) (xy 111.816896 -369.417092) (xy 111.789629 -369.416545)
			(xy 111.73565 -369.408784) (xy 111.683325 -369.393419) (xy 111.633719 -369.370765) (xy 111.587842 -369.341281)
			(xy 111.546629 -369.305569) (xy 111.510917 -369.264354) (xy 111.481433 -369.218477) (xy 111.458779 -369.168871)
			(xy 111.443415 -369.116546) (xy 111.435654 -369.062567) (xy 102.314806 -369.062567) (xy 102.314806 -369.062571)
			(xy 102.307043 -369.116559) (xy 102.291677 -369.168893) (xy 102.269019 -369.218507) (xy 102.239531 -369.264391)
			(xy 102.203813 -369.305612) (xy 102.162593 -369.34133) (xy 102.116708 -369.370818) (xy 102.067094 -369.393476)
			(xy 102.014761 -369.408843) (xy 101.960773 -369.416605) (xy 101.933502 -369.417092) (xy 101.069902 -369.417092)
			(xy 101.042633 -369.416569) (xy 100.98865 -369.408807) (xy 100.936321 -369.393443) (xy 100.886712 -369.370787)
			(xy 100.840832 -369.341302) (xy 100.799614 -369.305587) (xy 100.7639 -369.26437) (xy 100.734414 -369.21849)
			(xy 100.711758 -369.16888) (xy 100.696393 -369.116552) (xy 100.688631 -369.062569) (xy 98.911206 -369.062569)
			(xy 98.911206 -369.062571) (xy 98.903443 -369.116559) (xy 98.888077 -369.168893) (xy 98.865419 -369.218507)
			(xy 98.835931 -369.264391) (xy 98.800213 -369.305612) (xy 98.758993 -369.34133) (xy 98.713108 -369.370818)
			(xy 98.663494 -369.393476) (xy 98.611161 -369.408843) (xy 98.557173 -369.416605) (xy 98.529902 -369.417092)
			(xy 97.666302 -369.417092) (xy 97.639033 -369.416569) (xy 97.58505 -369.408807) (xy 97.532721 -369.393443)
			(xy 97.483112 -369.370787) (xy 97.437232 -369.341302) (xy 97.396014 -369.305587) (xy 97.3603 -369.26437)
			(xy 97.330814 -369.21849) (xy 97.308158 -369.16888) (xy 97.292793 -369.116552) (xy 97.285031 -369.062569)
			(xy 92.104006 -369.062569) (xy 92.104006 -369.062571) (xy 92.096243 -369.116559) (xy 92.080877 -369.168893)
			(xy 92.058219 -369.218507) (xy 92.028731 -369.264391) (xy 91.993013 -369.305612) (xy 91.951793 -369.34133)
			(xy 91.905908 -369.370818) (xy 91.856294 -369.393476) (xy 91.803961 -369.408843) (xy 91.749973 -369.416605)
			(xy 91.722702 -369.417092) (xy 90.859102 -369.417092) (xy 90.831833 -369.416569) (xy 90.77785 -369.408807)
			(xy 90.725521 -369.393443) (xy 90.675912 -369.370787) (xy 90.630032 -369.341302) (xy 90.588814 -369.305587)
			(xy 90.5531 -369.26437) (xy 90.523614 -369.21849) (xy 90.500958 -369.16888) (xy 90.485593 -369.116552)
			(xy 90.477831 -369.062569) (xy 85.296806 -369.062569) (xy 85.296806 -369.062571) (xy 85.289043 -369.116559)
			(xy 85.273677 -369.168893) (xy 85.251019 -369.218507) (xy 85.221531 -369.264391) (xy 85.185813 -369.305612)
			(xy 85.144593 -369.34133) (xy 85.098708 -369.370818) (xy 85.049094 -369.393476) (xy 84.996761 -369.408843)
			(xy 84.942773 -369.416605) (xy 84.915502 -369.417092) (xy 84.051902 -369.417092) (xy 84.024633 -369.416569)
			(xy 83.97065 -369.408807) (xy 83.918321 -369.393443) (xy 83.868712 -369.370787) (xy 83.822832 -369.341302)
			(xy 83.781614 -369.305587) (xy 83.7459 -369.26437) (xy 83.716414 -369.21849) (xy 83.693758 -369.16888)
			(xy 83.678393 -369.116552) (xy 83.670631 -369.062569) (xy 78.489606 -369.062569) (xy 78.489606 -369.062571)
			(xy 78.481843 -369.116559) (xy 78.466477 -369.168893) (xy 78.443819 -369.218507) (xy 78.414331 -369.264391)
			(xy 78.378613 -369.305612) (xy 78.337393 -369.34133) (xy 78.291508 -369.370818) (xy 78.241894 -369.393476)
			(xy 78.189561 -369.408843) (xy 78.135573 -369.416605) (xy 78.108302 -369.417092) (xy 77.244702 -369.417092)
			(xy 77.217433 -369.416569) (xy 77.16345 -369.408807) (xy 77.111121 -369.393443) (xy 77.061512 -369.370787)
			(xy 77.015632 -369.341302) (xy 76.974414 -369.305587) (xy 76.9387 -369.26437) (xy 76.909214 -369.21849)
			(xy 76.886558 -369.16888) (xy 76.871193 -369.116552) (xy 76.863431 -369.062569) (xy 69.843396 -369.062569)
			(xy 69.843396 -369.397788) (xy 69.843831 -369.407484) (xy 69.85102 -369.425495) (xy 69.857366 -369.43284)
			(xy 69.875234 -369.452254) (xy 69.906 -369.495118) (xy 69.93056 -369.541816) (xy 69.948445 -369.591454)
			(xy 69.959314 -369.643085) (xy 69.962958 -369.695722) (xy 69.959308 -369.748358) (xy 69.948434 -369.799987)
			(xy 69.930543 -369.849624) (xy 69.905977 -369.896319) (xy 69.875206 -369.939179) (xy 69.857366 -369.95862)
			(xy 69.850981 -369.96594) (xy 69.843793 -369.983967) (xy 69.843396 -369.993672) (xy 69.843396 -370.206778)
			(xy 138.3665 -370.206778) (xy 138.3665 -369.343178) (xy 138.366986 -369.315909) (xy 138.374748 -369.261925)
			(xy 138.390113 -369.209595) (xy 138.41277 -369.159985) (xy 138.442256 -369.114104) (xy 138.477971 -369.072887)
			(xy 138.519188 -369.037172) (xy 138.565069 -369.007686) (xy 138.614679 -368.985029) (xy 138.667009 -368.969664)
			(xy 138.720993 -368.961902) (xy 138.775531 -368.961902) (xy 138.829515 -368.969664) (xy 138.881845 -368.985029)
			(xy 138.931455 -369.007686) (xy 138.977336 -369.037172) (xy 139.006648 -369.062571) (xy 143.963332 -369.062571)
			(xy 143.963332 -369.008029) (xy 143.971094 -368.954043) (xy 143.986461 -368.901711) (xy 144.009121 -368.852098)
			(xy 144.03861 -368.806216) (xy 144.074329 -368.764998) (xy 144.115551 -368.729284) (xy 144.161437 -368.699799)
			(xy 144.211052 -368.677146) (xy 144.263386 -368.661785) (xy 144.317373 -368.654028) (xy 144.344644 -368.653568)
			(xy 145.208244 -368.653568) (xy 145.235513 -368.653998) (xy 145.289497 -368.661765) (xy 145.341825 -368.677135)
			(xy 145.391433 -368.699796) (xy 145.437312 -368.729285) (xy 145.478528 -368.765003) (xy 145.514241 -368.806223)
			(xy 145.543725 -368.852105) (xy 145.56638 -368.901716) (xy 145.581744 -368.954047) (xy 145.589506 -369.00803)
			(xy 145.589506 -369.06257) (xy 145.589506 -369.062571) (xy 150.770532 -369.062571) (xy 150.770532 -369.008029)
			(xy 150.778294 -368.954043) (xy 150.793661 -368.901711) (xy 150.816321 -368.852098) (xy 150.84581 -368.806216)
			(xy 150.881529 -368.764998) (xy 150.922751 -368.729284) (xy 150.968637 -368.699799) (xy 151.018252 -368.677146)
			(xy 151.070586 -368.661785) (xy 151.124573 -368.654028) (xy 151.151844 -368.653568) (xy 152.015444 -368.653568)
			(xy 152.042713 -368.653998) (xy 152.096697 -368.661765) (xy 152.149025 -368.677135) (xy 152.198633 -368.699796)
			(xy 152.244512 -368.729285) (xy 152.285728 -368.765003) (xy 152.321441 -368.806223) (xy 152.350925 -368.852105)
			(xy 152.37358 -368.901716) (xy 152.388944 -368.954047) (xy 152.396706 -369.00803) (xy 152.396706 -369.06257)
			(xy 152.396706 -369.062571) (xy 157.577732 -369.062571) (xy 157.577732 -369.008029) (xy 157.585494 -368.954043)
			(xy 157.600861 -368.901711) (xy 157.623521 -368.852098) (xy 157.65301 -368.806216) (xy 157.688729 -368.764998)
			(xy 157.729951 -368.729284) (xy 157.775837 -368.699799) (xy 157.825452 -368.677146) (xy 157.877786 -368.661785)
			(xy 157.931773 -368.654028) (xy 157.959044 -368.653568) (xy 158.822644 -368.653568) (xy 158.849913 -368.653998)
			(xy 158.903897 -368.661765) (xy 158.956225 -368.677135) (xy 159.005833 -368.699796) (xy 159.051712 -368.729285)
			(xy 159.092928 -368.765003) (xy 159.128641 -368.806223) (xy 159.158125 -368.852105) (xy 159.18078 -368.901716)
			(xy 159.196144 -368.954047) (xy 159.203906 -369.00803) (xy 159.203906 -369.06257) (xy 159.203906 -369.062571)
			(xy 164.384932 -369.062571) (xy 164.384932 -369.008029) (xy 164.392694 -368.954043) (xy 164.408061 -368.901711)
			(xy 164.430721 -368.852098) (xy 164.46021 -368.806216) (xy 164.495929 -368.764998) (xy 164.537151 -368.729284)
			(xy 164.583037 -368.699799) (xy 164.632652 -368.677146) (xy 164.684986 -368.661785) (xy 164.738973 -368.654028)
			(xy 164.766244 -368.653568) (xy 165.629844 -368.653568) (xy 165.657113 -368.653998) (xy 165.711097 -368.661765)
			(xy 165.763425 -368.677135) (xy 165.813033 -368.699796) (xy 165.858912 -368.729285) (xy 165.900128 -368.765003)
			(xy 165.935841 -368.806223) (xy 165.965325 -368.852105) (xy 165.98798 -368.901716) (xy 166.003344 -368.954047)
			(xy 166.011106 -369.00803) (xy 166.011106 -369.06257) (xy 166.011106 -369.062571) (xy 167.788532 -369.062571)
			(xy 167.788532 -369.008029) (xy 167.796294 -368.954043) (xy 167.811661 -368.901711) (xy 167.834321 -368.852098)
			(xy 167.86381 -368.806216) (xy 167.899529 -368.764998) (xy 167.940751 -368.729284) (xy 167.986637 -368.699799)
			(xy 168.036252 -368.677146) (xy 168.088586 -368.661785) (xy 168.142573 -368.654028) (xy 168.169844 -368.653568)
			(xy 169.033444 -368.653568) (xy 169.060713 -368.653998) (xy 169.114697 -368.661765) (xy 169.167025 -368.677135)
			(xy 169.216633 -368.699796) (xy 169.262512 -368.729285) (xy 169.303728 -368.765003) (xy 169.339441 -368.806223)
			(xy 169.368925 -368.852105) (xy 169.39158 -368.901716) (xy 169.406944 -368.954047) (xy 169.414706 -369.00803)
			(xy 169.414706 -369.06257) (xy 169.406944 -369.116553) (xy 169.39158 -369.168884) (xy 169.368925 -369.218495)
			(xy 169.339441 -369.264377) (xy 169.303728 -369.305597) (xy 169.262512 -369.341315) (xy 169.216633 -369.370804)
			(xy 169.167025 -369.393465) (xy 169.114697 -369.408835) (xy 169.060713 -369.416602) (xy 169.033444 -369.417092)
			(xy 168.169844 -369.417092) (xy 168.142573 -369.416572) (xy 168.088586 -369.408815) (xy 168.036252 -369.393454)
			(xy 167.986637 -369.370801) (xy 167.940751 -369.341316) (xy 167.899529 -369.305602) (xy 167.86381 -369.264384)
			(xy 167.834321 -369.218502) (xy 167.811661 -369.168889) (xy 167.796294 -369.116557) (xy 167.788532 -369.062571)
			(xy 166.011106 -369.062571) (xy 166.003344 -369.116553) (xy 165.98798 -369.168884) (xy 165.965325 -369.218495)
			(xy 165.935841 -369.264377) (xy 165.900128 -369.305597) (xy 165.858912 -369.341315) (xy 165.813033 -369.370804)
			(xy 165.763425 -369.393465) (xy 165.711097 -369.408835) (xy 165.657113 -369.416602) (xy 165.629844 -369.417092)
			(xy 164.766244 -369.417092) (xy 164.738973 -369.416572) (xy 164.684986 -369.408815) (xy 164.632652 -369.393454)
			(xy 164.583037 -369.370801) (xy 164.537151 -369.341316) (xy 164.495929 -369.305602) (xy 164.46021 -369.264384)
			(xy 164.430721 -369.218502) (xy 164.408061 -369.168889) (xy 164.392694 -369.116557) (xy 164.384932 -369.062571)
			(xy 159.203906 -369.062571) (xy 159.196144 -369.116553) (xy 159.18078 -369.168884) (xy 159.158125 -369.218495)
			(xy 159.128641 -369.264377) (xy 159.092928 -369.305597) (xy 159.051712 -369.341315) (xy 159.005833 -369.370804)
			(xy 158.956225 -369.393465) (xy 158.903897 -369.408835) (xy 158.849913 -369.416602) (xy 158.822644 -369.417092)
			(xy 157.959044 -369.417092) (xy 157.931773 -369.416572) (xy 157.877786 -369.408815) (xy 157.825452 -369.393454)
			(xy 157.775837 -369.370801) (xy 157.729951 -369.341316) (xy 157.688729 -369.305602) (xy 157.65301 -369.264384)
			(xy 157.623521 -369.218502) (xy 157.600861 -369.168889) (xy 157.585494 -369.116557) (xy 157.577732 -369.062571)
			(xy 152.396706 -369.062571) (xy 152.388944 -369.116553) (xy 152.37358 -369.168884) (xy 152.350925 -369.218495)
			(xy 152.321441 -369.264377) (xy 152.285728 -369.305597) (xy 152.244512 -369.341315) (xy 152.198633 -369.370804)
			(xy 152.149025 -369.393465) (xy 152.096697 -369.408835) (xy 152.042713 -369.416602) (xy 152.015444 -369.417092)
			(xy 151.151844 -369.417092) (xy 151.124573 -369.416572) (xy 151.070586 -369.408815) (xy 151.018252 -369.393454)
			(xy 150.968637 -369.370801) (xy 150.922751 -369.341316) (xy 150.881529 -369.305602) (xy 150.84581 -369.264384)
			(xy 150.816321 -369.218502) (xy 150.793661 -369.168889) (xy 150.778294 -369.116557) (xy 150.770532 -369.062571)
			(xy 145.589506 -369.062571) (xy 145.581744 -369.116553) (xy 145.56638 -369.168884) (xy 145.543725 -369.218495)
			(xy 145.514241 -369.264377) (xy 145.478528 -369.305597) (xy 145.437312 -369.341315) (xy 145.391433 -369.370804)
			(xy 145.341825 -369.393465) (xy 145.289497 -369.408835) (xy 145.235513 -369.416602) (xy 145.208244 -369.417092)
			(xy 144.344644 -369.417092) (xy 144.317373 -369.416572) (xy 144.263386 -369.408815) (xy 144.211052 -369.393454)
			(xy 144.161437 -369.370801) (xy 144.115551 -369.341316) (xy 144.074329 -369.305602) (xy 144.03861 -369.264384)
			(xy 144.009121 -369.218502) (xy 143.986461 -369.168889) (xy 143.971094 -369.116557) (xy 143.963332 -369.062571)
			(xy 139.006648 -369.062571) (xy 139.018553 -369.072887) (xy 139.054268 -369.114104) (xy 139.083754 -369.159985)
			(xy 139.106411 -369.209595) (xy 139.121776 -369.261925) (xy 139.129538 -369.315909) (xy 139.130024 -369.343178)
			(xy 139.130024 -370.206778) (xy 139.129538 -370.234047) (xy 139.121776 -370.288031) (xy 139.106411 -370.340361)
			(xy 139.083754 -370.389971) (xy 139.071223 -370.40947) (xy 141.572996 -370.40947) (xy 141.572996 -369.54587)
			(xy 141.573482 -369.518619) (xy 141.581238 -369.464671) (xy 141.596593 -369.412376) (xy 141.619235 -369.362799)
			(xy 141.648701 -369.316949) (xy 141.684392 -369.275758) (xy 141.725583 -369.240067) (xy 141.771433 -369.210601)
			(xy 141.82101 -369.187959) (xy 141.873305 -369.172604) (xy 141.927253 -369.164848) (xy 141.981755 -369.164848)
			(xy 142.035703 -369.172604) (xy 142.087998 -369.187959) (xy 142.137575 -369.210601) (xy 142.183425 -369.240067)
			(xy 142.224616 -369.275758) (xy 142.260307 -369.316949) (xy 142.289773 -369.362799) (xy 142.312415 -369.412376)
			(xy 142.32777 -369.464671) (xy 142.335526 -369.518619) (xy 142.336012 -369.54587) (xy 142.336012 -369.62565)
			(xy 175.203103 -369.62565) (xy 175.203103 -369.57115) (xy 175.210859 -369.517206) (xy 175.226214 -369.464914)
			(xy 175.248854 -369.41534) (xy 175.278318 -369.369493) (xy 175.314008 -369.328305) (xy 175.355196 -369.292616)
			(xy 175.401044 -369.263152) (xy 175.450618 -369.240512) (xy 175.50291 -369.225158) (xy 175.556854 -369.217403)
			(xy 175.584104 -369.21694) (xy 176.447704 -369.21694) (xy 176.474958 -369.21733) (xy 176.528913 -369.225088)
			(xy 176.581213 -369.240446) (xy 176.630796 -369.26309) (xy 176.676652 -369.29256) (xy 176.717847 -369.328256)
			(xy 176.753543 -369.369451) (xy 176.783012 -369.415307) (xy 176.805656 -369.46489) (xy 176.821013 -369.517191)
			(xy 176.82877 -369.571146) (xy 176.82877 -369.625654) (xy 176.821013 -369.679609) (xy 176.805656 -369.73191)
			(xy 176.783012 -369.781493) (xy 176.753543 -369.827349) (xy 176.717847 -369.868544) (xy 176.676652 -369.90424)
			(xy 176.630796 -369.93371) (xy 176.581213 -369.956354) (xy 176.528913 -369.971712) (xy 176.474958 -369.97947)
			(xy 176.447704 -369.979956) (xy 175.584104 -369.979956) (xy 175.556854 -369.979397) (xy 175.50291 -369.971642)
			(xy 175.450618 -369.956288) (xy 175.401044 -369.933648) (xy 175.355196 -369.904184) (xy 175.314008 -369.868495)
			(xy 175.278318 -369.827307) (xy 175.248854 -369.78146) (xy 175.226214 -369.731886) (xy 175.210859 -369.679594)
			(xy 175.203103 -369.62565) (xy 142.336012 -369.62565) (xy 142.336012 -370.40947) (xy 142.335526 -370.436721)
			(xy 142.32777 -370.490669) (xy 142.312415 -370.542964) (xy 142.289773 -370.592541) (xy 142.260307 -370.638391)
			(xy 142.224616 -370.679582) (xy 142.183425 -370.715273) (xy 142.137575 -370.744739) (xy 142.087998 -370.767381)
			(xy 142.035703 -370.782736) (xy 141.981755 -370.790492) (xy 141.927253 -370.790492) (xy 141.873305 -370.782736)
			(xy 141.82101 -370.767381) (xy 141.771433 -370.744739) (xy 141.725583 -370.715273) (xy 141.684392 -370.679582)
			(xy 141.648701 -370.638391) (xy 141.619235 -370.592541) (xy 141.596593 -370.542964) (xy 141.581238 -370.490669)
			(xy 141.573482 -370.436721) (xy 141.572996 -370.40947) (xy 139.071223 -370.40947) (xy 139.054268 -370.435852)
			(xy 139.018553 -370.477069) (xy 138.977336 -370.512784) (xy 138.931455 -370.54227) (xy 138.881845 -370.564927)
			(xy 138.829515 -370.580292) (xy 138.775531 -370.588054) (xy 138.720993 -370.588054) (xy 138.667009 -370.580292)
			(xy 138.614679 -370.564927) (xy 138.565069 -370.54227) (xy 138.519188 -370.512784) (xy 138.477971 -370.477069)
			(xy 138.442256 -370.435852) (xy 138.41277 -370.389971) (xy 138.390113 -370.340361) (xy 138.374748 -370.288031)
			(xy 138.366986 -370.234047) (xy 138.3665 -370.206778) (xy 69.843396 -370.206778) (xy 69.843396 -371.526369)
			(xy 75.161631 -371.526369) (xy 75.161631 -371.471831) (xy 75.169393 -371.417848) (xy 75.184758 -371.36552)
			(xy 75.207414 -371.31591) (xy 75.2369 -371.27003) (xy 75.272614 -371.228813) (xy 75.313832 -371.193098)
			(xy 75.359712 -371.163613) (xy 75.409321 -371.140957) (xy 75.46165 -371.125593) (xy 75.515633 -371.117831)
			(xy 75.542902 -371.117368) (xy 76.406502 -371.117368) (xy 76.433773 -371.117795) (xy 76.487761 -371.125557)
			(xy 76.540094 -371.140924) (xy 76.589708 -371.163582) (xy 76.635593 -371.19307) (xy 76.676813 -371.228788)
			(xy 76.712531 -371.270009) (xy 76.742019 -371.315893) (xy 76.764677 -371.365507) (xy 76.780043 -371.417841)
			(xy 76.787806 -371.471829) (xy 76.787806 -371.526369) (xy 81.968831 -371.526369) (xy 81.968831 -371.471831)
			(xy 81.976593 -371.417848) (xy 81.991958 -371.36552) (xy 82.014614 -371.31591) (xy 82.0441 -371.27003)
			(xy 82.079814 -371.228813) (xy 82.121032 -371.193098) (xy 82.166912 -371.163613) (xy 82.216521 -371.140957)
			(xy 82.26885 -371.125593) (xy 82.322833 -371.117831) (xy 82.350102 -371.117368) (xy 83.213702 -371.117368)
			(xy 83.240973 -371.117795) (xy 83.294961 -371.125557) (xy 83.347294 -371.140924) (xy 83.396908 -371.163582)
			(xy 83.442793 -371.19307) (xy 83.484013 -371.228788) (xy 83.519731 -371.270009) (xy 83.549219 -371.315893)
			(xy 83.571877 -371.365507) (xy 83.587243 -371.417841) (xy 83.595006 -371.471829) (xy 83.595006 -371.526369)
			(xy 88.776031 -371.526369) (xy 88.776031 -371.471831) (xy 88.783793 -371.417848) (xy 88.799158 -371.36552)
			(xy 88.821814 -371.31591) (xy 88.8513 -371.27003) (xy 88.887014 -371.228813) (xy 88.928232 -371.193098)
			(xy 88.974112 -371.163613) (xy 89.023721 -371.140957) (xy 89.07605 -371.125593) (xy 89.130033 -371.117831)
			(xy 89.157302 -371.117368) (xy 90.020902 -371.117368) (xy 90.048173 -371.117795) (xy 90.102161 -371.125557)
			(xy 90.154494 -371.140924) (xy 90.204108 -371.163582) (xy 90.249993 -371.19307) (xy 90.291213 -371.228788)
			(xy 90.326931 -371.270009) (xy 90.356419 -371.315893) (xy 90.379077 -371.365507) (xy 90.394443 -371.417841)
			(xy 90.402206 -371.471829) (xy 90.402206 -371.526369) (xy 95.583231 -371.526369) (xy 95.583231 -371.471831)
			(xy 95.590993 -371.417848) (xy 95.606358 -371.36552) (xy 95.629014 -371.31591) (xy 95.6585 -371.27003)
			(xy 95.694214 -371.228813) (xy 95.735432 -371.193098) (xy 95.781312 -371.163613) (xy 95.830921 -371.140957)
			(xy 95.88325 -371.125593) (xy 95.937233 -371.117831) (xy 95.964502 -371.117368) (xy 96.828102 -371.117368)
			(xy 96.855373 -371.117795) (xy 96.909361 -371.125557) (xy 96.961694 -371.140924) (xy 97.011308 -371.163582)
			(xy 97.057193 -371.19307) (xy 97.098413 -371.228788) (xy 97.134131 -371.270009) (xy 97.163619 -371.315893)
			(xy 97.186277 -371.365507) (xy 97.201643 -371.417841) (xy 97.209406 -371.471829) (xy 97.209406 -371.526367)
			(xy 109.733854 -371.526367) (xy 109.733854 -371.471833) (xy 109.741615 -371.417854) (xy 109.756979 -371.365529)
			(xy 109.779633 -371.315923) (xy 109.809117 -371.270046) (xy 109.844829 -371.228831) (xy 109.886042 -371.193119)
			(xy 109.931919 -371.163635) (xy 109.981525 -371.140981) (xy 110.03385 -371.125616) (xy 110.087829 -371.117855)
			(xy 110.115096 -371.117368) (xy 110.978696 -371.117368) (xy 111.005969 -371.117771) (xy 111.059961 -371.125534)
			(xy 111.112298 -371.140901) (xy 111.161916 -371.16356) (xy 111.207803 -371.19305) (xy 111.249027 -371.22877)
			(xy 111.284748 -371.269993) (xy 111.314238 -371.315881) (xy 111.336898 -371.365498) (xy 111.352266 -371.417835)
			(xy 111.360028 -371.471827) (xy 111.360028 -371.526367) (xy 116.541054 -371.526367) (xy 116.541054 -371.471833)
			(xy 116.548815 -371.417854) (xy 116.564179 -371.365529) (xy 116.586833 -371.315923) (xy 116.616317 -371.270046)
			(xy 116.652029 -371.228831) (xy 116.693242 -371.193119) (xy 116.739119 -371.163635) (xy 116.788725 -371.140981)
			(xy 116.84105 -371.125616) (xy 116.895029 -371.117855) (xy 116.922296 -371.117368) (xy 117.785896 -371.117368)
			(xy 117.813169 -371.117771) (xy 117.867161 -371.125534) (xy 117.919498 -371.140901) (xy 117.969116 -371.16356)
			(xy 118.015003 -371.19305) (xy 118.056227 -371.22877) (xy 118.091948 -371.269993) (xy 118.121438 -371.315881)
			(xy 118.144098 -371.365498) (xy 118.159466 -371.417835) (xy 118.167228 -371.471827) (xy 118.167228 -371.526367)
			(xy 123.348254 -371.526367) (xy 123.348254 -371.471833) (xy 123.356015 -371.417854) (xy 123.371379 -371.365529)
			(xy 123.394033 -371.315923) (xy 123.423517 -371.270046) (xy 123.459229 -371.228831) (xy 123.500442 -371.193119)
			(xy 123.546319 -371.163635) (xy 123.595925 -371.140981) (xy 123.64825 -371.125616) (xy 123.702229 -371.117855)
			(xy 123.729496 -371.117368) (xy 124.593096 -371.117368) (xy 124.620369 -371.117771) (xy 124.674361 -371.125534)
			(xy 124.726698 -371.140901) (xy 124.776316 -371.16356) (xy 124.822203 -371.19305) (xy 124.863427 -371.22877)
			(xy 124.899148 -371.269993) (xy 124.928638 -371.315881) (xy 124.951298 -371.365498) (xy 124.966666 -371.417835)
			(xy 124.974428 -371.471827) (xy 124.974428 -371.526367) (xy 130.155454 -371.526367) (xy 130.155454 -371.471833)
			(xy 130.163215 -371.417854) (xy 130.178579 -371.365529) (xy 130.201233 -371.315923) (xy 130.230717 -371.270046)
			(xy 130.266429 -371.228831) (xy 130.307642 -371.193119) (xy 130.353519 -371.163635) (xy 130.403125 -371.140981)
			(xy 130.45545 -371.125616) (xy 130.509429 -371.117855) (xy 130.536696 -371.117368) (xy 131.400296 -371.117368)
			(xy 131.427569 -371.117771) (xy 131.481561 -371.125534) (xy 131.533898 -371.140901) (xy 131.583516 -371.16356)
			(xy 131.629403 -371.19305) (xy 131.670627 -371.22877) (xy 131.706348 -371.269993) (xy 131.735838 -371.315881)
			(xy 131.758498 -371.365498) (xy 131.773866 -371.417835) (xy 131.781628 -371.471827) (xy 131.781628 -371.526371)
			(xy 142.261532 -371.526371) (xy 142.261532 -371.471829) (xy 142.269294 -371.417843) (xy 142.284661 -371.365511)
			(xy 142.307321 -371.315898) (xy 142.33681 -371.270016) (xy 142.372529 -371.228798) (xy 142.413751 -371.193084)
			(xy 142.459637 -371.163599) (xy 142.509252 -371.140946) (xy 142.561586 -371.125585) (xy 142.615573 -371.117828)
			(xy 142.642844 -371.117368) (xy 143.506444 -371.117368) (xy 143.533713 -371.117798) (xy 143.587697 -371.125565)
			(xy 143.640025 -371.140935) (xy 143.689633 -371.163596) (xy 143.735512 -371.193085) (xy 143.776728 -371.228803)
			(xy 143.812441 -371.270023) (xy 143.841925 -371.315905) (xy 143.86458 -371.365516) (xy 143.879944 -371.417847)
			(xy 143.887706 -371.47183) (xy 143.887706 -371.52637) (xy 143.887706 -371.526371) (xy 149.068732 -371.526371)
			(xy 149.068732 -371.471829) (xy 149.076494 -371.417843) (xy 149.091861 -371.365511) (xy 149.114521 -371.315898)
			(xy 149.14401 -371.270016) (xy 149.179729 -371.228798) (xy 149.220951 -371.193084) (xy 149.266837 -371.163599)
			(xy 149.316452 -371.140946) (xy 149.368786 -371.125585) (xy 149.422773 -371.117828) (xy 149.450044 -371.117368)
			(xy 150.313644 -371.117368) (xy 150.340913 -371.117798) (xy 150.394897 -371.125565) (xy 150.447225 -371.140935)
			(xy 150.496833 -371.163596) (xy 150.542712 -371.193085) (xy 150.583928 -371.228803) (xy 150.619641 -371.270023)
			(xy 150.649125 -371.315905) (xy 150.67178 -371.365516) (xy 150.687144 -371.417847) (xy 150.694906 -371.47183)
			(xy 150.694906 -371.52637) (xy 150.694906 -371.526371) (xy 155.875932 -371.526371) (xy 155.875932 -371.471829)
			(xy 155.883694 -371.417843) (xy 155.899061 -371.365511) (xy 155.921721 -371.315898) (xy 155.95121 -371.270016)
			(xy 155.986929 -371.228798) (xy 156.028151 -371.193084) (xy 156.074037 -371.163599) (xy 156.123652 -371.140946)
			(xy 156.175986 -371.125585) (xy 156.229973 -371.117828) (xy 156.257244 -371.117368) (xy 157.120844 -371.117368)
			(xy 157.148113 -371.117798) (xy 157.202097 -371.125565) (xy 157.254425 -371.140935) (xy 157.304033 -371.163596)
			(xy 157.349912 -371.193085) (xy 157.391128 -371.228803) (xy 157.426841 -371.270023) (xy 157.456325 -371.315905)
			(xy 157.47898 -371.365516) (xy 157.494344 -371.417847) (xy 157.502106 -371.47183) (xy 157.502106 -371.52637)
			(xy 157.502106 -371.526371) (xy 162.683132 -371.526371) (xy 162.683132 -371.471829) (xy 162.690894 -371.417843)
			(xy 162.706261 -371.365511) (xy 162.728921 -371.315898) (xy 162.75841 -371.270016) (xy 162.794129 -371.228798)
			(xy 162.835351 -371.193084) (xy 162.881237 -371.163599) (xy 162.930852 -371.140946) (xy 162.983186 -371.125585)
			(xy 163.037173 -371.117828) (xy 163.064444 -371.117368) (xy 163.928044 -371.117368) (xy 163.955313 -371.117798)
			(xy 164.009297 -371.125565) (xy 164.061625 -371.140935) (xy 164.111233 -371.163596) (xy 164.157112 -371.193085)
			(xy 164.198328 -371.228803) (xy 164.234041 -371.270023) (xy 164.263525 -371.315905) (xy 164.28618 -371.365516)
			(xy 164.301544 -371.417847) (xy 164.309306 -371.47183) (xy 164.309306 -371.52637) (xy 164.301544 -371.580353)
			(xy 164.28618 -371.632684) (xy 164.263525 -371.682295) (xy 164.234041 -371.728177) (xy 164.198328 -371.769397)
			(xy 164.157112 -371.805115) (xy 164.111233 -371.834604) (xy 164.061625 -371.857265) (xy 164.009297 -371.872635)
			(xy 163.955313 -371.880402) (xy 163.928044 -371.880892) (xy 163.064444 -371.880892) (xy 163.037173 -371.880372)
			(xy 162.983186 -371.872615) (xy 162.930852 -371.857254) (xy 162.881237 -371.834601) (xy 162.835351 -371.805116)
			(xy 162.794129 -371.769402) (xy 162.75841 -371.728184) (xy 162.728921 -371.682302) (xy 162.706261 -371.632689)
			(xy 162.690894 -371.580357) (xy 162.683132 -371.526371) (xy 157.502106 -371.526371) (xy 157.494344 -371.580353)
			(xy 157.47898 -371.632684) (xy 157.456325 -371.682295) (xy 157.426841 -371.728177) (xy 157.391128 -371.769397)
			(xy 157.349912 -371.805115) (xy 157.304033 -371.834604) (xy 157.254425 -371.857265) (xy 157.202097 -371.872635)
			(xy 157.148113 -371.880402) (xy 157.120844 -371.880892) (xy 156.257244 -371.880892) (xy 156.229973 -371.880372)
			(xy 156.175986 -371.872615) (xy 156.123652 -371.857254) (xy 156.074037 -371.834601) (xy 156.028151 -371.805116)
			(xy 155.986929 -371.769402) (xy 155.95121 -371.728184) (xy 155.921721 -371.682302) (xy 155.899061 -371.632689)
			(xy 155.883694 -371.580357) (xy 155.875932 -371.526371) (xy 150.694906 -371.526371) (xy 150.687144 -371.580353)
			(xy 150.67178 -371.632684) (xy 150.649125 -371.682295) (xy 150.619641 -371.728177) (xy 150.583928 -371.769397)
			(xy 150.542712 -371.805115) (xy 150.496833 -371.834604) (xy 150.447225 -371.857265) (xy 150.394897 -371.872635)
			(xy 150.340913 -371.880402) (xy 150.313644 -371.880892) (xy 149.450044 -371.880892) (xy 149.422773 -371.880372)
			(xy 149.368786 -371.872615) (xy 149.316452 -371.857254) (xy 149.266837 -371.834601) (xy 149.220951 -371.805116)
			(xy 149.179729 -371.769402) (xy 149.14401 -371.728184) (xy 149.114521 -371.682302) (xy 149.091861 -371.632689)
			(xy 149.076494 -371.580357) (xy 149.068732 -371.526371) (xy 143.887706 -371.526371) (xy 143.879944 -371.580353)
			(xy 143.86458 -371.632684) (xy 143.841925 -371.682295) (xy 143.812441 -371.728177) (xy 143.776728 -371.769397)
			(xy 143.735512 -371.805115) (xy 143.689633 -371.834604) (xy 143.640025 -371.857265) (xy 143.587697 -371.872635)
			(xy 143.533713 -371.880402) (xy 143.506444 -371.880892) (xy 142.642844 -371.880892) (xy 142.615573 -371.880372)
			(xy 142.561586 -371.872615) (xy 142.509252 -371.857254) (xy 142.459637 -371.834601) (xy 142.413751 -371.805116)
			(xy 142.372529 -371.769402) (xy 142.33681 -371.728184) (xy 142.307321 -371.682302) (xy 142.284661 -371.632689)
			(xy 142.269294 -371.580357) (xy 142.261532 -371.526371) (xy 131.781628 -371.526371) (xy 131.781628 -371.526373)
			(xy 131.773866 -371.580365) (xy 131.758498 -371.632702) (xy 131.735838 -371.682319) (xy 131.706348 -371.728207)
			(xy 131.670627 -371.76943) (xy 131.629403 -371.80515) (xy 131.583516 -371.83464) (xy 131.533898 -371.857299)
			(xy 131.481561 -371.872666) (xy 131.427569 -371.880429) (xy 131.400296 -371.880892) (xy 130.536696 -371.880892)
			(xy 130.509429 -371.880345) (xy 130.45545 -371.872584) (xy 130.403125 -371.857219) (xy 130.353519 -371.834565)
			(xy 130.307642 -371.805081) (xy 130.266429 -371.769369) (xy 130.230717 -371.728154) (xy 130.201233 -371.682277)
			(xy 130.178579 -371.632671) (xy 130.163215 -371.580346) (xy 130.155454 -371.526367) (xy 124.974428 -371.526367)
			(xy 124.974428 -371.526373) (xy 124.966666 -371.580365) (xy 124.951298 -371.632702) (xy 124.928638 -371.682319)
			(xy 124.899148 -371.728207) (xy 124.863427 -371.76943) (xy 124.822203 -371.80515) (xy 124.776316 -371.83464)
			(xy 124.726698 -371.857299) (xy 124.674361 -371.872666) (xy 124.620369 -371.880429) (xy 124.593096 -371.880892)
			(xy 123.729496 -371.880892) (xy 123.702229 -371.880345) (xy 123.64825 -371.872584) (xy 123.595925 -371.857219)
			(xy 123.546319 -371.834565) (xy 123.500442 -371.805081) (xy 123.459229 -371.769369) (xy 123.423517 -371.728154)
			(xy 123.394033 -371.682277) (xy 123.371379 -371.632671) (xy 123.356015 -371.580346) (xy 123.348254 -371.526367)
			(xy 118.167228 -371.526367) (xy 118.167228 -371.526373) (xy 118.159466 -371.580365) (xy 118.144098 -371.632702)
			(xy 118.121438 -371.682319) (xy 118.091948 -371.728207) (xy 118.056227 -371.76943) (xy 118.015003 -371.80515)
			(xy 117.969116 -371.83464) (xy 117.919498 -371.857299) (xy 117.867161 -371.872666) (xy 117.813169 -371.880429)
			(xy 117.785896 -371.880892) (xy 116.922296 -371.880892) (xy 116.895029 -371.880345) (xy 116.84105 -371.872584)
			(xy 116.788725 -371.857219) (xy 116.739119 -371.834565) (xy 116.693242 -371.805081) (xy 116.652029 -371.769369)
			(xy 116.616317 -371.728154) (xy 116.586833 -371.682277) (xy 116.564179 -371.632671) (xy 116.548815 -371.580346)
			(xy 116.541054 -371.526367) (xy 111.360028 -371.526367) (xy 111.360028 -371.526373) (xy 111.352266 -371.580365)
			(xy 111.336898 -371.632702) (xy 111.314238 -371.682319) (xy 111.284748 -371.728207) (xy 111.249027 -371.76943)
			(xy 111.207803 -371.80515) (xy 111.161916 -371.83464) (xy 111.112298 -371.857299) (xy 111.059961 -371.872666)
			(xy 111.005969 -371.880429) (xy 110.978696 -371.880892) (xy 110.115096 -371.880892) (xy 110.087829 -371.880345)
			(xy 110.03385 -371.872584) (xy 109.981525 -371.857219) (xy 109.931919 -371.834565) (xy 109.886042 -371.805081)
			(xy 109.844829 -371.769369) (xy 109.809117 -371.728154) (xy 109.779633 -371.682277) (xy 109.756979 -371.632671)
			(xy 109.741615 -371.580346) (xy 109.733854 -371.526367) (xy 97.209406 -371.526367) (xy 97.209406 -371.526371)
			(xy 97.201643 -371.580359) (xy 97.186277 -371.632693) (xy 97.163619 -371.682307) (xy 97.134131 -371.728191)
			(xy 97.098413 -371.769412) (xy 97.057193 -371.80513) (xy 97.011308 -371.834618) (xy 96.961694 -371.857276)
			(xy 96.909361 -371.872643) (xy 96.855373 -371.880405) (xy 96.828102 -371.880892) (xy 95.964502 -371.880892)
			(xy 95.937233 -371.880369) (xy 95.88325 -371.872607) (xy 95.830921 -371.857243) (xy 95.781312 -371.834587)
			(xy 95.735432 -371.805102) (xy 95.694214 -371.769387) (xy 95.6585 -371.72817) (xy 95.629014 -371.68229)
			(xy 95.606358 -371.63268) (xy 95.590993 -371.580352) (xy 95.583231 -371.526369) (xy 90.402206 -371.526369)
			(xy 90.402206 -371.526371) (xy 90.394443 -371.580359) (xy 90.379077 -371.632693) (xy 90.356419 -371.682307)
			(xy 90.326931 -371.728191) (xy 90.291213 -371.769412) (xy 90.249993 -371.80513) (xy 90.204108 -371.834618)
			(xy 90.154494 -371.857276) (xy 90.102161 -371.872643) (xy 90.048173 -371.880405) (xy 90.020902 -371.880892)
			(xy 89.157302 -371.880892) (xy 89.130033 -371.880369) (xy 89.07605 -371.872607) (xy 89.023721 -371.857243)
			(xy 88.974112 -371.834587) (xy 88.928232 -371.805102) (xy 88.887014 -371.769387) (xy 88.8513 -371.72817)
			(xy 88.821814 -371.68229) (xy 88.799158 -371.63268) (xy 88.783793 -371.580352) (xy 88.776031 -371.526369)
			(xy 83.595006 -371.526369) (xy 83.595006 -371.526371) (xy 83.587243 -371.580359) (xy 83.571877 -371.632693)
			(xy 83.549219 -371.682307) (xy 83.519731 -371.728191) (xy 83.484013 -371.769412) (xy 83.442793 -371.80513)
			(xy 83.396908 -371.834618) (xy 83.347294 -371.857276) (xy 83.294961 -371.872643) (xy 83.240973 -371.880405)
			(xy 83.213702 -371.880892) (xy 82.350102 -371.880892) (xy 82.322833 -371.880369) (xy 82.26885 -371.872607)
			(xy 82.216521 -371.857243) (xy 82.166912 -371.834587) (xy 82.121032 -371.805102) (xy 82.079814 -371.769387)
			(xy 82.0441 -371.72817) (xy 82.014614 -371.68229) (xy 81.991958 -371.63268) (xy 81.976593 -371.580352)
			(xy 81.968831 -371.526369) (xy 76.787806 -371.526369) (xy 76.787806 -371.526371) (xy 76.780043 -371.580359)
			(xy 76.764677 -371.632693) (xy 76.742019 -371.682307) (xy 76.712531 -371.728191) (xy 76.676813 -371.769412)
			(xy 76.635593 -371.80513) (xy 76.589708 -371.834618) (xy 76.540094 -371.857276) (xy 76.487761 -371.872643)
			(xy 76.433773 -371.880405) (xy 76.406502 -371.880892) (xy 75.542902 -371.880892) (xy 75.515633 -371.880369)
			(xy 75.46165 -371.872607) (xy 75.409321 -371.857243) (xy 75.359712 -371.834587) (xy 75.313832 -371.805102)
			(xy 75.272614 -371.769387) (xy 75.2369 -371.72817) (xy 75.207414 -371.68229) (xy 75.184758 -371.63268)
			(xy 75.169393 -371.580352) (xy 75.161631 -371.526369) (xy 69.843396 -371.526369) (xy 69.843396 -373.990169)
			(xy 80.267031 -373.990169) (xy 80.267031 -373.935631) (xy 80.274793 -373.881648) (xy 80.290158 -373.82932)
			(xy 80.312814 -373.77971) (xy 80.3423 -373.73383) (xy 80.378014 -373.692613) (xy 80.419232 -373.656898)
			(xy 80.465112 -373.627413) (xy 80.514721 -373.604757) (xy 80.56705 -373.589393) (xy 80.621033 -373.581631)
			(xy 80.648302 -373.581168) (xy 81.511902 -373.581168) (xy 81.539173 -373.581595) (xy 81.593161 -373.589357)
			(xy 81.645494 -373.604724) (xy 81.695108 -373.627382) (xy 81.740993 -373.65687) (xy 81.782213 -373.692588)
			(xy 81.817931 -373.733809) (xy 81.847419 -373.779693) (xy 81.870077 -373.829307) (xy 81.885443 -373.881641)
			(xy 81.893206 -373.935629) (xy 81.893206 -373.990169) (xy 87.074231 -373.990169) (xy 87.074231 -373.935631)
			(xy 87.081993 -373.881648) (xy 87.097358 -373.82932) (xy 87.120014 -373.77971) (xy 87.1495 -373.73383)
			(xy 87.185214 -373.692613) (xy 87.226432 -373.656898) (xy 87.272312 -373.627413) (xy 87.321921 -373.604757)
			(xy 87.37425 -373.589393) (xy 87.428233 -373.581631) (xy 87.455502 -373.581168) (xy 88.319102 -373.581168)
			(xy 88.346373 -373.581595) (xy 88.400361 -373.589357) (xy 88.452694 -373.604724) (xy 88.502308 -373.627382)
			(xy 88.548193 -373.65687) (xy 88.589413 -373.692588) (xy 88.625131 -373.733809) (xy 88.654619 -373.779693)
			(xy 88.677277 -373.829307) (xy 88.692643 -373.881641) (xy 88.700406 -373.935629) (xy 88.700406 -373.990169)
			(xy 93.881431 -373.990169) (xy 93.881431 -373.935631) (xy 93.889193 -373.881648) (xy 93.904558 -373.82932)
			(xy 93.927214 -373.77971) (xy 93.9567 -373.73383) (xy 93.992414 -373.692613) (xy 94.033632 -373.656898)
			(xy 94.079512 -373.627413) (xy 94.129121 -373.604757) (xy 94.18145 -373.589393) (xy 94.235433 -373.581631)
			(xy 94.262702 -373.581168) (xy 95.126302 -373.581168) (xy 95.153573 -373.581595) (xy 95.207561 -373.589357)
			(xy 95.259894 -373.604724) (xy 95.309508 -373.627382) (xy 95.355393 -373.65687) (xy 95.396613 -373.692588)
			(xy 95.432331 -373.733809) (xy 95.461819 -373.779693) (xy 95.484477 -373.829307) (xy 95.499843 -373.881641)
			(xy 95.507606 -373.935629) (xy 95.507606 -373.990167) (xy 114.839254 -373.990167) (xy 114.839254 -373.935633)
			(xy 114.847015 -373.881654) (xy 114.862379 -373.829329) (xy 114.885033 -373.779723) (xy 114.914517 -373.733846)
			(xy 114.950229 -373.692631) (xy 114.991442 -373.656919) (xy 115.037319 -373.627435) (xy 115.086925 -373.604781)
			(xy 115.13925 -373.589416) (xy 115.193229 -373.581655) (xy 115.220496 -373.581168) (xy 116.084096 -373.581168)
			(xy 116.111369 -373.581571) (xy 116.165361 -373.589334) (xy 116.217698 -373.604701) (xy 116.267316 -373.62736)
			(xy 116.313203 -373.65685) (xy 116.354427 -373.69257) (xy 116.390148 -373.733793) (xy 116.419638 -373.779681)
			(xy 116.442298 -373.829298) (xy 116.457666 -373.881635) (xy 116.465428 -373.935627) (xy 116.465428 -373.990167)
			(xy 121.646454 -373.990167) (xy 121.646454 -373.935633) (xy 121.654215 -373.881654) (xy 121.669579 -373.829329)
			(xy 121.692233 -373.779723) (xy 121.721717 -373.733846) (xy 121.757429 -373.692631) (xy 121.798642 -373.656919)
			(xy 121.844519 -373.627435) (xy 121.894125 -373.604781) (xy 121.94645 -373.589416) (xy 122.000429 -373.581655)
			(xy 122.027696 -373.581168) (xy 122.891296 -373.581168) (xy 122.918569 -373.581571) (xy 122.972561 -373.589334)
			(xy 123.024898 -373.604701) (xy 123.074516 -373.62736) (xy 123.120403 -373.65685) (xy 123.161627 -373.69257)
			(xy 123.197348 -373.733793) (xy 123.226838 -373.779681) (xy 123.249498 -373.829298) (xy 123.264866 -373.881635)
			(xy 123.272628 -373.935627) (xy 123.272628 -373.990167) (xy 128.453654 -373.990167) (xy 128.453654 -373.935633)
			(xy 128.461415 -373.881654) (xy 128.476779 -373.829329) (xy 128.499433 -373.779723) (xy 128.528917 -373.733846)
			(xy 128.564629 -373.692631) (xy 128.605842 -373.656919) (xy 128.651719 -373.627435) (xy 128.701325 -373.604781)
			(xy 128.75365 -373.589416) (xy 128.807629 -373.581655) (xy 128.834896 -373.581168) (xy 129.698496 -373.581168)
			(xy 129.725769 -373.581571) (xy 129.779761 -373.589334) (xy 129.832098 -373.604701) (xy 129.881716 -373.62736)
			(xy 129.927603 -373.65685) (xy 129.968827 -373.69257) (xy 130.004548 -373.733793) (xy 130.034038 -373.779681)
			(xy 130.056698 -373.829298) (xy 130.072066 -373.881635) (xy 130.079828 -373.935627) (xy 130.079828 -373.990171)
			(xy 147.366932 -373.990171) (xy 147.366932 -373.935629) (xy 147.374694 -373.881643) (xy 147.390061 -373.829311)
			(xy 147.412721 -373.779698) (xy 147.44221 -373.733816) (xy 147.477929 -373.692598) (xy 147.519151 -373.656884)
			(xy 147.565037 -373.627399) (xy 147.614652 -373.604746) (xy 147.666986 -373.589385) (xy 147.720973 -373.581628)
			(xy 147.748244 -373.581168) (xy 148.611844 -373.581168) (xy 148.639113 -373.581598) (xy 148.693097 -373.589365)
			(xy 148.745425 -373.604735) (xy 148.795033 -373.627396) (xy 148.840912 -373.656885) (xy 148.882128 -373.692603)
			(xy 148.917841 -373.733823) (xy 148.947325 -373.779705) (xy 148.96998 -373.829316) (xy 148.985344 -373.881647)
			(xy 148.993106 -373.93563) (xy 148.993106 -373.99017) (xy 148.993106 -373.990171) (xy 154.174132 -373.990171)
			(xy 154.174132 -373.935629) (xy 154.181894 -373.881643) (xy 154.197261 -373.829311) (xy 154.219921 -373.779698)
			(xy 154.24941 -373.733816) (xy 154.285129 -373.692598) (xy 154.326351 -373.656884) (xy 154.372237 -373.627399)
			(xy 154.421852 -373.604746) (xy 154.474186 -373.589385) (xy 154.528173 -373.581628) (xy 154.555444 -373.581168)
			(xy 155.419044 -373.581168) (xy 155.446313 -373.581598) (xy 155.500297 -373.589365) (xy 155.552625 -373.604735)
			(xy 155.602233 -373.627396) (xy 155.648112 -373.656885) (xy 155.689328 -373.692603) (xy 155.725041 -373.733823)
			(xy 155.754525 -373.779705) (xy 155.77718 -373.829316) (xy 155.792544 -373.881647) (xy 155.800306 -373.93563)
			(xy 155.800306 -373.99017) (xy 155.800306 -373.990171) (xy 160.981332 -373.990171) (xy 160.981332 -373.935629)
			(xy 160.989094 -373.881643) (xy 161.004461 -373.829311) (xy 161.027121 -373.779698) (xy 161.05661 -373.733816)
			(xy 161.092329 -373.692598) (xy 161.133551 -373.656884) (xy 161.179437 -373.627399) (xy 161.229052 -373.604746)
			(xy 161.281386 -373.589385) (xy 161.335373 -373.581628) (xy 161.362644 -373.581168) (xy 162.226244 -373.581168)
			(xy 162.253513 -373.581598) (xy 162.307497 -373.589365) (xy 162.359825 -373.604735) (xy 162.409433 -373.627396)
			(xy 162.455312 -373.656885) (xy 162.496528 -373.692603) (xy 162.532241 -373.733823) (xy 162.561725 -373.779705)
			(xy 162.58438 -373.829316) (xy 162.599744 -373.881647) (xy 162.607506 -373.93563) (xy 162.607506 -373.99017)
			(xy 162.599744 -374.044153) (xy 162.58438 -374.096484) (xy 162.561725 -374.146095) (xy 162.532241 -374.191977)
			(xy 162.496528 -374.233197) (xy 162.455312 -374.268915) (xy 162.409433 -374.298404) (xy 162.359825 -374.321065)
			(xy 162.307497 -374.336435) (xy 162.253513 -374.344202) (xy 162.226244 -374.344692) (xy 161.362644 -374.344692)
			(xy 161.335373 -374.344172) (xy 161.281386 -374.336415) (xy 161.229052 -374.321054) (xy 161.179437 -374.298401)
			(xy 161.133551 -374.268916) (xy 161.092329 -374.233202) (xy 161.05661 -374.191984) (xy 161.027121 -374.146102)
			(xy 161.004461 -374.096489) (xy 160.989094 -374.044157) (xy 160.981332 -373.990171) (xy 155.800306 -373.990171)
			(xy 155.792544 -374.044153) (xy 155.77718 -374.096484) (xy 155.754525 -374.146095) (xy 155.725041 -374.191977)
			(xy 155.689328 -374.233197) (xy 155.648112 -374.268915) (xy 155.602233 -374.298404) (xy 155.552625 -374.321065)
			(xy 155.500297 -374.336435) (xy 155.446313 -374.344202) (xy 155.419044 -374.344692) (xy 154.555444 -374.344692)
			(xy 154.528173 -374.344172) (xy 154.474186 -374.336415) (xy 154.421852 -374.321054) (xy 154.372237 -374.298401)
			(xy 154.326351 -374.268916) (xy 154.285129 -374.233202) (xy 154.24941 -374.191984) (xy 154.219921 -374.146102)
			(xy 154.197261 -374.096489) (xy 154.181894 -374.044157) (xy 154.174132 -373.990171) (xy 148.993106 -373.990171)
			(xy 148.985344 -374.044153) (xy 148.96998 -374.096484) (xy 148.947325 -374.146095) (xy 148.917841 -374.191977)
			(xy 148.882128 -374.233197) (xy 148.840912 -374.268915) (xy 148.795033 -374.298404) (xy 148.745425 -374.321065)
			(xy 148.693097 -374.336435) (xy 148.639113 -374.344202) (xy 148.611844 -374.344692) (xy 147.748244 -374.344692)
			(xy 147.720973 -374.344172) (xy 147.666986 -374.336415) (xy 147.614652 -374.321054) (xy 147.565037 -374.298401)
			(xy 147.519151 -374.268916) (xy 147.477929 -374.233202) (xy 147.44221 -374.191984) (xy 147.412721 -374.146102)
			(xy 147.390061 -374.096489) (xy 147.374694 -374.044157) (xy 147.366932 -373.990171) (xy 130.079828 -373.990171)
			(xy 130.079828 -373.990173) (xy 130.072066 -374.044165) (xy 130.056698 -374.096502) (xy 130.034038 -374.146119)
			(xy 130.004548 -374.192007) (xy 129.968827 -374.23323) (xy 129.927603 -374.26895) (xy 129.881716 -374.29844)
			(xy 129.832098 -374.321099) (xy 129.779761 -374.336466) (xy 129.725769 -374.344229) (xy 129.698496 -374.344692)
			(xy 128.834896 -374.344692) (xy 128.807629 -374.344145) (xy 128.75365 -374.336384) (xy 128.701325 -374.321019)
			(xy 128.651719 -374.298365) (xy 128.605842 -374.268881) (xy 128.564629 -374.233169) (xy 128.528917 -374.191954)
			(xy 128.499433 -374.146077) (xy 128.476779 -374.096471) (xy 128.461415 -374.044146) (xy 128.453654 -373.990167)
			(xy 123.272628 -373.990167) (xy 123.272628 -373.990173) (xy 123.264866 -374.044165) (xy 123.249498 -374.096502)
			(xy 123.226838 -374.146119) (xy 123.197348 -374.192007) (xy 123.161627 -374.23323) (xy 123.120403 -374.26895)
			(xy 123.074516 -374.29844) (xy 123.024898 -374.321099) (xy 122.972561 -374.336466) (xy 122.918569 -374.344229)
			(xy 122.891296 -374.344692) (xy 122.027696 -374.344692) (xy 122.000429 -374.344145) (xy 121.94645 -374.336384)
			(xy 121.894125 -374.321019) (xy 121.844519 -374.298365) (xy 121.798642 -374.268881) (xy 121.757429 -374.233169)
			(xy 121.721717 -374.191954) (xy 121.692233 -374.146077) (xy 121.669579 -374.096471) (xy 121.654215 -374.044146)
			(xy 121.646454 -373.990167) (xy 116.465428 -373.990167) (xy 116.465428 -373.990173) (xy 116.457666 -374.044165)
			(xy 116.442298 -374.096502) (xy 116.419638 -374.146119) (xy 116.390148 -374.192007) (xy 116.354427 -374.23323)
			(xy 116.313203 -374.26895) (xy 116.267316 -374.29844) (xy 116.217698 -374.321099) (xy 116.165361 -374.336466)
			(xy 116.111369 -374.344229) (xy 116.084096 -374.344692) (xy 115.220496 -374.344692) (xy 115.193229 -374.344145)
			(xy 115.13925 -374.336384) (xy 115.086925 -374.321019) (xy 115.037319 -374.298365) (xy 114.991442 -374.268881)
			(xy 114.950229 -374.233169) (xy 114.914517 -374.191954) (xy 114.885033 -374.146077) (xy 114.862379 -374.096471)
			(xy 114.847015 -374.044146) (xy 114.839254 -373.990167) (xy 95.507606 -373.990167) (xy 95.507606 -373.990171)
			(xy 95.499843 -374.044159) (xy 95.484477 -374.096493) (xy 95.461819 -374.146107) (xy 95.432331 -374.191991)
			(xy 95.396613 -374.233212) (xy 95.355393 -374.26893) (xy 95.309508 -374.298418) (xy 95.259894 -374.321076)
			(xy 95.207561 -374.336443) (xy 95.153573 -374.344205) (xy 95.126302 -374.344692) (xy 94.262702 -374.344692)
			(xy 94.235433 -374.344169) (xy 94.18145 -374.336407) (xy 94.129121 -374.321043) (xy 94.079512 -374.298387)
			(xy 94.033632 -374.268902) (xy 93.992414 -374.233187) (xy 93.9567 -374.19197) (xy 93.927214 -374.14609)
			(xy 93.904558 -374.09648) (xy 93.889193 -374.044152) (xy 93.881431 -373.990169) (xy 88.700406 -373.990169)
			(xy 88.700406 -373.990171) (xy 88.692643 -374.044159) (xy 88.677277 -374.096493) (xy 88.654619 -374.146107)
			(xy 88.625131 -374.191991) (xy 88.589413 -374.233212) (xy 88.548193 -374.26893) (xy 88.502308 -374.298418)
			(xy 88.452694 -374.321076) (xy 88.400361 -374.336443) (xy 88.346373 -374.344205) (xy 88.319102 -374.344692)
			(xy 87.455502 -374.344692) (xy 87.428233 -374.344169) (xy 87.37425 -374.336407) (xy 87.321921 -374.321043)
			(xy 87.272312 -374.298387) (xy 87.226432 -374.268902) (xy 87.185214 -374.233187) (xy 87.1495 -374.19197)
			(xy 87.120014 -374.14609) (xy 87.097358 -374.09648) (xy 87.081993 -374.044152) (xy 87.074231 -373.990169)
			(xy 81.893206 -373.990169) (xy 81.893206 -373.990171) (xy 81.885443 -374.044159) (xy 81.870077 -374.096493)
			(xy 81.847419 -374.146107) (xy 81.817931 -374.191991) (xy 81.782213 -374.233212) (xy 81.740993 -374.26893)
			(xy 81.695108 -374.298418) (xy 81.645494 -374.321076) (xy 81.593161 -374.336443) (xy 81.539173 -374.344205)
			(xy 81.511902 -374.344692) (xy 80.648302 -374.344692) (xy 80.621033 -374.344169) (xy 80.56705 -374.336407)
			(xy 80.514721 -374.321043) (xy 80.465112 -374.298387) (xy 80.419232 -374.268902) (xy 80.378014 -374.233187)
			(xy 80.3423 -374.19197) (xy 80.312814 -374.14609) (xy 80.290158 -374.09648) (xy 80.274793 -374.044152)
			(xy 80.267031 -373.990169) (xy 69.843396 -373.990169) (xy 69.843396 -376.956828) (xy 70.895972 -376.956828)
			(xy 70.895972 -376.093228) (xy 70.896458 -376.065959) (xy 70.90422 -376.011975) (xy 70.919585 -375.959645)
			(xy 70.942242 -375.910035) (xy 70.971728 -375.864154) (xy 71.007443 -375.822937) (xy 71.04866 -375.787222)
			(xy 71.094541 -375.757736) (xy 71.144151 -375.735079) (xy 71.196481 -375.719714) (xy 71.250465 -375.711952)
			(xy 71.305003 -375.711952) (xy 71.358987 -375.719714) (xy 71.411317 -375.735079) (xy 71.460927 -375.757736)
			(xy 71.506808 -375.787222) (xy 71.548025 -375.822937) (xy 71.58374 -375.864154) (xy 71.613226 -375.910035)
			(xy 71.635883 -375.959645) (xy 71.651248 -376.011975) (xy 71.65901 -376.065959) (xy 71.659496 -376.093228)
			(xy 71.659496 -376.83186) (xy 73.576688 -376.83186) (xy 73.576688 -375.96826) (xy 73.577174 -375.940991)
			(xy 73.584936 -375.887007) (xy 73.600301 -375.834677) (xy 73.622958 -375.785067) (xy 73.652444 -375.739186)
			(xy 73.688159 -375.697969) (xy 73.729376 -375.662254) (xy 73.775257 -375.632768) (xy 73.824867 -375.610111)
			(xy 73.877197 -375.594746) (xy 73.931181 -375.586984) (xy 73.985719 -375.586984) (xy 74.039703 -375.594746)
			(xy 74.092033 -375.610111) (xy 74.141643 -375.632768) (xy 74.187524 -375.662254) (xy 74.228741 -375.697969)
			(xy 74.264456 -375.739186) (xy 74.293942 -375.785067) (xy 74.316599 -375.834677) (xy 74.331964 -375.887007)
			(xy 74.339726 -375.940991) (xy 74.340212 -375.96826) (xy 74.340212 -376.83186) (xy 74.339726 -376.859129)
			(xy 74.331964 -376.913113) (xy 74.319129 -376.956828) (xy 103.42372 -376.956828) (xy 103.42372 -376.093228)
			(xy 103.424206 -376.065959) (xy 103.431968 -376.011975) (xy 103.447333 -375.959645) (xy 103.46999 -375.910035)
			(xy 103.499476 -375.864154) (xy 103.535191 -375.822937) (xy 103.576408 -375.787222) (xy 103.622289 -375.757736)
			(xy 103.671899 -375.735079) (xy 103.724229 -375.719714) (xy 103.778213 -375.711952) (xy 103.832751 -375.711952)
			(xy 103.886735 -375.719714) (xy 103.939065 -375.735079) (xy 103.988675 -375.757736) (xy 104.034556 -375.787222)
			(xy 104.075773 -375.822937) (xy 104.111488 -375.864154) (xy 104.140974 -375.910035) (xy 104.163631 -375.959645)
			(xy 104.178996 -376.011975) (xy 104.186758 -376.065959) (xy 104.187244 -376.093228) (xy 104.187244 -376.83186)
			(xy 108.149136 -376.83186) (xy 108.149136 -375.96826) (xy 108.149622 -375.941009) (xy 108.157378 -375.887061)
			(xy 108.172733 -375.834766) (xy 108.195375 -375.785189) (xy 108.224841 -375.739339) (xy 108.260532 -375.698148)
			(xy 108.301723 -375.662457) (xy 108.347573 -375.632991) (xy 108.39715 -375.610349) (xy 108.449445 -375.594994)
			(xy 108.503393 -375.587238) (xy 108.557895 -375.587238) (xy 108.611843 -375.594994) (xy 108.664138 -375.610349)
			(xy 108.713715 -375.632991) (xy 108.759565 -375.662457) (xy 108.800756 -375.698148) (xy 108.836447 -375.739339)
			(xy 108.865913 -375.785189) (xy 108.888555 -375.834766) (xy 108.90391 -375.887061) (xy 108.911666 -375.941009)
			(xy 108.912152 -375.96826) (xy 108.912152 -376.83186) (xy 108.911666 -376.859111) (xy 108.90391 -376.913059)
			(xy 108.891058 -376.956828) (xy 137.996168 -376.956828) (xy 137.996168 -376.093228) (xy 137.996654 -376.065977)
			(xy 138.00441 -376.012029) (xy 138.019765 -375.959734) (xy 138.042407 -375.910157) (xy 138.071873 -375.864307)
			(xy 138.107564 -375.823116) (xy 138.148755 -375.787425) (xy 138.194605 -375.757959) (xy 138.244182 -375.735317)
			(xy 138.296477 -375.719962) (xy 138.350425 -375.712206) (xy 138.404927 -375.712206) (xy 138.458875 -375.719962)
			(xy 138.51117 -375.735317) (xy 138.560747 -375.757959) (xy 138.606597 -375.787425) (xy 138.647788 -375.823116)
			(xy 138.683479 -375.864307) (xy 138.712945 -375.910157) (xy 138.735587 -375.959734) (xy 138.750942 -376.012029)
			(xy 138.758698 -376.065977) (xy 138.759184 -376.093228) (xy 138.759184 -376.83186) (xy 140.676884 -376.83186)
			(xy 140.676884 -375.96826) (xy 140.67737 -375.941009) (xy 140.685126 -375.887061) (xy 140.700481 -375.834766)
			(xy 140.723123 -375.785189) (xy 140.752589 -375.739339) (xy 140.78828 -375.698148) (xy 140.829471 -375.662457)
			(xy 140.875321 -375.632991) (xy 140.924898 -375.610349) (xy 140.977193 -375.594994) (xy 141.031141 -375.587238)
			(xy 141.085643 -375.587238) (xy 141.139591 -375.594994) (xy 141.191886 -375.610349) (xy 141.241463 -375.632991)
			(xy 141.287313 -375.662457) (xy 141.328504 -375.698148) (xy 141.364195 -375.739339) (xy 141.393661 -375.785189)
			(xy 141.416303 -375.834766) (xy 141.431658 -375.887061) (xy 141.439414 -375.941009) (xy 141.4399 -375.96826)
			(xy 141.4399 -376.83186) (xy 141.439414 -376.859111) (xy 141.431658 -376.913059) (xy 141.418806 -376.956828)
			(xy 170.523916 -376.956828) (xy 170.523916 -376.093228) (xy 170.524402 -376.065977) (xy 170.532158 -376.012029)
			(xy 170.547513 -375.959734) (xy 170.570155 -375.910157) (xy 170.599621 -375.864307) (xy 170.635312 -375.823116)
			(xy 170.676503 -375.787425) (xy 170.722353 -375.757959) (xy 170.77193 -375.735317) (xy 170.824225 -375.719962)
			(xy 170.878173 -375.712206) (xy 170.932675 -375.712206) (xy 170.986623 -375.719962) (xy 171.038918 -375.735317)
			(xy 171.088495 -375.757959) (xy 171.134345 -375.787425) (xy 171.175536 -375.823116) (xy 171.211227 -375.864307)
			(xy 171.240693 -375.910157) (xy 171.263335 -375.959734) (xy 171.27869 -376.012029) (xy 171.286446 -376.065977)
			(xy 171.286932 -376.093228) (xy 171.286932 -376.589497) (xy 173.177954 -376.589497) (xy 173.177954 -376.403663)
			(xy 173.185949 -376.218) (xy 173.201924 -376.032854) (xy 173.22585 -375.848566) (xy 173.257682 -375.665478)
			(xy 173.297362 -375.483929) (xy 173.344815 -375.304255) (xy 173.399955 -375.126789) (xy 173.462678 -374.95186)
			(xy 173.532869 -374.779791) (xy 173.610398 -374.610902) (xy 173.695121 -374.445504) (xy 173.786882 -374.283904)
			(xy 173.88551 -374.126402) (xy 173.990823 -373.973288) (xy 174.102625 -373.824848) (xy 174.22071 -373.681354)
			(xy 174.34486 -373.543074) (xy 174.474843 -373.410263) (xy 174.61042 -373.283167) (xy 174.75134 -373.162022)
			(xy 174.89734 -373.047051) (xy 175.048152 -372.938468) (xy 175.203496 -372.836475) (xy 175.363084 -372.741258)
			(xy 175.526621 -372.652996) (xy 175.693803 -372.571851) (xy 175.864322 -372.497974) (xy 176.037861 -372.431501)
			(xy 176.2141 -372.372556) (xy 176.392711 -372.321248) (xy 176.573364 -372.277671) (xy 176.755725 -372.241907)
			(xy 176.939455 -372.214021) (xy 177.124215 -372.194066) (xy 177.309662 -372.182078) (xy 177.495454 -372.17808)
			(xy 177.681246 -372.182078) (xy 177.866693 -372.194066) (xy 178.051453 -372.214021) (xy 178.235183 -372.241907)
			(xy 178.417544 -372.277671) (xy 178.598197 -372.321248) (xy 178.776808 -372.372556) (xy 178.953047 -372.431501)
			(xy 179.126586 -372.497974) (xy 179.297105 -372.571851) (xy 179.464287 -372.652996) (xy 179.627824 -372.741258)
			(xy 179.787412 -372.836475) (xy 179.942756 -372.938468) (xy 180.093568 -373.047051) (xy 180.239568 -373.162022)
			(xy 180.380488 -373.283167) (xy 180.516065 -373.410263) (xy 180.646048 -373.543074) (xy 180.770198 -373.681354)
			(xy 180.888283 -373.824848) (xy 181.000085 -373.973288) (xy 181.105398 -374.126402) (xy 181.204026 -374.283904)
			(xy 181.295787 -374.445504) (xy 181.38051 -374.610902) (xy 181.458039 -374.779791) (xy 181.52823 -374.95186)
			(xy 181.590953 -375.126789) (xy 181.646093 -375.304255) (xy 181.693546 -375.483929) (xy 181.733226 -375.665478)
			(xy 181.765058 -375.848566) (xy 181.788984 -376.032854) (xy 181.804959 -376.218) (xy 181.812954 -376.403663)
			(xy 181.813454 -376.49658) (xy 181.812954 -376.589497) (xy 181.804959 -376.77516) (xy 181.788984 -376.960306)
			(xy 181.765058 -377.144594) (xy 181.733226 -377.327682) (xy 181.693546 -377.509231) (xy 181.646093 -377.688905)
			(xy 181.590953 -377.866371) (xy 181.52823 -378.0413) (xy 181.458039 -378.213369) (xy 181.38051 -378.382258)
			(xy 181.295787 -378.547656) (xy 181.204026 -378.709256) (xy 181.105398 -378.866758) (xy 181.000085 -379.019872)
			(xy 180.888283 -379.168312) (xy 180.770198 -379.311806) (xy 180.646048 -379.450086) (xy 180.516065 -379.582897)
			(xy 180.380488 -379.709993) (xy 180.239568 -379.831138) (xy 180.093568 -379.946109) (xy 179.942756 -380.054692)
			(xy 179.787412 -380.156685) (xy 179.627824 -380.251902) (xy 179.464287 -380.340164) (xy 179.297105 -380.421309)
			(xy 179.126586 -380.495186) (xy 178.953047 -380.561659) (xy 178.776808 -380.620604) (xy 178.598197 -380.671912)
			(xy 178.417544 -380.715489) (xy 178.235183 -380.751253) (xy 178.051453 -380.779139) (xy 177.866693 -380.799094)
			(xy 177.681246 -380.811082) (xy 177.495454 -380.81508) (xy 177.309662 -380.811082) (xy 177.124215 -380.799094)
			(xy 176.939455 -380.779139) (xy 176.755725 -380.751253) (xy 176.573364 -380.715489) (xy 176.392711 -380.671912)
			(xy 176.2141 -380.620604) (xy 176.037861 -380.561659) (xy 175.864322 -380.495186) (xy 175.693803 -380.421309)
			(xy 175.526621 -380.340164) (xy 175.363084 -380.251902) (xy 175.203496 -380.156685) (xy 175.048152 -380.054692)
			(xy 174.89734 -379.946109) (xy 174.75134 -379.831138) (xy 174.61042 -379.709993) (xy 174.474843 -379.582897)
			(xy 174.34486 -379.450086) (xy 174.22071 -379.311806) (xy 174.102625 -379.168312) (xy 173.990823 -379.019872)
			(xy 173.88551 -378.866758) (xy 173.786882 -378.709256) (xy 173.695121 -378.547656) (xy 173.610398 -378.382258)
			(xy 173.532869 -378.213369) (xy 173.462678 -378.0413) (xy 173.399955 -377.866371) (xy 173.344815 -377.688905)
			(xy 173.297362 -377.509231) (xy 173.257682 -377.327682) (xy 173.22585 -377.144594) (xy 173.201924 -376.960306)
			(xy 173.185949 -376.77516) (xy 173.177954 -376.589497) (xy 171.286932 -376.589497) (xy 171.286932 -376.956828)
			(xy 171.286446 -376.984079) (xy 171.27869 -377.038027) (xy 171.263335 -377.090322) (xy 171.240693 -377.139899)
			(xy 171.211227 -377.185749) (xy 171.175536 -377.22694) (xy 171.134345 -377.262631) (xy 171.088495 -377.292097)
			(xy 171.038918 -377.314739) (xy 170.986623 -377.330094) (xy 170.932675 -377.33785) (xy 170.878173 -377.33785)
			(xy 170.824225 -377.330094) (xy 170.77193 -377.314739) (xy 170.722353 -377.292097) (xy 170.676503 -377.262631)
			(xy 170.635312 -377.22694) (xy 170.599621 -377.185749) (xy 170.570155 -377.139899) (xy 170.547513 -377.090322)
			(xy 170.532158 -377.038027) (xy 170.524402 -376.984079) (xy 170.523916 -376.956828) (xy 141.418806 -376.956828)
			(xy 141.416303 -376.965354) (xy 141.393661 -377.014931) (xy 141.364195 -377.060781) (xy 141.328504 -377.101972)
			(xy 141.287313 -377.137663) (xy 141.241463 -377.167129) (xy 141.191886 -377.189771) (xy 141.139591 -377.205126)
			(xy 141.085643 -377.212882) (xy 141.031141 -377.212882) (xy 140.977193 -377.205126) (xy 140.924898 -377.189771)
			(xy 140.875321 -377.167129) (xy 140.829471 -377.137663) (xy 140.78828 -377.101972) (xy 140.752589 -377.060781)
			(xy 140.723123 -377.014931) (xy 140.700481 -376.965354) (xy 140.685126 -376.913059) (xy 140.67737 -376.859111)
			(xy 140.676884 -376.83186) (xy 138.759184 -376.83186) (xy 138.759184 -376.956828) (xy 138.758698 -376.984079)
			(xy 138.750942 -377.038027) (xy 138.735587 -377.090322) (xy 138.712945 -377.139899) (xy 138.683479 -377.185749)
			(xy 138.647788 -377.22694) (xy 138.606597 -377.262631) (xy 138.560747 -377.292097) (xy 138.51117 -377.314739)
			(xy 138.458875 -377.330094) (xy 138.404927 -377.33785) (xy 138.350425 -377.33785) (xy 138.296477 -377.330094)
			(xy 138.244182 -377.314739) (xy 138.194605 -377.292097) (xy 138.148755 -377.262631) (xy 138.107564 -377.22694)
			(xy 138.071873 -377.185749) (xy 138.042407 -377.139899) (xy 138.019765 -377.090322) (xy 138.00441 -377.038027)
			(xy 137.996654 -376.984079) (xy 137.996168 -376.956828) (xy 108.891058 -376.956828) (xy 108.888555 -376.965354)
			(xy 108.865913 -377.014931) (xy 108.836447 -377.060781) (xy 108.800756 -377.101972) (xy 108.759565 -377.137663)
			(xy 108.713715 -377.167129) (xy 108.664138 -377.189771) (xy 108.611843 -377.205126) (xy 108.557895 -377.212882)
			(xy 108.503393 -377.212882) (xy 108.449445 -377.205126) (xy 108.39715 -377.189771) (xy 108.347573 -377.167129)
			(xy 108.301723 -377.137663) (xy 108.260532 -377.101972) (xy 108.224841 -377.060781) (xy 108.195375 -377.014931)
			(xy 108.172733 -376.965354) (xy 108.157378 -376.913059) (xy 108.149622 -376.859111) (xy 108.149136 -376.83186)
			(xy 104.187244 -376.83186) (xy 104.187244 -376.956828) (xy 104.186758 -376.984097) (xy 104.178996 -377.038081)
			(xy 104.163631 -377.090411) (xy 104.140974 -377.140021) (xy 104.111488 -377.185902) (xy 104.075773 -377.227119)
			(xy 104.034556 -377.262834) (xy 103.988675 -377.29232) (xy 103.939065 -377.314977) (xy 103.886735 -377.330342)
			(xy 103.832751 -377.338104) (xy 103.778213 -377.338104) (xy 103.724229 -377.330342) (xy 103.671899 -377.314977)
			(xy 103.622289 -377.29232) (xy 103.576408 -377.262834) (xy 103.535191 -377.227119) (xy 103.499476 -377.185902)
			(xy 103.46999 -377.140021) (xy 103.447333 -377.090411) (xy 103.431968 -377.038081) (xy 103.424206 -376.984097)
			(xy 103.42372 -376.956828) (xy 74.319129 -376.956828) (xy 74.316599 -376.965443) (xy 74.293942 -377.015053)
			(xy 74.264456 -377.060934) (xy 74.228741 -377.102151) (xy 74.187524 -377.137866) (xy 74.141643 -377.167352)
			(xy 74.092033 -377.190009) (xy 74.039703 -377.205374) (xy 73.985719 -377.213136) (xy 73.931181 -377.213136)
			(xy 73.877197 -377.205374) (xy 73.824867 -377.190009) (xy 73.775257 -377.167352) (xy 73.729376 -377.137866)
			(xy 73.688159 -377.102151) (xy 73.652444 -377.060934) (xy 73.622958 -377.015053) (xy 73.600301 -376.965443)
			(xy 73.584936 -376.913113) (xy 73.577174 -376.859129) (xy 73.576688 -376.83186) (xy 71.659496 -376.83186)
			(xy 71.659496 -376.956828) (xy 71.65901 -376.984097) (xy 71.651248 -377.038081) (xy 71.635883 -377.090411)
			(xy 71.613226 -377.140021) (xy 71.58374 -377.185902) (xy 71.548025 -377.227119) (xy 71.506808 -377.262834)
			(xy 71.460927 -377.29232) (xy 71.411317 -377.314977) (xy 71.358987 -377.330342) (xy 71.305003 -377.338104)
			(xy 71.250465 -377.338104) (xy 71.196481 -377.330342) (xy 71.144151 -377.314977) (xy 71.094541 -377.29232)
			(xy 71.04866 -377.262834) (xy 71.007443 -377.227119) (xy 70.971728 -377.185902) (xy 70.942242 -377.140021)
			(xy 70.919585 -377.090411) (xy 70.90422 -377.038081) (xy 70.896458 -376.984097) (xy 70.895972 -376.956828)
			(xy 69.843396 -376.956828) (xy 69.843396 -380.360428) (xy 70.895972 -380.360428) (xy 70.895972 -379.496828)
			(xy 70.896458 -379.469559) (xy 70.90422 -379.415575) (xy 70.919585 -379.363245) (xy 70.942242 -379.313635)
			(xy 70.971728 -379.267754) (xy 71.007443 -379.226537) (xy 71.04866 -379.190822) (xy 71.094541 -379.161336)
			(xy 71.144151 -379.138679) (xy 71.196481 -379.123314) (xy 71.250465 -379.115552) (xy 71.305003 -379.115552)
			(xy 71.358987 -379.123314) (xy 71.411317 -379.138679) (xy 71.460927 -379.161336) (xy 71.506808 -379.190822)
			(xy 71.548025 -379.226537) (xy 71.58374 -379.267754) (xy 71.613226 -379.313635) (xy 71.635883 -379.363245)
			(xy 71.651248 -379.415575) (xy 71.65901 -379.469559) (xy 71.659496 -379.496828) (xy 71.659496 -380.360428)
			(xy 103.42372 -380.360428) (xy 103.42372 -379.496828) (xy 103.424206 -379.469559) (xy 103.431968 -379.415575)
			(xy 103.447333 -379.363245) (xy 103.46999 -379.313635) (xy 103.499476 -379.267754) (xy 103.535191 -379.226537)
			(xy 103.576408 -379.190822) (xy 103.622289 -379.161336) (xy 103.671899 -379.138679) (xy 103.724229 -379.123314)
			(xy 103.778213 -379.115552) (xy 103.832751 -379.115552) (xy 103.886735 -379.123314) (xy 103.939065 -379.138679)
			(xy 103.988675 -379.161336) (xy 104.034556 -379.190822) (xy 104.075773 -379.226537) (xy 104.111488 -379.267754)
			(xy 104.140974 -379.313635) (xy 104.163631 -379.363245) (xy 104.178996 -379.415575) (xy 104.186758 -379.469559)
			(xy 104.187244 -379.496828) (xy 104.187244 -380.360428) (xy 137.996168 -380.360428) (xy 137.996168 -379.496828)
			(xy 137.996654 -379.469577) (xy 138.00441 -379.415629) (xy 138.019765 -379.363334) (xy 138.042407 -379.313757)
			(xy 138.071873 -379.267907) (xy 138.107564 -379.226716) (xy 138.148755 -379.191025) (xy 138.194605 -379.161559)
			(xy 138.244182 -379.138917) (xy 138.296477 -379.123562) (xy 138.350425 -379.115806) (xy 138.404927 -379.115806)
			(xy 138.458875 -379.123562) (xy 138.51117 -379.138917) (xy 138.560747 -379.161559) (xy 138.606597 -379.191025)
			(xy 138.647788 -379.226716) (xy 138.683479 -379.267907) (xy 138.712945 -379.313757) (xy 138.735587 -379.363334)
			(xy 138.750942 -379.415629) (xy 138.758698 -379.469577) (xy 138.759184 -379.496828) (xy 138.759184 -380.360428)
			(xy 170.523916 -380.360428) (xy 170.523916 -379.496828) (xy 170.524402 -379.469577) (xy 170.532158 -379.415629)
			(xy 170.547513 -379.363334) (xy 170.570155 -379.313757) (xy 170.599621 -379.267907) (xy 170.635312 -379.226716)
			(xy 170.676503 -379.191025) (xy 170.722353 -379.161559) (xy 170.77193 -379.138917) (xy 170.824225 -379.123562)
			(xy 170.878173 -379.115806) (xy 170.932675 -379.115806) (xy 170.986623 -379.123562) (xy 171.038918 -379.138917)
			(xy 171.088495 -379.161559) (xy 171.134345 -379.191025) (xy 171.175536 -379.226716) (xy 171.211227 -379.267907)
			(xy 171.240693 -379.313757) (xy 171.263335 -379.363334) (xy 171.27869 -379.415629) (xy 171.286446 -379.469577)
			(xy 171.286932 -379.496828) (xy 171.286932 -380.360428) (xy 171.286446 -380.387679) (xy 171.27869 -380.441627)
			(xy 171.263335 -380.493922) (xy 171.240693 -380.543499) (xy 171.211227 -380.589349) (xy 171.175536 -380.63054)
			(xy 171.134345 -380.666231) (xy 171.088495 -380.695697) (xy 171.038918 -380.718339) (xy 170.986623 -380.733694)
			(xy 170.932675 -380.74145) (xy 170.878173 -380.74145) (xy 170.824225 -380.733694) (xy 170.77193 -380.718339)
			(xy 170.722353 -380.695697) (xy 170.676503 -380.666231) (xy 170.635312 -380.63054) (xy 170.599621 -380.589349)
			(xy 170.570155 -380.543499) (xy 170.547513 -380.493922) (xy 170.532158 -380.441627) (xy 170.524402 -380.387679)
			(xy 170.523916 -380.360428) (xy 138.759184 -380.360428) (xy 138.758698 -380.387679) (xy 138.750942 -380.441627)
			(xy 138.735587 -380.493922) (xy 138.712945 -380.543499) (xy 138.683479 -380.589349) (xy 138.647788 -380.63054)
			(xy 138.606597 -380.666231) (xy 138.560747 -380.695697) (xy 138.51117 -380.718339) (xy 138.458875 -380.733694)
			(xy 138.404927 -380.74145) (xy 138.350425 -380.74145) (xy 138.296477 -380.733694) (xy 138.244182 -380.718339)
			(xy 138.194605 -380.695697) (xy 138.148755 -380.666231) (xy 138.107564 -380.63054) (xy 138.071873 -380.589349)
			(xy 138.042407 -380.543499) (xy 138.019765 -380.493922) (xy 138.00441 -380.441627) (xy 137.996654 -380.387679)
			(xy 137.996168 -380.360428) (xy 104.187244 -380.360428) (xy 104.186758 -380.387697) (xy 104.178996 -380.441681)
			(xy 104.163631 -380.494011) (xy 104.140974 -380.543621) (xy 104.111488 -380.589502) (xy 104.075773 -380.630719)
			(xy 104.034556 -380.666434) (xy 103.988675 -380.69592) (xy 103.939065 -380.718577) (xy 103.886735 -380.733942)
			(xy 103.832751 -380.741704) (xy 103.778213 -380.741704) (xy 103.724229 -380.733942) (xy 103.671899 -380.718577)
			(xy 103.622289 -380.69592) (xy 103.576408 -380.666434) (xy 103.535191 -380.630719) (xy 103.499476 -380.589502)
			(xy 103.46999 -380.543621) (xy 103.447333 -380.494011) (xy 103.431968 -380.441681) (xy 103.424206 -380.387697)
			(xy 103.42372 -380.360428) (xy 71.659496 -380.360428) (xy 71.65901 -380.387697) (xy 71.651248 -380.441681)
			(xy 71.635883 -380.494011) (xy 71.613226 -380.543621) (xy 71.58374 -380.589502) (xy 71.548025 -380.630719)
			(xy 71.506808 -380.666434) (xy 71.460927 -380.69592) (xy 71.411317 -380.718577) (xy 71.358987 -380.733942)
			(xy 71.305003 -380.741704) (xy 71.250465 -380.741704) (xy 71.196481 -380.733942) (xy 71.144151 -380.718577)
			(xy 71.094541 -380.69592) (xy 71.04866 -380.666434) (xy 71.007443 -380.630719) (xy 70.971728 -380.589502)
			(xy 70.942242 -380.543621) (xy 70.919585 -380.494011) (xy 70.90422 -380.441681) (xy 70.896458 -380.387697)
			(xy 70.895972 -380.360428) (xy 69.843396 -380.360428) (xy 69.843396 -382.36906) (xy 73.576688 -382.36906)
			(xy 73.576688 -381.50546) (xy 73.577174 -381.478191) (xy 73.584936 -381.424207) (xy 73.600301 -381.371877)
			(xy 73.622958 -381.322267) (xy 73.652444 -381.276386) (xy 73.688159 -381.235169) (xy 73.729376 -381.199454)
			(xy 73.775257 -381.169968) (xy 73.824867 -381.147311) (xy 73.877197 -381.131946) (xy 73.931181 -381.124184)
			(xy 73.985719 -381.124184) (xy 74.039703 -381.131946) (xy 74.092033 -381.147311) (xy 74.141643 -381.169968)
			(xy 74.187524 -381.199454) (xy 74.228741 -381.235169) (xy 74.264456 -381.276386) (xy 74.293942 -381.322267)
			(xy 74.316599 -381.371877) (xy 74.331964 -381.424207) (xy 74.339726 -381.478191) (xy 74.340212 -381.50546)
			(xy 74.340212 -382.36906) (xy 108.149136 -382.36906) (xy 108.149136 -381.50546) (xy 108.149622 -381.478209)
			(xy 108.157378 -381.424261) (xy 108.172733 -381.371966) (xy 108.195375 -381.322389) (xy 108.224841 -381.276539)
			(xy 108.260532 -381.235348) (xy 108.301723 -381.199657) (xy 108.347573 -381.170191) (xy 108.39715 -381.147549)
			(xy 108.449445 -381.132194) (xy 108.503393 -381.124438) (xy 108.557895 -381.124438) (xy 108.611843 -381.132194)
			(xy 108.664138 -381.147549) (xy 108.713715 -381.170191) (xy 108.759565 -381.199657) (xy 108.800756 -381.235348)
			(xy 108.836447 -381.276539) (xy 108.865913 -381.322389) (xy 108.888555 -381.371966) (xy 108.90391 -381.424261)
			(xy 108.911666 -381.478209) (xy 108.912152 -381.50546) (xy 108.912152 -382.36906) (xy 140.676884 -382.36906)
			(xy 140.676884 -381.50546) (xy 140.67737 -381.478209) (xy 140.685126 -381.424261) (xy 140.700481 -381.371966)
			(xy 140.723123 -381.322389) (xy 140.752589 -381.276539) (xy 140.78828 -381.235348) (xy 140.829471 -381.199657)
			(xy 140.875321 -381.170191) (xy 140.924898 -381.147549) (xy 140.977193 -381.132194) (xy 141.031141 -381.124438)
			(xy 141.085643 -381.124438) (xy 141.139591 -381.132194) (xy 141.191886 -381.147549) (xy 141.241463 -381.170191)
			(xy 141.287313 -381.199657) (xy 141.328504 -381.235348) (xy 141.364195 -381.276539) (xy 141.393661 -381.322389)
			(xy 141.416303 -381.371966) (xy 141.431658 -381.424261) (xy 141.439414 -381.478209) (xy 141.4399 -381.50546)
			(xy 141.4399 -382.36906) (xy 141.439414 -382.396311) (xy 141.431658 -382.450259) (xy 141.416303 -382.502554)
			(xy 141.393661 -382.552131) (xy 141.364195 -382.597981) (xy 141.328504 -382.639172) (xy 141.287313 -382.674863)
			(xy 141.241463 -382.704329) (xy 141.191886 -382.726971) (xy 141.139591 -382.742326) (xy 141.085643 -382.750082)
			(xy 141.031141 -382.750082) (xy 140.977193 -382.742326) (xy 140.924898 -382.726971) (xy 140.875321 -382.704329)
			(xy 140.829471 -382.674863) (xy 140.78828 -382.639172) (xy 140.752589 -382.597981) (xy 140.723123 -382.552131)
			(xy 140.700481 -382.502554) (xy 140.685126 -382.450259) (xy 140.67737 -382.396311) (xy 140.676884 -382.36906)
			(xy 108.912152 -382.36906) (xy 108.911666 -382.396311) (xy 108.90391 -382.450259) (xy 108.888555 -382.502554)
			(xy 108.865913 -382.552131) (xy 108.836447 -382.597981) (xy 108.800756 -382.639172) (xy 108.759565 -382.674863)
			(xy 108.713715 -382.704329) (xy 108.664138 -382.726971) (xy 108.611843 -382.742326) (xy 108.557895 -382.750082)
			(xy 108.503393 -382.750082) (xy 108.449445 -382.742326) (xy 108.39715 -382.726971) (xy 108.347573 -382.704329)
			(xy 108.301723 -382.674863) (xy 108.260532 -382.639172) (xy 108.224841 -382.597981) (xy 108.195375 -382.552131)
			(xy 108.172733 -382.502554) (xy 108.157378 -382.450259) (xy 108.149622 -382.396311) (xy 108.149136 -382.36906)
			(xy 74.340212 -382.36906) (xy 74.339726 -382.396329) (xy 74.331964 -382.450313) (xy 74.316599 -382.502643)
			(xy 74.293942 -382.552253) (xy 74.264456 -382.598134) (xy 74.228741 -382.639351) (xy 74.187524 -382.675066)
			(xy 74.141643 -382.704552) (xy 74.092033 -382.727209) (xy 74.039703 -382.742574) (xy 73.985719 -382.750336)
			(xy 73.931181 -382.750336) (xy 73.877197 -382.742574) (xy 73.824867 -382.727209) (xy 73.775257 -382.704552)
			(xy 73.729376 -382.675066) (xy 73.688159 -382.639351) (xy 73.652444 -382.598134) (xy 73.622958 -382.552253)
			(xy 73.600301 -382.502643) (xy 73.584936 -382.450313) (xy 73.577174 -382.396329) (xy 73.576688 -382.36906)
			(xy 69.843396 -382.36906) (xy 69.843396 -383.351278) (xy 69.843833 -383.361342) (xy 69.851567 -383.379926)
			(xy 69.858382 -383.387346) (xy 70.113398 -383.642362) (xy 70.130659 -383.660402) (xy 70.158418 -383.701895)
			(xy 70.177531 -383.748014) (xy 70.187262 -383.796979) (xy 70.18782 -383.82194) (xy 70.18782 -384.62077)
			(xy 70.187262 -384.644816) (xy 70.178224 -384.692051) (xy 70.160465 -384.736744) (xy 70.134618 -384.7773)
			(xy 70.101605 -384.812272) (xy 70.08241 -384.826764) (xy 70.072994 -384.834428) (xy 70.062011 -384.856042)
			(xy 70.061328 -384.868166) (xy 70.061328 -386.174488) (xy 70.060908 -386.18456) (xy 70.0532 -386.20317)
			(xy 70.046342 -386.210556) (xy 69.89826 -386.358384) (xy 69.891577 -386.365795) (xy 69.883996 -386.38423)
			(xy 69.883528 -386.394198) (xy 69.883528 -386.44195) (xy 69.884142 -386.454091) (xy 69.895145 -386.475726)
			(xy 69.90461 -386.483352) (xy 69.923785 -386.497872) (xy 69.956804 -386.532835) (xy 69.98266 -386.573383)
			(xy 70.000431 -386.61807) (xy 70.009484 -386.665301) (xy 70.01002 -386.689346) (xy 70.01002 -386.70357)
			(xy 70.061074 -386.73405) (xy 70.07202 -386.739694) (xy 70.096573 -386.74102) (xy 70.108064 -386.73659)
			(xy 70.132953 -386.725831) (xy 70.185009 -386.710659) (xy 70.238687 -386.703003) (xy 70.265798 -386.702554)
			(xy 70.29375 -386.70305) (xy 70.349053 -386.711224) (xy 70.402571 -386.727383) (xy 70.453157 -386.75118)
			(xy 70.499728 -386.782105) (xy 70.541286 -386.819497) (xy 70.576942 -386.862555) (xy 70.605931 -386.910355)
			(xy 70.627632 -386.961875) (xy 70.635114 -386.988812) (xy 70.639686 -387.00583) (xy 70.666864 -387.026912)
			(xy 71.576692 -387.026912) (xy 71.586763 -387.026491) (xy 71.605371 -387.01878) (xy 71.61276 -387.011926)
			(xy 73.00976 -385.614926) (xy 73.016599 -385.607525) (xy 73.024313 -385.588927) (xy 73.024746 -385.578858)
			(xy 73.024746 -384.41249) (xy 73.025318 -384.38753) (xy 73.035061 -384.338571) (xy 73.054168 -384.292453)
			(xy 73.081907 -384.25095) (xy 73.099168 -384.232912) (xy 73.7997 -383.53238) (xy 73.817742 -383.515123)
			(xy 73.859237 -383.487373) (xy 73.905355 -383.468268) (xy 73.954318 -383.458546) (xy 73.979278 -383.457958)
			(xy 76.321666 -383.457958) (xy 76.33036 -383.457617) (xy 76.346736 -383.451781) (xy 76.35367 -383.446528)
			(xy 76.374141 -383.430549) (xy 76.418585 -383.403686) (xy 76.466258 -383.383093) (xy 76.516282 -383.369149)
			(xy 76.567734 -383.362112) (xy 76.5937 -383.361692) (xy 76.619667 -383.362111) (xy 76.671124 -383.369125)
			(xy 76.721151 -383.383063) (xy 76.768822 -383.403667) (xy 76.813253 -383.430555) (xy 76.83373 -383.446528)
			(xy 76.840692 -383.451732) (xy 76.857051 -383.457575) (xy 76.865734 -383.457958) (xy 86.228682 -383.457958)
			(xy 86.253639 -383.458537) (xy 86.30259 -383.468292) (xy 86.348698 -383.487409) (xy 86.39019 -383.515155)
			(xy 86.40826 -383.53238) (xy 86.522814 -383.646934) (xy 86.530226 -383.653618) (xy 86.548659 -383.661215)
			(xy 86.568597 -383.661215) (xy 86.58703 -383.653618) (xy 86.594442 -383.646934) (xy 86.886288 -383.355342)
			(xy 86.904331 -383.338086) (xy 86.945826 -383.310338) (xy 86.991944 -383.291234) (xy 87.040906 -383.281511)
			(xy 87.065866 -383.28092) (xy 102.181406 -383.28092) (xy 102.206366 -383.281492) (xy 102.255327 -383.291233)
			(xy 102.301446 -383.310338) (xy 102.342952 -383.338075) (xy 102.360984 -383.355342) (xy 102.641146 -383.635504)
			(xy 102.658401 -383.653547) (xy 102.686148 -383.695043) (xy 102.70525 -383.741161) (xy 102.714971 -383.790123)
			(xy 102.715568 -383.815082) (xy 102.715568 -384.62077) (xy 102.71501 -384.644815) (xy 102.705971 -384.692049)
			(xy 102.688209 -384.736739) (xy 102.662358 -384.777291) (xy 102.629342 -384.812257) (xy 102.610158 -384.826764)
			(xy 102.600735 -384.834425) (xy 102.589741 -384.856039) (xy 102.589076 -384.868166) (xy 102.589076 -386.174488)
			(xy 102.588655 -386.184559) (xy 102.580941 -386.203164) (xy 102.57409 -386.210556) (xy 102.426008 -386.358384)
			(xy 102.41932 -386.365792) (xy 102.411731 -386.384229) (xy 102.411276 -386.394198) (xy 102.411276 -386.44195)
			(xy 102.411889 -386.454093) (xy 102.422884 -386.475736) (xy 102.432358 -386.483352) (xy 102.45153 -386.497874)
			(xy 102.484543 -386.532839) (xy 102.510394 -386.573388) (xy 102.528162 -386.618073) (xy 102.537212 -386.665302)
			(xy 102.537768 -386.689346) (xy 102.537768 -387.19887) (xy 102.538272 -387.208921) (xy 102.54599 -387.227485)
			(xy 102.552754 -387.234938) (xy 102.559104 -387.241288) (xy 102.566502 -387.248135) (xy 102.5851 -387.25587)
			(xy 102.595172 -387.256274) (xy 107.950508 -387.256274) (xy 107.960526 -387.255852) (xy 107.979036 -387.24818)
			(xy 107.993199 -387.234007) (xy 108.000859 -387.215493) (xy 108.001308 -387.205474) (xy 108.001308 -386.926074)
			(xy 108.001794 -386.898823) (xy 108.00955 -386.844875) (xy 108.024905 -386.79258) (xy 108.047547 -386.743003)
			(xy 108.077013 -386.697153) (xy 108.112704 -386.655962) (xy 108.153895 -386.620271) (xy 108.199745 -386.590805)
			(xy 108.249322 -386.568163) (xy 108.301617 -386.552808) (xy 108.355565 -386.545052) (xy 108.410067 -386.545052)
			(xy 108.464015 -386.552808) (xy 108.51631 -386.568163) (xy 108.565887 -386.590805) (xy 108.611737 -386.620271)
			(xy 108.652928 -386.655962) (xy 108.688619 -386.697153) (xy 108.718085 -386.743003) (xy 108.740727 -386.79258)
			(xy 108.756082 -386.844875) (xy 108.763838 -386.898823) (xy 108.764324 -386.926074) (xy 108.764324 -387.205474)
			(xy 108.76474 -387.215497) (xy 108.772406 -387.234019) (xy 108.78658 -387.248193) (xy 108.805101 -387.25586)
			(xy 108.815124 -387.256274) (xy 109.633258 -387.256274) (xy 109.643323 -387.25584) (xy 109.66191 -387.248108)
			(xy 109.669326 -387.241288) (xy 110.066582 -386.844032) (xy 110.07342 -386.836631) (xy 110.081132 -386.818032)
			(xy 110.081568 -386.807964) (xy 110.081568 -384.090926) (xy 110.082186 -384.065972) (xy 110.091935 -384.017025)
			(xy 110.111044 -383.97092) (xy 110.138778 -383.929427) (xy 110.15599 -383.911348) (xy 110.569502 -383.497836)
			(xy 110.587545 -383.480582) (xy 110.629041 -383.452836) (xy 110.675159 -383.433735) (xy 110.724121 -383.424015)
			(xy 110.74908 -383.423414) (xy 110.94339 -383.423414) (xy 110.950278 -383.423154) (xy 110.963545 -383.419429)
			(xy 110.969552 -383.416048) (xy 110.995114 -383.401357) (xy 111.049734 -383.37917) (xy 111.107115 -383.365643)
			(xy 111.165894 -383.361098) (xy 111.224673 -383.365643) (xy 111.282054 -383.37917) (xy 111.336674 -383.401357)
			(xy 111.362236 -383.416048) (xy 111.36823 -383.419464) (xy 111.381502 -383.423215) (xy 111.388398 -383.423414)
			(xy 120.79478 -383.423414) (xy 120.819733 -383.424033) (xy 120.868678 -383.433784) (xy 120.914781 -383.452896)
			(xy 120.95627 -383.480634) (xy 120.974358 -383.497836) (xy 121.159778 -383.683256) (xy 121.16719 -383.68994)
			(xy 121.185623 -383.697537) (xy 121.205561 -383.697537) (xy 121.223994 -383.68994) (xy 121.231406 -383.683256)
			(xy 121.616724 -383.297938) (xy 121.634765 -383.280678) (xy 121.676259 -383.25292) (xy 121.722377 -383.233804)
			(xy 121.771341 -383.224069) (xy 121.796302 -383.223516) (xy 136.689338 -383.223516) (xy 136.714297 -383.224091)
			(xy 136.763254 -383.233837) (xy 136.80937 -383.252946) (xy 136.850871 -383.280686) (xy 136.868916 -383.297938)
			(xy 137.21334 -383.642362) (xy 137.230599 -383.660403) (xy 137.258353 -383.701898) (xy 137.277463 -383.748016)
			(xy 137.287192 -383.796979) (xy 137.287762 -383.82194) (xy 137.287762 -384.62077) (xy 137.287204 -384.644815)
			(xy 137.278164 -384.692049) (xy 137.260402 -384.736739) (xy 137.234552 -384.77729) (xy 137.201535 -384.812256)
			(xy 137.182352 -384.826764) (xy 137.172853 -384.834385) (xy 137.161727 -384.856007) (xy 137.161016 -384.868166)
			(xy 137.161016 -386.174488) (xy 137.160572 -386.184518) (xy 137.15299 -386.203085) (xy 137.146284 -386.210556)
			(xy 136.998202 -386.358384) (xy 136.991404 -386.365734) (xy 136.983702 -386.384197) (xy 136.983216 -386.394198)
			(xy 136.983216 -386.44195) (xy 136.983918 -386.454107) (xy 136.995065 -386.475716) (xy 137.004552 -386.483352)
			(xy 137.023724 -386.497874) (xy 137.056738 -386.532839) (xy 137.08259 -386.573387) (xy 137.100358 -386.618073)
			(xy 137.109408 -386.665302) (xy 137.109962 -386.689346) (xy 137.109962 -387.32079) (xy 137.110448 -387.330802)
			(xy 137.118104 -387.349304) (xy 137.132256 -387.363469) (xy 137.150751 -387.371143) (xy 137.160762 -387.37159)
			(xy 138.462258 -387.37159) (xy 138.472323 -387.371156) (xy 138.490911 -387.363426) (xy 138.498326 -387.356604)
			(xy 139.953238 -385.901692) (xy 139.96009 -385.894296) (xy 139.967831 -385.875697) (xy 139.968224 -385.865624)
			(xy 139.968224 -384.1369) (xy 139.968795 -384.11194) (xy 139.978535 -384.062978) (xy 139.997641 -384.016858)
			(xy 140.025377 -383.975352) (xy 140.042646 -383.957322) (xy 140.839952 -383.160016) (xy 140.857992 -383.142754)
			(xy 140.899484 -383.114992) (xy 140.945603 -383.095875) (xy 140.994568 -383.086142) (xy 141.01953 -383.085594)
			(xy 169.051478 -383.085594) (xy 169.076432 -383.086213) (xy 169.125378 -383.095963) (xy 169.171481 -383.115074)
			(xy 169.212972 -383.14281) (xy 169.231056 -383.160016) (xy 169.72534 -383.6543) (xy 169.742595 -383.672343)
			(xy 169.770344 -383.713838) (xy 169.789447 -383.759956) (xy 169.799169 -383.808918) (xy 169.799762 -383.833878)
			(xy 169.799762 -388.19328) (xy 169.800201 -388.203342) (xy 169.807943 -388.22192) (xy 169.814748 -388.229348)
			(xy 170.647106 -389.061706) (xy 170.654505 -389.068551) (xy 170.673103 -389.076282) (xy 170.683174 -389.076692)
		)
		(stroke
			(width 0)
			(type solid)
		)
		(fill yes)
		(layer "In9.Cu")
		(net "P1V8_CPU1_RT_1D")
	)
	(gr_poly
		(pts
			(xy 143.734536 -266.656566) (xy 143.74114 -266.643866) (xy 143.753486 -266.621193) (xy 143.784122 -266.579643)
			(xy 143.820838 -266.543355) (xy 143.862744 -266.513208) (xy 143.908822 -266.489933) (xy 143.957956 -266.474096)
			(xy 144.008953 -266.46608) (xy 144.060575 -266.46608) (xy 144.111572 -266.474096) (xy 144.160706 -266.489933)
			(xy 144.206784 -266.513208) (xy 144.24869 -266.543355) (xy 144.285406 -266.579643) (xy 144.316042 -266.621193)
			(xy 144.328388 -266.643866) (xy 144.334992 -266.656566) (xy 144.359122 -266.671298) (xy 145.443194 -266.671298)
			(xy 145.455331 -266.670675) (xy 145.476954 -266.659665) (xy 145.484596 -266.650216) (xy 145.499095 -266.63096)
			(xy 145.534057 -266.597788) (xy 145.57465 -266.571809) (xy 145.619416 -266.553956) (xy 145.666747 -266.54487)
			(xy 145.690844 -266.544298) (xy 163.992814 -266.544298) (xy 164.002883 -266.543872) (xy 164.021484 -266.536154)
			(xy 164.028882 -266.529312) (xy 164.110416 -266.447778) (xy 164.118255 -266.439219) (xy 164.125885 -266.417326)
			(xy 164.123114 -266.394307) (xy 164.117274 -266.384278) (xy 164.103508 -266.361903) (xy 164.081757 -266.314085)
			(xy 164.067007 -266.263665) (xy 164.059557 -266.211663) (xy 164.059108 -266.185396) (xy 164.059633 -266.157225)
			(xy 164.068186 -266.101537) (xy 164.085108 -266.047797) (xy 164.110004 -265.997255) (xy 164.142297 -265.951087)
			(xy 164.181234 -265.910366) (xy 164.225911 -265.876039) (xy 164.25037 -265.862054) (xy 164.258137 -265.85736)
			(xy 164.270004 -265.843646) (xy 164.276387 -265.82667) (xy 164.276786 -265.817604) (xy 164.276786 -264.853166)
			(xy 164.27642 -264.844089) (xy 164.270075 -264.827081) (xy 164.258166 -264.813379) (xy 164.25037 -264.808716)
			(xy 164.227564 -264.795642) (xy 164.185567 -264.764029) (xy 164.148481 -264.726775) (xy 164.117057 -264.684636)
			(xy 164.091931 -264.638463) (xy 164.073613 -264.589192) (xy 164.062472 -264.537821) (xy 164.058734 -264.485387)
			(xy 164.062475 -264.432955) (xy 164.07362 -264.381583) (xy 164.091942 -264.332314) (xy 164.117071 -264.286143)
			(xy 164.148497 -264.244006) (xy 164.185586 -264.206755) (xy 164.227585 -264.175144) (xy 164.25037 -264.162032)
			(xy 164.258135 -264.157337) (xy 164.269996 -264.143622) (xy 164.276372 -264.126646) (xy 164.276786 -264.117582)
			(xy 164.276786 -263.153144) (xy 164.276433 -263.14406) (xy 164.270104 -263.127031) (xy 164.258201 -263.113307)
			(xy 164.25037 -263.108694) (xy 164.227566 -263.09562) (xy 164.185572 -263.064007) (xy 164.148489 -263.026755)
			(xy 164.117068 -262.984617) (xy 164.091945 -262.938446) (xy 164.073628 -262.889177) (xy 164.06249 -262.837807)
			(xy 164.058754 -262.785377) (xy 164.062496 -262.732947) (xy 164.073641 -262.681579) (xy 164.091964 -262.632312)
			(xy 164.117092 -262.586144) (xy 164.148519 -262.54401) (xy 164.185606 -262.506762) (xy 164.227605 -262.475154)
			(xy 164.25037 -262.46201) (xy 164.258132 -262.457314) (xy 164.269988 -262.443598) (xy 164.276356 -262.426623)
			(xy 164.276786 -262.41756) (xy 164.276786 -255.503172) (xy 164.276421 -255.494094) (xy 164.270077 -255.477085)
			(xy 164.258169 -255.463381) (xy 164.25037 -255.458722) (xy 164.227564 -255.445648) (xy 164.185566 -255.414035)
			(xy 164.148479 -255.376781) (xy 164.117054 -255.334641) (xy 164.091928 -255.288468) (xy 164.073609 -255.239197)
			(xy 164.062467 -255.187824) (xy 164.058729 -255.13539) (xy 164.06247 -255.082957) (xy 164.073614 -255.031585)
			(xy 164.091936 -254.982314) (xy 164.117065 -254.936143) (xy 164.148491 -254.894004) (xy 164.18558 -254.856752)
			(xy 164.22758 -254.825141) (xy 164.25037 -254.812038) (xy 164.258135 -254.807343) (xy 164.269998 -254.793628)
			(xy 164.276376 -254.776653) (xy 164.276786 -254.767588) (xy 164.276786 -252.953012) (xy 164.276427 -252.943931)
			(xy 164.270092 -252.92691) (xy 164.258187 -252.913196) (xy 164.25037 -252.908562) (xy 164.227561 -252.895488)
			(xy 164.185557 -252.863874) (xy 164.148465 -252.826619) (xy 164.117035 -252.784476) (xy 164.091904 -252.7383)
			(xy 164.07358 -252.689025) (xy 164.062435 -252.637648) (xy 164.058694 -252.58521) (xy 164.062432 -252.532771)
			(xy 164.073575 -252.481393) (xy 164.091896 -252.432117) (xy 164.117025 -252.38594) (xy 164.148452 -252.343796)
			(xy 164.185543 -252.306539) (xy 164.227545 -252.274922) (xy 164.25037 -252.261878) (xy 164.258129 -252.25718)
			(xy 164.269976 -252.243462) (xy 164.276334 -252.226489) (xy 164.276786 -252.217428) (xy 164.276786 -251.25299)
			(xy 164.276424 -251.243911) (xy 164.270084 -251.226896) (xy 164.258177 -251.213188) (xy 164.25037 -251.20854)
			(xy 164.227563 -251.195466) (xy 164.185562 -251.163852) (xy 164.148472 -251.126598) (xy 164.117046 -251.084457)
			(xy 164.091917 -251.038283) (xy 164.073596 -250.989009) (xy 164.062453 -250.937635) (xy 164.058713 -250.885199)
			(xy 164.062453 -250.832763) (xy 164.073596 -250.781389) (xy 164.091918 -250.732116) (xy 164.117047 -250.685941)
			(xy 164.148474 -250.643801) (xy 164.185563 -250.606546) (xy 164.227564 -250.574933) (xy 164.25037 -250.561856)
			(xy 164.258137 -250.557162) (xy 164.270005 -250.543448) (xy 164.276388 -250.526472) (xy 164.276786 -250.517406)
			(xy 164.276786 -249.553222) (xy 164.276429 -249.54414) (xy 164.270096 -249.527117) (xy 164.258191 -249.513399)
			(xy 164.25037 -249.508772) (xy 164.22756 -249.495698) (xy 164.185555 -249.464084) (xy 164.148461 -249.426828)
			(xy 164.11703 -249.384685) (xy 164.091898 -249.338508) (xy 164.073573 -249.289232) (xy 164.062427 -249.237854)
			(xy 164.058685 -249.185414) (xy 164.062423 -249.132974) (xy 164.073565 -249.081596) (xy 164.091886 -249.032318)
			(xy 164.117015 -248.986139) (xy 164.148442 -248.943994) (xy 164.185533 -248.906735) (xy 164.227536 -248.875118)
			(xy 164.25037 -248.862088) (xy 164.25813 -248.857391) (xy 164.269979 -248.843673) (xy 164.276341 -248.826699)
			(xy 164.276786 -248.817638) (xy 164.276786 -247.8532) (xy 164.276426 -247.84412) (xy 164.270088 -247.827103)
			(xy 164.258182 -247.813391) (xy 164.25037 -247.80875) (xy 164.227562 -247.795676) (xy 164.18556 -247.764062)
			(xy 164.148469 -247.726807) (xy 164.117041 -247.684666) (xy 164.091911 -247.638491) (xy 164.073589 -247.589217)
			(xy 164.062445 -247.537841) (xy 164.058704 -247.485404) (xy 164.062444 -247.432967) (xy 164.073587 -247.381591)
			(xy 164.091908 -247.332316) (xy 164.117037 -247.286141) (xy 164.148464 -247.243998) (xy 164.185554 -247.206743)
			(xy 164.227556 -247.175128) (xy 164.25037 -247.162066) (xy 164.258138 -247.157372) (xy 164.270009 -247.143659)
			(xy 164.276395 -247.126683) (xy 164.276786 -247.117616) (xy 164.276786 -246.153178) (xy 164.276422 -246.1441)
			(xy 164.270079 -246.127089) (xy 164.258172 -246.113384) (xy 164.25037 -246.108728) (xy 164.227564 -246.095654)
			(xy 164.185564 -246.064041) (xy 164.148477 -246.026787) (xy 164.117051 -245.984647) (xy 164.091924 -245.938473)
			(xy 164.073604 -245.889201) (xy 164.062462 -245.837828) (xy 164.058724 -245.785393) (xy 164.062464 -245.732959)
			(xy 164.073608 -245.681586) (xy 164.09193 -245.632315) (xy 164.117059 -245.586142) (xy 164.148485 -245.544003)
			(xy 164.185575 -245.50675) (xy 164.227575 -245.475138) (xy 164.25037 -245.462044) (xy 164.258136 -245.45735)
			(xy 164.27 -245.443635) (xy 164.27638 -245.426659) (xy 164.276786 -245.417594) (xy 164.276786 -244.453156)
			(xy 164.276418 -244.44408) (xy 164.270071 -244.427074) (xy 164.258162 -244.413376) (xy 164.25037 -244.408706)
			(xy 164.227565 -244.395632) (xy 164.185569 -244.364019) (xy 164.148484 -244.326766) (xy 164.117062 -244.284627)
			(xy 164.091937 -244.238455) (xy 164.07362 -244.189185) (xy 164.06248 -244.137815) (xy 164.058743 -244.085383)
			(xy 164.062485 -244.032951) (xy 164.07363 -243.981581) (xy 164.091952 -243.932313) (xy 164.117081 -243.886144)
			(xy 164.148507 -243.844008) (xy 164.185595 -243.806758) (xy 164.227594 -243.775149) (xy 164.25037 -243.762022)
			(xy 164.258134 -243.757327) (xy 164.269992 -243.743611) (xy 164.276365 -243.726636) (xy 164.276786 -243.717572)
			(xy 164.276786 -242.753134) (xy 164.276431 -242.744051) (xy 164.270101 -242.727024) (xy 164.258197 -242.713303)
			(xy 164.25037 -242.708684) (xy 164.22756 -242.69561) (xy 164.185553 -242.663995) (xy 164.148457 -242.626739)
			(xy 164.117025 -242.584596) (xy 164.091891 -242.538418) (xy 164.073565 -242.489141) (xy 164.062418 -242.437761)
			(xy 164.058675 -242.38532) (xy 164.062412 -242.332879) (xy 164.073553 -242.281498) (xy 164.091874 -242.232219)
			(xy 164.117003 -242.186038) (xy 164.148431 -242.143891) (xy 164.185522 -242.106631) (xy 164.227526 -242.075012)
			(xy 164.25037 -242.062) (xy 164.258131 -242.057303) (xy 164.269984 -242.043586) (xy 164.276349 -242.026612)
			(xy 164.276786 -242.01755) (xy 164.276786 -236.803184) (xy 164.276423 -236.794105) (xy 164.270081 -236.777092)
			(xy 164.258174 -236.763386) (xy 164.25037 -236.758734) (xy 164.227563 -236.74566) (xy 164.185563 -236.714047)
			(xy 164.148475 -236.676792) (xy 164.117048 -236.634652) (xy 164.091921 -236.588478) (xy 164.0736 -236.539205)
			(xy 164.062458 -236.487831) (xy 164.058718 -236.435396) (xy 164.062459 -236.382961) (xy 164.073602 -236.331587)
			(xy 164.091924 -236.282315) (xy 164.117053 -236.236142) (xy 164.14848 -236.194002) (xy 164.185569 -236.156748)
			(xy 164.22757 -236.125136) (xy 164.25037 -236.11205) (xy 164.258137 -236.107356) (xy 164.270003 -236.093641)
			(xy 164.276384 -236.076666) (xy 164.276786 -236.0676) (xy 164.276786 -235.103162) (xy 164.276419 -235.094085)
			(xy 164.270073 -235.077078) (xy 164.258165 -235.063378) (xy 164.25037 -235.058712) (xy 164.227565 -235.045638)
			(xy 164.185568 -235.014025) (xy 164.148482 -234.976772) (xy 164.117059 -234.934632) (xy 164.091934 -234.88846)
			(xy 164.073616 -234.83919) (xy 164.062475 -234.787818) (xy 164.058738 -234.735386) (xy 164.062479 -234.682953)
			(xy 164.073624 -234.631583) (xy 164.091946 -234.582313) (xy 164.117075 -234.536143) (xy 164.148501 -234.494006)
			(xy 164.18559 -234.456756) (xy 164.227589 -234.425146) (xy 164.25037 -234.412028) (xy 164.258134 -234.407333)
			(xy 164.269995 -234.393617) (xy 164.276369 -234.376642) (xy 164.276786 -234.367578) (xy 164.276786 -233.40314)
			(xy 164.276432 -233.394056) (xy 164.270103 -233.377028) (xy 164.258199 -233.363306) (xy 164.25037 -233.35869)
			(xy 164.227559 -233.345616) (xy 164.185551 -233.314001) (xy 164.148455 -233.276745) (xy 164.117022 -233.234601)
			(xy 164.091887 -233.188423) (xy 164.073561 -233.139145) (xy 164.062413 -233.087765) (xy 164.058669 -233.035323)
			(xy 164.062406 -232.982881) (xy 164.073548 -232.931499) (xy 164.091868 -232.882219) (xy 164.116997 -232.836038)
			(xy 164.148425 -232.79389) (xy 164.185516 -232.756629) (xy 164.22752 -232.725009) (xy 164.25037 -232.712006)
			(xy 164.258132 -232.70731) (xy 164.269986 -232.693593) (xy 164.276353 -232.676619) (xy 164.276786 -232.667556)
			(xy 164.276786 -227.45319) (xy 164.276424 -227.444111) (xy 164.270084 -227.427096) (xy 164.258177 -227.413388)
			(xy 164.25037 -227.40874) (xy 164.227563 -227.395666) (xy 164.185562 -227.364052) (xy 164.148472 -227.326798)
			(xy 164.117046 -227.284657) (xy 164.091917 -227.238483) (xy 164.073596 -227.189209) (xy 164.062453 -227.137835)
			(xy 164.058713 -227.085399) (xy 164.062453 -227.032963) (xy 164.073596 -226.981589) (xy 164.091918 -226.932316)
			(xy 164.117047 -226.886141) (xy 164.148474 -226.844001) (xy 164.185563 -226.806746) (xy 164.227564 -226.775133)
			(xy 164.25037 -226.762056) (xy 164.258137 -226.757362) (xy 164.270005 -226.743648) (xy 164.276388 -226.726672)
			(xy 164.276786 -226.717606) (xy 164.276786 -225.753168) (xy 164.27642 -225.744091) (xy 164.270075 -225.727082)
			(xy 164.258167 -225.71338) (xy 164.25037 -225.708718) (xy 164.227564 -225.695644) (xy 164.185566 -225.664031)
			(xy 164.14848 -225.626777) (xy 164.117056 -225.584638) (xy 164.09193 -225.538465) (xy 164.073611 -225.489194)
			(xy 164.06247 -225.437822) (xy 164.058733 -225.385388) (xy 164.062474 -225.332955) (xy 164.073618 -225.281584)
			(xy 164.09194 -225.232314) (xy 164.117069 -225.186143) (xy 164.148495 -225.144005) (xy 164.185584 -225.106754)
			(xy 164.227584 -225.075143) (xy 164.25037 -225.062034) (xy 164.258135 -225.057339) (xy 164.269997 -225.043624)
			(xy 164.276373 -225.026648) (xy 164.276786 -225.017584) (xy 164.276786 -224.053146) (xy 164.276433 -224.044061)
			(xy 164.270105 -224.027032) (xy 164.258202 -224.013308) (xy 164.25037 -224.008696) (xy 164.227566 -223.995622)
			(xy 164.185571 -223.964009) (xy 164.148488 -223.926757) (xy 164.117067 -223.884618) (xy 164.091943 -223.838447)
			(xy 164.073627 -223.789178) (xy 164.062488 -223.737808) (xy 164.058752 -223.685378) (xy 164.062494 -223.632948)
			(xy 164.073639 -223.581579) (xy 164.091962 -223.532312) (xy 164.117091 -223.486144) (xy 164.148517 -223.44401)
			(xy 164.185605 -223.406761) (xy 164.227603 -223.375154) (xy 164.25037 -223.362012) (xy 164.258133 -223.357316)
			(xy 164.269989 -223.3436) (xy 164.276358 -223.326625) (xy 164.276786 -223.317562) (xy 164.276786 -218.103196)
			(xy 164.276425 -218.094116) (xy 164.270086 -218.0771) (xy 164.25818 -218.06339) (xy 164.25037 -218.058746)
			(xy 164.227562 -218.045672) (xy 164.185561 -218.014058) (xy 164.14847 -217.976804) (xy 164.117043 -217.934662)
			(xy 164.091914 -217.888487) (xy 164.073592 -217.839214) (xy 164.062448 -217.787839) (xy 164.058708 -217.735402)
			(xy 164.062447 -217.682965) (xy 164.073591 -217.63159) (xy 164.091912 -217.582316) (xy 164.117041 -217.536141)
			(xy 164.148468 -217.493999) (xy 164.185558 -217.456744) (xy 164.227559 -217.42513) (xy 164.25037 -217.412062)
			(xy 164.258138 -217.407368) (xy 164.270007 -217.393654) (xy 164.276392 -217.376678) (xy 164.276786 -217.367612)
			(xy 164.276786 -216.403174) (xy 164.276421 -216.394096) (xy 164.270078 -216.377086) (xy 164.25817 -216.363382)
			(xy 164.25037 -216.358724) (xy 164.227564 -216.34565) (xy 164.185565 -216.314037) (xy 164.148478 -216.276783)
			(xy 164.117053 -216.234643) (xy 164.091927 -216.18847) (xy 164.073607 -216.139198) (xy 164.062466 -216.087825)
			(xy 164.058727 -216.035391) (xy 164.062468 -215.982957) (xy 164.073612 -215.931585) (xy 164.091934 -215.882314)
			(xy 164.117063 -215.836142) (xy 164.148489 -215.794004) (xy 164.185578 -215.756752) (xy 164.227578 -215.72514)
			(xy 164.25037 -215.71204) (xy 164.258135 -215.707345) (xy 164.269999 -215.69363) (xy 164.276377 -215.676655)
			(xy 164.276786 -215.66759) (xy 164.276786 -214.703152) (xy 164.276418 -214.694076) (xy 164.270069 -214.677072)
			(xy 164.25816 -214.663374) (xy 164.25037 -214.658702) (xy 164.227565 -214.645628) (xy 164.18557 -214.614015)
			(xy 164.148486 -214.576762) (xy 164.117064 -214.534624) (xy 164.09194 -214.488452) (xy 164.073623 -214.439183)
			(xy 164.062483 -214.387812) (xy 164.058747 -214.335381) (xy 164.062489 -214.28295) (xy 164.073634 -214.23158)
			(xy 164.091956 -214.182313) (xy 164.117085 -214.136144) (xy 164.148511 -214.094008) (xy 164.185599 -214.056759)
			(xy 164.227598 -214.025151) (xy 164.25037 -214.012018) (xy 164.258133 -214.007322) (xy 164.269991 -213.993606)
			(xy 164.276362 -213.976631) (xy 164.276786 -213.967568) (xy 164.276786 -208.753202) (xy 164.276426 -208.744122)
			(xy 164.270088 -208.727104) (xy 164.258182 -208.713392) (xy 164.25037 -208.708752) (xy 164.227562 -208.695678)
			(xy 164.185559 -208.664064) (xy 164.148468 -208.626809) (xy 164.11704 -208.584668) (xy 164.09191 -208.538492)
			(xy 164.073587 -208.489218) (xy 164.062443 -208.437842) (xy 164.058703 -208.385405) (xy 164.062442 -208.332967)
			(xy 164.073585 -208.281591) (xy 164.091906 -208.232316) (xy 164.117035 -208.186141) (xy 164.148462 -208.143998)
			(xy 164.185552 -208.106742) (xy 164.227554 -208.075127) (xy 164.25037 -208.062068) (xy 164.258138 -208.057375)
			(xy 164.270009 -208.043661) (xy 164.276397 -208.026685) (xy 164.276786 -208.017618) (xy 164.276786 -207.05318)
			(xy 164.276422 -207.044102) (xy 164.27008 -207.02709) (xy 164.258173 -207.013384) (xy 164.25037 -207.00873)
			(xy 164.227563 -206.995656) (xy 164.185564 -206.964043) (xy 164.148476 -206.926789) (xy 164.11705 -206.884648)
			(xy 164.091923 -206.838475) (xy 164.073603 -206.789202) (xy 164.062461 -206.737829) (xy 164.058722 -206.685394)
			(xy 164.062462 -206.63296) (xy 164.073606 -206.581586) (xy 164.091928 -206.532315) (xy 164.117057 -206.486142)
			(xy 164.148484 -206.444003) (xy 164.185573 -206.40675) (xy 164.227573 -206.375137) (xy 164.25037 -206.362046)
			(xy 164.258136 -206.357352) (xy 164.270001 -206.343637) (xy 164.276381 -206.326661) (xy 164.276786 -206.317596)
			(xy 164.276786 -205.353158) (xy 164.276419 -205.344082) (xy 164.270072 -205.327076) (xy 164.258163 -205.313376)
			(xy 164.25037 -205.308708) (xy 164.227565 -205.295634) (xy 164.185569 -205.264021) (xy 164.148484 -205.226768)
			(xy 164.117061 -205.184629) (xy 164.091936 -205.138457) (xy 164.073618 -205.089187) (xy 164.062478 -205.037816)
			(xy 164.058741 -204.985384) (xy 164.062483 -204.932952) (xy 164.073628 -204.881582) (xy 164.09195 -204.832313)
			(xy 164.117079 -204.786143) (xy 164.148505 -204.744007) (xy 164.185593 -204.706757) (xy 164.227593 -204.675148)
			(xy 164.25037 -204.662024) (xy 164.258134 -204.657329) (xy 164.269993 -204.643613) (xy 164.276366 -204.626638)
			(xy 164.276786 -204.617574) (xy 164.276786 -199.403208) (xy 164.276427 -199.394127) (xy 164.270091 -199.377108)
			(xy 164.258185 -199.363394) (xy 164.25037 -199.358758) (xy 164.227561 -199.345684) (xy 164.185558 -199.31407)
			(xy 164.148466 -199.276815) (xy 164.117037 -199.234673) (xy 164.091906 -199.188497) (xy 164.073583 -199.139222)
			(xy 164.062438 -199.087846) (xy 164.058697 -199.035408) (xy 164.062436 -198.982969) (xy 164.073579 -198.931593)
			(xy 164.0919 -198.882317) (xy 164.117029 -198.83614) (xy 164.148456 -198.793997) (xy 164.185546 -198.75674)
			(xy 164.227548 -198.725124) (xy 164.25037 -198.712074) (xy 164.258128 -198.707376) (xy 164.269974 -198.693658)
			(xy 164.276331 -198.676685) (xy 164.276786 -198.667624) (xy 164.276786 -197.703186) (xy 164.276423 -197.694107)
			(xy 164.270082 -197.677094) (xy 164.258175 -197.663386) (xy 164.25037 -197.658736) (xy 164.227563 -197.645662)
			(xy 164.185563 -197.614049) (xy 164.148474 -197.576794) (xy 164.117047 -197.534654) (xy 164.09192 -197.488479)
			(xy 164.073599 -197.439207) (xy 164.062456 -197.387833) (xy 164.058717 -197.335397) (xy 164.062457 -197.282962)
			(xy 164.0736 -197.231588) (xy 164.091922 -197.182315) (xy 164.117051 -197.136142) (xy 164.148478 -197.094001)
			(xy 164.185567 -197.056748) (xy 164.227568 -197.025135) (xy 164.25037 -197.012052) (xy 164.258137 -197.007358)
			(xy 164.270003 -196.993643) (xy 164.276385 -196.976668) (xy 164.276786 -196.967602) (xy 164.276786 -194.52336)
			(xy 164.276532 -194.522852) (xy 164.276532 -183.226456) (xy 164.276102 -183.216389) (xy 164.26838 -183.197793)
			(xy 164.261546 -183.190388) (xy 149.383242 -168.312084) (xy 149.375819 -168.305301) (xy 149.357222 -168.297695)
			(xy 149.347174 -168.297352) (xy 140.431266 -168.297352) (xy 140.421469 -168.297734) (xy 140.403271 -168.304979)
			(xy 140.389142 -168.318544) (xy 140.384784 -168.327324) (xy 140.368021 -168.363475) (xy 140.328033 -168.432406)
			(xy 140.281071 -168.496789) (xy 140.22765 -168.555921) (xy 140.168351 -168.609158) (xy 140.103822 -168.655918)
			(xy 140.034767 -168.695691) (xy 139.961939 -168.728044) (xy 139.886134 -168.752622) (xy 139.808178 -168.769158)
			(xy 139.728923 -168.777471) (xy 139.649233 -168.777471) (xy 139.569978 -168.769158) (xy 139.492022 -168.752622)
			(xy 139.416217 -168.728044) (xy 139.343389 -168.695691) (xy 139.274334 -168.655918) (xy 139.209805 -168.609158)
			(xy 139.150506 -168.555921) (xy 139.097085 -168.496789) (xy 139.050123 -168.432406) (xy 139.010135 -168.363475)
			(xy 138.993372 -168.327324) (xy 138.988938 -168.318601) (xy 138.974811 -168.305086) (xy 138.956666 -168.297806)
			(xy 138.94689 -168.297352) (xy 136.143492 -168.297352) (xy 136.143492 -168.296844) (xy 130.011424 -168.296844)
			(xy 130.001361 -168.297282) (xy 129.982781 -168.305021) (xy 129.975356 -168.31183) (xy 128.64338 -169.643806)
			(xy 128.625341 -169.66107) (xy 128.583849 -169.688835) (xy 128.53773 -169.707955) (xy 128.488765 -169.717694)
			(xy 128.463802 -169.718228) (xy 126.55296 -169.718228) (xy 126.542894 -169.718659) (xy 126.524302 -169.726387)
			(xy 126.516892 -169.733214) (xy 113.757456 -182.49265) (xy 113.753138 -182.52694) (xy 113.762028 -182.54218)
			(xy 113.774752 -182.564367) (xy 113.794795 -182.611423) (xy 113.80836 -182.660738) (xy 113.815204 -182.711425)
			(xy 113.815622 -182.736998) (xy 113.815136 -182.76425) (xy 113.80738 -182.818198) (xy 113.792025 -182.870494)
			(xy 113.769385 -182.920073) (xy 113.739919 -182.965924) (xy 113.704227 -183.007116) (xy 113.663037 -183.042809)
			(xy 113.617187 -183.072277) (xy 113.567609 -183.09492) (xy 113.515314 -183.110277) (xy 113.461366 -183.118035)
			(xy 113.434114 -183.118506) (xy 113.408542 -183.118078) (xy 113.357859 -183.111217) (xy 113.308544 -183.097657)
			(xy 113.261479 -183.07764) (xy 113.239296 -183.064912) (xy 113.224056 -183.056022) (xy 113.189766 -183.06034)
			(xy 112.196372 -184.053734) (xy 112.189523 -184.061131) (xy 112.18179 -184.07973) (xy 112.181386 -184.089802)
			(xy 112.181386 -192.092326) (xy 112.181813 -192.102394) (xy 112.189533 -192.120993) (xy 112.196372 -192.128394)
			(xy 131.697476 -211.629498) (xy 131.714735 -211.647539) (xy 131.742491 -211.689032) (xy 131.7616 -211.735151)
			(xy 131.771324 -211.784115) (xy 131.771898 -211.809076) (xy 131.771898 -212.98027) (xy 140.011662 -212.98027)
			(xy 140.015692 -212.83792) (xy 140.027769 -212.696027) (xy 140.047854 -212.555044) (xy 140.075883 -212.415423)
			(xy 140.111767 -212.277611) (xy 140.155389 -212.14205) (xy 140.206611 -212.009175) (xy 140.265269 -211.87941)
			(xy 140.331174 -211.753171) (xy 140.404115 -211.630863) (xy 140.483859 -211.512878) (xy 140.570151 -211.399593)
			(xy 140.662713 -211.291372) (xy 140.76125 -211.18856) (xy 140.865445 -211.091488) (xy 140.974966 -211.000467)
			(xy 141.08946 -210.915787) (xy 141.208562 -210.837721) (xy 141.33189 -210.766517) (xy 141.459048 -210.702405)
			(xy 141.58963 -210.64559) (xy 141.723218 -210.596253) (xy 141.859382 -210.554553) (xy 141.997688 -210.520624)
			(xy 142.137691 -210.494573) (xy 142.278945 -210.476485) (xy 142.420995 -210.466417) (xy 142.563387 -210.464402)
			(xy 142.705666 -210.470446) (xy 142.847374 -210.484529) (xy 142.988059 -210.506608) (xy 143.127269 -210.53661)
			(xy 143.264559 -210.57444) (xy 143.399489 -210.619976) (xy 143.531627 -210.673074) (xy 143.660549 -210.733561)
			(xy 143.785842 -210.801246) (xy 143.907105 -210.875911) (xy 144.02395 -210.957317) (xy 144.136003 -211.045203)
			(xy 144.242903 -211.139287) (xy 144.34431 -211.239269) (xy 144.439898 -211.344827) (xy 144.529361 -211.455625)
			(xy 144.612412 -211.571306) (xy 144.688785 -211.691501) (xy 144.758236 -211.815824) (xy 144.820542 -211.943877)
			(xy 144.875504 -212.07525) (xy 144.922945 -212.209522) (xy 144.962714 -212.346263) (xy 144.994683 -212.485035)
			(xy 145.01875 -212.625393) (xy 145.034838 -212.766888) (xy 145.042894 -212.909067) (xy 145.043398 -212.98027)
			(xy 145.042894 -213.051473) (xy 145.034838 -213.193652) (xy 145.01875 -213.335147) (xy 144.994683 -213.475505)
			(xy 144.962714 -213.614277) (xy 144.922945 -213.751018) (xy 144.875504 -213.88529) (xy 144.820542 -214.016663)
			(xy 144.758236 -214.144716) (xy 144.688785 -214.269039) (xy 144.612412 -214.389234) (xy 144.529361 -214.504915)
			(xy 144.439898 -214.615713) (xy 144.34431 -214.721271) (xy 144.242903 -214.821253) (xy 144.136003 -214.915337)
			(xy 144.02395 -215.003223) (xy 143.907105 -215.084629) (xy 143.785842 -215.159294) (xy 143.660549 -215.226979)
			(xy 143.531627 -215.287466) (xy 143.399489 -215.340564) (xy 143.264559 -215.3861) (xy 143.127269 -215.42393)
			(xy 142.988059 -215.453932) (xy 142.847374 -215.476011) (xy 142.705666 -215.490094) (xy 142.563387 -215.496138)
			(xy 142.420995 -215.494123) (xy 142.278945 -215.484055) (xy 142.137691 -215.465967) (xy 141.997688 -215.439916)
			(xy 141.859382 -215.405987) (xy 141.723218 -215.364287) (xy 141.58963 -215.31495) (xy 141.459048 -215.258135)
			(xy 141.33189 -215.194023) (xy 141.208562 -215.122819) (xy 141.08946 -215.044753) (xy 140.974966 -214.960073)
			(xy 140.865445 -214.869052) (xy 140.76125 -214.77198) (xy 140.662713 -214.669168) (xy 140.570151 -214.560947)
			(xy 140.483859 -214.447662) (xy 140.404115 -214.329677) (xy 140.331174 -214.207369) (xy 140.265269 -214.08113)
			(xy 140.206611 -213.951365) (xy 140.155389 -213.81849) (xy 140.111767 -213.682929) (xy 140.075883 -213.545117)
			(xy 140.047854 -213.405496) (xy 140.027769 -213.264513) (xy 140.015692 -213.12262) (xy 140.011662 -212.98027)
			(xy 131.771898 -212.98027) (xy 131.771898 -221.579186) (xy 131.772268 -221.58722) (xy 131.777326 -221.602476)
			(xy 131.781804 -221.609158) (xy 131.796838 -221.630538) (xy 131.820676 -221.677047) (xy 131.836886 -221.726733)
			(xy 131.845063 -221.778352) (xy 131.845558 -221.804484) (xy 131.845093 -221.829922) (xy 131.837304 -221.880199)
			(xy 131.821909 -221.928691) (xy 131.799271 -221.974253) (xy 131.769922 -222.015811) (xy 131.734556 -222.052385)
			(xy 131.694006 -222.083112) (xy 131.671822 -222.095568) (xy 131.65963 -222.102172) (xy 131.645152 -222.126048)
			(xy 131.645152 -223.102932) (xy 131.65963 -223.126808) (xy 131.671822 -223.133412) (xy 131.693993 -223.145894)
			(xy 131.734551 -223.176611) (xy 131.769926 -223.213178) (xy 131.799283 -223.254731) (xy 131.82193 -223.30029)
			(xy 131.837331 -223.34878) (xy 131.845124 -223.399057) (xy 131.845558 -223.424496) (xy 131.845075 -223.450484)
			(xy 131.836944 -223.50182) (xy 131.820882 -223.551252) (xy 131.797283 -223.597562) (xy 131.76673 -223.63961)
			(xy 131.729975 -223.67636) (xy 131.687923 -223.706907) (xy 131.641609 -223.730499) (xy 131.592175 -223.746555)
			(xy 131.540838 -223.754679) (xy 131.51485 -223.755204) (xy 131.503166 -223.75495) (xy 131.488942 -223.754442)
			(xy 131.464558 -223.767904) (xy 131.318 -224.020634) (xy 131.318508 -224.04832) (xy 131.325874 -224.060512)
			(xy 131.337608 -224.080199) (xy 131.356127 -224.12212) (xy 131.368679 -224.166198) (xy 131.375022 -224.211587)
			(xy 131.375404 -224.234502) (xy 131.374921 -224.260491) (xy 131.366789 -224.311829) (xy 131.350727 -224.361263)
			(xy 131.327129 -224.407576) (xy 131.296577 -224.449627) (xy 131.259822 -224.48638) (xy 131.217771 -224.516932)
			(xy 131.171458 -224.540529) (xy 131.122023 -224.556591) (xy 131.070685 -224.564721) (xy 131.044696 -224.56521)
			(xy 131.033266 -224.564956) (xy 131.019042 -224.564448) (xy 130.994658 -224.57791) (xy 130.8481 -224.830386)
			(xy 130.848608 -224.858326) (xy 130.855974 -224.870518) (xy 130.867707 -224.890205) (xy 130.886226 -224.932127)
			(xy 130.898777 -224.976204) (xy 130.905119 -225.021593) (xy 130.905504 -225.044508) (xy 130.904994 -225.070495)
			(xy 130.896862 -225.121828) (xy 130.880801 -225.171257) (xy 130.857204 -225.217565) (xy 130.826654 -225.259612)
			(xy 130.789903 -225.296362) (xy 130.747855 -225.32691) (xy 130.701546 -225.350505) (xy 130.652116 -225.366565)
			(xy 130.600783 -225.374695) (xy 130.574796 -225.375216) (xy 130.563112 -225.374962) (xy 130.549142 -225.374454)
			(xy 130.524504 -225.387916) (xy 130.377946 -225.640646) (xy 130.378454 -225.668586) (xy 130.38582 -225.680524)
			(xy 130.397552 -225.700211) (xy 130.416067 -225.742134) (xy 130.428615 -225.786211) (xy 130.434956 -225.8316)
			(xy 130.43535 -225.854514) (xy 130.434839 -225.880502) (xy 130.426707 -225.931837) (xy 130.410646 -225.981268)
			(xy 130.38705 -226.027579) (xy 130.356501 -226.069629) (xy 130.31975 -226.106382) (xy 130.277703 -226.136935)
			(xy 130.231394 -226.160535) (xy 130.181964 -226.176601) (xy 130.13063 -226.184737) (xy 130.104642 -226.185222)
			(xy 130.093212 -226.184968) (xy 130.078988 -226.18446) (xy 130.054604 -226.197922) (xy 129.908046 -226.450652)
			(xy 129.908554 -226.478338) (xy 129.91592 -226.49053) (xy 129.927651 -226.510218) (xy 129.946166 -226.55214)
			(xy 129.958713 -226.596218) (xy 129.965053 -226.641606) (xy 129.96545 -226.66452) (xy 129.964939 -226.690507)
			(xy 129.956806 -226.741842) (xy 129.940744 -226.791272) (xy 129.917148 -226.837582) (xy 129.886598 -226.879631)
			(xy 129.849848 -226.916384) (xy 129.807801 -226.946936) (xy 129.761493 -226.970536) (xy 129.712063 -226.986601)
			(xy 129.660729 -226.994737) (xy 129.634742 -226.995228) (xy 129.623312 -226.994974) (xy 129.609088 -226.994466)
			(xy 129.584704 -227.007928) (xy 129.438146 -227.260404) (xy 129.438654 -227.288344) (xy 129.44602 -227.300536)
			(xy 129.457751 -227.320224) (xy 129.476265 -227.362146) (xy 129.488811 -227.406224) (xy 129.49515 -227.451612)
			(xy 129.49555 -227.474526) (xy 129.495039 -227.500513) (xy 129.486905 -227.551847) (xy 129.470842 -227.601277)
			(xy 129.447246 -227.647586) (xy 129.416696 -227.689634) (xy 129.379946 -227.726386) (xy 129.337899 -227.756937)
			(xy 129.291591 -227.780536) (xy 129.242162 -227.796601) (xy 129.190829 -227.804737) (xy 129.164842 -227.805234)
			(xy 129.153158 -227.80498) (xy 129.138934 -227.804472) (xy 129.11455 -227.817934) (xy 128.967992 -228.070664)
			(xy 128.9685 -228.09835) (xy 128.975866 -228.110542) (xy 128.987598 -228.130229) (xy 129.006114 -228.172151)
			(xy 129.018662 -228.216229) (xy 129.025002 -228.261618) (xy 129.025396 -228.284532) (xy 129.024884 -228.310517)
			(xy 129.016749 -228.361847) (xy 129.000685 -228.411273) (xy 128.977088 -228.457577) (xy 128.946537 -228.49962)
			(xy 128.909786 -228.536366) (xy 128.867739 -228.566911) (xy 128.821432 -228.590502) (xy 128.772004 -228.60656)
			(xy 128.720673 -228.614688) (xy 128.694688 -228.61524) (xy 128.668889 -228.614743) (xy 128.617919 -228.606724)
			(xy 128.568814 -228.590882) (xy 128.522767 -228.567603) (xy 128.480897 -228.537451) (xy 128.44422 -228.501159)
			(xy 128.413628 -228.459609) (xy 128.401318 -228.436932) (xy 128.394714 -228.424232) (xy 128.370584 -228.4095)
			(xy 128.078738 -228.4095) (xy 128.054608 -228.424232) (xy 128.048004 -228.436932) (xy 128.035686 -228.459606)
			(xy 128.0051 -228.501163) (xy 127.968427 -228.537461) (xy 127.926559 -228.567619) (xy 127.880512 -228.590902)
			(xy 127.831405 -228.606746) (xy 127.780433 -228.614766) (xy 127.728835 -228.614766) (xy 127.677863 -228.606746)
			(xy 127.628756 -228.590902) (xy 127.582709 -228.567619) (xy 127.540841 -228.537461) (xy 127.504168 -228.501163)
			(xy 127.473582 -228.459606) (xy 127.461264 -228.436932) (xy 127.45466 -228.424232) (xy 127.43053 -228.4095)
			(xy 127.138938 -228.4095) (xy 127.114808 -228.424232) (xy 127.108204 -228.436932) (xy 127.095885 -228.459604)
			(xy 127.065298 -228.501156) (xy 127.028624 -228.537448) (xy 126.986755 -228.567599) (xy 126.940708 -228.590875)
			(xy 126.891602 -228.60671) (xy 126.840632 -228.61472) (xy 126.814834 -228.61524) (xy 126.80315 -228.614986)
			(xy 126.78918 -228.614478) (xy 126.764542 -228.62794) (xy 126.617984 -228.88067) (xy 126.618492 -228.90861)
			(xy 126.625858 -228.920548) (xy 126.63759 -228.940235) (xy 126.656106 -228.982157) (xy 126.668653 -229.026235)
			(xy 126.674992 -229.071624) (xy 126.675388 -229.094538) (xy 126.675015 -229.117153) (xy 126.668842 -229.161961)
			(xy 126.656615 -229.205508) (xy 126.638564 -229.246981) (xy 126.627128 -229.266496) (xy 126.619762 -229.278688)
			(xy 126.619508 -229.30612) (xy 126.766828 -229.560628) (xy 126.791466 -229.57409) (xy 126.805436 -229.573836)
			(xy 126.814834 -229.573582) (xy 126.84082 -229.574094) (xy 126.892152 -229.582229) (xy 126.94158 -229.598294)
			(xy 126.987886 -229.621892) (xy 127.029931 -229.652443) (xy 127.066679 -229.689195) (xy 127.097226 -229.731243)
			(xy 127.120819 -229.777552) (xy 127.136879 -229.826981) (xy 127.145009 -229.878314) (xy 127.145009 -229.930286)
			(xy 127.136879 -229.981619) (xy 127.120819 -230.031048) (xy 127.097226 -230.077357) (xy 127.066679 -230.119405)
			(xy 127.029931 -230.156157) (xy 126.987886 -230.186708) (xy 126.94158 -230.210306) (xy 126.892152 -230.226371)
			(xy 126.84082 -230.234506) (xy 126.814834 -230.234998) (xy 126.803404 -230.234744) (xy 126.78918 -230.234236)
			(xy 126.764796 -230.247698) (xy 126.60376 -230.52532) (xy 126.603506 -230.552244) (xy 126.610364 -230.564182)
			(xy 126.622819 -230.587266) (xy 126.64049 -230.636649) (xy 126.649453 -230.688326) (xy 126.649988 -230.71455)
			(xy 126.649446 -230.740432) (xy 126.640722 -230.791454) (xy 126.623516 -230.840274) (xy 126.61138 -230.86314)
			(xy 126.604776 -230.874824) (xy 126.60503 -230.901494) (xy 126.766828 -231.18064) (xy 126.791466 -231.194102)
			(xy 126.805436 -231.193848) (xy 126.814834 -231.193594) (xy 126.840819 -231.194106) (xy 126.892149 -231.202241)
			(xy 126.941575 -231.218305) (xy 126.98788 -231.241902) (xy 127.029923 -231.272452) (xy 127.06667 -231.309203)
			(xy 127.097216 -231.351249) (xy 127.120808 -231.397556) (xy 127.136867 -231.446984) (xy 127.144997 -231.498315)
			(xy 127.144997 -231.550285) (xy 127.136867 -231.601616) (xy 127.120808 -231.651044) (xy 127.097216 -231.697351)
			(xy 127.06667 -231.739397) (xy 127.029923 -231.776148) (xy 126.98788 -231.806698) (xy 126.941575 -231.830295)
			(xy 126.892149 -231.846359) (xy 126.840819 -231.854494) (xy 126.814834 -231.85501) (xy 126.803404 -231.854756)
			(xy 126.78918 -231.854248) (xy 126.764796 -231.86771) (xy 126.618238 -232.12044) (xy 126.618492 -232.14838)
			(xy 126.626112 -232.160572) (xy 126.637786 -232.180244) (xy 126.656201 -232.222118) (xy 126.668676 -232.266128)
			(xy 126.674973 -232.311436) (xy 126.675388 -232.334308) (xy 126.675035 -232.356956) (xy 126.668885 -232.401833)
			(xy 126.65666 -232.445448) (xy 126.63859 -232.486983) (xy 126.627128 -232.50652) (xy 126.619762 -232.518458)
			(xy 126.619254 -232.546144) (xy 126.767082 -232.800652) (xy 126.791466 -232.814114) (xy 126.805436 -232.81386)
			(xy 126.814834 -232.813606) (xy 126.840819 -232.814118) (xy 126.892149 -232.822253) (xy 126.941574 -232.838317)
			(xy 126.987877 -232.861915) (xy 127.02992 -232.892466) (xy 127.066666 -232.929217) (xy 127.09721 -232.971264)
			(xy 127.120801 -233.017571) (xy 127.136858 -233.066998) (xy 127.144986 -233.118329) (xy 127.145542 -233.144314)
			(xy 127.145167 -233.167002) (xy 127.138966 -233.211953) (xy 127.126681 -233.255635) (xy 127.108544 -233.297228)
			(xy 127.097028 -233.31678) (xy 127.089916 -233.328718) (xy 127.089408 -233.356658) (xy 127.236728 -233.610658)
			(xy 127.261112 -233.62412) (xy 127.275336 -233.623866) (xy 127.284734 -233.623612) (xy 127.310718 -233.624124)
			(xy 127.362045 -233.632258) (xy 127.411468 -233.648321) (xy 127.45777 -233.671918) (xy 127.499811 -233.702466)
			(xy 127.536556 -233.739215) (xy 127.5671 -233.781259) (xy 127.590692 -233.827563) (xy 127.60675 -233.876988)
			(xy 127.614879 -233.928316) (xy 127.614879 -233.980284) (xy 127.60675 -234.031612) (xy 127.590692 -234.081037)
			(xy 127.5671 -234.127341) (xy 127.536556 -234.169385) (xy 127.499811 -234.206134) (xy 127.45777 -234.236682)
			(xy 127.411468 -234.260279) (xy 127.362045 -234.276342) (xy 127.310718 -234.284476) (xy 127.284734 -234.285028)
			(xy 127.273304 -234.284774) (xy 127.25908 -234.284266) (xy 127.234696 -234.297728) (xy 127.088138 -234.550204)
			(xy 127.088646 -234.578144) (xy 127.096012 -234.590336) (xy 127.107743 -234.610024) (xy 127.126257 -234.651946)
			(xy 127.138804 -234.696024) (xy 127.145143 -234.741412) (xy 127.145542 -234.764326) (xy 127.145031 -234.790313)
			(xy 127.136897 -234.841646) (xy 127.120834 -234.891075) (xy 127.097237 -234.937384) (xy 127.066688 -234.979431)
			(xy 127.029937 -235.016183) (xy 126.987891 -235.046733) (xy 126.941583 -235.070331) (xy 126.892154 -235.086395)
			(xy 126.840821 -235.09453) (xy 126.814834 -235.095034) (xy 126.803404 -235.09478) (xy 126.78918 -235.094272)
			(xy 126.764796 -235.107734) (xy 126.618238 -235.360464) (xy 126.618492 -235.388404) (xy 126.626112 -235.400596)
			(xy 126.637791 -235.420267) (xy 126.656216 -235.462139) (xy 126.6687 -235.506149) (xy 126.675008 -235.551459)
			(xy 126.675388 -235.574332) (xy 126.675033 -235.59698) (xy 126.66888 -235.641855) (xy 126.656653 -235.685468)
			(xy 126.63858 -235.727002) (xy 126.627128 -235.746544) (xy 126.619762 -235.758482) (xy 126.619254 -235.786168)
			(xy 126.766828 -236.040676) (xy 126.791466 -236.054138) (xy 126.805436 -236.053884) (xy 126.814834 -236.05363)
			(xy 126.840816 -236.054142) (xy 126.892141 -236.062276) (xy 126.941561 -236.078338) (xy 126.98786 -236.101933)
			(xy 127.029899 -236.13248) (xy 127.066642 -236.169227) (xy 127.097184 -236.211269) (xy 127.120775 -236.25757)
			(xy 127.136832 -236.306992) (xy 127.14496 -236.358318) (xy 127.14496 -236.410282) (xy 127.136832 -236.461608)
			(xy 127.120775 -236.51103) (xy 127.097184 -236.557331) (xy 127.066642 -236.599373) (xy 127.029899 -236.63612)
			(xy 126.98786 -236.666667) (xy 126.941561 -236.690262) (xy 126.892141 -236.706324) (xy 126.840816 -236.714458)
			(xy 126.814834 -236.715046) (xy 126.80315 -236.714792) (xy 126.78918 -236.714284) (xy 126.764796 -236.727746)
			(xy 126.617984 -236.980476) (xy 126.618492 -237.008416) (xy 126.625858 -237.020354) (xy 126.63759 -237.040041)
			(xy 126.656105 -237.081963) (xy 126.668651 -237.126041) (xy 126.674989 -237.17143) (xy 126.675388 -237.194344)
			(xy 126.674875 -237.220328) (xy 126.666739 -237.271656) (xy 126.650674 -237.32108) (xy 126.627075 -237.367382)
			(xy 126.596524 -237.409422) (xy 126.559773 -237.446166) (xy 126.517727 -237.476709) (xy 126.471421 -237.500298)
			(xy 126.421994 -237.516354) (xy 126.370664 -237.52448) (xy 126.34468 -237.525052) (xy 126.33325 -237.524798)
			(xy 126.319026 -237.52429) (xy 126.294642 -237.537752) (xy 126.148084 -237.790482) (xy 126.148592 -237.818422)
			(xy 126.155958 -237.83036) (xy 126.16769 -237.850047) (xy 126.186204 -237.89197) (xy 126.198749 -237.936048)
			(xy 126.205086 -237.981436) (xy 126.205488 -238.00435) (xy 126.205488 -238.012986) (xy 126.20498 -238.026956)
			(xy 126.218696 -238.05134) (xy 127.07112 -238.540798) (xy 127.09906 -238.54029) (xy 127.110998 -238.532924)
			(xy 127.130669 -238.521245) (xy 127.172541 -238.502818) (xy 127.216551 -238.490332) (xy 127.261861 -238.484024)
			(xy 127.284734 -238.483648) (xy 127.310723 -238.48416) (xy 127.36206 -238.492296) (xy 127.411493 -238.508362)
			(xy 127.457804 -238.531963) (xy 127.499853 -238.562517) (xy 127.536605 -238.599273) (xy 127.567155 -238.641325)
			(xy 127.590751 -238.687639) (xy 127.606812 -238.737073) (xy 127.614942 -238.788411) (xy 127.614942 -238.840389)
			(xy 127.606812 -238.891727) (xy 127.590751 -238.941161) (xy 127.567155 -238.987475) (xy 127.536605 -239.029527)
			(xy 127.499853 -239.066283) (xy 127.457804 -239.096837) (xy 127.411493 -239.120438) (xy 127.36206 -239.136504)
			(xy 127.310723 -239.14464) (xy 127.284734 -239.145064) (xy 127.273304 -239.14481) (xy 127.25908 -239.144302)
			(xy 127.234696 -239.157764) (xy 127.088138 -239.410494) (xy 127.088646 -239.43818) (xy 127.096012 -239.450372)
			(xy 127.107741 -239.47006) (xy 127.12625 -239.511983) (xy 127.138793 -239.556061) (xy 127.145127 -239.601448)
			(xy 127.145542 -239.624362) (xy 127.145062 -239.650354) (xy 127.136935 -239.701699) (xy 127.120877 -239.751141)
			(xy 127.097282 -239.797462) (xy 127.066731 -239.839522) (xy 127.029976 -239.876284) (xy 126.987924 -239.906844)
			(xy 126.941608 -239.930449) (xy 126.892169 -239.946519) (xy 126.840826 -239.954656) (xy 126.814834 -239.95507)
			(xy 126.803404 -239.954816) (xy 126.78918 -239.954308) (xy 126.764796 -239.96777) (xy 126.618238 -240.2205)
			(xy 126.618492 -240.24844) (xy 126.626112 -240.260632) (xy 126.637788 -240.280304) (xy 126.656208 -240.322176)
			(xy 126.668688 -240.366186) (xy 126.674991 -240.411495) (xy 126.675388 -240.434368) (xy 126.675038 -240.457017)
			(xy 126.668893 -240.501896) (xy 126.656672 -240.545513) (xy 126.638606 -240.587052) (xy 126.627128 -240.60658)
			(xy 126.619762 -240.618518) (xy 126.619254 -240.646204) (xy 126.767082 -240.900712) (xy 126.791466 -240.914174)
			(xy 126.805436 -240.91392) (xy 126.814834 -240.913666) (xy 126.84082 -240.914178) (xy 126.892152 -240.922313)
			(xy 126.94158 -240.938376) (xy 126.987886 -240.961974) (xy 127.029932 -240.992523) (xy 127.066682 -241.029274)
			(xy 127.097231 -241.07132) (xy 127.120827 -241.117628) (xy 127.136889 -241.167056) (xy 127.145023 -241.218388)
			(xy 127.145542 -241.244374) (xy 127.145163 -241.267061) (xy 127.138954 -241.312008) (xy 127.126663 -241.355686)
			(xy 127.10852 -241.397275) (xy 127.097028 -241.41684) (xy 127.089916 -241.428778) (xy 127.089408 -241.456718)
			(xy 127.236728 -241.710718) (xy 127.261112 -241.72418) (xy 127.275336 -241.723926) (xy 127.284734 -241.723672)
			(xy 127.310721 -241.724184) (xy 127.362054 -241.732319) (xy 127.411483 -241.748384) (xy 127.457791 -241.771983)
			(xy 127.499837 -241.802536) (xy 127.536586 -241.839289) (xy 127.567134 -241.881338) (xy 127.590729 -241.927648)
			(xy 127.606789 -241.977079) (xy 127.614919 -242.028413) (xy 127.614919 -242.080387) (xy 127.606789 -242.131721)
			(xy 127.590729 -242.181152) (xy 127.567134 -242.227462) (xy 127.536586 -242.269511) (xy 127.499837 -242.306264)
			(xy 127.457791 -242.336817) (xy 127.411483 -242.360416) (xy 127.362054 -242.376481) (xy 127.310721 -242.384616)
			(xy 127.284734 -242.385088) (xy 127.273304 -242.384834) (xy 127.25908 -242.384326) (xy 127.234696 -242.397788)
			(xy 127.088138 -242.650264) (xy 127.088646 -242.678204) (xy 127.096012 -242.690396) (xy 127.107746 -242.710083)
			(xy 127.126265 -242.752005) (xy 127.138817 -242.796082) (xy 127.145162 -242.841471) (xy 127.145542 -242.864386)
			(xy 127.145034 -242.890375) (xy 127.136905 -242.941713) (xy 127.120846 -242.991148) (xy 127.097251 -243.037462)
			(xy 127.066702 -243.079514) (xy 127.029951 -243.116271) (xy 126.987903 -243.146826) (xy 126.941592 -243.170427)
			(xy 126.89216 -243.186494) (xy 126.840823 -243.19463) (xy 126.814834 -243.195094) (xy 126.803404 -243.19484)
			(xy 126.78918 -243.194332) (xy 126.764796 -243.207794) (xy 126.618238 -243.460524) (xy 126.618492 -243.488464)
			(xy 126.626112 -243.500656) (xy 126.637787 -243.520328) (xy 126.656204 -243.562201) (xy 126.668681 -243.606211)
			(xy 126.67498 -243.65152) (xy 126.675388 -243.674392) (xy 126.675036 -243.697041) (xy 126.668888 -243.741918)
			(xy 126.656665 -243.785534) (xy 126.638596 -243.827071) (xy 126.627128 -243.846604) (xy 126.619762 -243.858542)
			(xy 126.619254 -243.886228) (xy 126.767082 -244.140736) (xy 126.791466 -244.154198) (xy 126.805436 -244.153944)
			(xy 126.814834 -244.15369) (xy 126.840819 -244.154202) (xy 126.89215 -244.162337) (xy 126.941576 -244.178401)
			(xy 126.987881 -244.201998) (xy 127.029925 -244.232549) (xy 127.066672 -244.2693) (xy 127.097218 -244.311346)
			(xy 127.120811 -244.357653) (xy 127.136871 -244.407081) (xy 127.145 -244.458412) (xy 127.145542 -244.484398)
			(xy 127.145168 -244.507086) (xy 127.138969 -244.552038) (xy 127.126686 -244.595721) (xy 127.10855 -244.637316)
			(xy 127.097028 -244.656864) (xy 127.089916 -244.668802) (xy 127.089408 -244.696742) (xy 127.236728 -244.950742)
			(xy 127.261112 -244.964204) (xy 127.275336 -244.96395) (xy 127.284734 -244.963696) (xy 127.310719 -244.964208)
			(xy 127.362049 -244.972343) (xy 127.411474 -244.988407) (xy 127.457778 -245.012004) (xy 127.499822 -245.042554)
			(xy 127.536568 -245.079304) (xy 127.567114 -245.121351) (xy 127.590706 -245.167657) (xy 127.606765 -245.217084)
			(xy 127.614895 -245.268415) (xy 127.614895 -245.320385) (xy 127.606765 -245.371716) (xy 127.590706 -245.421143)
			(xy 127.567114 -245.467449) (xy 127.536568 -245.509496) (xy 127.499822 -245.546246) (xy 127.457778 -245.576796)
			(xy 127.411474 -245.600393) (xy 127.362049 -245.616457) (xy 127.310719 -245.624592) (xy 127.284734 -245.625112)
			(xy 127.273304 -245.624858) (xy 127.25908 -245.62435) (xy 127.234696 -245.637812) (xy 127.088138 -245.890288)
			(xy 127.088646 -245.918228) (xy 127.096012 -245.93042) (xy 127.107744 -245.950107) (xy 127.12626 -245.992029)
			(xy 127.138809 -246.036107) (xy 127.145151 -246.081495) (xy 127.145542 -246.10441) (xy 127.145032 -246.130398)
			(xy 127.1369 -246.181733) (xy 127.120839 -246.231164) (xy 127.097243 -246.277475) (xy 127.066694 -246.319524)
			(xy 127.029943 -246.356278) (xy 126.987895 -246.38683) (xy 126.941587 -246.41043) (xy 126.892156 -246.426495)
			(xy 126.840822 -246.43463) (xy 126.814834 -246.435118) (xy 126.803404 -246.434864) (xy 126.78918 -246.434356)
			(xy 126.764796 -246.447818) (xy 126.618238 -246.700548) (xy 126.618492 -246.728488) (xy 126.626112 -246.74068)
			(xy 126.637792 -246.760351) (xy 126.656219 -246.802223) (xy 126.668706 -246.846233) (xy 126.675015 -246.891543)
			(xy 126.675388 -246.914416) (xy 126.675035 -246.937064) (xy 126.668883 -246.98194) (xy 126.656658 -247.025554)
			(xy 126.638587 -247.067089) (xy 126.627128 -247.086628) (xy 126.619762 -247.098566) (xy 126.619254 -247.126252)
			(xy 126.767082 -247.38076) (xy 126.791466 -247.394222) (xy 126.805436 -247.393968) (xy 126.814834 -247.393714)
			(xy 126.840819 -247.394226) (xy 126.892148 -247.402361) (xy 126.941572 -247.418425) (xy 126.987876 -247.442023)
			(xy 127.029917 -247.472574) (xy 127.066662 -247.509325) (xy 127.097206 -247.551372) (xy 127.120796 -247.597679)
			(xy 127.136852 -247.647107) (xy 127.144978 -247.698437) (xy 127.145542 -247.724422) (xy 127.145167 -247.74711)
			(xy 127.138964 -247.79206) (xy 127.126679 -247.835741) (xy 127.108541 -247.877335) (xy 127.097028 -247.896888)
			(xy 127.089916 -247.908826) (xy 127.089408 -247.936766) (xy 127.236728 -248.190766) (xy 127.261112 -248.204228)
			(xy 127.275336 -248.203974) (xy 127.284734 -248.20372) (xy 127.310717 -248.204232) (xy 127.362043 -248.212366)
			(xy 127.411465 -248.228429) (xy 127.457766 -248.252024) (xy 127.499806 -248.282572) (xy 127.53655 -248.31932)
			(xy 127.567093 -248.361363) (xy 127.590684 -248.407666) (xy 127.606742 -248.45709) (xy 127.614871 -248.508417)
			(xy 127.614871 -248.560383) (xy 127.606742 -248.61171) (xy 127.590684 -248.661134) (xy 127.567093 -248.707437)
			(xy 127.53655 -248.74948) (xy 127.499806 -248.786228) (xy 127.457766 -248.816776) (xy 127.411465 -248.840371)
			(xy 127.362043 -248.856434) (xy 127.310717 -248.864568) (xy 127.284734 -248.865136) (xy 127.273304 -248.864882)
			(xy 127.25908 -248.864374) (xy 127.234696 -248.877836) (xy 127.088138 -249.130312) (xy 127.088646 -249.158252)
			(xy 127.096012 -249.170444) (xy 127.107743 -249.190132) (xy 127.126256 -249.232054) (xy 127.138802 -249.276132)
			(xy 127.14514 -249.32152) (xy 127.145542 -249.344434) (xy 127.14503 -249.37042) (xy 127.136895 -249.421753)
			(xy 127.120832 -249.471181) (xy 127.097235 -249.517488) (xy 127.066685 -249.559535) (xy 127.029935 -249.596285)
			(xy 126.987888 -249.626835) (xy 126.941581 -249.650432) (xy 126.892153 -249.666495) (xy 126.84082 -249.67463)
			(xy 126.814834 -249.675142) (xy 126.803404 -249.674888) (xy 126.78918 -249.67438) (xy 126.764796 -249.687842)
			(xy 126.618238 -249.940572) (xy 126.618492 -249.968512) (xy 126.625858 -249.98045) (xy 126.63759 -250.000137)
			(xy 126.656105 -250.042059) (xy 126.668653 -250.086137) (xy 126.674991 -250.131526) (xy 126.675388 -250.15444)
			(xy 126.674875 -250.180425) (xy 126.66674 -250.231753) (xy 126.650675 -250.281177) (xy 126.627077 -250.327479)
			(xy 126.596526 -250.36952) (xy 126.559775 -250.406265) (xy 126.517728 -250.436808) (xy 126.471421 -250.460398)
			(xy 126.421995 -250.476454) (xy 126.370665 -250.48458) (xy 126.34468 -250.485148) (xy 126.321353 -250.484728)
			(xy 126.275165 -250.478141) (xy 126.230357 -250.465141) (xy 126.187815 -250.445987) (xy 126.167896 -250.43384)
			(xy 126.155704 -250.42622) (xy 126.128018 -250.425712) (xy 125.278134 -250.9139) (xy 125.264672 -250.93803)
			(xy 125.26518 -250.952508) (xy 125.265434 -250.964446) (xy 125.264921 -250.990432) (xy 125.256785 -251.041762)
			(xy 125.24072 -251.091188) (xy 125.217122 -251.137493) (xy 125.186572 -251.179537) (xy 125.149822 -251.216285)
			(xy 125.107776 -251.246833) (xy 125.06147 -251.270428) (xy 125.012043 -251.28649) (xy 124.960712 -251.294623)
			(xy 124.934726 -251.295154) (xy 124.923296 -251.2949) (xy 124.909072 -251.294392) (xy 124.884688 -251.307854)
			(xy 124.73813 -251.56033) (xy 124.738384 -251.58827) (xy 124.746004 -251.600462) (xy 124.757734 -251.62015)
			(xy 124.776245 -251.662073) (xy 124.788789 -251.70615) (xy 124.795125 -251.751538) (xy 124.795534 -251.774452)
			(xy 124.795024 -251.800439) (xy 124.786894 -251.851774) (xy 124.770833 -251.901204) (xy 124.747237 -251.947514)
			(xy 124.716687 -251.989562) (xy 124.679936 -252.026313) (xy 124.637888 -252.056863) (xy 124.591578 -252.080459)
			(xy 124.542148 -252.09652) (xy 124.490813 -252.10465) (xy 124.438839 -252.10465) (xy 124.387504 -252.09652)
			(xy 124.338074 -252.080459) (xy 124.291764 -252.056863) (xy 124.249716 -252.026313) (xy 124.212965 -251.989562)
			(xy 124.182415 -251.947514) (xy 124.158819 -251.901204) (xy 124.142758 -251.851774) (xy 124.134628 -251.800439)
			(xy 124.134118 -251.774452) (xy 124.134372 -251.759466) (xy 124.135134 -251.744988) (xy 124.121672 -251.72035)
			(xy 123.274328 -251.233686) (xy 123.246134 -251.234448) (xy 123.233942 -251.242322) (xy 123.213805 -251.254829)
			(xy 123.170711 -251.274575) (xy 123.125238 -251.287965) (xy 123.07832 -251.294723) (xy 123.054618 -251.295154)
			(xy 123.028629 -251.294646) (xy 122.977289 -251.286518) (xy 122.927853 -251.270459) (xy 122.881538 -251.246865)
			(xy 122.839484 -251.216316) (xy 122.802725 -251.179565) (xy 122.772169 -251.137517) (xy 122.748566 -251.091206)
			(xy 122.732497 -251.041773) (xy 122.724359 -250.990435) (xy 122.72391 -250.964446) (xy 122.724325 -250.940859)
			(xy 122.731023 -250.894162) (xy 122.744289 -250.848891) (xy 122.763853 -250.805965) (xy 122.776234 -250.785884)
			(xy 122.784108 -250.773692) (xy 122.78487 -250.745498) (xy 122.640852 -250.49734) (xy 122.61596 -250.483878)
			(xy 122.601482 -250.48464) (xy 122.584718 -250.485148) (xy 122.561392 -250.484724) (xy 122.515208 -250.478129)
			(xy 122.470404 -250.465122) (xy 122.427868 -250.445962) (xy 122.407934 -250.43384) (xy 122.395742 -250.42622)
			(xy 122.367802 -250.425712) (xy 121.518426 -250.913646) (xy 121.50471 -250.938284) (xy 121.505218 -250.952508)
			(xy 121.505472 -250.964446) (xy 121.504959 -250.99043) (xy 121.496822 -251.041757) (xy 121.480757 -251.091179)
			(xy 121.457158 -251.137479) (xy 121.426607 -251.179518) (xy 121.389856 -251.21626) (xy 121.347809 -251.246801)
			(xy 121.301503 -251.270388) (xy 121.252077 -251.286442) (xy 121.200748 -251.294565) (xy 121.174764 -251.295154)
			(xy 121.163334 -251.2949) (xy 121.14911 -251.294392) (xy 121.124726 -251.307854) (xy 120.977914 -251.560584)
			(xy 120.978422 -251.588524) (xy 120.985788 -251.600462) (xy 120.997518 -251.62015) (xy 121.01603 -251.662072)
			(xy 121.028575 -251.70615) (xy 121.034911 -251.751538) (xy 121.035318 -251.774452) (xy 121.034808 -251.800439)
			(xy 121.026678 -251.851774) (xy 121.010617 -251.901204) (xy 120.987021 -251.947514) (xy 120.956471 -251.989562)
			(xy 120.91972 -252.026313) (xy 120.877672 -252.056863) (xy 120.831362 -252.080459) (xy 120.781932 -252.09652)
			(xy 120.730597 -252.10465) (xy 120.678623 -252.10465) (xy 120.627288 -252.09652) (xy 120.577858 -252.080459)
			(xy 120.531548 -252.056863) (xy 120.4895 -252.026313) (xy 120.452749 -251.989562) (xy 120.422199 -251.947514)
			(xy 120.398603 -251.901204) (xy 120.382542 -251.851774) (xy 120.374412 -251.800439) (xy 120.373902 -251.774452)
			(xy 120.374156 -251.759212) (xy 120.374918 -251.744988) (xy 120.361456 -251.720096) (xy 119.514366 -251.233686)
			(xy 119.486172 -251.234448) (xy 119.47398 -251.242322) (xy 119.453844 -251.254831) (xy 119.41075 -251.274583)
			(xy 119.365278 -251.287977) (xy 119.318358 -251.294741) (xy 119.294656 -251.295154) (xy 119.26867 -251.294641)
			(xy 119.217338 -251.286505) (xy 119.16791 -251.270441) (xy 119.121604 -251.246844) (xy 119.079558 -251.216294)
			(xy 119.042807 -251.179544) (xy 119.012257 -251.137498) (xy 118.98866 -251.091192) (xy 118.972595 -251.041764)
			(xy 118.964459 -250.990432) (xy 118.963948 -250.964446) (xy 118.964363 -250.940858) (xy 118.97106 -250.894161)
			(xy 118.984323 -250.848889) (xy 119.003885 -250.805961) (xy 119.016272 -250.785884) (xy 119.024146 -250.773692)
			(xy 119.024654 -250.745498) (xy 118.880636 -250.49734) (xy 118.855998 -250.483878) (xy 118.84152 -250.48464)
			(xy 118.824756 -250.485148) (xy 118.801429 -250.484726) (xy 118.755243 -250.478136) (xy 118.710437 -250.465134)
			(xy 118.667897 -250.445977) (xy 118.647972 -250.43384) (xy 118.636034 -250.42622) (xy 118.607586 -250.425712)
			(xy 117.758464 -250.913646) (xy 117.744748 -250.938284) (xy 117.745256 -250.952254) (xy 117.74551 -250.964446)
			(xy 117.744997 -250.990431) (xy 117.736861 -251.04176) (xy 117.720796 -251.091184) (xy 117.697197 -251.137488)
			(xy 117.666647 -251.17953) (xy 117.629896 -251.216276) (xy 117.58785 -251.246821) (xy 117.541544 -251.270413)
			(xy 117.492117 -251.286471) (xy 117.440787 -251.2946) (xy 117.414802 -251.295154) (xy 117.403372 -251.2949)
			(xy 117.389148 -251.294392) (xy 117.364764 -251.307854) (xy 117.217952 -251.560584) (xy 117.21846 -251.588524)
			(xy 117.225826 -251.600462) (xy 117.237555 -251.62015) (xy 117.256065 -251.662073) (xy 117.268608 -251.706151)
			(xy 117.274944 -251.751538) (xy 117.275356 -251.774452) (xy 117.274846 -251.800439) (xy 117.266716 -251.851774)
			(xy 117.250655 -251.901204) (xy 117.227059 -251.947514) (xy 117.196509 -251.989562) (xy 117.159758 -252.026313)
			(xy 117.11771 -252.056863) (xy 117.0714 -252.080459) (xy 117.02197 -252.09652) (xy 116.970635 -252.10465)
			(xy 116.918661 -252.10465) (xy 116.867326 -252.09652) (xy 116.817896 -252.080459) (xy 116.771586 -252.056863)
			(xy 116.729538 -252.026313) (xy 116.692787 -251.989562) (xy 116.662237 -251.947514) (xy 116.638641 -251.901204)
			(xy 116.62258 -251.851774) (xy 116.61445 -251.800439) (xy 116.61394 -251.774452) (xy 116.614194 -251.759212)
			(xy 116.614956 -251.744988) (xy 116.601494 -251.720096) (xy 115.754404 -251.233686) (xy 115.72621 -251.234448)
			(xy 115.714018 -251.242322) (xy 115.693882 -251.254834) (xy 115.650789 -251.27459) (xy 115.605317 -251.28799)
			(xy 115.558397 -251.294759) (xy 115.534694 -251.295154) (xy 115.508706 -251.294644) (xy 115.457369 -251.286513)
			(xy 115.407937 -251.270452) (xy 115.361625 -251.246857) (xy 115.319574 -251.216308) (xy 115.282818 -251.179557)
			(xy 115.252264 -251.137509) (xy 115.228663 -251.0912) (xy 115.212596 -251.04177) (xy 115.204459 -250.990434)
			(xy 115.203986 -250.964446) (xy 115.204401 -250.940859) (xy 115.211098 -250.894162) (xy 115.224363 -250.84889)
			(xy 115.243926 -250.805963) (xy 115.25631 -250.785884) (xy 115.264184 -250.773692) (xy 115.264692 -250.745498)
			(xy 115.120674 -250.49734) (xy 115.096036 -250.483878) (xy 115.081558 -250.48464) (xy 115.064794 -250.485148)
			(xy 115.041469 -250.484722) (xy 114.995286 -250.478124) (xy 114.950484 -250.465115) (xy 114.907949 -250.445952)
			(xy 114.88801 -250.43384) (xy 114.876072 -250.42622) (xy 114.847624 -250.425712) (xy 113.998248 -250.9139)
			(xy 113.984786 -250.93803) (xy 113.985294 -250.952508) (xy 113.985548 -250.964446) (xy 113.985035 -250.990432)
			(xy 113.976899 -251.041763) (xy 113.960834 -251.09119) (xy 113.937237 -251.137496) (xy 113.906687 -251.179541)
			(xy 113.869937 -251.216291) (xy 113.827891 -251.24684) (xy 113.781585 -251.270437) (xy 113.732157 -251.2865)
			(xy 113.680826 -251.294636) (xy 113.65484 -251.295154) (xy 113.629052 -251.294663) (xy 113.578101 -251.286664)
			(xy 113.529009 -251.270853) (xy 113.482966 -251.247614) (xy 113.441089 -251.217509) (xy 113.404391 -251.181269)
			(xy 113.373764 -251.139773) (xy 113.36147 -251.1171) (xy 113.354866 -251.1044) (xy 113.330736 -251.089668)
			(xy 110.817406 -251.089668) (xy 110.810759 -251.089489) (xy 110.797891 -251.086157) (xy 110.792006 -251.083064)
			(xy 109.648244 -250.425712) (xy 109.619796 -250.42622) (xy 109.607858 -250.43384) (xy 109.58794 -250.445994)
			(xy 109.545409 -250.465183) (xy 109.500599 -250.478191) (xy 109.454404 -250.484758) (xy 109.431074 -250.485148)
			(xy 109.41431 -250.48464) (xy 109.399832 -250.483878) (xy 109.375194 -250.49734) (xy 109.231176 -250.745498)
			(xy 109.231684 -250.773692) (xy 109.239558 -250.785884) (xy 109.251928 -250.805969) (xy 109.271477 -250.848899)
			(xy 109.284736 -250.894168) (xy 109.291437 -250.940861) (xy 109.291882 -250.964446) (xy 109.291369 -250.99043)
			(xy 109.283233 -251.041757) (xy 109.267167 -251.09118) (xy 109.243568 -251.137481) (xy 109.213017 -251.179521)
			(xy 109.176266 -251.216264) (xy 109.13422 -251.246806) (xy 109.087914 -251.270395) (xy 109.038487 -251.286449)
			(xy 108.987158 -251.294575) (xy 108.961174 -251.295154) (xy 108.937472 -251.294745) (xy 108.890555 -251.287974)
			(xy 108.845084 -251.274575) (xy 108.801993 -251.254821) (xy 108.78185 -251.242322) (xy 108.769658 -251.234448)
			(xy 108.741464 -251.233686) (xy 107.89412 -251.72035) (xy 107.880658 -251.744988) (xy 107.88142 -251.759466)
			(xy 107.881674 -251.774452) (xy 107.881164 -251.800439) (xy 107.873034 -251.851774) (xy 107.856973 -251.901204)
			(xy 107.833377 -251.947514) (xy 107.802827 -251.989562) (xy 107.766076 -252.026313) (xy 107.724028 -252.056863)
			(xy 107.677718 -252.080459) (xy 107.628288 -252.09652) (xy 107.576953 -252.10465) (xy 107.524979 -252.10465)
			(xy 107.473644 -252.09652) (xy 107.424214 -252.080459) (xy 107.377904 -252.056863) (xy 107.335856 -252.026313)
			(xy 107.299105 -251.989562) (xy 107.268555 -251.947514) (xy 107.244959 -251.901204) (xy 107.228898 -251.851774)
			(xy 107.220768 -251.800439) (xy 107.220258 -251.774452) (xy 107.220628 -251.751504) (xy 107.226939 -251.706046)
			(xy 107.239486 -251.6619) (xy 107.25803 -251.619918) (xy 107.269788 -251.600208) (xy 107.277408 -251.58827)
			(xy 107.277662 -251.56033) (xy 107.131104 -251.307854) (xy 107.10672 -251.294392) (xy 107.092496 -251.2949)
			(xy 107.081066 -251.295154) (xy 107.057364 -251.294745) (xy 107.010447 -251.287973) (xy 106.964978 -251.274572)
			(xy 106.921887 -251.254817) (xy 106.901742 -251.242322) (xy 106.88955 -251.234448) (xy 106.861356 -251.233686)
			(xy 106.014266 -251.720096) (xy 106.000804 -251.744988) (xy 106.001566 -251.759466) (xy 106.00182 -251.774452)
			(xy 106.00131 -251.800439) (xy 105.99318 -251.851774) (xy 105.977119 -251.901204) (xy 105.953523 -251.947514)
			(xy 105.922973 -251.989562) (xy 105.886222 -252.026313) (xy 105.844174 -252.056863) (xy 105.797864 -252.080459)
			(xy 105.748434 -252.09652) (xy 105.697099 -252.10465) (xy 105.645125 -252.10465) (xy 105.59379 -252.09652)
			(xy 105.54436 -252.080459) (xy 105.49805 -252.056863) (xy 105.456002 -252.026313) (xy 105.419251 -251.989562)
			(xy 105.388701 -251.947514) (xy 105.365105 -251.901204) (xy 105.349044 -251.851774) (xy 105.340914 -251.800439)
			(xy 105.340404 -251.774452) (xy 105.340792 -251.751536) (xy 105.347121 -251.706144) (xy 105.359665 -251.662063)
			(xy 105.378184 -251.620139) (xy 105.389934 -251.600462) (xy 105.3973 -251.588524) (xy 105.397808 -251.560584)
			(xy 105.250996 -251.307854) (xy 105.226612 -251.294392) (xy 105.212388 -251.2949) (xy 105.200958 -251.295154)
			(xy 105.177257 -251.294744) (xy 105.13034 -251.287971) (xy 105.084871 -251.27457) (xy 105.041781 -251.254814)
			(xy 105.021634 -251.242322) (xy 105.009442 -251.234448) (xy 104.981248 -251.233686) (xy 104.134158 -251.72035)
			(xy 104.120696 -251.744988) (xy 104.121458 -251.759466) (xy 104.121712 -251.774452) (xy 104.121202 -251.800439)
			(xy 104.113072 -251.851774) (xy 104.097011 -251.901204) (xy 104.073415 -251.947514) (xy 104.042865 -251.989562)
			(xy 104.006114 -252.026313) (xy 103.964066 -252.056863) (xy 103.917756 -252.080459) (xy 103.868326 -252.09652)
			(xy 103.816991 -252.10465) (xy 103.765017 -252.10465) (xy 103.713682 -252.09652) (xy 103.664252 -252.080459)
			(xy 103.617942 -252.056863) (xy 103.575894 -252.026313) (xy 103.539143 -251.989562) (xy 103.508593 -251.947514)
			(xy 103.484997 -251.901204) (xy 103.468936 -251.851774) (xy 103.460806 -251.800439) (xy 103.460296 -251.774452)
			(xy 103.460684 -251.751536) (xy 103.467013 -251.706144) (xy 103.479557 -251.662063) (xy 103.498075 -251.620139)
			(xy 103.509826 -251.600462) (xy 103.517446 -251.58827) (xy 103.5177 -251.56033) (xy 103.371142 -251.307854)
			(xy 103.346758 -251.294392) (xy 103.332534 -251.2949) (xy 103.321104 -251.295154) (xy 103.297371 -251.29476)
			(xy 103.250388 -251.288003) (xy 103.204853 -251.274601) (xy 103.161703 -251.254826) (xy 103.141526 -251.242322)
			(xy 103.129334 -251.234448) (xy 103.101394 -251.233686) (xy 102.254304 -251.720096) (xy 102.240842 -251.744988)
			(xy 102.241604 -251.759212) (xy 102.241858 -251.774452) (xy 102.241378 -251.800442) (xy 102.233253 -251.851784)
			(xy 102.217194 -251.901221) (xy 102.193598 -251.947538) (xy 102.163046 -251.989592) (xy 102.12629 -252.026347)
			(xy 102.084236 -252.056899) (xy 102.03792 -252.080495) (xy 101.988482 -252.096553) (xy 101.93714 -252.104679)
			(xy 101.91115 -252.10516) (xy 101.894132 -252.104652) (xy 101.879654 -252.10389) (xy 101.855016 -252.117352)
			(xy 101.710998 -252.365764) (xy 101.711506 -252.393704) (xy 101.71938 -252.405896) (xy 101.731755 -252.42598)
			(xy 101.751314 -252.468909) (xy 101.764584 -252.514177) (xy 101.771297 -252.560871) (xy 101.771704 -252.584458)
			(xy 101.771224 -252.610449) (xy 101.763098 -252.661793) (xy 101.747039 -252.711233) (xy 101.723444 -252.757551)
			(xy 101.692892 -252.799608) (xy 101.656137 -252.836368) (xy 101.614084 -252.866924) (xy 101.567768 -252.890525)
			(xy 101.51833 -252.906589) (xy 101.466987 -252.914721) (xy 101.440996 -252.915166) (xy 101.417294 -252.914759)
			(xy 101.370375 -252.907991) (xy 101.324903 -252.894594) (xy 101.281809 -252.874843) (xy 101.261672 -252.862334)
			(xy 101.24948 -252.85446) (xy 101.221286 -252.853698) (xy 100.374196 -253.340362) (xy 100.360734 -253.365)
			(xy 100.361496 -253.379478) (xy 100.36175 -253.394464) (xy 100.361496 -253.406148) (xy 100.360988 -253.420372)
			(xy 100.37445 -253.444756) (xy 101.224588 -253.932944) (xy 101.252528 -253.932436) (xy 101.264466 -253.924816)
			(xy 101.284369 -253.912719) (xy 101.326852 -253.893625) (xy 101.371593 -253.880681) (xy 101.417708 -253.874145)
			(xy 101.440996 -253.873762) (xy 101.466988 -253.874245) (xy 101.518332 -253.882376) (xy 101.567771 -253.89844)
			(xy 101.614089 -253.922039) (xy 101.656145 -253.952594) (xy 101.692903 -253.989352) (xy 101.723458 -254.031408)
			(xy 101.747059 -254.077725) (xy 101.763123 -254.127165) (xy 101.771255 -254.178508) (xy 101.771255 -254.230492)
			(xy 101.763123 -254.281835) (xy 101.747059 -254.331275) (xy 101.723458 -254.377592) (xy 101.692903 -254.419648)
			(xy 101.656145 -254.456406) (xy 101.614089 -254.486961) (xy 101.567771 -254.51056) (xy 101.518332 -254.526624)
			(xy 101.466988 -254.534755) (xy 101.440996 -254.535178) (xy 101.417294 -254.534771) (xy 101.370375 -254.528003)
			(xy 101.324902 -254.514607) (xy 101.281808 -254.494856) (xy 101.261672 -254.482346) (xy 101.24948 -254.474472)
			(xy 101.221286 -254.47371) (xy 100.374196 -254.960374) (xy 100.360734 -254.985012) (xy 100.361496 -254.99949)
			(xy 100.36175 -255.014476) (xy 100.361366 -255.037795) (xy 100.354846 -255.083974) (xy 100.341904 -255.128779)
			(xy 100.322796 -255.171322) (xy 100.310696 -255.19126) (xy 100.303076 -255.203198) (xy 100.302314 -255.231392)
			(xy 100.447348 -255.481074) (xy 100.471986 -255.49479) (xy 100.48621 -255.494028) (xy 100.500942 -255.493774)
			(xy 100.526928 -255.494287) (xy 100.578258 -255.502422) (xy 100.627684 -255.518487) (xy 100.673989 -255.542085)
			(xy 100.716033 -255.572635) (xy 100.752781 -255.609385) (xy 100.783328 -255.651431) (xy 100.806922 -255.697738)
			(xy 100.822983 -255.747165) (xy 100.831115 -255.798496) (xy 100.83165 -255.824482) (xy 100.831245 -255.847841)
			(xy 100.824673 -255.894095) (xy 100.811671 -255.938967) (xy 100.792498 -255.981569) (xy 100.780342 -256.00152)
			(xy 100.772468 -256.013712) (xy 100.77196 -256.041906) (xy 100.91674 -256.291334) (xy 100.941378 -256.304796)
			(xy 100.955856 -256.304034) (xy 100.971096 -256.30378) (xy 100.997084 -256.304289) (xy 101.048419 -256.312419)
			(xy 101.097851 -256.32848) (xy 101.144162 -256.352075) (xy 101.186212 -256.382625) (xy 101.222965 -256.419376)
			(xy 101.253516 -256.461424) (xy 101.277114 -256.507734) (xy 101.293177 -256.557165) (xy 101.30131 -256.6085)
			(xy 101.301804 -256.634488) (xy 101.301739 -256.64429) (xy 101.300595 -256.663861) (xy 101.299518 -256.673604)
			(xy 101.29774 -256.687574) (xy 101.309424 -256.713482) (xy 102.625906 -257.618738) (xy 102.655624 -257.619754)
			(xy 102.668324 -257.612388) (xy 102.689639 -257.600344) (xy 102.734769 -257.581364) (xy 102.78201 -257.56851)
			(xy 102.830535 -257.562007) (xy 102.855014 -257.561588) (xy 102.881358 -257.562059) (xy 102.933508 -257.569559)
			(xy 102.98406 -257.584404) (xy 103.031986 -257.606292) (xy 103.076308 -257.634778) (xy 103.116126 -257.669281)
			(xy 103.150628 -257.7091) (xy 103.179113 -257.753423) (xy 103.201 -257.801349) (xy 103.215843 -257.851902)
			(xy 103.223342 -257.904052) (xy 103.223822 -257.930396) (xy 103.22336 -257.956528) (xy 103.215969 -258.008267)
			(xy 103.201347 -258.058445) (xy 103.179788 -258.106055) (xy 103.151724 -258.150146) (xy 103.117716 -258.189833)
			(xy 103.078447 -258.224322) (xy 103.034702 -258.252921) (xy 103.011224 -258.264406) (xy 102.997762 -258.270756)
			(xy 102.982014 -258.295648) (xy 102.982014 -258.465066) (xy 102.997762 -258.489958) (xy 103.011224 -258.496308)
			(xy 103.036271 -258.508566) (xy 103.082669 -258.539497) (xy 103.123878 -258.577063) (xy 103.158959 -258.620409)
			(xy 103.18711 -258.668544) (xy 103.20769 -258.72037) (xy 103.220228 -258.774704) (xy 103.224438 -258.830308)
			(xy 103.220646 -258.880356) (xy 151.51202 -258.880356) (xy 151.51605 -258.738021) (xy 151.528125 -258.596141)
			(xy 151.548208 -258.455173) (xy 151.576235 -258.315566) (xy 151.612115 -258.177768) (xy 151.655733 -258.042221)
			(xy 151.70695 -257.909359) (xy 151.765601 -257.779607) (xy 151.831499 -257.653381) (xy 151.904433 -257.531085)
			(xy 151.98417 -257.413112) (xy 152.070452 -257.299839) (xy 152.163005 -257.191628) (xy 152.261532 -257.088827)
			(xy 152.365717 -256.991765) (xy 152.475226 -256.900753) (xy 152.589709 -256.816081) (xy 152.708799 -256.738023)
			(xy 152.832114 -256.666827) (xy 152.95926 -256.602721) (xy 153.089829 -256.545912) (xy 153.223403 -256.49658)
			(xy 153.359554 -256.454884) (xy 153.497845 -256.420958) (xy 153.637835 -256.39491) (xy 153.779074 -256.376824)
			(xy 153.92111 -256.366757) (xy 154.063488 -256.364742) (xy 154.205752 -256.370785) (xy 154.347446 -256.384867)
			(xy 154.488116 -256.406943) (xy 154.627313 -256.436943) (xy 154.764589 -256.474769) (xy 154.899505 -256.520301)
			(xy 155.031629 -256.573392) (xy 155.160538 -256.633874) (xy 155.285819 -256.701552) (xy 155.40707 -256.776209)
			(xy 155.523903 -256.857607) (xy 155.635944 -256.945484) (xy 155.742834 -257.039559) (xy 155.844231 -257.139531)
			(xy 155.939809 -257.245079) (xy 156.029263 -257.355865) (xy 156.112305 -257.471534) (xy 156.188671 -257.591717)
			(xy 156.258115 -257.716027) (xy 156.320415 -257.844068) (xy 156.375371 -257.975427) (xy 156.422808 -258.109686)
			(xy 156.462572 -258.246413) (xy 156.494538 -258.385171) (xy 156.518603 -258.525515) (xy 156.534689 -258.666996)
			(xy 156.542744 -258.80916) (xy 156.543248 -258.880356) (xy 156.542744 -258.951552) (xy 156.534689 -259.093716)
			(xy 156.518603 -259.235197) (xy 156.494538 -259.375541) (xy 156.462572 -259.514299) (xy 156.422808 -259.651026)
			(xy 156.375371 -259.785285) (xy 156.320415 -259.916644) (xy 156.258115 -260.044685) (xy 156.188671 -260.168995)
			(xy 156.112305 -260.289178) (xy 156.029263 -260.404847) (xy 155.939809 -260.515633) (xy 155.844231 -260.621181)
			(xy 155.742834 -260.721153) (xy 155.635944 -260.815228) (xy 155.523903 -260.903105) (xy 155.40707 -260.984503)
			(xy 155.285819 -261.05916) (xy 155.160538 -261.126838) (xy 155.031629 -261.18732) (xy 154.899505 -261.240411)
			(xy 154.764589 -261.285943) (xy 154.627313 -261.323769) (xy 154.488116 -261.353769) (xy 154.347446 -261.375845)
			(xy 154.205752 -261.389927) (xy 154.063488 -261.39597) (xy 153.92111 -261.393955) (xy 153.779074 -261.383888)
			(xy 153.637835 -261.365802) (xy 153.497845 -261.339754) (xy 153.359554 -261.305828) (xy 153.223403 -261.264132)
			(xy 153.089829 -261.2148) (xy 152.95926 -261.157991) (xy 152.832114 -261.093885) (xy 152.708799 -261.022689)
			(xy 152.589709 -260.944631) (xy 152.475226 -260.859959) (xy 152.365717 -260.768947) (xy 152.261532 -260.671885)
			(xy 152.163005 -260.569084) (xy 152.070452 -260.460873) (xy 151.98417 -260.3476) (xy 151.904433 -260.229627)
			(xy 151.831499 -260.107331) (xy 151.765601 -259.981105) (xy 151.70695 -259.851353) (xy 151.655733 -259.718491)
			(xy 151.612115 -259.582944) (xy 151.576235 -259.445146) (xy 151.548208 -259.305539) (xy 151.528125 -259.164571)
			(xy 151.51605 -259.022691) (xy 151.51202 -258.880356) (xy 103.220646 -258.880356) (xy 103.220225 -258.885911)
			(xy 103.207685 -258.940245) (xy 103.187104 -258.99207) (xy 103.15895 -259.040204) (xy 103.123868 -259.083548)
			(xy 103.082657 -259.121113) (xy 103.036258 -259.152041) (xy 103.011224 -259.164328) (xy 102.997762 -259.170678)
			(xy 102.982014 -259.19557) (xy 102.982014 -259.364988) (xy 102.997762 -259.38988) (xy 103.011224 -259.39623)
			(xy 103.034715 -259.407697) (xy 103.078483 -259.436278) (xy 103.117771 -259.470758) (xy 103.151793 -259.510444)
			(xy 103.179863 -259.554541) (xy 103.201419 -259.602162) (xy 103.216028 -259.652352) (xy 103.223396 -259.704103)
			(xy 103.223822 -259.73024) (xy 103.223349 -259.756583) (xy 103.215847 -259.808731) (xy 103.200999 -259.859281)
			(xy 103.17911 -259.907203) (xy 103.150624 -259.951523) (xy 103.11612 -259.991339) (xy 103.076303 -260.025839)
			(xy 103.031981 -260.054322) (xy 102.984056 -260.076208) (xy 102.933505 -260.091052) (xy 102.881357 -260.098551)
			(xy 102.855014 -260.099048) (xy 102.829742 -260.098638) (xy 102.779673 -260.091737) (xy 102.731018 -260.07805)
			(xy 102.707694 -260.068314) (xy 102.694232 -260.062472) (xy 102.664768 -260.067044) (xy 101.59746 -261.007098)
			(xy 101.589078 -261.034276) (xy 101.59238 -261.047992) (xy 101.596775 -261.067251) (xy 101.601491 -261.106472)
			(xy 101.601778 -261.126224) (xy 101.601373 -261.149853) (xy 101.594633 -261.196629) (xy 101.581296 -261.241967)
			(xy 101.561632 -261.284941) (xy 101.5492 -261.30504) (xy 101.541326 -261.317232) (xy 101.540818 -261.345426)
			(xy 101.684582 -261.59333) (xy 101.70922 -261.606792) (xy 101.723698 -261.60603) (xy 101.74097 -261.605522)
			(xy 101.766958 -261.606003) (xy 101.818296 -261.61413) (xy 101.86773 -261.630188) (xy 101.914043 -261.653782)
			(xy 101.956095 -261.684331) (xy 101.99285 -261.721082) (xy 102.023403 -261.763131) (xy 102.047001 -261.809442)
			(xy 102.063063 -261.858875) (xy 102.071195 -261.910212) (xy 102.071195 -261.962188) (xy 102.063063 -262.013525)
			(xy 102.047001 -262.062958) (xy 102.023403 -262.109269) (xy 101.99285 -262.151318) (xy 101.956095 -262.188069)
			(xy 101.914043 -262.218618) (xy 101.86773 -262.242212) (xy 101.818296 -262.25827) (xy 101.766958 -262.266397)
			(xy 101.74097 -262.266938) (xy 101.72573 -262.266684) (xy 101.711506 -262.265922) (xy 101.686614 -262.279384)
			(xy 101.542088 -262.528812) (xy 101.542596 -262.557006) (xy 101.55047 -262.569198) (xy 101.562638 -262.589144)
			(xy 101.581842 -262.631737) (xy 101.594845 -262.676613) (xy 101.601389 -262.722875) (xy 101.601778 -262.746236)
			(xy 101.601379 -262.769867) (xy 101.594651 -262.816648) (xy 101.581323 -262.861993) (xy 101.561669 -262.904974)
			(xy 101.5492 -262.925052) (xy 101.541326 -262.937244) (xy 101.540818 -262.965438) (xy 101.684582 -263.213342)
			(xy 101.709474 -263.226804) (xy 101.723952 -263.226042) (xy 101.74097 -263.225534) (xy 101.76696 -263.226015)
			(xy 101.818299 -263.234143) (xy 101.867735 -263.250203) (xy 101.91405 -263.2738) (xy 101.956102 -263.304352)
			(xy 101.992856 -263.341108) (xy 102.023407 -263.383161) (xy 102.047002 -263.429476) (xy 102.06306 -263.478912)
			(xy 102.071186 -263.530252) (xy 102.071678 -263.556242) (xy 102.071276 -263.579862) (xy 102.064596 -263.626625)
			(xy 102.051335 -263.671964) (xy 102.031763 -263.714957) (xy 102.019354 -263.735058) (xy 102.01148 -263.74725)
			(xy 102.010718 -263.775444) (xy 102.154736 -264.023348) (xy 102.179374 -264.03681) (xy 102.193852 -264.036048)
			(xy 102.211124 -264.03554) (xy 102.234482 -264.035948) (xy 102.280733 -264.042525) (xy 102.325603 -264.055531)
			(xy 102.368202 -264.074709) (xy 102.388162 -264.086848) (xy 102.4001 -264.094468) (xy 102.428294 -264.094976)
			(xy 103.545894 -263.453372) (xy 103.55072 -263.45007) (xy 105.121202 -262.294624) (xy 105.13187 -262.266938)
			(xy 105.129076 -262.25246) (xy 105.125738 -262.234613) (xy 105.122177 -262.198479) (xy 105.121964 -262.180324)
			(xy 105.122432 -262.153978) (xy 105.129928 -262.101822) (xy 105.144769 -262.051264) (xy 105.166655 -262.003332)
			(xy 105.195139 -261.959003) (xy 105.229642 -261.919179) (xy 105.269461 -261.88467) (xy 105.313787 -261.85618)
			(xy 105.361715 -261.834287) (xy 105.412271 -261.819439) (xy 105.464426 -261.811936) (xy 105.490772 -261.811516)
			(xy 105.522869 -261.812207) (xy 105.586093 -261.823319) (xy 105.616502 -261.833614) (xy 105.630472 -261.838694)
			(xy 105.659174 -261.83209) (xy 106.06786 -261.423404) (xy 106.073702 -261.392924) (xy 106.067352 -261.378192)
			(xy 106.057551 -261.354793) (xy 106.043745 -261.305978) (xy 106.036779 -261.255729) (xy 106.036364 -261.230364)
			(xy 106.036836 -261.204021) (xy 106.044339 -261.151871) (xy 106.059185 -261.10132) (xy 106.081075 -261.053396)
			(xy 106.10956 -261.009075) (xy 106.144063 -260.969258) (xy 106.183881 -260.934756) (xy 106.228203 -260.906271)
			(xy 106.276128 -260.884383) (xy 106.326679 -260.869537) (xy 106.378829 -260.862036) (xy 106.405172 -260.861556)
			(xy 106.433196 -260.862076) (xy 106.488598 -260.870551) (xy 106.542081 -260.887311) (xy 106.592412 -260.911969)
			(xy 106.638433 -260.943958) (xy 106.679085 -260.982542) (xy 106.713431 -261.026832) (xy 106.740681 -261.075808)
			(xy 106.760208 -261.128344) (xy 106.76636 -261.155688) (xy 106.769916 -261.173468) (xy 106.797856 -261.196074)
			(xy 107.282742 -261.196074) (xy 107.307634 -261.180326) (xy 107.313984 -261.166864) (xy 107.326244 -261.141817)
			(xy 107.357177 -261.09542) (xy 107.394745 -261.054212) (xy 107.438092 -261.019132) (xy 107.486228 -260.990981)
			(xy 107.538055 -260.970402) (xy 107.59239 -260.957863) (xy 107.647994 -260.953652) (xy 107.703598 -260.957863)
			(xy 107.757933 -260.970402) (xy 107.80976 -260.990981) (xy 107.857896 -261.019132) (xy 107.901243 -261.054212)
			(xy 107.938811 -261.09542) (xy 107.969744 -261.141817) (xy 107.982004 -261.166864) (xy 107.988354 -261.180326)
			(xy 108.013246 -261.196074) (xy 108.232702 -261.196074) (xy 108.257594 -261.180326) (xy 108.263944 -261.166864)
			(xy 108.276204 -261.141817) (xy 108.307137 -261.09542) (xy 108.344705 -261.054212) (xy 108.388052 -261.019132)
			(xy 108.436188 -260.990981) (xy 108.488015 -260.970402) (xy 108.54235 -260.957863) (xy 108.597954 -260.953652)
			(xy 108.653558 -260.957863) (xy 108.707893 -260.970402) (xy 108.75972 -260.990981) (xy 108.807856 -261.019132)
			(xy 108.851203 -261.054212) (xy 108.888771 -261.09542) (xy 108.919704 -261.141817) (xy 108.931964 -261.166864)
			(xy 108.938314 -261.180326) (xy 108.963206 -261.196074) (xy 109.182662 -261.196074) (xy 109.207554 -261.180326)
			(xy 109.213904 -261.166864) (xy 109.226164 -261.141817) (xy 109.257097 -261.09542) (xy 109.294665 -261.054212)
			(xy 109.338012 -261.019132) (xy 109.386148 -260.990981) (xy 109.437975 -260.970402) (xy 109.49231 -260.957863)
			(xy 109.547914 -260.953652) (xy 109.603518 -260.957863) (xy 109.657853 -260.970402) (xy 109.70968 -260.990981)
			(xy 109.757816 -261.019132) (xy 109.801163 -261.054212) (xy 109.838731 -261.09542) (xy 109.869664 -261.141817)
			(xy 109.881924 -261.166864) (xy 109.888274 -261.180326) (xy 109.913166 -261.196074) (xy 110.132622 -261.196074)
			(xy 110.157514 -261.180326) (xy 110.163864 -261.166864) (xy 110.176124 -261.141817) (xy 110.207057 -261.09542)
			(xy 110.244625 -261.054212) (xy 110.287972 -261.019132) (xy 110.336108 -260.990981) (xy 110.387935 -260.970402)
			(xy 110.44227 -260.957863) (xy 110.497874 -260.953652) (xy 110.553478 -260.957863) (xy 110.607813 -260.970402)
			(xy 110.65964 -260.990981) (xy 110.707776 -261.019132) (xy 110.751123 -261.054212) (xy 110.788691 -261.09542)
			(xy 110.819624 -261.141817) (xy 110.831884 -261.166864) (xy 110.838234 -261.180326) (xy 110.863126 -261.196074)
			(xy 111.082582 -261.196074) (xy 111.107474 -261.180326) (xy 111.113824 -261.166864) (xy 111.126084 -261.141817)
			(xy 111.157017 -261.09542) (xy 111.194585 -261.054212) (xy 111.237932 -261.019132) (xy 111.286068 -260.990981)
			(xy 111.337895 -260.970402) (xy 111.39223 -260.957863) (xy 111.447834 -260.953652) (xy 111.503438 -260.957863)
			(xy 111.557773 -260.970402) (xy 111.6096 -260.990981) (xy 111.657736 -261.019132) (xy 111.701083 -261.054212)
			(xy 111.738651 -261.09542) (xy 111.769584 -261.141817) (xy 111.781844 -261.166864) (xy 111.788194 -261.180326)
			(xy 111.813086 -261.196074) (xy 112.032542 -261.196074) (xy 112.057434 -261.180326) (xy 112.063784 -261.166864)
			(xy 112.076044 -261.141817) (xy 112.106977 -261.09542) (xy 112.144545 -261.054212) (xy 112.187892 -261.019132)
			(xy 112.236028 -260.990981) (xy 112.287855 -260.970402) (xy 112.34219 -260.957863) (xy 112.397794 -260.953652)
			(xy 112.453398 -260.957863) (xy 112.507733 -260.970402) (xy 112.55956 -260.990981) (xy 112.607696 -261.019132)
			(xy 112.651043 -261.054212) (xy 112.688611 -261.09542) (xy 112.719544 -261.141817) (xy 112.731804 -261.166864)
			(xy 112.738154 -261.180326) (xy 112.763046 -261.196074) (xy 112.982756 -261.196074) (xy 113.007648 -261.180326)
			(xy 113.013998 -261.166864) (xy 113.026258 -261.141817) (xy 113.057191 -261.09542) (xy 113.094759 -261.054212)
			(xy 113.138106 -261.019132) (xy 113.186242 -260.990981) (xy 113.238069 -260.970402) (xy 113.292404 -260.957863)
			(xy 113.348008 -260.953652) (xy 113.403612 -260.957863) (xy 113.457947 -260.970402) (xy 113.509774 -260.990981)
			(xy 113.55791 -261.019132) (xy 113.601257 -261.054212) (xy 113.638825 -261.09542) (xy 113.669758 -261.141817)
			(xy 113.682018 -261.166864) (xy 113.688368 -261.180326) (xy 113.71326 -261.196074) (xy 113.932716 -261.196074)
			(xy 113.957608 -261.180326) (xy 113.963958 -261.166864) (xy 113.976218 -261.141817) (xy 114.007151 -261.09542)
			(xy 114.044719 -261.054212) (xy 114.088066 -261.019132) (xy 114.136202 -260.990981) (xy 114.188029 -260.970402)
			(xy 114.242364 -260.957863) (xy 114.297968 -260.953652) (xy 114.353572 -260.957863) (xy 114.407907 -260.970402)
			(xy 114.459734 -260.990981) (xy 114.50787 -261.019132) (xy 114.551217 -261.054212) (xy 114.588785 -261.09542)
			(xy 114.619718 -261.141817) (xy 114.631978 -261.166864) (xy 114.638328 -261.180326) (xy 114.66322 -261.196074)
			(xy 114.882676 -261.196074) (xy 114.907568 -261.180326) (xy 114.913918 -261.166864) (xy 114.926178 -261.141817)
			(xy 114.957111 -261.09542) (xy 114.994679 -261.054212) (xy 115.038026 -261.019132) (xy 115.086162 -260.990981)
			(xy 115.137989 -260.970402) (xy 115.192324 -260.957863) (xy 115.247928 -260.953652) (xy 115.303532 -260.957863)
			(xy 115.357867 -260.970402) (xy 115.409694 -260.990981) (xy 115.45783 -261.019132) (xy 115.501177 -261.054212)
			(xy 115.538745 -261.09542) (xy 115.569678 -261.141817) (xy 115.581938 -261.166864) (xy 115.588288 -261.180326)
			(xy 115.61318 -261.196074) (xy 115.832636 -261.196074) (xy 115.857528 -261.180326) (xy 115.863878 -261.166864)
			(xy 115.875347 -261.143376) (xy 115.903929 -261.099613) (xy 115.938411 -261.06033) (xy 115.978098 -261.026315)
			(xy 116.022195 -260.998251) (xy 116.069816 -260.976702) (xy 116.120004 -260.9621) (xy 116.171753 -260.954739)
			(xy 116.197888 -260.954266) (xy 116.224233 -260.954735) (xy 116.276388 -260.962232) (xy 116.326945 -260.977074)
			(xy 116.374875 -260.998961) (xy 116.419202 -261.027445) (xy 116.459025 -261.061948) (xy 116.493532 -261.101768)
			(xy 116.522021 -261.146092) (xy 116.543912 -261.19402) (xy 116.55876 -261.244575) (xy 116.566262 -261.296729)
			(xy 116.566696 -261.323074) (xy 116.566005 -261.355171) (xy 116.554893 -261.418395) (xy 116.544598 -261.448804)
			(xy 116.539518 -261.463028) (xy 116.545868 -261.491476) (xy 116.582698 -261.528306) (xy 116.590097 -261.535152)
			(xy 116.608695 -261.542886) (xy 116.618766 -261.543292) (xy 120.270524 -261.543292) (xy 120.2871 -261.543856)
			(xy 120.319116 -261.552463) (xy 120.34783 -261.569036) (xy 120.359932 -261.580376) (xy 120.611138 -261.831836)
			(xy 120.621806 -261.839964) (xy 121.727468 -262.474964) (xy 121.755662 -262.474456) (xy 121.7676 -262.466836)
			(xy 121.787546 -262.454668) (xy 121.830139 -262.435464) (xy 121.875015 -262.422461) (xy 121.921277 -262.415917)
			(xy 121.944638 -262.415528) (xy 121.96191 -262.416036) (xy 121.976388 -262.416798) (xy 122.001026 -262.403336)
			(xy 122.145044 -262.155432) (xy 122.144536 -262.127238) (xy 122.136662 -262.115046) (xy 122.124217 -262.094956)
			(xy 122.104572 -262.051975) (xy 122.091246 -262.006635) (xy 122.084513 -261.959859) (xy 122.084084 -261.93623)
			(xy 122.084594 -261.910243) (xy 122.092724 -261.858908) (xy 122.108785 -261.809478) (xy 122.132381 -261.763168)
			(xy 122.162931 -261.72112) (xy 122.199682 -261.684369) (xy 122.24173 -261.653819) (xy 122.28804 -261.630223)
			(xy 122.33747 -261.614162) (xy 122.388805 -261.606032) (xy 122.440779 -261.606032) (xy 122.492114 -261.614162)
			(xy 122.541544 -261.630223) (xy 122.587854 -261.653819) (xy 122.629902 -261.684369) (xy 122.666653 -261.72112)
			(xy 122.697203 -261.763168) (xy 122.720799 -261.809478) (xy 122.73686 -261.858908) (xy 122.74499 -261.910243)
			(xy 122.7455 -261.93623) (xy 122.745246 -261.948422) (xy 122.744738 -261.962646) (xy 122.758454 -261.987284)
			(xy 123.607576 -262.475218) (xy 123.63577 -262.474456) (xy 123.647708 -262.466836) (xy 123.667654 -262.454669)
			(xy 123.710247 -262.435466) (xy 123.755123 -262.422463) (xy 123.801385 -262.415921) (xy 123.824746 -262.415528)
			(xy 123.85073 -262.416041) (xy 123.902057 -262.424178) (xy 123.951479 -262.440243) (xy 123.997779 -262.463842)
			(xy 124.039818 -262.494393) (xy 124.07656 -262.531144) (xy 124.107101 -262.573191) (xy 124.130688 -262.619497)
			(xy 124.146742 -262.668923) (xy 124.154865 -262.720252) (xy 124.155454 -262.746236) (xy 124.1552 -262.758428)
			(xy 124.154692 -262.772652) (xy 124.168408 -262.79729) (xy 125.01753 -263.28497) (xy 125.045724 -263.284462)
			(xy 125.057662 -263.276842) (xy 125.077609 -263.264675) (xy 125.120202 -263.245472) (xy 125.165077 -263.232467)
			(xy 125.211339 -263.22592) (xy 125.2347 -263.225534) (xy 125.251972 -263.226042) (xy 125.26645 -263.226804)
			(xy 125.291088 -263.213342) (xy 125.435106 -262.965438) (xy 125.434598 -262.937244) (xy 125.426724 -262.925052)
			(xy 125.41428 -262.904961) (xy 125.394636 -262.86198) (xy 125.381311 -262.81664) (xy 125.374578 -262.769865)
			(xy 125.374146 -262.746236) (xy 125.374656 -262.720249) (xy 125.382786 -262.668914) (xy 125.398847 -262.619484)
			(xy 125.422443 -262.573174) (xy 125.452993 -262.531126) (xy 125.489744 -262.494375) (xy 125.531792 -262.463825)
			(xy 125.578102 -262.440229) (xy 125.627532 -262.424168) (xy 125.678867 -262.416038) (xy 125.730841 -262.416038)
			(xy 125.782176 -262.424168) (xy 125.831606 -262.440229) (xy 125.877916 -262.463825) (xy 125.919964 -262.494375)
			(xy 125.956715 -262.531126) (xy 125.987265 -262.573174) (xy 126.010861 -262.619484) (xy 126.026922 -262.668914)
			(xy 126.035052 -262.720249) (xy 126.035562 -262.746236) (xy 126.035308 -262.758428) (xy 126.0348 -262.772652)
			(xy 126.048516 -262.79729) (xy 126.897384 -263.285224) (xy 126.925832 -263.284462) (xy 126.93777 -263.276842)
			(xy 126.957717 -263.264676) (xy 127.00031 -263.245473) (xy 127.045186 -263.232469) (xy 127.091447 -263.225924)
			(xy 127.114808 -263.225534) (xy 127.131826 -263.226042) (xy 127.146304 -263.226804) (xy 127.171196 -263.213342)
			(xy 127.31496 -262.965692) (xy 127.314198 -262.937244) (xy 127.306578 -262.925052) (xy 127.294133 -262.904962)
			(xy 127.274485 -262.861981) (xy 127.261158 -262.816641) (xy 127.254423 -262.769865) (xy 127.254 -262.746236)
			(xy 127.25448 -262.720245) (xy 127.262607 -262.668903) (xy 127.278666 -262.619464) (xy 127.302262 -262.573146)
			(xy 127.332814 -262.53109) (xy 127.369569 -262.494332) (xy 127.411622 -262.463777) (xy 127.457938 -262.440177)
			(xy 127.507375 -262.424114) (xy 127.558717 -262.415983) (xy 127.584708 -262.415528) (xy 127.61052 -262.416024)
			(xy 127.661517 -262.424043) (xy 127.71065 -262.439885) (xy 127.756727 -262.463165) (xy 127.798629 -262.49332)
			(xy 127.835339 -262.529616) (xy 127.865966 -262.571173) (xy 127.878332 -262.593836) (xy 127.884936 -262.606536)
			(xy 127.909066 -262.621268) (xy 128.200404 -262.621268) (xy 128.224534 -262.606536) (xy 128.231138 -262.593836)
			(xy 128.243484 -262.571163) (xy 128.27412 -262.529613) (xy 128.310836 -262.493325) (xy 128.352742 -262.463178)
			(xy 128.39882 -262.439903) (xy 128.447954 -262.424066) (xy 128.498951 -262.41605) (xy 128.550573 -262.41605)
			(xy 128.60157 -262.424066) (xy 128.650704 -262.439903) (xy 128.696782 -262.463178) (xy 128.738688 -262.493325)
			(xy 128.775404 -262.529613) (xy 128.80604 -262.571163) (xy 128.818386 -262.593836) (xy 128.82499 -262.606536)
			(xy 128.84912 -262.621268) (xy 129.140458 -262.621268) (xy 129.164588 -262.606536) (xy 129.171192 -262.593836)
			(xy 129.183538 -262.571163) (xy 129.214174 -262.529613) (xy 129.25089 -262.493325) (xy 129.292796 -262.463178)
			(xy 129.338874 -262.439903) (xy 129.388008 -262.424066) (xy 129.439005 -262.41605) (xy 129.490627 -262.41605)
			(xy 129.541624 -262.424066) (xy 129.590758 -262.439903) (xy 129.636836 -262.463178) (xy 129.678742 -262.493325)
			(xy 129.715458 -262.529613) (xy 129.746094 -262.571163) (xy 129.75844 -262.593836) (xy 129.765044 -262.606536)
			(xy 129.789174 -262.621268) (xy 130.080512 -262.621268) (xy 130.104642 -262.606536) (xy 130.111246 -262.593836)
			(xy 130.123596 -262.571168) (xy 130.154238 -262.529627) (xy 130.190956 -262.493347) (xy 130.232862 -262.463207)
			(xy 130.278938 -262.439937) (xy 130.328068 -262.424101) (xy 130.379061 -262.416084) (xy 130.40487 -262.415528)
			(xy 130.43086 -262.416009) (xy 130.4822 -262.424137) (xy 130.531636 -262.440197) (xy 130.577951 -262.463793)
			(xy 130.620003 -262.494346) (xy 130.656758 -262.531101) (xy 130.68731 -262.573154) (xy 130.710906 -262.619469)
			(xy 130.726965 -262.668906) (xy 130.735092 -262.720246) (xy 130.735578 -262.746236) (xy 130.735324 -262.758428)
			(xy 130.734816 -262.772652) (xy 130.748532 -262.79729) (xy 131.5974 -263.285224) (xy 131.625594 -263.284462)
			(xy 131.637786 -263.277096) (xy 131.65773 -263.264909) (xy 131.700317 -263.245656) (xy 131.74519 -263.232585)
			(xy 131.791456 -263.225957) (xy 131.814824 -263.225534) (xy 131.840635 -263.226031) (xy 131.891631 -263.234052)
			(xy 131.940762 -263.249896) (xy 131.986836 -263.273178) (xy 132.028735 -263.303333) (xy 132.065443 -263.33963)
			(xy 132.096068 -263.381187) (xy 132.108448 -263.403842) (xy 132.115052 -263.416542) (xy 132.139182 -263.431274)
			(xy 132.43052 -263.431274) (xy 132.45465 -263.416542) (xy 132.461254 -263.403842) (xy 132.4736 -263.381169)
			(xy 132.504236 -263.339619) (xy 132.540952 -263.303331) (xy 132.582858 -263.273184) (xy 132.628936 -263.249909)
			(xy 132.67807 -263.234072) (xy 132.729067 -263.226056) (xy 132.780689 -263.226056) (xy 132.831686 -263.234072)
			(xy 132.88082 -263.249909) (xy 132.926898 -263.273184) (xy 132.968804 -263.303331) (xy 133.00552 -263.339619)
			(xy 133.036156 -263.381169) (xy 133.048502 -263.403842) (xy 133.055106 -263.416542) (xy 133.079236 -263.431274)
			(xy 133.37032 -263.431274) (xy 133.39445 -263.416542) (xy 133.401054 -263.403842) (xy 133.4134 -263.381169)
			(xy 133.444036 -263.339619) (xy 133.480752 -263.303331) (xy 133.522658 -263.273184) (xy 133.568736 -263.249909)
			(xy 133.61787 -263.234072) (xy 133.668867 -263.226056) (xy 133.720489 -263.226056) (xy 133.771486 -263.234072)
			(xy 133.82062 -263.249909) (xy 133.866698 -263.273184) (xy 133.908604 -263.303331) (xy 133.94532 -263.339619)
			(xy 133.975956 -263.381169) (xy 133.988302 -263.403842) (xy 133.994906 -263.416542) (xy 134.019036 -263.431274)
			(xy 134.310374 -263.431274) (xy 134.334504 -263.416542) (xy 134.341108 -263.403842) (xy 134.353454 -263.381169)
			(xy 134.38409 -263.339619) (xy 134.420806 -263.303331) (xy 134.462712 -263.273184) (xy 134.50879 -263.249909)
			(xy 134.557924 -263.234072) (xy 134.608921 -263.226056) (xy 134.660543 -263.226056) (xy 134.71154 -263.234072)
			(xy 134.760674 -263.249909) (xy 134.806752 -263.273184) (xy 134.848658 -263.303331) (xy 134.885374 -263.339619)
			(xy 134.91601 -263.381169) (xy 134.928356 -263.403842) (xy 134.93496 -263.416542) (xy 134.95909 -263.431274)
			(xy 135.250428 -263.431274) (xy 135.274558 -263.416542) (xy 135.281162 -263.403842) (xy 135.293508 -263.381169)
			(xy 135.324144 -263.339619) (xy 135.36086 -263.303331) (xy 135.402766 -263.273184) (xy 135.448844 -263.249909)
			(xy 135.497978 -263.234072) (xy 135.548975 -263.226056) (xy 135.600597 -263.226056) (xy 135.651594 -263.234072)
			(xy 135.700728 -263.249909) (xy 135.746806 -263.273184) (xy 135.788712 -263.303331) (xy 135.825428 -263.339619)
			(xy 135.856064 -263.381169) (xy 135.86841 -263.403842) (xy 135.875014 -263.416542) (xy 135.899144 -263.431274)
			(xy 136.190482 -263.431274) (xy 136.214612 -263.416542) (xy 136.221216 -263.403842) (xy 136.233565 -263.381172)
			(xy 136.264206 -263.339628) (xy 136.300923 -263.303344) (xy 136.342829 -263.273199) (xy 136.388905 -263.249925)
			(xy 136.438036 -263.234084) (xy 136.48903 -263.226062) (xy 136.51484 -263.225534) (xy 136.540826 -263.22602)
			(xy 136.592157 -263.234157) (xy 136.641584 -263.250223) (xy 136.687888 -263.273823) (xy 136.729931 -263.304377)
			(xy 136.766676 -263.341132) (xy 136.797219 -263.383182) (xy 136.820809 -263.429492) (xy 136.836863 -263.478923)
			(xy 136.844986 -263.530256) (xy 136.845548 -263.556242) (xy 136.84515 -263.579228) (xy 136.838778 -263.624757)
			(xy 136.826161 -263.668964) (xy 136.807544 -263.710998) (xy 136.795764 -263.73074) (xy 136.788398 -263.742678)
			(xy 136.78789 -263.770618) (xy 136.934448 -264.02284) (xy 136.958832 -264.036302) (xy 136.973056 -264.035794)
			(xy 136.98474 -264.03554) (xy 137.010554 -264.036031) (xy 137.061558 -264.044041) (xy 137.110698 -264.059877)
			(xy 137.156783 -264.083153) (xy 137.198692 -264.113305) (xy 137.235409 -264.1496) (xy 137.266043 -264.191159)
			(xy 137.278364 -264.213848) (xy 137.284968 -264.226548) (xy 137.309098 -264.24128) (xy 137.600436 -264.24128)
			(xy 137.624566 -264.226548) (xy 137.63117 -264.213848) (xy 137.643516 -264.191175) (xy 137.674152 -264.149625)
			(xy 137.710868 -264.113337) (xy 137.752774 -264.08319) (xy 137.798852 -264.059915) (xy 137.847986 -264.044078)
			(xy 137.898983 -264.036062) (xy 137.950605 -264.036062) (xy 138.001602 -264.044078) (xy 138.050736 -264.059915)
			(xy 138.096814 -264.08319) (xy 138.13872 -264.113337) (xy 138.175436 -264.149625) (xy 138.206072 -264.191175)
			(xy 138.218418 -264.213848) (xy 138.225022 -264.226548) (xy 138.249152 -264.24128) (xy 138.54049 -264.24128)
			(xy 138.56462 -264.226548) (xy 138.571224 -264.213848) (xy 138.58357 -264.191175) (xy 138.614206 -264.149625)
			(xy 138.650922 -264.113337) (xy 138.692828 -264.08319) (xy 138.738906 -264.059915) (xy 138.78804 -264.044078)
			(xy 138.839037 -264.036062) (xy 138.890659 -264.036062) (xy 138.941656 -264.044078) (xy 138.99079 -264.059915)
			(xy 139.036868 -264.08319) (xy 139.078774 -264.113337) (xy 139.11549 -264.149625) (xy 139.146126 -264.191175)
			(xy 139.158472 -264.213848) (xy 139.165076 -264.226548) (xy 139.189206 -264.24128) (xy 139.48029 -264.24128)
			(xy 139.50442 -264.226548) (xy 139.511024 -264.213848) (xy 139.52337 -264.191175) (xy 139.554006 -264.149625)
			(xy 139.590722 -264.113337) (xy 139.632628 -264.08319) (xy 139.678706 -264.059915) (xy 139.72784 -264.044078)
			(xy 139.778837 -264.036062) (xy 139.830459 -264.036062) (xy 139.881456 -264.044078) (xy 139.93059 -264.059915)
			(xy 139.976668 -264.08319) (xy 140.018574 -264.113337) (xy 140.05529 -264.149625) (xy 140.085926 -264.191175)
			(xy 140.098272 -264.213848) (xy 140.104876 -264.226548) (xy 140.129006 -264.24128) (xy 140.420344 -264.24128)
			(xy 140.444474 -264.226548) (xy 140.451078 -264.213848) (xy 140.463424 -264.191175) (xy 140.49406 -264.149625)
			(xy 140.530776 -264.113337) (xy 140.572682 -264.08319) (xy 140.61876 -264.059915) (xy 140.667894 -264.044078)
			(xy 140.718891 -264.036062) (xy 140.770513 -264.036062) (xy 140.82151 -264.044078) (xy 140.870644 -264.059915)
			(xy 140.916722 -264.08319) (xy 140.958628 -264.113337) (xy 140.995344 -264.149625) (xy 141.02598 -264.191175)
			(xy 141.038326 -264.213848) (xy 141.04493 -264.226548) (xy 141.06906 -264.24128) (xy 141.360398 -264.24128)
			(xy 141.384528 -264.226548) (xy 141.391132 -264.213848) (xy 141.403481 -264.191178) (xy 141.434122 -264.149635)
			(xy 141.47084 -264.113352) (xy 141.512745 -264.083209) (xy 141.558822 -264.059936) (xy 141.607952 -264.044098)
			(xy 141.658946 -264.036078) (xy 141.684756 -264.03554) (xy 141.710746 -264.03602) (xy 141.762087 -264.044146)
			(xy 141.811525 -264.060205) (xy 141.85784 -264.083801) (xy 141.899894 -264.114353) (xy 141.936649 -264.151109)
			(xy 141.967201 -264.193163) (xy 141.990797 -264.239479) (xy 142.006855 -264.288917) (xy 142.01498 -264.340258)
			(xy 142.015464 -264.366248) (xy 142.015072 -264.389236) (xy 142.00871 -264.434769) (xy 141.996102 -264.478981)
			(xy 141.97749 -264.52102) (xy 141.96568 -264.540746) (xy 141.958314 -264.552684) (xy 141.957806 -264.580624)
			(xy 142.10411 -264.832846) (xy 142.128494 -264.846308) (xy 142.142718 -264.8458) (xy 142.154656 -264.845546)
			(xy 142.180647 -264.846052) (xy 142.231989 -264.854177) (xy 142.281429 -264.870234) (xy 142.327748 -264.893826)
			(xy 142.369806 -264.924375) (xy 142.406567 -264.961126) (xy 142.437127 -265.003176) (xy 142.460732 -265.049488)
			(xy 142.476802 -265.098923) (xy 142.484941 -265.150263) (xy 142.485364 -265.176254) (xy 142.484993 -265.199202)
			(xy 142.478683 -265.24466) (xy 142.466135 -265.288806) (xy 142.447592 -265.330788) (xy 142.435834 -265.350498)
			(xy 142.428214 -265.36269) (xy 142.427706 -265.390376) (xy 142.588488 -265.66749) (xy 142.611856 -265.680952)
			(xy 142.625572 -265.680952) (xy 142.649525 -265.68148) (xy 142.696826 -265.689082) (xy 142.742359 -265.703977)
			(xy 142.785007 -265.7258) (xy 142.823724 -265.754017) (xy 142.85756 -265.787933) (xy 142.885683 -265.826718)
			(xy 142.907404 -265.869418) (xy 142.92219 -265.914987) (xy 142.929678 -265.962306) (xy 142.930118 -265.98626)
			(xy 142.929562 -266.012578) (xy 142.920532 -266.064433) (xy 142.902748 -266.113974) (xy 142.89024 -266.137136)
			(xy 142.883382 -266.149074) (xy 142.883636 -266.175744) (xy 143.044418 -266.452858) (xy 143.068802 -266.46632)
			(xy 143.083026 -266.465812) (xy 143.09471 -266.465558) (xy 143.120521 -266.466054) (xy 143.171518 -266.474074)
			(xy 143.220649 -266.489917) (xy 143.266724 -266.513199) (xy 143.308623 -266.543355) (xy 143.34533 -266.579652)
			(xy 143.375954 -266.621211) (xy 143.388334 -266.643866) (xy 143.394938 -266.656566) (xy 143.419068 -266.671298)
			(xy 143.710406 -266.671298)
		)
		(stroke
			(width 0)
			(type solid)
		)
		(fill yes)
		(layer "In9.Cu")
		(net "PVDDCR_SOC_P1")
	)
	(gr_poly
		(pts
			(xy 78.898496 -354.3046) (xy 78.908567 -354.304177) (xy 78.927172 -354.296464) (xy 78.934564 -354.289614)
			(xy 81.632552 -351.591626) (xy 81.650591 -351.574363) (xy 81.692083 -351.5466) (xy 81.738202 -351.527483)
			(xy 81.787168 -351.517749) (xy 81.81213 -351.517204) (xy 84.958174 -351.517204) (xy 84.968238 -351.516767)
			(xy 84.986824 -351.509034) (xy 84.994242 -351.502218) (xy 85.233256 -351.263204) (xy 85.240754 -351.254844)
			(xy 85.248304 -351.233724) (xy 85.24614 -351.211399) (xy 85.240876 -351.201482) (xy 85.181948 -351.10166)
			(xy 85.14969 -351.08896) (xy 85.132926 -351.09404) (xy 85.092411 -351.105333) (xy 85.009798 -351.121139)
			(xy 84.926062 -351.129093) (xy 84.884006 -351.1296) (xy 84.842891 -351.129125) (xy 84.761012 -351.121539)
			(xy 84.680181 -351.10643) (xy 84.60109 -351.083928) (xy 84.524412 -351.054224) (xy 84.450802 -351.017572)
			(xy 84.380888 -350.974285) (xy 84.315266 -350.924732) (xy 84.254496 -350.869335) (xy 84.199096 -350.808568)
			(xy 84.14954 -350.742948) (xy 84.106249 -350.673036) (xy 84.069594 -350.599428) (xy 84.039886 -350.522752)
			(xy 84.01738 -350.443661) (xy 84.002267 -350.362832) (xy 83.994677 -350.280953) (xy 83.994244 -350.239838)
			(xy 83.994756 -350.196891) (xy 84.003031 -350.111396) (xy 84.019518 -350.027098) (xy 84.044063 -349.944785)
			(xy 84.059776 -349.904812) (xy 84.063053 -349.895497) (xy 84.063065 -349.875768) (xy 84.059776 -349.866458)
			(xy 84.044087 -349.826477) (xy 84.019565 -349.744161) (xy 84.003079 -349.659867) (xy 83.994781 -349.574377)
			(xy 83.994244 -349.531432) (xy 83.994836 -349.485786) (xy 84.004216 -349.394977) (xy 84.02286 -349.305609)
			(xy 84.036154 -349.261938) (xy 84.038612 -349.252927) (xy 84.037578 -349.234293) (xy 84.034122 -349.225616)
			(xy 84.015452 -349.182532) (xy 83.986244 -349.093287) (xy 83.966602 -349.001462) (xy 83.956746 -348.908078)
			(xy 83.956144 -348.861126) (xy 83.956586 -348.820566) (xy 83.963951 -348.739782) (xy 83.978632 -348.660002)
			(xy 84.000507 -348.581887) (xy 84.029395 -348.506086) (xy 84.046822 -348.469458) (xy 84.050803 -348.46039)
			(xy 84.05223 -348.440657) (xy 84.049616 -348.431104) (xy 84.035432 -348.386079) (xy 84.015541 -348.293794)
			(xy 84.005527 -348.199922) (xy 84.004912 -348.15272) (xy 84.005416 -348.110372) (xy 84.013467 -348.026058)
			(xy 84.029496 -347.942892) (xy 84.053357 -347.861625) (xy 84.084836 -347.782995) (xy 84.123647 -347.707714)
			(xy 84.169437 -347.636462) (xy 84.221793 -347.569886) (xy 84.280241 -347.508588) (xy 84.344251 -347.453123)
			(xy 84.413243 -347.403994) (xy 84.486593 -347.361645) (xy 84.563636 -347.326461) (xy 84.643675 -347.298759)
			(xy 84.725984 -347.278791) (xy 84.809819 -347.266738) (xy 84.89442 -347.262708) (xy 84.979021 -347.266738)
			(xy 85.062856 -347.278791) (xy 85.145165 -347.298759) (xy 85.225204 -347.326461) (xy 85.302247 -347.361645)
			(xy 85.375597 -347.403994) (xy 85.444589 -347.453123) (xy 85.508599 -347.508588) (xy 85.567047 -347.569886)
			(xy 85.619403 -347.636462) (xy 85.665193 -347.707714) (xy 85.704004 -347.782995) (xy 85.735483 -347.861625)
			(xy 85.759344 -347.942892) (xy 85.775373 -348.026058) (xy 85.783424 -348.110372) (xy 85.783928 -348.15272)
			(xy 85.78347 -348.193279) (xy 85.776102 -348.274061) (xy 85.761418 -348.353839) (xy 85.739542 -348.431951)
			(xy 85.710654 -348.50775) (xy 85.69325 -348.544388) (xy 85.689254 -348.553455) (xy 85.687805 -348.573196)
			(xy 85.690456 -348.582742) (xy 85.704637 -348.627767) (xy 85.724522 -348.720053) (xy 85.73453 -348.813924)
			(xy 85.73516 -348.861126) (xy 85.734608 -348.906766) (xy 85.725314 -348.997571) (xy 85.706764 -349.086945)
			(xy 85.693504 -349.13062) (xy 85.691059 -349.139631) (xy 85.692111 -349.158255) (xy 85.695536 -349.166942)
			(xy 85.714229 -349.210023) (xy 85.74349 -349.299263) (xy 85.763197 -349.391087) (xy 85.773131 -349.484475)
			(xy 85.773768 -349.531432) (xy 85.773258 -349.57438) (xy 85.764985 -349.659876) (xy 85.748501 -349.744174)
			(xy 85.723959 -349.826489) (xy 85.708236 -349.866458) (xy 85.704913 -349.875763) (xy 85.704926 -349.895501)
			(xy 85.708236 -349.904812) (xy 85.723926 -349.944792) (xy 85.74845 -350.027109) (xy 85.764939 -350.111403)
			(xy 85.77324 -350.196892) (xy 85.773768 -350.239838) (xy 85.773283 -350.281896) (xy 85.765346 -350.365635)
			(xy 85.749527 -350.448249) (xy 85.738208 -350.488758) (xy 85.733128 -350.505522) (xy 85.745828 -350.53778)
			(xy 85.84565 -350.596708) (xy 85.855587 -350.601923) (xy 85.877898 -350.604086) (xy 85.899018 -350.596579)
			(xy 85.907372 -350.589088) (xy 86.863936 -349.632524) (xy 86.881975 -349.61526) (xy 86.923467 -349.587494)
			(xy 86.969585 -349.568374) (xy 87.018551 -349.558638) (xy 87.043514 -349.558102) (xy 108.26242 -349.558102)
			(xy 108.272489 -349.557675) (xy 108.291088 -349.549956) (xy 108.298488 -349.543116) (xy 115.78463 -342.056974)
			(xy 115.80267 -342.039712) (xy 115.844163 -342.011951) (xy 115.890281 -341.992834) (xy 115.939246 -341.983098)
			(xy 115.964208 -341.982552) (xy 131.294632 -341.982552) (xy 131.298442 -341.978742) (xy 131.54914 -341.728044)
			(xy 131.555984 -341.720645) (xy 131.563708 -341.702046) (xy 131.564126 -341.691976) (xy 131.564126 -327.905364)
			(xy 131.563632 -327.895359) (xy 131.555967 -327.876875) (xy 131.541816 -327.862727) (xy 131.523331 -327.855066)
			(xy 131.513326 -327.854564) (xy 111.260636 -327.854564) (xy 111.251353 -327.854961) (xy 111.234017 -327.8616)
			(xy 111.226854 -327.867518) (xy 111.205796 -327.885578) (xy 111.159436 -327.916044) (xy 111.109148 -327.939462)
			(xy 111.055994 -327.955339) (xy 111.001099 -327.963337) (xy 110.973362 -327.963784) (xy 110.94563 -327.96328)
			(xy 110.890752 -327.955245) (xy 110.83761 -327.939364) (xy 110.787321 -327.91597) (xy 110.740941 -327.885554)
			(xy 110.71987 -327.867518) (xy 110.712679 -327.861647) (xy 110.695361 -327.855001) (xy 110.686088 -327.854564)
			(xy 105.730548 -327.854564) (xy 105.720372 -327.855078) (xy 105.701653 -327.863081) (xy 105.694226 -327.870058)
			(xy 105.63606 -327.929748) (xy 105.628694 -327.948544) (xy 105.628948 -327.958958) (xy 105.629202 -327.969626)
			(xy 105.628714 -327.996876) (xy 105.620955 -328.05082) (xy 105.605597 -328.103112) (xy 105.582955 -328.152685)
			(xy 105.553488 -328.198532) (xy 105.517796 -328.239719) (xy 105.476606 -328.275407) (xy 105.430757 -328.30487)
			(xy 105.381182 -328.327509) (xy 105.328889 -328.342862) (xy 105.274944 -328.350617) (xy 105.247694 -328.351134)
			(xy 105.221417 -328.350713) (xy 105.169358 -328.343531) (xy 105.11878 -328.329263) (xy 105.094532 -328.31913)
			(xy 105.080054 -328.31278) (xy 105.049574 -328.318368) (xy 104.769412 -328.59853) (xy 104.75137 -328.615787)
			(xy 104.709875 -328.643538) (xy 104.663757 -328.662645) (xy 104.614794 -328.672369) (xy 104.589834 -328.672952)
			(xy 99.041712 -328.672952) (xy 99.014788 -328.693272) (xy 99.009962 -328.709528) (xy 99.001891 -328.73562)
			(xy 98.979325 -328.785357) (xy 98.949899 -328.831368) (xy 98.914214 -328.872715) (xy 98.873 -328.908552)
			(xy 98.827098 -328.938148) (xy 98.777445 -328.960898) (xy 98.725056 -328.976338) (xy 98.671002 -328.984151)
			(xy 98.643694 -328.98461) (xy 98.616443 -328.984124) (xy 98.562496 -328.976367) (xy 98.510202 -328.961011)
			(xy 98.460625 -328.93837) (xy 98.414775 -328.908903) (xy 98.373586 -328.873212) (xy 98.337894 -328.832022)
			(xy 98.308429 -328.786171) (xy 98.285788 -328.736595) (xy 98.270433 -328.6843) (xy 98.262676 -328.630353)
			(xy 98.262186 -328.603102) (xy 98.262692 -328.574637) (xy 98.271113 -328.518334) (xy 98.287814 -328.46391)
			(xy 98.312423 -328.412574) (xy 98.327972 -328.388726) (xy 98.338386 -328.373486) (xy 98.335084 -328.337418)
			(xy 96.216216 -326.21855) (xy 96.208816 -326.211711) (xy 96.190217 -326.203999) (xy 96.180148 -326.203564)
			(xy 74.588624 -326.203564) (xy 74.578561 -326.204003) (xy 74.559983 -326.211744) (xy 74.552556 -326.21855)
			(xy 70.958964 -329.812142) (xy 70.940923 -329.829402) (xy 70.89943 -329.857161) (xy 70.853312 -329.876276)
			(xy 70.804347 -329.88601) (xy 70.779386 -329.886564) (xy 65.825624 -329.886564) (xy 65.815561 -329.887003)
			(xy 65.796983 -329.894744) (xy 65.789556 -329.90155) (xy 65.206372 -330.484734) (xy 65.199523 -330.492131)
			(xy 65.19179 -330.51073) (xy 65.191386 -330.520802) (xy 65.191386 -334.994504) (xy 65.190814 -335.019464)
			(xy 65.181074 -335.068425) (xy 65.161969 -335.114545) (xy 65.134233 -335.156052) (xy 65.116964 -335.174082)
			(xy 64.624204 -335.666842) (xy 64.606161 -335.684097) (xy 64.564666 -335.711846) (xy 64.518548 -335.73095)
			(xy 64.469586 -335.740673) (xy 64.444626 -335.741264) (xy 59.559698 -335.741264) (xy 59.53379 -335.759044)
			(xy 59.528202 -335.773776) (xy 59.51738 -335.800363) (xy 59.488916 -335.850211) (xy 59.453313 -335.895236)
			(xy 59.41137 -335.934425) (xy 59.364035 -335.966895) (xy 59.312372 -335.991914) (xy 59.257547 -336.008917)
			(xy 59.200795 -336.017523) (xy 59.172094 -336.018124) (xy 59.145899 -336.017691) (xy 59.094002 -336.010525)
			(xy 59.043572 -335.99633) (xy 58.995557 -335.975371) (xy 58.950859 -335.948043) (xy 58.910319 -335.91486)
			(xy 58.892186 -335.89595) (xy 58.884712 -335.888621) (xy 58.865557 -335.880237) (xy 58.855102 -335.879694)
			(xy 58.780426 -335.879694) (xy 58.769982 -335.880263) (xy 58.750848 -335.888663) (xy 58.743342 -335.89595)
			(xy 58.725212 -335.914861) (xy 58.684668 -335.94804) (xy 58.639969 -335.975365) (xy 58.591954 -335.996322)
			(xy 58.541525 -336.010517) (xy 58.489629 -336.017684) (xy 58.463434 -336.018124) (xy 58.434727 -336.017608)
			(xy 58.377961 -336.009013) (xy 58.323123 -335.992011) (xy 58.271451 -335.966987) (xy 58.22411 -335.934504)
			(xy 58.18217 -335.895296) (xy 58.146576 -335.850248) (xy 58.118131 -335.800376) (xy 58.107326 -335.773776)
			(xy 58.101738 -335.759044) (xy 58.07583 -335.741264) (xy 57.407048 -335.741264) (xy 57.380886 -335.759298)
			(xy 57.375298 -335.774284) (xy 57.364636 -335.801152) (xy 57.33638 -335.851577) (xy 57.300842 -335.897163)
			(xy 57.258835 -335.936868) (xy 57.211319 -335.969783) (xy 57.159383 -335.995154) (xy 57.104214 -336.012402)
			(xy 57.047075 -336.021132) (xy 57.018174 -336.02168) (xy 56.989436 -336.021157) (xy 56.93261 -336.012531)
			(xy 56.877722 -335.995477) (xy 56.826013 -335.970382) (xy 56.778655 -335.937813) (xy 56.757316 -335.918556)
			(xy 56.750204 -335.911952) (xy 56.732678 -335.90484) (xy 56.64327 -335.90484) (xy 56.625744 -335.911952)
			(xy 56.618632 -335.918556) (xy 56.597303 -335.937822) (xy 56.549938 -335.970377) (xy 56.498225 -335.99546)
			(xy 56.443336 -336.012502) (xy 56.386511 -336.021119) (xy 56.357774 -336.02168) (xy 56.32887 -336.021151)
			(xy 56.271721 -336.012438) (xy 56.216543 -335.995199) (xy 56.164598 -335.969831) (xy 56.117077 -335.936913)
			(xy 56.075068 -335.897201) (xy 56.039533 -335.851603) (xy 56.011288 -335.801165) (xy 56.00065 -335.774284)
			(xy 55.995062 -335.759298) (xy 55.9689 -335.741264) (xy 23.700486 -335.741264) (xy 23.675526 -335.740691)
			(xy 23.626567 -335.730949) (xy 23.580449 -335.711841) (xy 23.538946 -335.684102) (xy 23.520908 -335.666842)
			(xy 23.495 -335.640934) (xy 23.487557 -335.63424) (xy 23.469059 -335.626642) (xy 23.449061 -335.626658)
			(xy 23.439628 -335.630012) (xy 23.425404 -335.635854) (xy 23.408386 -335.661254) (xy 23.408386 -336.9884)
			(xy 70.218517 -336.9884) (xy 70.222508 -336.904617) (xy 70.234446 -336.821593) (xy 70.254221 -336.74008)
			(xy 70.281655 -336.660815) (xy 70.3165 -336.584518) (xy 70.35844 -336.511878) (xy 70.407095 -336.443554)
			(xy 70.462025 -336.380164) (xy 70.522731 -336.322283) (xy 70.588664 -336.270435) (xy 70.659228 -336.225089)
			(xy 70.733783 -336.186656) (xy 70.811653 -336.155484) (xy 70.892134 -336.131855) (xy 70.974497 -336.115984)
			(xy 71.057995 -336.108014) (xy 71.099934 -336.107532) (xy 71.137123 -336.107938) (xy 71.211236 -336.114223)
			(xy 71.284556 -336.126727) (xy 71.356562 -336.145363) (xy 71.39178 -336.157316) (xy 71.399976 -336.159839)
			(xy 71.417112 -336.159839) (xy 71.425308 -336.157316) (xy 71.470669 -336.142069) (xy 71.563884 -336.120393)
			(xy 71.658899 -336.108952) (xy 71.70674 -336.107786) (xy 71.718176 -336.107007) (xy 71.738659 -336.096778)
			(xy 71.752714 -336.078706) (xy 71.755762 -336.067654) (xy 71.765272 -336.026636) (xy 71.791094 -335.946486)
			(xy 71.807324 -335.907634) (xy 71.810983 -335.897931) (xy 71.810971 -335.877211) (xy 71.807324 -335.867502)
			(xy 71.790169 -335.826159) (xy 71.763338 -335.74076) (xy 71.7453 -335.653081) (xy 71.736241 -335.564026)
			(xy 71.735696 -335.519268) (xy 71.736195 -335.477343) (xy 71.744165 -335.393872) (xy 71.760034 -335.311537)
			(xy 71.783657 -335.231083) (xy 71.814821 -335.153239) (xy 71.853244 -335.078709) (xy 71.898577 -335.00817)
			(xy 71.95041 -334.942259) (xy 72.008273 -334.881573) (xy 72.071643 -334.826663) (xy 72.139946 -334.778025)
			(xy 72.212563 -334.7361) (xy 72.288836 -334.701267) (xy 72.368075 -334.673842) (xy 72.449561 -334.654073)
			(xy 72.532558 -334.64214) (xy 72.616314 -334.638151) (xy 72.70007 -334.64214) (xy 72.783067 -334.654073)
			(xy 72.864553 -334.673842) (xy 72.943792 -334.701267) (xy 73.020065 -334.7361) (xy 73.092682 -334.778025)
			(xy 73.160985 -334.826663) (xy 73.224355 -334.881573) (xy 73.282218 -334.942259) (xy 73.334051 -335.00817)
			(xy 73.379384 -335.078709) (xy 73.417807 -335.153239) (xy 73.448971 -335.231083) (xy 73.472594 -335.311537)
			(xy 73.488463 -335.393872) (xy 73.496433 -335.477343) (xy 73.496932 -335.519268) (xy 73.496405 -335.564027)
			(xy 73.487367 -335.653088) (xy 73.469332 -335.740771) (xy 73.442485 -335.826168) (xy 73.425304 -335.867502)
			(xy 73.421681 -335.877216) (xy 73.421669 -335.897926) (xy 73.425304 -335.907634) (xy 73.441139 -335.945575)
			(xy 73.466487 -336.02379) (xy 73.484436 -336.104027) (xy 73.494829 -336.185587) (xy 73.496678 -336.226658)
			(xy 73.496932 -336.240374) (xy 73.511156 -336.263234) (xy 73.61301 -336.31759) (xy 73.639934 -336.316828)
			(xy 73.651618 -336.309462) (xy 73.686811 -336.288202) (xy 73.76042 -336.251553) (xy 73.837094 -336.221845)
			(xy 73.91618 -336.199333) (xy 73.997005 -336.184209) (xy 74.07888 -336.1766) (xy 74.119994 -336.176112)
			(xy 74.161107 -336.176619) (xy 74.242983 -336.184205) (xy 74.32381 -336.199313) (xy 74.402898 -336.221815)
			(xy 74.479573 -336.251518) (xy 74.553179 -336.288168) (xy 74.623091 -336.331454) (xy 74.68871 -336.381006)
			(xy 74.749477 -336.4364) (xy 74.804874 -336.497166) (xy 74.854428 -336.562783) (xy 74.897716 -336.632693)
			(xy 74.934369 -336.706298) (xy 74.964075 -336.782971) (xy 74.986579 -336.862059) (xy 75.001691 -336.942885)
			(xy 75.005252 -336.9813) (xy 78.574105 -336.9813) (xy 78.578096 -336.897517) (xy 78.590033 -336.814493)
			(xy 78.609809 -336.732979) (xy 78.637243 -336.653715) (xy 78.672087 -336.577417) (xy 78.714027 -336.504776)
			(xy 78.762681 -336.436452) (xy 78.81761 -336.373061) (xy 78.878316 -336.31518) (xy 78.94425 -336.26333)
			(xy 79.014813 -336.217984) (xy 79.089367 -336.179549) (xy 79.167237 -336.148376) (xy 79.247718 -336.124747)
			(xy 79.330081 -336.108874) (xy 79.413579 -336.100902) (xy 79.455518 -336.10042) (xy 79.492708 -336.100802)
			(xy 79.566821 -336.107094) (xy 79.640141 -336.119606) (xy 79.712146 -336.138248) (xy 79.747364 -336.150204)
			(xy 79.75556 -336.152727) (xy 79.772696 -336.152727) (xy 79.780892 -336.150204) (xy 79.82711 -336.134723)
			(xy 79.922101 -336.112853) (xy 80.018924 -336.101587) (xy 80.067658 -336.100674) (xy 80.079173 -336.100035)
			(xy 80.099844 -336.089868) (xy 80.113999 -336.071694) (xy 80.116934 -336.060542) (xy 80.12645 -336.018737)
			(xy 80.152526 -335.937055) (xy 80.169004 -335.897474) (xy 80.172641 -335.887764) (xy 80.172644 -335.86705)
			(xy 80.169004 -335.857342) (xy 80.151829 -335.816007) (xy 80.125003 -335.730605) (xy 80.10697 -335.642924)
			(xy 80.097917 -335.553866) (xy 80.097376 -335.509108) (xy 80.097875 -335.467183) (xy 80.105845 -335.383712)
			(xy 80.121714 -335.301377) (xy 80.145337 -335.220923) (xy 80.176501 -335.143079) (xy 80.214924 -335.068549)
			(xy 80.260257 -334.99801) (xy 80.31209 -334.932099) (xy 80.369953 -334.871413) (xy 80.433323 -334.816503)
			(xy 80.501626 -334.767865) (xy 80.574243 -334.72594) (xy 80.650516 -334.691107) (xy 80.729755 -334.663682)
			(xy 80.811241 -334.643913) (xy 80.894238 -334.63198) (xy 80.977994 -334.627991) (xy 81.06175 -334.63198)
			(xy 81.144747 -334.643913) (xy 81.226233 -334.663682) (xy 81.305472 -334.691107) (xy 81.381745 -334.72594)
			(xy 81.454362 -334.767865) (xy 81.522665 -334.816503) (xy 81.586035 -334.871413) (xy 81.643898 -334.932099)
			(xy 81.695731 -334.99801) (xy 81.741064 -335.068549) (xy 81.779487 -335.143079) (xy 81.810651 -335.220923)
			(xy 81.834274 -335.301377) (xy 81.850143 -335.383712) (xy 81.858113 -335.467183) (xy 81.858612 -335.509108)
			(xy 81.8581 -335.553868) (xy 81.849058 -335.642929) (xy 81.831019 -335.730611) (xy 81.804167 -335.816009)
			(xy 81.786984 -335.857342) (xy 81.783338 -335.867049) (xy 81.783341 -335.887765) (xy 81.786984 -335.897474)
			(xy 81.802748 -335.935334) (xy 81.827987 -336.013369) (xy 81.845871 -336.093411) (xy 81.856247 -336.174768)
			(xy 81.858104 -336.215736) (xy 81.858612 -336.229452) (xy 81.872836 -336.252312) (xy 81.974182 -336.306922)
			(xy 82.000852 -336.30616) (xy 82.012536 -336.299048) (xy 82.047432 -336.278305) (xy 82.120306 -336.242523)
			(xy 82.19614 -336.213534) (xy 82.2743 -336.191579) (xy 82.354137 -336.176843) (xy 82.434985 -336.169448)
			(xy 82.475578 -336.169) (xy 82.516691 -336.169534) (xy 82.598566 -336.177119) (xy 82.679391 -336.192225)
			(xy 82.758479 -336.214725) (xy 82.835153 -336.244426) (xy 82.908759 -336.281075) (xy 82.97867 -336.324359)
			(xy 83.044289 -336.373909) (xy 83.105056 -336.429302) (xy 83.160453 -336.490065) (xy 83.210007 -336.555681)
			(xy 83.253296 -336.625589) (xy 83.28995 -336.699193) (xy 83.319656 -336.775864) (xy 83.342161 -336.85495)
			(xy 83.357273 -336.935775) (xy 83.360149 -336.9668) (xy 86.931981 -336.9668) (xy 86.935971 -336.883042)
			(xy 86.947905 -336.800043) (xy 86.967674 -336.718554) (xy 86.9951 -336.639313) (xy 87.029935 -336.563039)
			(xy 87.071862 -336.490421) (xy 87.120503 -336.422117) (xy 87.175416 -336.358746) (xy 87.236104 -336.300883)
			(xy 87.302018 -336.24905) (xy 87.37256 -336.203717) (xy 87.447092 -336.165296) (xy 87.52494 -336.134133)
			(xy 87.605396 -336.110512) (xy 87.687734 -336.094645) (xy 87.771208 -336.086677) (xy 87.813134 -336.086196)
			(xy 87.850319 -336.08655) (xy 87.924427 -336.092775) (xy 87.997747 -336.105222) (xy 88.069757 -336.123801)
			(xy 88.10498 -336.135726) (xy 88.113176 -336.138249) (xy 88.130312 -336.138249) (xy 88.138508 -336.135726)
			(xy 88.183102 -336.120718) (xy 88.274708 -336.09922) (xy 88.368084 -336.087605) (xy 88.415114 -336.086196)
			(xy 88.426305 -336.085461) (xy 88.446408 -336.075565) (xy 88.460424 -336.058085) (xy 88.463628 -336.047334)
			(xy 88.472739 -336.011599) (xy 88.496138 -335.941658) (xy 88.510364 -335.907634) (xy 88.514021 -335.89793)
			(xy 88.514009 -335.877211) (xy 88.510364 -335.867502) (xy 88.493206 -335.82616) (xy 88.466376 -335.74076)
			(xy 88.448339 -335.653081) (xy 88.43928 -335.564026) (xy 88.438736 -335.519268) (xy 88.439235 -335.477343)
			(xy 88.447205 -335.393872) (xy 88.463074 -335.311537) (xy 88.486697 -335.231083) (xy 88.517861 -335.153239)
			(xy 88.556284 -335.078709) (xy 88.601617 -335.00817) (xy 88.65345 -334.942259) (xy 88.711313 -334.881573)
			(xy 88.774683 -334.826663) (xy 88.842986 -334.778025) (xy 88.915603 -334.7361) (xy 88.991876 -334.701267)
			(xy 89.071115 -334.673842) (xy 89.152601 -334.654073) (xy 89.235598 -334.64214) (xy 89.319354 -334.638151)
			(xy 89.40311 -334.64214) (xy 89.486107 -334.654073) (xy 89.567593 -334.673842) (xy 89.646832 -334.701267)
			(xy 89.723105 -334.7361) (xy 89.795722 -334.778025) (xy 89.864025 -334.826663) (xy 89.927395 -334.881573)
			(xy 89.985258 -334.942259) (xy 90.037091 -335.00817) (xy 90.082424 -335.078709) (xy 90.120847 -335.153239)
			(xy 90.152011 -335.231083) (xy 90.175634 -335.311537) (xy 90.191503 -335.393872) (xy 90.199473 -335.477343)
			(xy 90.199972 -335.519268) (xy 90.199441 -335.564027) (xy 90.190404 -335.653088) (xy 90.17237 -335.74077)
			(xy 90.145524 -335.826168) (xy 90.128344 -335.867502) (xy 90.124724 -335.877216) (xy 90.124712 -335.897925)
			(xy 90.128344 -335.907634) (xy 90.14352 -335.944017) (xy 90.168055 -336.018939) (xy 90.185802 -336.095753)
			(xy 90.196619 -336.173844) (xy 90.198956 -336.213196) (xy 90.199718 -336.226912) (xy 90.214196 -336.249518)
			(xy 90.316812 -336.302604) (xy 90.343482 -336.301334) (xy 90.355166 -336.293968) (xy 90.390919 -336.271811)
			(xy 90.465823 -336.23353) (xy 90.544005 -336.202491) (xy 90.624768 -336.178971) (xy 90.70739 -336.163179)
			(xy 90.791135 -336.155257) (xy 90.833194 -336.154776) (xy 90.874302 -336.155218) (xy 90.956167 -336.162803)
			(xy 91.036983 -336.177907) (xy 91.116061 -336.200402) (xy 91.192727 -336.230097) (xy 91.266326 -336.266738)
			(xy 91.336231 -336.310013) (xy 91.401845 -336.359552) (xy 91.46261 -336.414933) (xy 91.518006 -336.475684)
			(xy 91.567562 -336.541286) (xy 91.610854 -336.61118) (xy 91.647513 -336.68477) (xy 91.677227 -336.761428)
			(xy 91.699742 -336.840501) (xy 91.714867 -336.921313) (xy 91.722471 -337.003176) (xy 91.722641 -337.0176)
			(xy 95.263181 -337.0176) (xy 95.267171 -336.933842) (xy 95.279105 -336.850843) (xy 95.298874 -336.769354)
			(xy 95.3263 -336.690113) (xy 95.361135 -336.613839) (xy 95.403062 -336.541221) (xy 95.451703 -336.472917)
			(xy 95.506616 -336.409546) (xy 95.567304 -336.351683) (xy 95.633218 -336.29985) (xy 95.70376 -336.254517)
			(xy 95.778292 -336.216096) (xy 95.85614 -336.184933) (xy 95.936596 -336.161312) (xy 96.018934 -336.145445)
			(xy 96.102408 -336.137477) (xy 96.144334 -336.136996) (xy 96.181519 -336.13735) (xy 96.255627 -336.143575)
			(xy 96.328947 -336.156022) (xy 96.400957 -336.174601) (xy 96.43618 -336.186526) (xy 96.444376 -336.189049)
			(xy 96.461512 -336.189049) (xy 96.469708 -336.186526) (xy 96.515925 -336.171041) (xy 96.610917 -336.149172)
			(xy 96.70774 -336.137908) (xy 96.756474 -336.136996) (xy 96.767661 -336.136387) (xy 96.787899 -336.126839)
			(xy 96.802151 -336.109589) (xy 96.805496 -336.098896) (xy 96.81425 -336.066254) (xy 96.836121 -336.002303)
			(xy 96.849184 -335.971134) (xy 96.852845 -335.961431) (xy 96.852833 -335.940711) (xy 96.849184 -335.931002)
			(xy 96.832027 -335.88966) (xy 96.805196 -335.80426) (xy 96.787159 -335.716581) (xy 96.7781 -335.627526)
			(xy 96.777556 -335.582768) (xy 96.778055 -335.540843) (xy 96.786025 -335.457372) (xy 96.801894 -335.375037)
			(xy 96.825517 -335.294583) (xy 96.856681 -335.216739) (xy 96.895104 -335.142209) (xy 96.940437 -335.07167)
			(xy 96.99227 -335.005759) (xy 97.050133 -334.945073) (xy 97.113503 -334.890163) (xy 97.181806 -334.841525)
			(xy 97.254423 -334.7996) (xy 97.330696 -334.764767) (xy 97.409935 -334.737342) (xy 97.491421 -334.717573)
			(xy 97.574418 -334.70564) (xy 97.658174 -334.701651) (xy 97.74193 -334.70564) (xy 97.824927 -334.717573)
			(xy 97.906413 -334.737342) (xy 97.985652 -334.764767) (xy 98.061925 -334.7996) (xy 98.134542 -334.841525)
			(xy 98.202845 -334.890163) (xy 98.266215 -334.945073) (xy 98.324078 -335.005759) (xy 98.375911 -335.07167)
			(xy 98.421244 -335.142209) (xy 98.459667 -335.216739) (xy 98.490831 -335.294583) (xy 98.514454 -335.375037)
			(xy 98.530323 -335.457372) (xy 98.538293 -335.540843) (xy 98.538792 -335.582768) (xy 98.538268 -335.627527)
			(xy 98.52923 -335.716588) (xy 98.511194 -335.804271) (xy 98.484346 -335.889668) (xy 98.467164 -335.931002)
			(xy 98.463542 -335.940716) (xy 98.463531 -335.961426) (xy 98.467164 -335.971134) (xy 98.48433 -336.012473)
			(xy 98.511159 -336.097874) (xy 98.529194 -336.185554) (xy 98.538249 -336.27461) (xy 98.538792 -336.319368)
			(xy 98.538552 -336.350973) (xy 98.534101 -336.414026) (xy 98.529902 -336.445352) (xy 98.528378 -336.456274)
			(xy 98.53422 -336.476848) (xy 98.597466 -336.551778) (xy 98.61677 -336.561176) (xy 98.627946 -336.56143)
			(xy 98.670902 -336.563008) (xy 98.756231 -336.573428) (xy 98.840158 -336.592031) (xy 98.921898 -336.618644)
			(xy 99.00069 -336.653018) (xy 99.075799 -336.694832) (xy 99.146523 -336.743697) (xy 99.212204 -336.799156)
			(xy 99.272228 -336.860693) (xy 99.326037 -336.927733) (xy 99.373127 -336.999651) (xy 99.413059 -337.075777)
			(xy 99.445462 -337.155399) (xy 99.470033 -337.237777) (xy 99.486543 -337.32214) (xy 99.494837 -337.407702)
			(xy 99.495356 -337.450684) (xy 99.494799 -337.493394) (xy 99.486541 -337.578416) (xy 99.470184 -337.662257)
			(xy 99.44588 -337.744149) (xy 99.430332 -337.783932) (xy 99.426798 -337.793999) (xy 99.427585 -337.815303)
			(xy 99.431856 -337.82508) (xy 99.448927 -337.861382) (xy 99.477247 -337.936442) (xy 99.498691 -338.013749)
			(xy 99.513085 -338.092672) (xy 99.520312 -338.172571) (xy 99.520756 -338.212684) (xy 99.520272 -338.252763)
			(xy 99.512982 -338.33259) (xy 99.498549 -338.411439) (xy 99.488244 -338.450174) (xy 99.485843 -338.460698)
			(xy 99.489132 -338.482012) (xy 99.494594 -338.491322) (xy 99.517345 -338.52734) (xy 99.556637 -338.602937)
			(xy 99.588514 -338.681946) (xy 99.612684 -338.763644) (xy 99.628925 -338.847279) (xy 99.637089 -338.932085)
			(xy 99.637596 -338.974684) (xy 99.637001 -339.021087) (xy 99.627302 -339.113385) (xy 99.608039 -339.204171)
			(xy 99.579422 -339.292455) (xy 99.561142 -339.33511) (xy 99.557344 -339.345055) (xy 99.557338 -339.366316)
			(xy 99.561142 -339.376258) (xy 99.579397 -339.418922) (xy 99.607993 -339.507209) (xy 99.627252 -339.597991)
			(xy 99.636966 -339.690283) (xy 99.637596 -339.736684) (xy 99.637132 -339.777795) (xy 99.629546 -339.859665)
			(xy 99.614436 -339.940487) (xy 99.591932 -340.019568) (xy 99.562226 -340.096236) (xy 99.525571 -340.169835)
			(xy 99.482281 -340.239737) (xy 99.432724 -340.305345) (xy 99.377324 -340.3661) (xy 99.316553 -340.421484)
			(xy 99.25093 -340.471022) (xy 99.181016 -340.514293) (xy 99.107407 -340.550927) (xy 99.030731 -340.580612)
			(xy 98.951643 -340.603093) (xy 98.870818 -340.61818) (xy 98.788945 -340.625744) (xy 98.747834 -340.626192)
			(xy 98.704859 -340.625663) (xy 98.619309 -340.617375) (xy 98.534957 -340.600874) (xy 98.45259 -340.576313)
			(xy 98.372977 -340.543922) (xy 98.296859 -340.504001) (xy 98.224947 -340.456925) (xy 98.157912 -340.403131)
			(xy 98.096378 -340.343122) (xy 98.040919 -340.277458) (xy 98.01606 -340.242398) (xy 98.010455 -340.235056)
			(xy 97.995216 -340.224641) (xy 97.986342 -340.222078) (xy 97.94544 -340.211492) (xy 97.865683 -340.183605)
			(xy 97.788928 -340.148281) (xy 97.715869 -340.105839) (xy 97.647164 -340.05666) (xy 97.583432 -340.001188)
			(xy 97.525246 -339.939922) (xy 97.473132 -339.873416) (xy 97.427559 -339.802268) (xy 97.388937 -339.727119)
			(xy 97.357615 -339.648646) (xy 97.333875 -339.567557) (xy 97.317931 -339.484583) (xy 97.309927 -339.40047)
			(xy 97.309432 -339.358224) (xy 97.309829 -339.321956) (xy 97.315809 -339.249667) (xy 97.327648 -339.178103)
			(xy 97.336102 -339.142832) (xy 97.338139 -339.132668) (xy 97.334873 -339.11222) (xy 97.329752 -339.103208)
			(xy 97.307698 -339.067555) (xy 97.269607 -338.992868) (xy 97.238709 -338.91493) (xy 97.215277 -338.834431)
			(xy 97.199521 -338.752086) (xy 97.191579 -338.668623) (xy 97.191068 -338.626704) (xy 97.191648 -338.581935)
			(xy 97.200654 -338.49285) (xy 97.218554 -338.405119) (xy 97.245168 -338.319627) (xy 97.262188 -338.278216)
			(xy 97.265753 -338.268625) (xy 97.265754 -338.248182) (xy 97.262188 -338.238592) (xy 97.246411 -338.200279)
			(xy 97.221196 -338.121347) (xy 97.203435 -338.04041) (xy 97.193281 -337.958173) (xy 97.191576 -337.916774)
			(xy 97.190731 -337.905855) (xy 97.181081 -337.886218) (xy 97.164168 -337.872338) (xy 97.15373 -337.869022)
			(xy 97.136858 -337.864524) (xy 97.103447 -337.854361) (xy 97.086928 -337.848702) (xy 97.078732 -337.846179)
			(xy 97.061596 -337.846179) (xy 97.0534 -337.848702) (xy 97.01818 -337.860638) (xy 96.946171 -337.879227)
			(xy 96.87285 -337.89167) (xy 96.798739 -337.897878) (xy 96.761554 -337.898232) (xy 96.724369 -337.89788)
			(xy 96.650261 -337.891654) (xy 96.576941 -337.879206) (xy 96.504931 -337.860627) (xy 96.469708 -337.848702)
			(xy 96.461512 -337.846179) (xy 96.444376 -337.846179) (xy 96.43618 -337.848702) (xy 96.400962 -337.860643)
			(xy 96.328952 -337.879231) (xy 96.25563 -337.891673) (xy 96.181519 -337.897879) (xy 96.144334 -337.898232)
			(xy 96.102408 -337.897723) (xy 96.018934 -337.889755) (xy 95.936596 -337.873888) (xy 95.85614 -337.850267)
			(xy 95.778292 -337.819104) (xy 95.70376 -337.780683) (xy 95.633218 -337.73535) (xy 95.567304 -337.683517)
			(xy 95.506616 -337.625654) (xy 95.451703 -337.562283) (xy 95.403062 -337.493979) (xy 95.361135 -337.421361)
			(xy 95.3263 -337.345087) (xy 95.298874 -337.265846) (xy 95.279105 -337.184357) (xy 95.267171 -337.101358)
			(xy 95.263181 -337.0176) (xy 91.722641 -337.0176) (xy 91.722956 -337.044284) (xy 91.722404 -337.089054)
			(xy 91.71339 -337.178139) (xy 91.695482 -337.26587) (xy 91.668861 -337.351361) (xy 91.651836 -337.392772)
			(xy 91.648282 -337.402366) (xy 91.648276 -337.422805) (xy 91.651836 -337.432396) (xy 91.668872 -337.473803)
			(xy 91.695506 -337.559291) (xy 91.71341 -337.647024) (xy 91.722404 -337.736113) (xy 91.722956 -337.780884)
			(xy 91.722404 -337.825654) (xy 91.71339 -337.914739) (xy 91.695482 -338.00247) (xy 91.668861 -338.087961)
			(xy 91.651836 -338.129372) (xy 91.648282 -338.138966) (xy 91.648276 -338.159405) (xy 91.651836 -338.168996)
			(xy 91.668872 -338.210403) (xy 91.695506 -338.295891) (xy 91.71341 -338.383624) (xy 91.722404 -338.472713)
			(xy 91.722956 -338.517484) (xy 91.722432 -338.558593) (xy 91.714846 -338.64046) (xy 91.699738 -338.721278)
			(xy 91.677236 -338.800357) (xy 91.647532 -338.877021) (xy 91.610881 -338.950618) (xy 91.567594 -339.020518)
			(xy 91.518041 -339.086125) (xy 91.462645 -339.146879) (xy 91.401879 -339.202262) (xy 91.336261 -339.251801)
			(xy 91.266352 -339.295073) (xy 91.192747 -339.331709) (xy 91.116076 -339.361396) (xy 91.036993 -339.383882)
			(xy 90.956172 -339.398973) (xy 90.874303 -339.406541) (xy 90.833194 -339.406992) (xy 90.791582 -339.406536)
			(xy 90.708719 -339.398784) (xy 90.626944 -339.383319) (xy 90.546973 -339.360277) (xy 90.469506 -339.329861)
			(xy 90.395222 -339.292336) (xy 90.359738 -339.270594) (xy 90.350613 -339.265518) (xy 90.329977 -339.262466)
			(xy 90.309819 -339.267832) (xy 90.301318 -339.273896) (xy 90.267632 -339.299829) (xy 90.196195 -339.345924)
			(xy 90.120687 -339.384993) (xy 90.041797 -339.416682) (xy 89.960243 -339.440701) (xy 89.87677 -339.456831)
			(xy 89.792139 -339.464925) (xy 89.74963 -339.465412) (xy 89.708522 -339.464959) (xy 89.626657 -339.457377)
			(xy 89.545841 -339.442274) (xy 89.466762 -339.41978) (xy 89.390096 -339.390087) (xy 89.316497 -339.353447)
			(xy 89.246591 -339.310173) (xy 89.180976 -339.260635) (xy 89.120211 -339.205254) (xy 89.064815 -339.144504)
			(xy 89.015259 -339.078902) (xy 88.971967 -339.009008) (xy 88.935308 -338.935418) (xy 88.905594 -338.85876)
			(xy 88.883079 -338.779687) (xy 88.867956 -338.698875) (xy 88.860352 -338.617012) (xy 88.859868 -338.575904)
			(xy 88.860448 -338.531135) (xy 88.869454 -338.44205) (xy 88.887354 -338.354319) (xy 88.913968 -338.268827)
			(xy 88.930988 -338.227416) (xy 88.934553 -338.217825) (xy 88.934554 -338.197382) (xy 88.930988 -338.187792)
			(xy 88.915211 -338.149479) (xy 88.889996 -338.070547) (xy 88.872235 -337.98961) (xy 88.862081 -337.907373)
			(xy 88.860376 -337.865974) (xy 88.859531 -337.855055) (xy 88.849881 -337.835418) (xy 88.832968 -337.821538)
			(xy 88.82253 -337.818222) (xy 88.805658 -337.813724) (xy 88.772247 -337.803561) (xy 88.755728 -337.797902)
			(xy 88.747532 -337.795379) (xy 88.730396 -337.795379) (xy 88.7222 -337.797902) (xy 88.68698 -337.809838)
			(xy 88.614971 -337.828427) (xy 88.54165 -337.84087) (xy 88.467539 -337.847078) (xy 88.430354 -337.847432)
			(xy 88.393169 -337.84708) (xy 88.319061 -337.840854) (xy 88.245741 -337.828406) (xy 88.173731 -337.809827)
			(xy 88.138508 -337.797902) (xy 88.130312 -337.795379) (xy 88.113176 -337.795379) (xy 88.10498 -337.797902)
			(xy 88.069762 -337.809843) (xy 87.997752 -337.828431) (xy 87.92443 -337.840873) (xy 87.850319 -337.847079)
			(xy 87.813134 -337.847432) (xy 87.771208 -337.846923) (xy 87.687734 -337.838955) (xy 87.605396 -337.823088)
			(xy 87.52494 -337.799467) (xy 87.447092 -337.768304) (xy 87.37256 -337.729883) (xy 87.302018 -337.68455)
			(xy 87.236104 -337.632717) (xy 87.175416 -337.574854) (xy 87.120503 -337.511483) (xy 87.071862 -337.443179)
			(xy 87.029935 -337.370561) (xy 86.9951 -337.294287) (xy 86.967674 -337.215046) (xy 86.947905 -337.133557)
			(xy 86.935971 -337.050558) (xy 86.931981 -336.9668) (xy 83.360149 -336.9668) (xy 83.364863 -337.017649)
			(xy 83.36534 -337.058762) (xy 83.364781 -337.103532) (xy 83.35577 -337.192617) (xy 83.337863 -337.280348)
			(xy 83.311243 -337.365839) (xy 83.29422 -337.40725) (xy 83.290679 -337.416847) (xy 83.290665 -337.437283)
			(xy 83.29422 -337.446874) (xy 83.311248 -337.488284) (xy 83.337884 -337.573771) (xy 83.355791 -337.661503)
			(xy 83.364787 -337.750591) (xy 83.36534 -337.795362) (xy 83.364781 -337.840132) (xy 83.35577 -337.929217)
			(xy 83.337863 -338.016948) (xy 83.311243 -338.102439) (xy 83.29422 -338.14385) (xy 83.290679 -338.153447)
			(xy 83.290665 -338.173883) (xy 83.29422 -338.183474) (xy 83.311248 -338.224884) (xy 83.337884 -338.310371)
			(xy 83.355791 -338.398103) (xy 83.364787 -338.487191) (xy 83.36534 -338.531962) (xy 83.364865 -338.573077)
			(xy 83.357281 -338.654956) (xy 83.342174 -338.735786) (xy 83.319674 -338.814878) (xy 83.289971 -338.891556)
			(xy 83.253319 -338.965166) (xy 83.210032 -339.03508) (xy 83.160479 -339.100701) (xy 83.105082 -339.16147)
			(xy 83.044313 -339.216869) (xy 82.978693 -339.266423) (xy 82.90878 -339.309712) (xy 82.83517 -339.346364)
			(xy 82.758493 -339.376068) (xy 82.679402 -339.398571) (xy 82.598572 -339.413679) (xy 82.516693 -339.421265)
			(xy 82.475578 -339.421724) (xy 82.433963 -339.421201) (xy 82.351099 -339.413386) (xy 82.269327 -339.397871)
			(xy 82.189359 -339.374793) (xy 82.111894 -339.344353) (xy 82.037608 -339.306816) (xy 82.002122 -339.285072)
			(xy 81.993008 -339.279971) (xy 81.972363 -339.276919) (xy 81.9522 -339.282299) (xy 81.943702 -339.288374)
			(xy 81.910029 -339.314336) (xy 81.838605 -339.360476) (xy 81.763103 -339.399589) (xy 81.684213 -339.431317)
			(xy 81.602655 -339.455371) (xy 81.519173 -339.47153) (xy 81.43453 -339.479647) (xy 81.392014 -339.480144)
			(xy 81.350899 -339.479688) (xy 81.269019 -339.472102) (xy 81.188189 -339.456993) (xy 81.109097 -339.434491)
			(xy 81.032419 -339.404786) (xy 80.95881 -339.368133) (xy 80.888896 -339.324845) (xy 80.823275 -339.27529)
			(xy 80.762506 -339.219892) (xy 80.707108 -339.159122) (xy 80.657553 -339.093501) (xy 80.614265 -339.023587)
			(xy 80.577612 -338.949977) (xy 80.547908 -338.873299) (xy 80.525406 -338.794207) (xy 80.510297 -338.713377)
			(xy 80.502712 -338.631497) (xy 80.502252 -338.590382) (xy 80.502826 -338.545613) (xy 80.511834 -338.456528)
			(xy 80.529735 -338.368797) (xy 80.556351 -338.283305) (xy 80.573372 -338.241894) (xy 80.576945 -338.232306)
			(xy 80.576939 -338.211861) (xy 80.573372 -338.20227) (xy 80.557588 -338.16396) (xy 80.532375 -338.085027)
			(xy 80.514616 -338.004089) (xy 80.504464 -337.921851) (xy 80.50276 -337.880452) (xy 80.501943 -337.869528)
			(xy 80.492281 -337.84989) (xy 80.475357 -337.836012) (xy 80.464914 -337.8327) (xy 80.448042 -337.828201)
			(xy 80.414631 -337.818039) (xy 80.398112 -337.81238) (xy 80.389916 -337.809857) (xy 80.37278 -337.809857)
			(xy 80.364584 -337.81238) (xy 80.329366 -337.824336) (xy 80.257364 -337.842992) (xy 80.184043 -337.855502)
			(xy 80.109928 -337.861777) (xy 80.072738 -337.862164) (xy 80.035549 -337.861761) (xy 79.961436 -337.855475)
			(xy 79.888116 -337.842969) (xy 79.81611 -337.824332) (xy 79.780892 -337.81238) (xy 79.772696 -337.809857)
			(xy 79.75556 -337.809857) (xy 79.747364 -337.81238) (xy 79.712148 -337.824342) (xy 79.640145 -337.842996)
			(xy 79.566824 -337.855505) (xy 79.492708 -337.861778) (xy 79.455518 -337.862164) (xy 79.413579 -337.861698)
			(xy 79.330081 -337.853726) (xy 79.247718 -337.837853) (xy 79.167237 -337.814224) (xy 79.089367 -337.783051)
			(xy 79.014813 -337.744616) (xy 78.94425 -337.69927) (xy 78.878316 -337.64742) (xy 78.81761 -337.589539)
			(xy 78.762681 -337.526148) (xy 78.714027 -337.457824) (xy 78.672087 -337.385183) (xy 78.637243 -337.308885)
			(xy 78.609809 -337.229621) (xy 78.590033 -337.148107) (xy 78.578096 -337.065083) (xy 78.574105 -336.9813)
			(xy 75.005252 -336.9813) (xy 75.00928 -337.024761) (xy 75.009756 -337.065874) (xy 75.009201 -337.110644)
			(xy 75.000188 -337.199729) (xy 74.982281 -337.28746) (xy 74.95566 -337.372951) (xy 74.938636 -337.414362)
			(xy 74.935088 -337.423957) (xy 74.935078 -337.444395) (xy 74.938636 -337.453986) (xy 74.955669 -337.495394)
			(xy 74.982303 -337.580882) (xy 75.000209 -337.668615) (xy 75.009203 -337.757703) (xy 75.009756 -337.802474)
			(xy 75.009201 -337.847244) (xy 75.000188 -337.936329) (xy 74.982281 -338.02406) (xy 74.95566 -338.109551)
			(xy 74.938636 -338.150962) (xy 74.935088 -338.160557) (xy 74.935078 -338.180995) (xy 74.938636 -338.190586)
			(xy 74.955669 -338.231994) (xy 74.982303 -338.317482) (xy 75.000209 -338.405215) (xy 75.009203 -338.494303)
			(xy 75.009756 -338.539074) (xy 75.009277 -338.580189) (xy 75.001692 -338.662067) (xy 74.986584 -338.742897)
			(xy 74.964083 -338.821988) (xy 74.93438 -338.898665) (xy 74.897729 -338.972274) (xy 74.854442 -339.042187)
			(xy 74.804888 -339.107809) (xy 74.749492 -339.168577) (xy 74.688724 -339.223976) (xy 74.623104 -339.27353)
			(xy 74.553192 -339.316819) (xy 74.479583 -339.353472) (xy 74.402907 -339.383177) (xy 74.323816 -339.40568)
			(xy 74.242987 -339.420789) (xy 74.161109 -339.428376) (xy 74.119994 -339.428836) (xy 74.078379 -339.428304)
			(xy 73.995516 -339.42049) (xy 73.913744 -339.404977) (xy 73.833776 -339.3819) (xy 73.756311 -339.351462)
			(xy 73.682025 -339.313927) (xy 73.646538 -339.292184) (xy 73.637413 -339.287109) (xy 73.616777 -339.284058)
			(xy 73.596619 -339.289422) (xy 73.588118 -339.295486) (xy 73.554476 -339.321488) (xy 73.483046 -339.367625)
			(xy 73.407538 -339.406732) (xy 73.328643 -339.438455) (xy 73.24708 -339.462501) (xy 73.163594 -339.478653)
			(xy 73.078947 -339.486763) (xy 73.03643 -339.487256) (xy 72.995315 -339.486773) (xy 72.913437 -339.479188)
			(xy 72.832607 -339.464081) (xy 72.753517 -339.44158) (xy 72.67684 -339.411877) (xy 72.60323 -339.375226)
			(xy 72.533317 -339.33194) (xy 72.467696 -339.282387) (xy 72.406927 -339.22699) (xy 72.351529 -339.166223)
			(xy 72.301974 -339.100603) (xy 72.258685 -339.030691) (xy 72.222032 -338.957082) (xy 72.192327 -338.880406)
			(xy 72.169824 -338.801316) (xy 72.154715 -338.720487) (xy 72.147128 -338.638609) (xy 72.146668 -338.597494)
			(xy 72.147245 -338.552725) (xy 72.156251 -338.46364) (xy 72.174152 -338.375909) (xy 72.200767 -338.290417)
			(xy 72.217788 -338.249006) (xy 72.221359 -338.239417) (xy 72.221356 -338.218972) (xy 72.217788 -338.209382)
			(xy 72.202008 -338.17107) (xy 72.176794 -338.092137) (xy 72.159033 -338.011201) (xy 72.148881 -337.928963)
			(xy 72.147176 -337.887564) (xy 72.146339 -337.876644) (xy 72.136685 -337.857006) (xy 72.119769 -337.843127)
			(xy 72.10933 -337.839812) (xy 72.092458 -337.835314) (xy 72.059047 -337.825151) (xy 72.042528 -337.819492)
			(xy 72.034332 -337.816969) (xy 72.017196 -337.816969) (xy 72.009 -337.819492) (xy 71.973781 -337.831444)
			(xy 71.901779 -337.850101) (xy 71.828459 -337.862612) (xy 71.754344 -337.868888) (xy 71.717154 -337.869276)
			(xy 71.679965 -337.868873) (xy 71.605852 -337.862587) (xy 71.532532 -337.850082) (xy 71.460526 -337.831445)
			(xy 71.425308 -337.819492) (xy 71.417112 -337.816969) (xy 71.399976 -337.816969) (xy 71.39178 -337.819492)
			(xy 71.356562 -337.83145) (xy 71.28456 -337.850105) (xy 71.211239 -337.862615) (xy 71.137124 -337.868889)
			(xy 71.099934 -337.869276) (xy 71.057995 -337.868786) (xy 70.974497 -337.860816) (xy 70.892134 -337.844945)
			(xy 70.811653 -337.821316) (xy 70.733783 -337.790144) (xy 70.659228 -337.751711) (xy 70.588664 -337.706365)
			(xy 70.522731 -337.654517) (xy 70.462025 -337.596636) (xy 70.407095 -337.533246) (xy 70.35844 -337.464922)
			(xy 70.3165 -337.392282) (xy 70.281655 -337.315985) (xy 70.254221 -337.23672) (xy 70.234446 -337.155207)
			(xy 70.222508 -337.072183) (xy 70.218517 -336.9884) (xy 23.408386 -336.9884) (xy 23.408386 -341.9277)
			(xy 103.538816 -341.9277) (xy 103.542807 -341.843921) (xy 103.554743 -341.760902) (xy 103.574517 -341.679392)
			(xy 103.601948 -341.600131) (xy 103.63679 -341.523837) (xy 103.678726 -341.4512) (xy 103.727376 -341.382878)
			(xy 103.7823 -341.319489) (xy 103.843001 -341.261608) (xy 103.908929 -341.20976) (xy 103.979486 -341.164412)
			(xy 104.054035 -341.125977) (xy 104.131899 -341.094802) (xy 104.212375 -341.071169) (xy 104.294732 -341.055293)
			(xy 104.378225 -341.047317) (xy 104.420162 -341.046816) (xy 104.457351 -341.047215) (xy 104.531464 -341.053502)
			(xy 104.604784 -341.066008) (xy 104.67679 -341.084646) (xy 104.712008 -341.0966) (xy 104.720204 -341.099123)
			(xy 104.73734 -341.099123) (xy 104.745536 -341.0966) (xy 104.791751 -341.081107) (xy 104.886744 -341.059242)
			(xy 104.983568 -341.047981) (xy 105.032302 -341.04707) (xy 105.043494 -341.046501) (xy 105.063736 -341.036937)
			(xy 105.077985 -341.01967) (xy 105.081324 -341.00897) (xy 105.090084 -340.97633) (xy 105.111951 -340.912377)
			(xy 105.125012 -340.881208) (xy 105.128629 -340.871492) (xy 105.128644 -340.850784) (xy 105.125012 -340.841076)
			(xy 105.107848 -340.799736) (xy 105.081019 -340.714336) (xy 105.062984 -340.626656) (xy 105.053927 -340.5376)
			(xy 105.053384 -340.492842) (xy 105.053883 -340.450917) (xy 105.061853 -340.367446) (xy 105.077722 -340.285111)
			(xy 105.101345 -340.204657) (xy 105.132509 -340.126813) (xy 105.170932 -340.052283) (xy 105.216265 -339.981744)
			(xy 105.268098 -339.915833) (xy 105.325961 -339.855147) (xy 105.389331 -339.800237) (xy 105.457634 -339.751599)
			(xy 105.530251 -339.709674) (xy 105.606524 -339.674841) (xy 105.685763 -339.647416) (xy 105.767249 -339.627647)
			(xy 105.850246 -339.615714) (xy 105.934002 -339.611725) (xy 106.017758 -339.615714) (xy 106.100755 -339.627647)
			(xy 106.182241 -339.647416) (xy 106.26148 -339.674841) (xy 106.337753 -339.709674) (xy 106.41037 -339.751599)
			(xy 106.478673 -339.800237) (xy 106.542043 -339.855147) (xy 106.599906 -339.915833) (xy 106.651739 -339.981744)
			(xy 106.697072 -340.052283) (xy 106.735495 -340.126813) (xy 106.766659 -340.204657) (xy 106.790282 -340.285111)
			(xy 106.806151 -340.367446) (xy 106.814121 -340.450917) (xy 106.81462 -340.492842) (xy 106.814084 -340.537601)
			(xy 106.80505 -340.626662) (xy 106.787017 -340.714344) (xy 106.760172 -340.799742) (xy 106.742992 -340.841076)
			(xy 106.739326 -340.850777) (xy 106.739342 -340.871499) (xy 106.742992 -340.881208) (xy 106.751374 -340.901528)
			(xy 106.755013 -340.909633) (xy 106.76682 -340.92289) (xy 106.782442 -340.931323) (xy 106.800005 -340.933918)
			(xy 106.808778 -340.932516) (xy 106.852626 -340.924181) (xy 106.94144 -340.915273) (xy 106.98607 -340.914736)
			(xy 107.027176 -340.915241) (xy 107.109038 -340.922823) (xy 107.189852 -340.937924) (xy 107.268928 -340.960416)
			(xy 107.345591 -340.990108) (xy 107.419189 -341.026745) (xy 107.489092 -341.070016) (xy 107.554706 -341.119551)
			(xy 107.61547 -341.174927) (xy 107.670867 -341.235674) (xy 107.720423 -341.301272) (xy 107.763716 -341.371161)
			(xy 107.800377 -341.444747) (xy 107.830093 -341.521401) (xy 107.85261 -341.60047) (xy 107.867738 -341.681278)
			(xy 107.875346 -341.763138) (xy 107.875832 -341.804244) (xy 107.875268 -341.849014) (xy 107.866258 -341.938099)
			(xy 107.848353 -342.02583) (xy 107.821735 -342.111321) (xy 107.804712 -342.152732) (xy 107.80112 -342.162315)
			(xy 107.801136 -342.182765) (xy 107.804712 -342.192356) (xy 107.821734 -342.233768) (xy 107.848372 -342.319255)
			(xy 107.86628 -342.406986) (xy 107.875278 -342.496074) (xy 107.875832 -342.540844) (xy 107.875381 -342.579473)
			(xy 107.868636 -342.656436) (xy 107.855235 -342.732523) (xy 107.83528 -342.807159) (xy 107.822492 -342.843612)
			(xy 107.819539 -342.853049) (xy 107.820333 -342.872788) (xy 107.824016 -342.881966) (xy 107.843087 -342.925345)
			(xy 107.872921 -343.015291) (xy 107.893015 -343.1079) (xy 107.90314 -343.202122) (xy 107.903772 -343.249504)
			(xy 107.903199 -343.294273) (xy 107.894192 -343.383358) (xy 107.87629 -343.471089) (xy 107.849674 -343.556581)
			(xy 107.832652 -343.597992) (xy 107.829086 -343.607582) (xy 107.829087 -343.628025) (xy 107.832652 -343.637616)
			(xy 107.849695 -343.67902) (xy 107.876327 -343.76451) (xy 107.894229 -343.852244) (xy 107.903221 -343.941333)
			(xy 107.903772 -343.986104) (xy 107.903351 -344.027216) (xy 107.895763 -344.109088) (xy 107.880651 -344.189911)
			(xy 107.858144 -344.268995) (xy 107.828436 -344.345663) (xy 107.791778 -344.419263) (xy 107.748485 -344.489166)
			(xy 107.698925 -344.554775) (xy 107.643522 -344.61553) (xy 107.582749 -344.670913) (xy 107.517123 -344.720451)
			(xy 107.447206 -344.763721) (xy 107.373594 -344.800355) (xy 107.296916 -344.830038) (xy 107.217825 -344.852518)
			(xy 107.136997 -344.867603) (xy 107.055122 -344.875165) (xy 107.01401 -344.875612) (xy 106.971444 -344.875093)
			(xy 106.8867 -344.86696) (xy 106.803121 -344.850767) (xy 106.721472 -344.826663) (xy 106.642499 -344.794868)
			(xy 106.566926 -344.755674) (xy 106.495442 -344.709437) (xy 106.428704 -344.656583) (xy 106.367321 -344.597594)
			(xy 106.311854 -344.53301) (xy 106.262812 -344.463422) (xy 106.220644 -344.389467) (xy 106.202734 -344.350848)
			(xy 106.197093 -344.340103) (xy 106.178145 -344.324993) (xy 106.166412 -344.321892) (xy 106.123833 -344.312714)
			(xy 106.040563 -344.287147) (xy 105.960191 -344.253561) (xy 105.883487 -344.212279) (xy 105.811187 -344.163696)
			(xy 105.743982 -344.108278) (xy 105.682517 -344.046555) (xy 105.627381 -343.979119) (xy 105.579102 -343.906615)
			(xy 105.538141 -343.829739) (xy 105.504893 -343.749227) (xy 105.479675 -343.665851) (xy 105.462728 -343.580408)
			(xy 105.454216 -343.493718) (xy 105.453688 -343.450164) (xy 105.454253 -343.405394) (xy 105.463263 -343.316309)
			(xy 105.481167 -343.228578) (xy 105.507785 -343.143087) (xy 105.524808 -343.101676) (xy 105.528395 -343.092092)
			(xy 105.528382 -343.071643) (xy 105.524808 -343.062052) (xy 105.508891 -343.02338) (xy 105.483531 -342.943684)
			(xy 105.46577 -342.861957) (xy 105.460292 -342.820498) (xy 105.458698 -342.810528) (xy 105.448788 -342.792957)
			(xy 105.432839 -342.780603) (xy 105.423208 -342.777572) (xy 105.40795 -342.773353) (xy 105.377717 -342.763951)
			(xy 105.362756 -342.758776) (xy 105.35456 -342.756253) (xy 105.337424 -342.756253) (xy 105.329228 -342.758776)
			(xy 105.294015 -342.770747) (xy 105.222011 -342.789399) (xy 105.148689 -342.801905) (xy 105.074572 -342.808175)
			(xy 105.037382 -342.80856) (xy 105.000192 -342.808173) (xy 104.926079 -342.801882) (xy 104.85276 -342.789372)
			(xy 104.780754 -342.770731) (xy 104.745536 -342.758776) (xy 104.73734 -342.756253) (xy 104.720204 -342.756253)
			(xy 104.712008 -342.758776) (xy 104.676797 -342.770753) (xy 104.604792 -342.789403) (xy 104.531469 -342.801908)
			(xy 104.457353 -342.808176) (xy 104.420162 -342.80856) (xy 104.378225 -342.808083) (xy 104.294732 -342.800107)
			(xy 104.212375 -342.784231) (xy 104.131899 -342.760598) (xy 104.054035 -342.729423) (xy 103.979486 -342.690988)
			(xy 103.908929 -342.64564) (xy 103.843001 -342.593792) (xy 103.7823 -342.535911) (xy 103.727376 -342.472522)
			(xy 103.678726 -342.4042) (xy 103.63679 -342.331563) (xy 103.601948 -342.255269) (xy 103.574517 -342.176008)
			(xy 103.554743 -342.094498) (xy 103.542807 -342.011479) (xy 103.538816 -341.9277) (xy 23.408386 -341.9277)
			(xy 23.408386 -342.73109) (xy 23.408712 -342.738897) (xy 23.413502 -342.753763) (xy 23.417784 -342.7603)
			(xy 23.434038 -342.784081) (xy 23.459792 -342.835604) (xy 23.477295 -342.89048) (xy 23.486128 -342.947399)
			(xy 23.486618 -342.9762) (xy 23.486078 -343.004996) (xy 23.47722 -343.061904) (xy 23.45973 -343.116776)
			(xy 23.434022 -343.168313) (xy 23.417784 -343.1921) (xy 23.413481 -343.198627) (xy 23.40869 -343.213499)
			(xy 23.408386 -343.22131) (xy 23.408386 -345.237562) (xy 88.42502 -345.237562) (xy 88.425476 -345.196455)
			(xy 88.433064 -345.114592) (xy 88.448171 -345.033778) (xy 88.470668 -344.954703) (xy 88.500364 -344.87804)
			(xy 88.537005 -344.804443) (xy 88.58028 -344.73454) (xy 88.629818 -344.668927) (xy 88.685198 -344.608163)
			(xy 88.745947 -344.552768) (xy 88.811546 -344.503212) (xy 88.881438 -344.459919) (xy 88.955025 -344.423259)
			(xy 89.031681 -344.393542) (xy 89.110751 -344.371024) (xy 89.19156 -344.355896) (xy 89.273421 -344.348287)
			(xy 89.314528 -344.3478) (xy 89.358923 -344.348358) (xy 89.447268 -344.357247) (xy 89.534288 -344.374894)
			(xy 89.619117 -344.401123) (xy 89.660222 -344.417904) (xy 89.668919 -344.421068) (xy 89.687398 -344.421734)
			(xy 89.69629 -344.419174) (xy 89.742575 -344.404089) (xy 89.837607 -344.382956) (xy 89.934379 -344.372329)
			(xy 89.983056 -344.371676) (xy 90.021341 -344.372048) (xy 90.09763 -344.378592) (xy 90.173072 -344.391678)
			(xy 90.247108 -344.411209) (xy 90.283284 -344.423746) (xy 90.291721 -344.426397) (xy 90.309391 -344.426397)
			(xy 90.317828 -344.423746) (xy 90.35401 -344.411232) (xy 90.428049 -344.391722) (xy 90.503488 -344.378639)
			(xy 90.579773 -344.372079) (xy 90.618056 -344.371676) (xy 90.664451 -344.372276) (xy 90.756739 -344.381916)
			(xy 90.847523 -344.401107) (xy 90.935817 -344.429641) (xy 90.978482 -344.447876) (xy 90.988424 -344.451682)
			(xy 91.009688 -344.451682) (xy 91.01963 -344.447876) (xy 91.062298 -344.429645) (xy 91.150588 -344.401097)
			(xy 91.241371 -344.381901) (xy 91.33366 -344.372263) (xy 91.380056 -344.371676) (xy 91.418341 -344.372048)
			(xy 91.49463 -344.378592) (xy 91.570072 -344.391678) (xy 91.644108 -344.411209) (xy 91.680284 -344.423746)
			(xy 91.688721 -344.426397) (xy 91.706391 -344.426397) (xy 91.714828 -344.423746) (xy 91.75101 -344.411232)
			(xy 91.825049 -344.391722) (xy 91.900488 -344.378639) (xy 91.976773 -344.372079) (xy 92.015056 -344.371676)
			(xy 92.053341 -344.372048) (xy 92.12963 -344.378592) (xy 92.205072 -344.391678) (xy 92.279108 -344.411209)
			(xy 92.315284 -344.423746) (xy 92.323721 -344.426397) (xy 92.341391 -344.426397) (xy 92.349828 -344.423746)
			(xy 92.38601 -344.411232) (xy 92.460049 -344.391722) (xy 92.535488 -344.378639) (xy 92.611773 -344.372079)
			(xy 92.650056 -344.371676) (xy 92.691158 -344.372194) (xy 92.773012 -344.379775) (xy 92.853817 -344.394876)
			(xy 92.932883 -344.417369) (xy 93.009537 -344.447061) (xy 93.083125 -344.4837) (xy 93.153018 -344.526972)
			(xy 93.21862 -344.576508) (xy 93.279371 -344.631887) (xy 93.334753 -344.692634) (xy 93.384294 -344.758233)
			(xy 93.427571 -344.828123) (xy 93.464215 -344.901708) (xy 93.493912 -344.97836) (xy 93.51641 -345.057425)
			(xy 93.531517 -345.138229) (xy 93.539103 -345.220082) (xy 93.539564 -345.261184) (xy 93.53916 -345.301746)
			(xy 93.531819 -345.382537) (xy 93.517144 -345.462323) (xy 93.495255 -345.540438) (xy 93.466335 -345.616232)
			(xy 93.448886 -345.652852) (xy 93.444878 -345.661912) (xy 93.443456 -345.681655) (xy 93.446092 -345.691206)
			(xy 93.460291 -345.736227) (xy 93.480181 -345.828513) (xy 93.490178 -345.922387) (xy 93.490796 -345.96959)
			(xy 93.490238 -346.015229) (xy 93.480936 -346.106032) (xy 93.462388 -346.195406) (xy 93.44914 -346.239084)
			(xy 93.446675 -346.248093) (xy 93.44772 -346.266727) (xy 93.451172 -346.275406) (xy 93.469867 -346.318487)
			(xy 93.49915 -346.407722) (xy 93.518862 -346.499547) (xy 93.528784 -346.592938) (xy 93.529404 -346.639896)
			(xy 93.528944 -346.681007) (xy 93.521356 -346.762877) (xy 93.506246 -346.843698) (xy 93.483741 -346.92278)
			(xy 93.454034 -346.999447) (xy 93.417379 -347.073045) (xy 93.374088 -347.142947) (xy 93.324531 -347.208555)
			(xy 93.269131 -347.26931) (xy 93.20836 -347.324693) (xy 93.142737 -347.374232) (xy 93.072823 -347.417503)
			(xy 92.999214 -347.454137) (xy 92.922539 -347.483822) (xy 92.843451 -347.506304) (xy 92.762626 -347.521391)
			(xy 92.680753 -347.528955) (xy 92.639642 -347.529404) (xy 92.601357 -347.529034) (xy 92.525068 -347.52249)
			(xy 92.449626 -347.509403) (xy 92.37559 -347.489871) (xy 92.339414 -347.477334) (xy 92.330977 -347.474683)
			(xy 92.313307 -347.474683) (xy 92.30487 -347.477334) (xy 92.268688 -347.489847) (xy 92.194649 -347.509358)
			(xy 92.119209 -347.522442) (xy 92.042925 -347.529001) (xy 92.004642 -347.529404) (xy 91.961524 -347.528886)
			(xy 91.875691 -347.520542) (xy 91.79107 -347.503927) (xy 91.708455 -347.479198) (xy 91.668346 -347.463364)
			(xy 91.658975 -347.460038) (xy 91.639109 -347.460038) (xy 91.629738 -347.463364) (xy 91.589624 -347.479187)
			(xy 91.507011 -347.50392) (xy 91.422391 -347.520541) (xy 91.33656 -347.528893) (xy 91.293442 -347.529404)
			(xy 91.255157 -347.529034) (xy 91.178868 -347.52249) (xy 91.103426 -347.509403) (xy 91.02939 -347.489871)
			(xy 90.993214 -347.477334) (xy 90.984777 -347.474683) (xy 90.967107 -347.474683) (xy 90.95867 -347.477334)
			(xy 90.922488 -347.489847) (xy 90.848449 -347.509358) (xy 90.773009 -347.522442) (xy 90.696725 -347.529001)
			(xy 90.658442 -347.529404) (xy 90.620157 -347.529034) (xy 90.543868 -347.52249) (xy 90.468426 -347.509403)
			(xy 90.39439 -347.489871) (xy 90.358214 -347.477334) (xy 90.349777 -347.474683) (xy 90.332107 -347.474683)
			(xy 90.32367 -347.477334) (xy 90.287488 -347.489847) (xy 90.213449 -347.509358) (xy 90.138009 -347.522442)
			(xy 90.061725 -347.529001) (xy 90.023442 -347.529404) (xy 89.985157 -347.529034) (xy 89.908868 -347.52249)
			(xy 89.833426 -347.509403) (xy 89.75939 -347.489871) (xy 89.723214 -347.477334) (xy 89.714777 -347.474683)
			(xy 89.697107 -347.474683) (xy 89.68867 -347.477334) (xy 89.652488 -347.489847) (xy 89.578449 -347.509358)
			(xy 89.503009 -347.522442) (xy 89.426725 -347.529001) (xy 89.388442 -347.529404) (xy 89.347337 -347.528847)
			(xy 89.265478 -347.521267) (xy 89.184667 -347.506168) (xy 89.105593 -347.483678) (xy 89.028932 -347.453989)
			(xy 88.955336 -347.417355) (xy 88.885433 -347.374087) (xy 88.81982 -347.324556) (xy 88.759057 -347.269183)
			(xy 88.70366 -347.20844) (xy 88.654104 -347.142846) (xy 88.61081 -347.07296) (xy 88.574148 -346.999378)
			(xy 88.54443 -346.922728) (xy 88.52191 -346.843663) (xy 88.506779 -346.762857) (xy 88.499168 -346.681001)
			(xy 88.49868 -346.639896) (xy 88.49928 -346.594251) (xy 88.508675 -346.503445) (xy 88.527305 -346.414075)
			(xy 88.54059 -346.370402) (xy 88.543068 -346.361395) (xy 88.542016 -346.342759) (xy 88.538558 -346.33408)
			(xy 88.519895 -346.290993) (xy 88.490688 -346.201748) (xy 88.471043 -346.109924) (xy 88.461176 -346.016541)
			(xy 88.46058 -345.96959) (xy 88.460997 -345.930463) (xy 88.467845 -345.852508) (xy 88.481506 -345.775455)
			(xy 88.501874 -345.699897) (xy 88.514936 -345.663012) (xy 88.517951 -345.653293) (xy 88.516917 -345.632991)
			(xy 88.512904 -345.623642) (xy 88.496009 -345.587453) (xy 88.467989 -345.512656) (xy 88.446785 -345.43565)
			(xy 88.432566 -345.357053) (xy 88.425448 -345.277498) (xy 88.42502 -345.237562) (xy 23.408386 -345.237562)
			(xy 23.408386 -345.319096) (xy 23.408808 -345.329167) (xy 23.41652 -345.347774) (xy 23.423372 -345.355164)
			(xy 24.055578 -345.98737) (xy 24.072839 -346.00541) (xy 24.100599 -346.046903) (xy 24.119713 -346.093021)
			(xy 24.129443 -346.141986) (xy 24.13 -346.166948) (xy 24.13 -348.70949) (xy 28.410141 -348.70949)
			(xy 28.414132 -348.625708) (xy 28.426069 -348.542686) (xy 28.445844 -348.461173) (xy 28.473277 -348.38191)
			(xy 28.508121 -348.305613) (xy 28.550059 -348.232974) (xy 28.598712 -348.16465) (xy 28.65364 -348.101261)
			(xy 28.714345 -348.043379) (xy 28.780276 -347.99153) (xy 28.850838 -347.946183) (xy 28.92539 -347.907749)
			(xy 29.003259 -347.876576) (xy 29.083738 -347.852945) (xy 29.166099 -347.837072) (xy 29.249596 -347.829099)
			(xy 29.291534 -347.828616) (xy 29.328723 -347.829023) (xy 29.402836 -347.835307) (xy 29.476156 -347.847812)
			(xy 29.548162 -347.866448) (xy 29.58338 -347.8784) (xy 29.591576 -347.880923) (xy 29.608712 -347.880923)
			(xy 29.616908 -347.8784) (xy 29.658685 -347.864329) (xy 29.744376 -347.84362) (xy 29.831705 -347.831558)
			(xy 29.875734 -347.829378) (xy 29.88701 -347.828307) (xy 29.907032 -347.817779) (xy 29.920624 -347.799697)
			(xy 29.923486 -347.788738) (xy 29.932967 -347.744976) (xy 29.959558 -347.659468) (xy 29.976572 -347.61805)
			(xy 29.980113 -347.608453) (xy 29.980127 -347.588017) (xy 29.976572 -347.578426) (xy 29.959544 -347.537016)
			(xy 29.932908 -347.451529) (xy 29.915001 -347.363797) (xy 29.906005 -347.274709) (xy 29.905452 -347.229938)
			(xy 29.905888 -347.189346) (xy 29.913291 -347.108501) (xy 29.928029 -347.028666) (xy 29.949981 -346.950507)
			(xy 29.978963 -346.874673) (xy 30.014735 -346.801795) (xy 30.056998 -346.73248) (xy 30.105401 -346.667304)
			(xy 30.159542 -346.60681) (xy 30.218969 -346.5515) (xy 30.283189 -346.501836) (xy 30.351667 -346.45823)
			(xy 30.387544 -346.439236) (xy 30.396074 -346.434297) (xy 30.408824 -346.419289) (xy 30.414958 -346.400576)
			(xy 30.414722 -346.390722) (xy 30.41396 -346.365322) (xy 30.414481 -346.337437) (xy 30.422793 -346.28229)
			(xy 30.439231 -346.228998) (xy 30.463429 -346.178752) (xy 30.494845 -346.132673) (xy 30.532778 -346.091791)
			(xy 30.57638 -346.057019) (xy 30.624678 -346.029134) (xy 30.676593 -346.008759) (xy 30.730964 -345.996349)
			(xy 30.786578 -345.992182) (xy 30.842192 -345.996349) (xy 30.896563 -346.008759) (xy 30.948478 -346.029134)
			(xy 30.996776 -346.057019) (xy 31.040378 -346.091791) (xy 31.078311 -346.132673) (xy 31.109727 -346.178752)
			(xy 31.133925 -346.228998) (xy 31.150363 -346.28229) (xy 31.158675 -346.337437) (xy 31.159196 -346.365322)
			(xy 31.158688 -346.383356) (xy 31.15866 -346.393249) (xy 31.165282 -346.411875) (xy 31.178455 -346.426614)
			(xy 31.187136 -346.431362) (xy 31.224041 -346.449965) (xy 31.294555 -346.49308) (xy 31.360766 -346.542551)
			(xy 31.4221 -346.597952) (xy 31.47803 -346.658805) (xy 31.528073 -346.724585) (xy 31.571797 -346.794724)
			(xy 31.608825 -346.868616) (xy 31.638837 -346.945626) (xy 31.661575 -347.025088) (xy 31.676842 -347.106317)
			(xy 31.684507 -347.188612) (xy 31.684976 -347.229938) (xy 31.684414 -347.274708) (xy 31.675404 -347.363793)
			(xy 31.657499 -347.451524) (xy 31.630879 -347.537015) (xy 31.613856 -347.578426) (xy 31.61027 -347.58801)
			(xy 31.610284 -347.608459) (xy 31.613856 -347.61805) (xy 31.630031 -347.657368) (xy 31.655701 -347.738424)
			(xy 31.673532 -347.821557) (xy 31.68336 -347.906011) (xy 31.684722 -347.948504) (xy 31.684976 -347.96222)
			(xy 31.6992 -347.985588) (xy 31.801054 -348.040706) (xy 31.828232 -348.039944) (xy 31.84017 -348.032578)
			(xy 31.875522 -348.010993) (xy 31.949529 -347.973778) (xy 32.026677 -347.943609) (xy 32.106297 -347.920748)
			(xy 32.187699 -347.905393) (xy 32.270176 -347.897677) (xy 32.311594 -347.897196) (xy 32.352707 -347.897719)
			(xy 32.434582 -347.905305) (xy 32.515408 -347.920413) (xy 32.594495 -347.942914) (xy 32.671169 -347.972616)
			(xy 32.744775 -348.009266) (xy 32.814686 -348.05255) (xy 32.880304 -348.102101) (xy 32.941071 -348.157495)
			(xy 32.996468 -348.218259) (xy 33.046022 -348.283875) (xy 33.089311 -348.353783) (xy 33.125965 -348.427387)
			(xy 33.155671 -348.504059) (xy 33.178176 -348.583145) (xy 33.193289 -348.66397) (xy 33.197509 -348.70949)
			(xy 36.690541 -348.70949) (xy 36.694532 -348.625708) (xy 36.706469 -348.542686) (xy 36.726244 -348.461173)
			(xy 36.753677 -348.38191) (xy 36.788521 -348.305613) (xy 36.830459 -348.232974) (xy 36.879112 -348.16465)
			(xy 36.93404 -348.101261) (xy 36.994745 -348.043379) (xy 37.060676 -347.99153) (xy 37.131238 -347.946183)
			(xy 37.20579 -347.907749) (xy 37.283659 -347.876576) (xy 37.364138 -347.852945) (xy 37.446499 -347.837072)
			(xy 37.529996 -347.829099) (xy 37.571934 -347.828616) (xy 37.609123 -347.829023) (xy 37.683236 -347.835307)
			(xy 37.756556 -347.847812) (xy 37.828562 -347.866448) (xy 37.86378 -347.8784) (xy 37.871976 -347.880923)
			(xy 37.889112 -347.880923) (xy 37.897308 -347.8784) (xy 37.935448 -347.865479) (xy 38.013548 -347.845826)
			(xy 38.093117 -347.833397) (xy 38.133274 -347.830394) (xy 38.144263 -347.829135) (xy 38.163705 -347.818647)
			(xy 38.176935 -347.800955) (xy 38.179756 -347.790262) (xy 38.189168 -347.74808) (xy 38.215125 -347.665638)
			(xy 38.231572 -347.62567) (xy 38.235159 -347.616086) (xy 38.235144 -347.595637) (xy 38.231572 -347.586046)
			(xy 38.21455 -347.544634) (xy 38.187912 -347.459147) (xy 38.170004 -347.371416) (xy 38.161006 -347.282328)
			(xy 38.160452 -347.237558) (xy 38.160956 -347.195197) (xy 38.169009 -347.11086) (xy 38.185043 -347.02767)
			(xy 38.208911 -346.94638) (xy 38.240399 -346.867728) (xy 38.279221 -346.792425) (xy 38.325024 -346.721153)
			(xy 38.377395 -346.654557) (xy 38.43586 -346.593242) (xy 38.499888 -346.537761) (xy 38.5689 -346.488618)
			(xy 38.64227 -346.446258) (xy 38.719335 -346.411063) (xy 38.799397 -346.383354) (xy 38.88173 -346.36338)
			(xy 38.965589 -346.351323) (xy 39.050214 -346.347292) (xy 39.134839 -346.351323) (xy 39.218698 -346.36338)
			(xy 39.301031 -346.383354) (xy 39.381093 -346.411063) (xy 39.458158 -346.446258) (xy 39.531528 -346.488618)
			(xy 39.60054 -346.537761) (xy 39.664568 -346.593242) (xy 39.723033 -346.654557) (xy 39.775404 -346.721153)
			(xy 39.821207 -346.792425) (xy 39.860029 -346.867728) (xy 39.891517 -346.94638) (xy 39.915385 -347.02767)
			(xy 39.931419 -347.11086) (xy 39.939472 -347.195197) (xy 39.939976 -347.237558) (xy 39.939421 -347.282328)
			(xy 39.930409 -347.371413) (xy 39.912502 -347.459144) (xy 39.88588 -347.544635) (xy 39.868856 -347.586046)
			(xy 39.865315 -347.595644) (xy 39.8653 -347.61608) (xy 39.868856 -347.62567) (xy 39.885384 -347.665905)
			(xy 39.911453 -347.748896) (xy 39.92929 -347.834036) (xy 39.938724 -347.920512) (xy 39.939722 -347.963998)
			(xy 39.939976 -347.977968) (xy 39.954454 -348.001844) (xy 40.05834 -348.056454) (xy 40.08628 -348.05493)
			(xy 40.09771 -348.04731) (xy 40.134305 -348.023444) (xy 40.211348 -347.98223) (xy 40.292061 -347.948768)
			(xy 40.375665 -347.923381) (xy 40.461356 -347.906311) (xy 40.548307 -347.897725) (xy 40.591994 -347.897196)
			(xy 40.633107 -347.897719) (xy 40.714982 -347.905305) (xy 40.795808 -347.920413) (xy 40.874895 -347.942914)
			(xy 40.951569 -347.972616) (xy 41.025175 -348.009266) (xy 41.095086 -348.05255) (xy 41.160704 -348.102101)
			(xy 41.221471 -348.157495) (xy 41.276868 -348.218259) (xy 41.326422 -348.283875) (xy 41.369711 -348.353783)
			(xy 41.406365 -348.427387) (xy 41.436071 -348.504059) (xy 41.458576 -348.583145) (xy 41.473689 -348.66397)
			(xy 41.47791 -348.7095) (xy 44.996301 -348.7095) (xy 45.000292 -348.625716) (xy 45.01223 -348.54269)
			(xy 45.032006 -348.461175) (xy 45.05944 -348.381909) (xy 45.094286 -348.30561) (xy 45.136227 -348.232969)
			(xy 45.184883 -348.164644) (xy 45.239813 -348.101253) (xy 45.30052 -348.043371) (xy 45.366455 -347.991522)
			(xy 45.43702 -347.946175) (xy 45.511576 -347.907741) (xy 45.589448 -347.876568) (xy 45.66993 -347.852939)
			(xy 45.752294 -347.837068) (xy 45.835794 -347.829098) (xy 45.877734 -347.828616) (xy 45.914923 -347.829023)
			(xy 45.989036 -347.835307) (xy 46.062356 -347.847812) (xy 46.134362 -347.866448) (xy 46.16958 -347.8784)
			(xy 46.177776 -347.880923) (xy 46.194912 -347.880923) (xy 46.203108 -347.8784) (xy 46.244357 -347.864476)
			(xy 46.328947 -347.843861) (xy 46.415158 -347.831701) (xy 46.458632 -347.829378) (xy 46.469417 -347.828405)
			(xy 46.488732 -347.818658) (xy 46.502367 -347.80186) (xy 46.505622 -347.791532) (xy 46.514117 -347.760219)
			(xy 46.535095 -347.698817) (xy 46.547532 -347.66885) (xy 46.551076 -347.659253) (xy 46.55109 -347.638816)
			(xy 46.547532 -347.629226) (xy 46.530501 -347.587817) (xy 46.503866 -347.502329) (xy 46.485961 -347.414597)
			(xy 46.476965 -347.325509) (xy 46.476412 -347.280738) (xy 46.476916 -347.238377) (xy 46.484969 -347.15404)
			(xy 46.501003 -347.07085) (xy 46.524871 -346.98956) (xy 46.556359 -346.910908) (xy 46.595181 -346.835605)
			(xy 46.640984 -346.764333) (xy 46.693355 -346.697737) (xy 46.75182 -346.636422) (xy 46.815848 -346.580941)
			(xy 46.88486 -346.531798) (xy 46.95823 -346.489438) (xy 47.035295 -346.454243) (xy 47.115357 -346.426534)
			(xy 47.19769 -346.40656) (xy 47.281549 -346.394503) (xy 47.366174 -346.390472) (xy 47.450799 -346.394503)
			(xy 47.534658 -346.40656) (xy 47.616991 -346.426534) (xy 47.697053 -346.454243) (xy 47.774118 -346.489438)
			(xy 47.847488 -346.531798) (xy 47.9165 -346.580941) (xy 47.980528 -346.636422) (xy 48.038993 -346.697737)
			(xy 48.091364 -346.764333) (xy 48.137167 -346.835605) (xy 48.175989 -346.910908) (xy 48.207477 -346.98956)
			(xy 48.231345 -347.07085) (xy 48.247379 -347.15404) (xy 48.255432 -347.238377) (xy 48.255936 -347.280738)
			(xy 48.25537 -347.325508) (xy 48.24636 -347.414592) (xy 48.228456 -347.502324) (xy 48.201838 -347.587815)
			(xy 48.184816 -347.629226) (xy 48.181232 -347.638811) (xy 48.181246 -347.659259) (xy 48.184816 -347.66885)
			(xy 48.199304 -347.703977) (xy 48.222973 -347.776187) (xy 48.2404 -347.850153) (xy 48.251457 -347.925335)
			(xy 48.254158 -347.963236) (xy 48.25492 -347.976952) (xy 48.269906 -347.999558) (xy 48.372776 -348.051374)
			(xy 48.3997 -348.04985) (xy 48.41113 -348.04223) (xy 48.447343 -348.019182) (xy 48.523387 -347.979349)
			(xy 48.602912 -347.947022) (xy 48.685181 -347.922504) (xy 48.769429 -347.90602) (xy 48.854872 -347.897725)
			(xy 48.897794 -347.897196) (xy 48.938907 -347.897719) (xy 49.020782 -347.905305) (xy 49.101608 -347.920413)
			(xy 49.180695 -347.942914) (xy 49.257369 -347.972616) (xy 49.330975 -348.009266) (xy 49.400886 -348.05255)
			(xy 49.466504 -348.102101) (xy 49.527271 -348.157495) (xy 49.582668 -348.218259) (xy 49.632222 -348.283875)
			(xy 49.675511 -348.353783) (xy 49.712165 -348.427387) (xy 49.741871 -348.504059) (xy 49.764376 -348.583145)
			(xy 49.779489 -348.66397) (xy 49.78371 -348.7095) (xy 53.352901 -348.7095) (xy 53.356892 -348.625716)
			(xy 53.36883 -348.54269) (xy 53.388606 -348.461175) (xy 53.41604 -348.381909) (xy 53.450886 -348.30561)
			(xy 53.492827 -348.232969) (xy 53.541483 -348.164644) (xy 53.596413 -348.101253) (xy 53.65712 -348.043371)
			(xy 53.723055 -347.991522) (xy 53.79362 -347.946175) (xy 53.868176 -347.907741) (xy 53.946048 -347.876568)
			(xy 54.02653 -347.852939) (xy 54.108894 -347.837068) (xy 54.192394 -347.829098) (xy 54.234334 -347.828616)
			(xy 54.271523 -347.829023) (xy 54.345636 -347.835307) (xy 54.418956 -347.847812) (xy 54.490962 -347.866448)
			(xy 54.52618 -347.8784) (xy 54.534376 -347.880923) (xy 54.551512 -347.880923) (xy 54.559708 -347.8784)
			(xy 54.600957 -347.864476) (xy 54.685547 -347.843861) (xy 54.771758 -347.831701) (xy 54.815232 -347.829378)
			(xy 54.826186 -347.828354) (xy 54.84574 -347.818319) (xy 54.859356 -347.801066) (xy 54.862476 -347.790516)
			(xy 54.871519 -347.754203) (xy 54.894919 -347.683115) (xy 54.909212 -347.64853) (xy 54.912768 -347.638937)
			(xy 54.912774 -347.618496) (xy 54.909212 -347.608906) (xy 54.892173 -347.5675) (xy 54.865541 -347.482011)
			(xy 54.847637 -347.394278) (xy 54.838644 -347.305189) (xy 54.838092 -347.260418) (xy 54.838596 -347.218057)
			(xy 54.846649 -347.13372) (xy 54.862683 -347.05053) (xy 54.886551 -346.96924) (xy 54.918039 -346.890588)
			(xy 54.956861 -346.815285) (xy 55.002664 -346.744013) (xy 55.055035 -346.677417) (xy 55.1135 -346.616102)
			(xy 55.177528 -346.560621) (xy 55.24654 -346.511478) (xy 55.31991 -346.469118) (xy 55.396975 -346.433923)
			(xy 55.477037 -346.406214) (xy 55.55937 -346.38624) (xy 55.643229 -346.374183) (xy 55.727854 -346.370152)
			(xy 55.812479 -346.374183) (xy 55.896338 -346.38624) (xy 55.978671 -346.406214) (xy 56.058733 -346.433923)
			(xy 56.135798 -346.469118) (xy 56.209168 -346.511478) (xy 56.27818 -346.560621) (xy 56.342208 -346.616102)
			(xy 56.400673 -346.677417) (xy 56.453044 -346.744013) (xy 56.498847 -346.815285) (xy 56.537669 -346.890588)
			(xy 56.569157 -346.96924) (xy 56.593025 -347.05053) (xy 56.609059 -347.13372) (xy 56.617112 -347.218057)
			(xy 56.617616 -347.260418) (xy 56.617044 -347.305187) (xy 56.608037 -347.394272) (xy 56.590134 -347.482003)
			(xy 56.563518 -347.567495) (xy 56.546496 -347.608906) (xy 56.542919 -347.618493) (xy 56.542926 -347.63894)
			(xy 56.546496 -347.64853) (xy 56.561684 -347.685398) (xy 56.586189 -347.761282) (xy 56.603812 -347.839053)
			(xy 56.614411 -347.918088) (xy 56.6166 -347.957902) (xy 56.617108 -347.971364) (xy 56.63184 -347.994478)
			(xy 56.734456 -348.04731) (xy 56.761634 -348.04604) (xy 56.773064 -348.038674) (xy 56.808981 -348.016152)
			(xy 56.88432 -347.977266) (xy 56.963017 -347.945725) (xy 57.044358 -347.921816) (xy 57.127605 -347.905754)
			(xy 57.212003 -347.897686) (xy 57.254394 -347.897196) (xy 57.295507 -347.897719) (xy 57.377382 -347.905305)
			(xy 57.458208 -347.920413) (xy 57.537295 -347.942914) (xy 57.613969 -347.972616) (xy 57.687575 -348.009266)
			(xy 57.757486 -348.05255) (xy 57.823104 -348.102101) (xy 57.883871 -348.157495) (xy 57.939268 -348.218259)
			(xy 57.988822 -348.283875) (xy 58.032111 -348.353783) (xy 58.068765 -348.427387) (xy 58.098471 -348.504059)
			(xy 58.120976 -348.583145) (xy 58.136089 -348.66397) (xy 58.14031 -348.7095) (xy 61.684101 -348.7095)
			(xy 61.688092 -348.625716) (xy 61.70003 -348.54269) (xy 61.719806 -348.461175) (xy 61.74724 -348.381909)
			(xy 61.782086 -348.30561) (xy 61.824027 -348.232969) (xy 61.872683 -348.164644) (xy 61.927613 -348.101253)
			(xy 61.98832 -348.043371) (xy 62.054255 -347.991522) (xy 62.12482 -347.946175) (xy 62.199376 -347.907741)
			(xy 62.277248 -347.876568) (xy 62.35773 -347.852939) (xy 62.440094 -347.837068) (xy 62.523594 -347.829098)
			(xy 62.565534 -347.828616) (xy 62.602723 -347.829023) (xy 62.676836 -347.835307) (xy 62.750156 -347.847812)
			(xy 62.822162 -347.866448) (xy 62.85738 -347.8784) (xy 62.865576 -347.880923) (xy 62.882712 -347.880923)
			(xy 62.890908 -347.8784) (xy 62.93563 -347.863377) (xy 63.027487 -347.841848) (xy 63.121119 -347.830251)
			(xy 63.168276 -347.82887) (xy 63.179057 -347.82822) (xy 63.198555 -347.818959) (xy 63.212545 -347.802521)
			(xy 63.216028 -347.792294) (xy 63.223799 -347.76642) (xy 63.242101 -347.715585) (xy 63.252604 -347.690694)
			(xy 63.256229 -347.680981) (xy 63.25624 -347.66027) (xy 63.252604 -347.650562) (xy 63.235435 -347.609224)
			(xy 63.208608 -347.523823) (xy 63.190573 -347.436143) (xy 63.181518 -347.347086) (xy 63.180976 -347.302328)
			(xy 63.181475 -347.260403) (xy 63.189445 -347.176932) (xy 63.205314 -347.094597) (xy 63.228937 -347.014143)
			(xy 63.260101 -346.936299) (xy 63.298524 -346.861769) (xy 63.343857 -346.79123) (xy 63.39569 -346.725319)
			(xy 63.453553 -346.664633) (xy 63.516923 -346.609723) (xy 63.585226 -346.561085) (xy 63.657843 -346.51916)
			(xy 63.734116 -346.484327) (xy 63.813355 -346.456902) (xy 63.894841 -346.437133) (xy 63.977838 -346.4252)
			(xy 64.061594 -346.421211) (xy 64.14535 -346.4252) (xy 64.228347 -346.437133) (xy 64.309833 -346.456902)
			(xy 64.389072 -346.484327) (xy 64.465345 -346.51916) (xy 64.537962 -346.561085) (xy 64.606265 -346.609723)
			(xy 64.669635 -346.664633) (xy 64.727498 -346.725319) (xy 64.779331 -346.79123) (xy 64.824664 -346.861769)
			(xy 64.863087 -346.936299) (xy 64.894251 -347.014143) (xy 64.917874 -347.094597) (xy 64.933743 -347.176932)
			(xy 64.941713 -347.260403) (xy 64.942212 -347.302328) (xy 64.941672 -347.347087) (xy 64.932639 -347.436147)
			(xy 64.914607 -347.52383) (xy 64.887763 -347.609228) (xy 64.870584 -347.650562) (xy 64.866927 -347.660266)
			(xy 64.866937 -347.680985) (xy 64.870584 -347.690694) (xy 64.888862 -347.734789) (xy 64.91689 -347.826038)
			(xy 64.934892 -347.919782) (xy 64.939418 -347.9673) (xy 64.940434 -347.980762) (xy 64.95542 -348.00286)
			(xy 65.058544 -348.053152) (xy 65.08496 -348.051374) (xy 65.096644 -348.043754) (xy 65.132959 -348.020439)
			(xy 65.209305 -347.980191) (xy 65.289189 -347.947525) (xy 65.371861 -347.922748) (xy 65.456544 -347.906093)
			(xy 65.542442 -347.897716) (xy 65.585594 -347.897196) (xy 65.626707 -347.897719) (xy 65.708582 -347.905305)
			(xy 65.789408 -347.920413) (xy 65.868495 -347.942914) (xy 65.945169 -347.972616) (xy 66.018775 -348.009266)
			(xy 66.088686 -348.05255) (xy 66.154304 -348.102101) (xy 66.215071 -348.157495) (xy 66.270468 -348.218259)
			(xy 66.320022 -348.283875) (xy 66.363311 -348.353783) (xy 66.399965 -348.427387) (xy 66.429671 -348.504059)
			(xy 66.452176 -348.583145) (xy 66.467289 -348.66397) (xy 66.474879 -348.745845) (xy 66.475356 -348.786958)
			(xy 66.474795 -348.831728) (xy 66.467942 -348.89948) (xy 81.294224 -348.89948) (xy 81.294687 -348.858913)
			(xy 81.30208 -348.778118) (xy 81.316804 -348.698332) (xy 81.338734 -348.620219) (xy 81.36769 -348.544429)
			(xy 81.385156 -348.507812) (xy 81.389129 -348.49874) (xy 81.390571 -348.479008) (xy 81.38795 -348.469458)
			(xy 81.37371 -348.424443) (xy 81.353732 -348.332162) (xy 81.343651 -348.238283) (xy 81.342992 -348.191074)
			(xy 81.343496 -348.148713) (xy 81.351549 -348.064376) (xy 81.367583 -347.981186) (xy 81.391451 -347.899896)
			(xy 81.422939 -347.821244) (xy 81.461761 -347.745941) (xy 81.507564 -347.674669) (xy 81.559935 -347.608073)
			(xy 81.6184 -347.546758) (xy 81.682428 -347.491277) (xy 81.75144 -347.442134) (xy 81.82481 -347.399774)
			(xy 81.901875 -347.364579) (xy 81.981937 -347.33687) (xy 82.06427 -347.316896) (xy 82.148129 -347.304839)
			(xy 82.232754 -347.300808) (xy 82.317379 -347.304839) (xy 82.401238 -347.316896) (xy 82.483571 -347.33687)
			(xy 82.563633 -347.364579) (xy 82.640698 -347.399774) (xy 82.714068 -347.442134) (xy 82.78308 -347.491277)
			(xy 82.847108 -347.546758) (xy 82.905573 -347.608073) (xy 82.957944 -347.674669) (xy 83.003747 -347.745941)
			(xy 83.042569 -347.821244) (xy 83.074057 -347.899896) (xy 83.097925 -347.981186) (xy 83.113959 -348.064376)
			(xy 83.122012 -348.148713) (xy 83.122516 -348.191074) (xy 83.12207 -348.231641) (xy 83.114672 -348.312437)
			(xy 83.099945 -348.392223) (xy 83.07801 -348.470336) (xy 83.049051 -348.546125) (xy 83.031584 -348.582742)
			(xy 83.027581 -348.591804) (xy 83.026156 -348.611545) (xy 83.02879 -348.621096) (xy 83.043017 -348.666115)
			(xy 83.063 -348.758394) (xy 83.073086 -348.852272) (xy 83.073748 -348.89948) (xy 83.073141 -348.945125)
			(xy 83.063748 -349.035931) (xy 83.045121 -349.1253) (xy 83.031838 -349.168974) (xy 83.029379 -349.177985)
			(xy 83.03042 -349.196616) (xy 83.03387 -349.205296) (xy 83.052527 -349.248385) (xy 83.081735 -349.337629)
			(xy 83.101382 -349.429453) (xy 83.111251 -349.522835) (xy 83.111848 -349.569786) (xy 83.111412 -349.610119)
			(xy 83.104141 -349.690457) (xy 83.08963 -349.769807) (xy 83.067997 -349.847519) (xy 83.039422 -349.922954)
			(xy 83.022186 -349.959422) (xy 83.017736 -349.970094) (xy 83.017755 -349.993189) (xy 83.022186 -350.003872)
			(xy 83.039408 -350.040291) (xy 83.067973 -350.115623) (xy 83.089602 -350.193232) (xy 83.104117 -350.27248)
			(xy 83.111401 -350.352717) (xy 83.111848 -350.393) (xy 83.111344 -350.435361) (xy 83.103291 -350.519698)
			(xy 83.087257 -350.602888) (xy 83.063389 -350.684178) (xy 83.031901 -350.76283) (xy 82.993079 -350.838133)
			(xy 82.947276 -350.909405) (xy 82.894905 -350.976001) (xy 82.83644 -351.037316) (xy 82.772412 -351.092797)
			(xy 82.7034 -351.14194) (xy 82.63003 -351.1843) (xy 82.552965 -351.219495) (xy 82.472903 -351.247204)
			(xy 82.39057 -351.267178) (xy 82.306711 -351.279235) (xy 82.222086 -351.283267) (xy 82.137461 -351.279235)
			(xy 82.053602 -351.267178) (xy 81.971269 -351.247204) (xy 81.891207 -351.219495) (xy 81.814142 -351.1843)
			(xy 81.740772 -351.14194) (xy 81.67176 -351.092797) (xy 81.607732 -351.037316) (xy 81.549267 -350.976001)
			(xy 81.496896 -350.909405) (xy 81.451093 -350.838133) (xy 81.412271 -350.76283) (xy 81.380783 -350.684178)
			(xy 81.356915 -350.602888) (xy 81.340881 -350.519698) (xy 81.332828 -350.435361) (xy 81.332324 -350.393)
			(xy 81.332778 -350.35266) (xy 81.340081 -350.272312) (xy 81.354637 -350.192956) (xy 81.376326 -350.115246)
			(xy 81.404968 -350.039822) (xy 81.42224 -350.003364) (xy 81.426812 -349.992711) (xy 81.426828 -349.969558)
			(xy 81.42224 -349.958914) (xy 81.405059 -349.922483) (xy 81.376548 -349.847143) (xy 81.35497 -349.769534)
			(xy 81.340501 -349.69029) (xy 81.33326 -349.610063) (xy 81.332832 -349.569786) (xy 81.333382 -349.524146)
			(xy 81.342687 -349.433343) (xy 81.361239 -349.34397) (xy 81.374488 -349.300292) (xy 81.376971 -349.291286)
			(xy 81.375916 -349.272649) (xy 81.372456 -349.26397) (xy 81.353748 -349.220894) (xy 81.32447 -349.131657)
			(xy 81.304762 -349.039831) (xy 81.294843 -348.946439) (xy 81.294224 -348.89948) (xy 66.467942 -348.89948)
			(xy 66.465784 -348.920813) (xy 66.447878 -349.008544) (xy 66.421259 -349.094035) (xy 66.404236 -349.135446)
			(xy 66.400697 -349.145044) (xy 66.400681 -349.16548) (xy 66.404236 -349.17507) (xy 66.421263 -349.21648)
			(xy 66.4479 -349.301967) (xy 66.465806 -349.3897) (xy 66.474803 -349.478787) (xy 66.475356 -349.523558)
			(xy 66.474795 -349.568328) (xy 66.465784 -349.657413) (xy 66.447878 -349.745144) (xy 66.421259 -349.830635)
			(xy 66.404236 -349.872046) (xy 66.400697 -349.881644) (xy 66.400681 -349.90208) (xy 66.404236 -349.91167)
			(xy 66.421263 -349.95308) (xy 66.4479 -350.038567) (xy 66.465806 -350.1263) (xy 66.474803 -350.215387)
			(xy 66.475356 -350.260158) (xy 66.474861 -350.301272) (xy 66.467278 -350.383151) (xy 66.452172 -350.46398)
			(xy 66.429672 -350.54307) (xy 66.39997 -350.619748) (xy 66.36332 -350.693357) (xy 66.320034 -350.76327)
			(xy 66.270482 -350.828891) (xy 66.215086 -350.88966) (xy 66.154319 -350.945059) (xy 66.0887 -350.994614)
			(xy 66.018788 -351.037902) (xy 65.94518 -351.074555) (xy 65.868505 -351.10426) (xy 65.789415 -351.126764)
			(xy 65.708586 -351.141873) (xy 65.626708 -351.14946) (xy 65.585594 -351.14992) (xy 65.543979 -351.14939)
			(xy 65.461116 -351.141576) (xy 65.379344 -351.126063) (xy 65.299376 -351.102986) (xy 65.221911 -351.072547)
			(xy 65.147624 -351.035012) (xy 65.112138 -351.013268) (xy 65.103017 -351.008182) (xy 65.082377 -351.005125)
			(xy 65.062216 -351.010498) (xy 65.053718 -351.01657) (xy 65.020074 -351.04257) (xy 64.948645 -351.088707)
			(xy 64.873137 -351.127815) (xy 64.794242 -351.159538) (xy 64.712679 -351.183585) (xy 64.629193 -351.199737)
			(xy 64.544547 -351.207847) (xy 64.50203 -351.20834) (xy 64.460915 -351.207873) (xy 64.379035 -351.200288)
			(xy 64.298205 -351.185181) (xy 64.219114 -351.162679) (xy 64.142436 -351.132976) (xy 64.068826 -351.096324)
			(xy 63.998912 -351.053036) (xy 63.93329 -351.003482) (xy 63.872521 -350.948084) (xy 63.817123 -350.887316)
			(xy 63.767568 -350.821695) (xy 63.72428 -350.751781) (xy 63.687628 -350.678172) (xy 63.657923 -350.601494)
			(xy 63.635421 -350.522403) (xy 63.620313 -350.441573) (xy 63.612727 -350.359693) (xy 63.612268 -350.318578)
			(xy 63.61284 -350.273809) (xy 63.621847 -350.184724) (xy 63.63975 -350.096993) (xy 63.666366 -350.011501)
			(xy 63.683388 -349.97009) (xy 63.686968 -349.960503) (xy 63.68696 -349.940056) (xy 63.683388 -349.930466)
			(xy 63.667603 -349.892156) (xy 63.642391 -349.813223) (xy 63.624631 -349.732285) (xy 63.61448 -349.650047)
			(xy 63.612776 -349.608648) (xy 63.61195 -349.597726) (xy 63.602291 -349.578089) (xy 63.585371 -349.56421)
			(xy 63.57493 -349.560896) (xy 63.558058 -349.556397) (xy 63.524647 -349.546235) (xy 63.508128 -349.540576)
			(xy 63.499932 -349.538053) (xy 63.482796 -349.538053) (xy 63.4746 -349.540576) (xy 63.43938 -349.552528)
			(xy 63.367379 -349.571185) (xy 63.294059 -349.583696) (xy 63.219944 -349.589972) (xy 63.182754 -349.59036)
			(xy 63.145565 -349.589952) (xy 63.071452 -349.583667) (xy 62.998133 -349.571163) (xy 62.926126 -349.552528)
			(xy 62.890908 -349.540576) (xy 62.882712 -349.538053) (xy 62.865576 -349.538053) (xy 62.85738 -349.540576)
			(xy 62.822162 -349.552533) (xy 62.75016 -349.571189) (xy 62.676839 -349.583699) (xy 62.602724 -349.589973)
			(xy 62.565534 -349.59036) (xy 62.523594 -349.589902) (xy 62.440094 -349.581932) (xy 62.35773 -349.566061)
			(xy 62.277248 -349.542432) (xy 62.199376 -349.511259) (xy 62.12482 -349.472825) (xy 62.054255 -349.427478)
			(xy 61.98832 -349.375629) (xy 61.927613 -349.317747) (xy 61.872683 -349.254356) (xy 61.824027 -349.186031)
			(xy 61.782086 -349.11339) (xy 61.74724 -349.037091) (xy 61.719806 -348.957825) (xy 61.70003 -348.87631)
			(xy 61.688092 -348.793284) (xy 61.684101 -348.7095) (xy 58.14031 -348.7095) (xy 58.143679 -348.745845)
			(xy 58.144156 -348.786958) (xy 58.143595 -348.831728) (xy 58.134584 -348.920813) (xy 58.116678 -349.008544)
			(xy 58.090059 -349.094035) (xy 58.073036 -349.135446) (xy 58.069497 -349.145044) (xy 58.069481 -349.16548)
			(xy 58.073036 -349.17507) (xy 58.090063 -349.21648) (xy 58.1167 -349.301967) (xy 58.134606 -349.3897)
			(xy 58.143603 -349.478787) (xy 58.144156 -349.523558) (xy 58.143595 -349.568328) (xy 58.134584 -349.657413)
			(xy 58.116678 -349.745144) (xy 58.090059 -349.830635) (xy 58.073036 -349.872046) (xy 58.069497 -349.881644)
			(xy 58.069481 -349.90208) (xy 58.073036 -349.91167) (xy 58.090063 -349.95308) (xy 58.1167 -350.038567)
			(xy 58.134606 -350.1263) (xy 58.143603 -350.215387) (xy 58.144156 -350.260158) (xy 58.143661 -350.301272)
			(xy 58.136078 -350.383151) (xy 58.120972 -350.46398) (xy 58.098472 -350.54307) (xy 58.06877 -350.619748)
			(xy 58.03212 -350.693357) (xy 57.988834 -350.76327) (xy 57.939282 -350.828891) (xy 57.883886 -350.88966)
			(xy 57.823119 -350.945059) (xy 57.7575 -350.994614) (xy 57.687588 -351.037902) (xy 57.61398 -351.074555)
			(xy 57.537305 -351.10426) (xy 57.458215 -351.126764) (xy 57.377386 -351.141873) (xy 57.295508 -351.14946)
			(xy 57.254394 -351.14992) (xy 57.212779 -351.14939) (xy 57.129916 -351.141576) (xy 57.048144 -351.126063)
			(xy 56.968176 -351.102986) (xy 56.890711 -351.072547) (xy 56.816424 -351.035012) (xy 56.780938 -351.013268)
			(xy 56.771817 -351.008182) (xy 56.751177 -351.005125) (xy 56.731016 -351.010498) (xy 56.722518 -351.01657)
			(xy 56.688874 -351.04257) (xy 56.617445 -351.088707) (xy 56.541937 -351.127815) (xy 56.463042 -351.159538)
			(xy 56.381479 -351.183585) (xy 56.297993 -351.199737) (xy 56.213347 -351.207847) (xy 56.17083 -351.20834)
			(xy 56.129715 -351.207873) (xy 56.047835 -351.200288) (xy 55.967005 -351.185181) (xy 55.887914 -351.162679)
			(xy 55.811236 -351.132976) (xy 55.737626 -351.096324) (xy 55.667712 -351.053036) (xy 55.60209 -351.003482)
			(xy 55.541321 -350.948084) (xy 55.485923 -350.887316) (xy 55.436368 -350.821695) (xy 55.39308 -350.751781)
			(xy 55.356428 -350.678172) (xy 55.326723 -350.601494) (xy 55.304221 -350.522403) (xy 55.289113 -350.441573)
			(xy 55.281527 -350.359693) (xy 55.281068 -350.318578) (xy 55.28164 -350.273809) (xy 55.290647 -350.184724)
			(xy 55.30855 -350.096993) (xy 55.335166 -350.011501) (xy 55.352188 -349.97009) (xy 55.355768 -349.960503)
			(xy 55.35576 -349.940056) (xy 55.352188 -349.930466) (xy 55.336403 -349.892156) (xy 55.311191 -349.813223)
			(xy 55.293431 -349.732285) (xy 55.28328 -349.650047) (xy 55.281576 -349.608648) (xy 55.28075 -349.597726)
			(xy 55.271091 -349.578089) (xy 55.254171 -349.56421) (xy 55.24373 -349.560896) (xy 55.226858 -349.556397)
			(xy 55.193447 -349.546235) (xy 55.176928 -349.540576) (xy 55.168732 -349.538053) (xy 55.151596 -349.538053)
			(xy 55.1434 -349.540576) (xy 55.10818 -349.552528) (xy 55.036179 -349.571185) (xy 54.962859 -349.583696)
			(xy 54.888744 -349.589972) (xy 54.851554 -349.59036) (xy 54.814365 -349.589952) (xy 54.740252 -349.583667)
			(xy 54.666933 -349.571163) (xy 54.594926 -349.552528) (xy 54.559708 -349.540576) (xy 54.551512 -349.538053)
			(xy 54.534376 -349.538053) (xy 54.52618 -349.540576) (xy 54.490962 -349.552533) (xy 54.41896 -349.571189)
			(xy 54.345639 -349.583699) (xy 54.271524 -349.589973) (xy 54.234334 -349.59036) (xy 54.192394 -349.589902)
			(xy 54.108894 -349.581932) (xy 54.02653 -349.566061) (xy 53.946048 -349.542432) (xy 53.868176 -349.511259)
			(xy 53.79362 -349.472825) (xy 53.723055 -349.427478) (xy 53.65712 -349.375629) (xy 53.596413 -349.317747)
			(xy 53.541483 -349.254356) (xy 53.492827 -349.186031) (xy 53.450886 -349.11339) (xy 53.41604 -349.037091)
			(xy 53.388606 -348.957825) (xy 53.36883 -348.87631) (xy 53.356892 -348.793284) (xy 53.352901 -348.7095)
			(xy 49.78371 -348.7095) (xy 49.787079 -348.745845) (xy 49.787556 -348.786958) (xy 49.786995 -348.831728)
			(xy 49.777984 -348.920813) (xy 49.760078 -349.008544) (xy 49.733459 -349.094035) (xy 49.716436 -349.135446)
			(xy 49.712897 -349.145044) (xy 49.712881 -349.16548) (xy 49.716436 -349.17507) (xy 49.733463 -349.21648)
			(xy 49.7601 -349.301967) (xy 49.778006 -349.3897) (xy 49.787003 -349.478787) (xy 49.787556 -349.523558)
			(xy 49.786995 -349.568328) (xy 49.777984 -349.657413) (xy 49.760078 -349.745144) (xy 49.733459 -349.830635)
			(xy 49.716436 -349.872046) (xy 49.712897 -349.881644) (xy 49.712881 -349.90208) (xy 49.716436 -349.91167)
			(xy 49.733463 -349.95308) (xy 49.7601 -350.038567) (xy 49.778006 -350.1263) (xy 49.787003 -350.215387)
			(xy 49.787556 -350.260158) (xy 49.787061 -350.301272) (xy 49.779478 -350.383151) (xy 49.764372 -350.46398)
			(xy 49.741872 -350.54307) (xy 49.71217 -350.619748) (xy 49.67552 -350.693357) (xy 49.632234 -350.76327)
			(xy 49.582682 -350.828891) (xy 49.527286 -350.88966) (xy 49.466519 -350.945059) (xy 49.4009 -350.994614)
			(xy 49.330988 -351.037902) (xy 49.25738 -351.074555) (xy 49.180705 -351.10426) (xy 49.101615 -351.126764)
			(xy 49.020786 -351.141873) (xy 48.938908 -351.14946) (xy 48.897794 -351.14992) (xy 48.856179 -351.14939)
			(xy 48.773316 -351.141576) (xy 48.691544 -351.126063) (xy 48.611576 -351.102986) (xy 48.534111 -351.072547)
			(xy 48.459824 -351.035012) (xy 48.424338 -351.013268) (xy 48.415217 -351.008182) (xy 48.394577 -351.005125)
			(xy 48.374416 -351.010498) (xy 48.365918 -351.01657) (xy 48.332274 -351.04257) (xy 48.260845 -351.088707)
			(xy 48.185337 -351.127815) (xy 48.106442 -351.159538) (xy 48.024879 -351.183585) (xy 47.941393 -351.199737)
			(xy 47.856747 -351.207847) (xy 47.81423 -351.20834) (xy 47.773115 -351.207873) (xy 47.691235 -351.200288)
			(xy 47.610405 -351.185181) (xy 47.531314 -351.162679) (xy 47.454636 -351.132976) (xy 47.381026 -351.096324)
			(xy 47.311112 -351.053036) (xy 47.24549 -351.003482) (xy 47.184721 -350.948084) (xy 47.129323 -350.887316)
			(xy 47.079768 -350.821695) (xy 47.03648 -350.751781) (xy 46.999828 -350.678172) (xy 46.970123 -350.601494)
			(xy 46.947621 -350.522403) (xy 46.932513 -350.441573) (xy 46.924927 -350.359693) (xy 46.924468 -350.318578)
			(xy 46.92504 -350.273809) (xy 46.934047 -350.184724) (xy 46.95195 -350.096993) (xy 46.978566 -350.011501)
			(xy 46.995588 -349.97009) (xy 46.999168 -349.960503) (xy 46.99916 -349.940056) (xy 46.995588 -349.930466)
			(xy 46.979803 -349.892156) (xy 46.954591 -349.813223) (xy 46.936831 -349.732285) (xy 46.92668 -349.650047)
			(xy 46.924976 -349.608648) (xy 46.92415 -349.597726) (xy 46.914491 -349.578089) (xy 46.897571 -349.56421)
			(xy 46.88713 -349.560896) (xy 46.870258 -349.556397) (xy 46.836847 -349.546235) (xy 46.820328 -349.540576)
			(xy 46.812132 -349.538053) (xy 46.794996 -349.538053) (xy 46.7868 -349.540576) (xy 46.75158 -349.552528)
			(xy 46.679579 -349.571185) (xy 46.606259 -349.583696) (xy 46.532144 -349.589972) (xy 46.494954 -349.59036)
			(xy 46.457765 -349.589952) (xy 46.383652 -349.583667) (xy 46.310333 -349.571163) (xy 46.238326 -349.552528)
			(xy 46.203108 -349.540576) (xy 46.194912 -349.538053) (xy 46.177776 -349.538053) (xy 46.16958 -349.540576)
			(xy 46.134362 -349.552533) (xy 46.06236 -349.571189) (xy 45.989039 -349.583699) (xy 45.914924 -349.589973)
			(xy 45.877734 -349.59036) (xy 45.835794 -349.589902) (xy 45.752294 -349.581932) (xy 45.66993 -349.566061)
			(xy 45.589448 -349.542432) (xy 45.511576 -349.511259) (xy 45.43702 -349.472825) (xy 45.366455 -349.427478)
			(xy 45.30052 -349.375629) (xy 45.239813 -349.317747) (xy 45.184883 -349.254356) (xy 45.136227 -349.186031)
			(xy 45.094286 -349.11339) (xy 45.05944 -349.037091) (xy 45.032006 -348.957825) (xy 45.01223 -348.87631)
			(xy 45.000292 -348.793284) (xy 44.996301 -348.7095) (xy 41.47791 -348.7095) (xy 41.481279 -348.745845)
			(xy 41.481756 -348.786958) (xy 41.481195 -348.831728) (xy 41.472184 -348.920813) (xy 41.454278 -349.008544)
			(xy 41.427659 -349.094035) (xy 41.410636 -349.135446) (xy 41.407097 -349.145044) (xy 41.407081 -349.16548)
			(xy 41.410636 -349.17507) (xy 41.427663 -349.21648) (xy 41.4543 -349.301967) (xy 41.472206 -349.3897)
			(xy 41.481203 -349.478787) (xy 41.481756 -349.523558) (xy 41.481195 -349.568328) (xy 41.472184 -349.657413)
			(xy 41.454278 -349.745144) (xy 41.427659 -349.830635) (xy 41.410636 -349.872046) (xy 41.407097 -349.881644)
			(xy 41.407081 -349.90208) (xy 41.410636 -349.91167) (xy 41.427663 -349.95308) (xy 41.4543 -350.038567)
			(xy 41.472206 -350.1263) (xy 41.481203 -350.215387) (xy 41.481756 -350.260158) (xy 41.481261 -350.301272)
			(xy 41.473678 -350.383151) (xy 41.458572 -350.46398) (xy 41.436072 -350.54307) (xy 41.40637 -350.619748)
			(xy 41.36972 -350.693357) (xy 41.326434 -350.76327) (xy 41.276882 -350.828891) (xy 41.221486 -350.88966)
			(xy 41.160719 -350.945059) (xy 41.0951 -350.994614) (xy 41.025188 -351.037902) (xy 40.95158 -351.074555)
			(xy 40.874905 -351.10426) (xy 40.795815 -351.126764) (xy 40.714986 -351.141873) (xy 40.633108 -351.14946)
			(xy 40.591994 -351.14992) (xy 40.550379 -351.14939) (xy 40.467516 -351.141576) (xy 40.385744 -351.126063)
			(xy 40.305776 -351.102986) (xy 40.228311 -351.072547) (xy 40.154024 -351.035012) (xy 40.118538 -351.013268)
			(xy 40.109417 -351.008182) (xy 40.088777 -351.005125) (xy 40.068616 -351.010498) (xy 40.060118 -351.01657)
			(xy 40.026474 -351.04257) (xy 39.955045 -351.088707) (xy 39.879537 -351.127815) (xy 39.800642 -351.159538)
			(xy 39.719079 -351.183585) (xy 39.635593 -351.199737) (xy 39.550947 -351.207847) (xy 39.50843 -351.20834)
			(xy 39.467315 -351.207873) (xy 39.385435 -351.200288) (xy 39.304605 -351.185181) (xy 39.225514 -351.162679)
			(xy 39.148836 -351.132976) (xy 39.075226 -351.096324) (xy 39.005312 -351.053036) (xy 38.93969 -351.003482)
			(xy 38.878921 -350.948084) (xy 38.823523 -350.887316) (xy 38.773968 -350.821695) (xy 38.73068 -350.751781)
			(xy 38.694028 -350.678172) (xy 38.664323 -350.601494) (xy 38.641821 -350.522403) (xy 38.626713 -350.441573)
			(xy 38.619127 -350.359693) (xy 38.618668 -350.318578) (xy 38.61924 -350.273809) (xy 38.628247 -350.184724)
			(xy 38.64615 -350.096993) (xy 38.672766 -350.011501) (xy 38.689788 -349.97009) (xy 38.693368 -349.960503)
			(xy 38.69336 -349.940056) (xy 38.689788 -349.930466) (xy 38.674003 -349.892156) (xy 38.648791 -349.813223)
			(xy 38.631031 -349.732285) (xy 38.62088 -349.650047) (xy 38.619176 -349.608648) (xy 38.61835 -349.597726)
			(xy 38.608691 -349.578089) (xy 38.591771 -349.56421) (xy 38.58133 -349.560896) (xy 38.564458 -349.556397)
			(xy 38.531047 -349.546235) (xy 38.514528 -349.540576) (xy 38.506332 -349.538053) (xy 38.489196 -349.538053)
			(xy 38.481 -349.540576) (xy 38.44578 -349.552528) (xy 38.373779 -349.571185) (xy 38.300459 -349.583696)
			(xy 38.226344 -349.589972) (xy 38.189154 -349.59036) (xy 38.151965 -349.589952) (xy 38.077852 -349.583667)
			(xy 38.004533 -349.571163) (xy 37.932526 -349.552528) (xy 37.897308 -349.540576) (xy 37.889112 -349.538053)
			(xy 37.871976 -349.538053) (xy 37.86378 -349.540576) (xy 37.828562 -349.552533) (xy 37.75656 -349.571189)
			(xy 37.683239 -349.583699) (xy 37.609124 -349.589973) (xy 37.571934 -349.59036) (xy 37.529996 -349.589881)
			(xy 37.446499 -349.581908) (xy 37.364138 -349.566035) (xy 37.283659 -349.542404) (xy 37.20579 -349.511231)
			(xy 37.131238 -349.472797) (xy 37.060676 -349.42745) (xy 36.994745 -349.375601) (xy 36.93404 -349.317719)
			(xy 36.879112 -349.25433) (xy 36.830459 -349.186006) (xy 36.788521 -349.113367) (xy 36.753677 -349.03707)
			(xy 36.726244 -348.957807) (xy 36.706469 -348.876294) (xy 36.694532 -348.793272) (xy 36.690541 -348.70949)
			(xy 33.197509 -348.70949) (xy 33.200879 -348.745845) (xy 33.201356 -348.786958) (xy 33.200795 -348.831728)
			(xy 33.191784 -348.920813) (xy 33.173878 -349.008544) (xy 33.147259 -349.094035) (xy 33.130236 -349.135446)
			(xy 33.126697 -349.145044) (xy 33.126681 -349.16548) (xy 33.130236 -349.17507) (xy 33.147263 -349.21648)
			(xy 33.1739 -349.301967) (xy 33.191806 -349.3897) (xy 33.200803 -349.478787) (xy 33.201356 -349.523558)
			(xy 33.200795 -349.568328) (xy 33.191784 -349.657413) (xy 33.173878 -349.745144) (xy 33.147259 -349.830635)
			(xy 33.130236 -349.872046) (xy 33.126697 -349.881644) (xy 33.126681 -349.90208) (xy 33.130236 -349.91167)
			(xy 33.147263 -349.95308) (xy 33.1739 -350.038567) (xy 33.191806 -350.1263) (xy 33.200803 -350.215387)
			(xy 33.201356 -350.260158) (xy 33.200861 -350.301272) (xy 33.193278 -350.383151) (xy 33.178172 -350.46398)
			(xy 33.155672 -350.54307) (xy 33.12597 -350.619748) (xy 33.08932 -350.693357) (xy 33.046034 -350.76327)
			(xy 32.996482 -350.828891) (xy 32.941086 -350.88966) (xy 32.880319 -350.945059) (xy 32.8147 -350.994614)
			(xy 32.744788 -351.037902) (xy 32.67118 -351.074555) (xy 32.594505 -351.10426) (xy 32.515415 -351.126764)
			(xy 32.434586 -351.141873) (xy 32.352708 -351.14946) (xy 32.311594 -351.14992) (xy 32.269979 -351.14939)
			(xy 32.187116 -351.141576) (xy 32.105344 -351.126063) (xy 32.025376 -351.102986) (xy 31.947911 -351.072547)
			(xy 31.873624 -351.035012) (xy 31.838138 -351.013268) (xy 31.829017 -351.008182) (xy 31.808377 -351.005125)
			(xy 31.788216 -351.010498) (xy 31.779718 -351.01657) (xy 31.746074 -351.04257) (xy 31.674645 -351.088707)
			(xy 31.599137 -351.127815) (xy 31.520242 -351.159538) (xy 31.438679 -351.183585) (xy 31.355193 -351.199737)
			(xy 31.270547 -351.207847) (xy 31.22803 -351.20834) (xy 31.186915 -351.207873) (xy 31.105035 -351.200288)
			(xy 31.024205 -351.185181) (xy 30.945114 -351.162679) (xy 30.868436 -351.132976) (xy 30.794826 -351.096324)
			(xy 30.724912 -351.053036) (xy 30.65929 -351.003482) (xy 30.598521 -350.948084) (xy 30.543123 -350.887316)
			(xy 30.493568 -350.821695) (xy 30.45028 -350.751781) (xy 30.413628 -350.678172) (xy 30.383923 -350.601494)
			(xy 30.361421 -350.522403) (xy 30.346313 -350.441573) (xy 30.338727 -350.359693) (xy 30.338268 -350.318578)
			(xy 30.33884 -350.273809) (xy 30.347847 -350.184724) (xy 30.36575 -350.096993) (xy 30.392366 -350.011501)
			(xy 30.409388 -349.97009) (xy 30.412968 -349.960503) (xy 30.41296 -349.940056) (xy 30.409388 -349.930466)
			(xy 30.393603 -349.892156) (xy 30.368391 -349.813223) (xy 30.350631 -349.732285) (xy 30.34048 -349.650047)
			(xy 30.338776 -349.608648) (xy 30.33795 -349.597726) (xy 30.328291 -349.578089) (xy 30.311371 -349.56421)
			(xy 30.30093 -349.560896) (xy 30.284058 -349.556397) (xy 30.250647 -349.546235) (xy 30.234128 -349.540576)
			(xy 30.225932 -349.538053) (xy 30.208796 -349.538053) (xy 30.2006 -349.540576) (xy 30.16538 -349.552528)
			(xy 30.093379 -349.571185) (xy 30.020059 -349.583696) (xy 29.945944 -349.589972) (xy 29.908754 -349.59036)
			(xy 29.871565 -349.589952) (xy 29.797452 -349.583667) (xy 29.724133 -349.571163) (xy 29.652126 -349.552528)
			(xy 29.616908 -349.540576) (xy 29.608712 -349.538053) (xy 29.591576 -349.538053) (xy 29.58338 -349.540576)
			(xy 29.548162 -349.552533) (xy 29.47616 -349.571189) (xy 29.402839 -349.583699) (xy 29.328724 -349.589973)
			(xy 29.291534 -349.59036) (xy 29.249596 -349.589881) (xy 29.166099 -349.581908) (xy 29.083738 -349.566035)
			(xy 29.003259 -349.542404) (xy 28.92539 -349.511231) (xy 28.850838 -349.472797) (xy 28.780276 -349.42745)
			(xy 28.714345 -349.375601) (xy 28.65364 -349.317719) (xy 28.598712 -349.25433) (xy 28.550059 -349.186006)
			(xy 28.508121 -349.113367) (xy 28.473277 -349.03707) (xy 28.445844 -348.957807) (xy 28.426069 -348.876294)
			(xy 28.414132 -348.793272) (xy 28.410141 -348.70949) (xy 24.13 -348.70949) (xy 24.13 -351.12071)
			(xy 24.130425 -351.130779) (xy 24.138142 -351.149381) (xy 24.144986 -351.156778) (xy 24.626062 -351.637854)
			(xy 73.92162 -351.637854) (xy 73.922073 -351.597287) (xy 73.929469 -351.516491) (xy 73.944194 -351.436705)
			(xy 73.966127 -351.358593) (xy 73.995085 -351.282803) (xy 74.012552 -351.246186) (xy 74.016539 -351.237119)
			(xy 74.017973 -351.217383) (xy 74.015346 -351.207832) (xy 74.001124 -351.162812) (xy 73.98114 -351.070533)
			(xy 73.971051 -350.976656) (xy 73.970388 -350.929448) (xy 73.970892 -350.887087) (xy 73.978945 -350.80275)
			(xy 73.994979 -350.71956) (xy 74.018847 -350.63827) (xy 74.050335 -350.559618) (xy 74.089157 -350.484315)
			(xy 74.13496 -350.413043) (xy 74.187331 -350.346447) (xy 74.245796 -350.285132) (xy 74.309824 -350.229651)
			(xy 74.378836 -350.180508) (xy 74.452206 -350.138148) (xy 74.529271 -350.102953) (xy 74.609333 -350.075244)
			(xy 74.691666 -350.05527) (xy 74.775525 -350.043213) (xy 74.86015 -350.039182) (xy 74.944775 -350.043213)
			(xy 75.028634 -350.05527) (xy 75.110967 -350.075244) (xy 75.191029 -350.102953) (xy 75.268094 -350.138148)
			(xy 75.341464 -350.180508) (xy 75.410476 -350.229651) (xy 75.474504 -350.285132) (xy 75.532969 -350.346447)
			(xy 75.58534 -350.413043) (xy 75.631143 -350.484315) (xy 75.669965 -350.559618) (xy 75.701453 -350.63827)
			(xy 75.725321 -350.71956) (xy 75.741355 -350.80275) (xy 75.749408 -350.887087) (xy 75.749912 -350.929448)
			(xy 75.749456 -350.970015) (xy 75.742061 -351.05081) (xy 75.727336 -351.130596) (xy 75.705403 -351.208709)
			(xy 75.676446 -351.284499) (xy 75.65898 -351.321116) (xy 75.654992 -351.330183) (xy 75.653558 -351.34992)
			(xy 75.656186 -351.35947) (xy 75.670409 -351.40449) (xy 75.690393 -351.496768) (xy 75.700481 -351.590646)
			(xy 75.700605 -351.5995) (xy 76.58354 -351.5995) (xy 76.583977 -351.558938) (xy 76.59131 -351.478148)
			(xy 76.605978 -351.398363) (xy 76.62786 -351.320247) (xy 76.656772 -351.244452) (xy 76.674218 -351.207832)
			(xy 76.67818 -351.198756) (xy 76.679631 -351.179027) (xy 76.677012 -351.169478) (xy 76.662834 -351.124451)
			(xy 76.642936 -351.032168) (xy 76.632931 -350.938296) (xy 76.632308 -350.891094) (xy 76.632812 -350.848746)
			(xy 76.640863 -350.764432) (xy 76.656892 -350.681266) (xy 76.680753 -350.599999) (xy 76.712232 -350.521369)
			(xy 76.751043 -350.446088) (xy 76.796833 -350.374836) (xy 76.849189 -350.30826) (xy 76.907637 -350.246962)
			(xy 76.971647 -350.191497) (xy 77.040639 -350.142368) (xy 77.113989 -350.100019) (xy 77.191032 -350.064835)
			(xy 77.271071 -350.037133) (xy 77.35338 -350.017165) (xy 77.437215 -350.005112) (xy 77.521816 -350.001082)
			(xy 77.606417 -350.005112) (xy 77.690252 -350.017165) (xy 77.772561 -350.037133) (xy 77.8526 -350.064835)
			(xy 77.929643 -350.100019) (xy 78.002993 -350.142368) (xy 78.071985 -350.191497) (xy 78.135995 -350.246962)
			(xy 78.194443 -350.30826) (xy 78.246799 -350.374836) (xy 78.292589 -350.446088) (xy 78.3314 -350.521369)
			(xy 78.362879 -350.599999) (xy 78.38674 -350.681266) (xy 78.402769 -350.764432) (xy 78.41082 -350.848746)
			(xy 78.411324 -350.891094) (xy 78.410888 -350.931656) (xy 78.403556 -351.012446) (xy 78.388887 -351.092231)
			(xy 78.367006 -351.170347) (xy 78.338092 -351.246142) (xy 78.320646 -351.282762) (xy 78.316687 -351.291839)
			(xy 78.315236 -351.311567) (xy 78.317852 -351.321116) (xy 78.332052 -351.366136) (xy 78.351942 -351.458423)
			(xy 78.361938 -351.552297) (xy 78.362556 -351.5995) (xy 78.362003 -351.645139) (xy 78.352699 -351.735943)
			(xy 78.334149 -351.825316) (xy 78.3209 -351.868994) (xy 78.318425 -351.878002) (xy 78.319475 -351.896637)
			(xy 78.322932 -351.905316) (xy 78.341634 -351.948394) (xy 78.370914 -352.03763) (xy 78.390624 -352.129456)
			(xy 78.400545 -352.222848) (xy 78.401164 -352.269806) (xy 78.400618 -352.312751) (xy 78.392322 -352.39824)
			(xy 78.375839 -352.482535) (xy 78.351319 -352.564851) (xy 78.335632 -352.604832) (xy 78.332357 -352.614145)
			(xy 78.33236 -352.633871) (xy 78.335632 -352.643186) (xy 78.351338 -352.683162) (xy 78.375884 -352.765474)
			(xy 78.392373 -352.84977) (xy 78.400651 -352.935265) (xy 78.401164 -352.978212) (xy 78.40066 -353.020573)
			(xy 78.392607 -353.10491) (xy 78.376573 -353.1881) (xy 78.352705 -353.26939) (xy 78.321217 -353.348042)
			(xy 78.282395 -353.423345) (xy 78.236592 -353.494617) (xy 78.184221 -353.561213) (xy 78.125756 -353.622528)
			(xy 78.061728 -353.678009) (xy 77.992716 -353.727152) (xy 77.919346 -353.769512) (xy 77.842281 -353.804707)
			(xy 77.762219 -353.832416) (xy 77.679886 -353.85239) (xy 77.596027 -353.864447) (xy 77.511402 -353.868479)
			(xy 77.426777 -353.864447) (xy 77.342918 -353.85239) (xy 77.260585 -353.832416) (xy 77.180523 -353.804707)
			(xy 77.103458 -353.769512) (xy 77.030088 -353.727152) (xy 76.961076 -353.678009) (xy 76.897048 -353.622528)
			(xy 76.838583 -353.561213) (xy 76.786212 -353.494617) (xy 76.740409 -353.423345) (xy 76.701587 -353.348042)
			(xy 76.670099 -353.26939) (xy 76.646231 -353.1881) (xy 76.630197 -353.10491) (xy 76.622144 -353.020573)
			(xy 76.62164 -352.978212) (xy 76.622159 -352.935266) (xy 76.630462 -352.849776) (xy 76.646954 -352.765482)
			(xy 76.671481 -352.683166) (xy 76.687172 -352.643186) (xy 76.690497 -352.633879) (xy 76.6905 -352.614137)
			(xy 76.687172 -352.604832) (xy 76.671472 -352.564854) (xy 76.646924 -352.482543) (xy 76.630433 -352.398247)
			(xy 76.622154 -352.312753) (xy 76.62164 -352.269806) (xy 76.622244 -352.224161) (xy 76.631638 -352.133355)
			(xy 76.650266 -352.043985) (xy 76.66355 -352.000312) (xy 76.666018 -351.991303) (xy 76.664971 -351.972669)
			(xy 76.661518 -351.96399) (xy 76.642856 -351.920903) (xy 76.61365 -351.831658) (xy 76.594004 -351.739834)
			(xy 76.584137 -351.646451) (xy 76.58354 -351.5995) (xy 75.700605 -351.5995) (xy 75.701144 -351.637854)
			(xy 75.70053 -351.683499) (xy 75.691141 -351.774304) (xy 75.672516 -351.863674) (xy 75.659234 -351.907348)
			(xy 75.656789 -351.916361) (xy 75.657821 -351.93499) (xy 75.661266 -351.94367) (xy 75.679947 -351.986749)
			(xy 75.709149 -352.075997) (xy 75.728789 -352.167824) (xy 75.738651 -352.261208) (xy 75.739244 -352.30816)
			(xy 75.738798 -352.348493) (xy 75.731529 -352.428831) (xy 75.71702 -352.508181) (xy 75.69539 -352.585893)
			(xy 75.666817 -352.661328) (xy 75.649582 -352.697796) (xy 75.645149 -352.708474) (xy 75.645157 -352.731564)
			(xy 75.649582 -352.742246) (xy 75.666795 -352.778669) (xy 75.695361 -352.854001) (xy 75.716992 -352.931608)
			(xy 75.73151 -353.010855) (xy 75.738795 -353.091091) (xy 75.739244 -353.131374) (xy 75.73874 -353.173735)
			(xy 75.730687 -353.258072) (xy 75.714653 -353.341262) (xy 75.690785 -353.422552) (xy 75.659297 -353.501204)
			(xy 75.620475 -353.576507) (xy 75.574672 -353.647779) (xy 75.522301 -353.714375) (xy 75.463836 -353.77569)
			(xy 75.399808 -353.831171) (xy 75.330796 -353.880314) (xy 75.257426 -353.922674) (xy 75.180361 -353.957869)
			(xy 75.100299 -353.985578) (xy 75.017966 -354.005552) (xy 74.934107 -354.017609) (xy 74.849482 -354.021641)
			(xy 74.764857 -354.017609) (xy 74.680998 -354.005552) (xy 74.598665 -353.985578) (xy 74.518603 -353.957869)
			(xy 74.441538 -353.922674) (xy 74.368168 -353.880314) (xy 74.299156 -353.831171) (xy 74.235128 -353.77569)
			(xy 74.176663 -353.714375) (xy 74.124292 -353.647779) (xy 74.078489 -353.576507) (xy 74.039667 -353.501204)
			(xy 74.008179 -353.422552) (xy 73.984311 -353.341262) (xy 73.968277 -353.258072) (xy 73.960224 -353.173735)
			(xy 73.95972 -353.131374) (xy 73.960164 -353.091034) (xy 73.96747 -353.010685) (xy 73.982028 -352.931329)
			(xy 74.003719 -352.85362) (xy 74.032363 -352.778196) (xy 74.049636 -352.741738) (xy 74.054225 -352.731091)
			(xy 74.054231 -352.707932) (xy 74.049636 -352.697288) (xy 74.032445 -352.660861) (xy 74.003936 -352.58552)
			(xy 73.98236 -352.50791) (xy 73.967893 -352.428665) (xy 73.960655 -352.348437) (xy 73.960228 -352.30816)
			(xy 73.960797 -352.262521) (xy 73.970094 -352.171718) (xy 73.988639 -352.082344) (xy 74.001884 -352.038666)
			(xy 74.004328 -352.029652) (xy 74.003299 -352.011023) (xy 73.999852 -352.002344) (xy 73.981136 -351.959272)
			(xy 73.95186 -351.870033) (xy 73.932154 -351.778206) (xy 73.922237 -351.684813) (xy 73.92162 -351.637854)
			(xy 24.626062 -351.637854) (xy 24.638254 -351.650046) (xy 24.664162 -351.656904) (xy 24.67737 -351.653348)
			(xy 24.701733 -351.647175) (xy 24.751554 -351.640547) (xy 24.776684 -351.64014) (xy 24.803936 -351.640602)
			(xy 24.857886 -351.648358) (xy 24.910183 -351.663713) (xy 24.959763 -351.686355) (xy 25.005614 -351.715823)
			(xy 25.046805 -351.751518) (xy 25.082496 -351.792711) (xy 25.11196 -351.838566) (xy 25.134598 -351.888147)
			(xy 25.149949 -351.940445) (xy 25.1577 -351.994396) (xy 25.158192 -352.021648) (xy 25.157771 -352.046777)
			(xy 25.15114 -352.096595) (xy 25.144984 -352.120962) (xy 25.141428 -352.13417) (xy 25.148286 -352.160078)
			(xy 27.277822 -354.289614) (xy 27.285218 -354.296466) (xy 27.303817 -354.304206) (xy 27.31389 -354.3046)
		)
		(stroke
			(width 0)
			(type solid)
		)
		(fill yes)
		(layer "In9.Cu")
		(net "GND")
	)
	(gr_poly
		(pts
			(xy 295.90746 -399.579084) (xy 295.917525 -399.578649) (xy 295.936112 -399.570918) (xy 295.943528 -399.564098)
			(xy 301.013368 -394.494258) (xy 301.03141 -394.477) (xy 301.072904 -394.449247) (xy 301.119022 -394.430138)
			(xy 301.167986 -394.42041) (xy 301.192946 -394.419836) (xy 303.770792 -394.419836) (xy 303.779681 -394.419496)
			(xy 303.796383 -394.413406) (xy 303.809985 -394.401959) (xy 303.814734 -394.394436) (xy 303.821592 -394.382498)
			(xy 303.821592 -394.355574) (xy 303.52365 -393.839954) (xy 303.511756 -393.817285) (xy 303.494889 -393.768953)
			(xy 303.486337 -393.718483) (xy 303.485804 -393.692888) (xy 303.485804 -393.69238) (xy 303.486276 -393.66839)
			(xy 303.493785 -393.621002) (xy 303.508614 -393.575371) (xy 303.530399 -393.532622) (xy 303.558603 -393.493807)
			(xy 303.592531 -393.459882) (xy 303.631349 -393.431682) (xy 303.674101 -393.409902) (xy 303.719733 -393.395077)
			(xy 303.767122 -393.387574) (xy 303.791112 -393.387072) (xy 303.815046 -393.387538) (xy 303.862329 -393.395002)
			(xy 303.907869 -393.409747) (xy 303.950555 -393.431411) (xy 303.98934 -393.459466) (xy 304.023278 -393.493223)
			(xy 304.051538 -393.531859) (xy 304.062892 -393.552934) (xy 304.0634 -393.55395) (xy 304.45583 -394.232892)
			(xy 304.467531 -394.254168) (xy 304.484783 -394.299552) (xy 304.494644 -394.347092) (xy 304.496216 -394.371322)
			(xy 304.497232 -394.391896) (xy 304.526442 -394.419836) (xy 304.970688 -394.419836) (xy 304.979577 -394.419497)
			(xy 304.99628 -394.413407) (xy 305.009883 -394.401961) (xy 305.01463 -394.394436) (xy 305.021488 -394.382498)
			(xy 305.021488 -394.355574) (xy 304.723546 -393.839954) (xy 304.711652 -393.817285) (xy 304.694786 -393.768953)
			(xy 304.686233 -393.718483) (xy 304.6857 -393.692888) (xy 304.6857 -393.69238) (xy 304.686172 -393.66839)
			(xy 304.693681 -393.621001) (xy 304.70851 -393.57537) (xy 304.730295 -393.532621) (xy 304.758499 -393.493806)
			(xy 304.792427 -393.45988) (xy 304.831245 -393.43168) (xy 304.873996 -393.409899) (xy 304.919628 -393.395074)
			(xy 304.967018 -393.38757) (xy 304.991008 -393.387072) (xy 305.014942 -393.387537) (xy 305.062225 -393.395001)
			(xy 305.107766 -393.409746) (xy 305.150452 -393.43141) (xy 305.189238 -393.459464) (xy 305.223176 -393.493222)
			(xy 305.251437 -393.531858) (xy 305.262788 -393.552934) (xy 305.263296 -393.55395) (xy 305.655726 -394.232892)
			(xy 305.667427 -394.254168) (xy 305.68468 -394.299551) (xy 305.69454 -394.347092) (xy 305.696112 -394.371322)
			(xy 305.697128 -394.391896) (xy 305.726338 -394.419836) (xy 306.170584 -394.419836) (xy 306.179474 -394.419498)
			(xy 306.196177 -394.413409) (xy 306.209782 -394.401963) (xy 306.214526 -394.394436) (xy 306.221384 -394.382498)
			(xy 306.221384 -394.355574) (xy 305.923442 -393.839954) (xy 305.911548 -393.817285) (xy 305.894682 -393.768953)
			(xy 305.88613 -393.718483) (xy 305.885596 -393.692888) (xy 305.885596 -393.69238) (xy 305.886068 -393.66839)
			(xy 305.893577 -393.621001) (xy 305.908406 -393.57537) (xy 305.930191 -393.53262) (xy 305.958394 -393.493805)
			(xy 305.992323 -393.459879) (xy 306.031141 -393.431678) (xy 306.073892 -393.409897) (xy 306.119524 -393.395071)
			(xy 306.166914 -393.387566) (xy 306.190904 -393.387072) (xy 306.191158 -393.387072) (xy 306.21509 -393.387541)
			(xy 306.262368 -393.395012) (xy 306.307904 -393.409761) (xy 306.350583 -393.431429) (xy 306.389363 -393.459485)
			(xy 306.423295 -393.493243) (xy 306.45155 -393.531879) (xy 306.462938 -393.552934) (xy 306.463446 -393.55395)
			(xy 306.855876 -394.232892) (xy 306.867578 -394.254167) (xy 306.884834 -394.299551) (xy 306.894697 -394.347092)
			(xy 306.896262 -394.371322) (xy 306.897278 -394.391896) (xy 306.926488 -394.419836) (xy 307.370734 -394.419836)
			(xy 307.379628 -394.419506) (xy 307.396345 -394.413428) (xy 307.409963 -394.401985) (xy 307.414676 -394.394436)
			(xy 307.421534 -394.382498) (xy 307.421534 -394.355574) (xy 307.123592 -393.839954) (xy 307.111655 -393.817294)
			(xy 307.094696 -393.768971) (xy 307.086046 -393.718493) (xy 307.085492 -393.692888) (xy 307.085492 -393.69238)
			(xy 307.085941 -393.668375) (xy 307.093458 -393.620958) (xy 307.108304 -393.575301) (xy 307.130112 -393.532531)
			(xy 307.158346 -393.4937) (xy 307.192309 -393.459768) (xy 307.231165 -393.431569) (xy 307.273955 -393.409799)
			(xy 307.319625 -393.394994) (xy 307.367049 -393.387519) (xy 307.391054 -393.387072) (xy 307.414986 -393.387541)
			(xy 307.462265 -393.395011) (xy 307.507801 -393.40976) (xy 307.550481 -393.431427) (xy 307.589261 -393.459483)
			(xy 307.623194 -393.493242) (xy 307.651449 -393.531877) (xy 307.662834 -393.552934) (xy 307.663342 -393.55395)
			(xy 308.055772 -394.232892) (xy 308.067475 -394.254167) (xy 308.084731 -394.29955) (xy 308.094593 -394.347092)
			(xy 308.096158 -394.371322) (xy 308.097174 -394.391896) (xy 308.126384 -394.419836) (xy 308.57063 -394.419836)
			(xy 308.579524 -394.419506) (xy 308.596242 -394.413429) (xy 308.609862 -394.401987) (xy 308.614572 -394.394436)
			(xy 308.62143 -394.382498) (xy 308.62143 -394.355574) (xy 308.323488 -393.839954) (xy 308.311551 -393.817294)
			(xy 308.294592 -393.768971) (xy 308.285942 -393.718493) (xy 308.285388 -393.692888) (xy 308.285388 -393.69238)
			(xy 308.285837 -393.668375) (xy 308.293354 -393.620957) (xy 308.308199 -393.5753) (xy 308.330008 -393.53253)
			(xy 308.358242 -393.493699) (xy 308.392205 -393.459766) (xy 308.43106 -393.431567) (xy 308.47385 -393.409796)
			(xy 308.51952 -393.394991) (xy 308.566945 -393.387516) (xy 308.59095 -393.387072) (xy 308.614883 -393.38754)
			(xy 308.662161 -393.39501) (xy 308.707698 -393.409759) (xy 308.750378 -393.431426) (xy 308.789159 -393.459482)
			(xy 308.823092 -393.49324) (xy 308.851348 -393.531876) (xy 308.86273 -393.552934) (xy 308.863238 -393.55395)
			(xy 309.255668 -394.232892) (xy 309.267371 -394.254167) (xy 309.284627 -394.29955) (xy 309.29449 -394.347091)
			(xy 309.296054 -394.371322) (xy 309.29707 -394.391896) (xy 309.32628 -394.419836) (xy 309.77078 -394.419836)
			(xy 309.77967 -394.419498) (xy 309.796375 -394.41341) (xy 309.80998 -394.401964) (xy 309.814722 -394.394436)
			(xy 309.82158 -394.382498) (xy 309.82158 -394.355574) (xy 309.523638 -393.839954) (xy 309.511744 -393.817284)
			(xy 309.494878 -393.768953) (xy 309.486326 -393.718483) (xy 309.485792 -393.692888) (xy 309.485792 -393.69238)
			(xy 309.486264 -393.66839) (xy 309.493773 -393.621001) (xy 309.508602 -393.575369) (xy 309.530386 -393.532619)
			(xy 309.55859 -393.493803) (xy 309.592519 -393.459877) (xy 309.631336 -393.431676) (xy 309.674088 -393.409894)
			(xy 309.71972 -393.395068) (xy 309.76711 -393.387563) (xy 309.7911 -393.387072) (xy 309.796688 -393.387072)
			(xy 309.806407 -393.38679) (xy 309.824565 -393.379881) (xy 309.831994 -393.37361) (xy 309.854854 -393.352528)
			(xy 309.862306 -393.345038) (xy 309.870854 -393.325742) (xy 309.871364 -393.31519) (xy 309.871364 -392.47064)
			(xy 309.871981 -392.445685) (xy 309.881727 -392.396737) (xy 309.900834 -392.350629) (xy 309.928567 -392.309134)
			(xy 309.945786 -392.291062) (xy 310.284114 -391.952734) (xy 310.300857 -391.936689) (xy 310.339027 -391.910362)
			(xy 310.381341 -391.8914) (xy 310.403748 -391.885424) (xy 310.410606 -391.8839) (xy 310.422544 -391.877042)
			(xy 310.564784 -391.734802) (xy 310.582825 -391.717543) (xy 310.624319 -391.689787) (xy 310.670437 -391.670678)
			(xy 310.719401 -391.660951) (xy 310.744362 -391.66038) (xy 325.613522 -391.66038) (xy 325.638478 -391.660994)
			(xy 325.68743 -391.670734) (xy 325.733542 -391.689837) (xy 325.775042 -391.717567) (xy 325.7931 -391.734802)
			(xy 326.137524 -392.079226) (xy 326.154786 -392.097266) (xy 326.182548 -392.138759) (xy 326.201666 -392.184877)
			(xy 326.211403 -392.233842) (xy 326.211946 -392.258804) (xy 326.211946 -393.057634) (xy 326.211382 -393.081676)
			(xy 326.202332 -393.128902) (xy 326.184562 -393.173582) (xy 326.158705 -393.214123) (xy 326.125685 -393.249078)
			(xy 326.106536 -393.263628) (xy 326.097019 -393.27124) (xy 326.085858 -393.292863) (xy 326.0852 -393.30503)
			(xy 326.0852 -394.611352) (xy 326.084762 -394.621384) (xy 326.077188 -394.63996) (xy 326.070468 -394.64742)
			(xy 325.922386 -394.795248) (xy 325.915573 -394.802592) (xy 325.907845 -394.821055) (xy 325.9074 -394.831062)
			(xy 325.9074 -394.878814) (xy 325.908094 -394.890976) (xy 325.91923 -394.9126) (xy 325.928736 -394.920216)
			(xy 325.949126 -394.935706) (xy 325.983808 -394.973366) (xy 326.010238 -395.017214) (xy 326.019414 -395.04112)
			(xy 326.022716 -395.050518) (xy 326.035924 -395.06525) (xy 326.117458 -395.105128) (xy 326.13727 -395.106652)
			(xy 326.146668 -395.103604) (xy 326.175578 -395.094708) (xy 326.235298 -395.085134) (xy 326.26554 -395.084554)
			(xy 326.293176 -395.085047) (xy 326.347868 -395.093026) (xy 326.400837 -395.10881) (xy 326.450975 -395.132071)
			(xy 326.497234 -395.16232) (xy 326.538645 -395.198926) (xy 326.574343 -395.241123) (xy 326.60358 -395.288028)
			(xy 326.625746 -395.33866) (xy 326.640376 -395.39196) (xy 326.644254 -395.419326) (xy 326.64654 -395.438376)
			(xy 326.675242 -395.463776) (xy 327.600818 -395.463776) (xy 327.610886 -395.463349) (xy 327.629484 -395.455627)
			(xy 327.636886 -395.44879) (xy 329.033886 -394.05179) (xy 329.040732 -394.044391) (xy 329.048465 -394.025793)
			(xy 329.048872 -394.015722) (xy 329.048872 -392.849354) (xy 329.049488 -392.824399) (xy 329.059232 -392.775449)
			(xy 329.078337 -392.72934) (xy 329.106069 -392.687843) (xy 329.123294 -392.669776) (xy 329.823826 -391.969244)
			(xy 329.841867 -391.951984) (xy 329.883361 -391.924225) (xy 329.929478 -391.905109) (xy 329.978443 -391.895374)
			(xy 330.003404 -391.894822) (xy 332.26502 -391.894822) (xy 332.276037 -391.894278) (xy 332.296049 -391.885057)
			(xy 332.303628 -391.877042) (xy 332.321838 -391.856507) (xy 332.36314 -391.820363) (xy 332.409195 -391.79051)
			(xy 332.459052 -391.767564) (xy 332.511682 -391.751998) (xy 332.566 -391.744134) (xy 332.620884 -391.744134)
			(xy 332.675202 -391.751998) (xy 332.727832 -391.767564) (xy 332.777689 -391.79051) (xy 332.823744 -391.820363)
			(xy 332.865046 -391.856507) (xy 332.883256 -391.877042) (xy 332.890828 -391.885068) (xy 332.910844 -391.894297)
			(xy 332.921864 -391.894822) (xy 342.252808 -391.894822) (xy 342.277768 -391.895394) (xy 342.326728 -391.905135)
			(xy 342.372848 -391.924241) (xy 342.414353 -391.951978) (xy 342.432386 -391.969244) (xy 342.547194 -392.083798)
			(xy 342.554606 -392.090482) (xy 342.573039 -392.098079) (xy 342.592977 -392.098079) (xy 342.61141 -392.090482)
			(xy 342.618822 -392.083798) (xy 342.910414 -391.792206) (xy 342.928453 -391.774941) (xy 342.969944 -391.747174)
			(xy 343.016063 -391.728051) (xy 343.065029 -391.718311) (xy 343.089992 -391.717784) (xy 358.205532 -391.717784)
			(xy 358.230487 -391.718399) (xy 358.279439 -391.728141) (xy 358.325549 -391.747245) (xy 358.367047 -391.774977)
			(xy 358.38511 -391.792206) (xy 358.665272 -392.072368) (xy 358.682534 -392.090408) (xy 358.710295 -392.1319)
			(xy 358.729409 -392.178019) (xy 358.73914 -392.226984) (xy 358.739694 -392.251946) (xy 358.739694 -393.057634)
			(xy 358.73913 -393.081677) (xy 358.730082 -393.128904) (xy 358.712314 -393.173587) (xy 358.68646 -393.214131)
			(xy 358.653443 -393.249091) (xy 358.634284 -393.263628) (xy 358.624775 -393.271244) (xy 358.613626 -393.292866)
			(xy 358.612948 -393.30503) (xy 358.612948 -394.611352) (xy 358.612509 -394.621383) (xy 358.604929 -394.639954)
			(xy 358.598216 -394.64742) (xy 358.450134 -394.795248) (xy 358.443327 -394.802594) (xy 358.435607 -394.821057)
			(xy 358.435148 -394.831062) (xy 358.435148 -394.878814) (xy 358.435843 -394.890974) (xy 358.446986 -394.912591)
			(xy 358.456484 -394.920216) (xy 358.475656 -394.934737) (xy 358.508669 -394.969701) (xy 358.534518 -395.01025)
			(xy 358.55228 -395.054937) (xy 358.561322 -395.102166) (xy 358.561894 -395.12621) (xy 358.561894 -395.635734)
			(xy 358.562323 -395.645802) (xy 358.570045 -395.664398) (xy 358.57688 -395.671802) (xy 358.58323 -395.678152)
			(xy 358.590628 -395.684999) (xy 358.609226 -395.69273) (xy 358.619298 -395.693138) (xy 363.950504 -395.693138)
			(xy 363.960514 -395.69265) (xy 363.979011 -395.684991) (xy 363.993172 -395.670839) (xy 364.000843 -395.652348)
			(xy 364.001304 -395.642338) (xy 364.001304 -395.308074) (xy 364.00179 -395.280823) (xy 364.009546 -395.226875)
			(xy 364.024901 -395.17458) (xy 364.047543 -395.125003) (xy 364.077009 -395.079153) (xy 364.1127 -395.037962)
			(xy 364.153891 -395.002271) (xy 364.199741 -394.972805) (xy 364.249318 -394.950163) (xy 364.301613 -394.934808)
			(xy 364.355561 -394.927052) (xy 364.410063 -394.927052) (xy 364.464011 -394.934808) (xy 364.516306 -394.950163)
			(xy 364.565883 -394.972805) (xy 364.611733 -395.002271) (xy 364.652924 -395.037962) (xy 364.688615 -395.079153)
			(xy 364.718081 -395.125003) (xy 364.740723 -395.17458) (xy 364.756078 -395.226875) (xy 364.763834 -395.280823)
			(xy 364.76432 -395.308074) (xy 364.76432 -395.642338) (xy 364.764815 -395.652339) (xy 364.772482 -395.670814)
			(xy 364.786634 -395.684951) (xy 364.805118 -395.692597) (xy 364.81512 -395.693138) (xy 365.657384 -395.693138)
			(xy 365.667446 -395.692698) (xy 365.686022 -395.684955) (xy 365.693452 -395.678152) (xy 366.090708 -395.280896)
			(xy 366.097553 -395.273497) (xy 366.105285 -395.254899) (xy 366.105694 -395.244828) (xy 366.105694 -392.52779)
			(xy 366.106306 -392.502834) (xy 366.116046 -392.453881) (xy 366.135147 -392.407768) (xy 366.162878 -392.366268)
			(xy 366.180116 -392.348212) (xy 366.593628 -391.9347) (xy 366.611667 -391.917437) (xy 366.653159 -391.889672)
			(xy 366.699278 -391.870552) (xy 366.748244 -391.860815) (xy 366.773206 -391.860278) (xy 366.870488 -391.860278)
			(xy 366.880096 -391.859862) (xy 366.897973 -391.852809) (xy 366.905286 -391.846562) (xy 366.926604 -391.827334)
			(xy 366.973933 -391.794844) (xy 367.025596 -391.769813) (xy 367.080426 -391.752804) (xy 367.137186 -391.744203)
			(xy 367.194594 -391.744203) (xy 367.251354 -391.752804) (xy 367.306184 -391.769813) (xy 367.357847 -391.794844)
			(xy 367.405176 -391.827334) (xy 367.426494 -391.846562) (xy 367.433784 -391.852847) (xy 367.451675 -391.859903)
			(xy 367.461292 -391.860278) (xy 376.818906 -391.860278) (xy 376.843863 -391.86089) (xy 376.892817 -391.870628)
			(xy 376.938931 -391.889728) (xy 376.980433 -391.917458) (xy 376.998484 -391.9347) (xy 377.183904 -392.12012)
			(xy 377.191316 -392.126804) (xy 377.209749 -392.134401) (xy 377.229687 -392.134401) (xy 377.24812 -392.126804)
			(xy 377.255532 -392.12012) (xy 377.64085 -391.734802) (xy 377.65889 -391.71754) (xy 377.700383 -391.689779)
			(xy 377.746501 -391.670664) (xy 377.795466 -391.660931) (xy 377.820428 -391.66038) (xy 392.713464 -391.66038)
			(xy 392.738418 -391.660998) (xy 392.787366 -391.670745) (xy 392.833472 -391.689853) (xy 392.874966 -391.717587)
			(xy 392.893042 -391.734802) (xy 393.237466 -392.079226) (xy 393.254726 -392.097267) (xy 393.282483 -392.138761)
			(xy 393.301598 -392.184879) (xy 393.311333 -392.233843) (xy 393.311888 -392.258804) (xy 393.311888 -393.057634)
			(xy 393.311324 -393.081677) (xy 393.302275 -393.128904) (xy 393.284507 -393.173586) (xy 393.258653 -393.21413)
			(xy 393.225636 -393.249089) (xy 393.206478 -393.263628) (xy 393.19706 -393.271292) (xy 393.186069 -393.292905)
			(xy 393.185396 -393.30503) (xy 393.185396 -394.611352) (xy 393.184963 -394.621418) (xy 393.177235 -394.640008)
			(xy 393.17041 -394.64742) (xy 393.022328 -394.795248) (xy 393.015633 -394.802654) (xy 393.008027 -394.82109)
			(xy 393.007596 -394.831062) (xy 393.007596 -394.878814) (xy 393.008223 -394.890948) (xy 393.019237 -394.912566)
			(xy 393.028678 -394.920216) (xy 393.04785 -394.934736) (xy 393.080865 -394.9697) (xy 393.106714 -395.010249)
			(xy 393.124477 -395.054936) (xy 393.133518 -395.102166) (xy 393.134088 -395.12621) (xy 393.134088 -395.757654)
			(xy 393.1345 -395.767682) (xy 393.142161 -395.786217) (xy 393.156334 -395.800407) (xy 393.17486 -395.808089)
			(xy 393.184888 -395.808454) (xy 394.486384 -395.808454) (xy 394.496446 -395.808014) (xy 394.515024 -395.800273)
			(xy 394.522452 -395.793468) (xy 395.977364 -394.338556) (xy 395.984207 -394.331157) (xy 395.991931 -394.312558)
			(xy 395.99235 -394.302488) (xy 395.99235 -392.573764) (xy 395.992925 -392.548805) (xy 396.002671 -392.499849)
			(xy 396.021783 -392.453734) (xy 396.049524 -392.412236) (xy 396.066772 -392.394186) (xy 396.864078 -391.59688)
			(xy 396.88212 -391.579622) (xy 396.923614 -391.551868) (xy 396.969732 -391.532759) (xy 397.018695 -391.523032)
			(xy 397.043656 -391.522458) (xy 425.075604 -391.522458) (xy 425.100564 -391.52303) (xy 425.149524 -391.532771)
			(xy 425.195642 -391.551879) (xy 425.237145 -391.579619) (xy 425.255182 -391.59688) (xy 425.749466 -392.091164)
			(xy 425.766723 -392.109206) (xy 425.794474 -392.150701) (xy 425.813582 -392.196819) (xy 425.82331 -392.245782)
			(xy 425.823888 -392.270742) (xy 425.823888 -396.813786) (xy 425.824326 -396.82385) (xy 425.832061 -396.842433)
			(xy 425.838874 -396.849854) (xy 426.461936 -397.472916) (xy 426.469332 -397.479766) (xy 426.487931 -397.487501)
			(xy 426.498004 -397.487902) (xy 429.173132 -397.487902) (xy 429.1832 -397.487473) (xy 429.201796 -397.479751)
			(xy 429.2092 -397.472916) (xy 429.257206 -397.42491) (xy 429.263278 -397.418302) (xy 429.270749 -397.401999)
			(xy 429.272126 -397.384119) (xy 429.267237 -397.366865) (xy 429.262286 -397.359378) (xy 429.245243 -397.334805)
			(xy 429.2182 -397.281471) (xy 429.1998 -397.224573) (xy 429.190495 -397.165503) (xy 429.189896 -397.135604)
			(xy 429.190359 -397.108351) (xy 429.198116 -397.0544) (xy 429.213471 -397.002102) (xy 429.236114 -396.952521)
			(xy 429.265582 -396.906668) (xy 429.301275 -396.865475) (xy 429.342468 -396.829782) (xy 429.388321 -396.800314)
			(xy 429.437902 -396.777671) (xy 429.4902 -396.762316) (xy 429.544151 -396.754559) (xy 429.571404 -396.754096)
			(xy 429.597523 -396.754522) (xy 429.64927 -396.761656) (xy 429.674528 -396.76832) (xy 429.686212 -396.771622)
			(xy 429.709326 -396.76705) (xy 429.783494 -396.710916) (xy 429.792479 -396.703323) (xy 429.802931 -396.682277)
			(xy 429.80356 -396.67053) (xy 429.80356 -387.132322) (xy 429.803301 -387.125433) (xy 429.799575 -387.112167)
			(xy 429.796194 -387.10616) (xy 429.75016 -387.028798) (xy 429.663806 -386.870817) (xy 429.584111 -386.709374)
			(xy 429.511215 -386.54475) (xy 429.445244 -386.377231) (xy 429.386312 -386.207107) (xy 429.334522 -386.034675)
			(xy 429.289965 -385.860234) (xy 429.252717 -385.684087) (xy 429.222843 -385.506541) (xy 429.200396 -385.327904)
			(xy 429.185414 -385.148487) (xy 429.177923 -384.968601) (xy 429.17745 -384.87858) (xy 429.177965 -384.784031)
			(xy 429.186244 -384.595114) (xy 429.202785 -384.406741) (xy 429.227558 -384.219273) (xy 429.260513 -384.033069)
			(xy 429.301588 -383.848486) (xy 429.350705 -383.665878) (xy 429.407769 -383.485596) (xy 429.47267 -383.307984)
			(xy 429.545284 -383.133384) (xy 429.625473 -382.96213) (xy 429.713082 -382.794551) (xy 429.807943 -382.630968)
			(xy 429.909874 -382.471694) (xy 430.01868 -382.317036) (xy 430.134153 -382.167289) (xy 430.25607 -382.022741)
			(xy 430.384198 -381.883668) (xy 430.518292 -381.750338) (xy 430.658095 -381.623006) (xy 430.803337 -381.501917)
			(xy 430.953741 -381.387302) (xy 431.109019 -381.279381) (xy 431.268872 -381.178361) (xy 431.432995 -381.084437)
			(xy 431.51679 -381.04064) (xy 431.527712 -381.035052) (xy 431.541682 -381.015494) (xy 431.55616 -380.922276)
			(xy 431.557372 -380.910331) (xy 431.549943 -380.887535) (xy 431.541936 -380.878588) (xy 426.107606 -375.444258)
			(xy 426.100211 -375.437404) (xy 426.081612 -375.429658) (xy 426.071538 -375.429272) (xy 289.817556 -375.429272)
			(xy 289.807489 -375.429702) (xy 289.788893 -375.437425) (xy 289.781488 -375.444258) (xy 288.43224 -376.793506)
			(xy 288.425128 -376.81916) (xy 288.428176 -376.832114) (xy 288.433041 -376.853049) (xy 288.438262 -376.895713)
			(xy 288.43859 -376.917204) (xy 288.438128 -376.943373) (xy 288.43047 -376.995149) (xy 288.41532 -377.045247)
			(xy 288.393004 -377.09259) (xy 288.364002 -377.136159) (xy 288.328937 -377.175016) (xy 288.30905 -377.192032)
			(xy 288.300761 -377.199631) (xy 288.291128 -377.219921) (xy 288.290508 -377.231148) (xy 288.290508 -377.444567)
			(xy 300.335454 -377.444567) (xy 300.335454 -377.390033) (xy 300.343215 -377.336054) (xy 300.358579 -377.283729)
			(xy 300.381233 -377.234123) (xy 300.410717 -377.188246) (xy 300.446429 -377.147031) (xy 300.487642 -377.111319)
			(xy 300.533519 -377.081835) (xy 300.583125 -377.059181) (xy 300.63545 -377.043816) (xy 300.689429 -377.036055)
			(xy 300.716696 -377.035568) (xy 301.580296 -377.035568) (xy 301.607569 -377.035971) (xy 301.661561 -377.043734)
			(xy 301.713898 -377.059101) (xy 301.763516 -377.08176) (xy 301.809403 -377.11125) (xy 301.850627 -377.14697)
			(xy 301.886348 -377.188193) (xy 301.915838 -377.234081) (xy 301.938498 -377.283698) (xy 301.953866 -377.336035)
			(xy 301.961628 -377.390027) (xy 301.961628 -377.444567) (xy 307.142654 -377.444567) (xy 307.142654 -377.390033)
			(xy 307.150415 -377.336054) (xy 307.165779 -377.283729) (xy 307.188433 -377.234123) (xy 307.217917 -377.188246)
			(xy 307.253629 -377.147031) (xy 307.294842 -377.111319) (xy 307.340719 -377.081835) (xy 307.390325 -377.059181)
			(xy 307.44265 -377.043816) (xy 307.496629 -377.036055) (xy 307.523896 -377.035568) (xy 308.387496 -377.035568)
			(xy 308.414769 -377.035971) (xy 308.468761 -377.043734) (xy 308.521098 -377.059101) (xy 308.570716 -377.08176)
			(xy 308.616603 -377.11125) (xy 308.657827 -377.14697) (xy 308.693548 -377.188193) (xy 308.723038 -377.234081)
			(xy 308.745698 -377.283698) (xy 308.761066 -377.336035) (xy 308.768828 -377.390027) (xy 308.768828 -377.444567)
			(xy 313.949854 -377.444567) (xy 313.949854 -377.390033) (xy 313.957615 -377.336054) (xy 313.972979 -377.283729)
			(xy 313.995633 -377.234123) (xy 314.025117 -377.188246) (xy 314.060829 -377.147031) (xy 314.102042 -377.111319)
			(xy 314.147919 -377.081835) (xy 314.197525 -377.059181) (xy 314.24985 -377.043816) (xy 314.303829 -377.036055)
			(xy 314.331096 -377.035568) (xy 315.194696 -377.035568) (xy 315.221969 -377.035971) (xy 315.275961 -377.043734)
			(xy 315.328298 -377.059101) (xy 315.377916 -377.08176) (xy 315.423803 -377.11125) (xy 315.465027 -377.14697)
			(xy 315.500748 -377.188193) (xy 315.530238 -377.234081) (xy 315.552898 -377.283698) (xy 315.568266 -377.336035)
			(xy 315.576028 -377.390027) (xy 315.576028 -377.444567) (xy 320.757054 -377.444567) (xy 320.757054 -377.390033)
			(xy 320.764815 -377.336054) (xy 320.780179 -377.283729) (xy 320.802833 -377.234123) (xy 320.832317 -377.188246)
			(xy 320.868029 -377.147031) (xy 320.909242 -377.111319) (xy 320.955119 -377.081835) (xy 321.004725 -377.059181)
			(xy 321.05705 -377.043816) (xy 321.111029 -377.036055) (xy 321.138296 -377.035568) (xy 322.001896 -377.035568)
			(xy 322.029169 -377.035971) (xy 322.083161 -377.043734) (xy 322.135498 -377.059101) (xy 322.185116 -377.08176)
			(xy 322.231003 -377.11125) (xy 322.272227 -377.14697) (xy 322.307948 -377.188193) (xy 322.337438 -377.234081)
			(xy 322.360098 -377.283698) (xy 322.375466 -377.336035) (xy 322.383228 -377.390027) (xy 322.383228 -377.444567)
			(xy 324.160654 -377.444567) (xy 324.160654 -377.390033) (xy 324.168415 -377.336054) (xy 324.183779 -377.283729)
			(xy 324.206433 -377.234123) (xy 324.235917 -377.188246) (xy 324.271629 -377.147031) (xy 324.312842 -377.111319)
			(xy 324.358719 -377.081835) (xy 324.408325 -377.059181) (xy 324.46065 -377.043816) (xy 324.514629 -377.036055)
			(xy 324.541896 -377.035568) (xy 325.405496 -377.035568) (xy 325.432769 -377.035971) (xy 325.486761 -377.043734)
			(xy 325.539098 -377.059101) (xy 325.588716 -377.08176) (xy 325.634603 -377.11125) (xy 325.675827 -377.14697)
			(xy 325.711548 -377.188193) (xy 325.741038 -377.234081) (xy 325.763698 -377.283698) (xy 325.779066 -377.336035)
			(xy 325.786828 -377.390027) (xy 325.786828 -377.444571) (xy 332.863132 -377.444571) (xy 332.863132 -377.390029)
			(xy 332.870894 -377.336043) (xy 332.886261 -377.283711) (xy 332.908921 -377.234098) (xy 332.93841 -377.188216)
			(xy 332.974129 -377.146998) (xy 333.015351 -377.111284) (xy 333.061237 -377.081799) (xy 333.110852 -377.059146)
			(xy 333.163186 -377.043785) (xy 333.217173 -377.036028) (xy 333.244444 -377.035568) (xy 334.108044 -377.035568)
			(xy 334.135313 -377.035998) (xy 334.189297 -377.043765) (xy 334.241625 -377.059135) (xy 334.291233 -377.081796)
			(xy 334.337112 -377.111285) (xy 334.378328 -377.147003) (xy 334.414041 -377.188223) (xy 334.443525 -377.234105)
			(xy 334.46618 -377.283716) (xy 334.481544 -377.336047) (xy 334.489306 -377.39003) (xy 334.489306 -377.44457)
			(xy 334.489306 -377.444571) (xy 339.670332 -377.444571) (xy 339.670332 -377.390029) (xy 339.678094 -377.336043)
			(xy 339.693461 -377.283711) (xy 339.716121 -377.234098) (xy 339.74561 -377.188216) (xy 339.781329 -377.146998)
			(xy 339.822551 -377.111284) (xy 339.868437 -377.081799) (xy 339.918052 -377.059146) (xy 339.970386 -377.043785)
			(xy 340.024373 -377.036028) (xy 340.051644 -377.035568) (xy 340.915244 -377.035568) (xy 340.942513 -377.035998)
			(xy 340.996497 -377.043765) (xy 341.048825 -377.059135) (xy 341.098433 -377.081796) (xy 341.144312 -377.111285)
			(xy 341.185528 -377.147003) (xy 341.221241 -377.188223) (xy 341.250725 -377.234105) (xy 341.27338 -377.283716)
			(xy 341.288744 -377.336047) (xy 341.296506 -377.39003) (xy 341.296506 -377.44457) (xy 341.296506 -377.444571)
			(xy 346.477532 -377.444571) (xy 346.477532 -377.390029) (xy 346.485294 -377.336043) (xy 346.500661 -377.283711)
			(xy 346.523321 -377.234098) (xy 346.55281 -377.188216) (xy 346.588529 -377.146998) (xy 346.629751 -377.111284)
			(xy 346.675637 -377.081799) (xy 346.725252 -377.059146) (xy 346.777586 -377.043785) (xy 346.831573 -377.036028)
			(xy 346.858844 -377.035568) (xy 347.722444 -377.035568) (xy 347.749713 -377.035998) (xy 347.803697 -377.043765)
			(xy 347.856025 -377.059135) (xy 347.905633 -377.081796) (xy 347.951512 -377.111285) (xy 347.992728 -377.147003)
			(xy 348.028441 -377.188223) (xy 348.057925 -377.234105) (xy 348.08058 -377.283716) (xy 348.095944 -377.336047)
			(xy 348.103706 -377.39003) (xy 348.103706 -377.44457) (xy 348.103706 -377.444571) (xy 353.284732 -377.444571)
			(xy 353.284732 -377.390029) (xy 353.292494 -377.336043) (xy 353.307861 -377.283711) (xy 353.330521 -377.234098)
			(xy 353.36001 -377.188216) (xy 353.395729 -377.146998) (xy 353.436951 -377.111284) (xy 353.482837 -377.081799)
			(xy 353.532452 -377.059146) (xy 353.584786 -377.043785) (xy 353.638773 -377.036028) (xy 353.666044 -377.035568)
			(xy 354.529644 -377.035568) (xy 354.556913 -377.035998) (xy 354.610897 -377.043765) (xy 354.663225 -377.059135)
			(xy 354.712833 -377.081796) (xy 354.758712 -377.111285) (xy 354.799928 -377.147003) (xy 354.835641 -377.188223)
			(xy 354.865125 -377.234105) (xy 354.88778 -377.283716) (xy 354.903144 -377.336047) (xy 354.910906 -377.39003)
			(xy 354.910906 -377.44457) (xy 354.910906 -377.444571) (xy 356.688332 -377.444571) (xy 356.688332 -377.390029)
			(xy 356.696094 -377.336043) (xy 356.711461 -377.283711) (xy 356.734121 -377.234098) (xy 356.76361 -377.188216)
			(xy 356.799329 -377.146998) (xy 356.840551 -377.111284) (xy 356.886437 -377.081799) (xy 356.936052 -377.059146)
			(xy 356.988386 -377.043785) (xy 357.042373 -377.036028) (xy 357.069644 -377.035568) (xy 357.933244 -377.035568)
			(xy 357.960513 -377.035998) (xy 358.014497 -377.043765) (xy 358.066825 -377.059135) (xy 358.116433 -377.081796)
			(xy 358.162312 -377.111285) (xy 358.203528 -377.147003) (xy 358.239241 -377.188223) (xy 358.268725 -377.234105)
			(xy 358.29138 -377.283716) (xy 358.306744 -377.336047) (xy 358.314506 -377.39003) (xy 358.314506 -377.444567)
			(xy 367.435654 -377.444567) (xy 367.435654 -377.390033) (xy 367.443415 -377.336054) (xy 367.458779 -377.28373)
			(xy 367.481433 -377.234124) (xy 367.510916 -377.188247) (xy 367.546627 -377.147033) (xy 367.587841 -377.11132)
			(xy 367.633717 -377.081837) (xy 367.683322 -377.059182) (xy 367.735647 -377.043817) (xy 367.789625 -377.036055)
			(xy 367.816892 -377.035568) (xy 368.680492 -377.035568) (xy 368.707766 -377.035971) (xy 368.761757 -377.043733)
			(xy 368.814095 -377.0591) (xy 368.863713 -377.081759) (xy 368.909602 -377.111248) (xy 368.950826 -377.146968)
			(xy 368.986547 -377.188192) (xy 369.016038 -377.23408) (xy 369.038698 -377.283697) (xy 369.054065 -377.336035)
			(xy 369.061828 -377.390026) (xy 369.061828 -377.444567) (xy 374.242854 -377.444567) (xy 374.242854 -377.390033)
			(xy 374.250615 -377.336054) (xy 374.265979 -377.28373) (xy 374.288633 -377.234124) (xy 374.318116 -377.188247)
			(xy 374.353827 -377.147033) (xy 374.395041 -377.11132) (xy 374.440917 -377.081837) (xy 374.490522 -377.059182)
			(xy 374.542847 -377.043817) (xy 374.596825 -377.036055) (xy 374.624092 -377.035568) (xy 375.487692 -377.035568)
			(xy 375.514966 -377.035971) (xy 375.568957 -377.043733) (xy 375.621295 -377.0591) (xy 375.670913 -377.081759)
			(xy 375.716802 -377.111248) (xy 375.758026 -377.146968) (xy 375.793747 -377.188192) (xy 375.823238 -377.23408)
			(xy 375.845898 -377.283697) (xy 375.861265 -377.336035) (xy 375.869028 -377.390026) (xy 375.869028 -377.444567)
			(xy 381.050054 -377.444567) (xy 381.050054 -377.390033) (xy 381.057815 -377.336054) (xy 381.073179 -377.28373)
			(xy 381.095833 -377.234124) (xy 381.125316 -377.188247) (xy 381.161027 -377.147033) (xy 381.202241 -377.11132)
			(xy 381.248117 -377.081837) (xy 381.297722 -377.059182) (xy 381.350047 -377.043817) (xy 381.404025 -377.036055)
			(xy 381.431292 -377.035568) (xy 382.294892 -377.035568) (xy 382.322166 -377.035971) (xy 382.376157 -377.043733)
			(xy 382.428495 -377.0591) (xy 382.478113 -377.081759) (xy 382.524002 -377.111248) (xy 382.565226 -377.146968)
			(xy 382.600947 -377.188192) (xy 382.630438 -377.23408) (xy 382.653098 -377.283697) (xy 382.668465 -377.336035)
			(xy 382.676228 -377.390026) (xy 382.676228 -377.444567) (xy 387.857254 -377.444567) (xy 387.857254 -377.390033)
			(xy 387.865015 -377.336054) (xy 387.880379 -377.28373) (xy 387.903033 -377.234124) (xy 387.932516 -377.188247)
			(xy 387.968227 -377.147033) (xy 388.009441 -377.11132) (xy 388.055317 -377.081837) (xy 388.104922 -377.059182)
			(xy 388.157247 -377.043817) (xy 388.211225 -377.036055) (xy 388.238492 -377.035568) (xy 389.102092 -377.035568)
			(xy 389.129366 -377.035971) (xy 389.183357 -377.043733) (xy 389.235695 -377.0591) (xy 389.285313 -377.081759)
			(xy 389.331202 -377.111248) (xy 389.372426 -377.146968) (xy 389.408147 -377.188192) (xy 389.437638 -377.23408)
			(xy 389.460298 -377.283697) (xy 389.475665 -377.336035) (xy 389.483428 -377.390026) (xy 389.483428 -377.444567)
			(xy 391.260854 -377.444567) (xy 391.260854 -377.390033) (xy 391.268615 -377.336054) (xy 391.283979 -377.28373)
			(xy 391.306633 -377.234124) (xy 391.336116 -377.188247) (xy 391.371827 -377.147033) (xy 391.413041 -377.11132)
			(xy 391.458917 -377.081837) (xy 391.508522 -377.059182) (xy 391.560847 -377.043817) (xy 391.614825 -377.036055)
			(xy 391.642092 -377.035568) (xy 392.505692 -377.035568) (xy 392.532966 -377.035971) (xy 392.586957 -377.043733)
			(xy 392.639295 -377.0591) (xy 392.688913 -377.081759) (xy 392.734802 -377.111248) (xy 392.776026 -377.146968)
			(xy 392.811747 -377.188192) (xy 392.841238 -377.23408) (xy 392.863898 -377.283697) (xy 392.879265 -377.336035)
			(xy 392.887028 -377.390026) (xy 392.887028 -377.444571) (xy 399.963332 -377.444571) (xy 399.963332 -377.390029)
			(xy 399.971094 -377.336043) (xy 399.986461 -377.283711) (xy 400.00912 -377.234099) (xy 400.038609 -377.188217)
			(xy 400.074328 -377.147) (xy 400.11555 -377.111285) (xy 400.161435 -377.081801) (xy 400.211049 -377.059147)
			(xy 400.263382 -377.043786) (xy 400.317369 -377.036029) (xy 400.34464 -377.035568) (xy 401.20824 -377.035568)
			(xy 401.23551 -377.035997) (xy 401.289493 -377.043764) (xy 401.341822 -377.059134) (xy 401.391431 -377.081794)
			(xy 401.437311 -377.111284) (xy 401.478527 -377.147002) (xy 401.51424 -377.188222) (xy 401.543725 -377.234104)
			(xy 401.56638 -377.283716) (xy 401.581744 -377.336046) (xy 401.589506 -377.39003) (xy 401.589506 -377.44457)
			(xy 401.589506 -377.444571) (xy 406.770532 -377.444571) (xy 406.770532 -377.390029) (xy 406.778294 -377.336043)
			(xy 406.793661 -377.283711) (xy 406.81632 -377.234099) (xy 406.845809 -377.188217) (xy 406.881528 -377.147)
			(xy 406.92275 -377.111285) (xy 406.968635 -377.081801) (xy 407.018249 -377.059147) (xy 407.070582 -377.043786)
			(xy 407.124569 -377.036029) (xy 407.15184 -377.035568) (xy 408.01544 -377.035568) (xy 408.04271 -377.035997)
			(xy 408.096693 -377.043764) (xy 408.149022 -377.059134) (xy 408.198631 -377.081794) (xy 408.244511 -377.111284)
			(xy 408.285727 -377.147002) (xy 408.32144 -377.188222) (xy 408.350925 -377.234104) (xy 408.37358 -377.283716)
			(xy 408.388944 -377.336046) (xy 408.396706 -377.39003) (xy 408.396706 -377.44457) (xy 408.396706 -377.444571)
			(xy 413.577732 -377.444571) (xy 413.577732 -377.390029) (xy 413.585494 -377.336043) (xy 413.600861 -377.283711)
			(xy 413.62352 -377.234099) (xy 413.653009 -377.188217) (xy 413.688728 -377.147) (xy 413.72995 -377.111285)
			(xy 413.775835 -377.081801) (xy 413.825449 -377.059147) (xy 413.877782 -377.043786) (xy 413.931769 -377.036029)
			(xy 413.95904 -377.035568) (xy 414.82264 -377.035568) (xy 414.84991 -377.035997) (xy 414.903893 -377.043764)
			(xy 414.956222 -377.059134) (xy 415.005831 -377.081794) (xy 415.051711 -377.111284) (xy 415.092927 -377.147002)
			(xy 415.12864 -377.188222) (xy 415.158125 -377.234104) (xy 415.18078 -377.283716) (xy 415.196144 -377.336046)
			(xy 415.203906 -377.39003) (xy 415.203906 -377.44457) (xy 415.203906 -377.444571) (xy 420.384932 -377.444571)
			(xy 420.384932 -377.390029) (xy 420.392694 -377.336043) (xy 420.408061 -377.283711) (xy 420.43072 -377.234099)
			(xy 420.460209 -377.188217) (xy 420.495928 -377.147) (xy 420.53715 -377.111285) (xy 420.583035 -377.081801)
			(xy 420.632649 -377.059147) (xy 420.684982 -377.043786) (xy 420.738969 -377.036029) (xy 420.76624 -377.035568)
			(xy 421.62984 -377.035568) (xy 421.65711 -377.035997) (xy 421.711093 -377.043764) (xy 421.763422 -377.059134)
			(xy 421.813031 -377.081794) (xy 421.858911 -377.111284) (xy 421.900127 -377.147002) (xy 421.93584 -377.188222)
			(xy 421.965325 -377.234104) (xy 421.98798 -377.283716) (xy 422.003344 -377.336046) (xy 422.011106 -377.39003)
			(xy 422.011106 -377.44457) (xy 422.011106 -377.444571) (xy 423.788532 -377.444571) (xy 423.788532 -377.390029)
			(xy 423.796294 -377.336043) (xy 423.811661 -377.283711) (xy 423.83432 -377.234099) (xy 423.863809 -377.188217)
			(xy 423.899528 -377.147) (xy 423.94075 -377.111285) (xy 423.986635 -377.081801) (xy 424.036249 -377.059147)
			(xy 424.088582 -377.043786) (xy 424.142569 -377.036029) (xy 424.16984 -377.035568) (xy 425.03344 -377.035568)
			(xy 425.06071 -377.035997) (xy 425.114693 -377.043764) (xy 425.167022 -377.059134) (xy 425.216631 -377.081794)
			(xy 425.262511 -377.111284) (xy 425.303727 -377.147002) (xy 425.33944 -377.188222) (xy 425.368925 -377.234104)
			(xy 425.39158 -377.283716) (xy 425.406944 -377.336046) (xy 425.414706 -377.39003) (xy 425.414706 -377.44457)
			(xy 425.406944 -377.498554) (xy 425.39158 -377.550884) (xy 425.368925 -377.600496) (xy 425.33944 -377.646378)
			(xy 425.303727 -377.687598) (xy 425.262511 -377.723316) (xy 425.216631 -377.752806) (xy 425.167022 -377.775466)
			(xy 425.114693 -377.790836) (xy 425.06071 -377.798603) (xy 425.03344 -377.799092) (xy 424.16984 -377.799092)
			(xy 424.142569 -377.798571) (xy 424.088582 -377.790814) (xy 424.036249 -377.775453) (xy 423.986635 -377.752799)
			(xy 423.94075 -377.723315) (xy 423.899528 -377.6876) (xy 423.863809 -377.646383) (xy 423.83432 -377.600501)
			(xy 423.811661 -377.550889) (xy 423.796294 -377.498557) (xy 423.788532 -377.444571) (xy 422.011106 -377.444571)
			(xy 422.003344 -377.498554) (xy 421.98798 -377.550884) (xy 421.965325 -377.600496) (xy 421.93584 -377.646378)
			(xy 421.900127 -377.687598) (xy 421.858911 -377.723316) (xy 421.813031 -377.752806) (xy 421.763422 -377.775466)
			(xy 421.711093 -377.790836) (xy 421.65711 -377.798603) (xy 421.62984 -377.799092) (xy 420.76624 -377.799092)
			(xy 420.738969 -377.798571) (xy 420.684982 -377.790814) (xy 420.632649 -377.775453) (xy 420.583035 -377.752799)
			(xy 420.53715 -377.723315) (xy 420.495928 -377.6876) (xy 420.460209 -377.646383) (xy 420.43072 -377.600501)
			(xy 420.408061 -377.550889) (xy 420.392694 -377.498557) (xy 420.384932 -377.444571) (xy 415.203906 -377.444571)
			(xy 415.196144 -377.498554) (xy 415.18078 -377.550884) (xy 415.158125 -377.600496) (xy 415.12864 -377.646378)
			(xy 415.092927 -377.687598) (xy 415.051711 -377.723316) (xy 415.005831 -377.752806) (xy 414.956222 -377.775466)
			(xy 414.903893 -377.790836) (xy 414.84991 -377.798603) (xy 414.82264 -377.799092) (xy 413.95904 -377.799092)
			(xy 413.931769 -377.798571) (xy 413.877782 -377.790814) (xy 413.825449 -377.775453) (xy 413.775835 -377.752799)
			(xy 413.72995 -377.723315) (xy 413.688728 -377.6876) (xy 413.653009 -377.646383) (xy 413.62352 -377.600501)
			(xy 413.600861 -377.550889) (xy 413.585494 -377.498557) (xy 413.577732 -377.444571) (xy 408.396706 -377.444571)
			(xy 408.388944 -377.498554) (xy 408.37358 -377.550884) (xy 408.350925 -377.600496) (xy 408.32144 -377.646378)
			(xy 408.285727 -377.687598) (xy 408.244511 -377.723316) (xy 408.198631 -377.752806) (xy 408.149022 -377.775466)
			(xy 408.096693 -377.790836) (xy 408.04271 -377.798603) (xy 408.01544 -377.799092) (xy 407.15184 -377.799092)
			(xy 407.124569 -377.798571) (xy 407.070582 -377.790814) (xy 407.018249 -377.775453) (xy 406.968635 -377.752799)
			(xy 406.92275 -377.723315) (xy 406.881528 -377.6876) (xy 406.845809 -377.646383) (xy 406.81632 -377.600501)
			(xy 406.793661 -377.550889) (xy 406.778294 -377.498557) (xy 406.770532 -377.444571) (xy 401.589506 -377.444571)
			(xy 401.581744 -377.498554) (xy 401.56638 -377.550884) (xy 401.543725 -377.600496) (xy 401.51424 -377.646378)
			(xy 401.478527 -377.687598) (xy 401.437311 -377.723316) (xy 401.391431 -377.752806) (xy 401.341822 -377.775466)
			(xy 401.289493 -377.790836) (xy 401.23551 -377.798603) (xy 401.20824 -377.799092) (xy 400.34464 -377.799092)
			(xy 400.317369 -377.798571) (xy 400.263382 -377.790814) (xy 400.211049 -377.775453) (xy 400.161435 -377.752799)
			(xy 400.11555 -377.723315) (xy 400.074328 -377.6876) (xy 400.038609 -377.646383) (xy 400.00912 -377.600501)
			(xy 399.986461 -377.550889) (xy 399.971094 -377.498557) (xy 399.963332 -377.444571) (xy 392.887028 -377.444571)
			(xy 392.887028 -377.444574) (xy 392.879265 -377.498565) (xy 392.863898 -377.550903) (xy 392.841238 -377.60052)
			(xy 392.811747 -377.646408) (xy 392.776026 -377.687632) (xy 392.734802 -377.723352) (xy 392.688913 -377.752841)
			(xy 392.639295 -377.7755) (xy 392.586957 -377.790867) (xy 392.532966 -377.798629) (xy 392.505692 -377.799092)
			(xy 391.642092 -377.799092) (xy 391.614825 -377.798545) (xy 391.560847 -377.790783) (xy 391.508522 -377.775418)
			(xy 391.458917 -377.752763) (xy 391.413041 -377.72328) (xy 391.371827 -377.687567) (xy 391.336116 -377.646353)
			(xy 391.306633 -377.600476) (xy 391.283979 -377.55087) (xy 391.268615 -377.498546) (xy 391.260854 -377.444567)
			(xy 389.483428 -377.444567) (xy 389.483428 -377.444574) (xy 389.475665 -377.498565) (xy 389.460298 -377.550903)
			(xy 389.437638 -377.60052) (xy 389.408147 -377.646408) (xy 389.372426 -377.687632) (xy 389.331202 -377.723352)
			(xy 389.285313 -377.752841) (xy 389.235695 -377.7755) (xy 389.183357 -377.790867) (xy 389.129366 -377.798629)
			(xy 389.102092 -377.799092) (xy 388.238492 -377.799092) (xy 388.211225 -377.798545) (xy 388.157247 -377.790783)
			(xy 388.104922 -377.775418) (xy 388.055317 -377.752763) (xy 388.009441 -377.72328) (xy 387.968227 -377.687567)
			(xy 387.932516 -377.646353) (xy 387.903033 -377.600476) (xy 387.880379 -377.55087) (xy 387.865015 -377.498546)
			(xy 387.857254 -377.444567) (xy 382.676228 -377.444567) (xy 382.676228 -377.444574) (xy 382.668465 -377.498565)
			(xy 382.653098 -377.550903) (xy 382.630438 -377.60052) (xy 382.600947 -377.646408) (xy 382.565226 -377.687632)
			(xy 382.524002 -377.723352) (xy 382.478113 -377.752841) (xy 382.428495 -377.7755) (xy 382.376157 -377.790867)
			(xy 382.322166 -377.798629) (xy 382.294892 -377.799092) (xy 381.431292 -377.799092) (xy 381.404025 -377.798545)
			(xy 381.350047 -377.790783) (xy 381.297722 -377.775418) (xy 381.248117 -377.752763) (xy 381.202241 -377.72328)
			(xy 381.161027 -377.687567) (xy 381.125316 -377.646353) (xy 381.095833 -377.600476) (xy 381.073179 -377.55087)
			(xy 381.057815 -377.498546) (xy 381.050054 -377.444567) (xy 375.869028 -377.444567) (xy 375.869028 -377.444574)
			(xy 375.861265 -377.498565) (xy 375.845898 -377.550903) (xy 375.823238 -377.60052) (xy 375.793747 -377.646408)
			(xy 375.758026 -377.687632) (xy 375.716802 -377.723352) (xy 375.670913 -377.752841) (xy 375.621295 -377.7755)
			(xy 375.568957 -377.790867) (xy 375.514966 -377.798629) (xy 375.487692 -377.799092) (xy 374.624092 -377.799092)
			(xy 374.596825 -377.798545) (xy 374.542847 -377.790783) (xy 374.490522 -377.775418) (xy 374.440917 -377.752763)
			(xy 374.395041 -377.72328) (xy 374.353827 -377.687567) (xy 374.318116 -377.646353) (xy 374.288633 -377.600476)
			(xy 374.265979 -377.55087) (xy 374.250615 -377.498546) (xy 374.242854 -377.444567) (xy 369.061828 -377.444567)
			(xy 369.061828 -377.444574) (xy 369.054065 -377.498565) (xy 369.038698 -377.550903) (xy 369.016038 -377.60052)
			(xy 368.986547 -377.646408) (xy 368.950826 -377.687632) (xy 368.909602 -377.723352) (xy 368.863713 -377.752841)
			(xy 368.814095 -377.7755) (xy 368.761757 -377.790867) (xy 368.707766 -377.798629) (xy 368.680492 -377.799092)
			(xy 367.816892 -377.799092) (xy 367.789625 -377.798545) (xy 367.735647 -377.790783) (xy 367.683322 -377.775418)
			(xy 367.633717 -377.752763) (xy 367.587841 -377.72328) (xy 367.546627 -377.687567) (xy 367.510916 -377.646353)
			(xy 367.481433 -377.600476) (xy 367.458779 -377.55087) (xy 367.443415 -377.498546) (xy 367.435654 -377.444567)
			(xy 358.314506 -377.444567) (xy 358.314506 -377.44457) (xy 358.306744 -377.498553) (xy 358.29138 -377.550884)
			(xy 358.268725 -377.600495) (xy 358.239241 -377.646377) (xy 358.203528 -377.687597) (xy 358.162312 -377.723315)
			(xy 358.116433 -377.752804) (xy 358.066825 -377.775465) (xy 358.014497 -377.790835) (xy 357.960513 -377.798602)
			(xy 357.933244 -377.799092) (xy 357.069644 -377.799092) (xy 357.042373 -377.798572) (xy 356.988386 -377.790815)
			(xy 356.936052 -377.775454) (xy 356.886437 -377.752801) (xy 356.840551 -377.723316) (xy 356.799329 -377.687602)
			(xy 356.76361 -377.646384) (xy 356.734121 -377.600502) (xy 356.711461 -377.550889) (xy 356.696094 -377.498557)
			(xy 356.688332 -377.444571) (xy 354.910906 -377.444571) (xy 354.903144 -377.498553) (xy 354.88778 -377.550884)
			(xy 354.865125 -377.600495) (xy 354.835641 -377.646377) (xy 354.799928 -377.687597) (xy 354.758712 -377.723315)
			(xy 354.712833 -377.752804) (xy 354.663225 -377.775465) (xy 354.610897 -377.790835) (xy 354.556913 -377.798602)
			(xy 354.529644 -377.799092) (xy 353.666044 -377.799092) (xy 353.638773 -377.798572) (xy 353.584786 -377.790815)
			(xy 353.532452 -377.775454) (xy 353.482837 -377.752801) (xy 353.436951 -377.723316) (xy 353.395729 -377.687602)
			(xy 353.36001 -377.646384) (xy 353.330521 -377.600502) (xy 353.307861 -377.550889) (xy 353.292494 -377.498557)
			(xy 353.284732 -377.444571) (xy 348.103706 -377.444571) (xy 348.095944 -377.498553) (xy 348.08058 -377.550884)
			(xy 348.057925 -377.600495) (xy 348.028441 -377.646377) (xy 347.992728 -377.687597) (xy 347.951512 -377.723315)
			(xy 347.905633 -377.752804) (xy 347.856025 -377.775465) (xy 347.803697 -377.790835) (xy 347.749713 -377.798602)
			(xy 347.722444 -377.799092) (xy 346.858844 -377.799092) (xy 346.831573 -377.798572) (xy 346.777586 -377.790815)
			(xy 346.725252 -377.775454) (xy 346.675637 -377.752801) (xy 346.629751 -377.723316) (xy 346.588529 -377.687602)
			(xy 346.55281 -377.646384) (xy 346.523321 -377.600502) (xy 346.500661 -377.550889) (xy 346.485294 -377.498557)
			(xy 346.477532 -377.444571) (xy 341.296506 -377.444571) (xy 341.288744 -377.498553) (xy 341.27338 -377.550884)
			(xy 341.250725 -377.600495) (xy 341.221241 -377.646377) (xy 341.185528 -377.687597) (xy 341.144312 -377.723315)
			(xy 341.098433 -377.752804) (xy 341.048825 -377.775465) (xy 340.996497 -377.790835) (xy 340.942513 -377.798602)
			(xy 340.915244 -377.799092) (xy 340.051644 -377.799092) (xy 340.024373 -377.798572) (xy 339.970386 -377.790815)
			(xy 339.918052 -377.775454) (xy 339.868437 -377.752801) (xy 339.822551 -377.723316) (xy 339.781329 -377.687602)
			(xy 339.74561 -377.646384) (xy 339.716121 -377.600502) (xy 339.693461 -377.550889) (xy 339.678094 -377.498557)
			(xy 339.670332 -377.444571) (xy 334.489306 -377.444571) (xy 334.481544 -377.498553) (xy 334.46618 -377.550884)
			(xy 334.443525 -377.600495) (xy 334.414041 -377.646377) (xy 334.378328 -377.687597) (xy 334.337112 -377.723315)
			(xy 334.291233 -377.752804) (xy 334.241625 -377.775465) (xy 334.189297 -377.790835) (xy 334.135313 -377.798602)
			(xy 334.108044 -377.799092) (xy 333.244444 -377.799092) (xy 333.217173 -377.798572) (xy 333.163186 -377.790815)
			(xy 333.110852 -377.775454) (xy 333.061237 -377.752801) (xy 333.015351 -377.723316) (xy 332.974129 -377.687602)
			(xy 332.93841 -377.646384) (xy 332.908921 -377.600502) (xy 332.886261 -377.550889) (xy 332.870894 -377.498557)
			(xy 332.863132 -377.444571) (xy 325.786828 -377.444571) (xy 325.786828 -377.444573) (xy 325.779066 -377.498565)
			(xy 325.763698 -377.550902) (xy 325.741038 -377.600519) (xy 325.711548 -377.646407) (xy 325.675827 -377.68763)
			(xy 325.634603 -377.72335) (xy 325.588716 -377.75284) (xy 325.539098 -377.775499) (xy 325.486761 -377.790866)
			(xy 325.432769 -377.798629) (xy 325.405496 -377.799092) (xy 324.541896 -377.799092) (xy 324.514629 -377.798545)
			(xy 324.46065 -377.790784) (xy 324.408325 -377.775419) (xy 324.358719 -377.752765) (xy 324.312842 -377.723281)
			(xy 324.271629 -377.687569) (xy 324.235917 -377.646354) (xy 324.206433 -377.600477) (xy 324.183779 -377.550871)
			(xy 324.168415 -377.498546) (xy 324.160654 -377.444567) (xy 322.383228 -377.444567) (xy 322.383228 -377.444573)
			(xy 322.375466 -377.498565) (xy 322.360098 -377.550902) (xy 322.337438 -377.600519) (xy 322.307948 -377.646407)
			(xy 322.272227 -377.68763) (xy 322.231003 -377.72335) (xy 322.185116 -377.75284) (xy 322.135498 -377.775499)
			(xy 322.083161 -377.790866) (xy 322.029169 -377.798629) (xy 322.001896 -377.799092) (xy 321.138296 -377.799092)
			(xy 321.111029 -377.798545) (xy 321.05705 -377.790784) (xy 321.004725 -377.775419) (xy 320.955119 -377.752765)
			(xy 320.909242 -377.723281) (xy 320.868029 -377.687569) (xy 320.832317 -377.646354) (xy 320.802833 -377.600477)
			(xy 320.780179 -377.550871) (xy 320.764815 -377.498546) (xy 320.757054 -377.444567) (xy 315.576028 -377.444567)
			(xy 315.576028 -377.444573) (xy 315.568266 -377.498565) (xy 315.552898 -377.550902) (xy 315.530238 -377.600519)
			(xy 315.500748 -377.646407) (xy 315.465027 -377.68763) (xy 315.423803 -377.72335) (xy 315.377916 -377.75284)
			(xy 315.328298 -377.775499) (xy 315.275961 -377.790866) (xy 315.221969 -377.798629) (xy 315.194696 -377.799092)
			(xy 314.331096 -377.799092) (xy 314.303829 -377.798545) (xy 314.24985 -377.790784) (xy 314.197525 -377.775419)
			(xy 314.147919 -377.752765) (xy 314.102042 -377.723281) (xy 314.060829 -377.687569) (xy 314.025117 -377.646354)
			(xy 313.995633 -377.600477) (xy 313.972979 -377.550871) (xy 313.957615 -377.498546) (xy 313.949854 -377.444567)
			(xy 308.768828 -377.444567) (xy 308.768828 -377.444573) (xy 308.761066 -377.498565) (xy 308.745698 -377.550902)
			(xy 308.723038 -377.600519) (xy 308.693548 -377.646407) (xy 308.657827 -377.68763) (xy 308.616603 -377.72335)
			(xy 308.570716 -377.75284) (xy 308.521098 -377.775499) (xy 308.468761 -377.790866) (xy 308.414769 -377.798629)
			(xy 308.387496 -377.799092) (xy 307.523896 -377.799092) (xy 307.496629 -377.798545) (xy 307.44265 -377.790784)
			(xy 307.390325 -377.775419) (xy 307.340719 -377.752765) (xy 307.294842 -377.723281) (xy 307.253629 -377.687569)
			(xy 307.217917 -377.646354) (xy 307.188433 -377.600477) (xy 307.165779 -377.550871) (xy 307.150415 -377.498546)
			(xy 307.142654 -377.444567) (xy 301.961628 -377.444567) (xy 301.961628 -377.444573) (xy 301.953866 -377.498565)
			(xy 301.938498 -377.550902) (xy 301.915838 -377.600519) (xy 301.886348 -377.646407) (xy 301.850627 -377.68763)
			(xy 301.809403 -377.72335) (xy 301.763516 -377.75284) (xy 301.713898 -377.775499) (xy 301.661561 -377.790866)
			(xy 301.607569 -377.798629) (xy 301.580296 -377.799092) (xy 300.716696 -377.799092) (xy 300.689429 -377.798545)
			(xy 300.63545 -377.790784) (xy 300.583125 -377.775419) (xy 300.533519 -377.752765) (xy 300.487642 -377.723281)
			(xy 300.446429 -377.687569) (xy 300.410717 -377.646354) (xy 300.381233 -377.600477) (xy 300.358579 -377.550871)
			(xy 300.343215 -377.498546) (xy 300.335454 -377.444567) (xy 288.290508 -377.444567) (xy 288.290508 -379.908367)
			(xy 298.633654 -379.908367) (xy 298.633654 -379.853833) (xy 298.641415 -379.799854) (xy 298.656779 -379.747529)
			(xy 298.679433 -379.697923) (xy 298.708917 -379.652046) (xy 298.744629 -379.610831) (xy 298.785842 -379.575119)
			(xy 298.831719 -379.545635) (xy 298.881325 -379.522981) (xy 298.93365 -379.507616) (xy 298.987629 -379.499855)
			(xy 299.014896 -379.499368) (xy 299.878496 -379.499368) (xy 299.905769 -379.499771) (xy 299.959761 -379.507534)
			(xy 300.012098 -379.522901) (xy 300.061716 -379.54556) (xy 300.107603 -379.57505) (xy 300.148827 -379.61077)
			(xy 300.184548 -379.651993) (xy 300.214038 -379.697881) (xy 300.236698 -379.747498) (xy 300.252066 -379.799835)
			(xy 300.259828 -379.853827) (xy 300.259828 -379.908367) (xy 305.440854 -379.908367) (xy 305.440854 -379.853833)
			(xy 305.448615 -379.799854) (xy 305.463979 -379.747529) (xy 305.486633 -379.697923) (xy 305.516117 -379.652046)
			(xy 305.551829 -379.610831) (xy 305.593042 -379.575119) (xy 305.638919 -379.545635) (xy 305.688525 -379.522981)
			(xy 305.74085 -379.507616) (xy 305.794829 -379.499855) (xy 305.822096 -379.499368) (xy 306.685696 -379.499368)
			(xy 306.712969 -379.499771) (xy 306.766961 -379.507534) (xy 306.819298 -379.522901) (xy 306.868916 -379.54556)
			(xy 306.914803 -379.57505) (xy 306.956027 -379.61077) (xy 306.991748 -379.651993) (xy 307.021238 -379.697881)
			(xy 307.043898 -379.747498) (xy 307.059266 -379.799835) (xy 307.067028 -379.853827) (xy 307.067028 -379.908367)
			(xy 312.248054 -379.908367) (xy 312.248054 -379.853833) (xy 312.255815 -379.799854) (xy 312.271179 -379.747529)
			(xy 312.293833 -379.697923) (xy 312.323317 -379.652046) (xy 312.359029 -379.610831) (xy 312.400242 -379.575119)
			(xy 312.446119 -379.545635) (xy 312.495725 -379.522981) (xy 312.54805 -379.507616) (xy 312.602029 -379.499855)
			(xy 312.629296 -379.499368) (xy 313.492896 -379.499368) (xy 313.520169 -379.499771) (xy 313.574161 -379.507534)
			(xy 313.626498 -379.522901) (xy 313.676116 -379.54556) (xy 313.722003 -379.57505) (xy 313.763227 -379.61077)
			(xy 313.798948 -379.651993) (xy 313.828438 -379.697881) (xy 313.851098 -379.747498) (xy 313.866466 -379.799835)
			(xy 313.874228 -379.853827) (xy 313.874228 -379.908367) (xy 319.055254 -379.908367) (xy 319.055254 -379.853833)
			(xy 319.063015 -379.799854) (xy 319.078379 -379.747529) (xy 319.101033 -379.697923) (xy 319.130517 -379.652046)
			(xy 319.166229 -379.610831) (xy 319.207442 -379.575119) (xy 319.253319 -379.545635) (xy 319.302925 -379.522981)
			(xy 319.35525 -379.507616) (xy 319.409229 -379.499855) (xy 319.436496 -379.499368) (xy 320.300096 -379.499368)
			(xy 320.327369 -379.499771) (xy 320.381361 -379.507534) (xy 320.433698 -379.522901) (xy 320.483316 -379.54556)
			(xy 320.529203 -379.57505) (xy 320.570427 -379.61077) (xy 320.606148 -379.651993) (xy 320.635638 -379.697881)
			(xy 320.658298 -379.747498) (xy 320.673666 -379.799835) (xy 320.681428 -379.853827) (xy 320.681428 -379.908371)
			(xy 331.161332 -379.908371) (xy 331.161332 -379.853829) (xy 331.169094 -379.799843) (xy 331.184461 -379.747511)
			(xy 331.207121 -379.697898) (xy 331.23661 -379.652016) (xy 331.272329 -379.610798) (xy 331.313551 -379.575084)
			(xy 331.359437 -379.545599) (xy 331.409052 -379.522946) (xy 331.461386 -379.507585) (xy 331.515373 -379.499828)
			(xy 331.542644 -379.499368) (xy 332.406244 -379.499368) (xy 332.433513 -379.499798) (xy 332.487497 -379.507565)
			(xy 332.539825 -379.522935) (xy 332.589433 -379.545596) (xy 332.635312 -379.575085) (xy 332.676528 -379.610803)
			(xy 332.712241 -379.652023) (xy 332.741725 -379.697905) (xy 332.76438 -379.747516) (xy 332.779744 -379.799847)
			(xy 332.787506 -379.85383) (xy 332.787506 -379.90837) (xy 332.787506 -379.908371) (xy 337.968532 -379.908371)
			(xy 337.968532 -379.853829) (xy 337.976294 -379.799843) (xy 337.991661 -379.747511) (xy 338.014321 -379.697898)
			(xy 338.04381 -379.652016) (xy 338.079529 -379.610798) (xy 338.120751 -379.575084) (xy 338.166637 -379.545599)
			(xy 338.216252 -379.522946) (xy 338.268586 -379.507585) (xy 338.322573 -379.499828) (xy 338.349844 -379.499368)
			(xy 339.213444 -379.499368) (xy 339.240713 -379.499798) (xy 339.294697 -379.507565) (xy 339.347025 -379.522935)
			(xy 339.396633 -379.545596) (xy 339.442512 -379.575085) (xy 339.483728 -379.610803) (xy 339.519441 -379.652023)
			(xy 339.548925 -379.697905) (xy 339.57158 -379.747516) (xy 339.586944 -379.799847) (xy 339.594706 -379.85383)
			(xy 339.594706 -379.90837) (xy 339.594706 -379.908371) (xy 344.775732 -379.908371) (xy 344.775732 -379.853829)
			(xy 344.783494 -379.799843) (xy 344.798861 -379.747511) (xy 344.821521 -379.697898) (xy 344.85101 -379.652016)
			(xy 344.886729 -379.610798) (xy 344.927951 -379.575084) (xy 344.973837 -379.545599) (xy 345.023452 -379.522946)
			(xy 345.075786 -379.507585) (xy 345.129773 -379.499828) (xy 345.157044 -379.499368) (xy 346.020644 -379.499368)
			(xy 346.047913 -379.499798) (xy 346.101897 -379.507565) (xy 346.154225 -379.522935) (xy 346.203833 -379.545596)
			(xy 346.249712 -379.575085) (xy 346.290928 -379.610803) (xy 346.326641 -379.652023) (xy 346.356125 -379.697905)
			(xy 346.37878 -379.747516) (xy 346.394144 -379.799847) (xy 346.401906 -379.85383) (xy 346.401906 -379.90837)
			(xy 346.401906 -379.908371) (xy 351.582932 -379.908371) (xy 351.582932 -379.853829) (xy 351.590694 -379.799843)
			(xy 351.606061 -379.747511) (xy 351.628721 -379.697898) (xy 351.65821 -379.652016) (xy 351.693929 -379.610798)
			(xy 351.735151 -379.575084) (xy 351.781037 -379.545599) (xy 351.830652 -379.522946) (xy 351.882986 -379.507585)
			(xy 351.936973 -379.499828) (xy 351.964244 -379.499368) (xy 352.827844 -379.499368) (xy 352.855113 -379.499798)
			(xy 352.909097 -379.507565) (xy 352.961425 -379.522935) (xy 353.011033 -379.545596) (xy 353.056912 -379.575085)
			(xy 353.098128 -379.610803) (xy 353.133841 -379.652023) (xy 353.163325 -379.697905) (xy 353.18598 -379.747516)
			(xy 353.201344 -379.799847) (xy 353.209106 -379.85383) (xy 353.209106 -379.908367) (xy 365.733854 -379.908367)
			(xy 365.733854 -379.853833) (xy 365.741615 -379.799854) (xy 365.756979 -379.74753) (xy 365.779633 -379.697924)
			(xy 365.809116 -379.652047) (xy 365.844827 -379.610833) (xy 365.886041 -379.57512) (xy 365.931917 -379.545637)
			(xy 365.981522 -379.522982) (xy 366.033847 -379.507617) (xy 366.087825 -379.499855) (xy 366.115092 -379.499368)
			(xy 366.978692 -379.499368) (xy 367.005966 -379.499771) (xy 367.059957 -379.507533) (xy 367.112295 -379.5229)
			(xy 367.161913 -379.545559) (xy 367.207802 -379.575048) (xy 367.249026 -379.610768) (xy 367.284747 -379.651992)
			(xy 367.314238 -379.69788) (xy 367.336898 -379.747497) (xy 367.352265 -379.799835) (xy 367.360028 -379.853826)
			(xy 367.360028 -379.908367) (xy 372.541054 -379.908367) (xy 372.541054 -379.853833) (xy 372.548815 -379.799854)
			(xy 372.564179 -379.74753) (xy 372.586833 -379.697924) (xy 372.616316 -379.652047) (xy 372.652027 -379.610833)
			(xy 372.693241 -379.57512) (xy 372.739117 -379.545637) (xy 372.788722 -379.522982) (xy 372.841047 -379.507617)
			(xy 372.895025 -379.499855) (xy 372.922292 -379.499368) (xy 373.785892 -379.499368) (xy 373.813166 -379.499771)
			(xy 373.867157 -379.507533) (xy 373.919495 -379.5229) (xy 373.969113 -379.545559) (xy 374.015002 -379.575048)
			(xy 374.056226 -379.610768) (xy 374.091947 -379.651992) (xy 374.121438 -379.69788) (xy 374.144098 -379.747497)
			(xy 374.159465 -379.799835) (xy 374.167228 -379.853826) (xy 374.167228 -379.908367) (xy 379.348254 -379.908367)
			(xy 379.348254 -379.853833) (xy 379.356015 -379.799854) (xy 379.371379 -379.74753) (xy 379.394033 -379.697924)
			(xy 379.423516 -379.652047) (xy 379.459227 -379.610833) (xy 379.500441 -379.57512) (xy 379.546317 -379.545637)
			(xy 379.595922 -379.522982) (xy 379.648247 -379.507617) (xy 379.702225 -379.499855) (xy 379.729492 -379.499368)
			(xy 380.593092 -379.499368) (xy 380.620366 -379.499771) (xy 380.674357 -379.507533) (xy 380.726695 -379.5229)
			(xy 380.776313 -379.545559) (xy 380.822202 -379.575048) (xy 380.863426 -379.610768) (xy 380.899147 -379.651992)
			(xy 380.928638 -379.69788) (xy 380.951298 -379.747497) (xy 380.966665 -379.799835) (xy 380.974428 -379.853826)
			(xy 380.974428 -379.908367) (xy 386.155454 -379.908367) (xy 386.155454 -379.853833) (xy 386.163215 -379.799854)
			(xy 386.178579 -379.74753) (xy 386.201233 -379.697924) (xy 386.230716 -379.652047) (xy 386.266427 -379.610833)
			(xy 386.307641 -379.57512) (xy 386.353517 -379.545637) (xy 386.403122 -379.522982) (xy 386.455447 -379.507617)
			(xy 386.509425 -379.499855) (xy 386.536692 -379.499368) (xy 387.400292 -379.499368) (xy 387.427566 -379.499771)
			(xy 387.481557 -379.507533) (xy 387.533895 -379.5229) (xy 387.583513 -379.545559) (xy 387.629402 -379.575048)
			(xy 387.670626 -379.610768) (xy 387.706347 -379.651992) (xy 387.735838 -379.69788) (xy 387.758498 -379.747497)
			(xy 387.773865 -379.799835) (xy 387.781628 -379.853826) (xy 387.781628 -379.908371) (xy 398.261532 -379.908371)
			(xy 398.261532 -379.853829) (xy 398.269294 -379.799843) (xy 398.284661 -379.747511) (xy 398.30732 -379.697899)
			(xy 398.336809 -379.652017) (xy 398.372528 -379.6108) (xy 398.41375 -379.575085) (xy 398.459635 -379.545601)
			(xy 398.509249 -379.522947) (xy 398.561582 -379.507586) (xy 398.615569 -379.499829) (xy 398.64284 -379.499368)
			(xy 399.50644 -379.499368) (xy 399.53371 -379.499797) (xy 399.587693 -379.507564) (xy 399.640022 -379.522934)
			(xy 399.689631 -379.545594) (xy 399.735511 -379.575084) (xy 399.776727 -379.610802) (xy 399.81244 -379.652022)
			(xy 399.841925 -379.697904) (xy 399.86458 -379.747516) (xy 399.879944 -379.799846) (xy 399.887706 -379.85383)
			(xy 399.887706 -379.90837) (xy 399.887706 -379.908371) (xy 405.068732 -379.908371) (xy 405.068732 -379.853829)
			(xy 405.076494 -379.799843) (xy 405.091861 -379.747511) (xy 405.11452 -379.697899) (xy 405.144009 -379.652017)
			(xy 405.179728 -379.6108) (xy 405.22095 -379.575085) (xy 405.266835 -379.545601) (xy 405.316449 -379.522947)
			(xy 405.368782 -379.507586) (xy 405.422769 -379.499829) (xy 405.45004 -379.499368) (xy 406.31364 -379.499368)
			(xy 406.34091 -379.499797) (xy 406.394893 -379.507564) (xy 406.447222 -379.522934) (xy 406.496831 -379.545594)
			(xy 406.542711 -379.575084) (xy 406.583927 -379.610802) (xy 406.61964 -379.652022) (xy 406.649125 -379.697904)
			(xy 406.67178 -379.747516) (xy 406.687144 -379.799846) (xy 406.694906 -379.85383) (xy 406.694906 -379.90837)
			(xy 406.694906 -379.908371) (xy 411.875932 -379.908371) (xy 411.875932 -379.853829) (xy 411.883694 -379.799843)
			(xy 411.899061 -379.747511) (xy 411.92172 -379.697899) (xy 411.951209 -379.652017) (xy 411.986928 -379.6108)
			(xy 412.02815 -379.575085) (xy 412.074035 -379.545601) (xy 412.123649 -379.522947) (xy 412.175982 -379.507586)
			(xy 412.229969 -379.499829) (xy 412.25724 -379.499368) (xy 413.12084 -379.499368) (xy 413.14811 -379.499797)
			(xy 413.202093 -379.507564) (xy 413.254422 -379.522934) (xy 413.304031 -379.545594) (xy 413.349911 -379.575084)
			(xy 413.391127 -379.610802) (xy 413.42684 -379.652022) (xy 413.456325 -379.697904) (xy 413.47898 -379.747516)
			(xy 413.494344 -379.799846) (xy 413.502106 -379.85383) (xy 413.502106 -379.90837) (xy 413.502106 -379.908371)
			(xy 418.683132 -379.908371) (xy 418.683132 -379.853829) (xy 418.690894 -379.799843) (xy 418.706261 -379.747511)
			(xy 418.72892 -379.697899) (xy 418.758409 -379.652017) (xy 418.794128 -379.6108) (xy 418.83535 -379.575085)
			(xy 418.881235 -379.545601) (xy 418.930849 -379.522947) (xy 418.983182 -379.507586) (xy 419.037169 -379.499829)
			(xy 419.06444 -379.499368) (xy 419.92804 -379.499368) (xy 419.95531 -379.499797) (xy 420.009293 -379.507564)
			(xy 420.061622 -379.522934) (xy 420.111231 -379.545594) (xy 420.157111 -379.575084) (xy 420.198327 -379.610802)
			(xy 420.23404 -379.652022) (xy 420.263525 -379.697904) (xy 420.28618 -379.747516) (xy 420.301544 -379.799846)
			(xy 420.309306 -379.85383) (xy 420.309306 -379.90837) (xy 420.301544 -379.962354) (xy 420.28618 -380.014684)
			(xy 420.263525 -380.064296) (xy 420.23404 -380.110178) (xy 420.198327 -380.151398) (xy 420.157111 -380.187116)
			(xy 420.111231 -380.216606) (xy 420.061622 -380.239266) (xy 420.009293 -380.254636) (xy 419.95531 -380.262403)
			(xy 419.92804 -380.262892) (xy 419.06444 -380.262892) (xy 419.037169 -380.262371) (xy 418.983182 -380.254614)
			(xy 418.930849 -380.239253) (xy 418.881235 -380.216599) (xy 418.83535 -380.187115) (xy 418.794128 -380.1514)
			(xy 418.758409 -380.110183) (xy 418.72892 -380.064301) (xy 418.706261 -380.014689) (xy 418.690894 -379.962357)
			(xy 418.683132 -379.908371) (xy 413.502106 -379.908371) (xy 413.494344 -379.962354) (xy 413.47898 -380.014684)
			(xy 413.456325 -380.064296) (xy 413.42684 -380.110178) (xy 413.391127 -380.151398) (xy 413.349911 -380.187116)
			(xy 413.304031 -380.216606) (xy 413.254422 -380.239266) (xy 413.202093 -380.254636) (xy 413.14811 -380.262403)
			(xy 413.12084 -380.262892) (xy 412.25724 -380.262892) (xy 412.229969 -380.262371) (xy 412.175982 -380.254614)
			(xy 412.123649 -380.239253) (xy 412.074035 -380.216599) (xy 412.02815 -380.187115) (xy 411.986928 -380.1514)
			(xy 411.951209 -380.110183) (xy 411.92172 -380.064301) (xy 411.899061 -380.014689) (xy 411.883694 -379.962357)
			(xy 411.875932 -379.908371) (xy 406.694906 -379.908371) (xy 406.687144 -379.962354) (xy 406.67178 -380.014684)
			(xy 406.649125 -380.064296) (xy 406.61964 -380.110178) (xy 406.583927 -380.151398) (xy 406.542711 -380.187116)
			(xy 406.496831 -380.216606) (xy 406.447222 -380.239266) (xy 406.394893 -380.254636) (xy 406.34091 -380.262403)
			(xy 406.31364 -380.262892) (xy 405.45004 -380.262892) (xy 405.422769 -380.262371) (xy 405.368782 -380.254614)
			(xy 405.316449 -380.239253) (xy 405.266835 -380.216599) (xy 405.22095 -380.187115) (xy 405.179728 -380.1514)
			(xy 405.144009 -380.110183) (xy 405.11452 -380.064301) (xy 405.091861 -380.014689) (xy 405.076494 -379.962357)
			(xy 405.068732 -379.908371) (xy 399.887706 -379.908371) (xy 399.879944 -379.962354) (xy 399.86458 -380.014684)
			(xy 399.841925 -380.064296) (xy 399.81244 -380.110178) (xy 399.776727 -380.151398) (xy 399.735511 -380.187116)
			(xy 399.689631 -380.216606) (xy 399.640022 -380.239266) (xy 399.587693 -380.254636) (xy 399.53371 -380.262403)
			(xy 399.50644 -380.262892) (xy 398.64284 -380.262892) (xy 398.615569 -380.262371) (xy 398.561582 -380.254614)
			(xy 398.509249 -380.239253) (xy 398.459635 -380.216599) (xy 398.41375 -380.187115) (xy 398.372528 -380.1514)
			(xy 398.336809 -380.110183) (xy 398.30732 -380.064301) (xy 398.284661 -380.014689) (xy 398.269294 -379.962357)
			(xy 398.261532 -379.908371) (xy 387.781628 -379.908371) (xy 387.781628 -379.908374) (xy 387.773865 -379.962365)
			(xy 387.758498 -380.014703) (xy 387.735838 -380.06432) (xy 387.706347 -380.110208) (xy 387.670626 -380.151432)
			(xy 387.629402 -380.187152) (xy 387.583513 -380.216641) (xy 387.533895 -380.2393) (xy 387.481557 -380.254667)
			(xy 387.427566 -380.262429) (xy 387.400292 -380.262892) (xy 386.536692 -380.262892) (xy 386.509425 -380.262345)
			(xy 386.455447 -380.254583) (xy 386.403122 -380.239218) (xy 386.353517 -380.216563) (xy 386.307641 -380.18708)
			(xy 386.266427 -380.151367) (xy 386.230716 -380.110153) (xy 386.201233 -380.064276) (xy 386.178579 -380.01467)
			(xy 386.163215 -379.962346) (xy 386.155454 -379.908367) (xy 380.974428 -379.908367) (xy 380.974428 -379.908374)
			(xy 380.966665 -379.962365) (xy 380.951298 -380.014703) (xy 380.928638 -380.06432) (xy 380.899147 -380.110208)
			(xy 380.863426 -380.151432) (xy 380.822202 -380.187152) (xy 380.776313 -380.216641) (xy 380.726695 -380.2393)
			(xy 380.674357 -380.254667) (xy 380.620366 -380.262429) (xy 380.593092 -380.262892) (xy 379.729492 -380.262892)
			(xy 379.702225 -380.262345) (xy 379.648247 -380.254583) (xy 379.595922 -380.239218) (xy 379.546317 -380.216563)
			(xy 379.500441 -380.18708) (xy 379.459227 -380.151367) (xy 379.423516 -380.110153) (xy 379.394033 -380.064276)
			(xy 379.371379 -380.01467) (xy 379.356015 -379.962346) (xy 379.348254 -379.908367) (xy 374.167228 -379.908367)
			(xy 374.167228 -379.908374) (xy 374.159465 -379.962365) (xy 374.144098 -380.014703) (xy 374.121438 -380.06432)
			(xy 374.091947 -380.110208) (xy 374.056226 -380.151432) (xy 374.015002 -380.187152) (xy 373.969113 -380.216641)
			(xy 373.919495 -380.2393) (xy 373.867157 -380.254667) (xy 373.813166 -380.262429) (xy 373.785892 -380.262892)
			(xy 372.922292 -380.262892) (xy 372.895025 -380.262345) (xy 372.841047 -380.254583) (xy 372.788722 -380.239218)
			(xy 372.739117 -380.216563) (xy 372.693241 -380.18708) (xy 372.652027 -380.151367) (xy 372.616316 -380.110153)
			(xy 372.586833 -380.064276) (xy 372.564179 -380.01467) (xy 372.548815 -379.962346) (xy 372.541054 -379.908367)
			(xy 367.360028 -379.908367) (xy 367.360028 -379.908374) (xy 367.352265 -379.962365) (xy 367.336898 -380.014703)
			(xy 367.314238 -380.06432) (xy 367.284747 -380.110208) (xy 367.249026 -380.151432) (xy 367.207802 -380.187152)
			(xy 367.161913 -380.216641) (xy 367.112295 -380.2393) (xy 367.059957 -380.254667) (xy 367.005966 -380.262429)
			(xy 366.978692 -380.262892) (xy 366.115092 -380.262892) (xy 366.087825 -380.262345) (xy 366.033847 -380.254583)
			(xy 365.981522 -380.239218) (xy 365.931917 -380.216563) (xy 365.886041 -380.18708) (xy 365.844827 -380.151367)
			(xy 365.809116 -380.110153) (xy 365.779633 -380.064276) (xy 365.756979 -380.01467) (xy 365.741615 -379.962346)
			(xy 365.733854 -379.908367) (xy 353.209106 -379.908367) (xy 353.209106 -379.90837) (xy 353.201344 -379.962353)
			(xy 353.18598 -380.014684) (xy 353.163325 -380.064295) (xy 353.133841 -380.110177) (xy 353.098128 -380.151397)
			(xy 353.056912 -380.187115) (xy 353.011033 -380.216604) (xy 352.961425 -380.239265) (xy 352.909097 -380.254635)
			(xy 352.855113 -380.262402) (xy 352.827844 -380.262892) (xy 351.964244 -380.262892) (xy 351.936973 -380.262372)
			(xy 351.882986 -380.254615) (xy 351.830652 -380.239254) (xy 351.781037 -380.216601) (xy 351.735151 -380.187116)
			(xy 351.693929 -380.151402) (xy 351.65821 -380.110184) (xy 351.628721 -380.064302) (xy 351.606061 -380.014689)
			(xy 351.590694 -379.962357) (xy 351.582932 -379.908371) (xy 346.401906 -379.908371) (xy 346.394144 -379.962353)
			(xy 346.37878 -380.014684) (xy 346.356125 -380.064295) (xy 346.326641 -380.110177) (xy 346.290928 -380.151397)
			(xy 346.249712 -380.187115) (xy 346.203833 -380.216604) (xy 346.154225 -380.239265) (xy 346.101897 -380.254635)
			(xy 346.047913 -380.262402) (xy 346.020644 -380.262892) (xy 345.157044 -380.262892) (xy 345.129773 -380.262372)
			(xy 345.075786 -380.254615) (xy 345.023452 -380.239254) (xy 344.973837 -380.216601) (xy 344.927951 -380.187116)
			(xy 344.886729 -380.151402) (xy 344.85101 -380.110184) (xy 344.821521 -380.064302) (xy 344.798861 -380.014689)
			(xy 344.783494 -379.962357) (xy 344.775732 -379.908371) (xy 339.594706 -379.908371) (xy 339.586944 -379.962353)
			(xy 339.57158 -380.014684) (xy 339.548925 -380.064295) (xy 339.519441 -380.110177) (xy 339.483728 -380.151397)
			(xy 339.442512 -380.187115) (xy 339.396633 -380.216604) (xy 339.347025 -380.239265) (xy 339.294697 -380.254635)
			(xy 339.240713 -380.262402) (xy 339.213444 -380.262892) (xy 338.349844 -380.262892) (xy 338.322573 -380.262372)
			(xy 338.268586 -380.254615) (xy 338.216252 -380.239254) (xy 338.166637 -380.216601) (xy 338.120751 -380.187116)
			(xy 338.079529 -380.151402) (xy 338.04381 -380.110184) (xy 338.014321 -380.064302) (xy 337.991661 -380.014689)
			(xy 337.976294 -379.962357) (xy 337.968532 -379.908371) (xy 332.787506 -379.908371) (xy 332.779744 -379.962353)
			(xy 332.76438 -380.014684) (xy 332.741725 -380.064295) (xy 332.712241 -380.110177) (xy 332.676528 -380.151397)
			(xy 332.635312 -380.187115) (xy 332.589433 -380.216604) (xy 332.539825 -380.239265) (xy 332.487497 -380.254635)
			(xy 332.433513 -380.262402) (xy 332.406244 -380.262892) (xy 331.542644 -380.262892) (xy 331.515373 -380.262372)
			(xy 331.461386 -380.254615) (xy 331.409052 -380.239254) (xy 331.359437 -380.216601) (xy 331.313551 -380.187116)
			(xy 331.272329 -380.151402) (xy 331.23661 -380.110184) (xy 331.207121 -380.064302) (xy 331.184461 -380.014689)
			(xy 331.169094 -379.962357) (xy 331.161332 -379.908371) (xy 320.681428 -379.908371) (xy 320.681428 -379.908373)
			(xy 320.673666 -379.962365) (xy 320.658298 -380.014702) (xy 320.635638 -380.064319) (xy 320.606148 -380.110207)
			(xy 320.570427 -380.15143) (xy 320.529203 -380.18715) (xy 320.483316 -380.21664) (xy 320.433698 -380.239299)
			(xy 320.381361 -380.254666) (xy 320.327369 -380.262429) (xy 320.300096 -380.262892) (xy 319.436496 -380.262892)
			(xy 319.409229 -380.262345) (xy 319.35525 -380.254584) (xy 319.302925 -380.239219) (xy 319.253319 -380.216565)
			(xy 319.207442 -380.187081) (xy 319.166229 -380.151369) (xy 319.130517 -380.110154) (xy 319.101033 -380.064277)
			(xy 319.078379 -380.014671) (xy 319.063015 -379.962346) (xy 319.055254 -379.908367) (xy 313.874228 -379.908367)
			(xy 313.874228 -379.908373) (xy 313.866466 -379.962365) (xy 313.851098 -380.014702) (xy 313.828438 -380.064319)
			(xy 313.798948 -380.110207) (xy 313.763227 -380.15143) (xy 313.722003 -380.18715) (xy 313.676116 -380.21664)
			(xy 313.626498 -380.239299) (xy 313.574161 -380.254666) (xy 313.520169 -380.262429) (xy 313.492896 -380.262892)
			(xy 312.629296 -380.262892) (xy 312.602029 -380.262345) (xy 312.54805 -380.254584) (xy 312.495725 -380.239219)
			(xy 312.446119 -380.216565) (xy 312.400242 -380.187081) (xy 312.359029 -380.151369) (xy 312.323317 -380.110154)
			(xy 312.293833 -380.064277) (xy 312.271179 -380.014671) (xy 312.255815 -379.962346) (xy 312.248054 -379.908367)
			(xy 307.067028 -379.908367) (xy 307.067028 -379.908373) (xy 307.059266 -379.962365) (xy 307.043898 -380.014702)
			(xy 307.021238 -380.064319) (xy 306.991748 -380.110207) (xy 306.956027 -380.15143) (xy 306.914803 -380.18715)
			(xy 306.868916 -380.21664) (xy 306.819298 -380.239299) (xy 306.766961 -380.254666) (xy 306.712969 -380.262429)
			(xy 306.685696 -380.262892) (xy 305.822096 -380.262892) (xy 305.794829 -380.262345) (xy 305.74085 -380.254584)
			(xy 305.688525 -380.239219) (xy 305.638919 -380.216565) (xy 305.593042 -380.187081) (xy 305.551829 -380.151369)
			(xy 305.516117 -380.110154) (xy 305.486633 -380.064277) (xy 305.463979 -380.014671) (xy 305.448615 -379.962346)
			(xy 305.440854 -379.908367) (xy 300.259828 -379.908367) (xy 300.259828 -379.908373) (xy 300.252066 -379.962365)
			(xy 300.236698 -380.014702) (xy 300.214038 -380.064319) (xy 300.184548 -380.110207) (xy 300.148827 -380.15143)
			(xy 300.107603 -380.18715) (xy 300.061716 -380.21664) (xy 300.012098 -380.239299) (xy 299.959761 -380.254666)
			(xy 299.905769 -380.262429) (xy 299.878496 -380.262892) (xy 299.014896 -380.262892) (xy 298.987629 -380.262345)
			(xy 298.93365 -380.254584) (xy 298.881325 -380.239219) (xy 298.831719 -380.216565) (xy 298.785842 -380.187081)
			(xy 298.744629 -380.151369) (xy 298.708917 -380.110154) (xy 298.679433 -380.064277) (xy 298.656779 -380.014671)
			(xy 298.641415 -379.962346) (xy 298.633654 -379.908367) (xy 288.290508 -379.908367) (xy 288.290508 -381.36068)
			(xy 288.290836 -381.370157) (xy 288.297619 -381.387852) (xy 288.310374 -381.401867) (xy 288.318702 -381.4064)
			(xy 288.41319 -381.453136) (xy 288.442146 -381.450342) (xy 288.453576 -381.441706) (xy 288.528371 -381.385444)
			(xy 288.682126 -381.278688) (xy 288.840363 -381.178695) (xy 289.002785 -381.085653) (xy 289.169087 -380.999738)
			(xy 289.338955 -380.92111) (xy 289.512072 -380.849918) (xy 289.688111 -380.786295) (xy 289.866741 -380.730361)
			(xy 290.047629 -380.682221) (xy 290.230432 -380.641965) (xy 290.414808 -380.609669) (xy 290.600411 -380.585394)
			(xy 290.786891 -380.569185) (xy 290.973898 -380.561072) (xy 291.06749 -380.56058) (xy 291.160408 -380.561073)
			(xy 291.346072 -380.569067) (xy 291.53122 -380.585042) (xy 291.715509 -380.608968) (xy 291.898599 -380.6408)
			(xy 292.080149 -380.680479) (xy 292.259824 -380.727933) (xy 292.437292 -380.783072) (xy 292.612222 -380.845796)
			(xy 292.784293 -380.915987) (xy 292.953184 -380.993517) (xy 293.118583 -381.07824) (xy 293.280184 -381.170001)
			(xy 293.437688 -381.26863) (xy 293.590803 -381.373943) (xy 293.739245 -381.485746) (xy 293.882739 -381.603832)
			(xy 294.021021 -381.727982) (xy 294.153833 -381.857967) (xy 294.28093 -381.993545) (xy 294.402076 -382.134465)
			(xy 294.517048 -382.280467) (xy 294.583071 -382.372167) (xy 303.739054 -382.372167) (xy 303.739054 -382.317633)
			(xy 303.746815 -382.263654) (xy 303.762179 -382.211329) (xy 303.784833 -382.161723) (xy 303.814317 -382.115846)
			(xy 303.850029 -382.074631) (xy 303.891242 -382.038919) (xy 303.937119 -382.009435) (xy 303.986725 -381.986781)
			(xy 304.03905 -381.971416) (xy 304.093029 -381.963655) (xy 304.120296 -381.963168) (xy 304.983896 -381.963168)
			(xy 305.011169 -381.963571) (xy 305.065161 -381.971334) (xy 305.117498 -381.986701) (xy 305.167116 -382.00936)
			(xy 305.213003 -382.03885) (xy 305.254227 -382.07457) (xy 305.289948 -382.115793) (xy 305.319438 -382.161681)
			(xy 305.342098 -382.211298) (xy 305.357466 -382.263635) (xy 305.365228 -382.317627) (xy 305.365228 -382.372167)
			(xy 310.546254 -382.372167) (xy 310.546254 -382.317633) (xy 310.554015 -382.263654) (xy 310.569379 -382.211329)
			(xy 310.592033 -382.161723) (xy 310.621517 -382.115846) (xy 310.657229 -382.074631) (xy 310.698442 -382.038919)
			(xy 310.744319 -382.009435) (xy 310.793925 -381.986781) (xy 310.84625 -381.971416) (xy 310.900229 -381.963655)
			(xy 310.927496 -381.963168) (xy 311.791096 -381.963168) (xy 311.818369 -381.963571) (xy 311.872361 -381.971334)
			(xy 311.924698 -381.986701) (xy 311.974316 -382.00936) (xy 312.020203 -382.03885) (xy 312.061427 -382.07457)
			(xy 312.097148 -382.115793) (xy 312.126638 -382.161681) (xy 312.149298 -382.211298) (xy 312.164666 -382.263635)
			(xy 312.172428 -382.317627) (xy 312.172428 -382.372167) (xy 317.353454 -382.372167) (xy 317.353454 -382.317633)
			(xy 317.361215 -382.263654) (xy 317.376579 -382.211329) (xy 317.399233 -382.161723) (xy 317.428717 -382.115846)
			(xy 317.464429 -382.074631) (xy 317.505642 -382.038919) (xy 317.551519 -382.009435) (xy 317.601125 -381.986781)
			(xy 317.65345 -381.971416) (xy 317.707429 -381.963655) (xy 317.734696 -381.963168) (xy 318.598296 -381.963168)
			(xy 318.625569 -381.963571) (xy 318.679561 -381.971334) (xy 318.731898 -381.986701) (xy 318.781516 -382.00936)
			(xy 318.827403 -382.03885) (xy 318.868627 -382.07457) (xy 318.904348 -382.115793) (xy 318.933838 -382.161681)
			(xy 318.956498 -382.211298) (xy 318.971866 -382.263635) (xy 318.979628 -382.317627) (xy 318.979628 -382.372171)
			(xy 336.266732 -382.372171) (xy 336.266732 -382.317629) (xy 336.274494 -382.263643) (xy 336.289861 -382.211311)
			(xy 336.312521 -382.161698) (xy 336.34201 -382.115816) (xy 336.377729 -382.074598) (xy 336.418951 -382.038884)
			(xy 336.464837 -382.009399) (xy 336.514452 -381.986746) (xy 336.566786 -381.971385) (xy 336.620773 -381.963628)
			(xy 336.648044 -381.963168) (xy 337.511644 -381.963168) (xy 337.538913 -381.963598) (xy 337.592897 -381.971365)
			(xy 337.645225 -381.986735) (xy 337.694833 -382.009396) (xy 337.740712 -382.038885) (xy 337.781928 -382.074603)
			(xy 337.817641 -382.115823) (xy 337.847125 -382.161705) (xy 337.86978 -382.211316) (xy 337.885144 -382.263647)
			(xy 337.892906 -382.31763) (xy 337.892906 -382.37217) (xy 337.892906 -382.372171) (xy 343.073932 -382.372171)
			(xy 343.073932 -382.317629) (xy 343.081694 -382.263643) (xy 343.097061 -382.211311) (xy 343.119721 -382.161698)
			(xy 343.14921 -382.115816) (xy 343.184929 -382.074598) (xy 343.226151 -382.038884) (xy 343.272037 -382.009399)
			(xy 343.321652 -381.986746) (xy 343.373986 -381.971385) (xy 343.427973 -381.963628) (xy 343.455244 -381.963168)
			(xy 344.318844 -381.963168) (xy 344.346113 -381.963598) (xy 344.400097 -381.971365) (xy 344.452425 -381.986735)
			(xy 344.502033 -382.009396) (xy 344.547912 -382.038885) (xy 344.589128 -382.074603) (xy 344.624841 -382.115823)
			(xy 344.654325 -382.161705) (xy 344.67698 -382.211316) (xy 344.692344 -382.263647) (xy 344.700106 -382.31763)
			(xy 344.700106 -382.37217) (xy 344.700106 -382.372171) (xy 349.881132 -382.372171) (xy 349.881132 -382.317629)
			(xy 349.888894 -382.263643) (xy 349.904261 -382.211311) (xy 349.926921 -382.161698) (xy 349.95641 -382.115816)
			(xy 349.992129 -382.074598) (xy 350.033351 -382.038884) (xy 350.079237 -382.009399) (xy 350.128852 -381.986746)
			(xy 350.181186 -381.971385) (xy 350.235173 -381.963628) (xy 350.262444 -381.963168) (xy 351.126044 -381.963168)
			(xy 351.153313 -381.963598) (xy 351.207297 -381.971365) (xy 351.259625 -381.986735) (xy 351.309233 -382.009396)
			(xy 351.355112 -382.038885) (xy 351.396328 -382.074603) (xy 351.432041 -382.115823) (xy 351.461525 -382.161705)
			(xy 351.48418 -382.211316) (xy 351.499544 -382.263647) (xy 351.507306 -382.31763) (xy 351.507306 -382.372167)
			(xy 370.839254 -382.372167) (xy 370.839254 -382.317633) (xy 370.847015 -382.263654) (xy 370.862379 -382.21133)
			(xy 370.885033 -382.161724) (xy 370.914516 -382.115847) (xy 370.950227 -382.074633) (xy 370.991441 -382.03892)
			(xy 371.037317 -382.009437) (xy 371.086922 -381.986782) (xy 371.139247 -381.971417) (xy 371.193225 -381.963655)
			(xy 371.220492 -381.963168) (xy 372.084092 -381.963168) (xy 372.111366 -381.963571) (xy 372.165357 -381.971333)
			(xy 372.217695 -381.9867) (xy 372.267313 -382.009359) (xy 372.313202 -382.038848) (xy 372.354426 -382.074568)
			(xy 372.390147 -382.115792) (xy 372.419638 -382.16168) (xy 372.442298 -382.211297) (xy 372.457665 -382.263635)
			(xy 372.465428 -382.317626) (xy 372.465428 -382.372167) (xy 377.646454 -382.372167) (xy 377.646454 -382.317633)
			(xy 377.654215 -382.263654) (xy 377.669579 -382.21133) (xy 377.692233 -382.161724) (xy 377.721716 -382.115847)
			(xy 377.757427 -382.074633) (xy 377.798641 -382.03892) (xy 377.844517 -382.009437) (xy 377.894122 -381.986782)
			(xy 377.946447 -381.971417) (xy 378.000425 -381.963655) (xy 378.027692 -381.963168) (xy 378.891292 -381.963168)
			(xy 378.918566 -381.963571) (xy 378.972557 -381.971333) (xy 379.024895 -381.9867) (xy 379.074513 -382.009359)
			(xy 379.120402 -382.038848) (xy 379.161626 -382.074568) (xy 379.197347 -382.115792) (xy 379.226838 -382.16168)
			(xy 379.249498 -382.211297) (xy 379.264865 -382.263635) (xy 379.272628 -382.317626) (xy 379.272628 -382.372167)
			(xy 384.453654 -382.372167) (xy 384.453654 -382.317633) (xy 384.461415 -382.263654) (xy 384.476779 -382.21133)
			(xy 384.499433 -382.161724) (xy 384.528916 -382.115847) (xy 384.564627 -382.074633) (xy 384.605841 -382.03892)
			(xy 384.651717 -382.009437) (xy 384.701322 -381.986782) (xy 384.753647 -381.971417) (xy 384.807625 -381.963655)
			(xy 384.834892 -381.963168) (xy 385.698492 -381.963168) (xy 385.725766 -381.963571) (xy 385.779757 -381.971333)
			(xy 385.832095 -381.9867) (xy 385.881713 -382.009359) (xy 385.927602 -382.038848) (xy 385.968826 -382.074568)
			(xy 386.004547 -382.115792) (xy 386.034038 -382.16168) (xy 386.056698 -382.211297) (xy 386.072065 -382.263635)
			(xy 386.079828 -382.317626) (xy 386.079828 -382.372171) (xy 403.366932 -382.372171) (xy 403.366932 -382.317629)
			(xy 403.374694 -382.263643) (xy 403.390061 -382.211311) (xy 403.41272 -382.161699) (xy 403.442209 -382.115817)
			(xy 403.477928 -382.0746) (xy 403.51915 -382.038885) (xy 403.565035 -382.009401) (xy 403.614649 -381.986747)
			(xy 403.666982 -381.971386) (xy 403.720969 -381.963629) (xy 403.74824 -381.963168) (xy 404.61184 -381.963168)
			(xy 404.63911 -381.963597) (xy 404.693093 -381.971364) (xy 404.745422 -381.986734) (xy 404.795031 -382.009394)
			(xy 404.840911 -382.038884) (xy 404.882127 -382.074602) (xy 404.91784 -382.115822) (xy 404.947325 -382.161704)
			(xy 404.96998 -382.211316) (xy 404.985344 -382.263646) (xy 404.993106 -382.31763) (xy 404.993106 -382.37217)
			(xy 404.993106 -382.372171) (xy 410.174132 -382.372171) (xy 410.174132 -382.317629) (xy 410.181894 -382.263643)
			(xy 410.197261 -382.211311) (xy 410.21992 -382.161699) (xy 410.249409 -382.115817) (xy 410.285128 -382.0746)
			(xy 410.32635 -382.038885) (xy 410.372235 -382.009401) (xy 410.421849 -381.986747) (xy 410.474182 -381.971386)
			(xy 410.528169 -381.963629) (xy 410.55544 -381.963168) (xy 411.41904 -381.963168) (xy 411.44631 -381.963597)
			(xy 411.500293 -381.971364) (xy 411.552622 -381.986734) (xy 411.602231 -382.009394) (xy 411.648111 -382.038884)
			(xy 411.689327 -382.074602) (xy 411.72504 -382.115822) (xy 411.754525 -382.161704) (xy 411.77718 -382.211316)
			(xy 411.792544 -382.263646) (xy 411.800306 -382.31763) (xy 411.800306 -382.37217) (xy 411.800306 -382.372171)
			(xy 416.981332 -382.372171) (xy 416.981332 -382.317629) (xy 416.989094 -382.263643) (xy 417.004461 -382.211311)
			(xy 417.02712 -382.161699) (xy 417.056609 -382.115817) (xy 417.092328 -382.0746) (xy 417.13355 -382.038885)
			(xy 417.179435 -382.009401) (xy 417.229049 -381.986747) (xy 417.281382 -381.971386) (xy 417.335369 -381.963629)
			(xy 417.36264 -381.963168) (xy 418.22624 -381.963168) (xy 418.25351 -381.963597) (xy 418.307493 -381.971364)
			(xy 418.359822 -381.986734) (xy 418.409431 -382.009394) (xy 418.455311 -382.038884) (xy 418.496527 -382.074602)
			(xy 418.53224 -382.115822) (xy 418.561725 -382.161704) (xy 418.58438 -382.211316) (xy 418.599744 -382.263646)
			(xy 418.607506 -382.31763) (xy 418.607506 -382.37217) (xy 418.599744 -382.426154) (xy 418.58438 -382.478484)
			(xy 418.561725 -382.528096) (xy 418.53224 -382.573978) (xy 418.496527 -382.615198) (xy 418.455311 -382.650916)
			(xy 418.409431 -382.680406) (xy 418.359822 -382.703066) (xy 418.307493 -382.718436) (xy 418.25351 -382.726203)
			(xy 418.22624 -382.726692) (xy 417.36264 -382.726692) (xy 417.335369 -382.726171) (xy 417.281382 -382.718414)
			(xy 417.229049 -382.703053) (xy 417.179435 -382.680399) (xy 417.13355 -382.650915) (xy 417.092328 -382.6152)
			(xy 417.056609 -382.573983) (xy 417.02712 -382.528101) (xy 417.004461 -382.478489) (xy 416.989094 -382.426157)
			(xy 416.981332 -382.372171) (xy 411.800306 -382.372171) (xy 411.792544 -382.426154) (xy 411.77718 -382.478484)
			(xy 411.754525 -382.528096) (xy 411.72504 -382.573978) (xy 411.689327 -382.615198) (xy 411.648111 -382.650916)
			(xy 411.602231 -382.680406) (xy 411.552622 -382.703066) (xy 411.500293 -382.718436) (xy 411.44631 -382.726203)
			(xy 411.41904 -382.726692) (xy 410.55544 -382.726692) (xy 410.528169 -382.726171) (xy 410.474182 -382.718414)
			(xy 410.421849 -382.703053) (xy 410.372235 -382.680399) (xy 410.32635 -382.650915) (xy 410.285128 -382.6152)
			(xy 410.249409 -382.573983) (xy 410.21992 -382.528101) (xy 410.197261 -382.478489) (xy 410.181894 -382.426157)
			(xy 410.174132 -382.372171) (xy 404.993106 -382.372171) (xy 404.985344 -382.426154) (xy 404.96998 -382.478484)
			(xy 404.947325 -382.528096) (xy 404.91784 -382.573978) (xy 404.882127 -382.615198) (xy 404.840911 -382.650916)
			(xy 404.795031 -382.680406) (xy 404.745422 -382.703066) (xy 404.693093 -382.718436) (xy 404.63911 -382.726203)
			(xy 404.61184 -382.726692) (xy 403.74824 -382.726692) (xy 403.720969 -382.726171) (xy 403.666982 -382.718414)
			(xy 403.614649 -382.703053) (xy 403.565035 -382.680399) (xy 403.51915 -382.650915) (xy 403.477928 -382.6152)
			(xy 403.442209 -382.573983) (xy 403.41272 -382.528101) (xy 403.390061 -382.478489) (xy 403.374694 -382.426157)
			(xy 403.366932 -382.372171) (xy 386.079828 -382.372171) (xy 386.079828 -382.372174) (xy 386.072065 -382.426165)
			(xy 386.056698 -382.478503) (xy 386.034038 -382.52812) (xy 386.004547 -382.574008) (xy 385.968826 -382.615232)
			(xy 385.927602 -382.650952) (xy 385.881713 -382.680441) (xy 385.832095 -382.7031) (xy 385.779757 -382.718467)
			(xy 385.725766 -382.726229) (xy 385.698492 -382.726692) (xy 384.834892 -382.726692) (xy 384.807625 -382.726145)
			(xy 384.753647 -382.718383) (xy 384.701322 -382.703018) (xy 384.651717 -382.680363) (xy 384.605841 -382.65088)
			(xy 384.564627 -382.615167) (xy 384.528916 -382.573953) (xy 384.499433 -382.528076) (xy 384.476779 -382.47847)
			(xy 384.461415 -382.426146) (xy 384.453654 -382.372167) (xy 379.272628 -382.372167) (xy 379.272628 -382.372174)
			(xy 379.264865 -382.426165) (xy 379.249498 -382.478503) (xy 379.226838 -382.52812) (xy 379.197347 -382.574008)
			(xy 379.161626 -382.615232) (xy 379.120402 -382.650952) (xy 379.074513 -382.680441) (xy 379.024895 -382.7031)
			(xy 378.972557 -382.718467) (xy 378.918566 -382.726229) (xy 378.891292 -382.726692) (xy 378.027692 -382.726692)
			(xy 378.000425 -382.726145) (xy 377.946447 -382.718383) (xy 377.894122 -382.703018) (xy 377.844517 -382.680363)
			(xy 377.798641 -382.65088) (xy 377.757427 -382.615167) (xy 377.721716 -382.573953) (xy 377.692233 -382.528076)
			(xy 377.669579 -382.47847) (xy 377.654215 -382.426146) (xy 377.646454 -382.372167) (xy 372.465428 -382.372167)
			(xy 372.465428 -382.372174) (xy 372.457665 -382.426165) (xy 372.442298 -382.478503) (xy 372.419638 -382.52812)
			(xy 372.390147 -382.574008) (xy 372.354426 -382.615232) (xy 372.313202 -382.650952) (xy 372.267313 -382.680441)
			(xy 372.217695 -382.7031) (xy 372.165357 -382.718467) (xy 372.111366 -382.726229) (xy 372.084092 -382.726692)
			(xy 371.220492 -382.726692) (xy 371.193225 -382.726145) (xy 371.139247 -382.718383) (xy 371.086922 -382.703018)
			(xy 371.037317 -382.680363) (xy 370.991441 -382.65088) (xy 370.950227 -382.615167) (xy 370.914516 -382.573953)
			(xy 370.885033 -382.528076) (xy 370.862379 -382.47847) (xy 370.847015 -382.426146) (xy 370.839254 -382.372167)
			(xy 351.507306 -382.372167) (xy 351.507306 -382.37217) (xy 351.499544 -382.426153) (xy 351.48418 -382.478484)
			(xy 351.461525 -382.528095) (xy 351.432041 -382.573977) (xy 351.396328 -382.615197) (xy 351.355112 -382.650915)
			(xy 351.309233 -382.680404) (xy 351.259625 -382.703065) (xy 351.207297 -382.718435) (xy 351.153313 -382.726202)
			(xy 351.126044 -382.726692) (xy 350.262444 -382.726692) (xy 350.235173 -382.726172) (xy 350.181186 -382.718415)
			(xy 350.128852 -382.703054) (xy 350.079237 -382.680401) (xy 350.033351 -382.650916) (xy 349.992129 -382.615202)
			(xy 349.95641 -382.573984) (xy 349.926921 -382.528102) (xy 349.904261 -382.478489) (xy 349.888894 -382.426157)
			(xy 349.881132 -382.372171) (xy 344.700106 -382.372171) (xy 344.692344 -382.426153) (xy 344.67698 -382.478484)
			(xy 344.654325 -382.528095) (xy 344.624841 -382.573977) (xy 344.589128 -382.615197) (xy 344.547912 -382.650915)
			(xy 344.502033 -382.680404) (xy 344.452425 -382.703065) (xy 344.400097 -382.718435) (xy 344.346113 -382.726202)
			(xy 344.318844 -382.726692) (xy 343.455244 -382.726692) (xy 343.427973 -382.726172) (xy 343.373986 -382.718415)
			(xy 343.321652 -382.703054) (xy 343.272037 -382.680401) (xy 343.226151 -382.650916) (xy 343.184929 -382.615202)
			(xy 343.14921 -382.573984) (xy 343.119721 -382.528102) (xy 343.097061 -382.478489) (xy 343.081694 -382.426157)
			(xy 343.073932 -382.372171) (xy 337.892906 -382.372171) (xy 337.885144 -382.426153) (xy 337.86978 -382.478484)
			(xy 337.847125 -382.528095) (xy 337.817641 -382.573977) (xy 337.781928 -382.615197) (xy 337.740712 -382.650915)
			(xy 337.694833 -382.680404) (xy 337.645225 -382.703065) (xy 337.592897 -382.718435) (xy 337.538913 -382.726202)
			(xy 337.511644 -382.726692) (xy 336.648044 -382.726692) (xy 336.620773 -382.726172) (xy 336.566786 -382.718415)
			(xy 336.514452 -382.703054) (xy 336.464837 -382.680401) (xy 336.418951 -382.650916) (xy 336.377729 -382.615202)
			(xy 336.34201 -382.573984) (xy 336.312521 -382.528102) (xy 336.289861 -382.478489) (xy 336.274494 -382.426157)
			(xy 336.266732 -382.372171) (xy 318.979628 -382.372171) (xy 318.979628 -382.372173) (xy 318.971866 -382.426165)
			(xy 318.956498 -382.478502) (xy 318.933838 -382.528119) (xy 318.904348 -382.574007) (xy 318.868627 -382.61523)
			(xy 318.827403 -382.65095) (xy 318.781516 -382.68044) (xy 318.731898 -382.703099) (xy 318.679561 -382.718466)
			(xy 318.625569 -382.726229) (xy 318.598296 -382.726692) (xy 317.734696 -382.726692) (xy 317.707429 -382.726145)
			(xy 317.65345 -382.718384) (xy 317.601125 -382.703019) (xy 317.551519 -382.680365) (xy 317.505642 -382.650881)
			(xy 317.464429 -382.615169) (xy 317.428717 -382.573954) (xy 317.399233 -382.528077) (xy 317.376579 -382.478471)
			(xy 317.361215 -382.426146) (xy 317.353454 -382.372167) (xy 312.172428 -382.372167) (xy 312.172428 -382.372173)
			(xy 312.164666 -382.426165) (xy 312.149298 -382.478502) (xy 312.126638 -382.528119) (xy 312.097148 -382.574007)
			(xy 312.061427 -382.61523) (xy 312.020203 -382.65095) (xy 311.974316 -382.68044) (xy 311.924698 -382.703099)
			(xy 311.872361 -382.718466) (xy 311.818369 -382.726229) (xy 311.791096 -382.726692) (xy 310.927496 -382.726692)
			(xy 310.900229 -382.726145) (xy 310.84625 -382.718384) (xy 310.793925 -382.703019) (xy 310.744319 -382.680365)
			(xy 310.698442 -382.650881) (xy 310.657229 -382.615169) (xy 310.621517 -382.573954) (xy 310.592033 -382.528077)
			(xy 310.569379 -382.478471) (xy 310.554015 -382.426146) (xy 310.546254 -382.372167) (xy 305.365228 -382.372167)
			(xy 305.365228 -382.372173) (xy 305.357466 -382.426165) (xy 305.342098 -382.478502) (xy 305.319438 -382.528119)
			(xy 305.289948 -382.574007) (xy 305.254227 -382.61523) (xy 305.213003 -382.65095) (xy 305.167116 -382.68044)
			(xy 305.117498 -382.703099) (xy 305.065161 -382.718466) (xy 305.011169 -382.726229) (xy 304.983896 -382.726692)
			(xy 304.120296 -382.726692) (xy 304.093029 -382.726145) (xy 304.03905 -382.718384) (xy 303.986725 -382.703019)
			(xy 303.937119 -382.680365) (xy 303.891242 -382.650881) (xy 303.850029 -382.615169) (xy 303.814317 -382.573954)
			(xy 303.784833 -382.528077) (xy 303.762179 -382.478471) (xy 303.746815 -382.426146) (xy 303.739054 -382.372167)
			(xy 294.583071 -382.372167) (xy 294.625632 -382.43128) (xy 294.727626 -382.586625) (xy 294.822844 -382.746214)
			(xy 294.911107 -382.909752) (xy 294.992252 -383.076936) (xy 295.06613 -383.247456) (xy 295.132604 -383.420996)
			(xy 295.191549 -383.597236) (xy 295.242858 -383.775848) (xy 295.286435 -383.956503) (xy 295.322199 -384.138865)
			(xy 295.350085 -384.322597) (xy 295.370041 -384.507358) (xy 295.382029 -384.692807) (xy 295.386027 -384.8786)
			(xy 295.382029 -385.064393) (xy 295.372367 -385.21386) (xy 297.048936 -385.21386) (xy 297.048936 -384.35026)
			(xy 297.049422 -384.323009) (xy 297.057178 -384.269061) (xy 297.072533 -384.216766) (xy 297.095175 -384.167189)
			(xy 297.124641 -384.121339) (xy 297.160332 -384.080148) (xy 297.201523 -384.044457) (xy 297.247373 -384.014991)
			(xy 297.29695 -383.992349) (xy 297.349245 -383.976994) (xy 297.403193 -383.969238) (xy 297.457695 -383.969238)
			(xy 297.511643 -383.976994) (xy 297.563938 -383.992349) (xy 297.613515 -384.014991) (xy 297.659365 -384.044457)
			(xy 297.700556 -384.080148) (xy 297.736247 -384.121339) (xy 297.765713 -384.167189) (xy 297.788355 -384.216766)
			(xy 297.80371 -384.269061) (xy 297.811466 -384.323009) (xy 297.811952 -384.35026) (xy 297.811952 -385.21386)
			(xy 297.811466 -385.241111) (xy 297.80371 -385.295059) (xy 297.790858 -385.338828) (xy 326.895968 -385.338828)
			(xy 326.895968 -384.475228) (xy 326.896454 -384.447977) (xy 326.90421 -384.394029) (xy 326.919565 -384.341734)
			(xy 326.942207 -384.292157) (xy 326.971673 -384.246307) (xy 327.007364 -384.205116) (xy 327.048555 -384.169425)
			(xy 327.094405 -384.139959) (xy 327.143982 -384.117317) (xy 327.196277 -384.101962) (xy 327.250225 -384.094206)
			(xy 327.304727 -384.094206) (xy 327.358675 -384.101962) (xy 327.41097 -384.117317) (xy 327.460547 -384.139959)
			(xy 327.506397 -384.169425) (xy 327.547588 -384.205116) (xy 327.583279 -384.246307) (xy 327.612745 -384.292157)
			(xy 327.635387 -384.341734) (xy 327.650742 -384.394029) (xy 327.658498 -384.447977) (xy 327.658984 -384.475228)
			(xy 327.658984 -385.21386) (xy 329.576684 -385.21386) (xy 329.576684 -384.35026) (xy 329.57717 -384.323009)
			(xy 329.584926 -384.269061) (xy 329.600281 -384.216766) (xy 329.622923 -384.167189) (xy 329.652389 -384.121339)
			(xy 329.68808 -384.080148) (xy 329.729271 -384.044457) (xy 329.775121 -384.014991) (xy 329.824698 -383.992349)
			(xy 329.876993 -383.976994) (xy 329.930941 -383.969238) (xy 329.985443 -383.969238) (xy 330.039391 -383.976994)
			(xy 330.091686 -383.992349) (xy 330.141263 -384.014991) (xy 330.187113 -384.044457) (xy 330.228304 -384.080148)
			(xy 330.263995 -384.121339) (xy 330.293461 -384.167189) (xy 330.316103 -384.216766) (xy 330.331458 -384.269061)
			(xy 330.339214 -384.323009) (xy 330.3397 -384.35026) (xy 330.3397 -385.21386) (xy 330.339214 -385.241111)
			(xy 330.331458 -385.295059) (xy 330.318606 -385.338828) (xy 359.423716 -385.338828) (xy 359.423716 -384.475228)
			(xy 359.424202 -384.447977) (xy 359.431958 -384.394029) (xy 359.447313 -384.341734) (xy 359.469955 -384.292157)
			(xy 359.499421 -384.246307) (xy 359.535112 -384.205116) (xy 359.576303 -384.169425) (xy 359.622153 -384.139959)
			(xy 359.67173 -384.117317) (xy 359.724025 -384.101962) (xy 359.777973 -384.094206) (xy 359.832475 -384.094206)
			(xy 359.886423 -384.101962) (xy 359.938718 -384.117317) (xy 359.988295 -384.139959) (xy 360.034145 -384.169425)
			(xy 360.075336 -384.205116) (xy 360.111027 -384.246307) (xy 360.140493 -384.292157) (xy 360.163135 -384.341734)
			(xy 360.17849 -384.394029) (xy 360.186246 -384.447977) (xy 360.186732 -384.475228) (xy 360.186732 -385.21386)
			(xy 364.149132 -385.21386) (xy 364.149132 -384.35026) (xy 364.149618 -384.323009) (xy 364.157374 -384.269061)
			(xy 364.172729 -384.216766) (xy 364.195371 -384.167189) (xy 364.224837 -384.121339) (xy 364.260528 -384.080148)
			(xy 364.301719 -384.044457) (xy 364.347569 -384.014991) (xy 364.397146 -383.992349) (xy 364.449441 -383.976994)
			(xy 364.503389 -383.969238) (xy 364.557891 -383.969238) (xy 364.611839 -383.976994) (xy 364.664134 -383.992349)
			(xy 364.713711 -384.014991) (xy 364.759561 -384.044457) (xy 364.800752 -384.080148) (xy 364.836443 -384.121339)
			(xy 364.865909 -384.167189) (xy 364.888551 -384.216766) (xy 364.903906 -384.269061) (xy 364.911662 -384.323009)
			(xy 364.912148 -384.35026) (xy 364.912148 -385.21386) (xy 364.911662 -385.241111) (xy 364.903906 -385.295059)
			(xy 364.891054 -385.338828) (xy 393.996164 -385.338828) (xy 393.996164 -384.475228) (xy 393.99665 -384.447977)
			(xy 394.004406 -384.394029) (xy 394.019761 -384.341734) (xy 394.042403 -384.292157) (xy 394.071869 -384.246307)
			(xy 394.10756 -384.205116) (xy 394.148751 -384.169425) (xy 394.194601 -384.139959) (xy 394.244178 -384.117317)
			(xy 394.296473 -384.101962) (xy 394.350421 -384.094206) (xy 394.404923 -384.094206) (xy 394.458871 -384.101962)
			(xy 394.511166 -384.117317) (xy 394.560743 -384.139959) (xy 394.606593 -384.169425) (xy 394.647784 -384.205116)
			(xy 394.683475 -384.246307) (xy 394.712941 -384.292157) (xy 394.735583 -384.341734) (xy 394.750938 -384.394029)
			(xy 394.758694 -384.447977) (xy 394.75918 -384.475228) (xy 394.75918 -385.21386) (xy 396.67688 -385.21386)
			(xy 396.67688 -384.35026) (xy 396.677366 -384.323009) (xy 396.685122 -384.269061) (xy 396.700477 -384.216766)
			(xy 396.723119 -384.167189) (xy 396.752585 -384.121339) (xy 396.788276 -384.080148) (xy 396.829467 -384.044457)
			(xy 396.875317 -384.014991) (xy 396.924894 -383.992349) (xy 396.977189 -383.976994) (xy 397.031137 -383.969238)
			(xy 397.085639 -383.969238) (xy 397.139587 -383.976994) (xy 397.191882 -383.992349) (xy 397.241459 -384.014991)
			(xy 397.287309 -384.044457) (xy 397.3285 -384.080148) (xy 397.364191 -384.121339) (xy 397.393657 -384.167189)
			(xy 397.416299 -384.216766) (xy 397.431654 -384.269061) (xy 397.43941 -384.323009) (xy 397.439896 -384.35026)
			(xy 397.439896 -385.21386) (xy 397.43941 -385.241111) (xy 397.431654 -385.295059) (xy 397.418802 -385.338828)
			(xy 426.523912 -385.338828) (xy 426.523912 -384.475228) (xy 426.524398 -384.447977) (xy 426.532154 -384.394029)
			(xy 426.547509 -384.341734) (xy 426.570151 -384.292157) (xy 426.599617 -384.246307) (xy 426.635308 -384.205116)
			(xy 426.676499 -384.169425) (xy 426.722349 -384.139959) (xy 426.771926 -384.117317) (xy 426.824221 -384.101962)
			(xy 426.878169 -384.094206) (xy 426.932671 -384.094206) (xy 426.986619 -384.101962) (xy 427.038914 -384.117317)
			(xy 427.088491 -384.139959) (xy 427.134341 -384.169425) (xy 427.175532 -384.205116) (xy 427.211223 -384.246307)
			(xy 427.240689 -384.292157) (xy 427.263331 -384.341734) (xy 427.278686 -384.394029) (xy 427.286442 -384.447977)
			(xy 427.286928 -384.475228) (xy 427.286928 -385.338828) (xy 427.286442 -385.366079) (xy 427.278686 -385.420027)
			(xy 427.263331 -385.472322) (xy 427.240689 -385.521899) (xy 427.211223 -385.567749) (xy 427.175532 -385.60894)
			(xy 427.134341 -385.644631) (xy 427.088491 -385.674097) (xy 427.038914 -385.696739) (xy 426.986619 -385.712094)
			(xy 426.932671 -385.71985) (xy 426.878169 -385.71985) (xy 426.824221 -385.712094) (xy 426.771926 -385.696739)
			(xy 426.722349 -385.674097) (xy 426.676499 -385.644631) (xy 426.635308 -385.60894) (xy 426.599617 -385.567749)
			(xy 426.570151 -385.521899) (xy 426.547509 -385.472322) (xy 426.532154 -385.420027) (xy 426.524398 -385.366079)
			(xy 426.523912 -385.338828) (xy 397.418802 -385.338828) (xy 397.416299 -385.347354) (xy 397.393657 -385.396931)
			(xy 397.364191 -385.442781) (xy 397.3285 -385.483972) (xy 397.287309 -385.519663) (xy 397.241459 -385.549129)
			(xy 397.191882 -385.571771) (xy 397.139587 -385.587126) (xy 397.085639 -385.594882) (xy 397.031137 -385.594882)
			(xy 396.977189 -385.587126) (xy 396.924894 -385.571771) (xy 396.875317 -385.549129) (xy 396.829467 -385.519663)
			(xy 396.788276 -385.483972) (xy 396.752585 -385.442781) (xy 396.723119 -385.396931) (xy 396.700477 -385.347354)
			(xy 396.685122 -385.295059) (xy 396.677366 -385.241111) (xy 396.67688 -385.21386) (xy 394.75918 -385.21386)
			(xy 394.75918 -385.338828) (xy 394.758694 -385.366079) (xy 394.750938 -385.420027) (xy 394.735583 -385.472322)
			(xy 394.712941 -385.521899) (xy 394.683475 -385.567749) (xy 394.647784 -385.60894) (xy 394.606593 -385.644631)
			(xy 394.560743 -385.674097) (xy 394.511166 -385.696739) (xy 394.458871 -385.712094) (xy 394.404923 -385.71985)
			(xy 394.350421 -385.71985) (xy 394.296473 -385.712094) (xy 394.244178 -385.696739) (xy 394.194601 -385.674097)
			(xy 394.148751 -385.644631) (xy 394.10756 -385.60894) (xy 394.071869 -385.567749) (xy 394.042403 -385.521899)
			(xy 394.019761 -385.472322) (xy 394.004406 -385.420027) (xy 393.99665 -385.366079) (xy 393.996164 -385.338828)
			(xy 364.891054 -385.338828) (xy 364.888551 -385.347354) (xy 364.865909 -385.396931) (xy 364.836443 -385.442781)
			(xy 364.800752 -385.483972) (xy 364.759561 -385.519663) (xy 364.713711 -385.549129) (xy 364.664134 -385.571771)
			(xy 364.611839 -385.587126) (xy 364.557891 -385.594882) (xy 364.503389 -385.594882) (xy 364.449441 -385.587126)
			(xy 364.397146 -385.571771) (xy 364.347569 -385.549129) (xy 364.301719 -385.519663) (xy 364.260528 -385.483972)
			(xy 364.224837 -385.442781) (xy 364.195371 -385.396931) (xy 364.172729 -385.347354) (xy 364.157374 -385.295059)
			(xy 364.149618 -385.241111) (xy 364.149132 -385.21386) (xy 360.186732 -385.21386) (xy 360.186732 -385.338828)
			(xy 360.186246 -385.366079) (xy 360.17849 -385.420027) (xy 360.163135 -385.472322) (xy 360.140493 -385.521899)
			(xy 360.111027 -385.567749) (xy 360.075336 -385.60894) (xy 360.034145 -385.644631) (xy 359.988295 -385.674097)
			(xy 359.938718 -385.696739) (xy 359.886423 -385.712094) (xy 359.832475 -385.71985) (xy 359.777973 -385.71985)
			(xy 359.724025 -385.712094) (xy 359.67173 -385.696739) (xy 359.622153 -385.674097) (xy 359.576303 -385.644631)
			(xy 359.535112 -385.60894) (xy 359.499421 -385.567749) (xy 359.469955 -385.521899) (xy 359.447313 -385.472322)
			(xy 359.431958 -385.420027) (xy 359.424202 -385.366079) (xy 359.423716 -385.338828) (xy 330.318606 -385.338828)
			(xy 330.316103 -385.347354) (xy 330.293461 -385.396931) (xy 330.263995 -385.442781) (xy 330.228304 -385.483972)
			(xy 330.187113 -385.519663) (xy 330.141263 -385.549129) (xy 330.091686 -385.571771) (xy 330.039391 -385.587126)
			(xy 329.985443 -385.594882) (xy 329.930941 -385.594882) (xy 329.876993 -385.587126) (xy 329.824698 -385.571771)
			(xy 329.775121 -385.549129) (xy 329.729271 -385.519663) (xy 329.68808 -385.483972) (xy 329.652389 -385.442781)
			(xy 329.622923 -385.396931) (xy 329.600281 -385.347354) (xy 329.584926 -385.295059) (xy 329.57717 -385.241111)
			(xy 329.576684 -385.21386) (xy 327.658984 -385.21386) (xy 327.658984 -385.338828) (xy 327.658498 -385.366079)
			(xy 327.650742 -385.420027) (xy 327.635387 -385.472322) (xy 327.612745 -385.521899) (xy 327.583279 -385.567749)
			(xy 327.547588 -385.60894) (xy 327.506397 -385.644631) (xy 327.460547 -385.674097) (xy 327.41097 -385.696739)
			(xy 327.358675 -385.712094) (xy 327.304727 -385.71985) (xy 327.250225 -385.71985) (xy 327.196277 -385.712094)
			(xy 327.143982 -385.696739) (xy 327.094405 -385.674097) (xy 327.048555 -385.644631) (xy 327.007364 -385.60894)
			(xy 326.971673 -385.567749) (xy 326.942207 -385.521899) (xy 326.919565 -385.472322) (xy 326.90421 -385.420027)
			(xy 326.896454 -385.366079) (xy 326.895968 -385.338828) (xy 297.790858 -385.338828) (xy 297.788355 -385.347354)
			(xy 297.765713 -385.396931) (xy 297.736247 -385.442781) (xy 297.700556 -385.483972) (xy 297.659365 -385.519663)
			(xy 297.613515 -385.549129) (xy 297.563938 -385.571771) (xy 297.511643 -385.587126) (xy 297.457695 -385.594882)
			(xy 297.403193 -385.594882) (xy 297.349245 -385.587126) (xy 297.29695 -385.571771) (xy 297.247373 -385.549129)
			(xy 297.201523 -385.519663) (xy 297.160332 -385.483972) (xy 297.124641 -385.442781) (xy 297.095175 -385.396931)
			(xy 297.072533 -385.347354) (xy 297.057178 -385.295059) (xy 297.049422 -385.241111) (xy 297.048936 -385.21386)
			(xy 295.372367 -385.21386) (xy 295.370041 -385.249842) (xy 295.350085 -385.434603) (xy 295.322199 -385.618335)
			(xy 295.286435 -385.800697) (xy 295.242858 -385.981352) (xy 295.191549 -386.159964) (xy 295.132604 -386.336204)
			(xy 295.06613 -386.509744) (xy 294.992252 -386.680264) (xy 294.911107 -386.847448) (xy 294.822844 -387.010986)
			(xy 294.727626 -387.170575) (xy 294.625632 -387.32592) (xy 294.517048 -387.476733) (xy 294.402076 -387.622735)
			(xy 294.28093 -387.763655) (xy 294.153833 -387.899233) (xy 294.021021 -388.029218) (xy 293.882739 -388.153368)
			(xy 293.739245 -388.271454) (xy 293.590803 -388.383257) (xy 293.437688 -388.48857) (xy 293.280184 -388.587199)
			(xy 293.118583 -388.67896) (xy 292.994679 -388.742428) (xy 326.895968 -388.742428) (xy 326.895968 -387.878828)
			(xy 326.896454 -387.851577) (xy 326.90421 -387.797629) (xy 326.919565 -387.745334) (xy 326.942207 -387.695757)
			(xy 326.971673 -387.649907) (xy 327.007364 -387.608716) (xy 327.048555 -387.573025) (xy 327.094405 -387.543559)
			(xy 327.143982 -387.520917) (xy 327.196277 -387.505562) (xy 327.250225 -387.497806) (xy 327.304727 -387.497806)
			(xy 327.358675 -387.505562) (xy 327.41097 -387.520917) (xy 327.460547 -387.543559) (xy 327.506397 -387.573025)
			(xy 327.547588 -387.608716) (xy 327.583279 -387.649907) (xy 327.612745 -387.695757) (xy 327.635387 -387.745334)
			(xy 327.650742 -387.797629) (xy 327.658498 -387.851577) (xy 327.658984 -387.878828) (xy 327.658984 -388.742428)
			(xy 359.423716 -388.742428) (xy 359.423716 -387.878828) (xy 359.424202 -387.851577) (xy 359.431958 -387.797629)
			(xy 359.447313 -387.745334) (xy 359.469955 -387.695757) (xy 359.499421 -387.649907) (xy 359.535112 -387.608716)
			(xy 359.576303 -387.573025) (xy 359.622153 -387.543559) (xy 359.67173 -387.520917) (xy 359.724025 -387.505562)
			(xy 359.777973 -387.497806) (xy 359.832475 -387.497806) (xy 359.886423 -387.505562) (xy 359.938718 -387.520917)
			(xy 359.988295 -387.543559) (xy 360.034145 -387.573025) (xy 360.075336 -387.608716) (xy 360.111027 -387.649907)
			(xy 360.140493 -387.695757) (xy 360.163135 -387.745334) (xy 360.17849 -387.797629) (xy 360.186246 -387.851577)
			(xy 360.186732 -387.878828) (xy 360.186732 -388.742428) (xy 393.996164 -388.742428) (xy 393.996164 -387.878828)
			(xy 393.99665 -387.851577) (xy 394.004406 -387.797629) (xy 394.019761 -387.745334) (xy 394.042403 -387.695757)
			(xy 394.071869 -387.649907) (xy 394.10756 -387.608716) (xy 394.148751 -387.573025) (xy 394.194601 -387.543559)
			(xy 394.244178 -387.520917) (xy 394.296473 -387.505562) (xy 394.350421 -387.497806) (xy 394.404923 -387.497806)
			(xy 394.458871 -387.505562) (xy 394.511166 -387.520917) (xy 394.560743 -387.543559) (xy 394.606593 -387.573025)
			(xy 394.647784 -387.608716) (xy 394.683475 -387.649907) (xy 394.712941 -387.695757) (xy 394.735583 -387.745334)
			(xy 394.750938 -387.797629) (xy 394.758694 -387.851577) (xy 394.75918 -387.878828) (xy 394.75918 -388.742428)
			(xy 426.523912 -388.742428) (xy 426.523912 -387.878828) (xy 426.524398 -387.851577) (xy 426.532154 -387.797629)
			(xy 426.547509 -387.745334) (xy 426.570151 -387.695757) (xy 426.599617 -387.649907) (xy 426.635308 -387.608716)
			(xy 426.676499 -387.573025) (xy 426.722349 -387.543559) (xy 426.771926 -387.520917) (xy 426.824221 -387.505562)
			(xy 426.878169 -387.497806) (xy 426.932671 -387.497806) (xy 426.986619 -387.505562) (xy 427.038914 -387.520917)
			(xy 427.088491 -387.543559) (xy 427.134341 -387.573025) (xy 427.175532 -387.608716) (xy 427.211223 -387.649907)
			(xy 427.240689 -387.695757) (xy 427.263331 -387.745334) (xy 427.278686 -387.797629) (xy 427.286442 -387.851577)
			(xy 427.286928 -387.878828) (xy 427.286928 -388.742428) (xy 427.286442 -388.769679) (xy 427.278686 -388.823627)
			(xy 427.263331 -388.875922) (xy 427.240689 -388.925499) (xy 427.211223 -388.971349) (xy 427.175532 -389.01254)
			(xy 427.134341 -389.048231) (xy 427.088491 -389.077697) (xy 427.038914 -389.100339) (xy 426.986619 -389.115694)
			(xy 426.932671 -389.12345) (xy 426.878169 -389.12345) (xy 426.824221 -389.115694) (xy 426.771926 -389.100339)
			(xy 426.722349 -389.077697) (xy 426.676499 -389.048231) (xy 426.635308 -389.01254) (xy 426.599617 -388.971349)
			(xy 426.570151 -388.925499) (xy 426.547509 -388.875922) (xy 426.532154 -388.823627) (xy 426.524398 -388.769679)
			(xy 426.523912 -388.742428) (xy 394.75918 -388.742428) (xy 394.758694 -388.769679) (xy 394.750938 -388.823627)
			(xy 394.735583 -388.875922) (xy 394.712941 -388.925499) (xy 394.683475 -388.971349) (xy 394.647784 -389.01254)
			(xy 394.606593 -389.048231) (xy 394.560743 -389.077697) (xy 394.511166 -389.100339) (xy 394.458871 -389.115694)
			(xy 394.404923 -389.12345) (xy 394.350421 -389.12345) (xy 394.296473 -389.115694) (xy 394.244178 -389.100339)
			(xy 394.194601 -389.077697) (xy 394.148751 -389.048231) (xy 394.10756 -389.01254) (xy 394.071869 -388.971349)
			(xy 394.042403 -388.925499) (xy 394.019761 -388.875922) (xy 394.004406 -388.823627) (xy 393.99665 -388.769679)
			(xy 393.996164 -388.742428) (xy 360.186732 -388.742428) (xy 360.186246 -388.769679) (xy 360.17849 -388.823627)
			(xy 360.163135 -388.875922) (xy 360.140493 -388.925499) (xy 360.111027 -388.971349) (xy 360.075336 -389.01254)
			(xy 360.034145 -389.048231) (xy 359.988295 -389.077697) (xy 359.938718 -389.100339) (xy 359.886423 -389.115694)
			(xy 359.832475 -389.12345) (xy 359.777973 -389.12345) (xy 359.724025 -389.115694) (xy 359.67173 -389.100339)
			(xy 359.622153 -389.077697) (xy 359.576303 -389.048231) (xy 359.535112 -389.01254) (xy 359.499421 -388.971349)
			(xy 359.469955 -388.925499) (xy 359.447313 -388.875922) (xy 359.431958 -388.823627) (xy 359.424202 -388.769679)
			(xy 359.423716 -388.742428) (xy 327.658984 -388.742428) (xy 327.658498 -388.769679) (xy 327.650742 -388.823627)
			(xy 327.635387 -388.875922) (xy 327.612745 -388.925499) (xy 327.583279 -388.971349) (xy 327.547588 -389.01254)
			(xy 327.506397 -389.048231) (xy 327.460547 -389.077697) (xy 327.41097 -389.100339) (xy 327.358675 -389.115694)
			(xy 327.304727 -389.12345) (xy 327.250225 -389.12345) (xy 327.196277 -389.115694) (xy 327.143982 -389.100339)
			(xy 327.094405 -389.077697) (xy 327.048555 -389.048231) (xy 327.007364 -389.01254) (xy 326.971673 -388.971349)
			(xy 326.942207 -388.925499) (xy 326.919565 -388.875922) (xy 326.90421 -388.823627) (xy 326.896454 -388.769679)
			(xy 326.895968 -388.742428) (xy 292.994679 -388.742428) (xy 292.953184 -388.763683) (xy 292.784293 -388.841213)
			(xy 292.612222 -388.911404) (xy 292.437292 -388.974128) (xy 292.259824 -389.029267) (xy 292.080149 -389.076721)
			(xy 291.898599 -389.1164) (xy 291.715509 -389.148232) (xy 291.53122 -389.172158) (xy 291.346072 -389.188133)
			(xy 291.160408 -389.196127) (xy 291.06749 -389.19658) (xy 290.973899 -389.196079) (xy 290.786892 -389.187967)
			(xy 290.600412 -389.171758) (xy 290.41481 -389.147482) (xy 290.230434 -389.115186) (xy 290.047631 -389.07493)
			(xy 289.866745 -389.026789) (xy 289.688115 -388.970855) (xy 289.512076 -388.907232) (xy 289.33896 -388.836039)
			(xy 289.169093 -388.757411) (xy 289.002792 -388.671495) (xy 288.840371 -388.578453) (xy 288.682135 -388.47846)
			(xy 288.52838 -388.371703) (xy 288.453576 -388.315454) (xy 288.442146 -388.306818) (xy 288.41319 -388.304024)
			(xy 288.318702 -388.35076) (xy 288.310398 -388.355325) (xy 288.297662 -388.369337) (xy 288.290865 -388.387011)
			(xy 288.290508 -388.39648) (xy 288.290508 -390.75106) (xy 297.048936 -390.75106) (xy 297.048936 -389.88746)
			(xy 297.049422 -389.860209) (xy 297.057178 -389.806261) (xy 297.072533 -389.753966) (xy 297.095175 -389.704389)
			(xy 297.124641 -389.658539) (xy 297.160332 -389.617348) (xy 297.201523 -389.581657) (xy 297.247373 -389.552191)
			(xy 297.29695 -389.529549) (xy 297.349245 -389.514194) (xy 297.403193 -389.506438) (xy 297.457695 -389.506438)
			(xy 297.511643 -389.514194) (xy 297.563938 -389.529549) (xy 297.613515 -389.552191) (xy 297.659365 -389.581657)
			(xy 297.700556 -389.617348) (xy 297.736247 -389.658539) (xy 297.765713 -389.704389) (xy 297.788355 -389.753966)
			(xy 297.80371 -389.806261) (xy 297.811466 -389.860209) (xy 297.811952 -389.88746) (xy 297.811952 -390.75106)
			(xy 329.576684 -390.75106) (xy 329.576684 -389.88746) (xy 329.57717 -389.860209) (xy 329.584926 -389.806261)
			(xy 329.600281 -389.753966) (xy 329.622923 -389.704389) (xy 329.652389 -389.658539) (xy 329.68808 -389.617348)
			(xy 329.729271 -389.581657) (xy 329.775121 -389.552191) (xy 329.824698 -389.529549) (xy 329.876993 -389.514194)
			(xy 329.930941 -389.506438) (xy 329.985443 -389.506438) (xy 330.039391 -389.514194) (xy 330.091686 -389.529549)
			(xy 330.141263 -389.552191) (xy 330.187113 -389.581657) (xy 330.228304 -389.617348) (xy 330.263995 -389.658539)
			(xy 330.293461 -389.704389) (xy 330.316103 -389.753966) (xy 330.331458 -389.806261) (xy 330.339214 -389.860209)
			(xy 330.3397 -389.88746) (xy 330.3397 -390.75106) (xy 364.149132 -390.75106) (xy 364.149132 -389.88746)
			(xy 364.149618 -389.860209) (xy 364.157374 -389.806261) (xy 364.172729 -389.753966) (xy 364.195371 -389.704389)
			(xy 364.224837 -389.658539) (xy 364.260528 -389.617348) (xy 364.301719 -389.581657) (xy 364.347569 -389.552191)
			(xy 364.397146 -389.529549) (xy 364.449441 -389.514194) (xy 364.503389 -389.506438) (xy 364.557891 -389.506438)
			(xy 364.611839 -389.514194) (xy 364.664134 -389.529549) (xy 364.713711 -389.552191) (xy 364.759561 -389.581657)
			(xy 364.800752 -389.617348) (xy 364.836443 -389.658539) (xy 364.865909 -389.704389) (xy 364.888551 -389.753966)
			(xy 364.903906 -389.806261) (xy 364.911662 -389.860209) (xy 364.912148 -389.88746) (xy 364.912148 -390.75106)
			(xy 396.67688 -390.75106) (xy 396.67688 -389.88746) (xy 396.677366 -389.860209) (xy 396.685122 -389.806261)
			(xy 396.700477 -389.753966) (xy 396.723119 -389.704389) (xy 396.752585 -389.658539) (xy 396.788276 -389.617348)
			(xy 396.829467 -389.581657) (xy 396.875317 -389.552191) (xy 396.924894 -389.529549) (xy 396.977189 -389.514194)
			(xy 397.031137 -389.506438) (xy 397.085639 -389.506438) (xy 397.139587 -389.514194) (xy 397.191882 -389.529549)
			(xy 397.241459 -389.552191) (xy 397.287309 -389.581657) (xy 397.3285 -389.617348) (xy 397.364191 -389.658539)
			(xy 397.393657 -389.704389) (xy 397.416299 -389.753966) (xy 397.431654 -389.806261) (xy 397.43941 -389.860209)
			(xy 397.439896 -389.88746) (xy 397.439896 -390.75106) (xy 397.43941 -390.778311) (xy 397.431654 -390.832259)
			(xy 397.416299 -390.884554) (xy 397.393657 -390.934131) (xy 397.364191 -390.979981) (xy 397.3285 -391.021172)
			(xy 397.287309 -391.056863) (xy 397.241459 -391.086329) (xy 397.191882 -391.108971) (xy 397.139587 -391.124326)
			(xy 397.085639 -391.132082) (xy 397.031137 -391.132082) (xy 396.977189 -391.124326) (xy 396.924894 -391.108971)
			(xy 396.875317 -391.086329) (xy 396.829467 -391.056863) (xy 396.788276 -391.021172) (xy 396.752585 -390.979981)
			(xy 396.723119 -390.934131) (xy 396.700477 -390.884554) (xy 396.685122 -390.832259) (xy 396.677366 -390.778311)
			(xy 396.67688 -390.75106) (xy 364.912148 -390.75106) (xy 364.911662 -390.778311) (xy 364.903906 -390.832259)
			(xy 364.888551 -390.884554) (xy 364.865909 -390.934131) (xy 364.836443 -390.979981) (xy 364.800752 -391.021172)
			(xy 364.759561 -391.056863) (xy 364.713711 -391.086329) (xy 364.664134 -391.108971) (xy 364.611839 -391.124326)
			(xy 364.557891 -391.132082) (xy 364.503389 -391.132082) (xy 364.449441 -391.124326) (xy 364.397146 -391.108971)
			(xy 364.347569 -391.086329) (xy 364.301719 -391.056863) (xy 364.260528 -391.021172) (xy 364.224837 -390.979981)
			(xy 364.195371 -390.934131) (xy 364.172729 -390.884554) (xy 364.157374 -390.832259) (xy 364.149618 -390.778311)
			(xy 364.149132 -390.75106) (xy 330.3397 -390.75106) (xy 330.339214 -390.778311) (xy 330.331458 -390.832259)
			(xy 330.316103 -390.884554) (xy 330.293461 -390.934131) (xy 330.263995 -390.979981) (xy 330.228304 -391.021172)
			(xy 330.187113 -391.056863) (xy 330.141263 -391.086329) (xy 330.091686 -391.108971) (xy 330.039391 -391.124326)
			(xy 329.985443 -391.132082) (xy 329.930941 -391.132082) (xy 329.876993 -391.124326) (xy 329.824698 -391.108971)
			(xy 329.775121 -391.086329) (xy 329.729271 -391.056863) (xy 329.68808 -391.021172) (xy 329.652389 -390.979981)
			(xy 329.622923 -390.934131) (xy 329.600281 -390.884554) (xy 329.584926 -390.832259) (xy 329.57717 -390.778311)
			(xy 329.576684 -390.75106) (xy 297.811952 -390.75106) (xy 297.811466 -390.778311) (xy 297.80371 -390.832259)
			(xy 297.788355 -390.884554) (xy 297.765713 -390.934131) (xy 297.736247 -390.979981) (xy 297.700556 -391.021172)
			(xy 297.659365 -391.056863) (xy 297.613515 -391.086329) (xy 297.563938 -391.108971) (xy 297.511643 -391.124326)
			(xy 297.457695 -391.132082) (xy 297.403193 -391.132082) (xy 297.349245 -391.124326) (xy 297.29695 -391.108971)
			(xy 297.247373 -391.086329) (xy 297.201523 -391.056863) (xy 297.160332 -391.021172) (xy 297.124641 -390.979981)
			(xy 297.095175 -390.934131) (xy 297.072533 -390.884554) (xy 297.057178 -390.832259) (xy 297.049422 -390.778311)
			(xy 297.048936 -390.75106) (xy 288.290508 -390.75106) (xy 288.290508 -396.171674) (xy 296.901108 -396.171674)
			(xy 296.901108 -395.308074) (xy 296.901594 -395.280823) (xy 296.90935 -395.226875) (xy 296.924705 -395.17458)
			(xy 296.947347 -395.125003) (xy 296.976813 -395.079153) (xy 297.012504 -395.037962) (xy 297.053695 -395.002271)
			(xy 297.099545 -394.972805) (xy 297.149122 -394.950163) (xy 297.201417 -394.934808) (xy 297.255365 -394.927052)
			(xy 297.309867 -394.927052) (xy 297.363815 -394.934808) (xy 297.41611 -394.950163) (xy 297.465687 -394.972805)
			(xy 297.511537 -395.002271) (xy 297.552728 -395.037962) (xy 297.588419 -395.079153) (xy 297.617885 -395.125003)
			(xy 297.640527 -395.17458) (xy 297.655882 -395.226875) (xy 297.663638 -395.280823) (xy 297.664124 -395.308074)
			(xy 297.664124 -396.171674) (xy 297.663638 -396.198925) (xy 297.655882 -396.252873) (xy 297.640527 -396.305168)
			(xy 297.617885 -396.354745) (xy 297.588419 -396.400595) (xy 297.552728 -396.441786) (xy 297.511537 -396.477477)
			(xy 297.465687 -396.506943) (xy 297.41611 -396.529585) (xy 297.363815 -396.54494) (xy 297.309867 -396.552696)
			(xy 297.255365 -396.552696) (xy 297.201417 -396.54494) (xy 297.149122 -396.529585) (xy 297.099545 -396.506943)
			(xy 297.053695 -396.477477) (xy 297.012504 -396.441786) (xy 296.976813 -396.400595) (xy 296.947347 -396.354745)
			(xy 296.924705 -396.305168) (xy 296.90935 -396.252873) (xy 296.901594 -396.198925) (xy 296.901108 -396.171674)
			(xy 288.290508 -396.171674) (xy 288.290508 -398.339818) (xy 288.293048 -398.350994) (xy 288.295842 -398.356328)
			(xy 288.307389 -398.380957) (xy 288.323703 -398.432845) (xy 288.331933 -398.486611) (xy 288.332418 -398.513808)
			(xy 288.332302 -398.526937) (xy 288.330392 -398.553125) (xy 288.328608 -398.566132) (xy 288.32683 -398.57807)
			(xy 288.334196 -398.60093) (xy 289.297364 -399.564098) (xy 289.304766 -399.570935) (xy 289.323364 -399.578646)
			(xy 289.333432 -399.579084)
		)
		(stroke
			(width 0)
			(type solid)
		)
		(fill yes)
		(layer "In9.Cu")
		(net "P1V8_CPU0_RT_1D")
	)
	(gr_poly
		(pts
			(xy 285.486856 -355.918262) (xy 285.487872 -355.898196) (xy 285.4909 -355.855081) (xy 285.504276 -355.769685)
			(xy 285.525868 -355.685989) (xy 285.540196 -355.645212) (xy 285.543022 -355.636325) (xy 285.542766 -355.617693)
			(xy 285.539688 -355.60889) (xy 285.524477 -355.569491) (xy 285.50071 -355.488443) (xy 285.484739 -355.405506)
			(xy 285.476708 -355.321428) (xy 285.476188 -355.279198) (xy 285.476649 -355.238084) (xy 285.484236 -355.156207)
			(xy 285.499346 -355.075379) (xy 285.52185 -354.99629) (xy 285.551555 -354.919615) (xy 285.588209 -354.846009)
			(xy 285.631498 -354.776098) (xy 285.681053 -354.71048) (xy 285.736451 -354.649714) (xy 285.79722 -354.594319)
			(xy 285.862841 -354.544768) (xy 285.932754 -354.501483) (xy 286.006363 -354.464834) (xy 286.08304 -354.435133)
			(xy 286.16213 -354.412634) (xy 286.242958 -354.397529) (xy 286.324836 -354.389946) (xy 286.36595 -354.389436)
			(xy 286.404238 -354.389874) (xy 286.480527 -354.396501) (xy 286.555965 -354.409651) (xy 286.629997 -354.429226)
			(xy 286.666178 -354.44176) (xy 286.674615 -354.444411) (xy 286.692285 -354.444411) (xy 286.700722 -354.44176)
			(xy 286.736893 -354.429194) (xy 286.810924 -354.409605) (xy 286.886367 -354.39646) (xy 286.962661 -354.389856)
			(xy 287.00095 -354.389436) (xy 287.039238 -354.389874) (xy 287.115527 -354.396501) (xy 287.190965 -354.409651)
			(xy 287.264997 -354.429226) (xy 287.301178 -354.44176) (xy 287.309615 -354.444411) (xy 287.327285 -354.444411)
			(xy 287.335722 -354.44176) (xy 287.371893 -354.429194) (xy 287.445924 -354.409605) (xy 287.521367 -354.39646)
			(xy 287.597661 -354.389856) (xy 287.63595 -354.389436) (xy 287.674238 -354.389874) (xy 287.750527 -354.396501)
			(xy 287.825965 -354.409651) (xy 287.899997 -354.429226) (xy 287.936178 -354.44176) (xy 287.944615 -354.444411)
			(xy 287.962285 -354.444411) (xy 287.970722 -354.44176) (xy 288.006893 -354.429194) (xy 288.080924 -354.409605)
			(xy 288.156367 -354.39646) (xy 288.232661 -354.389856) (xy 288.27095 -354.389436) (xy 288.309238 -354.389874)
			(xy 288.385527 -354.396501) (xy 288.460965 -354.409651) (xy 288.534997 -354.429226) (xy 288.571178 -354.44176)
			(xy 288.579615 -354.444411) (xy 288.597285 -354.444411) (xy 288.605722 -354.44176) (xy 288.641893 -354.429194)
			(xy 288.715924 -354.409605) (xy 288.791367 -354.39646) (xy 288.867661 -354.389856) (xy 288.90595 -354.389436)
			(xy 288.947066 -354.389894) (xy 289.028949 -354.397477) (xy 289.109782 -354.412584) (xy 289.188877 -354.435084)
			(xy 289.265558 -354.464786) (xy 289.339171 -354.501438) (xy 289.409089 -354.544725) (xy 289.474713 -354.594279)
			(xy 289.535486 -354.649677) (xy 289.590887 -354.710447) (xy 289.640445 -354.776069) (xy 289.683737 -354.845983)
			(xy 289.720393 -354.919594) (xy 289.7501 -354.996274) (xy 289.772605 -355.075367) (xy 289.787715 -355.1562)
			(xy 289.795303 -355.238082) (xy 289.795712 -355.279198) (xy 289.79529 -355.318061) (xy 289.78849 -355.395489)
			(xy 289.774959 -355.472028) (xy 289.754801 -355.547095) (xy 289.741864 -355.583744) (xy 289.739049 -355.592631)
			(xy 289.739324 -355.611255) (xy 289.742372 -355.620066) (xy 289.75948 -355.664606) (xy 289.785183 -355.756496)
			(xy 289.800924 -355.850606) (xy 289.804348 -355.898196) (xy 289.805364 -355.918262) (xy 289.834828 -355.945948)
			(xy 305.153314 -355.945948) (xy 305.162236 -355.945559) (xy 305.179005 -355.939459) (xy 305.18608 -355.93401)
			(xy 305.206777 -355.917305) (xy 305.251922 -355.889185) (xy 305.300534 -355.867604) (xy 305.351671 -355.85298)
			(xy 305.404343 -355.845596) (xy 305.457529 -355.845596) (xy 305.510201 -355.85298) (xy 305.561338 -355.867604)
			(xy 305.60995 -355.889185) (xy 305.655095 -355.917305) (xy 305.675792 -355.93401) (xy 305.682842 -355.939504)
			(xy 305.699626 -355.945614) (xy 305.708558 -355.945948) (xy 420.089076 -355.945948) (xy 420.096027 -355.945707)
			(xy 420.109417 -355.941968) (xy 420.115492 -355.938582) (xy 420.141129 -355.923764) (xy 420.195945 -355.901373)
			(xy 420.253562 -355.887719) (xy 420.312596 -355.883131) (xy 420.37163 -355.887719) (xy 420.429247 -355.901373)
			(xy 420.484063 -355.923764) (xy 420.5097 -355.938582) (xy 420.515755 -355.942014) (xy 420.529159 -355.945746)
			(xy 420.536116 -355.945948) (xy 423.16019 -355.945948) (xy 423.167603 -355.945695) (xy 423.181803 -355.941437)
			(xy 423.18813 -355.937566) (xy 423.21157 -355.922792) (xy 423.26181 -355.899434) (xy 423.3149 -355.883585)
			(xy 423.369723 -355.875576) (xy 423.425129 -355.875576) (xy 423.479952 -355.883585) (xy 423.533042 -355.899434)
			(xy 423.583282 -355.922792) (xy 423.606722 -355.937566) (xy 423.613051 -355.941433) (xy 423.62725 -355.945695)
			(xy 423.634662 -355.945948) (xy 427.889416 -355.945948) (xy 427.901262 -355.945327) (xy 427.922455 -355.934734)
			(xy 427.930056 -355.925628) (xy 427.946795 -355.904267) (xy 427.985314 -355.86604) (xy 428.028859 -355.833653)
			(xy 428.076552 -355.807761) (xy 428.127431 -355.788884) (xy 428.180471 -355.777403) (xy 428.234602 -355.77355)
			(xy 428.288733 -355.777403) (xy 428.341773 -355.788884) (xy 428.392652 -355.807761) (xy 428.440345 -355.833653)
			(xy 428.48389 -355.86604) (xy 428.522409 -355.904267) (xy 428.539148 -355.925628) (xy 428.546754 -355.934728)
			(xy 428.567944 -355.945318) (xy 428.579788 -355.945948) (xy 431.53711 -355.945948) (xy 431.548286 -355.943408)
			(xy 431.55362 -355.940614) (xy 431.580223 -355.927942) (xy 431.636364 -355.910049) (xy 431.694592 -355.901022)
			(xy 431.724054 -355.900482) (xy 431.753513 -355.901037) (xy 431.811731 -355.910097) (xy 431.86787 -355.927979)
			(xy 431.894488 -355.940614) (xy 431.899822 -355.943408) (xy 431.910998 -355.945948) (xy 439.547762 -355.945948)
			(xy 439.557826 -355.945512) (xy 439.576409 -355.937776) (xy 439.58383 -355.930962) (xy 440.572652 -354.94214)
			(xy 440.579494 -354.934741) (xy 440.587214 -354.916142) (xy 440.587638 -354.906072) (xy 440.587638 -354.000816)
			(xy 440.587279 -353.991736) (xy 440.580941 -353.974719) (xy 440.569031 -353.961013) (xy 440.561222 -353.956366)
			(xy 440.49516 -353.91964) (xy 440.366534 -353.840228) (xy 440.242225 -353.754214) (xy 440.122572 -353.661833)
			(xy 440.007902 -353.563336) (xy 439.898526 -353.458991) (xy 439.794742 -353.349082) (xy 439.696833 -353.233909)
			(xy 439.605065 -353.113785) (xy 439.519689 -352.989038) (xy 439.440937 -352.860007) (xy 439.369022 -352.727043)
			(xy 439.304142 -352.590509) (xy 439.246473 -352.450776) (xy 439.196172 -352.308225) (xy 439.153375 -352.163244)
			(xy 439.1182 -352.016228) (xy 439.090741 -351.867577) (xy 439.071075 -351.717697) (xy 439.059254 -351.566994)
			(xy 439.055311 -351.41588) (xy 439.059256 -351.264766) (xy 439.071079 -351.114063) (xy 439.090748 -350.964183)
			(xy 439.118208 -350.815532) (xy 439.153385 -350.668517) (xy 439.196184 -350.523537) (xy 439.246487 -350.380986)
			(xy 439.304159 -350.241254) (xy 439.369041 -350.104721) (xy 439.440957 -349.971758) (xy 439.519711 -349.842728)
			(xy 439.605089 -349.717982) (xy 439.696858 -349.59786) (xy 439.794769 -349.482688) (xy 439.898554 -349.372781)
			(xy 440.007932 -349.268437) (xy 440.122604 -349.169942) (xy 440.242258 -349.077562) (xy 440.366567 -348.99155)
			(xy 440.495195 -348.91214) (xy 440.561222 -348.87535) (xy 440.568994 -348.87066) (xy 440.580872 -348.856948)
			(xy 440.58726 -348.839969) (xy 440.587638 -348.8309) (xy 440.587638 -347.923866) (xy 440.587298 -347.914681)
			(xy 440.580916 -347.897459) (xy 440.568875 -347.883591) (xy 440.560968 -347.878908) (xy 440.535319 -347.864541)
			(xy 440.488385 -347.829141) (xy 440.447442 -347.786956) (xy 440.413459 -347.738987) (xy 440.387242 -347.686369)
			(xy 440.369413 -347.630351) (xy 440.360394 -347.57226) (xy 440.3598 -347.542866) (xy 440.360323 -347.514128)
			(xy 440.368951 -347.457303) (xy 440.386005 -347.402415) (xy 440.411099 -347.350706) (xy 440.443667 -347.303347)
			(xy 440.462924 -347.282008) (xy 440.469528 -347.274896) (xy 440.47664 -347.25737) (xy 440.47664 -347.167962)
			(xy 440.469528 -347.150436) (xy 440.462924 -347.143324) (xy 440.443649 -347.121998) (xy 440.411076 -347.074638)
			(xy 440.385975 -347.022927) (xy 440.368916 -346.968036) (xy 440.360284 -346.911206) (xy 440.3598 -346.882466)
			(xy 440.360274 -346.855097) (xy 440.368102 -346.800921) (xy 440.383593 -346.74842) (xy 440.406428 -346.698672)
			(xy 440.436139 -346.652699) (xy 440.45378 -346.631768) (xy 440.459876 -346.624656) (xy 440.466226 -346.607638)
			(xy 440.466226 -346.522294) (xy 440.459876 -346.505276) (xy 440.45378 -346.498164) (xy 440.436141 -346.477232)
			(xy 440.406421 -346.431264) (xy 440.383583 -346.381517) (xy 440.368099 -346.329014) (xy 440.360286 -346.274836)
			(xy 440.3598 -346.247466) (xy 440.360346 -346.218071) (xy 440.369375 -346.159978) (xy 440.387213 -346.10396)
			(xy 440.413439 -346.051343) (xy 440.447429 -346.003375) (xy 440.48838 -345.961192) (xy 440.53532 -345.925795)
			(xy 440.560968 -345.911424) (xy 440.56886 -345.906719) (xy 440.580902 -345.89286) (xy 440.58729 -345.875648)
			(xy 440.587638 -345.866466) (xy 440.587638 -341.08898) (xy 440.587139 -341.078985) (xy 440.579502 -341.060509)
			(xy 440.565419 -341.046318) (xy 440.556396 -341.04199) (xy 440.541918 -341.035894) (xy 440.511946 -341.04199)
			(xy 439.52922 -342.024716) (xy 439.511179 -342.041974) (xy 439.469685 -342.069728) (xy 439.423566 -342.088837)
			(xy 439.374603 -342.098564) (xy 439.349642 -342.099138) (xy 416.31235 -342.099138) (xy 416.287395 -342.098522)
			(xy 416.238445 -342.088777) (xy 416.192336 -342.069672) (xy 416.15084 -342.04194) (xy 416.132772 -342.024716)
			(xy 413.210248 -339.102192) (xy 413.202846 -339.095355) (xy 413.184248 -339.08764) (xy 413.17418 -339.087206)
			(xy 408.676602 -339.087206) (xy 408.66822 -339.090254) (xy 408.643103 -339.09888) (xy 408.59115 -339.10989)
			(xy 408.538172 -339.113584) (xy 408.485194 -339.10989) (xy 408.433241 -339.09888) (xy 408.408124 -339.090254)
			(xy 408.399742 -339.087206) (xy 390.99109 -339.087206) (xy 390.966134 -339.086594) (xy 390.917181 -339.076854)
			(xy 390.871068 -339.057753) (xy 390.829568 -339.030022) (xy 390.811512 -339.012784) (xy 379.668532 -327.869804)
			(xy 379.66113 -327.862968) (xy 379.642532 -327.855257) (xy 379.632464 -327.854818) (xy 359.442766 -327.854818)
			(xy 359.435056 -327.855046) (xy 359.420317 -327.859567) (xy 359.41381 -327.863708) (xy 359.389849 -327.879519)
			(xy 359.338187 -327.904545) (xy 359.283364 -327.921565) (xy 359.226612 -327.930196) (xy 359.19791 -327.930764)
			(xy 359.169203 -327.93025) (xy 359.112439 -327.921644) (xy 359.057611 -327.904612) (xy 359.005962 -327.879539)
			(xy 358.98201 -327.863708) (xy 358.975498 -327.859578) (xy 358.960762 -327.855061) (xy 358.953054 -327.854818)
			(xy 353.638104 -327.854818) (xy 353.627856 -327.855277) (xy 353.608979 -327.863262) (xy 353.601528 -327.870312)
			(xy 353.543616 -327.930764) (xy 353.53625 -327.950068) (xy 353.536758 -327.960482) (xy 353.537012 -327.975722)
			(xy 353.536525 -328.002972) (xy 353.528766 -328.056918) (xy 353.513409 -328.10921) (xy 353.490766 -328.158785)
			(xy 353.4613 -328.204633) (xy 353.425608 -328.245821) (xy 353.384418 -328.28151) (xy 353.338569 -328.310975)
			(xy 353.288993 -328.333615) (xy 353.2367 -328.34897) (xy 353.182754 -328.356726) (xy 353.155504 -328.35723)
			(xy 353.132292 -328.35689) (xy 353.086212 -328.351258) (xy 353.041159 -328.340065) (xy 353.01936 -328.332084)
			(xy 353.005136 -328.32675) (xy 352.975926 -328.332846) (xy 352.709988 -328.598784) (xy 352.69195 -328.61605)
			(xy 352.650458 -328.643818) (xy 352.60434 -328.662942) (xy 352.555373 -328.672683) (xy 352.53041 -328.673206)
			(xy 346.977208 -328.673206) (xy 346.950284 -328.693018) (xy 346.945458 -328.709274) (xy 346.93714 -328.735017)
			(xy 346.914252 -328.784036) (xy 346.884669 -328.829331) (xy 346.848985 -328.869993) (xy 346.807915 -328.905207)
			(xy 346.762283 -328.934266) (xy 346.713004 -328.956589) (xy 346.661065 -328.971727) (xy 346.60751 -328.979377)
			(xy 346.58046 -328.979784) (xy 346.553211 -328.979295) (xy 346.499269 -328.971534) (xy 346.446981 -328.956175)
			(xy 346.39741 -328.933531) (xy 346.351566 -328.904063) (xy 346.310383 -328.868372) (xy 346.274698 -328.827182)
			(xy 346.245238 -328.781334) (xy 346.222603 -328.731759) (xy 346.207253 -328.679468) (xy 346.1995 -328.625525)
			(xy 346.198952 -328.598276) (xy 346.199493 -328.569919) (xy 346.207928 -328.513833) (xy 346.224563 -328.459612)
			(xy 346.249033 -328.408447) (xy 346.264484 -328.384662) (xy 346.270588 -328.374553) (xy 346.27372 -328.351175)
			(xy 346.266113 -328.328849) (xy 346.258134 -328.320146) (xy 344.156792 -326.218804) (xy 344.149393 -326.211959)
			(xy 344.130795 -326.204226) (xy 344.120724 -326.203818) (xy 322.5292 -326.203818) (xy 322.51913 -326.204242)
			(xy 322.500527 -326.211958) (xy 322.493132 -326.218804) (xy 318.89954 -329.812396) (xy 318.8815 -329.829657)
			(xy 318.840007 -329.857417) (xy 318.793888 -329.876531) (xy 318.744924 -329.886262) (xy 318.719962 -329.886818)
			(xy 313.0042 -329.886818) (xy 312.99413 -329.887242) (xy 312.975527 -329.894958) (xy 312.968132 -329.901804)
			(xy 312.384948 -330.484988) (xy 312.378095 -330.492384) (xy 312.370348 -330.510982) (xy 312.369962 -330.521056)
			(xy 312.369962 -334.994758) (xy 312.369385 -335.019716) (xy 312.359635 -335.068671) (xy 312.340522 -335.114782)
			(xy 312.312779 -335.156279) (xy 312.29554 -335.174336) (xy 311.80278 -335.667096) (xy 311.784741 -335.68436)
			(xy 311.743249 -335.712127) (xy 311.697131 -335.731248) (xy 311.648165 -335.740987) (xy 311.623202 -335.741518)
			(xy 306.512722 -335.741518) (xy 306.486052 -335.760822) (xy 306.480972 -335.77657) (xy 306.47233 -335.8018)
			(xy 306.448986 -335.849749) (xy 306.41919 -335.893979) (xy 306.383524 -335.933628) (xy 306.342684 -335.967922)
			(xy 306.297464 -335.996193) (xy 306.248747 -336.01789) (xy 306.197483 -336.032589) (xy 306.144671 -336.040005)
			(xy 306.118006 -336.040476) (xy 306.090636 -336.040005) (xy 306.036458 -336.032181) (xy 305.983954 -336.016694)
			(xy 305.934203 -335.993861) (xy 305.888227 -335.964152) (xy 305.867308 -335.946496) (xy 305.860196 -335.9404)
			(xy 305.843178 -335.93405) (xy 305.757834 -335.93405) (xy 305.740816 -335.9404) (xy 305.733704 -335.946496)
			(xy 305.712773 -335.964138) (xy 305.666807 -335.993865) (xy 305.61706 -336.016709) (xy 305.564556 -336.0322)
			(xy 305.510377 -336.040019) (xy 305.483006 -336.040476) (xy 305.45634 -336.040032) (xy 305.403529 -336.032607)
			(xy 305.352265 -336.0179) (xy 305.303549 -335.996198) (xy 305.25833 -335.967924) (xy 305.217488 -335.933629)
			(xy 305.18182 -335.893981) (xy 305.15202 -335.849752) (xy 305.128669 -335.801805) (xy 305.12004 -335.77657)
			(xy 305.11496 -335.760822) (xy 305.08829 -335.741518) (xy 304.248312 -335.741518) (xy 304.221388 -335.761838)
			(xy 304.216562 -335.778348) (xy 304.208571 -335.804562) (xy 304.186116 -335.854552) (xy 304.156741 -335.900815)
			(xy 304.12105 -335.9424) (xy 304.079776 -335.978452) (xy 304.03377 -336.008228) (xy 303.983978 -336.031117)
			(xy 303.931423 -336.046647) (xy 303.877187 -336.054499) (xy 303.849786 -336.054954) (xy 303.821048 -336.054432)
			(xy 303.764222 -336.045807) (xy 303.709333 -336.028753) (xy 303.657624 -336.003658) (xy 303.610265 -335.971089)
			(xy 303.588928 -335.95183) (xy 303.581816 -335.945226) (xy 303.56429 -335.938114) (xy 303.474882 -335.938114)
			(xy 303.457356 -335.945226) (xy 303.450244 -335.95183) (xy 303.428916 -335.971098) (xy 303.381552 -336.003657)
			(xy 303.329839 -336.028743) (xy 303.27495 -336.045788) (xy 303.218124 -336.054407) (xy 303.189386 -336.054954)
			(xy 303.161986 -336.054479) (xy 303.10775 -336.046635) (xy 303.055195 -336.031111) (xy 303.005402 -336.008226)
			(xy 302.959397 -335.978451) (xy 302.918126 -335.942399) (xy 302.882438 -335.900813) (xy 302.853069 -335.854547)
			(xy 302.830623 -335.804555) (xy 302.82261 -335.778348) (xy 302.817784 -335.761838) (xy 302.79086 -335.741518)
			(xy 271.536668 -335.741518) (xy 271.526601 -335.741947) (xy 271.508006 -335.749672) (xy 271.5006 -335.756504)
			(xy 271.363948 -335.893156) (xy 271.357105 -335.900555) (xy 271.349384 -335.919154) (xy 271.348962 -335.929224)
			(xy 271.348962 -336.9836) (xy 318.155561 -336.9836) (xy 318.15955 -336.899842) (xy 318.171484 -336.816843)
			(xy 318.191253 -336.735354) (xy 318.218678 -336.656114) (xy 318.253512 -336.579839) (xy 318.295438 -336.50722)
			(xy 318.344078 -336.438916) (xy 318.398989 -336.375544) (xy 318.459676 -336.317679) (xy 318.525589 -336.265845)
			(xy 318.59613 -336.220511) (xy 318.670661 -336.182087) (xy 318.748507 -336.150922) (xy 318.828963 -336.127298)
			(xy 318.911301 -336.111429) (xy 318.994774 -336.103459) (xy 319.0367 -336.10296) (xy 319.073884 -336.103325)
			(xy 319.147992 -336.109548) (xy 319.221312 -336.121992) (xy 319.293323 -336.140567) (xy 319.328546 -336.15249)
			(xy 319.336742 -336.155013) (xy 319.353878 -336.155013) (xy 319.362074 -336.15249) (xy 319.406878 -336.137448)
			(xy 319.498905 -336.115902) (xy 319.592708 -336.104321) (xy 319.63995 -336.10296) (xy 319.651488 -336.102265)
			(xy 319.672113 -336.091876) (xy 319.686133 -336.073526) (xy 319.688972 -336.06232) (xy 319.698432 -336.018429)
			(xy 319.725027 -335.932667) (xy 319.742058 -335.891124) (xy 319.745615 -335.881531) (xy 319.745619 -335.861091)
			(xy 319.742058 -335.8515) (xy 319.72505 -335.810089) (xy 319.698496 -335.72459) (xy 319.68066 -335.636857)
			(xy 319.671721 -335.547776) (xy 319.671192 -335.503012) (xy 319.671696 -335.460664) (xy 319.679747 -335.37635)
			(xy 319.695776 -335.293184) (xy 319.719637 -335.211917) (xy 319.751116 -335.133287) (xy 319.789927 -335.058006)
			(xy 319.835717 -334.986754) (xy 319.888073 -334.920178) (xy 319.946521 -334.85888) (xy 320.010531 -334.803415)
			(xy 320.079523 -334.754286) (xy 320.152873 -334.711937) (xy 320.229916 -334.676753) (xy 320.309955 -334.649051)
			(xy 320.392264 -334.629083) (xy 320.476099 -334.61703) (xy 320.5607 -334.613) (xy 320.645301 -334.61703)
			(xy 320.729136 -334.629083) (xy 320.811445 -334.649051) (xy 320.891484 -334.676753) (xy 320.968527 -334.711937)
			(xy 321.041877 -334.754286) (xy 321.110869 -334.803415) (xy 321.174879 -334.85888) (xy 321.233327 -334.920178)
			(xy 321.285683 -334.986754) (xy 321.331473 -335.058006) (xy 321.370284 -335.133287) (xy 321.401763 -335.211917)
			(xy 321.425624 -335.293184) (xy 321.441653 -335.37635) (xy 321.449704 -335.460664) (xy 321.450208 -335.503012)
			(xy 321.449678 -335.547776) (xy 321.440749 -335.636858) (xy 321.42291 -335.724591) (xy 321.396343 -335.810086)
			(xy 321.379342 -335.8515) (xy 321.375771 -335.861089) (xy 321.375776 -335.881533) (xy 321.379342 -335.891124)
			(xy 321.395061 -335.929255) (xy 321.42019 -336.007817) (xy 321.437947 -336.088366) (xy 321.448179 -336.170212)
			(xy 321.449954 -336.211418) (xy 321.450208 -336.22488) (xy 321.464432 -336.247994) (xy 321.564762 -336.303112)
			(xy 321.591686 -336.302604) (xy 321.603116 -336.295746) (xy 321.637462 -336.275884) (xy 321.709064 -336.241691)
			(xy 321.783427 -336.214009) (xy 321.859958 -336.193059) (xy 321.938052 -336.179007) (xy 322.017086 -336.171964)
			(xy 322.05676 -336.17154) (xy 322.097864 -336.17199) (xy 322.179721 -336.179572) (xy 322.26053 -336.194675)
			(xy 322.3396 -336.21717) (xy 322.416257 -336.246866) (xy 322.489847 -336.283508) (xy 322.559742 -336.326784)
			(xy 322.625346 -336.376325) (xy 322.686098 -336.431708) (xy 322.74148 -336.492461) (xy 322.791021 -336.558064)
			(xy 322.834296 -336.62796) (xy 322.870938 -336.70155) (xy 322.900632 -336.778207) (xy 322.923127 -336.857278)
			(xy 322.938229 -336.938087) (xy 322.941787 -336.9765) (xy 326.511148 -336.9765) (xy 326.515138 -336.892742)
			(xy 326.527072 -336.809743) (xy 326.546841 -336.728254) (xy 326.574266 -336.649013) (xy 326.609099 -336.572737)
			(xy 326.651025 -336.500118) (xy 326.699664 -336.431814) (xy 326.754575 -336.368441) (xy 326.815262 -336.310576)
			(xy 326.881174 -336.258741) (xy 326.951715 -336.213406) (xy 327.026246 -336.174981) (xy 327.104092 -336.143815)
			(xy 327.184547 -336.12019) (xy 327.266885 -336.104319) (xy 327.350358 -336.096347) (xy 327.392284 -336.095848)
			(xy 327.429468 -336.096219) (xy 327.503576 -336.10244) (xy 327.576896 -336.114882) (xy 327.648907 -336.133456)
			(xy 327.68413 -336.145378) (xy 327.692326 -336.147901) (xy 327.709462 -336.147901) (xy 327.717658 -336.145378)
			(xy 327.763554 -336.130002) (xy 327.857867 -336.108208) (xy 327.953999 -336.096874) (xy 328.002392 -336.095848)
			(xy 328.013767 -336.095113) (xy 328.034196 -336.085063) (xy 328.048298 -336.06719) (xy 328.051414 -336.056224)
			(xy 328.060633 -336.017607) (xy 328.085057 -335.942056) (xy 328.100182 -335.905348) (xy 328.103724 -335.895751)
			(xy 328.103738 -335.875315) (xy 328.100182 -335.865724) (xy 328.083183 -335.82431) (xy 328.056627 -335.738812)
			(xy 328.038788 -335.65108) (xy 328.029846 -335.562) (xy 328.029316 -335.517236) (xy 328.02982 -335.474888)
			(xy 328.037871 -335.390574) (xy 328.0539 -335.307408) (xy 328.077761 -335.226141) (xy 328.10924 -335.147511)
			(xy 328.148051 -335.07223) (xy 328.193841 -335.000978) (xy 328.246197 -334.934402) (xy 328.304645 -334.873104)
			(xy 328.368655 -334.817639) (xy 328.437647 -334.76851) (xy 328.510997 -334.726161) (xy 328.58804 -334.690977)
			(xy 328.668079 -334.663275) (xy 328.750388 -334.643307) (xy 328.834223 -334.631254) (xy 328.918824 -334.627224)
			(xy 329.003425 -334.631254) (xy 329.08726 -334.643307) (xy 329.169569 -334.663275) (xy 329.249608 -334.690977)
			(xy 329.326651 -334.726161) (xy 329.400001 -334.76851) (xy 329.468993 -334.817639) (xy 329.533003 -334.873104)
			(xy 329.591451 -334.934402) (xy 329.643807 -335.000978) (xy 329.689597 -335.07223) (xy 329.728408 -335.147511)
			(xy 329.759887 -335.226141) (xy 329.783748 -335.307408) (xy 329.799777 -335.390574) (xy 329.807828 -335.474888)
			(xy 329.808332 -335.517236) (xy 329.807817 -335.562001) (xy 329.798884 -335.651083) (xy 329.781041 -335.738816)
			(xy 329.75447 -335.824311) (xy 329.737466 -335.865724) (xy 329.733881 -335.875309) (xy 329.733894 -335.895757)
			(xy 329.737466 -335.905348) (xy 329.752245 -335.941179) (xy 329.776235 -336.014886) (xy 329.793723 -336.090401)
			(xy 329.804575 -336.167151) (xy 329.807062 -336.20583) (xy 329.807824 -336.219038) (xy 329.822048 -336.24139)
			(xy 329.922124 -336.294984) (xy 329.948794 -336.294476) (xy 329.960224 -336.287872) (xy 329.994483 -336.268147)
			(xy 330.065868 -336.23417) (xy 330.139986 -336.206662) (xy 330.216254 -336.18584) (xy 330.294068 -336.171868)
			(xy 330.372815 -336.164856) (xy 330.412344 -336.164428) (xy 330.453448 -336.164825) (xy 330.535306 -336.172414)
			(xy 330.616114 -336.187524) (xy 330.695183 -336.210025) (xy 330.771839 -336.239726) (xy 330.845427 -336.276373)
			(xy 330.91532 -336.319653) (xy 330.980922 -336.369198) (xy 331.041672 -336.424584) (xy 331.097053 -336.48534)
			(xy 331.146592 -336.550946) (xy 331.189866 -336.620843) (xy 331.226507 -336.694434) (xy 331.256201 -336.771093)
			(xy 331.278695 -336.850164) (xy 331.293797 -336.930973) (xy 331.296671 -336.962) (xy 334.868517 -336.962)
			(xy 334.872507 -336.878219) (xy 334.884444 -336.795197) (xy 334.904219 -336.713686) (xy 334.931652 -336.634423)
			(xy 334.966495 -336.558127) (xy 335.008433 -336.485488) (xy 335.057086 -336.417165) (xy 335.112013 -336.353776)
			(xy 335.172717 -336.295895) (xy 335.238647 -336.244046) (xy 335.309208 -336.198699) (xy 335.38376 -336.160265)
			(xy 335.461628 -336.129092) (xy 335.542106 -336.105461) (xy 335.624466 -336.089588) (xy 335.707962 -336.081615)
			(xy 335.7499 -336.081116) (xy 335.78709 -336.081504) (xy 335.861203 -336.087794) (xy 335.934522 -336.100304)
			(xy 336.006528 -336.118945) (xy 336.041746 -336.1309) (xy 336.049942 -336.133423) (xy 336.067078 -336.133423)
			(xy 336.075274 -336.1309) (xy 336.110496 -336.118972) (xy 336.182504 -336.10038) (xy 336.255825 -336.087935)
			(xy 336.329935 -336.081725) (xy 336.36712 -336.08137) (xy 336.378455 -336.080768) (xy 336.398918 -336.071018)
			(xy 336.413169 -336.05339) (xy 336.416396 -336.042508) (xy 336.425304 -336.007451) (xy 336.448069 -335.938786)
			(xy 336.461862 -335.905348) (xy 336.465405 -335.895751) (xy 336.465418 -335.875315) (xy 336.461862 -335.865724)
			(xy 336.444862 -335.82431) (xy 336.418306 -335.738812) (xy 336.400467 -335.65108) (xy 336.391526 -335.562)
			(xy 336.390996 -335.517236) (xy 336.3915 -335.474888) (xy 336.399551 -335.390574) (xy 336.41558 -335.307408)
			(xy 336.439441 -335.226141) (xy 336.47092 -335.147511) (xy 336.509731 -335.07223) (xy 336.555521 -335.000978)
			(xy 336.607877 -334.934402) (xy 336.666325 -334.873104) (xy 336.730335 -334.817639) (xy 336.799327 -334.76851)
			(xy 336.872677 -334.726161) (xy 336.94972 -334.690977) (xy 337.029759 -334.663275) (xy 337.112068 -334.643307)
			(xy 337.195903 -334.631254) (xy 337.280504 -334.627224) (xy 337.365105 -334.631254) (xy 337.44894 -334.643307)
			(xy 337.531249 -334.663275) (xy 337.611288 -334.690977) (xy 337.688331 -334.726161) (xy 337.761681 -334.76851)
			(xy 337.830673 -334.817639) (xy 337.894683 -334.873104) (xy 337.953131 -334.934402) (xy 338.005487 -335.000978)
			(xy 338.051277 -335.07223) (xy 338.090088 -335.147511) (xy 338.121567 -335.226141) (xy 338.145428 -335.307408)
			(xy 338.161457 -335.390574) (xy 338.169508 -335.474888) (xy 338.170012 -335.517236) (xy 338.169491 -335.562001)
			(xy 338.160559 -335.651083) (xy 338.142718 -335.738815) (xy 338.116149 -335.824311) (xy 338.099146 -335.865724)
			(xy 338.095561 -335.875309) (xy 338.095575 -335.895757) (xy 338.099146 -335.905348) (xy 338.117792 -335.95091)
			(xy 338.146101 -336.045203) (xy 338.163844 -336.142042) (xy 338.16798 -336.191098) (xy 338.168742 -336.204306)
			(xy 338.18322 -336.226404) (xy 338.283042 -336.278982) (xy 338.309204 -336.278474) (xy 338.320634 -336.271616)
			(xy 338.354723 -336.252133) (xy 338.425722 -336.218592) (xy 338.499399 -336.191437) (xy 338.575183 -336.170878)
			(xy 338.652483 -336.157075) (xy 338.730699 -336.150137) (xy 338.76996 -336.149696) (xy 338.81107 -336.150191)
			(xy 338.89294 -336.157775) (xy 338.97376 -336.172882) (xy 339.052841 -336.195384) (xy 339.129508 -336.225088)
			(xy 339.203107 -336.261741) (xy 339.273008 -336.305029) (xy 339.338617 -336.354584) (xy 339.399372 -336.409982)
			(xy 339.454755 -336.470751) (xy 339.504294 -336.536372) (xy 339.547565 -336.606284) (xy 339.5842 -336.679891)
			(xy 339.613885 -336.756566) (xy 339.636368 -336.835652) (xy 339.651455 -336.916476) (xy 339.659019 -336.998348)
			(xy 339.659177 -337.0128) (xy 343.199717 -337.0128) (xy 343.203707 -336.929019) (xy 343.215644 -336.845997)
			(xy 343.235419 -336.764486) (xy 343.262852 -336.685223) (xy 343.297695 -336.608927) (xy 343.339633 -336.536288)
			(xy 343.388286 -336.467965) (xy 343.443213 -336.404576) (xy 343.503917 -336.346695) (xy 343.569847 -336.294846)
			(xy 343.640408 -336.249499) (xy 343.71496 -336.211065) (xy 343.792828 -336.179892) (xy 343.873306 -336.156261)
			(xy 343.955666 -336.140388) (xy 344.039162 -336.132415) (xy 344.0811 -336.131916) (xy 344.11829 -336.132304)
			(xy 344.192403 -336.138594) (xy 344.265722 -336.151104) (xy 344.337728 -336.169745) (xy 344.372946 -336.1817)
			(xy 344.381142 -336.184223) (xy 344.398278 -336.184223) (xy 344.406474 -336.1817) (xy 344.441687 -336.169727)
			(xy 344.513691 -336.151076) (xy 344.587013 -336.13857) (xy 344.661129 -336.1323) (xy 344.69832 -336.131916)
			(xy 344.712798 -336.13217) (xy 344.724169 -336.131792) (xy 344.744841 -336.122355) (xy 344.759419 -336.104924)
			(xy 344.762836 -336.09407) (xy 344.771394 -336.062107) (xy 344.792623 -335.999431) (xy 344.805254 -335.968848)
			(xy 344.808797 -335.959251) (xy 344.808811 -335.938814) (xy 344.805254 -335.929224) (xy 344.788254 -335.887811)
			(xy 344.761698 -335.802312) (xy 344.743859 -335.71458) (xy 344.734918 -335.6255) (xy 344.734388 -335.580736)
			(xy 344.734892 -335.538388) (xy 344.742943 -335.454074) (xy 344.758972 -335.370908) (xy 344.782833 -335.289641)
			(xy 344.814312 -335.211011) (xy 344.853123 -335.13573) (xy 344.898913 -335.064478) (xy 344.951269 -334.997902)
			(xy 345.009717 -334.936604) (xy 345.073727 -334.881139) (xy 345.142719 -334.83201) (xy 345.216069 -334.789661)
			(xy 345.293112 -334.754477) (xy 345.373151 -334.726775) (xy 345.45546 -334.706807) (xy 345.539295 -334.694754)
			(xy 345.623896 -334.690724) (xy 345.708497 -334.694754) (xy 345.792332 -334.706807) (xy 345.874641 -334.726775)
			(xy 345.95468 -334.754477) (xy 346.031723 -334.789661) (xy 346.105073 -334.83201) (xy 346.174065 -334.881139)
			(xy 346.238075 -334.936604) (xy 346.296523 -334.997902) (xy 346.348879 -335.064478) (xy 346.394669 -335.13573)
			(xy 346.43348 -335.211011) (xy 346.464959 -335.289641) (xy 346.48882 -335.370908) (xy 346.504849 -335.454074)
			(xy 346.5129 -335.538388) (xy 346.513404 -335.580736) (xy 346.512883 -335.625501) (xy 346.503951 -335.714582)
			(xy 346.48611 -335.802315) (xy 346.45954 -335.887811) (xy 346.442538 -335.929224) (xy 346.438954 -335.938809)
			(xy 346.438967 -335.959257) (xy 346.442538 -335.968848) (xy 346.459529 -336.010265) (xy 346.486087 -336.095762)
			(xy 346.503929 -336.183493) (xy 346.512872 -336.272572) (xy 346.513404 -336.317336) (xy 346.513182 -336.348682)
			(xy 346.508857 -336.411225) (xy 346.504768 -336.442304) (xy 346.503244 -336.452972) (xy 346.508832 -336.473292)
			(xy 346.569538 -336.547714) (xy 346.58808 -336.557366) (xy 346.598748 -336.558128) (xy 346.640541 -336.561266)
			(xy 346.723318 -336.574429) (xy 346.804489 -336.59532) (xy 346.883336 -336.623754) (xy 346.959158 -336.659479)
			(xy 347.031283 -336.702177) (xy 347.099073 -336.75147) (xy 347.161925 -336.806921) (xy 347.219283 -336.868039)
			(xy 347.270637 -336.93428) (xy 347.315532 -337.005059) (xy 347.353571 -337.079747) (xy 347.384416 -337.157682)
			(xy 347.407793 -337.238172) (xy 347.423495 -337.320505) (xy 347.431383 -337.40395) (xy 347.431868 -337.445858)
			(xy 347.431361 -337.488564) (xy 347.423173 -337.573582) (xy 347.406877 -337.657424) (xy 347.382624 -337.739319)
			(xy 347.367098 -337.779106) (xy 347.363667 -337.789193) (xy 347.364442 -337.810456) (xy 347.368622 -337.820254)
			(xy 347.385657 -337.856566) (xy 347.413925 -337.931633) (xy 347.435319 -338.008941) (xy 347.449664 -338.08786)
			(xy 347.456846 -338.167751) (xy 347.457268 -338.207858) (xy 347.456674 -338.254253) (xy 347.447033 -338.346541)
			(xy 347.42784 -338.437325) (xy 347.399305 -338.525619) (xy 347.381068 -338.568284) (xy 347.377284 -338.578233)
			(xy 347.377268 -338.599491) (xy 347.381068 -338.609432) (xy 347.399296 -338.652101) (xy 347.427845 -338.740391)
			(xy 347.447043 -338.831174) (xy 347.456681 -338.923462) (xy 347.457268 -338.969858) (xy 347.456674 -339.016253)
			(xy 347.447033 -339.108541) (xy 347.42784 -339.199325) (xy 347.399305 -339.287619) (xy 347.381068 -339.330284)
			(xy 347.377284 -339.340233) (xy 347.377268 -339.361491) (xy 347.381068 -339.371432) (xy 347.399296 -339.414101)
			(xy 347.427845 -339.502391) (xy 347.447043 -339.593174) (xy 347.456681 -339.685462) (xy 347.457268 -339.731858)
			(xy 347.456747 -339.772964) (xy 347.449167 -339.854825) (xy 347.434067 -339.935639) (xy 347.411576 -340.014714)
			(xy 347.381885 -340.091377) (xy 347.345249 -340.164975) (xy 347.30198 -340.234878) (xy 347.252446 -340.300492)
			(xy 347.19707 -340.361256) (xy 347.136324 -340.416653) (xy 347.070727 -340.466209) (xy 347.000838 -340.509502)
			(xy 346.927254 -340.546163) (xy 346.8506 -340.575879) (xy 346.771533 -340.598397) (xy 346.690725 -340.613525)
			(xy 346.608866 -340.621133) (xy 346.56776 -340.62162) (xy 346.525159 -340.621134) (xy 346.440349 -340.612975)
			(xy 346.356708 -340.596745) (xy 346.275001 -340.572593) (xy 346.195978 -340.540739) (xy 346.120362 -340.501477)
			(xy 346.048846 -340.455165) (xy 345.982085 -340.402229) (xy 345.920691 -340.343152) (xy 345.865226 -340.278476)
			(xy 345.840304 -340.243922) (xy 345.834716 -340.236562) (xy 345.819472 -340.226142) (xy 345.810586 -340.223602)
			(xy 345.769427 -340.213207) (xy 345.689122 -340.185668) (xy 345.611806 -340.150603) (xy 345.538183 -340.108332)
			(xy 345.468921 -340.05924) (xy 345.40465 -340.003772) (xy 345.345957 -339.942434) (xy 345.293373 -339.875784)
			(xy 345.247379 -339.804427) (xy 345.208391 -339.729013) (xy 345.176765 -339.650228) (xy 345.152789 -339.568788)
			(xy 345.136679 -339.485435) (xy 345.128584 -339.400926) (xy 345.128088 -339.358478) (xy 345.128614 -339.313713)
			(xy 345.137545 -339.224632) (xy 345.155384 -339.136899) (xy 345.181952 -339.051403) (xy 345.198954 -339.00999)
			(xy 345.202531 -339.000403) (xy 345.202523 -338.979957) (xy 345.198954 -338.970366) (xy 345.181967 -338.928947)
			(xy 345.155408 -338.843451) (xy 345.137565 -338.75572) (xy 345.12862 -338.666642) (xy 345.128088 -338.621878)
			(xy 345.128614 -338.577113) (xy 345.137545 -338.488032) (xy 345.155384 -338.400299) (xy 345.181952 -338.314803)
			(xy 345.198954 -338.27339) (xy 345.202531 -338.263803) (xy 345.202523 -338.243357) (xy 345.198954 -338.233766)
			(xy 345.183168 -338.195457) (xy 345.157955 -338.116523) (xy 345.140197 -338.035586) (xy 345.130046 -337.953347)
			(xy 345.128342 -337.911948) (xy 345.12754 -337.901022) (xy 345.117874 -337.881381) (xy 345.100942 -337.867505)
			(xy 345.090496 -337.864196) (xy 345.073624 -337.859698) (xy 345.040213 -337.849535) (xy 345.023694 -337.843876)
			(xy 345.015498 -337.841353) (xy 344.998362 -337.841353) (xy 344.990166 -337.843876) (xy 344.95495 -337.855837)
			(xy 344.882946 -337.874492) (xy 344.809626 -337.887) (xy 344.73551 -337.893274) (xy 344.69832 -337.89366)
			(xy 344.661131 -337.893262) (xy 344.587018 -337.886974) (xy 344.513698 -337.874467) (xy 344.441692 -337.855829)
			(xy 344.406474 -337.843876) (xy 344.398278 -337.841353) (xy 344.381142 -337.841353) (xy 344.372946 -337.843876)
			(xy 344.337731 -337.855842) (xy 344.265728 -337.874496) (xy 344.192406 -337.887003) (xy 344.11829 -337.893275)
			(xy 344.0811 -337.89366) (xy 344.039162 -337.893185) (xy 343.955666 -337.885212) (xy 343.873306 -337.869339)
			(xy 343.792828 -337.845708) (xy 343.71496 -337.814535) (xy 343.640408 -337.776101) (xy 343.569847 -337.730754)
			(xy 343.503917 -337.678905) (xy 343.443213 -337.621024) (xy 343.388286 -337.557635) (xy 343.339633 -337.489312)
			(xy 343.297695 -337.416673) (xy 343.262852 -337.340377) (xy 343.235419 -337.261114) (xy 343.215644 -337.179603)
			(xy 343.203707 -337.096581) (xy 343.199717 -337.0128) (xy 339.659177 -337.0128) (xy 339.659468 -337.039458)
			(xy 339.658957 -337.084223) (xy 339.650022 -337.173305) (xy 339.632178 -337.261038) (xy 339.605606 -337.346533)
			(xy 339.588602 -337.387946) (xy 339.585059 -337.397543) (xy 339.585044 -337.41798) (xy 339.588602 -337.42757)
			(xy 339.605598 -337.468985) (xy 339.632155 -337.554483) (xy 339.649995 -337.642215) (xy 339.658937 -337.731294)
			(xy 339.659468 -337.776058) (xy 339.658957 -337.820823) (xy 339.650022 -337.909905) (xy 339.632178 -337.997638)
			(xy 339.605606 -338.083133) (xy 339.588602 -338.124546) (xy 339.585059 -338.134143) (xy 339.585044 -338.15458)
			(xy 339.588602 -338.16417) (xy 339.605598 -338.205585) (xy 339.632155 -338.291083) (xy 339.649995 -338.378815)
			(xy 339.658937 -338.467894) (xy 339.659468 -338.512658) (xy 339.658947 -338.553764) (xy 339.651367 -338.635625)
			(xy 339.636267 -338.716439) (xy 339.613776 -338.795514) (xy 339.584085 -338.872177) (xy 339.547449 -338.945775)
			(xy 339.50418 -339.015678) (xy 339.454646 -339.081292) (xy 339.39927 -339.142056) (xy 339.338524 -339.197453)
			(xy 339.272927 -339.247009) (xy 339.203038 -339.290302) (xy 339.129454 -339.326963) (xy 339.0528 -339.356679)
			(xy 338.973733 -339.379197) (xy 338.892925 -339.394325) (xy 338.811066 -339.401933) (xy 338.76996 -339.40242)
			(xy 338.728345 -339.401907) (xy 338.645481 -339.394089) (xy 338.563708 -339.378573) (xy 338.483741 -339.355493)
			(xy 338.406276 -339.325051) (xy 338.33199 -339.287513) (xy 338.296504 -339.265768) (xy 338.287397 -339.260652)
			(xy 338.266748 -339.257605) (xy 338.246582 -339.262991) (xy 338.238084 -339.26907) (xy 338.204417 -339.295039)
			(xy 338.132992 -339.341179) (xy 338.057489 -339.380291) (xy 337.978598 -339.412018) (xy 337.897038 -339.436071)
			(xy 337.813556 -339.452228) (xy 337.728912 -339.460344) (xy 337.686396 -339.46084) (xy 337.645286 -339.460351)
			(xy 337.563418 -339.452764) (xy 337.482599 -339.437653) (xy 337.403519 -339.415149) (xy 337.326853 -339.385443)
			(xy 337.253256 -339.348789) (xy 337.183356 -339.3055) (xy 337.117748 -339.255944) (xy 337.056994 -339.200546)
			(xy 337.001611 -339.139778) (xy 336.952073 -339.074158) (xy 336.908801 -339.004246) (xy 336.872166 -338.93064)
			(xy 336.842479 -338.853967) (xy 336.819995 -338.774881) (xy 336.804905 -338.694058) (xy 336.797338 -338.612188)
			(xy 336.796888 -338.571078) (xy 336.797414 -338.526313) (xy 336.806345 -338.437232) (xy 336.824184 -338.349499)
			(xy 336.850752 -338.264003) (xy 336.867754 -338.22259) (xy 336.871331 -338.213003) (xy 336.871323 -338.192557)
			(xy 336.867754 -338.182966) (xy 336.851968 -338.144657) (xy 336.826755 -338.065723) (xy 336.808997 -337.984786)
			(xy 336.798846 -337.902547) (xy 336.797142 -337.861148) (xy 336.79634 -337.850222) (xy 336.786674 -337.830581)
			(xy 336.769742 -337.816705) (xy 336.759296 -337.813396) (xy 336.742424 -337.808898) (xy 336.709013 -337.798735)
			(xy 336.692494 -337.793076) (xy 336.684298 -337.790553) (xy 336.667162 -337.790553) (xy 336.658966 -337.793076)
			(xy 336.62375 -337.805037) (xy 336.551746 -337.823692) (xy 336.478426 -337.8362) (xy 336.40431 -337.842474)
			(xy 336.36712 -337.84286) (xy 336.329931 -337.842462) (xy 336.255818 -337.836174) (xy 336.182498 -337.823667)
			(xy 336.110492 -337.805029) (xy 336.075274 -337.793076) (xy 336.067078 -337.790553) (xy 336.049942 -337.790553)
			(xy 336.041746 -337.793076) (xy 336.006531 -337.805042) (xy 335.934528 -337.823696) (xy 335.861206 -337.836203)
			(xy 335.78709 -337.842475) (xy 335.7499 -337.84286) (xy 335.707962 -337.842385) (xy 335.624466 -337.834412)
			(xy 335.542106 -337.818539) (xy 335.461628 -337.794908) (xy 335.38376 -337.763735) (xy 335.309208 -337.725301)
			(xy 335.238647 -337.679954) (xy 335.172717 -337.628105) (xy 335.112013 -337.570224) (xy 335.057086 -337.506835)
			(xy 335.008433 -337.438512) (xy 334.966495 -337.365873) (xy 334.931652 -337.289577) (xy 334.904219 -337.210314)
			(xy 334.884444 -337.128803) (xy 334.872507 -337.045781) (xy 334.868517 -336.962) (xy 331.296671 -336.962)
			(xy 331.301379 -337.012832) (xy 331.301852 -337.053936) (xy 331.301335 -337.098701) (xy 331.292402 -337.187783)
			(xy 331.27456 -337.275516) (xy 331.247989 -337.361011) (xy 331.230986 -337.402424) (xy 331.227399 -337.412008)
			(xy 331.227413 -337.432457) (xy 331.230986 -337.442048) (xy 331.247974 -337.483466) (xy 331.274534 -337.568963)
			(xy 331.292376 -337.656694) (xy 331.30132 -337.745772) (xy 331.301852 -337.790536) (xy 331.301335 -337.835301)
			(xy 331.292402 -337.924383) (xy 331.27456 -338.012116) (xy 331.247989 -338.097611) (xy 331.230986 -338.139024)
			(xy 331.227399 -338.148608) (xy 331.227413 -338.169057) (xy 331.230986 -338.178648) (xy 331.247974 -338.220066)
			(xy 331.274534 -338.305563) (xy 331.292376 -338.393294) (xy 331.30132 -338.482372) (xy 331.301852 -338.527136)
			(xy 331.301368 -338.568238) (xy 331.29378 -338.65009) (xy 331.278673 -338.730894) (xy 331.256175 -338.809959)
			(xy 331.226478 -338.886611) (xy 331.189836 -338.960196) (xy 331.14656 -339.030087) (xy 331.097021 -339.095686)
			(xy 331.041641 -339.156436) (xy 330.980892 -339.211816) (xy 330.915293 -339.261356) (xy 330.845403 -339.304632)
			(xy 330.771818 -339.341275) (xy 330.695167 -339.370972) (xy 330.616102 -339.393471) (xy 330.535298 -339.408579)
			(xy 330.453446 -339.416167) (xy 330.412344 -339.416644) (xy 330.370732 -339.416171) (xy 330.28787 -339.408423)
			(xy 330.206095 -339.392962) (xy 330.126124 -339.369924) (xy 330.048657 -339.33951) (xy 329.974372 -339.301987)
			(xy 329.938888 -339.280246) (xy 329.929745 -339.275207) (xy 329.90912 -339.272136) (xy 329.888967 -339.277488)
			(xy 329.880468 -339.283548) (xy 329.846805 -339.309512) (xy 329.775363 -339.355602) (xy 329.699851 -339.394667)
			(xy 329.620956 -339.426351) (xy 329.539399 -339.450365) (xy 329.455923 -339.46649) (xy 329.37129 -339.474579)
			(xy 329.32878 -339.475064) (xy 329.287675 -339.474667) (xy 329.205817 -339.46708) (xy 329.125007 -339.451972)
			(xy 329.045936 -339.429472) (xy 328.969279 -339.399772) (xy 328.895689 -339.363126) (xy 328.825795 -339.319846)
			(xy 328.760192 -339.270301) (xy 328.69944 -339.214915) (xy 328.644058 -339.154159) (xy 328.594518 -339.088553)
			(xy 328.551243 -339.018655) (xy 328.514602 -338.945062) (xy 328.484908 -338.868403) (xy 328.462414 -338.789331)
			(xy 328.447312 -338.70852) (xy 328.43973 -338.626661) (xy 328.439272 -338.585556) (xy 328.439784 -338.540791)
			(xy 328.448718 -338.451709) (xy 328.466562 -338.363976) (xy 328.493134 -338.278481) (xy 328.510138 -338.237068)
			(xy 328.513728 -338.227485) (xy 328.513711 -338.207035) (xy 328.510138 -338.197444) (xy 328.494344 -338.159138)
			(xy 328.469134 -338.080203) (xy 328.451378 -337.999265) (xy 328.441229 -337.917025) (xy 328.439526 -337.875626)
			(xy 328.438678 -337.864706) (xy 328.429036 -337.845063) (xy 328.41212 -337.831185) (xy 328.40168 -337.827874)
			(xy 328.384807 -337.823378) (xy 328.351397 -337.813214) (xy 328.334878 -337.807554) (xy 328.326682 -337.805031)
			(xy 328.309546 -337.805031) (xy 328.30135 -337.807554) (xy 328.266125 -337.819474) (xy 328.194118 -337.838068)
			(xy 328.120798 -337.850516) (xy 328.046689 -337.856728) (xy 328.009504 -337.857084) (xy 327.97232 -337.856715)
			(xy 327.898212 -337.850493) (xy 327.824892 -337.838051) (xy 327.752881 -337.819476) (xy 327.717658 -337.807554)
			(xy 327.709462 -337.805031) (xy 327.692326 -337.805031) (xy 327.68413 -337.807554) (xy 327.648907 -337.819479)
			(xy 327.576899 -337.838072) (xy 327.503579 -337.850518) (xy 327.429469 -337.856729) (xy 327.392284 -337.857084)
			(xy 327.350358 -337.856653) (xy 327.266885 -337.848681) (xy 327.184547 -337.83281) (xy 327.104092 -337.809185)
			(xy 327.026246 -337.778019) (xy 326.951715 -337.739594) (xy 326.881174 -337.694259) (xy 326.815262 -337.642424)
			(xy 326.754575 -337.584559) (xy 326.699664 -337.521186) (xy 326.651025 -337.452882) (xy 326.609099 -337.380263)
			(xy 326.574266 -337.303987) (xy 326.546841 -337.224746) (xy 326.527072 -337.143257) (xy 326.515138 -337.060258)
			(xy 326.511148 -336.9765) (xy 322.941787 -336.9765) (xy 322.94581 -337.019944) (xy 322.946268 -337.061048)
			(xy 322.945754 -337.105813) (xy 322.93682 -337.194895) (xy 322.918977 -337.282628) (xy 322.892406 -337.368123)
			(xy 322.875402 -337.409536) (xy 322.871808 -337.419118) (xy 322.871825 -337.439569) (xy 322.875402 -337.44916)
			(xy 322.892395 -337.490576) (xy 322.918953 -337.576074) (xy 322.936794 -337.663805) (xy 322.945737 -337.752884)
			(xy 322.946268 -337.797648) (xy 322.945754 -337.842413) (xy 322.93682 -337.931495) (xy 322.918977 -338.019228)
			(xy 322.892406 -338.104723) (xy 322.875402 -338.146136) (xy 322.871808 -338.155718) (xy 322.871825 -338.176169)
			(xy 322.875402 -338.18576) (xy 322.892395 -338.227176) (xy 322.918953 -338.312674) (xy 322.936794 -338.400405)
			(xy 322.945737 -338.489484) (xy 322.946268 -338.534248) (xy 322.945879 -338.575352) (xy 322.938289 -338.65721)
			(xy 322.923179 -338.738019) (xy 322.900678 -338.817088) (xy 322.870976 -338.893744) (xy 322.834329 -338.967333)
			(xy 322.791048 -339.037226) (xy 322.741503 -339.102828) (xy 322.686116 -339.163578) (xy 322.62536 -339.218959)
			(xy 322.559753 -339.268498) (xy 322.489856 -339.311772) (xy 322.416264 -339.348412) (xy 322.339605 -339.378106)
			(xy 322.260533 -339.400599) (xy 322.179723 -339.415702) (xy 322.097864 -339.423283) (xy 322.05676 -339.423756)
			(xy 322.015148 -339.423274) (xy 321.932286 -339.415527) (xy 321.850512 -339.400068) (xy 321.770541 -339.377031)
			(xy 321.693073 -339.346619) (xy 321.618788 -339.309098) (xy 321.583304 -339.287358) (xy 321.574197 -339.282243)
			(xy 321.553548 -339.279197) (xy 321.533382 -339.284582) (xy 321.524884 -339.29066) (xy 321.491217 -339.316618)
			(xy 321.419776 -339.362709) (xy 321.344264 -339.401774) (xy 321.26537 -339.433459) (xy 321.183814 -339.457474)
			(xy 321.100338 -339.4736) (xy 321.015705 -339.48169) (xy 320.973196 -339.482176) (xy 320.932092 -339.481752)
			(xy 320.850234 -339.474166) (xy 320.769426 -339.459059) (xy 320.690356 -339.436561) (xy 320.613699 -339.406863)
			(xy 320.54011 -339.370219) (xy 320.470216 -339.326941) (xy 320.404613 -339.277398) (xy 320.343861 -339.222013)
			(xy 320.288479 -339.161259) (xy 320.238939 -339.095655) (xy 320.195664 -339.025759) (xy 320.159022 -338.952168)
			(xy 320.129327 -338.87551) (xy 320.106832 -338.796439) (xy 320.091729 -338.71563) (xy 320.084147 -338.633772)
			(xy 320.083688 -338.592668) (xy 320.084211 -338.547903) (xy 320.093142 -338.458822) (xy 320.110983 -338.371089)
			(xy 320.137551 -338.285593) (xy 320.154554 -338.24418) (xy 320.158136 -338.234595) (xy 320.158125 -338.214147)
			(xy 320.154554 -338.204556) (xy 320.138765 -338.166248) (xy 320.113553 -338.087314) (xy 320.095796 -338.006376)
			(xy 320.085645 -337.924137) (xy 320.083942 -337.882738) (xy 320.083148 -337.871811) (xy 320.073477 -337.85217)
			(xy 320.056543 -337.838295) (xy 320.046096 -337.834986) (xy 320.029224 -337.830489) (xy 319.995813 -337.820325)
			(xy 319.979294 -337.814666) (xy 319.971098 -337.812143) (xy 319.953962 -337.812143) (xy 319.945766 -337.814666)
			(xy 319.910549 -337.82661) (xy 319.838539 -337.845197) (xy 319.765217 -337.857638) (xy 319.691106 -337.863844)
			(xy 319.65392 -337.864196) (xy 319.616736 -337.863827) (xy 319.542628 -337.857606) (xy 319.469308 -337.845164)
			(xy 319.397297 -337.826589) (xy 319.362074 -337.814666) (xy 319.353878 -337.812143) (xy 319.336742 -337.812143)
			(xy 319.328546 -337.814666) (xy 319.293322 -337.826587) (xy 319.221314 -337.845181) (xy 319.147994 -337.857628)
			(xy 319.073885 -337.86384) (xy 319.0367 -337.864196) (xy 318.994774 -337.863741) (xy 318.911301 -337.855771)
			(xy 318.828963 -337.839902) (xy 318.748507 -337.816278) (xy 318.670661 -337.785113) (xy 318.59613 -337.746689)
			(xy 318.525589 -337.701355) (xy 318.459676 -337.649521) (xy 318.398989 -337.591656) (xy 318.344078 -337.528284)
			(xy 318.295438 -337.45998) (xy 318.253512 -337.387361) (xy 318.218678 -337.311086) (xy 318.191253 -337.231846)
			(xy 318.171484 -337.150357) (xy 318.15955 -337.067358) (xy 318.155561 -336.9836) (xy 271.348962 -336.9836)
			(xy 271.348962 -339.385656) (xy 271.36725 -339.411564) (xy 271.382744 -339.417152) (xy 271.408507 -339.426901)
			(xy 271.457146 -339.452751) (xy 271.501563 -339.485328) (xy 271.540833 -339.523953) (xy 271.574141 -339.567825)
			(xy 271.600793 -339.61603) (xy 271.620236 -339.667566) (xy 271.632066 -339.721364) (xy 271.636037 -339.776303)
			(xy 271.632065 -339.831242) (xy 271.620235 -339.885039) (xy 271.600791 -339.936575) (xy 271.574138 -339.98478)
			(xy 271.54083 -340.028651) (xy 271.501559 -340.067275) (xy 271.457142 -340.099851) (xy 271.408502 -340.125701)
			(xy 271.382744 -340.135464) (xy 271.36725 -340.141052) (xy 271.348962 -340.16696) (xy 271.348962 -341.9229)
			(xy 351.475729 -341.9229) (xy 351.479719 -341.839138) (xy 351.491654 -341.756134) (xy 351.511424 -341.674641)
			(xy 351.538852 -341.595396) (xy 351.573688 -341.519117) (xy 351.615617 -341.446494) (xy 351.66426 -341.378187)
			(xy 351.719176 -341.314813) (xy 351.779867 -341.256945) (xy 351.845785 -341.205109) (xy 351.916331 -341.159774)
			(xy 351.990867 -341.12135) (xy 352.068718 -341.090185) (xy 352.149179 -341.066562) (xy 352.231522 -341.050694)
			(xy 352.314999 -341.042726) (xy 352.356928 -341.042244) (xy 352.394113 -341.042602) (xy 352.46822 -341.048827)
			(xy 352.54154 -341.061273) (xy 352.613551 -341.07985) (xy 352.648774 -341.091774) (xy 352.65697 -341.094297)
			(xy 352.674106 -341.094297) (xy 352.682302 -341.091774) (xy 352.717522 -341.079841) (xy 352.789531 -341.06125)
			(xy 352.862852 -341.048806) (xy 352.936963 -341.042598) (xy 352.974148 -341.042244) (xy 352.988626 -341.042244)
			(xy 352.999994 -341.041829) (xy 353.020668 -341.032414) (xy 353.035248 -341.014994) (xy 353.038664 -341.004144)
			(xy 353.047218 -340.97218) (xy 353.068449 -340.909504) (xy 353.081082 -340.878922) (xy 353.084639 -340.869329)
			(xy 353.084643 -340.848889) (xy 353.081082 -340.839298) (xy 353.064075 -340.797887) (xy 353.03752 -340.712388)
			(xy 353.019684 -340.624655) (xy 353.010745 -340.535574) (xy 353.010216 -340.49081) (xy 353.01072 -340.448462)
			(xy 353.018771 -340.364148) (xy 353.0348 -340.280982) (xy 353.058661 -340.199715) (xy 353.09014 -340.121085)
			(xy 353.128951 -340.045804) (xy 353.174741 -339.974552) (xy 353.227097 -339.907976) (xy 353.285545 -339.846678)
			(xy 353.349555 -339.791213) (xy 353.418547 -339.742084) (xy 353.491897 -339.699735) (xy 353.56894 -339.664551)
			(xy 353.648979 -339.636849) (xy 353.731288 -339.616881) (xy 353.815123 -339.604828) (xy 353.899724 -339.600798)
			(xy 353.984325 -339.604828) (xy 354.06816 -339.616881) (xy 354.150469 -339.636849) (xy 354.230508 -339.664551)
			(xy 354.307551 -339.699735) (xy 354.380901 -339.742084) (xy 354.449893 -339.791213) (xy 354.513903 -339.846678)
			(xy 354.572351 -339.907976) (xy 354.624707 -339.974552) (xy 354.670497 -340.045804) (xy 354.709308 -340.121085)
			(xy 354.740787 -340.199715) (xy 354.764648 -340.280982) (xy 354.780677 -340.364148) (xy 354.788728 -340.448462)
			(xy 354.789232 -340.49081) (xy 354.788708 -340.535575) (xy 354.779777 -340.624657) (xy 354.761937 -340.712389)
			(xy 354.735368 -340.797885) (xy 354.718366 -340.839298) (xy 354.714795 -340.848887) (xy 354.714799 -340.869331)
			(xy 354.718366 -340.878922) (xy 354.735345 -340.920344) (xy 354.761907 -341.005839) (xy 354.779752 -341.093569)
			(xy 354.788699 -341.182647) (xy 354.789232 -341.22741) (xy 354.789232 -341.228172) (xy 354.789643 -341.238195)
			(xy 354.79731 -341.256718) (xy 354.811486 -341.270892) (xy 354.830009 -341.278557) (xy 354.840032 -341.278972)
			(xy 354.847906 -341.278972) (xy 354.862638 -341.2744) (xy 354.869242 -341.269828) (xy 354.906551 -341.244594)
			(xy 354.985338 -341.200935) (xy 355.068135 -341.165465) (xy 355.154094 -341.138546) (xy 355.242334 -341.120456)
			(xy 355.33195 -341.111378) (xy 355.376988 -341.110824) (xy 355.418092 -341.111264) (xy 355.499949 -341.118848)
			(xy 355.580757 -341.133953) (xy 355.659827 -341.15645) (xy 355.736484 -341.186147) (xy 355.810073 -341.22279)
			(xy 355.879967 -341.266067) (xy 355.94557 -341.315609) (xy 356.006322 -341.370992) (xy 356.061704 -341.431745)
			(xy 356.111244 -341.497349) (xy 356.15452 -341.567245) (xy 356.191162 -341.640835) (xy 356.220857 -341.717492)
			(xy 356.243352 -341.796562) (xy 356.258455 -341.877371) (xy 356.266037 -341.959228) (xy 356.266496 -342.000332)
			(xy 356.265974 -342.045097) (xy 356.257042 -342.134178) (xy 356.239201 -342.221911) (xy 356.212632 -342.307407)
			(xy 356.19563 -342.34882) (xy 356.192048 -342.358406) (xy 356.19206 -342.378853) (xy 356.19563 -342.388444)
			(xy 356.212619 -342.429862) (xy 356.239178 -342.515358) (xy 356.25702 -342.603089) (xy 356.265964 -342.692168)
			(xy 356.266496 -342.736932) (xy 356.265974 -342.781697) (xy 356.257042 -342.870778) (xy 356.239201 -342.958511)
			(xy 356.212632 -343.044007) (xy 356.19563 -343.08542) (xy 356.192048 -343.095006) (xy 356.19206 -343.115453)
			(xy 356.19563 -343.125044) (xy 356.212619 -343.166462) (xy 356.239178 -343.251958) (xy 356.25702 -343.339689)
			(xy 356.265964 -343.428768) (xy 356.266496 -343.473532) (xy 356.266064 -343.514635) (xy 356.258476 -343.596491)
			(xy 356.243368 -343.677298) (xy 356.220868 -343.756366) (xy 356.191169 -343.83302) (xy 356.154525 -343.906608)
			(xy 356.111246 -343.9765) (xy 356.061704 -344.042101) (xy 356.00632 -344.102851) (xy 355.945567 -344.158232)
			(xy 355.879964 -344.207771) (xy 355.810069 -344.251046) (xy 355.73648 -344.287687) (xy 355.659824 -344.317382)
			(xy 355.580755 -344.339878) (xy 355.499948 -344.354982) (xy 355.418091 -344.362566) (xy 355.376988 -344.36304)
			(xy 355.335375 -344.362595) (xy 355.252512 -344.354841) (xy 355.170737 -344.339375) (xy 355.090766 -344.316332)
			(xy 355.013299 -344.285913) (xy 354.939015 -344.248385) (xy 354.903532 -344.226642) (xy 354.894412 -344.221554)
			(xy 354.873772 -344.218501) (xy 354.853611 -344.223873) (xy 354.845112 -344.229944) (xy 354.811434 -344.255887)
			(xy 354.739995 -344.301979) (xy 354.664485 -344.341047) (xy 354.585593 -344.372734) (xy 354.504038 -344.396752)
			(xy 354.420565 -344.41288) (xy 354.335933 -344.420973) (xy 354.293424 -344.42146) (xy 354.25232 -344.421025)
			(xy 354.170462 -344.413441) (xy 354.089653 -344.398337) (xy 354.010583 -344.375841) (xy 353.933926 -344.346144)
			(xy 353.860336 -344.309501) (xy 353.790441 -344.266224) (xy 353.724837 -344.216682) (xy 353.664085 -344.161298)
			(xy 353.608703 -344.100544) (xy 353.559163 -344.03494) (xy 353.515887 -343.965043) (xy 353.479246 -343.891453)
			(xy 353.449552 -343.814794) (xy 353.427057 -343.735723) (xy 353.411955 -343.654914) (xy 353.404374 -343.573056)
			(xy 353.403916 -343.531952) (xy 353.404431 -343.487187) (xy 353.413365 -343.398105) (xy 353.431208 -343.310372)
			(xy 353.457779 -343.224877) (xy 353.474782 -343.183464) (xy 353.478372 -343.173881) (xy 353.478354 -343.153431)
			(xy 353.474782 -343.14384) (xy 353.458989 -343.105534) (xy 353.433779 -343.026599) (xy 353.416022 -342.945661)
			(xy 353.405873 -342.863421) (xy 353.40417 -342.822022) (xy 353.403294 -342.811106) (xy 353.39366 -342.791469)
			(xy 353.376758 -342.777587) (xy 353.366324 -342.77427) (xy 353.349452 -342.769771) (xy 353.316041 -342.759609)
			(xy 353.299522 -342.75395) (xy 353.291326 -342.751427) (xy 353.27419 -342.751427) (xy 353.265994 -342.75395)
			(xy 353.230774 -342.765885) (xy 353.158765 -342.784475) (xy 353.085444 -342.796919) (xy 353.011333 -342.803127)
			(xy 352.974148 -342.80348) (xy 352.936964 -342.803098) (xy 352.862857 -342.79688) (xy 352.789537 -342.784441)
			(xy 352.717525 -342.76587) (xy 352.682302 -342.75395) (xy 352.674106 -342.751427) (xy 352.65697 -342.751427)
			(xy 352.648774 -342.75395) (xy 352.613556 -342.765891) (xy 352.541546 -342.784479) (xy 352.468224 -342.796921)
			(xy 352.394113 -342.803127) (xy 352.356928 -342.80348) (xy 352.314999 -342.803074) (xy 352.231522 -342.795106)
			(xy 352.149179 -342.779238) (xy 352.068718 -342.755615) (xy 351.990867 -342.72445) (xy 351.916331 -342.686026)
			(xy 351.845785 -342.640691) (xy 351.779867 -342.588855) (xy 351.719176 -342.530987) (xy 351.66426 -342.467613)
			(xy 351.615617 -342.399306) (xy 351.573688 -342.326683) (xy 351.538852 -342.250404) (xy 351.511424 -342.171159)
			(xy 351.491654 -342.089666) (xy 351.479719 -342.006662) (xy 351.475729 -341.9229) (xy 271.348962 -341.9229)
			(xy 271.348962 -348.7047) (xy 275.231844 -348.7047) (xy 275.235834 -348.620942) (xy 275.247768 -348.537942)
			(xy 275.267537 -348.456452) (xy 275.294962 -348.377211) (xy 275.329796 -348.300935) (xy 275.371722 -348.228316)
			(xy 275.420361 -348.16001) (xy 275.475273 -348.096638) (xy 275.53596 -348.038772) (xy 275.601873 -347.986937)
			(xy 275.672414 -347.941602) (xy 275.746946 -347.903177) (xy 275.824792 -347.872011) (xy 275.905248 -347.848386)
			(xy 275.987586 -347.832515) (xy 276.071059 -347.824543) (xy 276.112986 -347.824044) (xy 276.15017 -347.824414)
			(xy 276.224278 -347.830636) (xy 276.297598 -347.843078) (xy 276.369609 -347.861652) (xy 276.404832 -347.873574)
			(xy 276.413028 -347.876097) (xy 276.430164 -347.876097) (xy 276.43836 -347.873574) (xy 276.478965 -347.859871)
			(xy 276.562206 -347.839476) (xy 276.647036 -347.82727) (xy 276.68982 -347.824806) (xy 276.700474 -347.823858)
			(xy 276.719614 -347.814355) (xy 276.733232 -347.797887) (xy 276.736556 -347.787722) (xy 276.744588 -347.759435)
			(xy 276.763907 -347.703889) (xy 276.775164 -347.676724) (xy 276.778721 -347.667131) (xy 276.778725 -347.646691)
			(xy 276.775164 -347.6371) (xy 276.758127 -347.595694) (xy 276.731493 -347.510205) (xy 276.713589 -347.422472)
			(xy 276.704596 -347.333383) (xy 276.704044 -347.288612) (xy 276.704548 -347.246251) (xy 276.712601 -347.161914)
			(xy 276.728635 -347.078724) (xy 276.752503 -346.997434) (xy 276.783991 -346.918782) (xy 276.822813 -346.843479)
			(xy 276.868616 -346.772207) (xy 276.920987 -346.705611) (xy 276.979452 -346.644296) (xy 277.04348 -346.588815)
			(xy 277.112492 -346.539672) (xy 277.185862 -346.497312) (xy 277.262927 -346.462117) (xy 277.342989 -346.434408)
			(xy 277.425322 -346.414434) (xy 277.509181 -346.402377) (xy 277.593806 -346.398346) (xy 277.678431 -346.402377)
			(xy 277.76229 -346.414434) (xy 277.844623 -346.434408) (xy 277.924685 -346.462117) (xy 278.00175 -346.497312)
			(xy 278.07512 -346.539672) (xy 278.144132 -346.588815) (xy 278.20816 -346.644296) (xy 278.266625 -346.705611)
			(xy 278.318996 -346.772207) (xy 278.364799 -346.843479) (xy 278.403621 -346.918782) (xy 278.435109 -346.997434)
			(xy 278.458977 -347.078724) (xy 278.475011 -347.161914) (xy 278.483064 -347.246251) (xy 278.483568 -347.288612)
			(xy 278.482998 -347.333381) (xy 278.47399 -347.422466) (xy 278.456088 -347.510198) (xy 278.42947 -347.595689)
			(xy 278.412448 -347.6371) (xy 278.408877 -347.646689) (xy 278.408882 -347.667133) (xy 278.412448 -347.676724)
			(xy 278.426621 -347.711083) (xy 278.449883 -347.78168) (xy 278.467176 -347.853971) (xy 278.47838 -347.927452)
			(xy 278.481282 -347.964506) (xy 278.482298 -347.978476) (xy 278.497284 -348.000574) (xy 278.600916 -348.051628)
			(xy 278.627586 -348.04985) (xy 278.639016 -348.04223) (xy 278.675617 -348.018437) (xy 278.752639 -347.977332)
			(xy 278.833317 -347.943969) (xy 278.916874 -347.918668) (xy 279.002507 -347.901673) (xy 279.089394 -347.893146)
			(xy 279.133046 -347.892624) (xy 279.174153 -347.893069) (xy 279.256016 -347.900657) (xy 279.336831 -347.915765)
			(xy 279.415907 -347.938263) (xy 279.49257 -347.96796) (xy 279.566167 -348.004602) (xy 279.63607 -348.047877)
			(xy 279.701683 -348.097416) (xy 279.762447 -348.152796) (xy 279.817842 -348.213546) (xy 279.867398 -348.279147)
			(xy 279.91069 -348.349039) (xy 279.947351 -348.422627) (xy 279.977067 -348.499283) (xy 279.999585 -348.578353)
			(xy 280.014712 -348.659164) (xy 280.018945 -348.7047) (xy 283.512244 -348.7047) (xy 283.516234 -348.620942)
			(xy 283.528168 -348.537942) (xy 283.547937 -348.456452) (xy 283.575362 -348.377211) (xy 283.610196 -348.300935)
			(xy 283.652122 -348.228316) (xy 283.700761 -348.16001) (xy 283.755673 -348.096638) (xy 283.81636 -348.038772)
			(xy 283.882273 -347.986937) (xy 283.952814 -347.941602) (xy 284.027346 -347.903177) (xy 284.105192 -347.872011)
			(xy 284.185648 -347.848386) (xy 284.267986 -347.832515) (xy 284.351459 -347.824543) (xy 284.393386 -347.824044)
			(xy 284.43057 -347.824414) (xy 284.504678 -347.830636) (xy 284.577998 -347.843078) (xy 284.650009 -347.861652)
			(xy 284.685232 -347.873574) (xy 284.693428 -347.876097) (xy 284.710564 -347.876097) (xy 284.71876 -347.873574)
			(xy 284.756938 -347.860634) (xy 284.835124 -347.840982) (xy 284.91478 -347.828562) (xy 284.95498 -347.825568)
			(xy 284.965838 -347.82436) (xy 284.985096 -347.814096) (xy 284.99831 -347.79673) (xy 285.001208 -347.786198)
			(xy 285.010486 -347.747118) (xy 285.035162 -347.670674) (xy 285.050484 -347.633544) (xy 285.054028 -347.623948)
			(xy 285.05404 -347.603511) (xy 285.050484 -347.59392) (xy 285.033454 -347.552511) (xy 285.006819 -347.467023)
			(xy 284.988912 -347.379291) (xy 284.979917 -347.290203) (xy 284.979364 -347.245432) (xy 284.979868 -347.203071)
			(xy 284.987921 -347.118734) (xy 285.003955 -347.035544) (xy 285.027823 -346.954254) (xy 285.059311 -346.875602)
			(xy 285.098133 -346.800299) (xy 285.143936 -346.729027) (xy 285.196307 -346.662431) (xy 285.254772 -346.601116)
			(xy 285.3188 -346.545635) (xy 285.387812 -346.496492) (xy 285.461182 -346.454132) (xy 285.538247 -346.418937)
			(xy 285.618309 -346.391228) (xy 285.700642 -346.371254) (xy 285.784501 -346.359197) (xy 285.869126 -346.355166)
			(xy 285.953751 -346.359197) (xy 286.03761 -346.371254) (xy 286.119943 -346.391228) (xy 286.200005 -346.418937)
			(xy 286.27707 -346.454132) (xy 286.35044 -346.496492) (xy 286.419452 -346.545635) (xy 286.48348 -346.601116)
			(xy 286.541945 -346.662431) (xy 286.594316 -346.729027) (xy 286.640119 -346.800299) (xy 286.678941 -346.875602)
			(xy 286.710429 -346.954254) (xy 286.734297 -347.035544) (xy 286.750331 -347.118734) (xy 286.758384 -347.203071)
			(xy 286.758888 -347.245432) (xy 286.758323 -347.290202) (xy 286.749314 -347.379287) (xy 286.73141 -347.467018)
			(xy 286.704791 -347.552509) (xy 286.687768 -347.59392) (xy 286.684185 -347.603505) (xy 286.684197 -347.623953)
			(xy 286.687768 -347.633544) (xy 286.703871 -347.672618) (xy 286.72945 -347.753174) (xy 286.747275 -347.835792)
			(xy 286.757183 -347.919728) (xy 286.758634 -347.961966) (xy 286.758888 -347.97619) (xy 286.773366 -347.999558)
			(xy 286.877506 -348.053406) (xy 286.905192 -348.051882) (xy 286.916876 -348.044008) (xy 286.953598 -348.019927)
			(xy 287.030944 -347.978334) (xy 287.112015 -347.944569) (xy 287.196019 -347.918962) (xy 287.282139 -347.901762)
			(xy 287.369535 -347.893138) (xy 287.413446 -347.892624) (xy 287.454553 -347.893069) (xy 287.536416 -347.900657)
			(xy 287.617231 -347.915765) (xy 287.696307 -347.938263) (xy 287.77297 -347.96796) (xy 287.846567 -348.004602)
			(xy 287.91647 -348.047877) (xy 287.982083 -348.097416) (xy 288.042847 -348.152796) (xy 288.098242 -348.213546)
			(xy 288.147798 -348.279147) (xy 288.19109 -348.349039) (xy 288.227751 -348.422627) (xy 288.257467 -348.499283)
			(xy 288.279985 -348.578353) (xy 288.295112 -348.659164) (xy 288.299345 -348.7047) (xy 291.818044 -348.7047)
			(xy 291.822034 -348.620942) (xy 291.833968 -348.537942) (xy 291.853737 -348.456452) (xy 291.881162 -348.377211)
			(xy 291.915996 -348.300935) (xy 291.957922 -348.228316) (xy 292.006561 -348.16001) (xy 292.061473 -348.096638)
			(xy 292.12216 -348.038772) (xy 292.188073 -347.986937) (xy 292.258614 -347.941602) (xy 292.333146 -347.903177)
			(xy 292.410992 -347.872011) (xy 292.491448 -347.848386) (xy 292.573786 -347.832515) (xy 292.657259 -347.824543)
			(xy 292.699186 -347.824044) (xy 292.73637 -347.824414) (xy 292.810478 -347.830636) (xy 292.883798 -347.843078)
			(xy 292.955809 -347.861652) (xy 292.991032 -347.873574) (xy 292.999228 -347.876097) (xy 293.016364 -347.876097)
			(xy 293.02456 -347.873574) (xy 293.057737 -347.862322) (xy 293.125493 -347.844496) (xy 293.194454 -347.832123)
			(xy 293.229284 -347.828362) (xy 293.240044 -347.82673) (xy 293.258819 -347.815766) (xy 293.271409 -347.798041)
			(xy 293.273988 -347.787468) (xy 293.28351 -347.742121) (xy 293.310744 -347.653548) (xy 293.328344 -347.610684)
			(xy 293.331924 -347.601098) (xy 293.331914 -347.580651) (xy 293.328344 -347.57106) (xy 293.311293 -347.529659)
			(xy 293.284663 -347.444168) (xy 293.266763 -347.356433) (xy 293.257774 -347.267343) (xy 293.257224 -347.222572)
			(xy 293.257728 -347.180211) (xy 293.265781 -347.095874) (xy 293.281815 -347.012684) (xy 293.305683 -346.931394)
			(xy 293.337171 -346.852742) (xy 293.375993 -346.777439) (xy 293.421796 -346.706167) (xy 293.474167 -346.639571)
			(xy 293.532632 -346.578256) (xy 293.59666 -346.522775) (xy 293.665672 -346.473632) (xy 293.739042 -346.431272)
			(xy 293.816107 -346.396077) (xy 293.896169 -346.368368) (xy 293.978502 -346.348394) (xy 294.062361 -346.336337)
			(xy 294.146986 -346.332306) (xy 294.231611 -346.336337) (xy 294.31547 -346.348394) (xy 294.397803 -346.368368)
			(xy 294.477865 -346.396077) (xy 294.55493 -346.431272) (xy 294.6283 -346.473632) (xy 294.697312 -346.522775)
			(xy 294.76134 -346.578256) (xy 294.819805 -346.639571) (xy 294.872176 -346.706167) (xy 294.917979 -346.777439)
			(xy 294.956801 -346.852742) (xy 294.988289 -346.931394) (xy 295.012157 -347.012684) (xy 295.028191 -347.095874)
			(xy 295.036244 -347.180211) (xy 295.036748 -347.222572) (xy 295.036192 -347.267342) (xy 295.027179 -347.356427)
			(xy 295.009272 -347.444158) (xy 294.982652 -347.529649) (xy 294.965628 -347.57106) (xy 294.962081 -347.580656)
			(xy 294.96207 -347.601093) (xy 294.965628 -347.610684) (xy 294.982659 -347.652092) (xy 295.009295 -347.73758)
			(xy 295.0272 -347.825313) (xy 295.036195 -347.914401) (xy 295.036748 -347.959172) (xy 295.036494 -347.977206)
			(xy 295.03624 -347.991938) (xy 295.050718 -348.016322) (xy 295.157144 -348.072202) (xy 295.185592 -348.07017)
			(xy 295.19753 -348.061534) (xy 295.230065 -348.038562) (xy 295.298502 -347.997814) (xy 295.370309 -347.96335)
			(xy 295.444911 -347.935446) (xy 295.521709 -347.914326) (xy 295.600089 -347.900158) (xy 295.679421 -347.893057)
			(xy 295.719246 -347.892624) (xy 295.760353 -347.893069) (xy 295.842216 -347.900657) (xy 295.923031 -347.915765)
			(xy 296.002107 -347.938263) (xy 296.07877 -347.96796) (xy 296.152367 -348.004602) (xy 296.22227 -348.047877)
			(xy 296.287883 -348.097416) (xy 296.348647 -348.152796) (xy 296.404042 -348.213546) (xy 296.453598 -348.279147)
			(xy 296.49689 -348.349039) (xy 296.533551 -348.422627) (xy 296.563267 -348.499283) (xy 296.585785 -348.578353)
			(xy 296.600912 -348.659164) (xy 296.605145 -348.7047) (xy 300.174644 -348.7047) (xy 300.178634 -348.620942)
			(xy 300.190568 -348.537942) (xy 300.210337 -348.456452) (xy 300.237762 -348.377211) (xy 300.272596 -348.300935)
			(xy 300.314522 -348.228316) (xy 300.363161 -348.16001) (xy 300.418073 -348.096638) (xy 300.47876 -348.038772)
			(xy 300.544673 -347.986937) (xy 300.615214 -347.941602) (xy 300.689746 -347.903177) (xy 300.767592 -347.872011)
			(xy 300.848048 -347.848386) (xy 300.930386 -347.832515) (xy 301.013859 -347.824543) (xy 301.055786 -347.824044)
			(xy 301.09297 -347.824414) (xy 301.167078 -347.830636) (xy 301.240398 -347.843078) (xy 301.312409 -347.861652)
			(xy 301.347632 -347.873574) (xy 301.355828 -347.876097) (xy 301.372964 -347.876097) (xy 301.38116 -347.873574)
			(xy 301.419296 -347.860641) (xy 301.497398 -347.840993) (xy 301.576968 -347.828568) (xy 301.617126 -347.825568)
			(xy 301.627815 -347.824425) (xy 301.646831 -347.814441) (xy 301.660064 -347.797526) (xy 301.6631 -347.787214)
			(xy 301.671959 -347.753143) (xy 301.694335 -347.686389) (xy 301.707804 -347.653864) (xy 301.711398 -347.644282)
			(xy 301.71138 -347.623831) (xy 301.707804 -347.61424) (xy 301.690776 -347.57283) (xy 301.66414 -347.487343)
			(xy 301.646234 -347.39961) (xy 301.637237 -347.310523) (xy 301.636684 -347.265752) (xy 301.637188 -347.223391)
			(xy 301.645241 -347.139054) (xy 301.661275 -347.055864) (xy 301.685143 -346.974574) (xy 301.716631 -346.895922)
			(xy 301.755453 -346.820619) (xy 301.801256 -346.749347) (xy 301.853627 -346.682751) (xy 301.912092 -346.621436)
			(xy 301.97612 -346.565955) (xy 302.045132 -346.516812) (xy 302.118502 -346.474452) (xy 302.195567 -346.439257)
			(xy 302.275629 -346.411548) (xy 302.357962 -346.391574) (xy 302.441821 -346.379517) (xy 302.526446 -346.375486)
			(xy 302.611071 -346.379517) (xy 302.69493 -346.391574) (xy 302.777263 -346.411548) (xy 302.857325 -346.439257)
			(xy 302.93439 -346.474452) (xy 303.00776 -346.516812) (xy 303.076772 -346.565955) (xy 303.1408 -346.621436)
			(xy 303.199265 -346.682751) (xy 303.251636 -346.749347) (xy 303.297439 -346.820619) (xy 303.336261 -346.895922)
			(xy 303.367749 -346.974574) (xy 303.391617 -347.055864) (xy 303.407651 -347.139054) (xy 303.415704 -347.223391)
			(xy 303.416208 -347.265752) (xy 303.415649 -347.310522) (xy 303.406637 -347.399607) (xy 303.388731 -347.487338)
			(xy 303.362111 -347.572829) (xy 303.345088 -347.61424) (xy 303.341549 -347.623838) (xy 303.341532 -347.644274)
			(xy 303.345088 -347.653864) (xy 303.36051 -347.691224) (xy 303.385289 -347.768163) (xy 303.402976 -347.847034)
			(xy 303.413426 -347.927187) (xy 303.415446 -347.967554) (xy 303.415954 -347.981524) (xy 303.43094 -348.004638)
			(xy 303.53508 -348.057216) (xy 303.562766 -348.055184) (xy 303.574196 -348.04731) (xy 303.611191 -348.022724)
			(xy 303.68921 -347.980246) (xy 303.771072 -347.945749) (xy 303.855962 -347.919575) (xy 303.943036 -347.901984)
			(xy 304.031429 -347.893153) (xy 304.075846 -347.892624) (xy 304.116953 -347.893069) (xy 304.198816 -347.900657)
			(xy 304.279631 -347.915765) (xy 304.358707 -347.938263) (xy 304.43537 -347.96796) (xy 304.508967 -348.004602)
			(xy 304.57887 -348.047877) (xy 304.644483 -348.097416) (xy 304.705247 -348.152796) (xy 304.760642 -348.213546)
			(xy 304.810198 -348.279147) (xy 304.85349 -348.349039) (xy 304.890151 -348.422627) (xy 304.919867 -348.499283)
			(xy 304.942385 -348.578353) (xy 304.957512 -348.659164) (xy 304.961745 -348.7047) (xy 308.505844 -348.7047)
			(xy 308.509834 -348.620942) (xy 308.521768 -348.537942) (xy 308.541537 -348.456452) (xy 308.568962 -348.377211)
			(xy 308.603796 -348.300935) (xy 308.645722 -348.228316) (xy 308.694361 -348.16001) (xy 308.749273 -348.096638)
			(xy 308.80996 -348.038772) (xy 308.875873 -347.986937) (xy 308.946414 -347.941602) (xy 309.020946 -347.903177)
			(xy 309.098792 -347.872011) (xy 309.179248 -347.848386) (xy 309.261586 -347.832515) (xy 309.345059 -347.824543)
			(xy 309.386986 -347.824044) (xy 309.42417 -347.824414) (xy 309.498278 -347.830636) (xy 309.571598 -347.843078)
			(xy 309.643609 -347.861652) (xy 309.678832 -347.873574) (xy 309.687028 -347.876097) (xy 309.704164 -347.876097)
			(xy 309.71236 -347.873574) (xy 309.752042 -347.860186) (xy 309.833344 -347.840073) (xy 309.916186 -347.827757)
			(xy 309.957978 -347.82506) (xy 309.968788 -347.824034) (xy 309.988074 -347.814091) (xy 310.00157 -347.797101)
			(xy 310.004714 -347.786706) (xy 310.013526 -347.752769) (xy 310.03578 -347.686272) (xy 310.049164 -347.653864)
			(xy 310.052755 -347.644281) (xy 310.052737 -347.623831) (xy 310.049164 -347.61424) (xy 310.03214 -347.572829)
			(xy 310.005503 -347.487342) (xy 309.987595 -347.39961) (xy 309.978598 -347.310522) (xy 309.978044 -347.265752)
			(xy 309.978548 -347.223391) (xy 309.986601 -347.139054) (xy 310.002635 -347.055864) (xy 310.026503 -346.974574)
			(xy 310.057991 -346.895922) (xy 310.096813 -346.820619) (xy 310.142616 -346.749347) (xy 310.194987 -346.682751)
			(xy 310.253452 -346.621436) (xy 310.31748 -346.565955) (xy 310.386492 -346.516812) (xy 310.459862 -346.474452)
			(xy 310.536927 -346.439257) (xy 310.616989 -346.411548) (xy 310.699322 -346.391574) (xy 310.783181 -346.379517)
			(xy 310.867806 -346.375486) (xy 310.952431 -346.379517) (xy 311.03629 -346.391574) (xy 311.118623 -346.411548)
			(xy 311.198685 -346.439257) (xy 311.27575 -346.474452) (xy 311.34912 -346.516812) (xy 311.418132 -346.565955)
			(xy 311.48216 -346.621436) (xy 311.540625 -346.682751) (xy 311.592996 -346.749347) (xy 311.638799 -346.820619)
			(xy 311.677621 -346.895922) (xy 311.709109 -346.974574) (xy 311.732977 -347.055864) (xy 311.749011 -347.139054)
			(xy 311.757064 -347.223391) (xy 311.757568 -347.265752) (xy 311.757012 -347.310522) (xy 311.748 -347.399607)
			(xy 311.730093 -347.487338) (xy 311.703472 -347.572829) (xy 311.686448 -347.61424) (xy 311.682911 -347.623839)
			(xy 311.682894 -347.644274) (xy 311.686448 -347.653864) (xy 311.701578 -347.690518) (xy 311.725997 -347.765967)
			(xy 311.743615 -347.843288) (xy 311.754293 -347.921869) (xy 311.756552 -347.961458) (xy 311.75706 -347.975428)
			(xy 311.771792 -347.998288) (xy 311.875424 -348.050866) (xy 311.902602 -348.049088) (xy 311.914286 -348.041468)
			(xy 311.950816 -348.017793) (xy 312.027663 -347.976887) (xy 312.10814 -347.94369) (xy 312.191477 -347.918518)
			(xy 312.276876 -347.901613) (xy 312.363518 -347.893137) (xy 312.407046 -347.892624) (xy 312.448153 -347.893069)
			(xy 312.530016 -347.900657) (xy 312.610831 -347.915765) (xy 312.689907 -347.938263) (xy 312.76657 -347.96796)
			(xy 312.840167 -348.004602) (xy 312.91007 -348.047877) (xy 312.975683 -348.097416) (xy 313.036447 -348.152796)
			(xy 313.091842 -348.213546) (xy 313.141398 -348.279147) (xy 313.18469 -348.349039) (xy 313.221351 -348.422627)
			(xy 313.251067 -348.499283) (xy 313.273585 -348.578353) (xy 313.288712 -348.659164) (xy 313.296321 -348.741025)
			(xy 313.296808 -348.782132) (xy 313.296242 -348.826902) (xy 313.287233 -348.915987) (xy 313.269329 -349.003718)
			(xy 313.242711 -349.089209) (xy 313.225688 -349.13062) (xy 313.222104 -349.140205) (xy 313.222115 -349.160653)
			(xy 313.225688 -349.170244) (xy 313.242711 -349.211656) (xy 313.269347 -349.297143) (xy 313.287256 -349.384874)
			(xy 313.291976 -349.43161) (xy 326.552821 -349.43161) (xy 326.556826 -349.325861) (xy 326.568816 -349.220718)
			(xy 326.588725 -349.116783) (xy 326.616436 -349.014651) (xy 326.651793 -348.914907) (xy 326.694591 -348.818123)
			(xy 326.744587 -348.724853) (xy 326.801494 -348.635632) (xy 326.864985 -348.550969) (xy 326.934697 -348.471351)
			(xy 327.010231 -348.397233) (xy 327.091154 -348.32904) (xy 327.177003 -348.267162) (xy 327.267286 -348.211955)
			(xy 327.361485 -348.163733) (xy 327.459062 -348.122773) (xy 327.559457 -348.089311) (xy 327.662095 -348.063537)
			(xy 327.766388 -348.045599) (xy 327.871739 -348.0356) (xy 327.977545 -348.033597) (xy 328.083199 -348.039602)
			(xy 328.188096 -348.053581) (xy 328.291636 -348.075452) (xy 328.393225 -348.105092) (xy 328.492282 -348.14233)
			(xy 328.588239 -348.186952) (xy 328.680546 -348.238704) (xy 328.768675 -348.297289) (xy 328.852121 -348.362371)
			(xy 328.930405 -348.433577) (xy 329.00308 -348.5105) (xy 329.06973 -348.5927) (xy 329.129972 -348.679704)
			(xy 329.183461 -348.771015) (xy 329.229892 -348.86611) (xy 329.268997 -348.964444) (xy 329.300554 -349.065455)
			(xy 329.324381 -349.168562) (xy 329.340342 -349.273176) (xy 329.348346 -349.378698) (xy 329.348846 -349.43161)
			(xy 334.012801 -349.43161) (xy 334.016806 -349.325861) (xy 334.028796 -349.220718) (xy 334.048705 -349.116783)
			(xy 334.076416 -349.014651) (xy 334.111773 -348.914907) (xy 334.154571 -348.818123) (xy 334.204567 -348.724853)
			(xy 334.261474 -348.635632) (xy 334.324965 -348.550969) (xy 334.394677 -348.471351) (xy 334.470211 -348.397233)
			(xy 334.551134 -348.32904) (xy 334.636983 -348.267162) (xy 334.727266 -348.211955) (xy 334.821465 -348.163733)
			(xy 334.919042 -348.122773) (xy 335.019437 -348.089311) (xy 335.122075 -348.063537) (xy 335.226368 -348.045599)
			(xy 335.331719 -348.0356) (xy 335.437525 -348.033597) (xy 335.543179 -348.039602) (xy 335.648076 -348.053581)
			(xy 335.751616 -348.075452) (xy 335.853205 -348.105092) (xy 335.952262 -348.14233) (xy 336.048219 -348.186952)
			(xy 336.140526 -348.238704) (xy 336.228655 -348.297289) (xy 336.312101 -348.362371) (xy 336.390385 -348.433577)
			(xy 336.46306 -348.5105) (xy 336.52971 -348.5927) (xy 336.589952 -348.679704) (xy 336.643441 -348.771015)
			(xy 336.689872 -348.86611) (xy 336.728977 -348.964444) (xy 336.760534 -349.065455) (xy 336.784361 -349.168562)
			(xy 336.800322 -349.273176) (xy 336.808326 -349.378698) (xy 336.808826 -349.43161) (xy 336.808326 -349.484522)
			(xy 336.800322 -349.590044) (xy 336.784361 -349.694658) (xy 336.760534 -349.797765) (xy 336.728977 -349.898776)
			(xy 336.689872 -349.99711) (xy 336.643441 -350.092205) (xy 336.589952 -350.183516) (xy 336.52971 -350.27052)
			(xy 336.46306 -350.35272) (xy 336.390385 -350.429643) (xy 336.312101 -350.500849) (xy 336.228655 -350.565931)
			(xy 336.140526 -350.624516) (xy 336.048219 -350.676268) (xy 335.952262 -350.72089) (xy 335.853205 -350.758128)
			(xy 335.751616 -350.787768) (xy 335.648076 -350.809639) (xy 335.543179 -350.823618) (xy 335.437525 -350.829623)
			(xy 335.331719 -350.82762) (xy 335.226368 -350.817621) (xy 335.122075 -350.799683) (xy 335.019437 -350.773909)
			(xy 334.919042 -350.740447) (xy 334.821465 -350.699487) (xy 334.727266 -350.651265) (xy 334.636983 -350.596058)
			(xy 334.551134 -350.53418) (xy 334.470211 -350.465987) (xy 334.394677 -350.391869) (xy 334.324965 -350.312251)
			(xy 334.261474 -350.227588) (xy 334.204567 -350.138367) (xy 334.154571 -350.045097) (xy 334.111773 -349.948313)
			(xy 334.076416 -349.848569) (xy 334.048705 -349.746437) (xy 334.028796 -349.642502) (xy 334.016806 -349.537359)
			(xy 334.012801 -349.43161) (xy 329.348846 -349.43161) (xy 329.348346 -349.484522) (xy 329.340342 -349.590044)
			(xy 329.324381 -349.694658) (xy 329.300554 -349.797765) (xy 329.268997 -349.898776) (xy 329.229892 -349.99711)
			(xy 329.183461 -350.092205) (xy 329.129972 -350.183516) (xy 329.06973 -350.27052) (xy 329.00308 -350.35272)
			(xy 328.930405 -350.429643) (xy 328.852121 -350.500849) (xy 328.768675 -350.565931) (xy 328.680546 -350.624516)
			(xy 328.588239 -350.676268) (xy 328.492282 -350.72089) (xy 328.393225 -350.758128) (xy 328.291636 -350.787768)
			(xy 328.188096 -350.809639) (xy 328.083199 -350.823618) (xy 327.977545 -350.829623) (xy 327.871739 -350.82762)
			(xy 327.766388 -350.817621) (xy 327.662095 -350.799683) (xy 327.559457 -350.773909) (xy 327.459062 -350.740447)
			(xy 327.361485 -350.699487) (xy 327.267286 -350.651265) (xy 327.177003 -350.596058) (xy 327.091154 -350.53418)
			(xy 327.010231 -350.465987) (xy 326.934697 -350.391869) (xy 326.864985 -350.312251) (xy 326.801494 -350.227588)
			(xy 326.744587 -350.138367) (xy 326.694591 -350.045097) (xy 326.651793 -349.948313) (xy 326.616436 -349.848569)
			(xy 326.588725 -349.746437) (xy 326.568816 -349.642502) (xy 326.556826 -349.537359) (xy 326.552821 -349.43161)
			(xy 313.291976 -349.43161) (xy 313.296254 -349.473962) (xy 313.296808 -349.518732) (xy 313.296242 -349.563502)
			(xy 313.287233 -349.652587) (xy 313.269329 -349.740318) (xy 313.242711 -349.825809) (xy 313.225688 -349.86722)
			(xy 313.222104 -349.876805) (xy 313.222115 -349.897253) (xy 313.225688 -349.906844) (xy 313.242711 -349.948256)
			(xy 313.269347 -350.033743) (xy 313.287256 -350.121474) (xy 313.296254 -350.210562) (xy 313.296808 -350.255332)
			(xy 313.296378 -350.296443) (xy 313.288787 -350.378314) (xy 313.273674 -350.459136) (xy 313.251166 -350.538217)
			(xy 313.221457 -350.614885) (xy 313.184799 -350.688483) (xy 313.141506 -350.758385) (xy 313.091947 -350.823993)
			(xy 313.036545 -350.884747) (xy 312.975772 -350.94013) (xy 312.910148 -350.989668) (xy 312.840233 -351.032938)
			(xy 312.766623 -351.069572) (xy 312.689946 -351.099257) (xy 312.610857 -351.121739) (xy 312.530031 -351.136827)
			(xy 312.448157 -351.144391) (xy 312.407046 -351.14484) (xy 312.365434 -351.144367) (xy 312.282572 -351.136619)
			(xy 312.200797 -351.121158) (xy 312.120826 -351.09812) (xy 312.043359 -351.067706) (xy 311.969074 -351.030183)
			(xy 311.93359 -351.008442) (xy 311.924446 -351.003405) (xy 311.903822 -351.000334) (xy 311.883669 -351.005685)
			(xy 311.87517 -351.011744) (xy 311.841506 -351.037707) (xy 311.770065 -351.083797) (xy 311.694552 -351.122862)
			(xy 311.615658 -351.154546) (xy 311.534101 -351.178561) (xy 311.450625 -351.194686) (xy 311.365992 -351.202775)
			(xy 311.323482 -351.20326) (xy 311.282375 -351.202805) (xy 311.200511 -351.195219) (xy 311.119697 -351.180113)
			(xy 311.04062 -351.157617) (xy 310.963956 -351.127921) (xy 310.890359 -351.09128) (xy 310.820455 -351.048006)
			(xy 310.754841 -350.998468) (xy 310.694077 -350.943088) (xy 310.638682 -350.882339) (xy 310.589126 -350.816738)
			(xy 310.545833 -350.746846) (xy 310.509173 -350.673258) (xy 310.479458 -350.596602) (xy 310.456941 -350.517531)
			(xy 310.441814 -350.43672) (xy 310.434206 -350.354859) (xy 310.43372 -350.313752) (xy 310.434279 -350.268982)
			(xy 310.44329 -350.179897) (xy 310.461196 -350.092166) (xy 310.487816 -350.006675) (xy 310.50484 -349.965264)
			(xy 310.508432 -349.955681) (xy 310.508415 -349.935231) (xy 310.50484 -349.92564) (xy 310.489045 -349.887334)
			(xy 310.463835 -349.808399) (xy 310.446079 -349.727461) (xy 310.435931 -349.645221) (xy 310.434228 -349.603822)
			(xy 310.433382 -349.592901) (xy 310.423739 -349.57326) (xy 310.406823 -349.559381) (xy 310.396382 -349.55607)
			(xy 310.379509 -349.551574) (xy 310.346099 -349.54141) (xy 310.32958 -349.53575) (xy 310.321384 -349.533227)
			(xy 310.304248 -349.533227) (xy 310.296052 -349.53575) (xy 310.260836 -349.547697) (xy 310.188826 -349.566284)
			(xy 310.115503 -349.578724) (xy 310.041392 -349.584928) (xy 310.004206 -349.58528) (xy 309.967022 -349.584911)
			(xy 309.892914 -349.578689) (xy 309.819594 -349.566246) (xy 309.747583 -349.547672) (xy 309.71236 -349.53575)
			(xy 309.704164 -349.533227) (xy 309.687028 -349.533227) (xy 309.678832 -349.53575) (xy 309.643609 -349.547675)
			(xy 309.571601 -349.566268) (xy 309.498281 -349.578714) (xy 309.424171 -349.584925) (xy 309.386986 -349.58528)
			(xy 309.345059 -349.584857) (xy 309.261586 -349.576885) (xy 309.179248 -349.561014) (xy 309.098792 -349.537389)
			(xy 309.020946 -349.506223) (xy 308.946414 -349.467798) (xy 308.875873 -349.422463) (xy 308.80996 -349.370628)
			(xy 308.749273 -349.312762) (xy 308.694361 -349.24939) (xy 308.645722 -349.181084) (xy 308.603796 -349.108465)
			(xy 308.568962 -349.032189) (xy 308.541537 -348.952948) (xy 308.521768 -348.871458) (xy 308.509834 -348.788458)
			(xy 308.505844 -348.7047) (xy 304.961745 -348.7047) (xy 304.965121 -348.741025) (xy 304.965608 -348.782132)
			(xy 304.965042 -348.826902) (xy 304.956033 -348.915987) (xy 304.938129 -349.003718) (xy 304.911511 -349.089209)
			(xy 304.894488 -349.13062) (xy 304.890904 -349.140205) (xy 304.890915 -349.160653) (xy 304.894488 -349.170244)
			(xy 304.911511 -349.211656) (xy 304.938147 -349.297143) (xy 304.956056 -349.384874) (xy 304.965054 -349.473962)
			(xy 304.965608 -349.518732) (xy 304.965042 -349.563502) (xy 304.956033 -349.652587) (xy 304.938129 -349.740318)
			(xy 304.911511 -349.825809) (xy 304.894488 -349.86722) (xy 304.890904 -349.876805) (xy 304.890915 -349.897253)
			(xy 304.894488 -349.906844) (xy 304.911511 -349.948256) (xy 304.938147 -350.033743) (xy 304.956056 -350.121474)
			(xy 304.965054 -350.210562) (xy 304.965608 -350.255332) (xy 304.965178 -350.296443) (xy 304.957587 -350.378314)
			(xy 304.942474 -350.459136) (xy 304.919966 -350.538217) (xy 304.890257 -350.614885) (xy 304.853599 -350.688483)
			(xy 304.810306 -350.758385) (xy 304.760747 -350.823993) (xy 304.705345 -350.884747) (xy 304.644572 -350.94013)
			(xy 304.578948 -350.989668) (xy 304.509033 -351.032938) (xy 304.435423 -351.069572) (xy 304.358746 -351.099257)
			(xy 304.279657 -351.121739) (xy 304.198831 -351.136827) (xy 304.116957 -351.144391) (xy 304.075846 -351.14484)
			(xy 304.034234 -351.144367) (xy 303.951372 -351.136619) (xy 303.869597 -351.121158) (xy 303.789626 -351.09812)
			(xy 303.712159 -351.067706) (xy 303.637874 -351.030183) (xy 303.60239 -351.008442) (xy 303.593246 -351.003405)
			(xy 303.572622 -351.000334) (xy 303.552469 -351.005685) (xy 303.54397 -351.011744) (xy 303.510306 -351.037707)
			(xy 303.438865 -351.083797) (xy 303.363352 -351.122862) (xy 303.284458 -351.154546) (xy 303.202901 -351.178561)
			(xy 303.119425 -351.194686) (xy 303.034792 -351.202775) (xy 302.992282 -351.20326) (xy 302.951175 -351.202805)
			(xy 302.869311 -351.195219) (xy 302.788497 -351.180113) (xy 302.70942 -351.157617) (xy 302.632756 -351.127921)
			(xy 302.559159 -351.09128) (xy 302.489255 -351.048006) (xy 302.423641 -350.998468) (xy 302.362877 -350.943088)
			(xy 302.307482 -350.882339) (xy 302.257926 -350.816738) (xy 302.214633 -350.746846) (xy 302.177973 -350.673258)
			(xy 302.148258 -350.596602) (xy 302.125741 -350.517531) (xy 302.110614 -350.43672) (xy 302.103006 -350.354859)
			(xy 302.10252 -350.313752) (xy 302.103079 -350.268982) (xy 302.11209 -350.179897) (xy 302.129996 -350.092166)
			(xy 302.156616 -350.006675) (xy 302.17364 -349.965264) (xy 302.177232 -349.955681) (xy 302.177215 -349.935231)
			(xy 302.17364 -349.92564) (xy 302.157845 -349.887334) (xy 302.132635 -349.808399) (xy 302.114879 -349.727461)
			(xy 302.104731 -349.645221) (xy 302.103028 -349.603822) (xy 302.102182 -349.592901) (xy 302.092539 -349.57326)
			(xy 302.075623 -349.559381) (xy 302.065182 -349.55607) (xy 302.048309 -349.551574) (xy 302.014899 -349.54141)
			(xy 301.99838 -349.53575) (xy 301.990184 -349.533227) (xy 301.973048 -349.533227) (xy 301.964852 -349.53575)
			(xy 301.929636 -349.547697) (xy 301.857626 -349.566284) (xy 301.784303 -349.578724) (xy 301.710192 -349.584928)
			(xy 301.673006 -349.58528) (xy 301.635822 -349.584911) (xy 301.561714 -349.578689) (xy 301.488394 -349.566246)
			(xy 301.416383 -349.547672) (xy 301.38116 -349.53575) (xy 301.372964 -349.533227) (xy 301.355828 -349.533227)
			(xy 301.347632 -349.53575) (xy 301.312409 -349.547675) (xy 301.240401 -349.566268) (xy 301.167081 -349.578714)
			(xy 301.092971 -349.584925) (xy 301.055786 -349.58528) (xy 301.013859 -349.584857) (xy 300.930386 -349.576885)
			(xy 300.848048 -349.561014) (xy 300.767592 -349.537389) (xy 300.689746 -349.506223) (xy 300.615214 -349.467798)
			(xy 300.544673 -349.422463) (xy 300.47876 -349.370628) (xy 300.418073 -349.312762) (xy 300.363161 -349.24939)
			(xy 300.314522 -349.181084) (xy 300.272596 -349.108465) (xy 300.237762 -349.032189) (xy 300.210337 -348.952948)
			(xy 300.190568 -348.871458) (xy 300.178634 -348.788458) (xy 300.174644 -348.7047) (xy 296.605145 -348.7047)
			(xy 296.608521 -348.741025) (xy 296.609008 -348.782132) (xy 296.608442 -348.826902) (xy 296.599433 -348.915987)
			(xy 296.581529 -349.003718) (xy 296.554911 -349.089209) (xy 296.537888 -349.13062) (xy 296.534304 -349.140205)
			(xy 296.534315 -349.160653) (xy 296.537888 -349.170244) (xy 296.554911 -349.211656) (xy 296.581547 -349.297143)
			(xy 296.599456 -349.384874) (xy 296.608454 -349.473962) (xy 296.609008 -349.518732) (xy 296.608442 -349.563502)
			(xy 296.599433 -349.652587) (xy 296.581529 -349.740318) (xy 296.554911 -349.825809) (xy 296.537888 -349.86722)
			(xy 296.534304 -349.876805) (xy 296.534315 -349.897253) (xy 296.537888 -349.906844) (xy 296.554911 -349.948256)
			(xy 296.581547 -350.033743) (xy 296.599456 -350.121474) (xy 296.608454 -350.210562) (xy 296.609008 -350.255332)
			(xy 296.608578 -350.296443) (xy 296.600987 -350.378314) (xy 296.585874 -350.459136) (xy 296.563366 -350.538217)
			(xy 296.533657 -350.614885) (xy 296.496999 -350.688483) (xy 296.453706 -350.758385) (xy 296.404147 -350.823993)
			(xy 296.348745 -350.884747) (xy 296.287972 -350.94013) (xy 296.222348 -350.989668) (xy 296.152433 -351.032938)
			(xy 296.078823 -351.069572) (xy 296.002146 -351.099257) (xy 295.923057 -351.121739) (xy 295.842231 -351.136827)
			(xy 295.760357 -351.144391) (xy 295.719246 -351.14484) (xy 295.677634 -351.144367) (xy 295.594772 -351.136619)
			(xy 295.512997 -351.121158) (xy 295.433026 -351.09812) (xy 295.355559 -351.067706) (xy 295.281274 -351.030183)
			(xy 295.24579 -351.008442) (xy 295.236646 -351.003405) (xy 295.216022 -351.000334) (xy 295.195869 -351.005685)
			(xy 295.18737 -351.011744) (xy 295.153706 -351.037707) (xy 295.082265 -351.083797) (xy 295.006752 -351.122862)
			(xy 294.927858 -351.154546) (xy 294.846301 -351.178561) (xy 294.762825 -351.194686) (xy 294.678192 -351.202775)
			(xy 294.635682 -351.20326) (xy 294.594575 -351.202805) (xy 294.512711 -351.195219) (xy 294.431897 -351.180113)
			(xy 294.35282 -351.157617) (xy 294.276156 -351.127921) (xy 294.202559 -351.09128) (xy 294.132655 -351.048006)
			(xy 294.067041 -350.998468) (xy 294.006277 -350.943088) (xy 293.950882 -350.882339) (xy 293.901326 -350.816738)
			(xy 293.858033 -350.746846) (xy 293.821373 -350.673258) (xy 293.791658 -350.596602) (xy 293.769141 -350.517531)
			(xy 293.754014 -350.43672) (xy 293.746406 -350.354859) (xy 293.74592 -350.313752) (xy 293.746479 -350.268982)
			(xy 293.75549 -350.179897) (xy 293.773396 -350.092166) (xy 293.800016 -350.006675) (xy 293.81704 -349.965264)
			(xy 293.820632 -349.955681) (xy 293.820615 -349.935231) (xy 293.81704 -349.92564) (xy 293.801245 -349.887334)
			(xy 293.776035 -349.808399) (xy 293.758279 -349.727461) (xy 293.748131 -349.645221) (xy 293.746428 -349.603822)
			(xy 293.745582 -349.592901) (xy 293.735939 -349.57326) (xy 293.719023 -349.559381) (xy 293.708582 -349.55607)
			(xy 293.691709 -349.551574) (xy 293.658299 -349.54141) (xy 293.64178 -349.53575) (xy 293.633584 -349.533227)
			(xy 293.616448 -349.533227) (xy 293.608252 -349.53575) (xy 293.573036 -349.547697) (xy 293.501026 -349.566284)
			(xy 293.427703 -349.578724) (xy 293.353592 -349.584928) (xy 293.316406 -349.58528) (xy 293.279222 -349.584911)
			(xy 293.205114 -349.578689) (xy 293.131794 -349.566246) (xy 293.059783 -349.547672) (xy 293.02456 -349.53575)
			(xy 293.016364 -349.533227) (xy 292.999228 -349.533227) (xy 292.991032 -349.53575) (xy 292.955809 -349.547675)
			(xy 292.883801 -349.566268) (xy 292.810481 -349.578714) (xy 292.736371 -349.584925) (xy 292.699186 -349.58528)
			(xy 292.657259 -349.584857) (xy 292.573786 -349.576885) (xy 292.491448 -349.561014) (xy 292.410992 -349.537389)
			(xy 292.333146 -349.506223) (xy 292.258614 -349.467798) (xy 292.188073 -349.422463) (xy 292.12216 -349.370628)
			(xy 292.061473 -349.312762) (xy 292.006561 -349.24939) (xy 291.957922 -349.181084) (xy 291.915996 -349.108465)
			(xy 291.881162 -349.032189) (xy 291.853737 -348.952948) (xy 291.833968 -348.871458) (xy 291.822034 -348.788458)
			(xy 291.818044 -348.7047) (xy 288.299345 -348.7047) (xy 288.302721 -348.741025) (xy 288.303208 -348.782132)
			(xy 288.302642 -348.826902) (xy 288.293633 -348.915987) (xy 288.275729 -349.003718) (xy 288.249111 -349.089209)
			(xy 288.232088 -349.13062) (xy 288.228504 -349.140205) (xy 288.228515 -349.160653) (xy 288.232088 -349.170244)
			(xy 288.249111 -349.211656) (xy 288.275747 -349.297143) (xy 288.293656 -349.384874) (xy 288.302654 -349.473962)
			(xy 288.303208 -349.518732) (xy 288.302642 -349.563502) (xy 288.293633 -349.652587) (xy 288.275729 -349.740318)
			(xy 288.249111 -349.825809) (xy 288.232088 -349.86722) (xy 288.228504 -349.876805) (xy 288.228515 -349.897253)
			(xy 288.232088 -349.906844) (xy 288.249111 -349.948256) (xy 288.275747 -350.033743) (xy 288.293656 -350.121474)
			(xy 288.302654 -350.210562) (xy 288.303208 -350.255332) (xy 288.302778 -350.296443) (xy 288.295187 -350.378314)
			(xy 288.280074 -350.459136) (xy 288.257566 -350.538217) (xy 288.227857 -350.614885) (xy 288.191199 -350.688483)
			(xy 288.147906 -350.758385) (xy 288.098347 -350.823993) (xy 288.042945 -350.884747) (xy 287.982172 -350.94013)
			(xy 287.916548 -350.989668) (xy 287.846633 -351.032938) (xy 287.773023 -351.069572) (xy 287.696346 -351.099257)
			(xy 287.617257 -351.121739) (xy 287.536431 -351.136827) (xy 287.454557 -351.144391) (xy 287.413446 -351.14484)
			(xy 287.371834 -351.144367) (xy 287.288972 -351.136619) (xy 287.207197 -351.121158) (xy 287.127226 -351.09812)
			(xy 287.049759 -351.067706) (xy 286.975474 -351.030183) (xy 286.93999 -351.008442) (xy 286.930846 -351.003405)
			(xy 286.910222 -351.000334) (xy 286.890069 -351.005685) (xy 286.88157 -351.011744) (xy 286.847906 -351.037707)
			(xy 286.776465 -351.083797) (xy 286.700952 -351.122862) (xy 286.622058 -351.154546) (xy 286.540501 -351.178561)
			(xy 286.457025 -351.194686) (xy 286.372392 -351.202775) (xy 286.329882 -351.20326) (xy 286.288775 -351.202805)
			(xy 286.206911 -351.195219) (xy 286.126097 -351.180113) (xy 286.04702 -351.157617) (xy 285.970356 -351.127921)
			(xy 285.896759 -351.09128) (xy 285.826855 -351.048006) (xy 285.761241 -350.998468) (xy 285.700477 -350.943088)
			(xy 285.645082 -350.882339) (xy 285.595526 -350.816738) (xy 285.552233 -350.746846) (xy 285.515573 -350.673258)
			(xy 285.485858 -350.596602) (xy 285.463341 -350.517531) (xy 285.448214 -350.43672) (xy 285.440606 -350.354859)
			(xy 285.44012 -350.313752) (xy 285.440679 -350.268982) (xy 285.44969 -350.179897) (xy 285.467596 -350.092166)
			(xy 285.494216 -350.006675) (xy 285.51124 -349.965264) (xy 285.514832 -349.955681) (xy 285.514815 -349.935231)
			(xy 285.51124 -349.92564) (xy 285.495445 -349.887334) (xy 285.470235 -349.808399) (xy 285.452479 -349.727461)
			(xy 285.442331 -349.645221) (xy 285.440628 -349.603822) (xy 285.439782 -349.592901) (xy 285.430139 -349.57326)
			(xy 285.413223 -349.559381) (xy 285.402782 -349.55607) (xy 285.385909 -349.551574) (xy 285.352499 -349.54141)
			(xy 285.33598 -349.53575) (xy 285.327784 -349.533227) (xy 285.310648 -349.533227) (xy 285.302452 -349.53575)
			(xy 285.267236 -349.547697) (xy 285.195226 -349.566284) (xy 285.121903 -349.578724) (xy 285.047792 -349.584928)
			(xy 285.010606 -349.58528) (xy 284.973422 -349.584911) (xy 284.899314 -349.578689) (xy 284.825994 -349.566246)
			(xy 284.753983 -349.547672) (xy 284.71876 -349.53575) (xy 284.710564 -349.533227) (xy 284.693428 -349.533227)
			(xy 284.685232 -349.53575) (xy 284.650009 -349.547675) (xy 284.578001 -349.566268) (xy 284.504681 -349.578714)
			(xy 284.430571 -349.584925) (xy 284.393386 -349.58528) (xy 284.351459 -349.584857) (xy 284.267986 -349.576885)
			(xy 284.185648 -349.561014) (xy 284.105192 -349.537389) (xy 284.027346 -349.506223) (xy 283.952814 -349.467798)
			(xy 283.882273 -349.422463) (xy 283.81636 -349.370628) (xy 283.755673 -349.312762) (xy 283.700761 -349.24939)
			(xy 283.652122 -349.181084) (xy 283.610196 -349.108465) (xy 283.575362 -349.032189) (xy 283.547937 -348.952948)
			(xy 283.528168 -348.871458) (xy 283.516234 -348.788458) (xy 283.512244 -348.7047) (xy 280.018945 -348.7047)
			(xy 280.022321 -348.741025) (xy 280.022808 -348.782132) (xy 280.022242 -348.826902) (xy 280.013233 -348.915987)
			(xy 279.995329 -349.003718) (xy 279.968711 -349.089209) (xy 279.951688 -349.13062) (xy 279.948104 -349.140205)
			(xy 279.948115 -349.160653) (xy 279.951688 -349.170244) (xy 279.968711 -349.211656) (xy 279.995347 -349.297143)
			(xy 280.013256 -349.384874) (xy 280.022254 -349.473962) (xy 280.022808 -349.518732) (xy 280.022242 -349.563502)
			(xy 280.013233 -349.652587) (xy 279.995329 -349.740318) (xy 279.968711 -349.825809) (xy 279.951688 -349.86722)
			(xy 279.948104 -349.876805) (xy 279.948115 -349.897253) (xy 279.951688 -349.906844) (xy 279.968711 -349.948256)
			(xy 279.995347 -350.033743) (xy 280.013256 -350.121474) (xy 280.022254 -350.210562) (xy 280.022808 -350.255332)
			(xy 280.022378 -350.296443) (xy 280.014787 -350.378314) (xy 279.999674 -350.459136) (xy 279.977166 -350.538217)
			(xy 279.947457 -350.614885) (xy 279.910799 -350.688483) (xy 279.867506 -350.758385) (xy 279.817947 -350.823993)
			(xy 279.762545 -350.884747) (xy 279.701772 -350.94013) (xy 279.636148 -350.989668) (xy 279.566233 -351.032938)
			(xy 279.492623 -351.069572) (xy 279.415946 -351.099257) (xy 279.336857 -351.121739) (xy 279.256031 -351.136827)
			(xy 279.174157 -351.144391) (xy 279.133046 -351.14484) (xy 279.091434 -351.144367) (xy 279.008572 -351.136619)
			(xy 278.926797 -351.121158) (xy 278.846826 -351.09812) (xy 278.769359 -351.067706) (xy 278.695074 -351.030183)
			(xy 278.65959 -351.008442) (xy 278.650446 -351.003405) (xy 278.629822 -351.000334) (xy 278.609669 -351.005685)
			(xy 278.60117 -351.011744) (xy 278.567506 -351.037707) (xy 278.496065 -351.083797) (xy 278.420552 -351.122862)
			(xy 278.341658 -351.154546) (xy 278.260101 -351.178561) (xy 278.176625 -351.194686) (xy 278.091992 -351.202775)
			(xy 278.049482 -351.20326) (xy 278.008375 -351.202805) (xy 277.926511 -351.195219) (xy 277.845697 -351.180113)
			(xy 277.76662 -351.157617) (xy 277.689956 -351.127921) (xy 277.616359 -351.09128) (xy 277.546455 -351.048006)
			(xy 277.480841 -350.998468) (xy 277.420077 -350.943088) (xy 277.364682 -350.882339) (xy 277.315126 -350.816738)
			(xy 277.271833 -350.746846) (xy 277.235173 -350.673258) (xy 277.205458 -350.596602) (xy 277.182941 -350.517531)
			(xy 277.167814 -350.43672) (xy 277.160206 -350.354859) (xy 277.15972 -350.313752) (xy 277.160279 -350.268982)
			(xy 277.16929 -350.179897) (xy 277.187196 -350.092166) (xy 277.213816 -350.006675) (xy 277.23084 -349.965264)
			(xy 277.234432 -349.955681) (xy 277.234415 -349.935231) (xy 277.23084 -349.92564) (xy 277.215045 -349.887334)
			(xy 277.189835 -349.808399) (xy 277.172079 -349.727461) (xy 277.161931 -349.645221) (xy 277.160228 -349.603822)
			(xy 277.159382 -349.592901) (xy 277.149739 -349.57326) (xy 277.132823 -349.559381) (xy 277.122382 -349.55607)
			(xy 277.105509 -349.551574) (xy 277.072099 -349.54141) (xy 277.05558 -349.53575) (xy 277.047384 -349.533227)
			(xy 277.030248 -349.533227) (xy 277.022052 -349.53575) (xy 276.986836 -349.547697) (xy 276.914826 -349.566284)
			(xy 276.841503 -349.578724) (xy 276.767392 -349.584928) (xy 276.730206 -349.58528) (xy 276.693022 -349.584911)
			(xy 276.618914 -349.578689) (xy 276.545594 -349.566246) (xy 276.473583 -349.547672) (xy 276.43836 -349.53575)
			(xy 276.430164 -349.533227) (xy 276.413028 -349.533227) (xy 276.404832 -349.53575) (xy 276.369609 -349.547675)
			(xy 276.297601 -349.566268) (xy 276.224281 -349.578714) (xy 276.150171 -349.584925) (xy 276.112986 -349.58528)
			(xy 276.071059 -349.584857) (xy 275.987586 -349.576885) (xy 275.905248 -349.561014) (xy 275.824792 -349.537389)
			(xy 275.746946 -349.506223) (xy 275.672414 -349.467798) (xy 275.601873 -349.422463) (xy 275.53596 -349.370628)
			(xy 275.475273 -349.312762) (xy 275.420361 -349.24939) (xy 275.371722 -349.181084) (xy 275.329796 -349.108465)
			(xy 275.294962 -349.032189) (xy 275.267537 -348.952948) (xy 275.247768 -348.871458) (xy 275.235834 -348.788458)
			(xy 275.231844 -348.7047) (xy 271.348962 -348.7047) (xy 271.348962 -352.973132) (xy 338.849208 -352.973132)
			(xy 338.849825 -352.926972) (xy 338.859426 -352.835153) (xy 338.878488 -352.744823) (xy 338.906804 -352.656953)
			(xy 338.9249 -352.614484) (xy 338.928699 -352.60454) (xy 338.928703 -352.583278) (xy 338.9249 -352.573336)
			(xy 338.90688 -352.530918) (xy 338.878719 -352.443158) (xy 338.859786 -352.352956) (xy 338.850284 -352.26128)
			(xy 338.849716 -352.215196) (xy 338.850295 -352.1688) (xy 338.859941 -352.076512) (xy 338.879138 -351.985728)
			(xy 338.907678 -351.897435) (xy 338.925916 -351.85477) (xy 338.929722 -351.844828) (xy 338.929721 -351.823565)
			(xy 338.925916 -351.813622) (xy 338.907671 -351.77096) (xy 338.879127 -351.682667) (xy 338.859934 -351.591882)
			(xy 338.850301 -351.499592) (xy 338.849716 -351.453196) (xy 338.850148 -351.412092) (xy 338.857734 -351.330235)
			(xy 338.87284 -351.249427) (xy 338.895338 -351.170357) (xy 338.925036 -351.093701) (xy 338.96168 -351.020112)
			(xy 339.004958 -350.950218) (xy 339.0545 -350.884616) (xy 339.109884 -350.823864) (xy 339.170637 -350.768482)
			(xy 339.236241 -350.718942) (xy 339.306137 -350.675666) (xy 339.379727 -350.639025) (xy 339.456384 -350.609329)
			(xy 339.535454 -350.586834) (xy 339.616263 -350.57173) (xy 339.69812 -350.564147) (xy 339.739224 -350.563688)
			(xy 339.785619 -350.564298) (xy 339.877906 -350.573935) (xy 339.96869 -350.593123) (xy 340.056984 -350.621654)
			(xy 340.09965 -350.639888) (xy 340.109592 -350.643694) (xy 340.130856 -350.643694) (xy 340.140798 -350.639888)
			(xy 340.183457 -350.621635) (xy 340.27175 -350.593093) (xy 340.362537 -350.573902) (xy 340.454828 -350.564272)
			(xy 340.501224 -350.563688) (xy 340.547619 -350.564298) (xy 340.639906 -350.573935) (xy 340.73069 -350.593123)
			(xy 340.818984 -350.621654) (xy 340.86165 -350.639888) (xy 340.871592 -350.643694) (xy 340.892856 -350.643694)
			(xy 340.902798 -350.639888) (xy 340.945457 -350.621635) (xy 341.03375 -350.593093) (xy 341.124537 -350.573902)
			(xy 341.216828 -350.564272) (xy 341.263224 -350.563688) (xy 341.309619 -350.564298) (xy 341.401906 -350.573935)
			(xy 341.49269 -350.593123) (xy 341.580984 -350.621654) (xy 341.62365 -350.639888) (xy 341.633592 -350.643694)
			(xy 341.654856 -350.643694) (xy 341.664798 -350.639888) (xy 341.707457 -350.621635) (xy 341.79575 -350.593093)
			(xy 341.886537 -350.573902) (xy 341.978828 -350.564272) (xy 342.025224 -350.563688) (xy 342.071619 -350.564298)
			(xy 342.163906 -350.573935) (xy 342.25469 -350.593123) (xy 342.342984 -350.621654) (xy 342.38565 -350.639888)
			(xy 342.395592 -350.643694) (xy 342.416856 -350.643694) (xy 342.426798 -350.639888) (xy 342.469457 -350.621635)
			(xy 342.55775 -350.593093) (xy 342.648537 -350.573902) (xy 342.740828 -350.564272) (xy 342.787224 -350.563688)
			(xy 342.833721 -350.564268) (xy 342.926211 -350.573942) (xy 343.017189 -350.593203) (xy 343.105663 -350.621842)
			(xy 343.148412 -350.640142) (xy 343.157173 -350.643559) (xy 343.175938 -350.644473) (xy 343.184988 -350.64192)
			(xy 343.230317 -350.627524) (xy 343.323273 -350.607389) (xy 343.417848 -350.597296) (xy 343.465404 -350.596708)
			(xy 343.506508 -350.597148) (xy 343.588364 -350.604734) (xy 343.669172 -350.61984) (xy 343.748241 -350.642338)
			(xy 343.824897 -350.672035) (xy 343.898486 -350.708679) (xy 343.968379 -350.751956) (xy 344.033982 -350.801498)
			(xy 344.094733 -350.856881) (xy 344.150115 -350.917634) (xy 344.199655 -350.983237) (xy 344.242931 -351.053132)
			(xy 344.279573 -351.126721) (xy 344.309269 -351.203378) (xy 344.331765 -351.282448) (xy 344.346869 -351.363255)
			(xy 344.354453 -351.445112) (xy 344.354912 -351.486216) (xy 344.354334 -351.532612) (xy 344.344688 -351.6249)
			(xy 344.32549 -351.715684) (xy 344.296951 -351.803977) (xy 344.278712 -351.846642) (xy 344.274897 -351.856581)
			(xy 344.274903 -351.877848) (xy 344.278712 -351.88779) (xy 344.296962 -351.93045) (xy 344.325505 -352.018743)
			(xy 344.344696 -352.109529) (xy 344.354328 -352.20182) (xy 344.354912 -352.248216) (xy 344.354328 -352.294369)
			(xy 344.344776 -352.386179) (xy 344.325776 -352.476508) (xy 344.297531 -352.564386) (xy 344.279474 -352.606864)
			(xy 344.275648 -352.6168) (xy 344.275662 -352.638069) (xy 344.279474 -352.648012) (xy 344.29749 -352.690438)
			(xy 344.325707 -352.77819) (xy 344.344711 -352.868387) (xy 344.354297 -352.960064) (xy 344.354912 -353.006152)
			(xy 344.354402 -353.047262) (xy 344.34922 -353.1032) (xy 423.453493 -353.1032) (xy 423.457484 -353.019415)
			(xy 423.469422 -352.936388) (xy 423.489198 -352.854872) (xy 423.516634 -352.775605) (xy 423.55148 -352.699305)
			(xy 423.593421 -352.626663) (xy 423.642078 -352.558337) (xy 423.697009 -352.494945) (xy 423.757718 -352.437063)
			(xy 423.823654 -352.385213) (xy 423.89422 -352.339866) (xy 423.968777 -352.301432) (xy 424.04665 -352.270259)
			(xy 424.127133 -352.24663) (xy 424.209499 -352.230759) (xy 424.293 -352.222789) (xy 424.33494 -352.222308)
			(xy 424.372129 -352.222714) (xy 424.446242 -352.228999) (xy 424.519562 -352.241503) (xy 424.591568 -352.260139)
			(xy 424.626786 -352.272092) (xy 424.634982 -352.274615) (xy 424.652118 -352.274615) (xy 424.660314 -352.272092)
			(xy 424.687596 -352.262757) (xy 424.74314 -352.24725) (xy 424.771312 -352.241104) (xy 424.781089 -352.238609)
			(xy 424.797722 -352.227214) (xy 424.808697 -352.210302) (xy 424.810936 -352.200464) (xy 424.820391 -352.151355)
			(xy 424.84891 -352.055495) (xy 424.867832 -352.009202) (xy 424.871403 -351.999613) (xy 424.871399 -351.979169)
			(xy 424.867832 -351.969578) (xy 424.850786 -351.928175) (xy 424.824155 -351.842685) (xy 424.806254 -351.754951)
			(xy 424.797263 -351.665861) (xy 424.796712 -351.62109) (xy 424.797216 -351.578729) (xy 424.805269 -351.494392)
			(xy 424.821303 -351.411202) (xy 424.845171 -351.329912) (xy 424.876659 -351.25126) (xy 424.915481 -351.175957)
			(xy 424.961284 -351.104685) (xy 425.013655 -351.038089) (xy 425.07212 -350.976774) (xy 425.136148 -350.921293)
			(xy 425.20516 -350.87215) (xy 425.27853 -350.82979) (xy 425.355595 -350.794595) (xy 425.435657 -350.766886)
			(xy 425.51799 -350.746912) (xy 425.601849 -350.734855) (xy 425.686474 -350.730824) (xy 425.771099 -350.734855)
			(xy 425.854958 -350.746912) (xy 425.937291 -350.766886) (xy 426.017353 -350.794595) (xy 426.094418 -350.82979)
			(xy 426.167788 -350.87215) (xy 426.2368 -350.921293) (xy 426.300828 -350.976774) (xy 426.359293 -351.038089)
			(xy 426.411664 -351.104685) (xy 426.457467 -351.175957) (xy 426.496289 -351.25126) (xy 426.527777 -351.329912)
			(xy 426.551645 -351.411202) (xy 426.567679 -351.494392) (xy 426.575732 -351.578729) (xy 426.576236 -351.62109)
			(xy 426.575653 -351.665859) (xy 426.566649 -351.754944) (xy 426.548749 -351.842675) (xy 426.522136 -351.928167)
			(xy 426.505116 -351.969578) (xy 426.501559 -351.979171) (xy 426.501555 -351.999611) (xy 426.505116 -352.009202)
			(xy 426.522153 -352.050608) (xy 426.548787 -352.136097) (xy 426.566691 -352.22383) (xy 426.575684 -352.312919)
			(xy 426.576236 -352.35769) (xy 426.575815 -352.394789) (xy 426.569551 -352.468723) (xy 426.557151 -352.541879)
			(xy 426.548296 -352.577908) (xy 426.546514 -352.586294) (xy 426.548018 -352.603361) (xy 426.555074 -352.618974)
			(xy 426.560742 -352.625406) (xy 426.601128 -352.668332) (xy 426.613574 -352.665538) (xy 426.622391 -352.663274)
			(xy 426.637739 -352.653501) (xy 426.643546 -352.646488) (xy 426.66867 -352.613784) (xy 426.724067 -352.552685)
			(xy 426.784882 -352.496976) (xy 426.850593 -352.447136) (xy 426.920635 -352.403592) (xy 426.994408 -352.366719)
			(xy 427.071277 -352.336834) (xy 427.150582 -352.314192) (xy 427.231643 -352.298989) (xy 427.313763 -352.291354)
			(xy 427.355 -352.290888) (xy 427.396111 -352.291352) (xy 427.477981 -352.29894) (xy 427.558801 -352.314051)
			(xy 427.637882 -352.336556) (xy 427.714549 -352.366262) (xy 427.788147 -352.402918) (xy 427.858049 -352.446208)
			(xy 427.923657 -352.495765) (xy 427.984412 -352.551165) (xy 428.039795 -352.611935) (xy 428.089333 -352.677557)
			(xy 428.132604 -352.747471) (xy 428.169239 -352.82108) (xy 428.198924 -352.897755) (xy 428.221406 -352.976842)
			(xy 428.236494 -353.057667) (xy 428.243048 -353.1286) (xy 431.780208 -353.1286) (xy 431.784199 -353.04482)
			(xy 431.796136 -352.961799) (xy 431.815909 -352.880289) (xy 431.843342 -352.801027) (xy 431.878184 -352.724732)
			(xy 431.92012 -352.652094) (xy 431.968771 -352.583771) (xy 432.023696 -352.520381) (xy 432.084398 -352.4625)
			(xy 432.150327 -352.410651) (xy 432.220886 -352.365303) (xy 432.295436 -352.326868) (xy 432.373301 -352.295693)
			(xy 432.453778 -352.27206) (xy 432.536136 -352.256184) (xy 432.619631 -352.248208) (xy 432.661568 -352.247708)
			(xy 432.698757 -352.248106) (xy 432.77287 -352.254393) (xy 432.84619 -352.2669) (xy 432.918196 -352.285538)
			(xy 432.953414 -352.297492) (xy 432.96161 -352.300015) (xy 432.978746 -352.300015) (xy 432.986942 -352.297492)
			(xy 433.014223 -352.288155) (xy 433.069768 -352.27265) (xy 433.09794 -352.266504) (xy 433.107722 -352.264025)
			(xy 433.124353 -352.252622) (xy 433.135327 -352.235704) (xy 433.137564 -352.225864) (xy 433.147017 -352.176755)
			(xy 433.175537 -352.080895) (xy 433.19446 -352.034602) (xy 433.19803 -352.025013) (xy 433.198026 -352.004569)
			(xy 433.19446 -351.994978) (xy 433.177416 -351.953575) (xy 433.150784 -351.868085) (xy 433.132882 -351.780351)
			(xy 433.123891 -351.691261) (xy 433.12334 -351.64649) (xy 433.123844 -351.604129) (xy 433.131897 -351.519792)
			(xy 433.147931 -351.436602) (xy 433.171799 -351.355312) (xy 433.203287 -351.27666) (xy 433.242109 -351.201357)
			(xy 433.287912 -351.130085) (xy 433.340283 -351.063489) (xy 433.398748 -351.002174) (xy 433.462776 -350.946693)
			(xy 433.531788 -350.89755) (xy 433.605158 -350.85519) (xy 433.682223 -350.819995) (xy 433.762285 -350.792286)
			(xy 433.844618 -350.772312) (xy 433.928477 -350.760255) (xy 434.013102 -350.756224) (xy 434.097727 -350.760255)
			(xy 434.181586 -350.772312) (xy 434.263919 -350.792286) (xy 434.343981 -350.819995) (xy 434.421046 -350.85519)
			(xy 434.494416 -350.89755) (xy 434.563428 -350.946693) (xy 434.627456 -351.002174) (xy 434.685921 -351.063489)
			(xy 434.738292 -351.130085) (xy 434.784095 -351.201357) (xy 434.822917 -351.27666) (xy 434.854405 -351.355312)
			(xy 434.878273 -351.436602) (xy 434.894307 -351.519792) (xy 434.90236 -351.604129) (xy 434.902864 -351.64649)
			(xy 434.902279 -351.691259) (xy 434.893275 -351.780343) (xy 434.875376 -351.868074) (xy 434.848764 -351.953566)
			(xy 434.831744 -351.994978) (xy 434.828186 -352.00457) (xy 434.828182 -352.025011) (xy 434.831744 -352.034602)
			(xy 434.848782 -352.076008) (xy 434.875415 -352.161497) (xy 434.893319 -352.24923) (xy 434.902312 -352.338319)
			(xy 434.902864 -352.38309) (xy 434.902442 -352.420189) (xy 434.896179 -352.494123) (xy 434.883778 -352.567279)
			(xy 434.874924 -352.603308) (xy 434.873134 -352.611693) (xy 434.874639 -352.628762) (xy 434.881699 -352.644375)
			(xy 434.88737 -352.650806) (xy 434.927756 -352.693732) (xy 434.940202 -352.690938) (xy 434.94901 -352.688645)
			(xy 434.964363 -352.678893) (xy 434.970174 -352.671888) (xy 434.995281 -352.639171) (xy 435.05068 -352.578072)
			(xy 435.111497 -352.522364) (xy 435.17721 -352.472524) (xy 435.247255 -352.428982) (xy 435.321029 -352.39211)
			(xy 435.3979 -352.362226) (xy 435.477207 -352.339586) (xy 435.558269 -352.324385) (xy 435.64039 -352.316753)
			(xy 435.681628 -352.316288) (xy 435.722739 -352.316726) (xy 435.80461 -352.324316) (xy 435.885431 -352.339429)
			(xy 435.964512 -352.361936) (xy 436.041179 -352.391645) (xy 436.114778 -352.428302) (xy 436.184679 -352.471595)
			(xy 436.250287 -352.521154) (xy 436.311041 -352.576555) (xy 436.366424 -352.637327) (xy 436.415962 -352.70295)
			(xy 436.459233 -352.772865) (xy 436.495867 -352.846475) (xy 436.525552 -352.923151) (xy 436.548034 -353.00224)
			(xy 436.563122 -353.083066) (xy 436.570687 -353.164939) (xy 436.571136 -353.20605) (xy 436.570625 -353.250815)
			(xy 436.561691 -353.339897) (xy 436.543847 -353.42763) (xy 436.517274 -353.513125) (xy 436.50027 -353.554538)
			(xy 436.496676 -353.56412) (xy 436.496695 -353.584571) (xy 436.50027 -353.594162) (xy 436.517262 -353.635579)
			(xy 436.543821 -353.721076) (xy 436.561662 -353.808807) (xy 436.570605 -353.897886) (xy 436.571136 -353.94265)
			(xy 436.570625 -353.987415) (xy 436.561691 -354.076497) (xy 436.543847 -354.16423) (xy 436.517274 -354.249725)
			(xy 436.50027 -354.291138) (xy 436.496676 -354.30072) (xy 436.496695 -354.321171) (xy 436.50027 -354.330762)
			(xy 436.517262 -354.372179) (xy 436.543821 -354.457676) (xy 436.561662 -354.545407) (xy 436.570605 -354.634486)
			(xy 436.571136 -354.67925) (xy 436.57064 -354.720357) (xy 436.56306 -354.80222) (xy 436.547959 -354.883035)
			(xy 436.525468 -354.962112) (xy 436.495777 -355.038776) (xy 436.45914 -355.112375) (xy 436.415869 -355.18228)
			(xy 436.366333 -355.247894) (xy 436.310956 -355.308659) (xy 436.250208 -355.364056) (xy 436.184609 -355.413612)
			(xy 436.114718 -355.456904) (xy 436.041131 -355.493565) (xy 435.964475 -355.523279) (xy 435.885405 -355.545796)
			(xy 435.804595 -355.560921) (xy 435.722735 -355.568527) (xy 435.681628 -355.569012) (xy 435.640012 -355.568516)
			(xy 435.557148 -355.560695) (xy 435.475375 -355.545175) (xy 435.395407 -355.522092) (xy 435.317943 -355.491648)
			(xy 435.243658 -355.454106) (xy 435.208172 -355.43236) (xy 435.199036 -355.427305) (xy 435.178406 -355.424238)
			(xy 435.15825 -355.429598) (xy 435.149752 -355.435662) (xy 435.116095 -355.461645) (xy 435.044668 -355.507784)
			(xy 434.969164 -355.546894) (xy 434.890271 -355.578619) (xy 434.80871 -355.602669) (xy 434.725225 -355.618825)
			(xy 434.64058 -355.626937) (xy 434.598064 -355.627432) (xy 434.556953 -355.626982) (xy 434.475084 -355.619391)
			(xy 434.394263 -355.604278) (xy 434.315183 -355.581771) (xy 434.238517 -355.552062) (xy 434.164919 -355.515405)
			(xy 434.095019 -355.472113) (xy 434.029411 -355.422555) (xy 433.968657 -355.367155) (xy 433.913275 -355.306384)
			(xy 433.863736 -355.240762) (xy 433.820465 -355.170848) (xy 433.783831 -355.09724) (xy 433.754145 -355.020565)
			(xy 433.731661 -354.941477) (xy 433.716572 -354.860653) (xy 433.709006 -354.778781) (xy 433.708556 -354.73767)
			(xy 433.709074 -354.692905) (xy 433.718007 -354.603823) (xy 433.735848 -354.51609) (xy 433.762419 -354.430595)
			(xy 433.779422 -354.389182) (xy 433.783005 -354.379596) (xy 433.782994 -354.359149) (xy 433.779422 -354.349558)
			(xy 433.763631 -354.311251) (xy 433.738421 -354.232316) (xy 433.720663 -354.151378) (xy 433.710513 -354.069139)
			(xy 433.70881 -354.02774) (xy 433.707967 -354.016821) (xy 433.698312 -353.997188) (xy 433.681401 -353.983306)
			(xy 433.670964 -353.979988) (xy 433.654091 -353.975492) (xy 433.620681 -353.965328) (xy 433.604162 -353.959668)
			(xy 433.595966 -353.957145) (xy 433.57883 -353.957145) (xy 433.570634 -353.959668) (xy 433.535422 -353.971642)
			(xy 433.463417 -353.990292) (xy 433.390095 -354.002797) (xy 433.315979 -354.009067) (xy 433.278788 -354.009452)
			(xy 433.241598 -354.009064) (xy 433.167486 -354.002773) (xy 433.094166 -353.990263) (xy 433.02216 -353.971623)
			(xy 432.986942 -353.959668) (xy 432.978746 -353.957145) (xy 432.96161 -353.957145) (xy 432.953414 -353.959668)
			(xy 432.918203 -353.971647) (xy 432.846198 -353.990296) (xy 432.772875 -354.0028) (xy 432.698759 -354.009068)
			(xy 432.661568 -354.009452) (xy 432.619631 -354.008992) (xy 432.536136 -354.001016) (xy 432.453778 -353.98514)
			(xy 432.373301 -353.961507) (xy 432.295436 -353.930332) (xy 432.220886 -353.891897) (xy 432.150327 -353.846549)
			(xy 432.084398 -353.7947) (xy 432.023696 -353.736819) (xy 431.968771 -353.673429) (xy 431.92012 -353.605106)
			(xy 431.878184 -353.532468) (xy 431.843342 -353.456173) (xy 431.815909 -353.376911) (xy 431.796136 -353.295401)
			(xy 431.784199 -353.21238) (xy 431.780208 -353.1286) (xy 428.243048 -353.1286) (xy 428.244059 -353.139539)
			(xy 428.244508 -353.18065) (xy 428.243992 -353.225415) (xy 428.235058 -353.314497) (xy 428.217216 -353.40223)
			(xy 428.190645 -353.487725) (xy 428.173642 -353.529138) (xy 428.17005 -353.538721) (xy 428.170068 -353.559171)
			(xy 428.173642 -353.568762) (xy 428.190638 -353.610177) (xy 428.217195 -353.695675) (xy 428.235035 -353.783407)
			(xy 428.243977 -353.872486) (xy 428.244508 -353.91725) (xy 428.243992 -353.962015) (xy 428.235058 -354.051097)
			(xy 428.217216 -354.13883) (xy 428.190645 -354.224325) (xy 428.173642 -354.265738) (xy 428.17005 -354.275321)
			(xy 428.170068 -354.295771) (xy 428.173642 -354.305362) (xy 428.190638 -354.346777) (xy 428.217195 -354.432275)
			(xy 428.235035 -354.520007) (xy 428.243977 -354.609086) (xy 428.244508 -354.65385) (xy 428.24394 -354.694955)
			(xy 428.23636 -354.776814) (xy 428.221262 -354.857624) (xy 428.198773 -354.936698) (xy 428.169085 -355.013359)
			(xy 428.132451 -355.086955) (xy 428.089184 -355.156857) (xy 428.039654 -355.22247) (xy 427.984281 -355.283233)
			(xy 427.923539 -355.33863) (xy 427.857946 -355.388186) (xy 427.788061 -355.431481) (xy 427.714479 -355.468143)
			(xy 427.63783 -355.497861) (xy 427.558765 -355.520382) (xy 427.47796 -355.535512) (xy 427.396104 -355.543124)
			(xy 427.355 -355.543612) (xy 427.313384 -355.543129) (xy 427.230519 -355.535306) (xy 427.148746 -355.519784)
			(xy 427.068779 -355.496698) (xy 426.991314 -355.466251) (xy 426.917029 -355.428708) (xy 426.881544 -355.40696)
			(xy 426.87242 -355.40188) (xy 426.851782 -355.398822) (xy 426.831622 -355.404192) (xy 426.823124 -355.410262)
			(xy 426.789477 -355.436258) (xy 426.718048 -355.482396) (xy 426.642542 -355.521504) (xy 426.563647 -355.553228)
			(xy 426.482084 -355.577275) (xy 426.398599 -355.593428) (xy 426.313953 -355.601539) (xy 426.271436 -355.602032)
			(xy 426.230327 -355.601513) (xy 426.148459 -355.593929) (xy 426.06764 -355.578822) (xy 425.98856 -355.556321)
			(xy 425.911894 -355.526617) (xy 425.838297 -355.489966) (xy 425.768396 -355.446679) (xy 425.702788 -355.397126)
			(xy 425.642034 -355.341729) (xy 425.58665 -355.280962) (xy 425.537111 -355.215344) (xy 425.49384 -355.145433)
			(xy 425.457204 -355.071828) (xy 425.427518 -354.995156) (xy 425.405034 -354.916071) (xy 425.389944 -354.835249)
			(xy 425.382378 -354.753379) (xy 425.381928 -354.71227) (xy 425.382449 -354.667505) (xy 425.391381 -354.578423)
			(xy 425.409222 -354.49069) (xy 425.435791 -354.405195) (xy 425.452794 -354.363782) (xy 425.456378 -354.354197)
			(xy 425.456367 -354.333749) (xy 425.452794 -354.324158) (xy 425.437002 -354.285851) (xy 425.411792 -354.206916)
			(xy 425.394035 -354.125978) (xy 425.383885 -354.043739) (xy 425.382182 -354.00234) (xy 425.381358 -353.991418)
			(xy 425.371697 -353.971782) (xy 425.354777 -353.957903) (xy 425.344336 -353.954588) (xy 425.327464 -353.950088)
			(xy 425.294053 -353.939926) (xy 425.277534 -353.934268) (xy 425.269338 -353.931745) (xy 425.252202 -353.931745)
			(xy 425.244006 -353.934268) (xy 425.208787 -353.946222) (xy 425.136785 -353.964878) (xy 425.063465 -353.977388)
			(xy 424.98935 -353.983664) (xy 424.95216 -353.984052) (xy 424.914971 -353.983643) (xy 424.840858 -353.977359)
			(xy 424.767539 -353.964855) (xy 424.695532 -353.94622) (xy 424.660314 -353.934268) (xy 424.652118 -353.931745)
			(xy 424.634982 -353.931745) (xy 424.626786 -353.934268) (xy 424.591569 -353.946227) (xy 424.519566 -353.964882)
			(xy 424.446245 -353.977391) (xy 424.37213 -353.983665) (xy 424.33494 -353.984052) (xy 424.293 -353.983611)
			(xy 424.209499 -353.975641) (xy 424.127133 -353.95977) (xy 424.04665 -353.936141) (xy 423.968777 -353.904968)
			(xy 423.89422 -353.866534) (xy 423.823654 -353.821187) (xy 423.757718 -353.769337) (xy 423.697009 -353.711455)
			(xy 423.642078 -353.648063) (xy 423.593421 -353.579737) (xy 423.55148 -353.507095) (xy 423.516634 -353.430795)
			(xy 423.489198 -353.351528) (xy 423.469422 -353.270012) (xy 423.457484 -353.186985) (xy 423.453493 -353.1032)
			(xy 344.34922 -353.1032) (xy 344.346818 -353.129131) (xy 344.331712 -353.20995) (xy 344.309211 -353.289031)
			(xy 344.279508 -353.365698) (xy 344.242856 -353.439296) (xy 344.199569 -353.509197) (xy 344.150015 -353.574806)
			(xy 344.094618 -353.635561) (xy 344.03385 -353.690944) (xy 343.968231 -353.740483) (xy 343.898319 -353.783755)
			(xy 343.824713 -353.82039) (xy 343.748039 -353.850075) (xy 343.668954 -353.872558) (xy 343.58813 -353.887646)
			(xy 343.50626 -353.895211) (xy 343.46515 -353.89566) (xy 343.421566 -353.895134) (xy 343.334811 -353.886653)
			(xy 343.249302 -353.869729) (xy 343.165858 -353.844524) (xy 343.085279 -353.81128) (xy 343.046558 -353.791266)
			(xy 343.035117 -353.785971) (xy 343.009938 -353.786108) (xy 342.998552 -353.79152) (xy 342.959312 -353.812286)
			(xy 342.877483 -353.846743) (xy 342.792629 -353.872876) (xy 342.705593 -353.890425) (xy 342.617242 -353.899215)
			(xy 342.572848 -353.899724) (xy 342.534563 -353.899351) (xy 342.458274 -353.892807) (xy 342.382832 -353.879722)
			(xy 342.308796 -353.860191) (xy 342.27262 -353.847654) (xy 342.264183 -353.845003) (xy 342.246513 -353.845003)
			(xy 342.238076 -353.847654) (xy 342.201893 -353.860167) (xy 342.127855 -353.879678) (xy 342.052415 -353.892761)
			(xy 341.976131 -353.89932) (xy 341.937848 -353.899724) (xy 341.899563 -353.899351) (xy 341.823274 -353.892807)
			(xy 341.747832 -353.879722) (xy 341.673796 -353.860191) (xy 341.63762 -353.847654) (xy 341.629183 -353.845003)
			(xy 341.611513 -353.845003) (xy 341.603076 -353.847654) (xy 341.566893 -353.860167) (xy 341.492855 -353.879678)
			(xy 341.417415 -353.892761) (xy 341.341131 -353.89932) (xy 341.302848 -353.899724) (xy 341.264563 -353.899351)
			(xy 341.188274 -353.892807) (xy 341.112832 -353.879722) (xy 341.038796 -353.860191) (xy 341.00262 -353.847654)
			(xy 340.994183 -353.845003) (xy 340.976513 -353.845003) (xy 340.968076 -353.847654) (xy 340.931893 -353.860167)
			(xy 340.857855 -353.879678) (xy 340.782415 -353.892761) (xy 340.706131 -353.89932) (xy 340.667848 -353.899724)
			(xy 340.626561 -353.899267) (xy 340.544342 -353.891612) (xy 340.463186 -353.876372) (xy 340.383791 -353.853679)
			(xy 340.306839 -353.823729) (xy 340.232994 -353.786777) (xy 340.197694 -353.765358) (xy 340.190048 -353.760984)
			(xy 340.172838 -353.757274) (xy 340.155388 -353.759605) (xy 340.147402 -353.763326) (xy 340.109478 -353.782391)
			(xy 340.030697 -353.814004) (xy 339.949262 -353.837968) (xy 339.865915 -353.854065) (xy 339.781414 -353.862149)
			(xy 339.73897 -353.86264) (xy 339.697862 -353.862216) (xy 339.615997 -353.854629) (xy 339.535181 -353.839522)
			(xy 339.456103 -353.817024) (xy 339.379438 -353.787327) (xy 339.30584 -353.750684) (xy 339.235936 -353.707408)
			(xy 339.170322 -353.657867) (xy 339.109558 -353.602485) (xy 339.054162 -353.541734) (xy 339.004606 -353.476131)
			(xy 338.961314 -353.406237) (xy 338.924655 -353.332646) (xy 338.89494 -353.255988) (xy 338.872425 -353.176916)
			(xy 338.857299 -353.096103) (xy 338.849693 -353.01424) (xy 338.849208 -352.973132) (xy 271.348962 -352.973132)
			(xy 271.348962 -354.118672) (xy 271.3494 -354.128735) (xy 271.35714 -354.147315) (xy 271.363948 -354.15474)
			(xy 273.14017 -355.930962) (xy 273.14757 -355.937802) (xy 273.166169 -355.945516) (xy 273.176238 -355.945948)
			(xy 285.457392 -355.945948)
		)
		(stroke
			(width 0)
			(type solid)
		)
		(fill yes)
		(layer "In9.Cu")
		(net "GND")
	)
	(gr_poly
		(pts
			(xy 64.318388 -335.233264) (xy 64.328458 -335.232842) (xy 64.347063 -335.225127) (xy 64.354456 -335.218278)
			(xy 64.6684 -334.904334) (xy 64.675236 -334.896932) (xy 64.682947 -334.878334) (xy 64.683386 -334.868266)
			(xy 64.683386 -330.394564) (xy 64.684001 -330.369609) (xy 64.693744 -330.320658) (xy 64.712849 -330.274548)
			(xy 64.740581 -330.233051) (xy 64.757808 -330.214986) (xy 65.519808 -329.452986) (xy 65.537847 -329.435722)
			(xy 65.579339 -329.407956) (xy 65.625457 -329.388834) (xy 65.674423 -329.379093) (xy 65.699386 -329.378564)
			(xy 70.653148 -329.378564) (xy 70.663214 -329.378131) (xy 70.681802 -329.370401) (xy 70.689216 -329.363578)
			(xy 71.76262 -328.290174) (xy 71.768462 -328.260456) (xy 71.76262 -328.245978) (xy 71.75368 -328.223033)
			(xy 71.741115 -328.175419) (xy 71.734796 -328.126582) (xy 71.734426 -328.10196) (xy 71.734915 -328.074712)
			(xy 71.742676 -328.02077) (xy 71.758035 -327.968482) (xy 71.780679 -327.918912) (xy 71.810147 -327.873069)
			(xy 71.845839 -327.831887) (xy 71.887029 -327.796203) (xy 71.932877 -327.766744) (xy 71.982451 -327.744109)
			(xy 72.034742 -327.728761) (xy 72.088685 -327.72101) (xy 72.115934 -327.720452) (xy 72.140555 -327.720837)
			(xy 72.18939 -327.727163) (xy 72.237008 -327.739707) (xy 72.259952 -327.748646) (xy 72.27443 -327.754488)
			(xy 72.304148 -327.748646) (xy 74.282808 -325.769986) (xy 74.300847 -325.752722) (xy 74.342339 -325.724956)
			(xy 74.388457 -325.705834) (xy 74.437423 -325.696093) (xy 74.462386 -325.695564) (xy 96.306386 -325.695564)
			(xy 96.33134 -325.696184) (xy 96.380285 -325.705934) (xy 96.426389 -325.725044) (xy 96.467881 -325.752779)
			(xy 96.485964 -325.769986) (xy 98.865944 -328.149966) (xy 98.873343 -328.156809) (xy 98.891942 -328.164533)
			(xy 98.902012 -328.164952) (xy 104.463596 -328.164952) (xy 104.473665 -328.164528) (xy 104.492266 -328.156809)
			(xy 104.499664 -328.149966) (xy 105.228644 -327.420986) (xy 105.246684 -327.403725) (xy 105.288177 -327.375964)
			(xy 105.334295 -327.356849) (xy 105.38326 -327.347115) (xy 105.408222 -327.346564) (xy 110.212124 -327.346564)
			(xy 110.222432 -327.346095) (xy 110.241384 -327.337982) (xy 110.255592 -327.323043) (xy 110.259622 -327.313544)
			(xy 110.27364 -327.27771) (xy 110.307891 -327.208801) (xy 110.348905 -327.143691) (xy 110.396268 -327.083042)
			(xy 110.449497 -327.02747) (xy 110.508051 -326.977541) (xy 110.571336 -326.933761) (xy 110.638707 -326.896577)
			(xy 110.70948 -326.866365) (xy 110.782935 -326.843434) (xy 110.858326 -326.828015) (xy 110.934886 -326.820267)
			(xy 111.011838 -326.820267) (xy 111.088398 -326.828015) (xy 111.163789 -326.843434) (xy 111.237244 -326.866365)
			(xy 111.308017 -326.896577) (xy 111.375388 -326.933761) (xy 111.438673 -326.977541) (xy 111.497227 -327.02747)
			(xy 111.550456 -327.083042) (xy 111.597819 -327.143691) (xy 111.638833 -327.208801) (xy 111.673084 -327.27771)
			(xy 111.687102 -327.313544) (xy 111.691168 -327.323016) (xy 111.705388 -327.337912) (xy 111.724305 -327.346051)
			(xy 111.7346 -327.346564) (xy 131.105148 -327.346564) (xy 131.115214 -327.346131) (xy 131.133802 -327.338401)
			(xy 131.141216 -327.331578) (xy 131.54914 -326.923654) (xy 131.555986 -326.916256) (xy 131.563713 -326.897657)
			(xy 131.564126 -326.887586) (xy 131.564126 -296.213022) (xy 131.563821 -296.204827) (xy 131.558646 -296.189275)
			(xy 131.553966 -296.182542) (xy 131.538313 -296.160915) (xy 131.513463 -296.113669) (xy 131.49653 -296.063042)
			(xy 131.487955 -296.010352) (xy 131.487418 -295.98366) (xy 131.487875 -295.958927) (xy 131.495237 -295.910011)
			(xy 131.509806 -295.862738) (xy 131.531256 -295.818164) (xy 131.544822 -295.797478) (xy 131.55295 -295.78554)
			(xy 131.553966 -295.75633) (xy 131.39928 -295.489376) (xy 131.374388 -295.475914) (xy 131.360164 -295.476676)
			(xy 131.34467 -295.47693) (xy 131.318684 -295.476418) (xy 131.267352 -295.468284) (xy 131.217924 -295.452221)
			(xy 131.171617 -295.428624) (xy 131.129571 -295.398074) (xy 131.092821 -295.361323) (xy 131.062272 -295.319276)
			(xy 131.038676 -295.272969) (xy 131.022614 -295.223541) (xy 131.014481 -295.172208) (xy 131.013962 -295.146222)
			(xy 131.014367 -295.122821) (xy 131.020968 -295.076487) (xy 131.03404 -295.031548) (xy 131.053323 -294.988903)
			(xy 131.065524 -294.96893) (xy 131.073144 -294.956738) (xy 131.073652 -294.928544) (xy 130.929126 -294.67937)
			(xy 130.904488 -294.665908) (xy 130.89001 -294.66667) (xy 130.87477 -294.666924) (xy 130.848784 -294.666412)
			(xy 130.797452 -294.658278) (xy 130.748025 -294.642215) (xy 130.701718 -294.618617) (xy 130.659673 -294.588067)
			(xy 130.622923 -294.551317) (xy 130.592375 -294.50927) (xy 130.56878 -294.462963) (xy 130.552719 -294.413534)
			(xy 130.544587 -294.362202) (xy 130.544062 -294.336216) (xy 130.544479 -294.312846) (xy 130.551092 -294.266576)
			(xy 130.564158 -294.221699) (xy 130.583418 -294.179111) (xy 130.595624 -294.159178) (xy 130.603244 -294.146986)
			(xy 130.603752 -294.118792) (xy 130.458972 -293.869364) (xy 130.434334 -293.855902) (xy 130.42011 -293.856664)
			(xy 130.40487 -293.856918) (xy 130.379351 -293.85645) (xy 130.328917 -293.848617) (xy 130.280285 -293.833127)
			(xy 130.234613 -293.810347) (xy 130.192983 -293.780819) (xy 130.156385 -293.745244) (xy 130.12569 -293.704468)
			(xy 130.113278 -293.682166) (xy 130.10642 -293.669466) (xy 130.082544 -293.655242) (xy 129.787142 -293.655242)
			(xy 129.763266 -293.669466) (xy 129.756408 -293.682166) (xy 129.743954 -293.704442) (xy 129.713256 -293.745209)
			(xy 129.676662 -293.780778) (xy 129.63504 -293.810306) (xy 129.589377 -293.833093) (xy 129.540757 -293.848597)
			(xy 129.490332 -293.856451) (xy 129.464816 -293.856918) (xy 129.438826 -293.856436) (xy 129.387485 -293.848307)
			(xy 129.338047 -293.832246) (xy 129.291731 -293.808649) (xy 129.249677 -293.778098) (xy 129.212919 -293.741343)
			(xy 129.182364 -293.699291) (xy 129.158764 -293.652977) (xy 129.142699 -293.603541) (xy 129.134566 -293.5522)
			(xy 129.134108 -293.52621) (xy 129.134526 -293.50284) (xy 129.141138 -293.456569) (xy 129.154203 -293.411692)
			(xy 129.173461 -293.369103) (xy 129.18567 -293.349172) (xy 129.19329 -293.33698) (xy 129.193798 -293.308786)
			(xy 129.049018 -293.059358) (xy 129.02438 -293.045896) (xy 129.009902 -293.046658) (xy 128.994662 -293.046912)
			(xy 128.968677 -293.0464) (xy 128.917347 -293.038264) (xy 128.867921 -293.0222) (xy 128.821616 -292.998602)
			(xy 128.779573 -292.968052) (xy 128.742826 -292.931301) (xy 128.71228 -292.889255) (xy 128.688687 -292.842948)
			(xy 128.672628 -292.79352) (xy 128.664498 -292.742189) (xy 128.663954 -292.716204) (xy 128.66436 -292.692803)
			(xy 128.670963 -292.64647) (xy 128.684037 -292.601532) (xy 128.703321 -292.558889) (xy 128.715516 -292.538912)
			(xy 128.723136 -292.526974) (xy 128.723644 -292.498526) (xy 128.579118 -292.249352) (xy 128.554226 -292.23589)
			(xy 128.540002 -292.236652) (xy 128.524762 -292.236906) (xy 128.498777 -292.236394) (xy 128.447447 -292.228258)
			(xy 128.398022 -292.212194) (xy 128.351718 -292.188596) (xy 128.309675 -292.158046) (xy 128.272928 -292.121295)
			(xy 128.242383 -292.079248) (xy 128.218791 -292.032941) (xy 128.202732 -291.983514) (xy 128.194603 -291.932183)
			(xy 128.194054 -291.906198) (xy 128.194461 -291.882797) (xy 128.201064 -291.836465) (xy 128.214139 -291.791527)
			(xy 128.233424 -291.748884) (xy 128.245616 -291.728906) (xy 128.253236 -291.716968) (xy 128.253744 -291.688774)
			(xy 128.109218 -291.439346) (xy 128.084326 -291.425884) (xy 128.070102 -291.426646) (xy 128.054862 -291.4269)
			(xy 128.028877 -291.426388) (xy 127.977548 -291.418252) (xy 127.928123 -291.402188) (xy 127.881819 -291.37859)
			(xy 127.839777 -291.348039) (xy 127.803031 -291.311288) (xy 127.772486 -291.269242) (xy 127.748895 -291.222935)
			(xy 127.732837 -291.173508) (xy 127.724709 -291.122177) (xy 127.724154 -291.096192) (xy 127.724561 -291.072834)
			(xy 127.731136 -291.026582) (xy 127.744141 -290.981711) (xy 127.763317 -290.939111) (xy 127.775462 -290.919154)
			(xy 127.783336 -290.906962) (xy 127.783844 -290.878768) (xy 127.639064 -290.62934) (xy 127.614172 -290.615878)
			(xy 127.599948 -290.61664) (xy 127.584708 -290.616894) (xy 127.558719 -290.616411) (xy 127.50738 -290.608281)
			(xy 127.457945 -290.592219) (xy 127.411632 -290.568622) (xy 127.369581 -290.53807) (xy 127.332827 -290.501315)
			(xy 127.302275 -290.459263) (xy 127.278678 -290.412949) (xy 127.262617 -290.363514) (xy 127.254488 -290.312175)
			(xy 127.254 -290.286186) (xy 127.254407 -290.262786) (xy 127.261012 -290.216453) (xy 127.274086 -290.171515)
			(xy 127.293369 -290.128872) (xy 127.305562 -290.108894) (xy 127.313182 -290.096956) (xy 127.31369 -290.068762)
			(xy 127.169164 -289.819334) (xy 127.144272 -289.805872) (xy 127.130048 -289.806634) (xy 127.114808 -289.806888)
			(xy 127.088819 -289.806405) (xy 127.037481 -289.798275) (xy 126.988046 -289.782213) (xy 126.941733 -289.758616)
			(xy 126.899682 -289.728063) (xy 126.862929 -289.691308) (xy 126.832378 -289.649256) (xy 126.808782 -289.602943)
			(xy 126.792722 -289.553508) (xy 126.784594 -289.502169) (xy 126.7841 -289.47618) (xy 126.784508 -289.452822)
			(xy 126.791084 -289.40657) (xy 126.804088 -289.361699) (xy 126.823263 -289.319099) (xy 126.835408 -289.299142)
			(xy 126.843282 -289.28695) (xy 126.84379 -289.258756) (xy 126.69901 -289.009328) (xy 126.674372 -288.995866)
			(xy 126.659894 -288.996628) (xy 126.644654 -288.996882) (xy 126.618671 -288.996369) (xy 126.567346 -288.988233)
			(xy 126.517926 -288.97217) (xy 126.471626 -288.948573) (xy 126.429588 -288.918025) (xy 126.392845 -288.881277)
			(xy 126.362303 -288.839234) (xy 126.338713 -288.792932) (xy 126.322656 -288.743509) (xy 126.314527 -288.692183)
			(xy 126.314527 -288.640217) (xy 126.322656 -288.588891) (xy 126.338713 -288.539468) (xy 126.362303 -288.493166)
			(xy 126.392845 -288.451123) (xy 126.429588 -288.414375) (xy 126.471626 -288.383827) (xy 126.517926 -288.36023)
			(xy 126.567346 -288.344167) (xy 126.618671 -288.336031) (xy 126.644654 -288.335466) (xy 126.66218 -288.335974)
			(xy 126.676404 -288.336736) (xy 126.70155 -288.32302) (xy 126.84506 -288.075624) (xy 126.844552 -288.04743)
			(xy 126.836678 -288.035238) (xy 126.824227 -288.015149) (xy 126.804568 -287.97217) (xy 126.79123 -287.92683)
			(xy 126.784483 -287.880053) (xy 126.7841 -287.856422) (xy 126.784581 -287.830432) (xy 126.79271 -287.779091)
			(xy 126.80877 -287.729654) (xy 126.832367 -287.683338) (xy 126.862919 -287.641285) (xy 126.899674 -287.604528)
			(xy 126.941726 -287.573974) (xy 126.988041 -287.550376) (xy 127.037477 -287.534313) (xy 127.088818 -287.526183)
			(xy 127.114808 -287.525714) (xy 127.13208 -287.526222) (xy 127.146558 -287.526984) (xy 127.17145 -287.513522)
			(xy 127.31496 -287.265872) (xy 127.314452 -287.23717) (xy 127.306578 -287.225232) (xy 127.294141 -287.205101)
			(xy 127.274481 -287.162059) (xy 127.261145 -287.116658) (xy 127.254404 -287.069821) (xy 127.254 -287.046162)
			(xy 127.254421 -287.022793) (xy 127.261039 -286.976525) (xy 127.27411 -286.931651) (xy 127.293372 -286.889066)
			(xy 127.305562 -286.869124) (xy 127.313182 -286.856932) (xy 127.31369 -286.828738) (xy 127.169164 -286.579564)
			(xy 127.144272 -286.566102) (xy 127.130048 -286.566864) (xy 127.114808 -286.567118) (xy 127.08882 -286.566609)
			(xy 127.037484 -286.55848) (xy 126.988052 -286.542419) (xy 126.94174 -286.518824) (xy 126.89969 -286.488275)
			(xy 126.862937 -286.451523) (xy 126.832385 -286.409475) (xy 126.808787 -286.363165) (xy 126.792725 -286.313733)
			(xy 126.784592 -286.262398) (xy 126.7841 -286.23641) (xy 126.784506 -286.213009) (xy 126.791107 -286.166675)
			(xy 126.804179 -286.121736) (xy 126.823459 -286.07909) (xy 126.835662 -286.059118) (xy 126.843282 -286.04718)
			(xy 126.84379 -286.018986) (xy 126.699264 -285.769558) (xy 126.674372 -285.756096) (xy 126.660148 -285.756858)
			(xy 126.644654 -285.757112) (xy 126.618669 -285.756599) (xy 126.567339 -285.748463) (xy 126.517914 -285.732397)
			(xy 126.471611 -285.708799) (xy 126.429568 -285.678248) (xy 126.392822 -285.641497) (xy 126.362277 -285.59945)
			(xy 126.338685 -285.553143) (xy 126.322627 -285.503716) (xy 126.314497 -285.452385) (xy 126.314497 -285.400415)
			(xy 126.322627 -285.349084) (xy 126.338685 -285.299657) (xy 126.362277 -285.25335) (xy 126.392822 -285.211303)
			(xy 126.429568 -285.174552) (xy 126.471611 -285.144001) (xy 126.517914 -285.120403) (xy 126.567339 -285.104337)
			(xy 126.618669 -285.096201) (xy 126.644654 -285.095696) (xy 126.66218 -285.096204) (xy 126.676404 -285.096966)
			(xy 126.70155 -285.08325) (xy 126.84506 -284.8356) (xy 126.844552 -284.807406) (xy 126.836678 -284.795214)
			(xy 126.824229 -284.775125) (xy 126.804573 -284.732146) (xy 126.791238 -284.686805) (xy 126.784494 -284.640028)
			(xy 126.7841 -284.616398) (xy 126.784583 -284.590409) (xy 126.792715 -284.539071) (xy 126.808777 -284.489637)
			(xy 126.832375 -284.443325) (xy 126.862928 -284.401275) (xy 126.899682 -284.364521) (xy 126.941734 -284.33397)
			(xy 126.988047 -284.310374) (xy 127.037481 -284.294312) (xy 127.088819 -284.286182) (xy 127.114808 -284.28569)
			(xy 127.13208 -284.286198) (xy 127.146558 -284.28696) (xy 127.17145 -284.273498) (xy 127.315214 -284.025848)
			(xy 127.314452 -283.997654) (xy 127.306578 -283.985208) (xy 127.294129 -283.965119) (xy 127.274474 -283.922139)
			(xy 127.26114 -283.876799) (xy 127.254397 -283.830022) (xy 127.254 -283.806392) (xy 127.254407 -283.782991)
			(xy 127.26101 -283.736658) (xy 127.274084 -283.69172) (xy 127.293367 -283.649076) (xy 127.305562 -283.6291)
			(xy 127.313182 -283.616908) (xy 127.31369 -283.588714) (xy 127.169164 -283.33954) (xy 127.144272 -283.326078)
			(xy 127.130048 -283.32684) (xy 127.114808 -283.327094) (xy 127.088819 -283.326611) (xy 127.03748 -283.318481)
			(xy 126.988045 -283.302419) (xy 126.941732 -283.278822) (xy 126.899681 -283.24827) (xy 126.862927 -283.211515)
			(xy 126.832375 -283.169463) (xy 126.808778 -283.123149) (xy 126.792717 -283.073714) (xy 126.784588 -283.022375)
			(xy 126.7841 -282.996386) (xy 126.784507 -282.972986) (xy 126.791112 -282.926653) (xy 126.804186 -282.881715)
			(xy 126.823469 -282.839072) (xy 126.835662 -282.819094) (xy 126.843282 -282.807156) (xy 126.84379 -282.778962)
			(xy 126.699264 -282.529534) (xy 126.674372 -282.516072) (xy 126.660148 -282.516834) (xy 126.644654 -282.517088)
			(xy 126.618671 -282.516575) (xy 126.567345 -282.508439) (xy 126.517924 -282.492375) (xy 126.471623 -282.468778)
			(xy 126.429584 -282.43823) (xy 126.39284 -282.401481) (xy 126.362298 -282.359438) (xy 126.338707 -282.313134)
			(xy 126.32265 -282.26371) (xy 126.314521 -282.212383) (xy 126.314521 -282.160417) (xy 126.32265 -282.10909)
			(xy 126.338707 -282.059666) (xy 126.362298 -282.013362) (xy 126.39284 -281.971319) (xy 126.429584 -281.93457)
			(xy 126.471623 -281.904022) (xy 126.517924 -281.880425) (xy 126.567345 -281.864361) (xy 126.618671 -281.856225)
			(xy 126.644654 -281.855672) (xy 126.661926 -281.85618) (xy 126.676404 -281.856942) (xy 126.70155 -281.843226)
			(xy 126.84506 -281.595576) (xy 126.844552 -281.567382) (xy 126.836678 -281.55519) (xy 126.82423 -281.535101)
			(xy 126.804578 -281.492121) (xy 126.791245 -281.44678) (xy 126.784505 -281.400004) (xy 126.7841 -281.376374)
			(xy 126.784508 -281.353016) (xy 126.791085 -281.306764) (xy 126.80409 -281.261894) (xy 126.823265 -281.219294)
			(xy 126.835408 -281.199336) (xy 126.843282 -281.187144) (xy 126.84379 -281.15895) (xy 126.69901 -280.909522)
			(xy 126.674118 -280.89606) (xy 126.659894 -280.896822) (xy 126.644654 -280.897076) (xy 126.61867 -280.896563)
			(xy 126.567343 -280.888426) (xy 126.517921 -280.872361) (xy 126.47162 -280.848762) (xy 126.429581 -280.818211)
			(xy 126.392838 -280.78146) (xy 126.362297 -280.739413) (xy 126.338709 -280.693107) (xy 126.322655 -280.643681)
			(xy 126.314531 -280.592352) (xy 126.313946 -280.566368) (xy 126.314348 -280.542966) (xy 126.320942 -280.496629)
			(xy 126.334009 -280.451686) (xy 126.353286 -280.409037) (xy 126.365508 -280.389076) (xy 126.373128 -280.377138)
			(xy 126.373636 -280.348944) (xy 126.22911 -280.099516) (xy 126.204218 -280.086054) (xy 126.189994 -280.086816)
			(xy 126.174754 -280.08707) (xy 126.148772 -280.086557) (xy 126.097449 -280.078421) (xy 126.048031 -280.062358)
			(xy 126.001733 -280.038763) (xy 125.959696 -280.008216) (xy 125.922955 -279.971469) (xy 125.892413 -279.929428)
			(xy 125.868824 -279.883127) (xy 125.852768 -279.833706) (xy 125.84464 -279.782382) (xy 125.84464 -279.730418)
			(xy 125.852768 -279.679094) (xy 125.868824 -279.629673) (xy 125.892413 -279.583372) (xy 125.922955 -279.541331)
			(xy 125.959696 -279.504584) (xy 126.001733 -279.474037) (xy 126.048031 -279.450442) (xy 126.097449 -279.434379)
			(xy 126.148772 -279.426243) (xy 126.174754 -279.425654) (xy 126.1985 -279.426057) (xy 126.245503 -279.432847)
			(xy 126.291046 -279.446308) (xy 126.334188 -279.466161) (xy 126.354332 -279.47874) (xy 126.366524 -279.486614)
			(xy 126.394718 -279.487376) (xy 127.241554 -279.000966) (xy 127.255016 -278.976328) (xy 127.254254 -278.96185)
			(xy 127.254 -278.946356) (xy 127.254421 -278.922987) (xy 127.26104 -278.87672) (xy 127.274112 -278.831846)
			(xy 127.293374 -278.789262) (xy 127.305562 -278.769318) (xy 127.313182 -278.757126) (xy 127.31369 -278.728932)
			(xy 127.16891 -278.479504) (xy 127.144272 -278.466042) (xy 127.130048 -278.466804) (xy 127.114808 -278.467058)
			(xy 127.08882 -278.466575) (xy 127.037483 -278.458445) (xy 126.988051 -278.442383) (xy 126.94174 -278.418785)
			(xy 126.899692 -278.388232) (xy 126.862941 -278.351476) (xy 126.832393 -278.309424) (xy 126.808801 -278.26311)
			(xy 126.792745 -278.213676) (xy 126.784621 -278.162338) (xy 126.7841 -278.13635) (xy 126.784522 -278.112981)
			(xy 126.791142 -278.066714) (xy 126.804213 -278.021841) (xy 126.823477 -277.979257) (xy 126.835662 -277.959312)
			(xy 126.843282 -277.94712) (xy 126.84379 -277.918926) (xy 126.699264 -277.669498) (xy 126.674372 -277.656036)
			(xy 126.660148 -277.656798) (xy 126.644654 -277.657052) (xy 126.618666 -277.656539) (xy 126.56733 -277.648402)
			(xy 126.517899 -277.632334) (xy 126.47159 -277.608733) (xy 126.429542 -277.578178) (xy 126.392792 -277.541423)
			(xy 126.362243 -277.499371) (xy 126.338648 -277.453058) (xy 126.322588 -277.403625) (xy 126.314457 -277.352288)
			(xy 126.314457 -277.300312) (xy 126.322588 -277.248975) (xy 126.338648 -277.199542) (xy 126.362243 -277.153229)
			(xy 126.392792 -277.111177) (xy 126.429542 -277.074422) (xy 126.47159 -277.043867) (xy 126.517899 -277.020266)
			(xy 126.56733 -277.004198) (xy 126.618666 -276.996061) (xy 126.644654 -276.995636) (xy 126.66218 -276.996144)
			(xy 126.676404 -276.996906) (xy 126.70155 -276.98319) (xy 126.84506 -276.73554) (xy 126.844552 -276.707346)
			(xy 126.836678 -276.695154) (xy 126.824232 -276.675064) (xy 126.804585 -276.632084) (xy 126.791257 -276.586743)
			(xy 126.784522 -276.539967) (xy 126.7841 -276.516338) (xy 126.78458 -276.490347) (xy 126.792707 -276.439004)
			(xy 126.808766 -276.389565) (xy 126.832362 -276.343247) (xy 126.862913 -276.301191) (xy 126.899668 -276.264433)
			(xy 126.941722 -276.233877) (xy 126.988037 -276.210277) (xy 127.037475 -276.194214) (xy 127.088817 -276.186083)
			(xy 127.114808 -276.18563) (xy 127.13208 -276.186138) (xy 127.146558 -276.1869) (xy 127.17145 -276.173438)
			(xy 127.315214 -275.925788) (xy 127.314452 -275.897594) (xy 127.306578 -275.885148) (xy 127.294133 -275.865058)
			(xy 127.274486 -275.822077) (xy 127.261159 -275.776737) (xy 127.254425 -275.729961) (xy 127.254 -275.706332)
			(xy 127.254404 -275.682931) (xy 127.261003 -275.636595) (xy 127.274072 -275.591654) (xy 127.29335 -275.549007)
			(xy 127.305562 -275.52904) (xy 127.313182 -275.516848) (xy 127.31369 -275.488654) (xy 127.169164 -275.23948)
			(xy 127.144272 -275.226018) (xy 127.130048 -275.22678) (xy 127.114808 -275.227034) (xy 127.08882 -275.226525)
			(xy 127.037483 -275.218396) (xy 126.988049 -275.202336) (xy 126.941737 -275.178741) (xy 126.899686 -275.148192)
			(xy 126.862931 -275.11144) (xy 126.832377 -275.069392) (xy 126.808777 -275.023082) (xy 126.792712 -274.97365)
			(xy 126.784578 -274.922314) (xy 126.7841 -274.896326) (xy 126.784505 -274.872925) (xy 126.791104 -274.82659)
			(xy 126.804174 -274.781649) (xy 126.823453 -274.739002) (xy 126.835662 -274.719034) (xy 126.843282 -274.707096)
			(xy 126.84379 -274.678902) (xy 126.699264 -274.429474) (xy 126.674372 -274.416012) (xy 126.660148 -274.416774)
			(xy 126.644654 -274.417028) (xy 126.618668 -274.416515) (xy 126.567336 -274.408378) (xy 126.517908 -274.392312)
			(xy 126.471602 -274.368712) (xy 126.429558 -274.33816) (xy 126.39281 -274.301407) (xy 126.362263 -274.259358)
			(xy 126.33867 -274.213049) (xy 126.322611 -274.16362) (xy 126.314481 -274.112286) (xy 126.314481 -274.060314)
			(xy 126.322611 -274.00898) (xy 126.33867 -273.959551) (xy 126.362263 -273.913242) (xy 126.39281 -273.871193)
			(xy 126.429558 -273.83444) (xy 126.471602 -273.803888) (xy 126.517908 -273.780288) (xy 126.567336 -273.764222)
			(xy 126.618668 -273.756085) (xy 126.644654 -273.755612) (xy 126.66218 -273.75612) (xy 126.676404 -273.756882)
			(xy 126.70155 -273.743166) (xy 126.84506 -273.495516) (xy 126.844552 -273.467322) (xy 126.836678 -273.45513)
			(xy 126.824228 -273.435041) (xy 126.80457 -273.392062) (xy 126.791232 -273.346722) (xy 126.784487 -273.299945)
			(xy 126.7841 -273.276314) (xy 126.784582 -273.250324) (xy 126.792712 -273.198984) (xy 126.808773 -273.149549)
			(xy 126.83237 -273.103234) (xy 126.862922 -273.061181) (xy 126.899677 -273.024426) (xy 126.941729 -272.993873)
			(xy 126.988043 -272.970275) (xy 127.037479 -272.954213) (xy 127.088818 -272.946083) (xy 127.114808 -272.945606)
			(xy 127.13208 -272.946114) (xy 127.146558 -272.946876) (xy 127.17145 -272.933414) (xy 127.315214 -272.685764)
			(xy 127.314452 -272.65757) (xy 127.306578 -272.645124) (xy 127.294128 -272.625035) (xy 127.274471 -272.582056)
			(xy 127.261134 -272.536716) (xy 127.254389 -272.489938) (xy 127.254 -272.466308) (xy 127.254406 -272.442907)
			(xy 127.261007 -272.396573) (xy 127.274079 -272.351634) (xy 127.29336 -272.308988) (xy 127.305562 -272.289016)
			(xy 127.313182 -272.276824) (xy 127.31369 -272.24863) (xy 127.169164 -271.999456) (xy 127.144272 -271.985994)
			(xy 127.130048 -271.986756) (xy 127.114808 -271.98701) (xy 127.088818 -271.986527) (xy 127.037479 -271.978397)
			(xy 126.988043 -271.962336) (xy 126.941728 -271.938738) (xy 126.899676 -271.908186) (xy 126.86292 -271.871432)
			(xy 126.832367 -271.82938) (xy 126.808768 -271.783066) (xy 126.792705 -271.733631) (xy 126.784573 -271.682292)
			(xy 126.7841 -271.656302) (xy 126.784506 -271.632901) (xy 126.791108 -271.586568) (xy 126.804181 -271.541629)
			(xy 126.823463 -271.498984) (xy 126.835662 -271.47901) (xy 126.843282 -271.467072) (xy 126.84379 -271.438878)
			(xy 126.699264 -271.18945) (xy 126.674372 -271.175988) (xy 126.660148 -271.17675) (xy 126.644654 -271.177004)
			(xy 126.618669 -271.176491) (xy 126.567341 -271.168355) (xy 126.517917 -271.15229) (xy 126.471615 -271.128692)
			(xy 126.429573 -271.098142) (xy 126.392828 -271.061391) (xy 126.362284 -271.019346) (xy 126.338692 -270.97304)
			(xy 126.322634 -270.923614) (xy 126.314505 -270.872285) (xy 126.314505 -270.820315) (xy 126.322634 -270.768986)
			(xy 126.338692 -270.71956) (xy 126.362284 -270.673254) (xy 126.392828 -270.631209) (xy 126.429573 -270.594458)
			(xy 126.471615 -270.563908) (xy 126.517917 -270.54031) (xy 126.567341 -270.524245) (xy 126.618669 -270.516109)
			(xy 126.644654 -270.515588) (xy 126.66218 -270.516096) (xy 126.676404 -270.516858) (xy 126.70155 -270.503142)
			(xy 126.84506 -270.255492) (xy 126.844552 -270.227298) (xy 126.836678 -270.215106) (xy 126.824229 -270.195017)
			(xy 126.804575 -270.152037) (xy 126.79124 -270.106697) (xy 126.784498 -270.05992) (xy 126.7841 -270.03629)
			(xy 126.78461 -270.010304) (xy 126.792742 -269.958971) (xy 126.808804 -269.909542) (xy 126.832401 -269.863235)
			(xy 126.862951 -269.821188) (xy 126.899702 -269.784439) (xy 126.94175 -269.753891) (xy 126.988059 -269.730297)
			(xy 127.037488 -269.714238) (xy 127.088822 -269.706109) (xy 127.114808 -269.705582) (xy 127.13208 -269.70609)
			(xy 127.146558 -269.706852) (xy 127.17145 -269.69339) (xy 127.315214 -269.44574) (xy 127.314452 -269.417546)
			(xy 127.306578 -269.4051) (xy 127.29413 -269.385011) (xy 127.274476 -269.342031) (xy 127.261142 -269.296691)
			(xy 127.254401 -269.249914) (xy 127.254 -269.226284) (xy 127.254408 -269.202884) (xy 127.261012 -269.156551)
			(xy 127.274087 -269.111614) (xy 127.29337 -269.06897) (xy 127.305562 -269.048992) (xy 127.313182 -269.037054)
			(xy 127.31369 -269.008606) (xy 127.169164 -268.759432) (xy 127.144272 -268.74597) (xy 127.130048 -268.746732)
			(xy 127.114808 -268.746986) (xy 127.088819 -268.746503) (xy 127.037481 -268.738373) (xy 126.988047 -268.722311)
			(xy 126.941734 -268.698714) (xy 126.899683 -268.668161) (xy 126.86293 -268.631406) (xy 126.832379 -268.589354)
			(xy 126.808783 -268.543041) (xy 126.792724 -268.493606) (xy 126.784595 -268.442267) (xy 126.7841 -268.416278)
			(xy 126.784508 -268.39292) (xy 126.791084 -268.346668) (xy 126.804088 -268.301797) (xy 126.823264 -268.259197)
			(xy 126.835408 -268.23924) (xy 126.843282 -268.227048) (xy 126.84379 -268.198854) (xy 126.69901 -267.949426)
			(xy 126.674372 -267.935964) (xy 126.659894 -267.936726) (xy 126.644654 -267.93698) (xy 126.61867 -267.936467)
			(xy 126.567343 -267.928331) (xy 126.51792 -267.912265) (xy 126.471619 -267.888666) (xy 126.429579 -267.858115)
			(xy 126.392837 -267.821364) (xy 126.362295 -267.779318) (xy 126.338706 -267.733011) (xy 126.322652 -267.683585)
			(xy 126.314527 -267.632256) (xy 126.313946 -267.606272) (xy 126.314366 -267.582903) (xy 126.320984 -267.536635)
			(xy 126.334055 -267.491761) (xy 126.353319 -267.449177) (xy 126.365508 -267.429234) (xy 126.373128 -267.417042)
			(xy 126.373636 -267.388848) (xy 126.214632 -267.115036) (xy 126.19101 -267.101574) (xy 126.177294 -267.101574)
			(xy 126.174754 -267.101574) (xy 126.14825 -267.101002) (xy 126.096038 -267.091839) (xy 126.046195 -267.073795)
			(xy 126.000216 -267.047414) (xy 125.959486 -267.013488) (xy 125.925227 -266.973037) (xy 125.911356 -266.950444)
			(xy 125.904244 -266.93876) (xy 125.88113 -266.925298) (xy 125.557026 -266.925298) (xy 125.53315 -266.939522)
			(xy 125.526292 -266.952222) (xy 125.51384 -266.9745) (xy 125.483144 -267.01527) (xy 125.446551 -267.050842)
			(xy 125.404928 -267.080372) (xy 125.359265 -267.10316) (xy 125.310643 -267.118664) (xy 125.260217 -267.126517)
			(xy 125.2347 -267.126974) (xy 125.224794 -267.12672) (xy 125.210824 -267.126466) (xy 125.18644 -267.139928)
			(xy 125.03912 -267.393674) (xy 125.039628 -267.421614) (xy 125.04674 -267.433552) (xy 125.058285 -267.453132)
			(xy 125.076493 -267.494779) (xy 125.088841 -267.538524) (xy 125.095096 -267.583545) (xy 125.095508 -267.606272)
			(xy 125.094998 -267.632259) (xy 125.086868 -267.683594) (xy 125.070807 -267.733024) (xy 125.047211 -267.779334)
			(xy 125.016661 -267.821382) (xy 124.97991 -267.858133) (xy 124.937862 -267.888683) (xy 124.891552 -267.912279)
			(xy 124.842122 -267.92834) (xy 124.790787 -267.93647) (xy 124.738813 -267.93647) (xy 124.687478 -267.92834)
			(xy 124.638048 -267.912279) (xy 124.591738 -267.888683) (xy 124.54969 -267.858133) (xy 124.512939 -267.821382)
			(xy 124.482389 -267.779334) (xy 124.458793 -267.733024) (xy 124.442732 -267.683594) (xy 124.434602 -267.632259)
			(xy 124.434092 -267.606272) (xy 124.434346 -267.594588) (xy 124.434854 -267.58011) (xy 124.421392 -267.555726)
			(xy 123.571508 -267.067538) (xy 123.543568 -267.068046) (xy 123.53163 -267.07592) (xy 123.511698 -267.088031)
			(xy 123.469154 -267.10714) (xy 123.424347 -267.120082) (xy 123.378166 -267.1266) (xy 123.354846 -267.126974)
			(xy 123.328855 -267.126494) (xy 123.277513 -267.118369) (xy 123.228075 -267.10231) (xy 123.181758 -267.078714)
			(xy 123.139703 -267.048162) (xy 123.102946 -267.011407) (xy 123.072392 -266.969353) (xy 123.048795 -266.923036)
			(xy 123.032734 -266.873598) (xy 123.024607 -266.822257) (xy 123.024138 -266.796266) (xy 123.024547 -266.772908)
			(xy 123.031125 -266.726657) (xy 123.044132 -266.681788) (xy 123.06331 -266.63919) (xy 123.075446 -266.619228)
			(xy 123.08332 -266.607036) (xy 123.083828 -266.578842) (xy 122.939048 -266.329414) (xy 122.914156 -266.315952)
			(xy 122.899932 -266.316714) (xy 122.884692 -266.316968) (xy 122.861778 -266.316576) (xy 122.816389 -266.310238)
			(xy 122.772313 -266.297686) (xy 122.730395 -266.279161) (xy 122.710702 -266.267438) (xy 122.698764 -266.260072)
			(xy 122.670824 -266.259564) (xy 121.818654 -266.749022) (xy 121.804938 -266.773406) (xy 121.805446 -266.787376)
			(xy 121.805446 -266.796266) (xy 121.804939 -266.822256) (xy 121.796813 -266.873597) (xy 121.780755 -266.923034)
			(xy 121.757162 -266.969351) (xy 121.726613 -267.011407) (xy 121.689862 -267.048167) (xy 121.647813 -267.078724)
			(xy 121.601501 -267.102328) (xy 121.552067 -267.118396) (xy 121.500728 -267.126533) (xy 121.474738 -267.126974)
			(xy 121.464832 -267.12672) (xy 121.450862 -267.126466) (xy 121.426224 -267.139928) (xy 121.279158 -267.393674)
			(xy 121.279412 -267.421614) (xy 121.286778 -267.433552) (xy 121.298322 -267.453132) (xy 121.316528 -267.49478)
			(xy 121.328875 -267.538525) (xy 121.335129 -267.583546) (xy 121.335546 -267.606272) (xy 121.335036 -267.632259)
			(xy 121.326906 -267.683594) (xy 121.310845 -267.733024) (xy 121.287249 -267.779334) (xy 121.256699 -267.821382)
			(xy 121.219948 -267.858133) (xy 121.1779 -267.888683) (xy 121.13159 -267.912279) (xy 121.08216 -267.92834)
			(xy 121.030825 -267.93647) (xy 120.978851 -267.93647) (xy 120.927516 -267.92834) (xy 120.878086 -267.912279)
			(xy 120.831776 -267.888683) (xy 120.789728 -267.858133) (xy 120.752977 -267.821382) (xy 120.722427 -267.779334)
			(xy 120.698831 -267.733024) (xy 120.68277 -267.683594) (xy 120.67464 -267.632259) (xy 120.67413 -267.606272)
			(xy 120.674384 -267.594588) (xy 120.674892 -267.58011) (xy 120.66143 -267.555726) (xy 119.811292 -267.067538)
			(xy 119.783606 -267.068046) (xy 119.771414 -267.075666) (xy 119.751495 -267.087816) (xy 119.708963 -267.106998)
			(xy 119.664153 -267.119999) (xy 119.617959 -267.12656) (xy 119.59463 -267.126974) (xy 119.56864 -267.126493)
			(xy 119.5173 -267.118365) (xy 119.467864 -267.102305) (xy 119.421549 -267.078709) (xy 119.379496 -267.048156)
			(xy 119.342741 -267.011401) (xy 119.312189 -266.969348) (xy 119.288593 -266.923033) (xy 119.272534 -266.873596)
			(xy 119.264407 -266.822256) (xy 119.263922 -266.796266) (xy 119.264324 -266.772864) (xy 119.270918 -266.726527)
			(xy 119.283984 -266.681584) (xy 119.303261 -266.638934) (xy 119.315484 -266.618974) (xy 119.323104 -266.607036)
			(xy 119.323612 -266.578842) (xy 119.178832 -266.329414) (xy 119.154194 -266.315952) (xy 119.139716 -266.316714)
			(xy 119.12473 -266.316968) (xy 119.101783 -266.316596) (xy 119.056325 -266.310284) (xy 119.01218 -266.297734)
			(xy 118.970199 -266.27919) (xy 118.950486 -266.267438) (xy 118.938548 -266.260072) (xy 118.910608 -266.259564)
			(xy 118.058692 -266.749022) (xy 118.044976 -266.773406) (xy 118.045484 -266.787376) (xy 118.045484 -266.796266)
			(xy 118.045003 -266.822256) (xy 118.036876 -266.873598) (xy 118.020817 -266.923035) (xy 117.99722 -266.969351)
			(xy 117.966668 -267.011405) (xy 117.929913 -267.048162) (xy 117.88786 -267.078715) (xy 117.841544 -267.102313)
			(xy 117.792107 -267.118374) (xy 117.740766 -267.126503) (xy 117.714776 -267.126974) (xy 117.70487 -267.12672)
			(xy 117.6909 -267.126466) (xy 117.666262 -267.139928) (xy 117.519196 -267.393928) (xy 117.51945 -267.421868)
			(xy 117.526816 -267.433806) (xy 117.538329 -267.45336) (xy 117.556478 -267.49495) (xy 117.568766 -267.538631)
			(xy 117.574964 -267.583583) (xy 117.57533 -267.606272) (xy 117.57482 -267.632259) (xy 117.56669 -267.683594)
			(xy 117.550629 -267.733024) (xy 117.527033 -267.779334) (xy 117.496483 -267.821382) (xy 117.459732 -267.858133)
			(xy 117.417684 -267.888683) (xy 117.371374 -267.912279) (xy 117.321944 -267.92834) (xy 117.270609 -267.93647)
			(xy 117.218635 -267.93647) (xy 117.1673 -267.92834) (xy 117.11787 -267.912279) (xy 117.07156 -267.888683)
			(xy 117.029512 -267.858133) (xy 116.992761 -267.821382) (xy 116.962211 -267.779334) (xy 116.938615 -267.733024)
			(xy 116.922554 -267.683594) (xy 116.914424 -267.632259) (xy 116.913914 -267.606272) (xy 116.914168 -267.594334)
			(xy 116.914676 -267.58011) (xy 116.901214 -267.555726) (xy 116.05133 -267.067538) (xy 116.023644 -267.068046)
			(xy 116.011452 -267.075666) (xy 115.991533 -267.087818) (xy 115.949002 -267.107005) (xy 115.904192 -267.120011)
			(xy 115.857998 -267.126578) (xy 115.834668 -267.126974) (xy 115.808681 -267.126488) (xy 115.757349 -267.118353)
			(xy 115.707921 -267.102288) (xy 115.661614 -267.078688) (xy 115.61957 -267.048134) (xy 115.582823 -267.01138)
			(xy 115.552278 -266.969329) (xy 115.528687 -266.923018) (xy 115.512632 -266.873587) (xy 115.504506 -266.822253)
			(xy 115.50396 -266.796266) (xy 115.504362 -266.772864) (xy 115.510957 -266.726527) (xy 115.524024 -266.681585)
			(xy 115.543303 -266.638936) (xy 115.555522 -266.618974) (xy 115.563142 -266.607036) (xy 115.56365 -266.578842)
			(xy 115.41887 -266.329414) (xy 115.394232 -266.315952) (xy 115.379754 -266.316714) (xy 115.364768 -266.316968)
			(xy 115.34182 -266.316599) (xy 115.29636 -266.310291) (xy 115.252212 -266.297746) (xy 115.210229 -266.279205)
			(xy 115.190524 -266.267438) (xy 115.178586 -266.260072) (xy 115.150646 -266.259564) (xy 114.29873 -266.749022)
			(xy 114.285014 -266.773406) (xy 114.285522 -266.787376) (xy 114.285522 -266.796266) (xy 114.285041 -266.822257)
			(xy 114.276915 -266.873601) (xy 114.260855 -266.923041) (xy 114.23726 -266.96936) (xy 114.206708 -267.011417)
			(xy 114.169954 -267.048177) (xy 114.127901 -267.078735) (xy 114.081585 -267.102337) (xy 114.032148 -267.118403)
			(xy 113.980805 -267.126538) (xy 113.954814 -267.126974) (xy 113.929297 -267.126501) (xy 113.87887 -267.118661)
			(xy 113.830247 -267.103163) (xy 113.784583 -267.080378) (xy 113.742963 -267.050845) (xy 113.706376 -267.015268)
			(xy 113.675692 -266.97449) (xy 113.663222 -266.952222) (xy 113.656364 -266.939522) (xy 113.632488 -266.925298)
			(xy 111.185198 -266.925298) (xy 111.178597 -266.925524) (xy 111.16586 -266.929009) (xy 111.160052 -266.932156)
			(xy 110.074456 -267.555726) (xy 110.060994 -267.58011) (xy 110.061502 -267.594334) (xy 110.061756 -267.606272)
			(xy 110.061246 -267.632259) (xy 110.053116 -267.683594) (xy 110.037055 -267.733024) (xy 110.013459 -267.779334)
			(xy 109.982909 -267.821382) (xy 109.946158 -267.858133) (xy 109.90411 -267.888683) (xy 109.8578 -267.912279)
			(xy 109.80837 -267.92834) (xy 109.757035 -267.93647) (xy 109.705061 -267.93647) (xy 109.653726 -267.92834)
			(xy 109.604296 -267.912279) (xy 109.557986 -267.888683) (xy 109.515938 -267.858133) (xy 109.479187 -267.821382)
			(xy 109.448637 -267.779334) (xy 109.425041 -267.733024) (xy 109.40898 -267.683594) (xy 109.40085 -267.632259)
			(xy 109.40034 -267.606272) (xy 109.400709 -267.583541) (xy 109.406931 -267.538506) (xy 109.41928 -267.494754)
			(xy 109.437522 -267.453112) (xy 109.449108 -267.433552) (xy 109.45622 -267.421614) (xy 109.456728 -267.393674)
			(xy 109.309408 -267.139928) (xy 109.285024 -267.126466) (xy 109.271054 -267.12672) (xy 109.261148 -267.126974)
			(xy 109.235157 -267.126494) (xy 109.183815 -267.118369) (xy 109.134376 -267.102311) (xy 109.088059 -267.078715)
			(xy 109.046003 -267.048163) (xy 109.009246 -267.011407) (xy 108.978693 -266.969353) (xy 108.955095 -266.923037)
			(xy 108.939034 -266.873599) (xy 108.930907 -266.822257) (xy 108.93044 -266.796266) (xy 108.93044 -266.78763)
			(xy 108.930948 -266.773406) (xy 108.917232 -266.749022) (xy 108.065062 -266.259564) (xy 108.037122 -266.260072)
			(xy 108.025184 -266.267438) (xy 108.005464 -266.279174) (xy 107.963476 -266.297694) (xy 107.919335 -266.310242)
			(xy 107.873885 -266.31658) (xy 107.85094 -266.316968) (xy 107.835954 -266.316714) (xy 107.82173 -266.315952)
			(xy 107.796838 -266.329414) (xy 107.652058 -266.578842) (xy 107.652566 -266.607036) (xy 107.66044 -266.619228)
			(xy 107.67261 -266.639174) (xy 107.691818 -266.681766) (xy 107.704829 -266.726642) (xy 107.711381 -266.772904)
			(xy 107.711748 -266.796266) (xy 107.711241 -266.822256) (xy 107.703115 -266.873597) (xy 107.687057 -266.923035)
			(xy 107.663464 -266.969352) (xy 107.632916 -267.011408) (xy 107.596164 -267.048167) (xy 107.554115 -267.078725)
			(xy 107.507803 -267.102329) (xy 107.458369 -267.118398) (xy 107.40703 -267.126535) (xy 107.38104 -267.126974)
			(xy 107.357721 -267.126591) (xy 107.311541 -267.120074) (xy 107.266734 -267.107134) (xy 107.224189 -267.088029)
			(xy 107.204256 -267.07592) (xy 107.192318 -267.068046) (xy 107.164378 -267.067538) (xy 106.314494 -267.555726)
			(xy 106.301032 -267.58011) (xy 106.30154 -267.594588) (xy 106.301794 -267.606272) (xy 106.301284 -267.632259)
			(xy 106.293154 -267.683594) (xy 106.277093 -267.733024) (xy 106.253497 -267.779334) (xy 106.222947 -267.821382)
			(xy 106.186196 -267.858133) (xy 106.144148 -267.888683) (xy 106.097838 -267.912279) (xy 106.048408 -267.92834)
			(xy 105.997073 -267.93647) (xy 105.945099 -267.93647) (xy 105.893764 -267.92834) (xy 105.844334 -267.912279)
			(xy 105.798024 -267.888683) (xy 105.755976 -267.858133) (xy 105.719225 -267.821382) (xy 105.688675 -267.779334)
			(xy 105.665079 -267.733024) (xy 105.649018 -267.683594) (xy 105.640888 -267.632259) (xy 105.640378 -267.606272)
			(xy 105.640747 -267.583541) (xy 105.646968 -267.538506) (xy 105.659314 -267.494752) (xy 105.677554 -267.453108)
			(xy 105.689146 -267.433552) (xy 105.696258 -267.421614) (xy 105.696766 -267.393674) (xy 105.549446 -267.139928)
			(xy 105.525062 -267.126466) (xy 105.511092 -267.12672) (xy 105.500932 -267.126974) (xy 105.474942 -267.126493)
			(xy 105.423602 -267.118366) (xy 105.374165 -267.102306) (xy 105.32785 -267.078709) (xy 105.285797 -267.048157)
			(xy 105.249042 -267.011402) (xy 105.21849 -266.969348) (xy 105.194893 -266.923033) (xy 105.178834 -266.873596)
			(xy 105.170707 -266.822256) (xy 105.170224 -266.796266) (xy 105.170224 -266.787376) (xy 105.170732 -266.773406)
			(xy 105.157016 -266.749022) (xy 104.3051 -266.259564) (xy 104.27716 -266.260072) (xy 104.265222 -266.267438)
			(xy 104.245501 -266.279171) (xy 104.203512 -266.297682) (xy 104.159371 -266.310222) (xy 104.113922 -266.316551)
			(xy 104.090978 -266.316968) (xy 104.075992 -266.316714) (xy 104.061768 -266.315952) (xy 104.036876 -266.329414)
			(xy 103.892096 -266.578842) (xy 103.892604 -266.607036) (xy 103.900478 -266.619228) (xy 103.91265 -266.639173)
			(xy 103.931862 -266.681765) (xy 103.944875 -266.726641) (xy 103.951428 -266.772903) (xy 103.951786 -266.796266)
			(xy 103.951305 -266.822256) (xy 103.943178 -266.873598) (xy 103.927119 -266.923035) (xy 103.903522 -266.969352)
			(xy 103.87297 -267.011406) (xy 103.836215 -267.048163) (xy 103.794162 -267.078716) (xy 103.747847 -267.102314)
			(xy 103.698409 -267.118375) (xy 103.647068 -267.126504) (xy 103.621078 -267.126974) (xy 103.597829 -267.126603)
			(xy 103.551785 -267.120131) (xy 103.507105 -267.10726) (xy 103.464673 -267.088247) (xy 103.444802 -267.076174)
			(xy 103.43261 -267.0683) (xy 103.40467 -267.067792) (xy 102.741476 -267.450316) (xy 102.726785 -267.458165)
			(xy 102.694623 -267.466775) (xy 102.677976 -267.467334) (xy 102.27945 -267.467334) (xy 102.262877 -267.466765)
			(xy 102.230868 -267.458149) (xy 102.202165 -267.441566) (xy 102.190042 -267.43025) (xy 101.876098 -267.116052)
			(xy 101.84892 -267.109194) (xy 101.835458 -267.113258) (xy 101.812365 -267.119675) (xy 101.764934 -267.126556)
			(xy 101.74097 -267.126974) (xy 101.714983 -267.126489) (xy 101.66365 -267.118353) (xy 101.614222 -267.102288)
			(xy 101.567915 -267.078688) (xy 101.525871 -267.048135) (xy 101.489123 -267.01138) (xy 101.458578 -266.96933)
			(xy 101.434987 -266.923019) (xy 101.418932 -266.873587) (xy 101.410806 -266.822253) (xy 101.410262 -266.796266)
			(xy 101.410262 -266.787376) (xy 101.41077 -266.773152) (xy 101.397054 -266.749022) (xy 100.545138 -266.259564)
			(xy 100.517198 -266.260072) (xy 100.50526 -266.267438) (xy 100.485539 -266.279173) (xy 100.443552 -266.297689)
			(xy 100.399411 -266.310234) (xy 100.353961 -266.316569) (xy 100.331016 -266.316968) (xy 100.316284 -266.316714)
			(xy 100.30206 -266.315952) (xy 100.277168 -266.329668) (xy 100.132388 -266.579096) (xy 100.132896 -266.60729)
			(xy 100.140516 -266.619482) (xy 100.152668 -266.639401) (xy 100.171853 -266.681932) (xy 100.184857 -266.726742)
			(xy 100.19142 -266.772937) (xy 100.191824 -266.796266) (xy 100.191343 -266.822257) (xy 100.183217 -266.873601)
			(xy 100.167157 -266.923041) (xy 100.143562 -266.96936) (xy 100.11301 -267.011418) (xy 100.076256 -267.048178)
			(xy 100.034203 -267.078736) (xy 99.987887 -267.102338) (xy 99.93845 -267.118405) (xy 99.887107 -267.12654)
			(xy 99.861116 -267.126974) (xy 99.84613 -267.12672) (xy 99.831906 -267.125958) (xy 99.807268 -267.13942)
			(xy 99.64801 -267.41374) (xy 99.64801 -267.440918) (xy 99.654868 -267.452856) (xy 99.667859 -267.476317)
			(xy 99.686312 -267.526667) (xy 99.695711 -267.579461) (xy 99.69627 -267.606272) (xy 99.695826 -267.630265)
			(xy 99.688322 -267.677662) (xy 99.673496 -267.723301) (xy 99.651711 -267.766058) (xy 99.623506 -267.804881)
			(xy 99.589573 -267.838812) (xy 99.55075 -267.867017) (xy 99.507992 -267.8888) (xy 99.462352 -267.903625)
			(xy 99.414956 -267.911127) (xy 99.390962 -267.91158) (xy 99.364472 -267.911011) (xy 99.312288 -267.901866)
			(xy 99.262464 -267.883855) (xy 99.216494 -267.857519) (xy 99.175756 -267.823648) (xy 99.141471 -267.783257)
			(xy 99.127564 -267.760704) (xy 99.120706 -267.74902) (xy 99.097338 -267.735812) (xy 98.773234 -267.735812)
			(xy 98.749358 -267.750036) (xy 98.742754 -267.762482) (xy 98.730281 -267.784731) (xy 98.699555 -267.825441)
			(xy 98.662946 -267.860956) (xy 98.621322 -267.890432) (xy 98.575668 -267.913173) (xy 98.527065 -267.928639)
			(xy 98.476664 -267.936465) (xy 98.42566 -267.936465) (xy 98.375259 -267.928639) (xy 98.326656 -267.913173)
			(xy 98.281002 -267.890432) (xy 98.239378 -267.860956) (xy 98.202769 -267.825441) (xy 98.172043 -267.784731)
			(xy 98.15957 -267.762482) (xy 98.152966 -267.750036) (xy 98.12909 -267.735812) (xy 97.804732 -267.735812)
			(xy 97.781364 -267.74902) (xy 97.774506 -267.760704) (xy 97.760626 -267.783257) (xy 97.726373 -267.82364)
			(xy 97.685682 -267.857525) (xy 97.663 -267.871194) (xy 97.653856 -267.876528) (xy 97.641156 -267.893292)
			(xy 97.61982 -267.986764) (xy 97.62363 -268.007338) (xy 97.629726 -268.016228) (xy 97.649255 -268.045766)
			(xy 97.683023 -268.10801) (xy 97.710445 -268.173298) (xy 97.731251 -268.240987) (xy 97.745234 -268.310406)
			(xy 97.752256 -268.380871) (xy 97.752662 -268.416278) (xy 97.752192 -268.453552) (xy 97.744401 -268.527692)
			(xy 97.728903 -268.600612) (xy 97.705867 -268.671512) (xy 97.675546 -268.739616) (xy 97.638272 -268.804176)
			(xy 97.594453 -268.864487) (xy 97.54457 -268.919887) (xy 97.489168 -268.969768) (xy 97.428856 -269.013585)
			(xy 97.364294 -269.050857) (xy 97.29619 -269.081176) (xy 97.225289 -269.104209) (xy 97.152369 -269.119705)
			(xy 97.078228 -269.127493) (xy 97.040954 -269.127986) (xy 97.007934 -269.127224) (xy 96.99752 -269.126716)
			(xy 96.978216 -269.133828) (xy 96.90989 -269.198852) (xy 96.901762 -269.217648) (xy 96.901762 -269.228062)
			(xy 96.901217 -269.251393) (xy 96.894373 -269.297555) (xy 96.881114 -269.342299) (xy 96.8617 -269.384736)
			(xy 96.849438 -269.404592) (xy 96.841818 -269.416784) (xy 96.841056 -269.444978) (xy 96.985074 -269.69339)
			(xy 97.009966 -269.706852) (xy 97.02419 -269.70609) (xy 97.040954 -269.705582) (xy 97.066946 -269.706062)
			(xy 97.118291 -269.714187) (xy 97.167732 -269.730245) (xy 97.214052 -269.75384) (xy 97.256111 -269.784392)
			(xy 97.292872 -269.821146) (xy 97.32343 -269.8632) (xy 97.347033 -269.909516) (xy 97.3631 -269.958955)
			(xy 97.371234 -270.010298) (xy 97.371662 -270.03629) (xy 97.371226 -270.059845) (xy 97.364505 -270.106473)
			(xy 97.351239 -270.151676) (xy 97.331698 -270.194542) (xy 97.319338 -270.214598) (xy 97.311464 -270.22679)
			(xy 97.310956 -270.254984) (xy 97.454974 -270.503396) (xy 97.479612 -270.516858) (xy 97.49409 -270.516096)
			(xy 97.511108 -270.515588) (xy 97.537095 -270.516098) (xy 97.588429 -270.52423) (xy 97.637859 -270.540292)
			(xy 97.684168 -270.563888) (xy 97.726216 -270.594439) (xy 97.762967 -270.63119) (xy 97.793516 -270.673239)
			(xy 97.817111 -270.719548) (xy 97.833172 -270.768979) (xy 97.841302 -270.820313) (xy 97.841302 -270.872287)
			(xy 97.833172 -270.923621) (xy 97.817111 -270.973052) (xy 97.793516 -271.019361) (xy 97.762967 -271.06141)
			(xy 97.726216 -271.098161) (xy 97.684168 -271.128712) (xy 97.637859 -271.152308) (xy 97.588429 -271.16837)
			(xy 97.537095 -271.176502) (xy 97.511108 -271.177004) (xy 97.496122 -271.17675) (xy 97.481898 -271.175988)
			(xy 97.45726 -271.18945) (xy 97.312226 -271.439132) (xy 97.312734 -271.46758) (xy 97.320354 -271.479518)
			(xy 97.332502 -271.499438) (xy 97.351681 -271.54197) (xy 97.364678 -271.58678) (xy 97.371235 -271.632974)
			(xy 97.371662 -271.656302) (xy 97.371179 -271.68229) (xy 97.363047 -271.733625) (xy 97.346984 -271.783057)
			(xy 97.323385 -271.829366) (xy 97.292832 -271.871414) (xy 97.256077 -271.908163) (xy 97.214025 -271.93871)
			(xy 97.167712 -271.962302) (xy 97.118279 -271.978358) (xy 97.066942 -271.986482) (xy 97.040954 -271.98701)
			(xy 97.026222 -271.986756) (xy 97.011998 -271.985994) (xy 96.98736 -271.99971) (xy 96.842326 -272.249392)
			(xy 96.843088 -272.277586) (xy 96.850708 -272.289524) (xy 96.862816 -272.309457) (xy 96.881919 -272.352002)
			(xy 96.894854 -272.396809) (xy 96.901364 -272.442989) (xy 96.901762 -272.466308) (xy 96.901324 -272.489862)
			(xy 96.894601 -272.536489) (xy 96.881334 -272.581692) (xy 96.861791 -272.624556) (xy 96.849438 -272.644616)
			(xy 96.841818 -272.656808) (xy 96.841056 -272.685002) (xy 96.985074 -272.933414) (xy 97.009966 -272.946876)
			(xy 97.02419 -272.946114) (xy 97.040954 -272.945606) (xy 97.066945 -272.946086) (xy 97.118289 -272.954211)
			(xy 97.167728 -272.97027) (xy 97.214047 -272.993865) (xy 97.256104 -273.024417) (xy 97.292862 -273.061172)
			(xy 97.323418 -273.103226) (xy 97.347018 -273.149542) (xy 97.363081 -273.19898) (xy 97.371212 -273.250323)
			(xy 97.371662 -273.276314) (xy 97.371224 -273.299868) (xy 97.3645 -273.346495) (xy 97.351232 -273.391697)
			(xy 97.331689 -273.434561) (xy 97.319338 -273.454622) (xy 97.311464 -273.466814) (xy 97.310956 -273.495008)
			(xy 97.454974 -273.74342) (xy 97.479612 -273.756882) (xy 97.49409 -273.75612) (xy 97.511108 -273.755612)
			(xy 97.537093 -273.756122) (xy 97.588424 -273.764253) (xy 97.63785 -273.780314) (xy 97.684156 -273.803909)
			(xy 97.7262 -273.834457) (xy 97.762948 -273.871206) (xy 97.793495 -273.913251) (xy 97.817089 -273.959557)
			(xy 97.833149 -274.008984) (xy 97.841279 -274.060315) (xy 97.841279 -274.112285) (xy 97.833149 -274.163616)
			(xy 97.817089 -274.213043) (xy 97.793495 -274.259349) (xy 97.762948 -274.301394) (xy 97.7262 -274.338143)
			(xy 97.684156 -274.368691) (xy 97.63785 -274.392286) (xy 97.588424 -274.408347) (xy 97.537093 -274.416478)
			(xy 97.511108 -274.417028) (xy 97.496122 -274.416774) (xy 97.481898 -274.416012) (xy 97.45726 -274.429474)
			(xy 97.312226 -274.679156) (xy 97.312734 -274.707604) (xy 97.320354 -274.719542) (xy 97.332507 -274.73946)
			(xy 97.351695 -274.781992) (xy 97.364703 -274.826801) (xy 97.37127 -274.872996) (xy 97.371662 -274.896326)
			(xy 97.371177 -274.922313) (xy 97.363042 -274.973645) (xy 97.346977 -275.023073) (xy 97.323377 -275.06938)
			(xy 97.292824 -275.111424) (xy 97.256069 -275.148171) (xy 97.214018 -275.178715) (xy 97.167707 -275.202305)
			(xy 97.118275 -275.218359) (xy 97.066941 -275.226483) (xy 97.040954 -275.227034) (xy 97.026222 -275.22678)
			(xy 97.011998 -275.226018) (xy 96.98736 -275.239734) (xy 96.842326 -275.489416) (xy 96.843088 -275.51761)
			(xy 96.850708 -275.529548) (xy 96.862821 -275.549479) (xy 96.881933 -275.592023) (xy 96.894879 -275.63683)
			(xy 96.9014 -275.683012) (xy 96.901762 -275.706332) (xy 96.901323 -275.729886) (xy 96.894596 -275.776511)
			(xy 96.881326 -275.821712) (xy 96.861781 -275.864574) (xy 96.849438 -275.88464) (xy 96.841818 -275.896832)
			(xy 96.841056 -275.925026) (xy 96.985074 -276.173438) (xy 97.009966 -276.1869) (xy 97.02419 -276.186138)
			(xy 97.040954 -276.18563) (xy 97.066945 -276.18611) (xy 97.118286 -276.194235) (xy 97.167725 -276.210294)
			(xy 97.214042 -276.23389) (xy 97.256096 -276.264442) (xy 97.292853 -276.301198) (xy 97.323406 -276.343252)
			(xy 97.347003 -276.389568) (xy 97.363063 -276.439006) (xy 97.37119 -276.490347) (xy 97.371662 -276.516338)
			(xy 97.371222 -276.539892) (xy 97.364495 -276.586517) (xy 97.351224 -276.631717) (xy 97.331679 -276.674579)
			(xy 97.319338 -276.694646) (xy 97.311464 -276.706838) (xy 97.310956 -276.735032) (xy 97.454974 -276.983444)
			(xy 97.479612 -276.996906) (xy 97.49409 -276.996144) (xy 97.511108 -276.995636) (xy 97.537091 -276.996146)
			(xy 97.588418 -277.004277) (xy 97.637841 -277.020336) (xy 97.684143 -277.04393) (xy 97.726184 -277.074475)
			(xy 97.76293 -277.111222) (xy 97.793475 -277.153264) (xy 97.817067 -277.199567) (xy 97.833125 -277.24899)
			(xy 97.841254 -277.300317) (xy 97.841254 -277.352283) (xy 97.833125 -277.40361) (xy 97.817067 -277.453033)
			(xy 97.793475 -277.499336) (xy 97.76293 -277.541378) (xy 97.726184 -277.578125) (xy 97.684143 -277.60867)
			(xy 97.637841 -277.632264) (xy 97.588418 -277.648323) (xy 97.537091 -277.656454) (xy 97.511108 -277.657052)
			(xy 97.496122 -277.656798) (xy 97.481898 -277.656036) (xy 97.45726 -277.669498) (xy 97.312226 -277.91918)
			(xy 97.312734 -277.947628) (xy 97.320354 -277.959566) (xy 97.332506 -277.979485) (xy 97.351691 -278.022016)
			(xy 97.364695 -278.066826) (xy 97.371259 -278.113021) (xy 97.371662 -278.13635) (xy 97.371183 -278.162341)
			(xy 97.363057 -278.213682) (xy 97.346999 -278.263121) (xy 97.323403 -278.309438) (xy 97.292851 -278.351492)
			(xy 97.256095 -278.388248) (xy 97.214041 -278.418801) (xy 97.167724 -278.442397) (xy 97.118286 -278.458456)
			(xy 97.066945 -278.466582) (xy 97.040954 -278.467058) (xy 97.026222 -278.466804) (xy 97.011998 -278.466042)
			(xy 96.98736 -278.479758) (xy 96.842326 -278.72944) (xy 96.843088 -278.757634) (xy 96.850708 -278.769572)
			(xy 96.862819 -278.789504) (xy 96.881929 -278.832048) (xy 96.894871 -278.876855) (xy 96.901388 -278.923036)
			(xy 96.901762 -278.946356) (xy 96.901508 -278.961342) (xy 96.900746 -278.97582) (xy 96.914208 -279.000458)
			(xy 97.761298 -279.487122) (xy 97.789492 -279.48636) (xy 97.801684 -279.478486) (xy 97.82182 -279.465974)
			(xy 97.864913 -279.446218) (xy 97.910385 -279.432818) (xy 97.957305 -279.426049) (xy 97.981008 -279.425654)
			(xy 98.006998 -279.426164) (xy 98.058337 -279.434297) (xy 98.107772 -279.45036) (xy 98.154086 -279.473959)
			(xy 98.196138 -279.504513) (xy 98.232893 -279.541268) (xy 98.263445 -279.583321) (xy 98.287043 -279.629635)
			(xy 98.303105 -279.679071) (xy 98.311236 -279.73041) (xy 98.311236 -279.78239) (xy 98.303105 -279.833729)
			(xy 98.287043 -279.883165) (xy 98.263445 -279.929479) (xy 98.232893 -279.971532) (xy 98.196138 -280.008287)
			(xy 98.154086 -280.038841) (xy 98.107772 -280.06244) (xy 98.058337 -280.078503) (xy 98.006998 -280.086636)
			(xy 97.981008 -280.08707) (xy 97.966022 -280.086816) (xy 97.951798 -280.086054) (xy 97.92716 -280.099516)
			(xy 97.78238 -280.349198) (xy 97.782888 -280.377392) (xy 97.790508 -280.389584) (xy 97.80266 -280.409502)
			(xy 97.821846 -280.452034) (xy 97.834849 -280.496844) (xy 97.841412 -280.543039) (xy 97.841816 -280.566368)
			(xy 97.841335 -280.592359) (xy 97.833208 -280.643702) (xy 97.817149 -280.693141) (xy 97.793553 -280.73946)
			(xy 97.763001 -280.781516) (xy 97.726247 -280.818275) (xy 97.684194 -280.848832) (xy 97.637878 -280.872433)
			(xy 97.588441 -280.888499) (xy 97.537099 -280.896632) (xy 97.511108 -280.897076) (xy 97.496376 -280.896822)
			(xy 97.481898 -280.89606) (xy 97.45726 -280.909522) (xy 97.312226 -281.159458) (xy 97.312988 -281.187652)
			(xy 97.320608 -281.19959) (xy 97.332718 -281.219522) (xy 97.351825 -281.262067) (xy 97.364765 -281.306874)
			(xy 97.37128 -281.353055) (xy 97.371662 -281.376374) (xy 97.371662 -281.3764) (xy 97.674859 -281.3764)
			(xy 97.679035 -281.32601) (xy 97.691448 -281.276995) (xy 97.711759 -281.230691) (xy 97.739414 -281.188362)
			(xy 97.77366 -281.151162) (xy 97.813561 -281.120107) (xy 97.85803 -281.096042) (xy 97.905853 -281.079626)
			(xy 97.955727 -281.071304) (xy 97.981008 -281.070812) (xy 98.921062 -281.070812) (xy 98.946341 -281.071354)
			(xy 98.996209 -281.07967) (xy 99.044029 -281.096081) (xy 99.088494 -281.12014) (xy 99.128393 -281.15119)
			(xy 99.162637 -281.188384) (xy 99.190291 -281.230707) (xy 99.210601 -281.277006) (xy 99.223013 -281.326016)
			(xy 99.227189 -281.3764) (xy 100.495088 -281.3764) (xy 100.499263 -281.326019) (xy 100.511672 -281.277012)
			(xy 100.531978 -281.230715) (xy 100.559627 -281.188392) (xy 100.593865 -281.151197) (xy 100.633757 -281.120144)
			(xy 100.678216 -281.09608) (xy 100.72603 -281.079662) (xy 100.775893 -281.071336) (xy 100.80117 -281.070812)
			(xy 101.741224 -281.070812) (xy 101.766497 -281.071388) (xy 101.816353 -281.079711) (xy 101.864159 -281.096126)
			(xy 101.908611 -281.120186) (xy 101.948498 -281.151233) (xy 101.98273 -281.188422) (xy 102.010375 -281.230738)
			(xy 102.030678 -281.277027) (xy 102.043086 -281.326027) (xy 102.04726 -281.3764) (xy 122.108688 -281.3764)
			(xy 122.112863 -281.326017) (xy 122.125274 -281.277007) (xy 122.145582 -281.230709) (xy 122.173233 -281.188385)
			(xy 122.207473 -281.151189) (xy 122.247369 -281.120136) (xy 122.291831 -281.096074) (xy 122.339648 -281.079657)
			(xy 122.389514 -281.071335) (xy 122.414792 -281.070812) (xy 123.354846 -281.070812) (xy 123.380118 -281.071389)
			(xy 123.429971 -281.079715) (xy 123.477774 -281.096133) (xy 123.522223 -281.120193) (xy 123.562106 -281.151241)
			(xy 123.596336 -281.18843) (xy 123.623978 -281.230745) (xy 123.64428 -281.277032) (xy 123.656686 -281.326029)
			(xy 123.66086 -281.3764) (xy 124.928589 -281.3764) (xy 124.932763 -281.326016) (xy 124.945174 -281.277006)
			(xy 124.965483 -281.230707) (xy 124.993135 -281.188382) (xy 125.027376 -281.151186) (xy 125.067273 -281.120134)
			(xy 125.111736 -281.096071) (xy 125.159554 -281.079655) (xy 125.209422 -281.071334) (xy 125.2347 -281.070812)
			(xy 126.174754 -281.070812) (xy 126.200033 -281.071353) (xy 126.249903 -281.079668) (xy 126.297723 -281.096079)
			(xy 126.34219 -281.120137) (xy 126.38209 -281.151187) (xy 126.416335 -281.188381) (xy 126.44399 -281.230705)
			(xy 126.464301 -281.277004) (xy 126.476713 -281.326015) (xy 126.480889 -281.3764) (xy 126.476713 -281.426785)
			(xy 126.464301 -281.475796) (xy 126.44399 -281.522095) (xy 126.416335 -281.564419) (xy 126.38209 -281.601613)
			(xy 126.34219 -281.632663) (xy 126.297723 -281.656721) (xy 126.249903 -281.673132) (xy 126.200033 -281.681447)
			(xy 126.174754 -281.681936) (xy 125.2347 -281.681936) (xy 125.209422 -281.681466) (xy 125.159554 -281.673145)
			(xy 125.111736 -281.656729) (xy 125.067273 -281.632666) (xy 125.027376 -281.601614) (xy 124.993135 -281.564418)
			(xy 124.965483 -281.522093) (xy 124.945174 -281.475794) (xy 124.932763 -281.426784) (xy 124.928589 -281.3764)
			(xy 123.66086 -281.3764) (xy 123.656686 -281.426771) (xy 123.64428 -281.475768) (xy 123.623978 -281.522055)
			(xy 123.596336 -281.56437) (xy 123.562106 -281.601559) (xy 123.522223 -281.632607) (xy 123.477774 -281.656667)
			(xy 123.429971 -281.673085) (xy 123.380118 -281.681411) (xy 123.354846 -281.681936) (xy 122.414792 -281.681936)
			(xy 122.389514 -281.681465) (xy 122.339648 -281.673143) (xy 122.291831 -281.656726) (xy 122.247369 -281.632664)
			(xy 122.207473 -281.601611) (xy 122.173233 -281.564415) (xy 122.145582 -281.522091) (xy 122.125274 -281.475793)
			(xy 122.112863 -281.426783) (xy 122.108688 -281.3764) (xy 102.04726 -281.3764) (xy 102.043086 -281.426773)
			(xy 102.030678 -281.475773) (xy 102.010375 -281.522062) (xy 101.98273 -281.564378) (xy 101.948498 -281.601567)
			(xy 101.908611 -281.632614) (xy 101.864159 -281.656674) (xy 101.816353 -281.673089) (xy 101.766497 -281.681412)
			(xy 101.741224 -281.681936) (xy 100.80117 -281.681936) (xy 100.775893 -281.681464) (xy 100.72603 -281.673138)
			(xy 100.678216 -281.65672) (xy 100.633757 -281.632656) (xy 100.593865 -281.601603) (xy 100.559627 -281.564408)
			(xy 100.531978 -281.522085) (xy 100.511672 -281.475788) (xy 100.499263 -281.426781) (xy 100.495088 -281.3764)
			(xy 99.227189 -281.3764) (xy 99.223013 -281.426784) (xy 99.210601 -281.475794) (xy 99.190291 -281.522093)
			(xy 99.162637 -281.564416) (xy 99.128393 -281.60161) (xy 99.088494 -281.63266) (xy 99.044029 -281.656719)
			(xy 98.996209 -281.67313) (xy 98.946341 -281.681446) (xy 98.921062 -281.681936) (xy 97.981008 -281.681936)
			(xy 97.955727 -281.681496) (xy 97.905853 -281.673174) (xy 97.85803 -281.656758) (xy 97.813561 -281.632693)
			(xy 97.77366 -281.601638) (xy 97.739414 -281.564438) (xy 97.711759 -281.522109) (xy 97.691448 -281.475805)
			(xy 97.679035 -281.42679) (xy 97.674859 -281.3764) (xy 97.371662 -281.3764) (xy 97.371227 -281.399929)
			(xy 97.364508 -281.446558) (xy 97.351244 -281.491763) (xy 97.331705 -281.53463) (xy 97.319338 -281.554682)
			(xy 97.311718 -281.566874) (xy 97.310956 -281.595068) (xy 97.454974 -281.84348) (xy 97.479612 -281.856942)
			(xy 97.494344 -281.85618) (xy 97.511108 -281.855672) (xy 97.537096 -281.856182) (xy 97.588433 -281.864314)
			(xy 97.637865 -281.880377) (xy 97.684177 -281.903975) (xy 97.726226 -281.934526) (xy 97.762979 -281.97128)
			(xy 97.79353 -282.01333) (xy 97.817126 -282.059642) (xy 97.833188 -282.109075) (xy 97.841318 -282.160412)
			(xy 97.841318 -282.1864) (xy 108.485149 -282.1864) (xy 108.48932 -282.136059) (xy 108.50172 -282.087092)
			(xy 108.522011 -282.040833) (xy 108.549639 -281.998544) (xy 108.58385 -281.96138) (xy 108.623712 -281.930354)
			(xy 108.668137 -281.906312) (xy 108.715913 -281.889909) (xy 108.765737 -281.881594) (xy 108.790994 -281.881072)
			(xy 109.731048 -281.881072) (xy 109.756299 -281.881637) (xy 109.806111 -281.889957) (xy 109.853875 -281.906361)
			(xy 109.898288 -281.930402) (xy 109.938139 -281.961425) (xy 109.97234 -281.998583) (xy 109.99996 -282.040863)
			(xy 110.020245 -282.087113) (xy 110.032641 -282.13607) (xy 110.036811 -282.1864) (xy 114.11882 -282.1864)
			(xy 114.122992 -282.136052) (xy 114.135394 -282.087078) (xy 114.155689 -282.040813) (xy 114.183321 -281.99852)
			(xy 114.217539 -281.961352) (xy 114.257407 -281.930323) (xy 114.301839 -281.906279) (xy 114.349622 -281.889877)
			(xy 114.399454 -281.881564) (xy 114.424714 -281.881072) (xy 115.364768 -281.881072) (xy 115.390026 -281.881602)
			(xy 115.439853 -281.889912) (xy 115.487633 -281.90631) (xy 115.532062 -281.93035) (xy 115.571927 -281.961375)
			(xy 115.606142 -281.998539) (xy 115.633773 -282.040827) (xy 115.654067 -282.087088) (xy 115.666468 -282.136057)
			(xy 115.67064 -282.1864) (xy 115.666468 -282.236743) (xy 115.654067 -282.285712) (xy 115.633773 -282.331973)
			(xy 115.606142 -282.374261) (xy 115.571927 -282.411425) (xy 115.532062 -282.44245) (xy 115.487633 -282.46649)
			(xy 115.439853 -282.482888) (xy 115.390026 -282.491198) (xy 115.364768 -282.491688) (xy 114.424714 -282.491688)
			(xy 114.399454 -282.491236) (xy 114.349622 -282.482923) (xy 114.301839 -282.466521) (xy 114.257407 -282.442477)
			(xy 114.217539 -282.411448) (xy 114.183321 -282.37428) (xy 114.155689 -282.331987) (xy 114.135394 -282.285722)
			(xy 114.122992 -282.236748) (xy 114.11882 -282.1864) (xy 110.036811 -282.1864) (xy 110.032641 -282.23673)
			(xy 110.020245 -282.285687) (xy 109.99996 -282.331937) (xy 109.97234 -282.374217) (xy 109.938139 -282.411375)
			(xy 109.898288 -282.442398) (xy 109.853875 -282.466439) (xy 109.806111 -282.482843) (xy 109.756299 -282.491163)
			(xy 109.731048 -282.491688) (xy 108.790994 -282.491688) (xy 108.765737 -282.491206) (xy 108.715913 -282.482891)
			(xy 108.668137 -282.466488) (xy 108.623712 -282.442446) (xy 108.58385 -282.41142) (xy 108.549639 -282.374256)
			(xy 108.522011 -282.331967) (xy 108.50172 -282.285708) (xy 108.48932 -282.236741) (xy 108.485149 -282.1864)
			(xy 97.841318 -282.1864) (xy 97.841318 -282.212388) (xy 97.833188 -282.263725) (xy 97.817126 -282.313158)
			(xy 97.79353 -282.35947) (xy 97.762979 -282.40152) (xy 97.726226 -282.438274) (xy 97.684177 -282.468825)
			(xy 97.637865 -282.492423) (xy 97.588433 -282.508486) (xy 97.537096 -282.516618) (xy 97.511108 -282.517088)
			(xy 97.496122 -282.516834) (xy 97.481898 -282.516072) (xy 97.45726 -282.529534) (xy 97.312226 -282.779216)
			(xy 97.312734 -282.807664) (xy 97.320354 -282.819602) (xy 97.332503 -282.839521) (xy 97.351684 -282.882054)
			(xy 97.364683 -282.926863) (xy 97.371242 -282.973057) (xy 97.371662 -282.996386) (xy 97.371662 -282.9964)
			(xy 97.674871 -282.9964) (xy 97.679047 -282.946012) (xy 97.691459 -282.896999) (xy 97.711769 -282.850697)
			(xy 97.739424 -282.808369) (xy 97.773668 -282.771171) (xy 97.813568 -282.740117) (xy 97.858035 -282.716053)
			(xy 97.905856 -282.699637) (xy 97.955728 -282.691316) (xy 97.981008 -282.690824) (xy 98.921062 -282.690824)
			(xy 98.946342 -282.691342) (xy 98.996212 -282.699658) (xy 99.044033 -282.71607) (xy 99.088501 -282.74013)
			(xy 99.128401 -282.771181) (xy 99.162646 -282.808377) (xy 99.190302 -282.850702) (xy 99.210613 -282.897002)
			(xy 99.223025 -282.946014) (xy 99.227201 -282.9964) (xy 100.4951 -282.9964) (xy 100.499275 -282.946021)
			(xy 100.511684 -282.897016) (xy 100.531989 -282.850721) (xy 100.559637 -282.8084) (xy 100.593873 -282.771206)
			(xy 100.633764 -282.740154) (xy 100.678221 -282.716091) (xy 100.726032 -282.699673) (xy 100.775894 -282.691348)
			(xy 100.80117 -282.690824) (xy 101.741224 -282.690824) (xy 101.766498 -282.691376) (xy 101.816356 -282.699699)
			(xy 101.864164 -282.716115) (xy 101.908618 -282.740176) (xy 101.948506 -282.771224) (xy 101.98274 -282.808415)
			(xy 102.010385 -282.850733) (xy 102.030689 -282.897024) (xy 102.043098 -282.946025) (xy 102.047272 -282.9964)
			(xy 103.315 -282.9964) (xy 103.319175 -282.94602) (xy 103.331584 -282.897014) (xy 103.35189 -282.850719)
			(xy 103.379539 -282.808397) (xy 103.413776 -282.771203) (xy 103.453668 -282.740151) (xy 103.498126 -282.716089)
			(xy 103.545939 -282.699672) (xy 103.595802 -282.691348) (xy 103.621078 -282.690824) (xy 104.561132 -282.690824)
			(xy 104.586405 -282.691376) (xy 104.636262 -282.699701) (xy 104.684069 -282.716117) (xy 104.728522 -282.740178)
			(xy 104.768409 -282.771227) (xy 104.802642 -282.808418) (xy 104.830287 -282.850735) (xy 104.85059 -282.897025)
			(xy 104.862998 -282.946026) (xy 104.867172 -282.9964) (xy 106.1349 -282.9964) (xy 106.139075 -282.946019)
			(xy 106.151485 -282.897012) (xy 106.171791 -282.850717) (xy 106.199441 -282.808394) (xy 106.233679 -282.7712)
			(xy 106.273572 -282.740149) (xy 106.318032 -282.716086) (xy 106.365846 -282.69967) (xy 106.415709 -282.691347)
			(xy 106.440986 -282.690824) (xy 107.38104 -282.690824) (xy 107.406313 -282.691377) (xy 107.456169 -282.699702)
			(xy 107.503975 -282.71612) (xy 107.548426 -282.740181) (xy 107.588312 -282.77123) (xy 107.622544 -282.80842)
			(xy 107.650188 -282.850737) (xy 107.67049 -282.897027) (xy 107.682898 -282.946026) (xy 107.687072 -282.9964)
			(xy 116.468571 -282.9964) (xy 116.472747 -282.946011) (xy 116.48516 -282.896996) (xy 116.505471 -282.850693)
			(xy 116.533127 -282.808365) (xy 116.567373 -282.771166) (xy 116.607275 -282.740112) (xy 116.651744 -282.716049)
			(xy 116.699568 -282.699634) (xy 116.749441 -282.691315) (xy 116.774722 -282.690824) (xy 117.714776 -282.690824)
			(xy 117.740055 -282.691343) (xy 117.789924 -282.699661) (xy 117.837743 -282.716074) (xy 117.882208 -282.740135)
			(xy 117.922107 -282.771186) (xy 117.95635 -282.808381) (xy 117.984004 -282.850706) (xy 118.004313 -282.897005)
			(xy 118.016725 -282.946015) (xy 118.020901 -282.9964) (xy 119.288471 -282.9964) (xy 119.292647 -282.94601)
			(xy 119.30506 -282.896994) (xy 119.325373 -282.850691) (xy 119.353029 -282.808362) (xy 119.387276 -282.771163)
			(xy 119.427179 -282.740109) (xy 119.47165 -282.716047) (xy 119.519474 -282.699633) (xy 119.569348 -282.691315)
			(xy 119.59463 -282.690824) (xy 120.534684 -282.690824) (xy 120.559962 -282.691344) (xy 120.60983 -282.699663)
			(xy 120.657648 -282.716077) (xy 120.702113 -282.740137) (xy 120.74201 -282.771189) (xy 120.776252 -282.808384)
			(xy 120.803905 -282.850708) (xy 120.824214 -282.897006) (xy 120.836625 -282.946016) (xy 120.840801 -282.9964)
			(xy 122.1087 -282.9964) (xy 122.112875 -282.946019) (xy 122.125285 -282.897011) (xy 122.145592 -282.850715)
			(xy 122.173242 -282.808392) (xy 122.207481 -282.771198) (xy 122.247375 -282.740147) (xy 122.291836 -282.716085)
			(xy 122.33965 -282.699669) (xy 122.389515 -282.691347) (xy 122.414792 -282.690824) (xy 123.354846 -282.690824)
			(xy 123.380119 -282.691377) (xy 123.429974 -282.699704) (xy 123.477779 -282.716122) (xy 123.52223 -282.740183)
			(xy 123.562114 -282.771232) (xy 123.596345 -282.808422) (xy 123.623989 -282.850739) (xy 123.644291 -282.897028)
			(xy 123.656698 -282.946027) (xy 123.660872 -282.9964) (xy 124.928601 -282.9964) (xy 124.932775 -282.946018)
			(xy 124.945186 -282.89701) (xy 124.965494 -282.850713) (xy 124.993144 -282.80839) (xy 125.027384 -282.771195)
			(xy 125.067279 -282.740144) (xy 125.111741 -282.716082) (xy 125.159557 -282.699667) (xy 125.209423 -282.691346)
			(xy 125.2347 -282.690824) (xy 126.174754 -282.690824) (xy 126.200034 -282.691341) (xy 126.249906 -282.699657)
			(xy 126.297728 -282.716068) (xy 126.342197 -282.740127) (xy 126.382098 -282.771178) (xy 126.416344 -282.808374)
			(xy 126.444 -282.850699) (xy 126.464312 -282.897) (xy 126.476725 -282.946013) (xy 126.480901 -282.9964)
			(xy 126.476725 -283.046787) (xy 126.464312 -283.0958) (xy 126.444 -283.142101) (xy 126.416344 -283.184426)
			(xy 126.382098 -283.221622) (xy 126.342197 -283.252673) (xy 126.297728 -283.276732) (xy 126.249906 -283.293143)
			(xy 126.200034 -283.301459) (xy 126.174754 -283.301948) (xy 125.2347 -283.301948) (xy 125.209423 -283.301454)
			(xy 125.159557 -283.293133) (xy 125.111741 -283.276718) (xy 125.067279 -283.252656) (xy 125.027384 -283.221605)
			(xy 124.993144 -283.18441) (xy 124.965494 -283.142087) (xy 124.945186 -283.09579) (xy 124.932775 -283.046782)
			(xy 124.928601 -282.9964) (xy 123.660872 -282.9964) (xy 123.656698 -283.046773) (xy 123.644291 -283.095772)
			(xy 123.623989 -283.142061) (xy 123.596345 -283.184378) (xy 123.562114 -283.221568) (xy 123.52223 -283.252617)
			(xy 123.477779 -283.276678) (xy 123.429974 -283.293096) (xy 123.380119 -283.301423) (xy 123.354846 -283.301948)
			(xy 122.414792 -283.301948) (xy 122.389515 -283.301453) (xy 122.33965 -283.293131) (xy 122.291836 -283.276715)
			(xy 122.247375 -283.252653) (xy 122.207481 -283.221602) (xy 122.173242 -283.184408) (xy 122.145592 -283.142085)
			(xy 122.125285 -283.095789) (xy 122.112875 -283.046781) (xy 122.1087 -282.9964) (xy 120.840801 -282.9964)
			(xy 120.836625 -283.046784) (xy 120.824214 -283.095794) (xy 120.803905 -283.142092) (xy 120.776252 -283.184416)
			(xy 120.74201 -283.221611) (xy 120.702113 -283.252663) (xy 120.657648 -283.276723) (xy 120.60983 -283.293137)
			(xy 120.559962 -283.301456) (xy 120.534684 -283.301948) (xy 119.59463 -283.301948) (xy 119.569348 -283.301485)
			(xy 119.519474 -283.293167) (xy 119.47165 -283.276753) (xy 119.427179 -283.252691) (xy 119.387276 -283.221637)
			(xy 119.353029 -283.184438) (xy 119.325373 -283.142109) (xy 119.30506 -283.095806) (xy 119.292647 -283.04679)
			(xy 119.288471 -282.9964) (xy 118.020901 -282.9964) (xy 118.016725 -283.046785) (xy 118.004313 -283.095795)
			(xy 117.984004 -283.142094) (xy 117.95635 -283.184419) (xy 117.922107 -283.221614) (xy 117.882208 -283.252665)
			(xy 117.837743 -283.276726) (xy 117.789924 -283.293139) (xy 117.740055 -283.301457) (xy 117.714776 -283.301948)
			(xy 116.774722 -283.301948) (xy 116.749441 -283.301485) (xy 116.699568 -283.293166) (xy 116.651744 -283.276751)
			(xy 116.607275 -283.252688) (xy 116.567373 -283.221634) (xy 116.533127 -283.184435) (xy 116.505471 -283.142107)
			(xy 116.48516 -283.095804) (xy 116.472747 -283.046789) (xy 116.468571 -282.9964) (xy 107.687072 -282.9964)
			(xy 107.682898 -283.046774) (xy 107.67049 -283.095773) (xy 107.650188 -283.142063) (xy 107.622544 -283.18438)
			(xy 107.588312 -283.22157) (xy 107.548426 -283.252619) (xy 107.503975 -283.27668) (xy 107.456169 -283.293098)
			(xy 107.406313 -283.301423) (xy 107.38104 -283.301948) (xy 106.440986 -283.301948) (xy 106.415709 -283.301453)
			(xy 106.365846 -283.29313) (xy 106.318032 -283.276714) (xy 106.273572 -283.252651) (xy 106.233679 -283.2216)
			(xy 106.199441 -283.184406) (xy 106.171791 -283.142083) (xy 106.151485 -283.095788) (xy 106.139075 -283.046781)
			(xy 106.1349 -282.9964) (xy 104.867172 -282.9964) (xy 104.862998 -283.046774) (xy 104.85059 -283.095775)
			(xy 104.830287 -283.142065) (xy 104.802642 -283.184382) (xy 104.768409 -283.221573) (xy 104.728522 -283.252622)
			(xy 104.684069 -283.276683) (xy 104.636262 -283.293099) (xy 104.586405 -283.301424) (xy 104.561132 -283.301948)
			(xy 103.621078 -283.301948) (xy 103.595802 -283.301452) (xy 103.545939 -283.293128) (xy 103.498126 -283.276711)
			(xy 103.453668 -283.252649) (xy 103.413776 -283.221597) (xy 103.379539 -283.184403) (xy 103.35189 -283.142081)
			(xy 103.331584 -283.095786) (xy 103.319175 -283.04678) (xy 103.315 -282.9964) (xy 102.047272 -282.9964)
			(xy 102.043098 -283.046775) (xy 102.030689 -283.095776) (xy 102.010385 -283.142067) (xy 101.98274 -283.184385)
			(xy 101.948506 -283.221576) (xy 101.908618 -283.252624) (xy 101.864164 -283.276685) (xy 101.816356 -283.293101)
			(xy 101.766498 -283.301424) (xy 101.741224 -283.301948) (xy 100.80117 -283.301948) (xy 100.775894 -283.301452)
			(xy 100.726032 -283.293127) (xy 100.678221 -283.276709) (xy 100.633764 -283.252646) (xy 100.593873 -283.221594)
			(xy 100.559637 -283.1844) (xy 100.531989 -283.142079) (xy 100.511684 -283.095784) (xy 100.499275 -283.046779)
			(xy 100.4951 -282.9964) (xy 99.227201 -282.9964) (xy 99.223025 -283.046786) (xy 99.210613 -283.095798)
			(xy 99.190302 -283.142098) (xy 99.162646 -283.184423) (xy 99.128401 -283.221619) (xy 99.088501 -283.25267)
			(xy 99.044033 -283.27673) (xy 98.996212 -283.293142) (xy 98.946342 -283.301458) (xy 98.921062 -283.301948)
			(xy 97.981008 -283.301948) (xy 97.955728 -283.301484) (xy 97.905856 -283.293163) (xy 97.858035 -283.276747)
			(xy 97.813568 -283.252683) (xy 97.773668 -283.221629) (xy 97.739424 -283.184431) (xy 97.711769 -283.142103)
			(xy 97.691459 -283.095801) (xy 97.679047 -283.046788) (xy 97.674871 -282.9964) (xy 97.371662 -282.9964)
			(xy 97.37118 -283.022375) (xy 97.36305 -283.073712) (xy 97.346989 -283.123146) (xy 97.323391 -283.169458)
			(xy 97.292838 -283.211507) (xy 97.256083 -283.248259) (xy 97.21403 -283.278808) (xy 97.167716 -283.302401)
			(xy 97.118281 -283.318458) (xy 97.066943 -283.326582) (xy 97.040954 -283.327094) (xy 97.026222 -283.32684)
			(xy 97.011998 -283.326078) (xy 96.98736 -283.339794) (xy 96.842326 -283.589476) (xy 96.843088 -283.61767)
			(xy 96.850708 -283.629608) (xy 96.862817 -283.64954) (xy 96.881922 -283.692085) (xy 96.894859 -283.736892)
			(xy 96.901372 -283.783073) (xy 96.901762 -283.806392) (xy 96.901762 -283.8064) (xy 108.485161 -283.8064)
			(xy 108.489332 -283.756061) (xy 108.501732 -283.707095) (xy 108.522022 -283.660838) (xy 108.549649 -283.618552)
			(xy 108.583859 -283.581389) (xy 108.623719 -283.550364) (xy 108.668142 -283.526323) (xy 108.715916 -283.509921)
			(xy 108.765738 -283.501606) (xy 108.790994 -283.501084) (xy 109.731048 -283.501084) (xy 109.7563 -283.501625)
			(xy 109.806114 -283.509945) (xy 109.85388 -283.52635) (xy 109.898295 -283.550392) (xy 109.938147 -283.581416)
			(xy 109.97235 -283.618576) (xy 109.999971 -283.660858) (xy 110.020256 -283.707109) (xy 110.032653 -283.756068)
			(xy 110.036823 -283.8064) (xy 114.118832 -283.8064) (xy 114.123004 -283.756054) (xy 114.135406 -283.707082)
			(xy 114.155699 -283.660819) (xy 114.183331 -283.618527) (xy 114.217547 -283.581361) (xy 114.257413 -283.550333)
			(xy 114.301844 -283.52629) (xy 114.349625 -283.509889) (xy 114.399455 -283.501576) (xy 114.424714 -283.501084)
			(xy 115.364768 -283.501084) (xy 115.390027 -283.50159) (xy 115.439856 -283.5099) (xy 115.487638 -283.526299)
			(xy 115.532068 -283.55034) (xy 115.571936 -283.581366) (xy 115.606152 -283.618531) (xy 115.633784 -283.660822)
			(xy 115.654078 -283.707084) (xy 115.66648 -283.756055) (xy 115.670652 -283.8064) (xy 115.66648 -283.856745)
			(xy 115.654078 -283.905716) (xy 115.633784 -283.951978) (xy 115.606152 -283.994269) (xy 115.571936 -284.031434)
			(xy 115.532068 -284.06246) (xy 115.487638 -284.086501) (xy 115.439856 -284.1029) (xy 115.390027 -284.11121)
			(xy 115.364768 -284.1117) (xy 114.424714 -284.1117) (xy 114.399455 -284.111224) (xy 114.349625 -284.102911)
			(xy 114.301844 -284.08651) (xy 114.257413 -284.062467) (xy 114.217547 -284.031439) (xy 114.183331 -283.994273)
			(xy 114.155699 -283.951981) (xy 114.135406 -283.905718) (xy 114.123004 -283.856746) (xy 114.118832 -283.8064)
			(xy 110.036823 -283.8064) (xy 110.032653 -283.856732) (xy 110.020256 -283.905691) (xy 109.999971 -283.951942)
			(xy 109.97235 -283.994224) (xy 109.938147 -284.031384) (xy 109.898295 -284.062408) (xy 109.85388 -284.08645)
			(xy 109.806114 -284.102855) (xy 109.7563 -284.111175) (xy 109.731048 -284.1117) (xy 108.790994 -284.1117)
			(xy 108.765738 -284.111194) (xy 108.715916 -284.102879) (xy 108.668142 -284.086477) (xy 108.623719 -284.062436)
			(xy 108.583859 -284.031411) (xy 108.549649 -283.994248) (xy 108.522022 -283.951962) (xy 108.501732 -283.905705)
			(xy 108.489332 -283.856739) (xy 108.485161 -283.8064) (xy 96.901762 -283.8064) (xy 96.901326 -283.829947)
			(xy 96.894604 -283.876574) (xy 96.881339 -283.921778) (xy 96.861798 -283.964644) (xy 96.849438 -283.9847)
			(xy 96.841818 -283.996892) (xy 96.841056 -284.025086) (xy 96.985074 -284.273498) (xy 97.009966 -284.28696)
			(xy 97.02419 -284.286198) (xy 97.040954 -284.28569) (xy 97.066946 -284.28617) (xy 97.11829 -284.294295)
			(xy 97.167731 -284.310353) (xy 97.21405 -284.333949) (xy 97.256108 -284.3645) (xy 97.292869 -284.401255)
			(xy 97.323426 -284.443309) (xy 97.347028 -284.489625) (xy 97.363094 -284.539063) (xy 97.371227 -284.590406)
			(xy 97.371662 -284.616398) (xy 97.371662 -284.6164) (xy 97.674883 -284.6164) (xy 97.679059 -284.566014)
			(xy 97.69147 -284.517003) (xy 97.71178 -284.470702) (xy 97.739433 -284.428377) (xy 97.773676 -284.39118)
			(xy 97.813574 -284.360127) (xy 97.85804 -284.336064) (xy 97.905859 -284.319649) (xy 97.955729 -284.311328)
			(xy 97.981008 -284.310836) (xy 98.921062 -284.310836) (xy 98.946343 -284.31133) (xy 98.996215 -284.319647)
			(xy 99.044038 -284.336059) (xy 99.088508 -284.36012) (xy 99.12841 -284.391172) (xy 99.162656 -284.428369)
			(xy 99.190312 -284.470696) (xy 99.210624 -284.516998) (xy 99.223037 -284.566012) (xy 99.227213 -284.6164)
			(xy 100.495112 -284.6164) (xy 100.499287 -284.566023) (xy 100.511695 -284.51702) (xy 100.532 -284.470727)
			(xy 100.559646 -284.428407) (xy 100.593881 -284.391215) (xy 100.63377 -284.360164) (xy 100.678226 -284.336102)
			(xy 100.726035 -284.319685) (xy 100.775895 -284.31136) (xy 100.80117 -284.310836) (xy 101.741224 -284.310836)
			(xy 101.766499 -284.311364) (xy 101.816359 -284.319688) (xy 101.864169 -284.336104) (xy 101.908625 -284.360165)
			(xy 101.948514 -284.391216) (xy 101.982749 -284.428408) (xy 102.010396 -284.470727) (xy 102.030701 -284.51702)
			(xy 102.043109 -284.566023) (xy 102.047284 -284.6164) (xy 103.315012 -284.6164) (xy 103.319187 -284.566022)
			(xy 103.331596 -284.517018) (xy 103.351901 -284.470725) (xy 103.379548 -284.428404) (xy 103.413784 -284.391212)
			(xy 103.453674 -284.360161) (xy 103.498131 -284.3361) (xy 103.545942 -284.319683) (xy 103.595803 -284.31136)
			(xy 103.621078 -284.310836) (xy 104.561132 -284.310836) (xy 104.586406 -284.311364) (xy 104.636265 -284.319689)
			(xy 104.684074 -284.336106) (xy 104.728529 -284.360168) (xy 104.768417 -284.391218) (xy 104.802651 -284.42841)
			(xy 104.830297 -284.470729) (xy 104.850601 -284.517021) (xy 104.863009 -284.566024) (xy 104.867184 -284.6164)
			(xy 106.134912 -284.6164) (xy 106.139087 -284.566021) (xy 106.151496 -284.517016) (xy 106.171802 -284.470722)
			(xy 106.19945 -284.428402) (xy 106.233687 -284.391209) (xy 106.273579 -284.360159) (xy 106.318037 -284.336097)
			(xy 106.365849 -284.319682) (xy 106.41571 -284.311359) (xy 106.440986 -284.310836) (xy 107.38104 -284.310836)
			(xy 107.406314 -284.311365) (xy 107.456172 -284.319691) (xy 107.503979 -284.336109) (xy 107.548433 -284.360171)
			(xy 107.58832 -284.391221) (xy 107.622553 -284.428413) (xy 107.650198 -284.470731) (xy 107.670502 -284.517023)
			(xy 107.68291 -284.566024) (xy 107.687084 -284.6164) (xy 116.468583 -284.6164) (xy 116.472759 -284.566013)
			(xy 116.485171 -284.517) (xy 116.505482 -284.470699) (xy 116.533137 -284.428372) (xy 116.567381 -284.391175)
			(xy 116.607282 -284.360122) (xy 116.651749 -284.33606) (xy 116.699571 -284.319646) (xy 116.749442 -284.311327)
			(xy 116.774722 -284.310836) (xy 117.714776 -284.310836) (xy 117.740056 -284.311331) (xy 117.789927 -284.319649)
			(xy 117.837748 -284.336063) (xy 117.882215 -284.360125) (xy 117.922115 -284.391177) (xy 117.95636 -284.428374)
			(xy 117.984014 -284.4707) (xy 118.004325 -284.517001) (xy 118.016737 -284.566013) (xy 118.020913 -284.6164)
			(xy 119.288483 -284.6164) (xy 119.292659 -284.566012) (xy 119.305072 -284.516998) (xy 119.325383 -284.470696)
			(xy 119.353039 -284.428369) (xy 119.387285 -284.391172) (xy 119.427186 -284.360119) (xy 119.471655 -284.336058)
			(xy 119.519477 -284.319644) (xy 119.569349 -284.311327) (xy 119.59463 -284.310836) (xy 120.534684 -284.310836)
			(xy 120.559963 -284.311332) (xy 120.609833 -284.319651) (xy 120.657653 -284.336066) (xy 120.702119 -284.360127)
			(xy 120.742018 -284.39118) (xy 120.776262 -284.428376) (xy 120.803915 -284.470702) (xy 120.824225 -284.517002)
			(xy 120.836637 -284.566014) (xy 120.840813 -284.6164) (xy 122.108712 -284.6164) (xy 122.112887 -284.56602)
			(xy 122.125297 -284.517015) (xy 122.145603 -284.470721) (xy 122.173252 -284.4284) (xy 122.207489 -284.391207)
			(xy 122.247382 -284.360157) (xy 122.291841 -284.336096) (xy 122.339653 -284.31968) (xy 122.389516 -284.311359)
			(xy 122.414792 -284.310836) (xy 123.354846 -284.310836) (xy 123.38012 -284.311366) (xy 123.429977 -284.319692)
			(xy 123.477783 -284.336111) (xy 123.522236 -284.360173) (xy 123.562123 -284.391223) (xy 123.596355 -284.428415)
			(xy 123.623999 -284.470733) (xy 123.644302 -284.517024) (xy 123.65671 -284.566025) (xy 123.660884 -284.6164)
			(xy 124.928613 -284.6164) (xy 124.932787 -284.56602) (xy 124.945197 -284.517014) (xy 124.965504 -284.470718)
			(xy 124.993154 -284.428397) (xy 125.027393 -284.391204) (xy 125.067286 -284.360154) (xy 125.111746 -284.336093)
			(xy 125.15956 -284.319679) (xy 125.209423 -284.311358) (xy 125.2347 -284.310836) (xy 126.174754 -284.310836)
			(xy 126.200035 -284.311329) (xy 126.249909 -284.319645) (xy 126.297733 -284.336057) (xy 126.342203 -284.360117)
			(xy 126.382107 -284.391169) (xy 126.416354 -284.428366) (xy 126.444011 -284.470694) (xy 126.464323 -284.516996)
			(xy 126.476737 -284.566011) (xy 126.480913 -284.6164) (xy 126.476737 -284.666789) (xy 126.464323 -284.715804)
			(xy 126.444011 -284.762106) (xy 126.416354 -284.804434) (xy 126.382107 -284.841631) (xy 126.342203 -284.872683)
			(xy 126.297733 -284.896743) (xy 126.249909 -284.913155) (xy 126.200035 -284.921471) (xy 126.174754 -284.92196)
			(xy 125.2347 -284.92196) (xy 125.209423 -284.921442) (xy 125.15956 -284.913121) (xy 125.111746 -284.896707)
			(xy 125.067286 -284.872646) (xy 125.027393 -284.841596) (xy 124.993154 -284.804403) (xy 124.965504 -284.762082)
			(xy 124.945197 -284.715786) (xy 124.932787 -284.66678) (xy 124.928613 -284.6164) (xy 123.660884 -284.6164)
			(xy 123.65671 -284.666775) (xy 123.644302 -284.715776) (xy 123.623999 -284.762067) (xy 123.596355 -284.804385)
			(xy 123.562123 -284.841577) (xy 123.522236 -284.872627) (xy 123.477783 -284.896689) (xy 123.429977 -284.913108)
			(xy 123.38012 -284.921434) (xy 123.354846 -284.92196) (xy 122.414792 -284.92196) (xy 122.389516 -284.921441)
			(xy 122.339653 -284.91312) (xy 122.291841 -284.896704) (xy 122.247382 -284.872643) (xy 122.207489 -284.841593)
			(xy 122.173252 -284.8044) (xy 122.145603 -284.762079) (xy 122.125297 -284.715785) (xy 122.112887 -284.66678)
			(xy 122.108712 -284.6164) (xy 120.840813 -284.6164) (xy 120.836637 -284.666786) (xy 120.824225 -284.715798)
			(xy 120.803915 -284.762098) (xy 120.776262 -284.804424) (xy 120.742018 -284.84162) (xy 120.702119 -284.872673)
			(xy 120.657653 -284.896734) (xy 120.609833 -284.913149) (xy 120.559963 -284.921468) (xy 120.534684 -284.92196)
			(xy 119.59463 -284.92196) (xy 119.569349 -284.921473) (xy 119.519477 -284.913156) (xy 119.471655 -284.896742)
			(xy 119.427186 -284.872681) (xy 119.387285 -284.841628) (xy 119.353039 -284.804431) (xy 119.325383 -284.762104)
			(xy 119.305072 -284.715802) (xy 119.292659 -284.666788) (xy 119.288483 -284.6164) (xy 118.020913 -284.6164)
			(xy 118.016737 -284.666787) (xy 118.004325 -284.715799) (xy 117.984014 -284.7621) (xy 117.95636 -284.804426)
			(xy 117.922115 -284.841623) (xy 117.882215 -284.872675) (xy 117.837748 -284.896737) (xy 117.789927 -284.913151)
			(xy 117.740056 -284.921469) (xy 117.714776 -284.92196) (xy 116.774722 -284.92196) (xy 116.749442 -284.921473)
			(xy 116.699571 -284.913154) (xy 116.651749 -284.89674) (xy 116.607282 -284.872678) (xy 116.567381 -284.841625)
			(xy 116.533137 -284.804428) (xy 116.505482 -284.762101) (xy 116.485171 -284.7158) (xy 116.472759 -284.666787)
			(xy 116.468583 -284.6164) (xy 107.687084 -284.6164) (xy 107.68291 -284.666776) (xy 107.670502 -284.715777)
			(xy 107.650198 -284.762069) (xy 107.622553 -284.804387) (xy 107.58832 -284.841579) (xy 107.548433 -284.872629)
			(xy 107.503979 -284.896691) (xy 107.456172 -284.913109) (xy 107.406314 -284.921435) (xy 107.38104 -284.92196)
			(xy 106.440986 -284.92196) (xy 106.41571 -284.921441) (xy 106.365849 -284.913118) (xy 106.318037 -284.896703)
			(xy 106.273579 -284.872641) (xy 106.233687 -284.841591) (xy 106.19945 -284.804398) (xy 106.171802 -284.762078)
			(xy 106.151496 -284.715784) (xy 106.139087 -284.666779) (xy 106.134912 -284.6164) (xy 104.867184 -284.6164)
			(xy 104.863009 -284.666776) (xy 104.850601 -284.715779) (xy 104.830297 -284.762071) (xy 104.802651 -284.80439)
			(xy 104.768417 -284.841582) (xy 104.728529 -284.872632) (xy 104.684074 -284.896694) (xy 104.636265 -284.913111)
			(xy 104.586406 -284.921436) (xy 104.561132 -284.92196) (xy 103.621078 -284.92196) (xy 103.595803 -284.92144)
			(xy 103.545942 -284.913117) (xy 103.498131 -284.8967) (xy 103.453674 -284.872639) (xy 103.413784 -284.841588)
			(xy 103.379548 -284.804396) (xy 103.351901 -284.762075) (xy 103.331596 -284.715782) (xy 103.319187 -284.666778)
			(xy 103.315012 -284.6164) (xy 102.047284 -284.6164) (xy 102.043109 -284.666777) (xy 102.030701 -284.71578)
			(xy 102.010396 -284.762073) (xy 101.982749 -284.804392) (xy 101.948514 -284.841584) (xy 101.908625 -284.872635)
			(xy 101.864169 -284.896696) (xy 101.816359 -284.913112) (xy 101.766499 -284.921436) (xy 101.741224 -284.92196)
			(xy 100.80117 -284.92196) (xy 100.775895 -284.92144) (xy 100.726035 -284.913115) (xy 100.678226 -284.896698)
			(xy 100.63377 -284.872636) (xy 100.593881 -284.841585) (xy 100.559646 -284.804393) (xy 100.532 -284.762073)
			(xy 100.511695 -284.71578) (xy 100.499287 -284.666777) (xy 100.495112 -284.6164) (xy 99.227213 -284.6164)
			(xy 99.223037 -284.666788) (xy 99.210624 -284.715802) (xy 99.190312 -284.762104) (xy 99.162656 -284.804431)
			(xy 99.12841 -284.841628) (xy 99.088508 -284.87268) (xy 99.044038 -284.896741) (xy 98.996215 -284.913153)
			(xy 98.946343 -284.92147) (xy 98.921062 -284.92196) (xy 97.981008 -284.92196) (xy 97.955729 -284.921472)
			(xy 97.905859 -284.913151) (xy 97.85804 -284.896736) (xy 97.813574 -284.872673) (xy 97.773676 -284.84162)
			(xy 97.739433 -284.804423) (xy 97.71178 -284.762098) (xy 97.69147 -284.715797) (xy 97.679059 -284.666786)
			(xy 97.674883 -284.6164) (xy 97.371662 -284.6164) (xy 97.371225 -284.639952) (xy 97.364503 -284.68658)
			(xy 97.351237 -284.731783) (xy 97.331695 -284.774648) (xy 97.319338 -284.794706) (xy 97.311464 -284.806898)
			(xy 97.310956 -284.835092) (xy 97.454974 -285.083504) (xy 97.479612 -285.096966) (xy 97.49409 -285.096204)
			(xy 97.511108 -285.095696) (xy 97.537094 -285.096206) (xy 97.588427 -285.104338) (xy 97.637856 -285.120399)
			(xy 97.684164 -285.143995) (xy 97.726211 -285.174545) (xy 97.762961 -285.211295) (xy 97.793509 -285.253343)
			(xy 97.817104 -285.299651) (xy 97.833164 -285.34908) (xy 97.841295 -285.400414) (xy 97.841295 -285.4264)
			(xy 108.485173 -285.4264) (xy 108.489344 -285.376063) (xy 108.501743 -285.327099) (xy 108.522032 -285.280844)
			(xy 108.549658 -285.238559) (xy 108.583867 -285.201398) (xy 108.623725 -285.170374) (xy 108.668147 -285.146334)
			(xy 108.715919 -285.129932) (xy 108.765739 -285.121618) (xy 108.790994 -285.121096) (xy 109.731048 -285.121096)
			(xy 109.756301 -285.121613) (xy 109.806117 -285.129933) (xy 109.853885 -285.146339) (xy 109.898301 -285.170382)
			(xy 109.938155 -285.201407) (xy 109.972359 -285.238568) (xy 109.999981 -285.280852) (xy 110.020267 -285.327105)
			(xy 110.032665 -285.376066) (xy 110.036835 -285.4264) (xy 114.118844 -285.4264) (xy 114.123016 -285.376056)
			(xy 114.135417 -285.327086) (xy 114.15571 -285.280825) (xy 114.18334 -285.238535) (xy 114.217555 -285.201369)
			(xy 114.25742 -285.170343) (xy 114.301849 -285.146301) (xy 114.349628 -285.1299) (xy 114.399456 -285.121588)
			(xy 114.424714 -285.121096) (xy 115.364768 -285.121096) (xy 115.390028 -285.121578) (xy 115.439859 -285.129889)
			(xy 115.487643 -285.146288) (xy 115.532075 -285.17033) (xy 115.571944 -285.201357) (xy 115.606161 -285.238524)
			(xy 115.633795 -285.280816) (xy 115.654089 -285.32708) (xy 115.666492 -285.376053) (xy 115.670664 -285.4264)
			(xy 115.666492 -285.476747) (xy 115.654089 -285.52572) (xy 115.633795 -285.571984) (xy 115.606161 -285.614276)
			(xy 115.571944 -285.651443) (xy 115.532075 -285.68247) (xy 115.487643 -285.706512) (xy 115.439859 -285.722911)
			(xy 115.390028 -285.731222) (xy 115.364768 -285.731712) (xy 114.424714 -285.731712) (xy 114.399456 -285.731212)
			(xy 114.349628 -285.7229) (xy 114.301849 -285.706499) (xy 114.25742 -285.682457) (xy 114.217555 -285.651431)
			(xy 114.18334 -285.614265) (xy 114.15571 -285.571975) (xy 114.135417 -285.525714) (xy 114.123016 -285.476744)
			(xy 114.118844 -285.4264) (xy 110.036835 -285.4264) (xy 110.032665 -285.476734) (xy 110.020267 -285.525695)
			(xy 109.999981 -285.571948) (xy 109.972359 -285.614232) (xy 109.938155 -285.651393) (xy 109.898301 -285.682418)
			(xy 109.853885 -285.706461) (xy 109.806117 -285.722867) (xy 109.756301 -285.731187) (xy 109.731048 -285.731712)
			(xy 108.790994 -285.731712) (xy 108.765739 -285.731182) (xy 108.715919 -285.722868) (xy 108.668147 -285.706466)
			(xy 108.623725 -285.682426) (xy 108.583867 -285.651402) (xy 108.549658 -285.614241) (xy 108.522032 -285.571956)
			(xy 108.501743 -285.525701) (xy 108.489344 -285.476737) (xy 108.485173 -285.4264) (xy 97.841295 -285.4264)
			(xy 97.841295 -285.452386) (xy 97.833164 -285.50372) (xy 97.817104 -285.553149) (xy 97.793509 -285.599457)
			(xy 97.762961 -285.641505) (xy 97.726211 -285.678255) (xy 97.684164 -285.708805) (xy 97.637856 -285.732401)
			(xy 97.588427 -285.748462) (xy 97.537094 -285.756594) (xy 97.511108 -285.757112) (xy 97.496122 -285.756858)
			(xy 97.481898 -285.756096) (xy 97.45726 -285.769558) (xy 97.312226 -286.01924) (xy 97.312734 -286.047688)
			(xy 97.320354 -286.059626) (xy 97.332508 -286.079544) (xy 97.351699 -286.122075) (xy 97.364708 -286.166885)
			(xy 97.371278 -286.21308) (xy 97.371662 -286.2364) (xy 97.675659 -286.2364) (xy 97.679824 -286.186142)
			(xy 97.692204 -286.137254) (xy 97.712462 -286.091072) (xy 97.740045 -286.048853) (xy 97.774201 -286.01175)
			(xy 97.813999 -285.980776) (xy 97.858351 -285.956774) (xy 97.90605 -285.940401) (xy 97.955793 -285.932101)
			(xy 97.981008 -285.93161) (xy 98.921062 -285.93161) (xy 98.946281 -285.932079) (xy 98.996031 -285.940375)
			(xy 99.043736 -285.956747) (xy 99.088097 -285.980749) (xy 99.127901 -286.011725) (xy 99.162063 -286.048831)
			(xy 99.189651 -286.091054) (xy 99.209913 -286.137242) (xy 99.222296 -286.186135) (xy 99.226461 -286.2364)
			(xy 100.495124 -286.2364) (xy 100.499298 -286.186025) (xy 100.511706 -286.137023) (xy 100.53201 -286.090733)
			(xy 100.559656 -286.048415) (xy 100.593889 -286.011224) (xy 100.633777 -285.980174) (xy 100.678231 -285.956113)
			(xy 100.726038 -285.939697) (xy 100.775896 -285.931372) (xy 100.80117 -285.930848) (xy 101.741224 -285.930848)
			(xy 101.7665 -285.931352) (xy 101.816362 -285.939676) (xy 101.864173 -285.956093) (xy 101.908631 -285.980155)
			(xy 101.948522 -286.011207) (xy 101.982759 -286.0484) (xy 102.010407 -286.090721) (xy 102.030712 -286.137016)
			(xy 102.043121 -286.186021) (xy 102.047296 -286.2364) (xy 103.315024 -286.2364) (xy 103.319199 -286.186024)
			(xy 103.331607 -286.137022) (xy 103.351911 -286.09073) (xy 103.379558 -286.048412) (xy 103.413792 -286.011221)
			(xy 103.453681 -285.980171) (xy 103.498136 -285.956111) (xy 103.545945 -285.939695) (xy 103.595804 -285.931372)
			(xy 103.621078 -285.930848) (xy 104.561132 -285.930848) (xy 104.586407 -285.931352) (xy 104.636268 -285.939678)
			(xy 104.684079 -285.956095) (xy 104.728535 -285.980158) (xy 104.768425 -286.01121) (xy 104.802661 -286.048403)
			(xy 104.830308 -286.090724) (xy 104.850613 -286.137017) (xy 104.863021 -286.186022) (xy 104.867196 -286.2364)
			(xy 106.134924 -286.2364) (xy 106.139099 -286.186023) (xy 106.151508 -286.13702) (xy 106.171813 -286.090728)
			(xy 106.19946 -286.048409) (xy 106.233695 -286.011218) (xy 106.273585 -285.980169) (xy 106.318041 -285.956108)
			(xy 106.365851 -285.939693) (xy 106.415711 -285.931371) (xy 106.440986 -285.930848) (xy 107.38104 -285.930848)
			(xy 107.406315 -285.931353) (xy 107.456175 -285.939679) (xy 107.503984 -285.956098) (xy 107.54844 -285.980161)
			(xy 107.588328 -286.011213) (xy 107.622563 -286.048406) (xy 107.650209 -286.090726) (xy 107.670513 -286.137019)
			(xy 107.682921 -286.186022) (xy 107.687096 -286.2364) (xy 116.468595 -286.2364) (xy 116.472771 -286.186015)
			(xy 116.485183 -286.137004) (xy 116.505492 -286.090704) (xy 116.533146 -286.048379) (xy 116.56739 -286.011184)
			(xy 116.607288 -285.980132) (xy 116.651754 -285.956071) (xy 116.699574 -285.939658) (xy 116.749443 -285.931339)
			(xy 116.774722 -285.930848) (xy 117.714776 -285.930848) (xy 117.740057 -285.931319) (xy 117.789929 -285.939638)
			(xy 117.837753 -285.956052) (xy 117.882222 -285.980115) (xy 117.922123 -286.011168) (xy 117.956369 -286.048366)
			(xy 117.984025 -286.090694) (xy 118.004336 -286.136997) (xy 118.016749 -286.186011) (xy 118.020925 -286.2364)
			(xy 119.288495 -286.2364) (xy 119.292671 -286.186014) (xy 119.305083 -286.137002) (xy 119.325394 -286.090702)
			(xy 119.353048 -286.048377) (xy 119.387293 -286.011181) (xy 119.427193 -285.980129) (xy 119.47166 -285.956069)
			(xy 119.51948 -285.939656) (xy 119.56935 -285.931339) (xy 119.59463 -285.930848) (xy 120.534684 -285.930848)
			(xy 120.559964 -285.93132) (xy 120.609836 -285.93964) (xy 120.657658 -285.956055) (xy 120.702126 -285.980117)
			(xy 120.742026 -286.011171) (xy 120.776271 -286.048369) (xy 120.803926 -286.090696) (xy 120.824237 -286.136998)
			(xy 120.836649 -286.186012) (xy 120.840825 -286.2364) (xy 122.108724 -286.2364) (xy 122.112899 -286.186022)
			(xy 122.125308 -286.137019) (xy 122.145613 -286.090726) (xy 122.173261 -286.048407) (xy 122.207498 -286.011216)
			(xy 122.247388 -285.980167) (xy 122.291845 -285.956107) (xy 122.339656 -285.939692) (xy 122.389517 -285.931371)
			(xy 122.414792 -285.930848) (xy 123.354846 -285.930848) (xy 123.380121 -285.931354) (xy 123.42998 -285.93968)
			(xy 123.477788 -285.9561) (xy 123.522243 -285.980163) (xy 123.562131 -286.011215) (xy 123.596364 -286.048408)
			(xy 123.62401 -286.090727) (xy 123.644314 -286.13702) (xy 123.656722 -286.186023) (xy 123.660896 -286.2364)
			(xy 123.656722 -286.286777) (xy 123.644314 -286.33578) (xy 123.62401 -286.382073) (xy 123.596364 -286.424392)
			(xy 123.562131 -286.461585) (xy 123.522243 -286.492637) (xy 123.477788 -286.5167) (xy 123.42998 -286.53312)
			(xy 123.380121 -286.541446) (xy 123.354846 -286.541972) (xy 122.414792 -286.541972) (xy 122.389517 -286.541429)
			(xy 122.339656 -286.533108) (xy 122.291845 -286.516693) (xy 122.247388 -286.492633) (xy 122.207498 -286.461584)
			(xy 122.173261 -286.424393) (xy 122.145613 -286.382074) (xy 122.125308 -286.335781) (xy 122.112899 -286.286778)
			(xy 122.108724 -286.2364) (xy 120.840825 -286.2364) (xy 120.836649 -286.286788) (xy 120.824237 -286.335802)
			(xy 120.803926 -286.382104) (xy 120.776271 -286.424431) (xy 120.742026 -286.461629) (xy 120.702126 -286.492683)
			(xy 120.657658 -286.516745) (xy 120.609836 -286.53316) (xy 120.559964 -286.54148) (xy 120.534684 -286.541972)
			(xy 119.59463 -286.541972) (xy 119.56935 -286.541461) (xy 119.51948 -286.533144) (xy 119.47166 -286.516731)
			(xy 119.427193 -286.492671) (xy 119.387293 -286.461619) (xy 119.353048 -286.424423) (xy 119.325394 -286.382098)
			(xy 119.305083 -286.335798) (xy 119.292671 -286.286786) (xy 119.288495 -286.2364) (xy 118.020925 -286.2364)
			(xy 118.016749 -286.286789) (xy 118.004336 -286.335803) (xy 117.984025 -286.382106) (xy 117.956369 -286.424434)
			(xy 117.922123 -286.461632) (xy 117.882222 -286.492685) (xy 117.837753 -286.516748) (xy 117.789929 -286.533162)
			(xy 117.740057 -286.541481) (xy 117.714776 -286.541972) (xy 116.774722 -286.541972) (xy 116.749443 -286.541461)
			(xy 116.699574 -286.533142) (xy 116.651754 -286.516729) (xy 116.607288 -286.492668) (xy 116.56739 -286.461616)
			(xy 116.533146 -286.424421) (xy 116.505492 -286.382096) (xy 116.485183 -286.335796) (xy 116.472771 -286.286785)
			(xy 116.468595 -286.2364) (xy 107.687096 -286.2364) (xy 107.682921 -286.286778) (xy 107.670513 -286.335781)
			(xy 107.650209 -286.382074) (xy 107.622563 -286.424394) (xy 107.588328 -286.461587) (xy 107.54844 -286.492639)
			(xy 107.503984 -286.516702) (xy 107.456175 -286.533121) (xy 107.406315 -286.541447) (xy 107.38104 -286.541972)
			(xy 106.440986 -286.541972) (xy 106.415711 -286.541429) (xy 106.365851 -286.533107) (xy 106.318041 -286.516692)
			(xy 106.273585 -286.492631) (xy 106.233695 -286.461582) (xy 106.19946 -286.424391) (xy 106.171813 -286.382072)
			(xy 106.151508 -286.33578) (xy 106.139099 -286.286777) (xy 106.134924 -286.2364) (xy 104.867196 -286.2364)
			(xy 104.863021 -286.286778) (xy 104.850613 -286.335783) (xy 104.830308 -286.382076) (xy 104.802661 -286.424397)
			(xy 104.768425 -286.46159) (xy 104.728535 -286.492642) (xy 104.684079 -286.516705) (xy 104.636268 -286.533122)
			(xy 104.586407 -286.541448) (xy 104.561132 -286.541972) (xy 103.621078 -286.541972) (xy 103.595804 -286.541428)
			(xy 103.545945 -286.533105) (xy 103.498136 -286.516689) (xy 103.453681 -286.492629) (xy 103.413792 -286.461579)
			(xy 103.379558 -286.424388) (xy 103.351911 -286.38207) (xy 103.331607 -286.335778) (xy 103.319199 -286.286776)
			(xy 103.315024 -286.2364) (xy 102.047296 -286.2364) (xy 102.043121 -286.286779) (xy 102.030712 -286.335784)
			(xy 102.010407 -286.382079) (xy 101.982759 -286.4244) (xy 101.948522 -286.461593) (xy 101.908631 -286.492645)
			(xy 101.864173 -286.516707) (xy 101.816362 -286.533124) (xy 101.7665 -286.541448) (xy 101.741224 -286.541972)
			(xy 100.80117 -286.541972) (xy 100.775896 -286.541428) (xy 100.726038 -286.533103) (xy 100.678231 -286.516687)
			(xy 100.633777 -286.492626) (xy 100.593889 -286.461576) (xy 100.559656 -286.424385) (xy 100.53201 -286.382067)
			(xy 100.511706 -286.335777) (xy 100.499298 -286.286775) (xy 100.495124 -286.2364) (xy 99.226461 -286.2364)
			(xy 99.222296 -286.286665) (xy 99.209913 -286.335558) (xy 99.189651 -286.381746) (xy 99.162063 -286.423969)
			(xy 99.127901 -286.461075) (xy 99.088097 -286.492051) (xy 99.043736 -286.516053) (xy 98.996031 -286.532425)
			(xy 98.946281 -286.540721) (xy 98.921062 -286.54121) (xy 97.981008 -286.54121) (xy 97.955793 -286.540699)
			(xy 97.90605 -286.532399) (xy 97.858351 -286.516026) (xy 97.813999 -286.492024) (xy 97.774201 -286.46105)
			(xy 97.740045 -286.423947) (xy 97.712462 -286.381728) (xy 97.692204 -286.335546) (xy 97.679824 -286.286658)
			(xy 97.675659 -286.2364) (xy 97.371662 -286.2364) (xy 97.371662 -286.23641) (xy 97.371178 -286.262397)
			(xy 97.363045 -286.313732) (xy 97.346982 -286.363162) (xy 97.323383 -286.409471) (xy 97.292829 -286.451517)
			(xy 97.256074 -286.488266) (xy 97.214023 -286.518812) (xy 97.167711 -286.542403) (xy 97.118278 -286.558458)
			(xy 97.066942 -286.566582) (xy 97.040954 -286.567118) (xy 97.026222 -286.566864) (xy 97.011998 -286.566102)
			(xy 96.98736 -286.579818) (xy 96.84258 -286.829246) (xy 96.843088 -286.85744) (xy 96.850708 -286.869632)
			(xy 96.862806 -286.889535) (xy 96.881903 -286.932017) (xy 96.89485 -286.976758) (xy 96.901391 -287.022874)
			(xy 96.901762 -287.046162) (xy 96.901761 -287.0462) (xy 108.485639 -287.0462) (xy 108.489804 -286.99594)
			(xy 108.502184 -286.947051) (xy 108.522443 -286.900866) (xy 108.550026 -286.858646) (xy 108.584183 -286.821541)
			(xy 108.62398 -286.790565) (xy 108.668334 -286.766561) (xy 108.716034 -286.750185) (xy 108.765778 -286.741883)
			(xy 108.790994 -286.741362) (xy 109.731048 -286.741362) (xy 109.756256 -286.741962) (xy 109.805982 -286.750268)
			(xy 109.853664 -286.766643) (xy 109.898 -286.790643) (xy 109.937782 -286.821612) (xy 109.971924 -286.858707)
			(xy 109.999496 -286.900914) (xy 110.019746 -286.947084) (xy 110.032121 -286.995957) (xy 110.036284 -287.0462)
			(xy 110.032121 -287.096443) (xy 110.019746 -287.145316) (xy 109.999496 -287.191486) (xy 109.971924 -287.233693)
			(xy 109.937782 -287.270788) (xy 109.898 -287.301757) (xy 109.853664 -287.325757) (xy 109.805982 -287.342132)
			(xy 109.756256 -287.350438) (xy 109.731048 -287.350962) (xy 108.790994 -287.350962) (xy 108.765778 -287.350517)
			(xy 108.716034 -287.342215) (xy 108.668334 -287.325839) (xy 108.62398 -287.301835) (xy 108.584183 -287.270859)
			(xy 108.550026 -287.233754) (xy 108.522443 -287.191534) (xy 108.502184 -287.145349) (xy 108.489804 -287.09646)
			(xy 108.485639 -287.0462) (xy 96.901761 -287.0462) (xy 96.901346 -287.069749) (xy 96.894649 -287.116446)
			(xy 96.881385 -287.161718) (xy 96.861823 -287.204646) (xy 96.849438 -287.224724) (xy 96.841564 -287.236916)
			(xy 96.841056 -287.26511) (xy 96.985074 -287.513522) (xy 97.009966 -287.526984) (xy 97.02419 -287.526222)
			(xy 97.040954 -287.525714) (xy 97.066945 -287.526194) (xy 97.118288 -287.534319) (xy 97.167727 -287.550378)
			(xy 97.214045 -287.573973) (xy 97.256101 -287.604525) (xy 97.292859 -287.641281) (xy 97.323414 -287.683334)
			(xy 97.347013 -287.729651) (xy 97.363075 -287.779089) (xy 97.371204 -287.830431) (xy 97.371662 -287.8564)
			(xy 97.675671 -287.8564) (xy 97.679835 -287.806144) (xy 97.692215 -287.757258) (xy 97.712472 -287.711077)
			(xy 97.740055 -287.66886) (xy 97.774209 -287.631759) (xy 97.814005 -287.600786) (xy 97.858356 -287.576785)
			(xy 97.906053 -287.560412) (xy 97.955794 -287.552113) (xy 97.981008 -287.551622) (xy 98.921062 -287.551622)
			(xy 98.946282 -287.552067) (xy 98.996034 -287.560363) (xy 99.043741 -287.576736) (xy 99.088103 -287.600739)
			(xy 99.127909 -287.631716) (xy 99.162072 -287.668823) (xy 99.189662 -287.711048) (xy 99.209924 -287.757238)
			(xy 99.222307 -287.806133) (xy 99.226473 -287.8564) (xy 100.495899 -287.8564) (xy 100.500063 -287.806152)
			(xy 100.512439 -287.757275) (xy 100.532692 -287.711101) (xy 100.560267 -287.668891) (xy 100.594414 -287.631794)
			(xy 100.634201 -287.600823) (xy 100.678542 -287.576823) (xy 100.726229 -287.560448) (xy 100.77596 -287.552145)
			(xy 100.80117 -287.551622) (xy 101.741224 -287.551622) (xy 101.766438 -287.5521) (xy 101.816177 -287.560404)
			(xy 101.863872 -287.576781) (xy 101.90822 -287.600784) (xy 101.948014 -287.631759) (xy 101.982166 -287.668862)
			(xy 102.009746 -287.711079) (xy 102.030002 -287.75726) (xy 102.04238 -287.806144) (xy 102.046545 -287.8564)
			(xy 103.315799 -287.8564) (xy 103.319963 -287.806151) (xy 103.33234 -287.757273) (xy 103.352593 -287.711099)
			(xy 103.380169 -287.668888) (xy 103.414317 -287.631791) (xy 103.454105 -287.60082) (xy 103.498447 -287.57682)
			(xy 103.546135 -287.560446) (xy 103.595868 -287.552144) (xy 103.621078 -287.551622) (xy 104.561132 -287.551622)
			(xy 104.586345 -287.552101) (xy 104.636084 -287.560406) (xy 104.683777 -287.576783) (xy 104.728125 -287.600787)
			(xy 104.767917 -287.631762) (xy 104.802068 -287.668864) (xy 104.829647 -287.711081) (xy 104.849902 -287.757261)
			(xy 104.862281 -287.806145) (xy 104.866445 -287.8564) (xy 106.135699 -287.8564) (xy 106.139863 -287.806151)
			(xy 106.152241 -287.757272) (xy 106.172494 -287.711097) (xy 106.200071 -287.668885) (xy 106.23422 -287.631788)
			(xy 106.274009 -287.600818) (xy 106.318353 -287.576818) (xy 106.366042 -287.560445) (xy 106.415775 -287.552143)
			(xy 106.440986 -287.551622) (xy 107.38104 -287.551622) (xy 107.406253 -287.552102) (xy 107.45599 -287.560407)
			(xy 107.503683 -287.576786) (xy 107.548029 -287.60079) (xy 107.58782 -287.631765) (xy 107.62197 -287.668867)
			(xy 107.649548 -287.711083) (xy 107.669803 -287.757263) (xy 107.682181 -287.806146) (xy 107.686345 -287.8564)
			(xy 107.682181 -287.906654) (xy 107.669803 -287.955537) (xy 107.649548 -288.001717) (xy 107.62197 -288.043933)
			(xy 107.58782 -288.081035) (xy 107.548029 -288.11201) (xy 107.503683 -288.136014) (xy 107.45599 -288.152393)
			(xy 107.406253 -288.160698) (xy 107.38104 -288.161222) (xy 106.440986 -288.161222) (xy 106.415775 -288.160657)
			(xy 106.366042 -288.152355) (xy 106.318353 -288.135982) (xy 106.274009 -288.111983) (xy 106.23422 -288.081012)
			(xy 106.200071 -288.043915) (xy 106.172494 -288.001703) (xy 106.152241 -287.955528) (xy 106.139863 -287.906649)
			(xy 106.135699 -287.8564) (xy 104.866445 -287.8564) (xy 104.862281 -287.906655) (xy 104.849902 -287.955539)
			(xy 104.829647 -288.001719) (xy 104.802068 -288.043936) (xy 104.767917 -288.081038) (xy 104.728125 -288.112013)
			(xy 104.683777 -288.136017) (xy 104.636084 -288.152394) (xy 104.586345 -288.160699) (xy 104.561132 -288.161222)
			(xy 103.621078 -288.161222) (xy 103.595868 -288.160656) (xy 103.546135 -288.152354) (xy 103.498447 -288.13598)
			(xy 103.454105 -288.11198) (xy 103.414317 -288.081009) (xy 103.380169 -288.043912) (xy 103.352593 -288.001701)
			(xy 103.33234 -287.955527) (xy 103.319963 -287.906649) (xy 103.315799 -287.8564) (xy 102.046545 -287.8564)
			(xy 102.04238 -287.906656) (xy 102.030002 -287.95554) (xy 102.009746 -288.001721) (xy 101.982166 -288.043938)
			(xy 101.948014 -288.081041) (xy 101.90822 -288.112016) (xy 101.863872 -288.136019) (xy 101.816177 -288.152396)
			(xy 101.766438 -288.1607) (xy 101.741224 -288.161222) (xy 100.80117 -288.161222) (xy 100.77596 -288.160655)
			(xy 100.726229 -288.152352) (xy 100.678542 -288.135977) (xy 100.634201 -288.111977) (xy 100.594414 -288.081006)
			(xy 100.560267 -288.043909) (xy 100.532692 -288.001699) (xy 100.512439 -287.955525) (xy 100.500063 -287.906648)
			(xy 100.495899 -287.8564) (xy 99.226473 -287.8564) (xy 99.222307 -287.906667) (xy 99.209924 -287.955562)
			(xy 99.189662 -288.001752) (xy 99.162072 -288.043977) (xy 99.127909 -288.081084) (xy 99.088103 -288.112061)
			(xy 99.043741 -288.136064) (xy 98.996034 -288.152437) (xy 98.946282 -288.160733) (xy 98.921062 -288.161222)
			(xy 97.981008 -288.161222) (xy 97.955794 -288.160687) (xy 97.906053 -288.152388) (xy 97.858356 -288.136015)
			(xy 97.814005 -288.112014) (xy 97.774209 -288.081041) (xy 97.740055 -288.04394) (xy 97.712472 -288.001723)
			(xy 97.692215 -287.955542) (xy 97.679835 -287.906656) (xy 97.675671 -287.8564) (xy 97.371662 -287.8564)
			(xy 97.371662 -287.856422) (xy 97.371223 -287.879976) (xy 97.364498 -287.926602) (xy 97.351229 -287.971803)
			(xy 97.331685 -288.014667) (xy 97.319338 -288.03473) (xy 97.311464 -288.046922) (xy 97.310956 -288.075116)
			(xy 97.45472 -288.323274) (xy 97.479612 -288.336736) (xy 97.49409 -288.335974) (xy 97.511108 -288.335466)
			(xy 97.537097 -288.335976) (xy 97.588434 -288.344108) (xy 97.637868 -288.360171) (xy 97.68418 -288.38377)
			(xy 97.72623 -288.414322) (xy 97.762983 -288.451076) (xy 97.793535 -288.493127) (xy 97.817132 -288.53944)
			(xy 97.833193 -288.588873) (xy 97.841324 -288.640211) (xy 97.841324 -288.6662) (xy 108.485651 -288.6662)
			(xy 108.489816 -288.615942) (xy 108.502196 -288.567055) (xy 108.522453 -288.520872) (xy 108.550036 -288.478653)
			(xy 108.584191 -288.44155) (xy 108.623987 -288.410575) (xy 108.668339 -288.386572) (xy 108.716036 -288.370196)
			(xy 108.765779 -288.361895) (xy 108.790994 -288.361374) (xy 109.731048 -288.361374) (xy 109.756257 -288.36195)
			(xy 109.805985 -288.370255) (xy 109.853669 -288.386632) (xy 109.898007 -288.410633) (xy 109.93779 -288.441603)
			(xy 109.971934 -288.478699) (xy 109.999507 -288.520908) (xy 110.019758 -288.56708) (xy 110.032133 -288.615955)
			(xy 110.036297 -288.6662) (xy 110.032133 -288.716445) (xy 110.019758 -288.76532) (xy 109.999507 -288.811492)
			(xy 109.971934 -288.853701) (xy 109.93779 -288.890797) (xy 109.898007 -288.921767) (xy 109.853669 -288.945768)
			(xy 109.805985 -288.962145) (xy 109.756257 -288.97045) (xy 109.731048 -288.970974) (xy 108.790994 -288.970974)
			(xy 108.765779 -288.970505) (xy 108.716036 -288.962204) (xy 108.668339 -288.945828) (xy 108.623987 -288.921825)
			(xy 108.584191 -288.89085) (xy 108.550036 -288.853747) (xy 108.522453 -288.811528) (xy 108.502196 -288.765345)
			(xy 108.489816 -288.716458) (xy 108.485651 -288.6662) (xy 97.841324 -288.6662) (xy 97.841324 -288.692189)
			(xy 97.833193 -288.743527) (xy 97.817132 -288.79296) (xy 97.793535 -288.839273) (xy 97.762983 -288.881324)
			(xy 97.72623 -288.918078) (xy 97.68418 -288.94863) (xy 97.637868 -288.972229) (xy 97.588434 -288.988292)
			(xy 97.537097 -288.996424) (xy 97.511108 -288.996882) (xy 97.496376 -288.996628) (xy 97.482152 -288.995866)
			(xy 97.45726 -289.009582) (xy 97.31248 -289.259264) (xy 97.312988 -289.287458) (xy 97.320608 -289.29965)
			(xy 97.332705 -289.319553) (xy 97.3518 -289.362036) (xy 97.364745 -289.406777) (xy 97.371283 -289.452892)
			(xy 97.371662 -289.47618) (xy 97.371662 -289.4762) (xy 97.675629 -289.4762) (xy 97.679794 -289.425937)
			(xy 97.692175 -289.377045) (xy 97.712435 -289.330857) (xy 97.740021 -289.288635) (xy 97.774181 -289.251528)
			(xy 97.813982 -289.220551) (xy 97.858339 -289.196547) (xy 97.906042 -289.180172) (xy 97.95579 -289.171871)
			(xy 97.981008 -289.17138) (xy 98.921062 -289.17138) (xy 98.946278 -289.171909) (xy 98.996023 -289.180204)
			(xy 99.043724 -289.196575) (xy 99.08808 -289.220574) (xy 99.12788 -289.251547) (xy 99.162039 -289.288649)
			(xy 99.189625 -289.330868) (xy 99.209885 -289.377052) (xy 99.222266 -289.42594) (xy 99.226431 -289.4762)
			(xy 100.495857 -289.4762) (xy 100.500021 -289.425945) (xy 100.5124 -289.377061) (xy 100.532655 -289.330881)
			(xy 100.560234 -289.288665) (xy 100.594386 -289.251563) (xy 100.634178 -289.220588) (xy 100.678525 -289.196584)
			(xy 100.726218 -289.180207) (xy 100.775957 -289.171903) (xy 100.80117 -289.17138) (xy 101.741224 -289.17138)
			(xy 101.766434 -289.171942) (xy 101.816167 -289.180245) (xy 101.863855 -289.196619) (xy 101.908197 -289.220619)
			(xy 101.947985 -289.25159) (xy 101.982133 -289.288687) (xy 102.009709 -289.330899) (xy 102.029962 -289.377073)
			(xy 102.042339 -289.425951) (xy 102.046503 -289.4762) (xy 103.315757 -289.4762) (xy 103.319922 -289.425945)
			(xy 103.3323 -289.37706) (xy 103.352556 -289.330879) (xy 103.380136 -289.288662) (xy 103.414289 -289.25156)
			(xy 103.454082 -289.220585) (xy 103.49843 -289.196582) (xy 103.546125 -289.180205) (xy 103.595864 -289.171902)
			(xy 103.621078 -289.17138) (xy 104.561132 -289.17138) (xy 104.586342 -289.171943) (xy 104.636073 -289.180246)
			(xy 104.68376 -289.196622) (xy 104.728102 -289.220622) (xy 104.767888 -289.251593) (xy 104.802035 -289.28869)
			(xy 104.82961 -289.330901) (xy 104.849863 -289.377075) (xy 104.862239 -289.425952) (xy 104.866403 -289.4762)
			(xy 106.135657 -289.4762) (xy 106.139822 -289.425944) (xy 106.152201 -289.377058) (xy 106.172457 -289.330877)
			(xy 106.200038 -289.288659) (xy 106.234192 -289.251557) (xy 106.273986 -289.220582) (xy 106.318336 -289.19658)
			(xy 106.366031 -289.180204) (xy 106.415772 -289.171901) (xy 106.440986 -289.17138) (xy 107.38104 -289.17138)
			(xy 107.40625 -289.171943) (xy 107.45598 -289.180248) (xy 107.503666 -289.196624) (xy 107.548006 -289.220625)
			(xy 107.587791 -289.251596) (xy 107.621937 -289.288693) (xy 107.649512 -289.330903) (xy 107.669763 -289.377076)
			(xy 107.682139 -289.425953) (xy 107.686303 -289.4762) (xy 107.682139 -289.526447) (xy 107.669763 -289.575324)
			(xy 107.649512 -289.621497) (xy 107.621937 -289.663707) (xy 107.587791 -289.700804) (xy 107.548006 -289.731775)
			(xy 107.503666 -289.755776) (xy 107.45598 -289.772152) (xy 107.40625 -289.780457) (xy 107.38104 -289.78098)
			(xy 106.440986 -289.78098) (xy 106.415772 -289.780499) (xy 106.366031 -289.772196) (xy 106.318336 -289.75582)
			(xy 106.273986 -289.731818) (xy 106.234192 -289.700843) (xy 106.200038 -289.663741) (xy 106.172457 -289.621523)
			(xy 106.152201 -289.575342) (xy 106.139822 -289.526456) (xy 106.135657 -289.4762) (xy 104.866403 -289.4762)
			(xy 104.862239 -289.526448) (xy 104.849863 -289.575325) (xy 104.82961 -289.621499) (xy 104.802035 -289.66371)
			(xy 104.767888 -289.700807) (xy 104.728102 -289.731778) (xy 104.68376 -289.755778) (xy 104.636074 -289.772154)
			(xy 104.586342 -289.780457) (xy 104.561132 -289.78098) (xy 103.621078 -289.78098) (xy 103.595864 -289.780498)
			(xy 103.546125 -289.772195) (xy 103.49843 -289.755818) (xy 103.454082 -289.731815) (xy 103.414289 -289.70084)
			(xy 103.380136 -289.663738) (xy 103.352556 -289.621521) (xy 103.3323 -289.57534) (xy 103.319922 -289.526455)
			(xy 103.315757 -289.4762) (xy 102.046503 -289.4762) (xy 102.042339 -289.526449) (xy 102.029962 -289.575327)
			(xy 102.009709 -289.621501) (xy 101.982133 -289.663713) (xy 101.947985 -289.70081) (xy 101.908197 -289.731781)
			(xy 101.863855 -289.755781) (xy 101.816167 -289.772155) (xy 101.766434 -289.780458) (xy 101.741224 -289.78098)
			(xy 100.80117 -289.78098) (xy 100.775957 -289.780497) (xy 100.726218 -289.772193) (xy 100.678525 -289.755816)
			(xy 100.634178 -289.731812) (xy 100.594386 -289.700837) (xy 100.560234 -289.663735) (xy 100.532655 -289.621519)
			(xy 100.5124 -289.575339) (xy 100.500021 -289.526455) (xy 100.495857 -289.4762) (xy 99.226431 -289.4762)
			(xy 99.222266 -289.52646) (xy 99.209885 -289.575348) (xy 99.189625 -289.621532) (xy 99.162039 -289.663751)
			(xy 99.12788 -289.700853) (xy 99.08808 -289.731826) (xy 99.043724 -289.755825) (xy 98.996023 -289.772196)
			(xy 98.946278 -289.780491) (xy 98.921062 -289.78098) (xy 97.981008 -289.78098) (xy 97.95579 -289.780529)
			(xy 97.906042 -289.772228) (xy 97.858339 -289.755853) (xy 97.813982 -289.731849) (xy 97.774181 -289.700872)
			(xy 97.740021 -289.663765) (xy 97.712435 -289.621543) (xy 97.692175 -289.575355) (xy 97.679794 -289.526463)
			(xy 97.675629 -289.4762) (xy 97.371662 -289.4762) (xy 97.37118 -289.502169) (xy 97.363051 -289.553507)
			(xy 97.34699 -289.602942) (xy 97.323393 -289.649254) (xy 97.29284 -289.691305) (xy 97.256085 -289.728057)
			(xy 97.214032 -289.758606) (xy 97.167717 -289.7822) (xy 97.118282 -289.798257) (xy 97.066943 -289.806382)
			(xy 97.040954 -289.806888) (xy 97.026476 -289.806634) (xy 97.012252 -289.805872) (xy 96.98736 -289.819588)
			(xy 96.84258 -290.06927) (xy 96.843088 -290.097464) (xy 96.850708 -290.109656) (xy 96.862805 -290.12956)
			(xy 96.881899 -290.172042) (xy 96.894843 -290.216783) (xy 96.90138 -290.262898) (xy 96.901762 -290.286186)
			(xy 96.901762 -290.2862) (xy 108.485663 -290.2862) (xy 108.489828 -290.235944) (xy 108.502207 -290.187059)
			(xy 108.522464 -290.140878) (xy 108.550045 -290.09866) (xy 108.584199 -290.061559) (xy 108.623994 -290.030585)
			(xy 108.668344 -290.006583) (xy 108.716039 -289.990208) (xy 108.76578 -289.981907) (xy 108.790994 -289.981386)
			(xy 109.731048 -289.981386) (xy 109.756258 -289.981938) (xy 109.805988 -289.990244) (xy 109.853673 -290.006621)
			(xy 109.898013 -290.030623) (xy 109.937798 -290.061594) (xy 109.971944 -290.098692) (xy 109.999518 -290.140903)
			(xy 110.019769 -290.187076) (xy 110.032145 -290.235953) (xy 110.036309 -290.2862) (xy 110.032145 -290.336447)
			(xy 110.019769 -290.385324) (xy 109.999518 -290.431497) (xy 109.971944 -290.473708) (xy 109.937798 -290.510806)
			(xy 109.898013 -290.541777) (xy 109.853673 -290.565779) (xy 109.805988 -290.582156) (xy 109.756258 -290.590462)
			(xy 109.731048 -290.590986) (xy 108.790994 -290.590986) (xy 108.76578 -290.590493) (xy 108.716039 -290.582192)
			(xy 108.668344 -290.565817) (xy 108.623994 -290.541815) (xy 108.584199 -290.510841) (xy 108.550045 -290.47374)
			(xy 108.522464 -290.431522) (xy 108.502207 -290.385341) (xy 108.489828 -290.336456) (xy 108.485663 -290.2862)
			(xy 96.901762 -290.2862) (xy 96.90128 -290.312175) (xy 96.89315 -290.363512) (xy 96.877089 -290.412946)
			(xy 96.853491 -290.459258) (xy 96.822938 -290.501307) (xy 96.786183 -290.538059) (xy 96.74413 -290.568608)
			(xy 96.697816 -290.592201) (xy 96.648381 -290.608258) (xy 96.597043 -290.616382) (xy 96.571054 -290.616894)
			(xy 96.556322 -290.61664) (xy 96.542098 -290.615878) (xy 96.51746 -290.629594) (xy 96.372426 -290.879022)
			(xy 96.372934 -290.907216) (xy 96.380554 -290.919408) (xy 96.392703 -290.939327) (xy 96.411883 -290.98186)
			(xy 96.424882 -291.02667) (xy 96.43144 -291.072863) (xy 96.431862 -291.096192) (xy 96.431862 -291.0962)
			(xy 97.675641 -291.0962) (xy 97.679806 -291.045939) (xy 97.692187 -290.997048) (xy 97.712446 -290.950863)
			(xy 97.740031 -290.908642) (xy 97.774189 -290.871537) (xy 97.813989 -290.840561) (xy 97.858344 -290.816558)
			(xy 97.906045 -290.800183) (xy 97.955791 -290.791883) (xy 97.981008 -290.791392) (xy 98.921062 -290.791392)
			(xy 98.946279 -290.791897) (xy 98.996026 -290.800193) (xy 99.043729 -290.816564) (xy 99.088087 -290.840564)
			(xy 99.127888 -290.871538) (xy 99.162049 -290.908642) (xy 99.189635 -290.950862) (xy 99.209896 -290.997048)
			(xy 99.222278 -291.045938) (xy 99.226443 -291.0962) (xy 100.495869 -291.0962) (xy 100.500033 -291.045947)
			(xy 100.512411 -290.997065) (xy 100.532665 -290.950887) (xy 100.560244 -290.908672) (xy 100.594394 -290.871572)
			(xy 100.634184 -290.840598) (xy 100.67853 -290.816595) (xy 100.726221 -290.800219) (xy 100.775958 -290.791915)
			(xy 100.80117 -290.791392) (xy 101.741224 -290.791392) (xy 101.766435 -290.79193) (xy 101.81617 -290.800233)
			(xy 101.86386 -290.816608) (xy 101.908204 -290.840609) (xy 101.947993 -290.871581) (xy 101.982142 -290.90868)
			(xy 102.00972 -290.950893) (xy 102.029973 -290.997069) (xy 102.042351 -291.045949) (xy 102.046515 -291.0962)
			(xy 103.315769 -291.0962) (xy 103.319933 -291.045947) (xy 103.332312 -290.997064) (xy 103.352567 -290.950885)
			(xy 103.380146 -290.908669) (xy 103.414297 -290.871569) (xy 103.454088 -290.840595) (xy 103.498435 -290.816593)
			(xy 103.546128 -290.800217) (xy 103.595865 -290.791914) (xy 103.621078 -290.791392) (xy 104.561132 -290.791392)
			(xy 104.586343 -290.791931) (xy 104.636076 -290.800235) (xy 104.683765 -290.816611) (xy 104.728108 -290.840612)
			(xy 104.767896 -290.871584) (xy 104.802044 -290.908683) (xy 104.829621 -290.950895) (xy 104.849874 -290.997071)
			(xy 104.862251 -291.04595) (xy 104.866415 -291.0962) (xy 106.135669 -291.0962) (xy 106.139834 -291.045946)
			(xy 106.152212 -290.997062) (xy 106.172468 -290.950883) (xy 106.200048 -290.908667) (xy 106.2342 -290.871566)
			(xy 106.273993 -290.840592) (xy 106.318341 -290.816591) (xy 106.366034 -290.800215) (xy 106.415773 -290.791913)
			(xy 106.440986 -290.791392) (xy 107.38104 -290.791392) (xy 107.40625 -290.791931) (xy 107.455983 -290.800236)
			(xy 107.50367 -290.816613) (xy 107.548012 -290.840615) (xy 107.587799 -290.871587) (xy 107.621946 -290.908685)
			(xy 107.649522 -290.950897) (xy 107.669774 -290.997073) (xy 107.682151 -291.045951) (xy 107.686315 -291.0962)
			(xy 107.682151 -291.146449) (xy 107.669774 -291.195327) (xy 107.649522 -291.241503) (xy 107.621946 -291.283715)
			(xy 107.587799 -291.320813) (xy 107.548012 -291.351785) (xy 107.50367 -291.375787) (xy 107.455983 -291.392164)
			(xy 107.406251 -291.400469) (xy 107.38104 -291.400992) (xy 106.440986 -291.400992) (xy 106.415773 -291.400487)
			(xy 106.366034 -291.392185) (xy 106.318341 -291.375809) (xy 106.273993 -291.351808) (xy 106.2342 -291.320834)
			(xy 106.200048 -291.283733) (xy 106.172468 -291.241517) (xy 106.152212 -291.195338) (xy 106.139834 -291.146454)
			(xy 106.135669 -291.0962) (xy 104.866415 -291.0962) (xy 104.862251 -291.14645) (xy 104.849874 -291.195329)
			(xy 104.829621 -291.241505) (xy 104.802044 -291.283717) (xy 104.767896 -291.320816) (xy 104.728108 -291.351788)
			(xy 104.683765 -291.375789) (xy 104.636076 -291.392165) (xy 104.586343 -291.400469) (xy 104.561132 -291.400992)
			(xy 103.621078 -291.400992) (xy 103.595865 -291.400486) (xy 103.546128 -291.392183) (xy 103.498435 -291.375807)
			(xy 103.454088 -291.351805) (xy 103.414297 -291.320831) (xy 103.380146 -291.283731) (xy 103.352567 -291.241515)
			(xy 103.332312 -291.195336) (xy 103.319933 -291.146453) (xy 103.315769 -291.0962) (xy 102.046515 -291.0962)
			(xy 102.042351 -291.146451) (xy 102.029973 -291.195331) (xy 102.00972 -291.241507) (xy 101.982142 -291.28372)
			(xy 101.947993 -291.320819) (xy 101.908204 -291.351791) (xy 101.86386 -291.375792) (xy 101.81617 -291.392167)
			(xy 101.766435 -291.40047) (xy 101.741224 -291.400992) (xy 100.80117 -291.400992) (xy 100.775958 -291.400485)
			(xy 100.726221 -291.392181) (xy 100.67853 -291.375805) (xy 100.634184 -291.351802) (xy 100.594394 -291.320828)
			(xy 100.560244 -291.283728) (xy 100.532665 -291.241513) (xy 100.512411 -291.195335) (xy 100.500033 -291.146453)
			(xy 100.495869 -291.0962) (xy 99.226443 -291.0962) (xy 99.222278 -291.146462) (xy 99.209896 -291.195352)
			(xy 99.189635 -291.241538) (xy 99.162049 -291.283758) (xy 99.127888 -291.320862) (xy 99.088087 -291.351836)
			(xy 99.043729 -291.375836) (xy 98.996026 -291.392207) (xy 98.946279 -291.400503) (xy 98.921062 -291.400992)
			(xy 97.981008 -291.400992) (xy 97.955791 -291.400517) (xy 97.906045 -291.392217) (xy 97.858344 -291.375842)
			(xy 97.813989 -291.351839) (xy 97.774189 -291.320863) (xy 97.740031 -291.283758) (xy 97.712446 -291.241537)
			(xy 97.692187 -291.195352) (xy 97.679806 -291.146461) (xy 97.675641 -291.0962) (xy 96.431862 -291.0962)
			(xy 96.431379 -291.12218) (xy 96.423249 -291.173517) (xy 96.407187 -291.22295) (xy 96.383589 -291.269261)
			(xy 96.353036 -291.31131) (xy 96.316281 -291.348061) (xy 96.274228 -291.378609) (xy 96.227915 -291.402201)
			(xy 96.17848 -291.418258) (xy 96.127142 -291.426382) (xy 96.101154 -291.4269) (xy 96.086422 -291.426646)
			(xy 96.071944 -291.425884) (xy 96.047306 -291.439346) (xy 95.902272 -291.689282) (xy 95.903034 -291.717476)
			(xy 95.910654 -291.729414) (xy 95.922761 -291.749347) (xy 95.941863 -291.791892) (xy 95.954797 -291.836699)
			(xy 95.961308 -291.882879) (xy 95.961708 -291.906198) (xy 95.961225 -291.932187) (xy 95.953094 -291.983526)
			(xy 95.937032 -292.032961) (xy 95.913434 -292.079274) (xy 95.882882 -292.121326) (xy 95.846128 -292.158081)
			(xy 95.804076 -292.188633) (xy 95.757763 -292.212231) (xy 95.708328 -292.228294) (xy 95.656989 -292.236425)
			(xy 95.631 -292.236906) (xy 95.616268 -292.236652) (xy 95.602044 -292.23589) (xy 95.577152 -292.249606)
			(xy 95.432372 -292.499034) (xy 95.43288 -292.527228) (xy 95.4405 -292.53942) (xy 95.452656 -292.559337)
			(xy 95.471851 -292.601868) (xy 95.484863 -292.646678) (xy 95.491435 -292.692873) (xy 95.491808 -292.716204)
			(xy 95.491298 -292.742191) (xy 95.483167 -292.793525) (xy 95.467106 -292.842955) (xy 95.44351 -292.889264)
			(xy 95.41296 -292.931312) (xy 95.376208 -292.968062) (xy 95.334161 -292.998612) (xy 95.287851 -293.022207)
			(xy 95.238421 -293.038268) (xy 95.187087 -293.046398) (xy 95.1611 -293.046912) (xy 95.146114 -293.046658)
			(xy 95.13189 -293.045896) (xy 95.107252 -293.059358) (xy 94.962218 -293.30904) (xy 94.962726 -293.337488)
			(xy 94.970346 -293.349426) (xy 94.9825 -293.369344) (xy 95.001691 -293.411875) (xy 95.014701 -293.456685)
			(xy 95.021271 -293.50288) (xy 95.021654 -293.52621) (xy 95.021144 -293.552198) (xy 95.013012 -293.603534)
			(xy 94.996951 -293.652966) (xy 94.973355 -293.699278) (xy 94.942806 -293.741328) (xy 94.906056 -293.778083)
			(xy 94.864008 -293.808636) (xy 94.817699 -293.832237) (xy 94.768269 -293.848304) (xy 94.716934 -293.856441)
			(xy 94.690946 -293.856918) (xy 94.665441 -293.85645) (xy 94.615034 -293.848627) (xy 94.566425 -293.833159)
			(xy 94.520766 -293.810413) (xy 94.47914 -293.780928) (xy 94.442534 -293.745402) (xy 94.411814 -293.704679)
			(xy 94.399354 -293.68242) (xy 94.39275 -293.669974) (xy 94.368874 -293.655496) (xy 94.073218 -293.655496)
			(xy 94.049342 -293.669974) (xy 94.042738 -293.68242) (xy 94.030261 -293.704667) (xy 93.99953 -293.745375)
			(xy 93.96292 -293.780888) (xy 93.921297 -293.810368) (xy 93.875646 -293.833117) (xy 93.827047 -293.848596)
			(xy 93.776648 -293.856439) (xy 93.751146 -293.856918) (xy 93.736414 -293.856664) (xy 93.721936 -293.855902)
			(xy 93.697298 -293.869364) (xy 93.53804 -294.143684) (xy 93.53804 -294.171116) (xy 93.544898 -294.1828)
			(xy 93.557884 -294.206263) (xy 93.576328 -294.256613) (xy 93.585719 -294.309406) (xy 93.5863 -294.336216)
			(xy 93.585828 -294.360206) (xy 93.57832 -294.407595) (xy 93.563491 -294.453227) (xy 93.541707 -294.495977)
			(xy 93.513503 -294.534792) (xy 93.479574 -294.568718) (xy 93.440756 -294.596919) (xy 93.398005 -294.6187)
			(xy 93.352372 -294.633526) (xy 93.304982 -294.64103) (xy 93.280992 -294.641524) (xy 93.265244 -294.641524)
			(xy 93.241622 -294.654986) (xy 93.06814 -294.95369) (xy 93.06814 -294.981122) (xy 93.074998 -294.992806)
			(xy 93.087984 -295.016269) (xy 93.106427 -295.066619) (xy 93.115816 -295.119412) (xy 93.1164 -295.146222)
			(xy 93.115928 -295.170212) (xy 93.108419 -295.2176) (xy 93.093589 -295.263231) (xy 93.071805 -295.30598)
			(xy 93.043601 -295.344795) (xy 93.009672 -295.37872) (xy 92.970854 -295.40692) (xy 92.928103 -295.428701)
			(xy 92.882471 -295.443526) (xy 92.835082 -295.45103) (xy 92.811092 -295.45153) (xy 92.795344 -295.45153)
			(xy 92.771468 -295.464992) (xy 92.61221 -295.739312) (xy 92.612972 -295.767506) (xy 92.620592 -295.779444)
			(xy 92.632705 -295.799375) (xy 92.651819 -295.841919) (xy 92.664766 -295.886726) (xy 92.671288 -295.932908)
			(xy 92.671646 -295.956228) (xy 92.671134 -295.982215) (xy 92.663001 -296.033548) (xy 92.646938 -296.082977)
			(xy 92.623341 -296.129286) (xy 92.592791 -296.171333) (xy 92.556041 -296.208085) (xy 92.513994 -296.238636)
			(xy 92.467687 -296.262234) (xy 92.418258 -296.278298) (xy 92.366925 -296.286434) (xy 92.340938 -296.286936)
			(xy 92.315433 -296.286467) (xy 92.265026 -296.278643) (xy 92.216417 -296.263175) (xy 92.170759 -296.240429)
			(xy 92.129133 -296.210945) (xy 92.092526 -296.17542) (xy 92.061805 -296.134698) (xy 92.049346 -296.112438)
			(xy 92.042742 -296.099992) (xy 92.018866 -296.085768) (xy 91.694762 -296.085768) (xy 91.671394 -296.098976)
			(xy 91.664536 -296.11066) (xy 91.651752 -296.13151) (xy 91.620609 -296.169215) (xy 91.583854 -296.201475)
			(xy 91.542427 -296.227463) (xy 91.497387 -296.246516) (xy 91.449886 -296.258147) (xy 91.401138 -296.262057)
			(xy 91.35239 -296.258147) (xy 91.304889 -296.246516) (xy 91.259849 -296.227463) (xy 91.218422 -296.201475)
			(xy 91.181667 -296.169215) (xy 91.150524 -296.13151) (xy 91.13774 -296.11066) (xy 91.130882 -296.098976)
			(xy 91.107514 -296.085768) (xy 90.783156 -296.085768) (xy 90.75928 -296.099992) (xy 90.752676 -296.112438)
			(xy 90.740203 -296.134687) (xy 90.709477 -296.175397) (xy 90.672868 -296.210912) (xy 90.631244 -296.240388)
			(xy 90.58559 -296.263129) (xy 90.536987 -296.278595) (xy 90.486586 -296.286421) (xy 90.435582 -296.286421)
			(xy 90.385181 -296.278595) (xy 90.336578 -296.263129) (xy 90.290924 -296.240388) (xy 90.2493 -296.210912)
			(xy 90.212691 -296.175397) (xy 90.181965 -296.134687) (xy 90.169492 -296.112438) (xy 90.162888 -296.099992)
			(xy 90.139012 -296.085768) (xy 89.814654 -296.085768) (xy 89.791286 -296.098976) (xy 89.784428 -296.11066)
			(xy 89.771644 -296.13151) (xy 89.740501 -296.169215) (xy 89.703746 -296.201475) (xy 89.662319 -296.227463)
			(xy 89.617279 -296.246516) (xy 89.569778 -296.258147) (xy 89.52103 -296.262057) (xy 89.472282 -296.258147)
			(xy 89.424781 -296.246516) (xy 89.379741 -296.227463) (xy 89.338314 -296.201475) (xy 89.301559 -296.169215)
			(xy 89.270416 -296.13151) (xy 89.257632 -296.11066) (xy 89.250774 -296.098976) (xy 89.227406 -296.085768)
			(xy 88.903048 -296.085768) (xy 88.879172 -296.099992) (xy 88.872568 -296.112438) (xy 88.860095 -296.134687)
			(xy 88.829369 -296.175397) (xy 88.79276 -296.210912) (xy 88.751136 -296.240388) (xy 88.705482 -296.263129)
			(xy 88.656879 -296.278595) (xy 88.606478 -296.286421) (xy 88.555474 -296.286421) (xy 88.505073 -296.278595)
			(xy 88.45647 -296.263129) (xy 88.410816 -296.240388) (xy 88.369192 -296.210912) (xy 88.332583 -296.175397)
			(xy 88.301857 -296.134687) (xy 88.289384 -296.112438) (xy 88.28278 -296.099992) (xy 88.258904 -296.085768)
			(xy 86.994746 -296.085768) (xy 86.971378 -296.098976) (xy 86.96452 -296.11066) (xy 86.951736 -296.13151)
			(xy 86.920593 -296.169215) (xy 86.883838 -296.201475) (xy 86.842411 -296.227463) (xy 86.797371 -296.246516)
			(xy 86.74987 -296.258147) (xy 86.701122 -296.262057) (xy 86.652374 -296.258147) (xy 86.604873 -296.246516)
			(xy 86.559833 -296.227463) (xy 86.518406 -296.201475) (xy 86.481651 -296.169215) (xy 86.450508 -296.13151)
			(xy 86.437724 -296.11066) (xy 86.430866 -296.098976) (xy 86.407498 -296.085768) (xy 86.08314 -296.085768)
			(xy 86.059264 -296.099992) (xy 86.05266 -296.112438) (xy 86.040187 -296.134687) (xy 86.009461 -296.175397)
			(xy 85.972852 -296.210912) (xy 85.931228 -296.240388) (xy 85.885574 -296.263129) (xy 85.836971 -296.278595)
			(xy 85.78657 -296.286421) (xy 85.735566 -296.286421) (xy 85.685165 -296.278595) (xy 85.636562 -296.263129)
			(xy 85.590908 -296.240388) (xy 85.549284 -296.210912) (xy 85.512675 -296.175397) (xy 85.481949 -296.134687)
			(xy 85.469476 -296.112438) (xy 85.462872 -296.099992) (xy 85.438996 -296.085768) (xy 85.114638 -296.085768)
			(xy 85.09127 -296.098976) (xy 85.084412 -296.11066) (xy 85.071628 -296.13151) (xy 85.040485 -296.169215)
			(xy 85.00373 -296.201475) (xy 84.962303 -296.227463) (xy 84.917263 -296.246516) (xy 84.869762 -296.258147)
			(xy 84.821014 -296.262057) (xy 84.772266 -296.258147) (xy 84.724765 -296.246516) (xy 84.679725 -296.227463)
			(xy 84.638298 -296.201475) (xy 84.601543 -296.169215) (xy 84.5704 -296.13151) (xy 84.557616 -296.11066)
			(xy 84.550758 -296.098976) (xy 84.52739 -296.085768) (xy 84.203032 -296.085768) (xy 84.179156 -296.099992)
			(xy 84.172552 -296.112438) (xy 84.160079 -296.134687) (xy 84.129353 -296.175397) (xy 84.092744 -296.210912)
			(xy 84.05112 -296.240388) (xy 84.005466 -296.263129) (xy 83.956863 -296.278595) (xy 83.906462 -296.286421)
			(xy 83.855458 -296.286421) (xy 83.805057 -296.278595) (xy 83.756454 -296.263129) (xy 83.7108 -296.240388)
			(xy 83.669176 -296.210912) (xy 83.632567 -296.175397) (xy 83.601841 -296.134687) (xy 83.589368 -296.112438)
			(xy 83.582764 -296.099992) (xy 83.558888 -296.085768) (xy 83.23453 -296.085768) (xy 83.211162 -296.098976)
			(xy 83.204304 -296.11066) (xy 83.19152 -296.13151) (xy 83.160377 -296.169215) (xy 83.123622 -296.201475)
			(xy 83.082195 -296.227463) (xy 83.037155 -296.246516) (xy 82.989654 -296.258147) (xy 82.940906 -296.262057)
			(xy 82.892158 -296.258147) (xy 82.844657 -296.246516) (xy 82.799617 -296.227463) (xy 82.75819 -296.201475)
			(xy 82.721435 -296.169215) (xy 82.690292 -296.13151) (xy 82.677508 -296.11066) (xy 82.67065 -296.098976)
			(xy 82.647282 -296.085768) (xy 79.503016 -296.085768) (xy 79.47914 -296.099992) (xy 79.472536 -296.112438)
			(xy 79.460063 -296.134689) (xy 79.429337 -296.175406) (xy 79.392729 -296.210928) (xy 79.351106 -296.240416)
			(xy 79.305453 -296.26317) (xy 79.256851 -296.278653) (xy 79.206448 -296.286499) (xy 79.180944 -296.286936)
			(xy 79.154615 -296.286422) (xy 79.102623 -296.278069) (xy 79.052611 -296.261583) (xy 79.005843 -296.237381)
			(xy 78.984348 -296.222166) (xy 78.97765 -296.217585) (xy 78.962233 -296.212544) (xy 78.954122 -296.21226)
			(xy 69.146928 -296.21226) (xy 69.136865 -296.212698) (xy 69.118285 -296.220437) (xy 69.11086 -296.227246)
			(xy 60.557664 -304.780442) (xy 78.812394 -304.780442) (xy 78.816423 -304.638121) (xy 78.828498 -304.496256)
			(xy 78.848579 -304.355302) (xy 78.876602 -304.215709) (xy 78.912478 -304.077925) (xy 78.956092 -303.942392)
			(xy 79.007304 -303.809543) (xy 79.06595 -303.679804) (xy 79.131841 -303.553591) (xy 79.204768 -303.431308)
			(xy 79.284496 -303.313346) (xy 79.37077 -303.200084) (xy 79.463314 -303.091885) (xy 79.56183 -302.989094)
			(xy 79.666005 -302.892042) (xy 79.775503 -302.801038) (xy 79.889974 -302.716376) (xy 80.009052 -302.638325)
			(xy 80.132355 -302.567136) (xy 80.259488 -302.503037) (xy 80.390044 -302.446233) (xy 80.523604 -302.396907)
			(xy 80.659741 -302.355215) (xy 80.798019 -302.321292) (xy 80.937994 -302.295247) (xy 81.079219 -302.277162)
			(xy 81.22124 -302.267097) (xy 81.363604 -302.265082) (xy 81.505854 -302.271125) (xy 81.647534 -302.285205)
			(xy 81.78819 -302.307279) (xy 81.927372 -302.337275) (xy 82.064634 -302.375097) (xy 82.199537 -302.420625)
			(xy 82.331648 -302.473711) (xy 82.460544 -302.534187) (xy 82.585812 -302.601858) (xy 82.707051 -302.676508)
			(xy 82.823872 -302.757897) (xy 82.935902 -302.845765) (xy 83.042781 -302.939831) (xy 83.144167 -303.039792)
			(xy 83.239736 -303.14533) (xy 83.329181 -303.256105) (xy 83.412215 -303.371763) (xy 83.488573 -303.491933)
			(xy 83.55801 -303.616231) (xy 83.620303 -303.744258) (xy 83.675254 -303.875605) (xy 83.722686 -304.00985)
			(xy 83.762447 -304.146563) (xy 83.794409 -304.285307) (xy 83.818471 -304.425637) (xy 83.834555 -304.567103)
			(xy 83.842611 -304.709253) (xy 83.843114 -304.780442) (xy 83.842611 -304.851631) (xy 83.834555 -304.993781)
			(xy 83.818471 -305.135247) (xy 83.794409 -305.275577) (xy 83.762447 -305.414321) (xy 83.722686 -305.551034)
			(xy 83.675254 -305.685279) (xy 83.620303 -305.816626) (xy 83.55801 -305.944653) (xy 83.488573 -306.068951)
			(xy 83.412215 -306.189121) (xy 83.329181 -306.304779) (xy 83.239736 -306.415554) (xy 83.144167 -306.521092)
			(xy 83.042781 -306.621053) (xy 82.935902 -306.715119) (xy 82.823872 -306.802987) (xy 82.707051 -306.884376)
			(xy 82.585812 -306.959026) (xy 82.460544 -307.026697) (xy 82.331648 -307.087173) (xy 82.199537 -307.140259)
			(xy 82.064634 -307.185787) (xy 81.927372 -307.223609) (xy 81.78819 -307.253605) (xy 81.647534 -307.275679)
			(xy 81.505854 -307.289759) (xy 81.363604 -307.295802) (xy 81.22124 -307.293787) (xy 81.079219 -307.283722)
			(xy 80.937994 -307.265637) (xy 80.798019 -307.239592) (xy 80.659741 -307.205669) (xy 80.523604 -307.163977)
			(xy 80.390044 -307.114651) (xy 80.259488 -307.057847) (xy 80.132355 -306.993748) (xy 80.009052 -306.922559)
			(xy 79.889974 -306.844508) (xy 79.775503 -306.759846) (xy 79.666005 -306.668842) (xy 79.56183 -306.57179)
			(xy 79.463314 -306.468999) (xy 79.37077 -306.3608) (xy 79.284496 -306.247538) (xy 79.204768 -306.129576)
			(xy 79.131841 -306.007293) (xy 79.06595 -305.88108) (xy 79.007304 -305.751341) (xy 78.956092 -305.618492)
			(xy 78.912478 -305.482959) (xy 78.876602 -305.345175) (xy 78.848579 -305.205582) (xy 78.828498 -305.064628)
			(xy 78.816423 -304.922763) (xy 78.812394 -304.780442) (xy 60.557664 -304.780442) (xy 57.078372 -308.259734)
			(xy 57.071523 -308.267131) (xy 57.06379 -308.28573) (xy 57.063386 -308.295802) (xy 57.063386 -309.504588)
			(xy 79.192628 -309.504588) (xy 79.192628 -308.640988) (xy 79.193114 -308.613737) (xy 79.20087 -308.559789)
			(xy 79.216225 -308.507494) (xy 79.238867 -308.457917) (xy 79.268333 -308.412067) (xy 79.304024 -308.370876)
			(xy 79.345215 -308.335185) (xy 79.391065 -308.305719) (xy 79.440642 -308.283077) (xy 79.492937 -308.267722)
			(xy 79.546885 -308.259966) (xy 79.601387 -308.259966) (xy 79.655335 -308.267722) (xy 79.70763 -308.283077)
			(xy 79.757207 -308.305719) (xy 79.803057 -308.335185) (xy 79.844248 -308.370876) (xy 79.879939 -308.412067)
			(xy 79.909405 -308.457917) (xy 79.92811 -308.498873) (xy 93.275072 -308.498873) (xy 93.275072 -308.444327)
			(xy 93.282834 -308.390335) (xy 93.298202 -308.337998) (xy 93.320862 -308.288381) (xy 93.350352 -308.242493)
			(xy 93.386073 -308.20127) (xy 93.427297 -308.16555) (xy 93.473184 -308.13606) (xy 93.522802 -308.113401)
			(xy 93.575139 -308.098034) (xy 93.629131 -308.090271) (xy 93.656404 -308.089808) (xy 94.520004 -308.089808)
			(xy 94.547271 -308.090355) (xy 94.60125 -308.098116) (xy 94.653575 -308.113481) (xy 94.703181 -308.136135)
			(xy 94.749058 -308.165619) (xy 94.790271 -308.201331) (xy 94.825983 -308.242546) (xy 94.855467 -308.288423)
			(xy 94.878121 -308.338029) (xy 94.893485 -308.390354) (xy 94.901246 -308.444333) (xy 94.901246 -308.498867)
			(xy 94.893485 -308.552846) (xy 94.878121 -308.605171) (xy 94.855467 -308.654777) (xy 94.825983 -308.700654)
			(xy 94.790271 -308.741869) (xy 94.749058 -308.777581) (xy 94.703181 -308.807065) (xy 94.653575 -308.829719)
			(xy 94.60125 -308.845084) (xy 94.547271 -308.852845) (xy 94.520004 -308.853332) (xy 93.656404 -308.853332)
			(xy 93.629131 -308.852929) (xy 93.575139 -308.845166) (xy 93.522802 -308.829799) (xy 93.473184 -308.80714)
			(xy 93.427297 -308.77765) (xy 93.386073 -308.74193) (xy 93.350352 -308.700707) (xy 93.320862 -308.654819)
			(xy 93.298202 -308.605202) (xy 93.282834 -308.552865) (xy 93.275072 -308.498873) (xy 79.92811 -308.498873)
			(xy 79.932047 -308.507494) (xy 79.947402 -308.559789) (xy 79.955158 -308.613737) (xy 79.955644 -308.640988)
			(xy 79.955644 -309.504588) (xy 79.955158 -309.531839) (xy 79.947402 -309.585787) (xy 79.932047 -309.638082)
			(xy 79.909405 -309.687659) (xy 79.879939 -309.733509) (xy 79.844248 -309.7747) (xy 79.803057 -309.810391)
			(xy 79.757207 -309.839857) (xy 79.70763 -309.862499) (xy 79.655335 -309.877854) (xy 79.601387 -309.88561)
			(xy 79.546885 -309.88561) (xy 79.492937 -309.877854) (xy 79.440642 -309.862499) (xy 79.391065 -309.839857)
			(xy 79.345215 -309.810391) (xy 79.304024 -309.7747) (xy 79.268333 -309.733509) (xy 79.238867 -309.687659)
			(xy 79.216225 -309.638082) (xy 79.20087 -309.585787) (xy 79.193114 -309.531839) (xy 79.192628 -309.504588)
			(xy 57.063386 -309.504588) (xy 57.063386 -310.603646) (xy 98.925888 -310.603646) (xy 98.925888 -309.740046)
			(xy 98.926374 -309.712795) (xy 98.93413 -309.658847) (xy 98.949485 -309.606552) (xy 98.972127 -309.556975)
			(xy 99.001593 -309.511125) (xy 99.037284 -309.469934) (xy 99.078475 -309.434243) (xy 99.124325 -309.404777)
			(xy 99.173902 -309.382135) (xy 99.226197 -309.36678) (xy 99.280145 -309.359024) (xy 99.334647 -309.359024)
			(xy 99.388595 -309.36678) (xy 99.44089 -309.382135) (xy 99.490467 -309.404777) (xy 99.536317 -309.434243)
			(xy 99.577508 -309.469934) (xy 99.613199 -309.511125) (xy 99.642665 -309.556975) (xy 99.665307 -309.606552)
			(xy 99.680662 -309.658847) (xy 99.688418 -309.712795) (xy 99.688904 -309.740046) (xy 99.688904 -310.603646)
			(xy 99.688418 -310.630897) (xy 99.680662 -310.684845) (xy 99.665307 -310.73714) (xy 99.642665 -310.786717)
			(xy 99.613199 -310.832567) (xy 99.577508 -310.873758) (xy 99.536317 -310.909449) (xy 99.490467 -310.938915)
			(xy 99.44089 -310.961557) (xy 99.388595 -310.976912) (xy 99.334647 -310.984668) (xy 99.280145 -310.984668)
			(xy 99.226197 -310.976912) (xy 99.173902 -310.961557) (xy 99.124325 -310.938915) (xy 99.078475 -310.909449)
			(xy 99.037284 -310.873758) (xy 99.001593 -310.832567) (xy 98.972127 -310.786717) (xy 98.949485 -310.73714)
			(xy 98.93413 -310.684845) (xy 98.926374 -310.630897) (xy 98.925888 -310.603646) (xy 57.063386 -310.603646)
			(xy 57.063386 -312.822082) (xy 57.065418 -312.829194) (xy 57.072764 -312.85512) (xy 57.08067 -312.908423)
			(xy 57.081166 -312.935366) (xy 57.080637 -312.962306) (xy 57.072731 -313.015604) (xy 57.065418 -313.041538)
			(xy 57.063386 -313.04865) (xy 57.063386 -314.997338) (xy 98.330512 -314.997338) (xy 98.330512 -314.133738)
			(xy 98.330998 -314.106487) (xy 98.338754 -314.052539) (xy 98.354109 -314.000244) (xy 98.376751 -313.950667)
			(xy 98.406217 -313.904817) (xy 98.441908 -313.863626) (xy 98.483099 -313.827935) (xy 98.528949 -313.798469)
			(xy 98.578526 -313.775827) (xy 98.630821 -313.760472) (xy 98.684769 -313.752716) (xy 98.739271 -313.752716)
			(xy 98.793219 -313.760472) (xy 98.845514 -313.775827) (xy 98.895091 -313.798469) (xy 98.940941 -313.827935)
			(xy 98.982132 -313.863626) (xy 99.017823 -313.904817) (xy 99.047289 -313.950667) (xy 99.069931 -314.000244)
			(xy 99.085286 -314.052539) (xy 99.093042 -314.106487) (xy 99.093528 -314.133738) (xy 99.093528 -314.997338)
			(xy 99.093042 -315.024589) (xy 99.085286 -315.078537) (xy 99.069931 -315.130832) (xy 99.047289 -315.180409)
			(xy 99.017823 -315.226259) (xy 98.982132 -315.26745) (xy 98.940941 -315.303141) (xy 98.895091 -315.332607)
			(xy 98.845514 -315.355249) (xy 98.793219 -315.370604) (xy 98.739271 -315.37836) (xy 98.684769 -315.37836)
			(xy 98.630821 -315.370604) (xy 98.578526 -315.355249) (xy 98.528949 -315.332607) (xy 98.483099 -315.303141)
			(xy 98.441908 -315.26745) (xy 98.406217 -315.226259) (xy 98.376751 -315.180409) (xy 98.354109 -315.130832)
			(xy 98.338754 -315.078537) (xy 98.330998 -315.024589) (xy 98.330512 -314.997338) (xy 57.063386 -314.997338)
			(xy 57.063386 -315.371988) (xy 57.065418 -315.3791) (xy 57.072764 -315.405026) (xy 57.080669 -315.458329)
			(xy 57.081166 -315.485272) (xy 57.080637 -315.512212) (xy 57.07273 -315.56551) (xy 57.065418 -315.591444)
			(xy 57.063386 -315.598556) (xy 57.063386 -334.781906) (xy 57.06381 -334.791976) (xy 57.071524 -334.81058)
			(xy 57.078372 -334.817974) (xy 57.478676 -335.218278) (xy 57.486078 -335.225115) (xy 57.504676 -335.232825)
			(xy 57.514744 -335.233264)
		)
		(stroke
			(width 0)
			(type solid)
		)
		(fill yes)
		(layer "In9.Cu")
		(net "PVDDCR_CPU1_P1")
	)
	(gr_poly
		(pts
			(xy 311.496964 -335.233518) (xy 311.507029 -335.233084) (xy 311.525619 -335.225355) (xy 311.533032 -335.218532)
			(xy 311.846976 -334.904588) (xy 311.853823 -334.89719) (xy 311.861557 -334.878592) (xy 311.861962 -334.86852)
			(xy 311.861962 -330.394818) (xy 311.862581 -330.369864) (xy 311.872331 -330.320918) (xy 311.89144 -330.274813)
			(xy 311.919175 -330.233321) (xy 311.936384 -330.21524) (xy 312.698384 -329.45324) (xy 312.716427 -329.435984)
			(xy 312.757922 -329.408235) (xy 312.80404 -329.389131) (xy 312.853002 -329.379407) (xy 312.877962 -329.378818)
			(xy 318.593724 -329.378818) (xy 318.603793 -329.378391) (xy 318.622393 -329.370673) (xy 318.629792 -329.363832)
			(xy 319.70218 -328.291444) (xy 319.708022 -328.261218) (xy 319.701672 -328.24674) (xy 319.692024 -328.222992)
			(xy 319.678453 -328.173563) (xy 319.671611 -328.122763) (xy 319.671192 -328.097134) (xy 319.671653 -328.06988)
			(xy 319.679406 -328.015925) (xy 319.694759 -327.963623) (xy 319.7174 -327.914039) (xy 319.746867 -327.868181)
			(xy 319.78256 -327.826985) (xy 319.823754 -327.791287) (xy 319.869609 -327.761816) (xy 319.919191 -327.739171)
			(xy 319.971492 -327.723813) (xy 320.025446 -327.716055) (xy 320.0527 -327.715626) (xy 320.078331 -327.716023)
			(xy 320.129133 -327.722861) (xy 320.17856 -327.736452) (xy 320.202306 -327.746106) (xy 320.216784 -327.752456)
			(xy 320.24701 -327.746614) (xy 322.223384 -325.77024) (xy 322.241427 -325.752984) (xy 322.282922 -325.725235)
			(xy 322.32904 -325.706131) (xy 322.378002 -325.696407) (xy 322.402962 -325.695818) (xy 344.246962 -325.695818)
			(xy 344.271916 -325.696435) (xy 344.320863 -325.706184) (xy 344.366968 -325.725294) (xy 344.408459 -325.753031)
			(xy 344.42654 -325.77024) (xy 346.80652 -328.15022) (xy 346.813916 -328.157072) (xy 346.832515 -328.164812)
			(xy 346.842588 -328.165206) (xy 352.404172 -328.165206) (xy 352.414237 -328.16477) (xy 352.432823 -328.157038)
			(xy 352.44024 -328.15022) (xy 353.16922 -327.42124) (xy 353.187261 -327.40398) (xy 353.228754 -327.37622)
			(xy 353.274872 -327.357104) (xy 353.323836 -327.347368) (xy 353.348798 -327.346818) (xy 358.441498 -327.346818)
			(xy 358.468168 -327.327514) (xy 358.473248 -327.311766) (xy 358.486153 -327.274052) (xy 358.518745 -327.201304)
			(xy 358.558749 -327.132353) (xy 358.605727 -327.067952) (xy 358.659166 -327.008802) (xy 358.718485 -326.95555)
			(xy 358.783035 -326.908777) (xy 358.852113 -326.868992) (xy 358.924963 -326.836631) (xy 359.000792 -326.812046)
			(xy 359.078772 -326.795505) (xy 359.158052 -326.787189) (xy 359.237768 -326.787189) (xy 359.317048 -326.795505)
			(xy 359.395028 -326.812046) (xy 359.470857 -326.836631) (xy 359.543707 -326.868992) (xy 359.612785 -326.908777)
			(xy 359.677335 -326.95555) (xy 359.736654 -327.008802) (xy 359.790093 -327.067952) (xy 359.837071 -327.132353)
			(xy 359.877075 -327.201304) (xy 359.909667 -327.274052) (xy 359.922572 -327.311766) (xy 359.927652 -327.327514)
			(xy 359.954322 -327.346818) (xy 379.045724 -327.346818) (xy 379.055793 -327.346391) (xy 379.074393 -327.338673)
			(xy 379.081792 -327.331832) (xy 379.489716 -326.923908) (xy 379.496573 -326.916514) (xy 379.504323 -326.897915)
			(xy 379.504702 -326.88784) (xy 379.504702 -299.798994) (xy 379.484382 -299.77207) (xy 379.468126 -299.767244)
			(xy 379.441983 -299.759204) (xy 379.392142 -299.736678) (xy 379.346029 -299.707266) (xy 379.304588 -299.671571)
			(xy 379.268669 -299.630323) (xy 379.239009 -299.58437) (xy 379.216214 -299.534651) (xy 379.200753 -299.482187)
			(xy 379.192942 -299.428053) (xy 379.192941 -299.373359) (xy 379.20075 -299.319225) (xy 379.21621 -299.26676)
			(xy 379.239003 -299.217041) (xy 379.268662 -299.171086) (xy 379.30458 -299.129838) (xy 379.346019 -299.094141)
			(xy 379.392132 -299.064728) (xy 379.441972 -299.0422) (xy 379.468126 -299.0342) (xy 379.484382 -299.029374)
			(xy 379.504702 -299.00245) (xy 379.504702 -296.21353) (xy 379.50442 -296.205273) (xy 379.499231 -296.189599)
			(xy 379.494542 -296.182796) (xy 379.478793 -296.161135) (xy 379.453773 -296.113788) (xy 379.436709 -296.063028)
			(xy 379.428047 -296.010181) (xy 379.427486 -295.983406) (xy 379.427947 -295.958674) (xy 379.435318 -295.909762)
			(xy 379.449896 -295.862496) (xy 379.471355 -295.817929) (xy 379.48489 -295.797224) (xy 379.493272 -295.785032)
			(xy 379.494288 -295.755822) (xy 379.339602 -295.489122) (xy 379.31471 -295.47566) (xy 379.300486 -295.476422)
			(xy 379.284738 -295.476676) (xy 379.258748 -295.476196) (xy 379.207406 -295.468069) (xy 379.157969 -295.45201)
			(xy 379.111653 -295.428413) (xy 379.069599 -295.397861) (xy 379.032843 -295.361106) (xy 379.00229 -295.319052)
			(xy 378.978693 -295.272737) (xy 378.962632 -295.223299) (xy 378.954505 -295.171958) (xy 378.95403 -295.145968)
			(xy 378.95442 -295.122535) (xy 378.961003 -295.076134) (xy 378.974076 -295.031129) (xy 378.993376 -294.988423)
			(xy 379.005592 -294.968422) (xy 379.013466 -294.956484) (xy 379.013974 -294.92829) (xy 378.869448 -294.679116)
			(xy 378.844556 -294.665654) (xy 378.830332 -294.666416) (xy 378.814838 -294.66667) (xy 378.788848 -294.66619)
			(xy 378.737507 -294.658063) (xy 378.68807 -294.642004) (xy 378.641754 -294.618407) (xy 378.599701 -294.587855)
			(xy 378.562945 -294.551099) (xy 378.532393 -294.509046) (xy 378.508796 -294.46273) (xy 378.492737 -294.413293)
			(xy 378.48461 -294.361952) (xy 378.48413 -294.335962) (xy 378.484532 -294.31256) (xy 378.491127 -294.266223)
			(xy 378.504194 -294.221281) (xy 378.523471 -294.178631) (xy 378.535692 -294.15867) (xy 378.543312 -294.146478)
			(xy 378.54382 -294.118284) (xy 378.399294 -293.86911) (xy 378.374656 -293.855648) (xy 378.360178 -293.85641)
			(xy 378.344938 -293.856664) (xy 378.319447 -293.856195) (xy 378.269068 -293.848371) (xy 378.220488 -293.832902)
			(xy 378.174861 -293.810156) (xy 378.133268 -293.780673) (xy 378.096697 -293.745151) (xy 378.066015 -293.704434)
			(xy 378.0536 -293.682166) (xy 378.046742 -293.66972) (xy 378.022866 -293.655496) (xy 377.726956 -293.655496)
			(xy 377.70308 -293.66972) (xy 377.696222 -293.682166) (xy 377.683775 -293.704415) (xy 377.653098 -293.745129)
			(xy 377.616531 -293.780649) (xy 377.574943 -293.810132) (xy 377.529321 -293.832878) (xy 377.480747 -293.848348)
			(xy 377.430373 -293.856174) (xy 377.404884 -293.856664) (xy 377.378897 -293.85618) (xy 377.327563 -293.848046)
			(xy 377.278133 -293.831982) (xy 377.231825 -293.808383) (xy 377.18978 -293.777829) (xy 377.153032 -293.741075)
			(xy 377.122486 -293.699023) (xy 377.098895 -293.652711) (xy 377.08284 -293.603279) (xy 377.074716 -293.551943)
			(xy 377.074176 -293.525956) (xy 377.074579 -293.502554) (xy 377.081175 -293.456218) (xy 377.094244 -293.411277)
			(xy 377.113524 -293.368629) (xy 377.125738 -293.348664) (xy 377.133358 -293.336472) (xy 377.133866 -293.308278)
			(xy 376.98934 -293.059104) (xy 376.964702 -293.045642) (xy 376.950224 -293.046404) (xy 376.93473 -293.046658)
			(xy 376.908741 -293.046177) (xy 376.857401 -293.038049) (xy 376.807966 -293.021989) (xy 376.761652 -292.998392)
			(xy 376.719601 -292.96784) (xy 376.682847 -292.931084) (xy 376.652297 -292.889031) (xy 376.628703 -292.842715)
			(xy 376.612646 -292.793279) (xy 376.604521 -292.741939) (xy 376.604022 -292.71595) (xy 376.604425 -292.692548)
			(xy 376.611021 -292.646212) (xy 376.624089 -292.60127) (xy 376.643367 -292.558622) (xy 376.655584 -292.538658)
			(xy 376.663204 -292.526466) (xy 376.663966 -292.498272) (xy 376.51944 -292.249098) (xy 376.494548 -292.235636)
			(xy 376.480324 -292.236398) (xy 376.46483 -292.236652) (xy 376.43884 -292.236145) (xy 376.387499 -292.228018)
			(xy 376.338062 -292.21196) (xy 376.291745 -292.188367) (xy 376.249689 -292.157818) (xy 376.21293 -292.121067)
			(xy 376.182372 -292.079018) (xy 376.158768 -292.032707) (xy 376.142699 -291.983273) (xy 376.134561 -291.931934)
			(xy 376.134122 -291.905944) (xy 376.134525 -291.882542) (xy 376.141123 -291.836207) (xy 376.154191 -291.791265)
			(xy 376.17347 -291.748617) (xy 376.185684 -291.728652) (xy 376.193304 -291.71646) (xy 376.193812 -291.688266)
			(xy 376.049286 -291.439092) (xy 376.024648 -291.42563) (xy 376.01017 -291.426392) (xy 375.99493 -291.426646)
			(xy 375.96894 -291.426139) (xy 375.9176 -291.418012) (xy 375.868163 -291.401954) (xy 375.821846 -291.378361)
			(xy 375.779791 -291.347812) (xy 375.743032 -291.311061) (xy 375.712475 -291.269012) (xy 375.688872 -291.2227)
			(xy 375.672804 -291.173266) (xy 375.664667 -291.121928) (xy 375.664222 -291.095938) (xy 375.664626 -291.072537)
			(xy 375.671224 -291.026201) (xy 375.684293 -290.98126) (xy 375.703572 -290.938612) (xy 375.715784 -290.918646)
			(xy 375.723404 -290.906708) (xy 375.723912 -290.87826) (xy 375.579386 -290.629086) (xy 375.554494 -290.615624)
			(xy 375.54027 -290.616386) (xy 375.524776 -290.61664) (xy 375.498789 -290.616129) (xy 375.447456 -290.607995)
			(xy 375.398026 -290.591933) (xy 375.351718 -290.568336) (xy 375.30967 -290.537786) (xy 375.272919 -290.501036)
			(xy 375.242368 -290.458989) (xy 375.21877 -290.412681) (xy 375.202707 -290.363252) (xy 375.194572 -290.311919)
			(xy 375.194068 -290.285932) (xy 375.194472 -290.262531) (xy 375.201072 -290.216196) (xy 375.214143 -290.171256)
			(xy 375.233425 -290.128611) (xy 375.24563 -290.10864) (xy 375.25325 -290.096448) (xy 375.254012 -290.068254)
			(xy 375.109232 -289.81908) (xy 375.084594 -289.805618) (xy 375.070116 -289.80638) (xy 375.054876 -289.806634)
			(xy 375.028889 -289.806123) (xy 374.977556 -289.797989) (xy 374.928127 -289.781927) (xy 374.881819 -289.75833)
			(xy 374.839772 -289.72778) (xy 374.803021 -289.691029) (xy 374.772471 -289.648983) (xy 374.748874 -289.602675)
			(xy 374.732811 -289.553246) (xy 374.724677 -289.501913) (xy 374.724168 -289.475926) (xy 374.724573 -289.452525)
			(xy 374.731173 -289.406191) (xy 374.744245 -289.361251) (xy 374.763528 -289.318606) (xy 374.77573 -289.298634)
			(xy 374.78335 -289.286442) (xy 374.783858 -289.258248) (xy 374.639332 -289.009074) (xy 374.61444 -288.995612)
			(xy 374.600216 -288.996374) (xy 374.584722 -288.996628) (xy 374.55873 -288.996146) (xy 374.507386 -288.988017)
			(xy 374.457945 -288.971956) (xy 374.411626 -288.948358) (xy 374.369569 -288.917805) (xy 374.33281 -288.881048)
			(xy 374.302253 -288.838993) (xy 374.278652 -288.792675) (xy 374.262588 -288.743236) (xy 374.254455 -288.691892)
			(xy 374.254455 -288.639908) (xy 374.262588 -288.588564) (xy 374.278652 -288.539125) (xy 374.302253 -288.492807)
			(xy 374.33281 -288.450752) (xy 374.369569 -288.413995) (xy 374.411626 -288.383442) (xy 374.457945 -288.359844)
			(xy 374.507386 -288.343783) (xy 374.55873 -288.335654) (xy 374.584722 -288.335212) (xy 374.60301 -288.33572)
			(xy 374.617234 -288.336482) (xy 374.64238 -288.32302) (xy 374.785636 -288.076386) (xy 374.784874 -288.047684)
			(xy 374.777 -288.035746) (xy 374.764477 -288.015581) (xy 374.74471 -287.972426) (xy 374.731319 -287.926887)
			(xy 374.724578 -287.879902) (xy 374.724168 -287.856168) (xy 374.72468 -287.830182) (xy 374.732814 -287.77885)
			(xy 374.748878 -287.729422) (xy 374.772475 -287.683115) (xy 374.803025 -287.641069) (xy 374.839775 -287.60432)
			(xy 374.881822 -287.573771) (xy 374.928129 -287.550175) (xy 374.977558 -287.534112) (xy 375.02889 -287.525979)
			(xy 375.054876 -287.52546) (xy 375.07291 -287.525968) (xy 375.087134 -287.52673) (xy 375.11228 -287.513014)
			(xy 375.255536 -287.266126) (xy 375.255028 -287.237678) (xy 375.247154 -287.225486) (xy 375.234613 -287.205324)
			(xy 375.214801 -287.162173) (xy 375.201348 -287.116638) (xy 375.19453 -287.069648) (xy 375.194068 -287.045908)
			(xy 375.194474 -287.022507) (xy 375.201077 -286.976174) (xy 375.214151 -286.931236) (xy 375.233435 -286.888592)
			(xy 375.24563 -286.868616) (xy 375.25325 -286.856424) (xy 375.253758 -286.82823) (xy 375.109486 -286.57931)
			(xy 375.084594 -286.565848) (xy 375.07037 -286.56661) (xy 375.054876 -286.566864) (xy 375.028889 -286.566379)
			(xy 374.977556 -286.558245) (xy 374.928128 -286.54218) (xy 374.881821 -286.51858) (xy 374.839776 -286.488027)
			(xy 374.803029 -286.451272) (xy 374.772485 -286.409221) (xy 374.748894 -286.362909) (xy 374.73284 -286.313478)
			(xy 374.724716 -286.262143) (xy 374.724168 -286.236156) (xy 374.724571 -286.212754) (xy 374.731167 -286.166418)
			(xy 374.744236 -286.121477) (xy 374.763515 -286.078829) (xy 374.77573 -286.058864) (xy 374.78335 -286.046672)
			(xy 374.784112 -286.018478) (xy 374.639332 -285.769304) (xy 374.614694 -285.755842) (xy 374.600216 -285.756604)
			(xy 374.584722 -285.756858) (xy 374.558728 -285.756376) (xy 374.507379 -285.748247) (xy 374.457934 -285.732184)
			(xy 374.411611 -285.708584) (xy 374.36955 -285.678027) (xy 374.332787 -285.641267) (xy 374.302228 -285.599208)
			(xy 374.278625 -285.552887) (xy 374.262559 -285.503443) (xy 374.254425 -285.452094) (xy 374.254425 -285.400106)
			(xy 374.262559 -285.348757) (xy 374.278625 -285.299313) (xy 374.302228 -285.252992) (xy 374.332787 -285.210933)
			(xy 374.36955 -285.174173) (xy 374.411611 -285.143616) (xy 374.457934 -285.120016) (xy 374.507379 -285.103953)
			(xy 374.558728 -285.095824) (xy 374.584722 -285.095442) (xy 374.602756 -285.09595) (xy 374.617234 -285.096712)
			(xy 374.64238 -285.08325) (xy 374.785636 -284.836362) (xy 374.784874 -284.80766) (xy 374.777 -284.795722)
			(xy 374.764472 -284.775559) (xy 374.744696 -284.732405) (xy 374.731294 -284.686866) (xy 374.724542 -284.639879)
			(xy 374.724168 -284.616144) (xy 374.724648 -284.590152) (xy 374.732773 -284.538806) (xy 374.748831 -284.489365)
			(xy 374.772427 -284.443044) (xy 374.802978 -284.400984) (xy 374.839732 -284.364222) (xy 374.881785 -284.333662)
			(xy 374.928102 -284.310058) (xy 374.97754 -284.293989) (xy 375.028884 -284.285853) (xy 375.054876 -284.285436)
			(xy 375.07291 -284.285944) (xy 375.087134 -284.286706) (xy 375.11228 -284.27299) (xy 375.255536 -284.026356)
			(xy 375.254774 -283.997654) (xy 375.247154 -283.985716) (xy 375.234611 -283.965555) (xy 375.214795 -283.922404)
			(xy 375.201339 -283.876869) (xy 375.194516 -283.829879) (xy 375.194068 -283.806138) (xy 375.194472 -283.782737)
			(xy 375.201071 -283.736402) (xy 375.214142 -283.691462) (xy 375.233423 -283.648815) (xy 375.24563 -283.628846)
			(xy 375.253504 -283.616654) (xy 375.254012 -283.58846) (xy 375.109486 -283.339286) (xy 375.084594 -283.325824)
			(xy 375.07037 -283.326586) (xy 375.054876 -283.32684) (xy 375.028889 -283.326329) (xy 374.977556 -283.318195)
			(xy 374.928126 -283.302133) (xy 374.881818 -283.278536) (xy 374.83977 -283.247986) (xy 374.803019 -283.211236)
			(xy 374.772468 -283.169189) (xy 374.74887 -283.122881) (xy 374.732807 -283.073452) (xy 374.724672 -283.022119)
			(xy 374.724168 -282.996132) (xy 374.724572 -282.972731) (xy 374.731172 -282.926396) (xy 374.744243 -282.881456)
			(xy 374.763525 -282.838811) (xy 374.77573 -282.81884) (xy 374.78335 -282.806648) (xy 374.784112 -282.778454)
			(xy 374.639332 -282.52928) (xy 374.614694 -282.515818) (xy 374.600216 -282.51658) (xy 374.584722 -282.516834)
			(xy 374.55873 -282.516352) (xy 374.507384 -282.508223) (xy 374.457943 -282.492162) (xy 374.411623 -282.468563)
			(xy 374.369565 -282.438009) (xy 374.332805 -282.401251) (xy 374.302248 -282.359196) (xy 374.278647 -282.312877)
			(xy 374.262582 -282.263437) (xy 374.254449 -282.212092) (xy 374.254449 -282.160108) (xy 374.262582 -282.108763)
			(xy 374.278647 -282.059323) (xy 374.302248 -282.013004) (xy 374.332805 -281.970949) (xy 374.369565 -281.934191)
			(xy 374.411623 -281.903637) (xy 374.457943 -281.880038) (xy 374.507384 -281.863977) (xy 374.55873 -281.855848)
			(xy 374.584722 -281.855418) (xy 374.602756 -281.855926) (xy 374.61698 -281.856688) (xy 374.642126 -281.843226)
			(xy 374.785382 -281.596084) (xy 374.784874 -281.567636) (xy 374.777 -281.555444) (xy 374.764492 -281.535307)
			(xy 374.744744 -281.492213) (xy 374.731353 -281.446741) (xy 374.724594 -281.399822) (xy 374.724168 -281.37612)
			(xy 374.724573 -281.352719) (xy 374.731174 -281.306385) (xy 374.744247 -281.261446) (xy 374.76353 -281.218802)
			(xy 374.77573 -281.198828) (xy 374.78335 -281.18689) (xy 374.783858 -281.158442) (xy 374.639332 -280.909268)
			(xy 374.61444 -280.895806) (xy 374.600216 -280.896568) (xy 374.584722 -280.896822) (xy 374.558731 -280.896341)
			(xy 374.507389 -280.888212) (xy 374.457951 -280.872152) (xy 374.411634 -280.848556) (xy 374.369578 -280.818004)
			(xy 374.332819 -280.78125) (xy 374.302263 -280.739197) (xy 374.278662 -280.692883) (xy 374.262596 -280.643446)
			(xy 374.254462 -280.592105) (xy 374.254014 -280.566114) (xy 374.254419 -280.542713) (xy 374.26102 -280.496379)
			(xy 374.274092 -280.451439) (xy 374.293373 -280.408794) (xy 374.305576 -280.388822) (xy 374.313196 -280.37663)
			(xy 374.313958 -280.348436) (xy 374.169432 -280.099262) (xy 374.14454 -280.0858) (xy 374.130316 -280.086562)
			(xy 374.114822 -280.086816) (xy 374.088831 -280.086334) (xy 374.037489 -280.078206) (xy 373.98805 -280.062145)
			(xy 373.941732 -280.038548) (xy 373.899677 -280.007995) (xy 373.862919 -279.97124) (xy 373.832364 -279.929186)
			(xy 373.808763 -279.882871) (xy 373.792699 -279.833433) (xy 373.784567 -279.782091) (xy 373.784567 -279.730109)
			(xy 373.792699 -279.678767) (xy 373.808763 -279.629329) (xy 373.832364 -279.583014) (xy 373.862919 -279.54096)
			(xy 373.899677 -279.504205) (xy 373.941732 -279.473652) (xy 373.98805 -279.450055) (xy 374.037489 -279.433994)
			(xy 374.088831 -279.425866) (xy 374.114822 -279.4254) (xy 374.138638 -279.425817) (xy 374.185775 -279.432656)
			(xy 374.231443 -279.446189) (xy 374.274697 -279.466135) (xy 374.294908 -279.47874) (xy 374.3071 -279.486614)
			(xy 374.335294 -279.487376) (xy 375.181368 -279.001728) (xy 375.195084 -278.976582) (xy 375.194576 -278.962104)
			(xy 375.194068 -278.946102) (xy 375.194474 -278.922701) (xy 375.201078 -278.876369) (xy 375.214153 -278.831431)
			(xy 375.233438 -278.788788) (xy 375.24563 -278.76881) (xy 375.25325 -278.756618) (xy 375.253758 -278.728424)
			(xy 375.109232 -278.47925) (xy 375.084594 -278.465788) (xy 375.070116 -278.46655) (xy 375.054876 -278.466804)
			(xy 375.02889 -278.466293) (xy 374.977559 -278.458159) (xy 374.928132 -278.442096) (xy 374.881826 -278.418499)
			(xy 374.839781 -278.387948) (xy 374.803033 -278.351197) (xy 374.772487 -278.30915) (xy 374.748893 -278.262842)
			(xy 374.732834 -278.213414) (xy 374.724705 -278.162082) (xy 374.724168 -278.136096) (xy 374.724575 -278.112696)
			(xy 374.731179 -278.066363) (xy 374.744255 -278.021426) (xy 374.76354 -277.978783) (xy 374.77573 -277.958804)
			(xy 374.78335 -277.946612) (xy 374.783858 -277.918418) (xy 374.639332 -277.669244) (xy 374.614694 -277.655782)
			(xy 374.600216 -277.656544) (xy 374.584722 -277.656798) (xy 374.558732 -277.656317) (xy 374.507393 -277.648188)
			(xy 374.457957 -277.632128) (xy 374.411642 -277.608533) (xy 374.369589 -277.577982) (xy 374.332833 -277.541228)
			(xy 374.302279 -277.499177) (xy 374.27868 -277.452864) (xy 374.262617 -277.403429) (xy 374.254485 -277.35209)
			(xy 374.254485 -277.30011) (xy 374.262617 -277.248771) (xy 374.27868 -277.199336) (xy 374.302279 -277.153023)
			(xy 374.332833 -277.110972) (xy 374.369589 -277.074218) (xy 374.411642 -277.043667) (xy 374.457957 -277.020072)
			(xy 374.507393 -277.004012) (xy 374.558732 -276.995883) (xy 374.584722 -276.995382) (xy 374.602756 -276.99589)
			(xy 374.617234 -276.996652) (xy 374.64238 -276.98319) (xy 374.785636 -276.736302) (xy 374.784874 -276.7076)
			(xy 374.777 -276.695662) (xy 374.764476 -276.675498) (xy 374.744707 -276.632343) (xy 374.731314 -276.586804)
			(xy 374.72457 -276.539818) (xy 374.724168 -276.516084) (xy 374.724679 -276.490097) (xy 374.732811 -276.438763)
			(xy 374.748873 -276.389333) (xy 374.77247 -276.343024) (xy 374.803019 -276.300976) (xy 374.83977 -276.264224)
			(xy 374.881817 -276.233674) (xy 374.928126 -276.210076) (xy 374.977555 -276.194013) (xy 375.028889 -276.185879)
			(xy 375.054876 -276.185376) (xy 375.07291 -276.185884) (xy 375.087134 -276.186646) (xy 375.11228 -276.17293)
			(xy 375.255536 -275.926296) (xy 375.254774 -275.897594) (xy 375.247154 -275.885656) (xy 375.234608 -275.865495)
			(xy 375.214788 -275.822346) (xy 375.201325 -275.77681) (xy 375.194498 -275.72982) (xy 375.194068 -275.706078)
			(xy 375.194469 -275.682676) (xy 375.201063 -275.636339) (xy 375.214129 -275.591395) (xy 375.233406 -275.548746)
			(xy 375.24563 -275.528786) (xy 375.253504 -275.516594) (xy 375.254012 -275.4884) (xy 375.109486 -275.239226)
			(xy 375.084594 -275.225764) (xy 375.07037 -275.226526) (xy 375.054876 -275.22678) (xy 375.028889 -275.226295)
			(xy 374.977555 -275.218161) (xy 374.928125 -275.202096) (xy 374.881817 -275.178496) (xy 374.839771 -275.147943)
			(xy 374.803023 -275.111189) (xy 374.772476 -275.069138) (xy 374.748884 -275.022827) (xy 374.732827 -274.973395)
			(xy 374.724701 -274.922059) (xy 374.724168 -274.896072) (xy 374.72457 -274.87267) (xy 374.731164 -274.826333)
			(xy 374.744231 -274.78139) (xy 374.763509 -274.738741) (xy 374.77573 -274.71878) (xy 374.78335 -274.706588)
			(xy 374.784112 -274.678394) (xy 374.639332 -274.42922) (xy 374.614694 -274.415758) (xy 374.600216 -274.41652)
			(xy 374.584722 -274.416774) (xy 374.558734 -274.416293) (xy 374.507398 -274.408165) (xy 374.457966 -274.392106)
			(xy 374.411654 -274.368512) (xy 374.369604 -274.337963) (xy 374.332851 -274.301213) (xy 374.302299 -274.259164)
			(xy 374.278702 -274.212854) (xy 374.26264 -274.163423) (xy 374.254509 -274.112088) (xy 374.254509 -274.060112)
			(xy 374.26264 -274.008777) (xy 374.278702 -273.959346) (xy 374.302299 -273.913036) (xy 374.332851 -273.870987)
			(xy 374.369604 -273.834237) (xy 374.411654 -273.803688) (xy 374.457966 -273.780094) (xy 374.507398 -273.764035)
			(xy 374.558734 -273.755907) (xy 374.584722 -273.755358) (xy 374.602756 -273.755866) (xy 374.617234 -273.756628)
			(xy 374.64238 -273.743166) (xy 374.785636 -273.496278) (xy 374.784874 -273.467576) (xy 374.777 -273.455638)
			(xy 374.764471 -273.435475) (xy 374.744693 -273.392321) (xy 374.731289 -273.346783) (xy 374.724534 -273.299795)
			(xy 374.724168 -273.27606) (xy 374.724681 -273.250074) (xy 374.732816 -273.198743) (xy 374.74888 -273.149316)
			(xy 374.772478 -273.103011) (xy 374.803028 -273.060966) (xy 374.839778 -273.024217) (xy 374.881824 -272.993669)
			(xy 374.928131 -272.970074) (xy 374.977559 -272.954012) (xy 375.02889 -272.945879) (xy 375.054876 -272.945352)
			(xy 375.07291 -272.94586) (xy 375.087134 -272.946622) (xy 375.11228 -272.932906) (xy 375.255536 -272.686272)
			(xy 375.254774 -272.65757) (xy 375.247154 -272.645632) (xy 375.23461 -272.625471) (xy 375.214792 -272.582321)
			(xy 375.201333 -272.536785) (xy 375.194509 -272.489795) (xy 375.194068 -272.466054) (xy 375.194471 -272.442652)
			(xy 375.201068 -272.396316) (xy 375.214137 -272.351375) (xy 375.233416 -272.308727) (xy 375.24563 -272.288762)
			(xy 375.253504 -272.27657) (xy 375.254012 -272.248376) (xy 375.109486 -271.999202) (xy 375.084594 -271.98574)
			(xy 375.07037 -271.986502) (xy 375.054876 -271.986756) (xy 375.028889 -271.986245) (xy 374.977554 -271.978111)
			(xy 374.928124 -271.962049) (xy 374.881814 -271.938453) (xy 374.839765 -271.907903) (xy 374.803012 -271.871153)
			(xy 374.77246 -271.829106) (xy 374.74886 -271.782798) (xy 374.732794 -271.733369) (xy 374.724657 -271.682035)
			(xy 374.724168 -271.656048) (xy 374.724571 -271.632647) (xy 374.731169 -271.586311) (xy 374.744238 -271.54137)
			(xy 374.763519 -271.498723) (xy 374.77573 -271.478756) (xy 374.78335 -271.466564) (xy 374.784112 -271.43837)
			(xy 374.639332 -271.189196) (xy 374.614694 -271.175734) (xy 374.600216 -271.176496) (xy 374.584722 -271.17675)
			(xy 374.558728 -271.176268) (xy 374.507381 -271.168139) (xy 374.457937 -271.152077) (xy 374.411615 -271.128477)
			(xy 374.369555 -271.097921) (xy 374.332793 -271.061162) (xy 374.302235 -271.019104) (xy 374.278632 -270.972784)
			(xy 374.262566 -270.923341) (xy 374.254433 -270.871994) (xy 374.254433 -270.820006) (xy 374.262566 -270.768659)
			(xy 374.278632 -270.719216) (xy 374.302235 -270.672896) (xy 374.332793 -270.630838) (xy 374.369555 -270.594079)
			(xy 374.411615 -270.563523) (xy 374.457937 -270.539923) (xy 374.507381 -270.523861) (xy 374.558728 -270.515732)
			(xy 374.584722 -270.515334) (xy 374.602756 -270.515842) (xy 374.617234 -270.516604) (xy 374.64238 -270.503142)
			(xy 374.785636 -270.256254) (xy 374.784874 -270.227552) (xy 374.777 -270.215614) (xy 374.764473 -270.19545)
			(xy 374.744697 -270.152296) (xy 374.731296 -270.106758) (xy 374.724546 -270.059771) (xy 374.724168 -270.036036)
			(xy 374.724648 -270.010044) (xy 374.732775 -269.9587) (xy 374.748834 -269.909259) (xy 374.772429 -269.862939)
			(xy 374.80298 -269.820881) (xy 374.839735 -269.784119) (xy 374.881788 -269.753561) (xy 374.928103 -269.729957)
			(xy 374.977541 -269.713889) (xy 375.028884 -269.705753) (xy 375.054876 -269.705328) (xy 375.07291 -269.705836)
			(xy 375.087134 -269.706598) (xy 375.11228 -269.692882) (xy 375.255536 -269.446248) (xy 375.254774 -269.417546)
			(xy 375.247154 -269.405608) (xy 375.234611 -269.385446) (xy 375.214797 -269.342296) (xy 375.201341 -269.29676)
			(xy 375.19452 -269.249771) (xy 375.194068 -269.22603) (xy 375.194472 -269.202629) (xy 375.201072 -269.156294)
			(xy 375.214144 -269.111355) (xy 375.233426 -269.068709) (xy 375.24563 -269.048738) (xy 375.25325 -269.036546)
			(xy 375.254012 -269.008352) (xy 375.109486 -268.759178) (xy 375.084594 -268.745716) (xy 375.07037 -268.746478)
			(xy 375.054876 -268.746732) (xy 375.028889 -268.746221) (xy 374.977556 -268.738087) (xy 374.928127 -268.722024)
			(xy 374.88182 -268.698428) (xy 374.839773 -268.667878) (xy 374.803022 -268.631127) (xy 374.772472 -268.58908)
			(xy 374.748876 -268.542773) (xy 374.732813 -268.493344) (xy 374.724679 -268.442011) (xy 374.724168 -268.416024)
			(xy 374.724573 -268.392623) (xy 374.731173 -268.346289) (xy 374.744246 -268.30135) (xy 374.763529 -268.258705)
			(xy 374.77573 -268.238732) (xy 374.78335 -268.22654) (xy 374.783858 -268.198346) (xy 374.639332 -267.949172)
			(xy 374.61444 -267.93571) (xy 374.600216 -267.936472) (xy 374.584722 -267.936726) (xy 374.558731 -267.936245)
			(xy 374.507389 -267.928116) (xy 374.45795 -267.912056) (xy 374.411633 -267.88846) (xy 374.369577 -267.857908)
			(xy 374.332818 -267.821154) (xy 374.302261 -267.779102) (xy 374.278659 -267.732787) (xy 374.262593 -267.68335)
			(xy 374.254459 -267.632009) (xy 374.254014 -267.606018) (xy 374.254419 -267.582617) (xy 374.26102 -267.536283)
			(xy 374.274091 -267.491343) (xy 374.293372 -267.448697) (xy 374.305576 -267.428726) (xy 374.313196 -267.416534)
			(xy 374.313704 -267.38834) (xy 374.154954 -267.114782) (xy 374.131332 -267.101066) (xy 374.117616 -267.10132)
			(xy 374.114822 -267.10132) (xy 374.088364 -267.10075) (xy 374.036241 -267.091617) (xy 373.986473 -267.073638)
			(xy 373.940547 -267.047352) (xy 373.899838 -267.013543) (xy 373.865565 -266.973226) (xy 373.851678 -266.950698)
			(xy 373.844566 -266.939014) (xy 373.821452 -266.925552) (xy 373.49684 -266.925552) (xy 373.472964 -266.939776)
			(xy 373.466106 -266.952222) (xy 373.453661 -266.974472) (xy 373.422985 -267.01519) (xy 373.38642 -267.050713)
			(xy 373.344832 -267.080198) (xy 373.299209 -267.102945) (xy 373.250633 -267.118415) (xy 373.200258 -267.12624)
			(xy 373.174768 -267.12672) (xy 373.165624 -267.12672) (xy 373.1514 -267.126212) (xy 373.127524 -267.139674)
			(xy 372.979696 -267.394182) (xy 372.97995 -267.421868) (xy 372.987316 -267.433806) (xy 372.998772 -267.453345)
			(xy 373.016821 -267.494886) (xy 373.02904 -267.538499) (xy 373.035198 -267.583371) (xy 373.035576 -267.606018)
			(xy 373.035066 -267.632005) (xy 373.026936 -267.68334) (xy 373.010875 -267.73277) (xy 372.987279 -267.77908)
			(xy 372.956729 -267.821128) (xy 372.919978 -267.857879) (xy 372.87793 -267.888429) (xy 372.83162 -267.912025)
			(xy 372.78219 -267.928086) (xy 372.730855 -267.936216) (xy 372.678881 -267.936216) (xy 372.627546 -267.928086)
			(xy 372.578116 -267.912025) (xy 372.531806 -267.888429) (xy 372.489758 -267.857879) (xy 372.453007 -267.821128)
			(xy 372.422457 -267.77908) (xy 372.398861 -267.73277) (xy 372.3828 -267.68334) (xy 372.37467 -267.632005)
			(xy 372.37416 -267.606018) (xy 372.374414 -267.594334) (xy 372.374922 -267.58011) (xy 372.36146 -267.555726)
			(xy 371.511322 -267.067538) (xy 371.483636 -267.068046) (xy 371.471444 -267.075666) (xy 371.45154 -267.087761)
			(xy 371.409057 -267.106852) (xy 371.364316 -267.119793) (xy 371.318202 -267.126329) (xy 371.294914 -267.12672)
			(xy 371.268924 -267.126238) (xy 371.217583 -267.118109) (xy 371.168146 -267.102048) (xy 371.12183 -267.078451)
			(xy 371.079775 -267.047899) (xy 371.043018 -267.011145) (xy 371.012463 -266.969093) (xy 370.988862 -266.922779)
			(xy 370.972798 -266.873343) (xy 370.964664 -266.822002) (xy 370.964206 -266.796012) (xy 370.964612 -266.772611)
			(xy 370.971213 -266.726277) (xy 370.984284 -266.681338) (xy 371.003565 -266.638692) (xy 371.015768 -266.61872)
			(xy 371.023388 -266.606782) (xy 371.023896 -266.578334) (xy 370.87937 -266.32916) (xy 370.854478 -266.315698)
			(xy 370.840254 -266.31646) (xy 370.82476 -266.316714) (xy 370.80192 -266.316307) (xy 370.756679 -266.309981)
			(xy 370.712736 -266.297496) (xy 370.670928 -266.279089) (xy 370.651278 -266.267438) (xy 370.63934 -266.260326)
			(xy 370.6114 -266.259818) (xy 369.758722 -266.74953) (xy 369.745006 -266.773914) (xy 369.745514 -266.787884)
			(xy 369.745514 -266.796012) (xy 369.745004 -266.821999) (xy 369.736872 -266.873332) (xy 369.72081 -266.922761)
			(xy 369.697213 -266.96907) (xy 369.666663 -267.011117) (xy 369.629912 -267.047867) (xy 369.587865 -267.078416)
			(xy 369.541556 -267.102012) (xy 369.492126 -267.118073) (xy 369.440793 -267.126204) (xy 369.414806 -267.12672)
			(xy 369.405408 -267.126466) (xy 369.391438 -267.126212) (xy 369.367308 -267.139674) (xy 369.21948 -267.394182)
			(xy 369.219734 -267.421614) (xy 369.227354 -267.433806) (xy 369.238808 -267.453345) (xy 369.256856 -267.494886)
			(xy 369.269073 -267.5385) (xy 369.275231 -267.583372) (xy 369.275614 -267.606018) (xy 369.275104 -267.632005)
			(xy 369.266974 -267.68334) (xy 369.250913 -267.73277) (xy 369.227317 -267.77908) (xy 369.196767 -267.821128)
			(xy 369.160016 -267.857879) (xy 369.117968 -267.888429) (xy 369.071658 -267.912025) (xy 369.022228 -267.928086)
			(xy 368.970893 -267.936216) (xy 368.918919 -267.936216) (xy 368.867584 -267.928086) (xy 368.818154 -267.912025)
			(xy 368.771844 -267.888429) (xy 368.729796 -267.857879) (xy 368.693045 -267.821128) (xy 368.662495 -267.77908)
			(xy 368.638899 -267.73277) (xy 368.622838 -267.68334) (xy 368.614708 -267.632005) (xy 368.614198 -267.606018)
			(xy 368.614452 -267.594334) (xy 368.61496 -267.58011) (xy 368.601498 -267.555726) (xy 367.75136 -267.067284)
			(xy 367.72342 -267.068046) (xy 367.711228 -267.075666) (xy 367.691323 -267.08776) (xy 367.64884 -267.106849)
			(xy 367.604099 -267.119788) (xy 367.557985 -267.126322) (xy 367.534698 -267.12672) (xy 367.508711 -267.12621)
			(xy 367.457376 -267.11808) (xy 367.407945 -267.102019) (xy 367.361634 -267.078423) (xy 367.319586 -267.047873)
			(xy 367.282833 -267.011122) (xy 367.252282 -266.969074) (xy 367.228685 -266.922765) (xy 367.212623 -266.873334)
			(xy 367.20449 -266.821999) (xy 367.20399 -266.796012) (xy 367.204396 -266.772611) (xy 367.210996 -266.726277)
			(xy 367.224067 -266.681337) (xy 367.243348 -266.638691) (xy 367.255552 -266.61872) (xy 367.263172 -266.606528)
			(xy 367.263934 -266.578334) (xy 367.119154 -266.32916) (xy 367.094262 -266.315698) (xy 367.080038 -266.31646)
			(xy 367.064798 -266.316714) (xy 367.041957 -266.31631) (xy 366.996714 -266.309989) (xy 366.952769 -266.297508)
			(xy 366.910957 -266.279104) (xy 366.891316 -266.267438) (xy 366.879378 -266.260072) (xy 366.851438 -266.259818)
			(xy 365.99876 -266.74953) (xy 365.985044 -266.773914) (xy 365.985552 -266.787884) (xy 365.985552 -266.796012)
			(xy 365.985042 -266.822) (xy 365.97691 -266.873335) (xy 365.960848 -266.922767) (xy 365.937253 -266.969078)
			(xy 365.906703 -267.011128) (xy 365.869953 -267.047883) (xy 365.827906 -267.078436) (xy 365.781597 -267.102036)
			(xy 365.732167 -267.118102) (xy 365.680832 -267.126239) (xy 365.654844 -267.12672) (xy 365.645446 -267.126466)
			(xy 365.631476 -267.126212) (xy 365.607346 -267.139674) (xy 365.459518 -267.394436) (xy 365.459772 -267.421868)
			(xy 365.467138 -267.43406) (xy 365.478591 -267.453566) (xy 365.496641 -267.495041) (xy 365.508864 -267.538591)
			(xy 365.515032 -267.583402) (xy 365.515398 -267.606018) (xy 365.514888 -267.632005) (xy 365.506758 -267.68334)
			(xy 365.490697 -267.73277) (xy 365.467101 -267.77908) (xy 365.436551 -267.821128) (xy 365.3998 -267.857879)
			(xy 365.357752 -267.888429) (xy 365.311442 -267.912025) (xy 365.262012 -267.928086) (xy 365.210677 -267.936216)
			(xy 365.158703 -267.936216) (xy 365.107368 -267.928086) (xy 365.057938 -267.912025) (xy 365.011628 -267.888429)
			(xy 364.96958 -267.857879) (xy 364.932829 -267.821128) (xy 364.902279 -267.77908) (xy 364.878683 -267.73277)
			(xy 364.862622 -267.68334) (xy 364.854492 -267.632005) (xy 364.853982 -267.606018) (xy 364.854236 -267.594334)
			(xy 364.854744 -267.579856) (xy 364.841282 -267.555472) (xy 363.991398 -267.067284) (xy 363.963458 -267.068046)
			(xy 363.951266 -267.075666) (xy 363.931362 -267.087762) (xy 363.88888 -267.106856) (xy 363.844139 -267.1198)
			(xy 363.798024 -267.12634) (xy 363.774736 -267.12672) (xy 363.748745 -267.12624) (xy 363.697401 -267.118113)
			(xy 363.647961 -267.102054) (xy 363.601642 -267.078458) (xy 363.559584 -267.047907) (xy 363.522824 -267.011152)
			(xy 363.492267 -266.969099) (xy 363.468664 -266.922784) (xy 363.452598 -266.873346) (xy 363.444464 -266.822003)
			(xy 363.444028 -266.796012) (xy 363.444434 -266.772611) (xy 363.451035 -266.726277) (xy 363.464107 -266.681338)
			(xy 363.483389 -266.638693) (xy 363.49559 -266.61872) (xy 363.50321 -266.606528) (xy 363.503972 -266.578334)
			(xy 363.359192 -266.32916) (xy 363.3343 -266.315698) (xy 363.320076 -266.31646) (xy 363.304836 -266.316714)
			(xy 363.281994 -266.316312) (xy 363.236749 -266.309996) (xy 363.192801 -266.297519) (xy 363.150987 -266.279119)
			(xy 363.131354 -266.267438) (xy 363.119416 -266.260072) (xy 363.091476 -266.259818) (xy 362.238798 -266.74953)
			(xy 362.225082 -266.773914) (xy 362.22559 -266.787884) (xy 362.22559 -266.796012) (xy 362.225106 -266.822)
			(xy 362.216973 -266.873336) (xy 362.20091 -266.922768) (xy 362.177311 -266.969078) (xy 362.146758 -267.011127)
			(xy 362.110004 -267.047878) (xy 362.067953 -267.078427) (xy 362.02164 -267.102021) (xy 361.972207 -267.11808)
			(xy 361.92087 -267.126208) (xy 361.894882 -267.12672) (xy 361.869393 -267.126247) (xy 361.819021 -267.118415)
			(xy 361.77045 -267.102939) (xy 361.724831 -267.080187) (xy 361.683248 -267.050699) (xy 361.646688 -267.015174)
			(xy 361.616017 -266.974456) (xy 361.603544 -266.952222) (xy 361.596686 -266.939776) (xy 361.57281 -266.925552)
			(xy 359.125774 -266.925552) (xy 359.119169 -266.925768) (xy 359.106422 -266.929234) (xy 359.100628 -266.93241)
			(xy 358.014778 -267.556234) (xy 358.001062 -267.580618) (xy 358.00157 -267.594842) (xy 358.001824 -267.606018)
			(xy 358.001314 -267.632005) (xy 357.993184 -267.68334) (xy 357.977123 -267.73277) (xy 357.953527 -267.77908)
			(xy 357.922977 -267.821128) (xy 357.886226 -267.857879) (xy 357.844178 -267.888429) (xy 357.797868 -267.912025)
			(xy 357.748438 -267.928086) (xy 357.697103 -267.936216) (xy 357.645129 -267.936216) (xy 357.593794 -267.928086)
			(xy 357.544364 -267.912025) (xy 357.498054 -267.888429) (xy 357.456006 -267.857879) (xy 357.419255 -267.821128)
			(xy 357.388705 -267.77908) (xy 357.365109 -267.73277) (xy 357.349048 -267.68334) (xy 357.340918 -267.632005)
			(xy 357.340408 -267.606018) (xy 357.34079 -267.583258) (xy 357.347027 -267.538168) (xy 357.359374 -267.494355)
			(xy 357.377598 -267.452642) (xy 357.389176 -267.433044) (xy 357.396542 -267.421106) (xy 357.396796 -267.393166)
			(xy 357.24973 -267.139674) (xy 357.225346 -267.126212) (xy 357.211122 -267.126466) (xy 357.201216 -267.12672)
			(xy 357.175226 -267.126238) (xy 357.123884 -267.118109) (xy 357.074447 -267.102048) (xy 357.028131 -267.078452)
			(xy 356.986076 -267.0479) (xy 356.949318 -267.011145) (xy 356.918763 -266.969093) (xy 356.895162 -266.922779)
			(xy 356.879098 -266.873343) (xy 356.870964 -266.822002) (xy 356.870508 -266.796012) (xy 356.870508 -266.787376)
			(xy 356.871016 -266.773406) (xy 356.8573 -266.749022) (xy 356.004876 -266.25931) (xy 355.976936 -266.259818)
			(xy 355.964998 -266.267184) (xy 355.945311 -266.278918) (xy 355.90339 -266.297438) (xy 355.859312 -266.309991)
			(xy 355.813923 -266.316335) (xy 355.791008 -266.316714) (xy 355.776784 -266.31646) (xy 355.76256 -266.315698)
			(xy 355.737668 -266.329414) (xy 355.592634 -266.579096) (xy 355.593142 -266.607544) (xy 355.600762 -266.619482)
			(xy 355.612856 -266.639387) (xy 355.631943 -266.68187) (xy 355.644881 -266.726611) (xy 355.651414 -266.772725)
			(xy 355.651816 -266.796012) (xy 355.651306 -266.821999) (xy 355.643174 -266.873332) (xy 355.627112 -266.922762)
			(xy 355.603515 -266.96907) (xy 355.572965 -267.011117) (xy 355.536214 -267.047868) (xy 355.494167 -267.078417)
			(xy 355.447858 -267.102013) (xy 355.398428 -267.118074) (xy 355.347095 -267.126206) (xy 355.321108 -267.12672)
			(xy 355.297893 -267.126327) (xy 355.251919 -267.119826) (xy 355.207309 -267.106951) (xy 355.164942 -267.087956)
			(xy 355.145086 -267.07592) (xy 355.132894 -267.0683) (xy 355.104954 -267.067792) (xy 354.254816 -267.556234)
			(xy 354.2411 -267.580618) (xy 354.241608 -267.594842) (xy 354.241862 -267.606018) (xy 354.241352 -267.632005)
			(xy 354.233222 -267.68334) (xy 354.217161 -267.73277) (xy 354.193565 -267.77908) (xy 354.163015 -267.821128)
			(xy 354.126264 -267.857879) (xy 354.084216 -267.888429) (xy 354.037906 -267.912025) (xy 353.988476 -267.928086)
			(xy 353.937141 -267.936216) (xy 353.885167 -267.936216) (xy 353.833832 -267.928086) (xy 353.784402 -267.912025)
			(xy 353.738092 -267.888429) (xy 353.696044 -267.857879) (xy 353.659293 -267.821128) (xy 353.628743 -267.77908)
			(xy 353.605147 -267.73277) (xy 353.589086 -267.68334) (xy 353.580956 -267.632005) (xy 353.580446 -267.606018)
			(xy 353.580828 -267.583258) (xy 353.587066 -267.538168) (xy 353.599414 -267.494356) (xy 353.61764 -267.452644)
			(xy 353.629214 -267.433044) (xy 353.63658 -267.421106) (xy 353.636834 -267.393166) (xy 353.489768 -267.139674)
			(xy 353.465384 -267.126212) (xy 353.45116 -267.126466) (xy 353.441 -267.12672) (xy 353.415012 -267.12621)
			(xy 353.363677 -267.11808) (xy 353.314246 -267.102019) (xy 353.267936 -267.078423) (xy 353.225886 -267.047874)
			(xy 353.189134 -267.011123) (xy 353.158583 -266.969075) (xy 353.134985 -266.922765) (xy 353.118923 -266.873334)
			(xy 353.11079 -266.822) (xy 353.110292 -266.796012) (xy 353.110292 -266.787376) (xy 353.1108 -266.773406)
			(xy 353.097084 -266.749022) (xy 352.244914 -266.25931) (xy 352.216974 -266.259818) (xy 352.205036 -266.267184)
			(xy 352.185348 -266.278914) (xy 352.143426 -266.297426) (xy 352.099348 -266.309971) (xy 352.05396 -266.316307)
			(xy 352.031046 -266.316714) (xy 352.016822 -266.31646) (xy 352.002598 -266.315698) (xy 351.977706 -266.329414)
			(xy 351.832672 -266.579096) (xy 351.83318 -266.607544) (xy 351.8408 -266.619482) (xy 351.852896 -266.639386)
			(xy 351.871987 -266.681869) (xy 351.884927 -266.72661) (xy 351.891461 -266.772724) (xy 351.891854 -266.796012)
			(xy 351.891344 -266.822) (xy 351.883212 -266.873336) (xy 351.86715 -266.922768) (xy 351.843555 -266.969079)
			(xy 351.813005 -267.011129) (xy 351.776255 -267.047883) (xy 351.734208 -267.078437) (xy 351.687899 -267.102037)
			(xy 351.638469 -267.118104) (xy 351.587134 -267.126241) (xy 351.561146 -267.12672) (xy 351.537972 -267.126334)
			(xy 351.492076 -267.119871) (xy 351.447532 -267.107065) (xy 351.405211 -267.088167) (xy 351.385378 -267.076174)
			(xy 351.373186 -267.068554) (xy 351.3455 -267.068046) (xy 350.682052 -267.45057) (xy 350.667383 -267.458476)
			(xy 350.635208 -267.467111) (xy 350.618552 -267.467588) (xy 350.220026 -267.467588) (xy 350.203453 -267.467017)
			(xy 350.171445 -267.458399) (xy 350.142743 -267.441818) (xy 350.130618 -267.430504) (xy 349.816166 -267.115798)
			(xy 349.788988 -267.10894) (xy 349.775526 -267.113004) (xy 349.752434 -267.119425) (xy 349.705003 -267.126314)
			(xy 349.681038 -267.12672) (xy 349.655046 -267.12624) (xy 349.603703 -267.118113) (xy 349.554262 -267.102055)
			(xy 349.507943 -267.078459) (xy 349.465885 -267.047908) (xy 349.429125 -267.011153) (xy 349.398567 -266.9691)
			(xy 349.374965 -266.922784) (xy 349.358898 -266.873346) (xy 349.350764 -266.822003) (xy 349.35033 -266.796012)
			(xy 349.35033 -266.787376) (xy 349.350838 -266.773152) (xy 349.337122 -266.748768) (xy 348.484952 -266.25931)
			(xy 348.457012 -266.259818) (xy 348.445074 -266.267184) (xy 348.425387 -266.278917) (xy 348.383465 -266.297434)
			(xy 348.339387 -266.309983) (xy 348.293999 -266.316324) (xy 348.271084 -266.316714) (xy 348.257114 -266.31646)
			(xy 348.24289 -266.315698) (xy 348.217998 -266.329414) (xy 348.072964 -266.579604) (xy 348.073472 -266.607798)
			(xy 348.081092 -266.619736) (xy 348.093128 -266.639626) (xy 348.112117 -266.682061) (xy 348.124988 -266.726734)
			(xy 348.131486 -266.772767) (xy 348.131892 -266.796012) (xy 348.131408 -266.822) (xy 348.123275 -266.873336)
			(xy 348.107212 -266.922768) (xy 348.083613 -266.969079) (xy 348.05306 -267.011127) (xy 348.016306 -267.047879)
			(xy 347.974255 -267.078428) (xy 347.927942 -267.102022) (xy 347.878509 -267.118082) (xy 347.827172 -267.12621)
			(xy 347.801184 -267.12672) (xy 347.78696 -267.126466) (xy 347.772736 -267.125704) (xy 347.748098 -267.13942)
			(xy 347.588586 -267.414248) (xy 347.588586 -267.441426) (xy 347.595444 -267.453364) (xy 347.608303 -267.476728)
			(xy 347.626542 -267.526838) (xy 347.635801 -267.579355) (xy 347.636338 -267.606018) (xy 347.635866 -267.630009)
			(xy 347.628358 -267.6774) (xy 347.613529 -267.723034) (xy 347.591745 -267.765786) (xy 347.563542 -267.804605)
			(xy 347.529614 -267.838534) (xy 347.490797 -267.866739) (xy 347.448045 -267.888525) (xy 347.402412 -267.903355)
			(xy 347.355021 -267.910865) (xy 347.33103 -267.911326) (xy 347.304585 -267.910766) (xy 347.252486 -267.901662)
			(xy 347.202733 -267.883719) (xy 347.156814 -267.857475) (xy 347.116102 -267.823714) (xy 347.081814 -267.783445)
			(xy 347.067886 -267.760958) (xy 347.061028 -267.749274) (xy 347.03766 -267.735812) (xy 346.713048 -267.735812)
			(xy 346.689172 -267.75029) (xy 346.682568 -267.762736) (xy 346.670078 -267.78493) (xy 346.63934 -267.825533)
			(xy 346.602744 -267.860948) (xy 346.561154 -267.890338) (xy 346.515554 -267.913011) (xy 346.467018 -267.92843)
			(xy 346.416693 -267.936231) (xy 346.365767 -267.936231) (xy 346.315442 -267.92843) (xy 346.266906 -267.913011)
			(xy 346.221306 -267.890338) (xy 346.179716 -267.860948) (xy 346.14312 -267.825533) (xy 346.112382 -267.78493)
			(xy 346.099892 -267.762736) (xy 346.093288 -267.75029) (xy 346.069412 -267.735812) (xy 345.744546 -267.735812)
			(xy 345.721178 -267.749274) (xy 345.71432 -267.760958) (xy 345.700455 -267.783413) (xy 345.66627 -267.823613)
			(xy 345.625686 -267.857343) (xy 345.603068 -267.87094) (xy 345.593924 -267.876274) (xy 345.581224 -267.893038)
			(xy 345.559888 -267.98651) (xy 345.563698 -268.007084) (xy 345.569794 -268.015974) (xy 345.589319 -268.045513)
			(xy 345.62308 -268.107758) (xy 345.650496 -268.173048) (xy 345.671295 -268.240736) (xy 345.685272 -268.310155)
			(xy 345.692289 -268.380618) (xy 345.69273 -268.416024) (xy 345.692241 -268.453297) (xy 345.684447 -268.527435)
			(xy 345.668946 -268.600351) (xy 345.645908 -268.671249) (xy 345.615587 -268.73935) (xy 345.578313 -268.803908)
			(xy 345.534495 -268.864217) (xy 345.484614 -268.919615) (xy 345.429215 -268.969496) (xy 345.368906 -269.013314)
			(xy 345.304348 -269.050588) (xy 345.236247 -269.080909) (xy 345.16535 -269.103947) (xy 345.092433 -269.119447)
			(xy 345.018295 -269.127241) (xy 344.981022 -269.127732) (xy 344.948002 -269.12697) (xy 344.937588 -269.126462)
			(xy 344.918284 -269.133574) (xy 344.849958 -269.198598) (xy 344.84183 -269.217394) (xy 344.84183 -269.227808)
			(xy 344.841328 -269.251132) (xy 344.834563 -269.297291) (xy 344.821368 -269.342037) (xy 344.802005 -269.384481)
			(xy 344.78976 -269.404338) (xy 344.781886 -269.41653) (xy 344.781378 -269.444724) (xy 344.925396 -269.692882)
			(xy 344.950034 -269.706344) (xy 344.964512 -269.705836) (xy 344.981022 -269.705328) (xy 345.007009 -269.705813)
			(xy 345.058343 -269.713947) (xy 345.107772 -269.730012) (xy 345.15408 -269.753611) (xy 345.196125 -269.784164)
			(xy 345.232873 -269.820919) (xy 345.263419 -269.86297) (xy 345.287011 -269.909281) (xy 345.303067 -269.958714)
			(xy 345.311192 -270.010049) (xy 345.31173 -270.036036) (xy 345.311338 -270.059584) (xy 345.304699 -270.10621)
			(xy 345.291502 -270.151419) (xy 345.272017 -270.194295) (xy 345.25966 -270.214344) (xy 345.251786 -270.226536)
			(xy 345.251278 -270.25473) (xy 345.395296 -270.503142) (xy 345.419934 -270.516604) (xy 345.434412 -270.515842)
			(xy 345.451176 -270.515334) (xy 345.477163 -270.515815) (xy 345.528498 -270.523942) (xy 345.57793 -270.540001)
			(xy 345.62424 -270.563594) (xy 345.66629 -270.594142) (xy 345.703042 -270.630892) (xy 345.733593 -270.672939)
			(xy 345.75719 -270.719248) (xy 345.773252 -270.768678) (xy 345.781383 -270.820013) (xy 345.781383 -270.871987)
			(xy 345.773252 -270.923322) (xy 345.75719 -270.972752) (xy 345.733593 -271.019061) (xy 345.703042 -271.061108)
			(xy 345.66629 -271.097858) (xy 345.62424 -271.128406) (xy 345.57793 -271.151999) (xy 345.528498 -271.168058)
			(xy 345.477163 -271.176185) (xy 345.451176 -271.17675) (xy 345.436952 -271.176496) (xy 345.422728 -271.175734)
			(xy 345.397836 -271.18945) (xy 345.252802 -271.43964) (xy 345.25331 -271.467834) (xy 345.26093 -271.479772)
			(xy 345.272968 -271.499662) (xy 345.291964 -271.542096) (xy 345.304841 -271.586768) (xy 345.311348 -271.632802)
			(xy 345.31173 -271.656048) (xy 345.311217 -271.682033) (xy 345.303081 -271.733363) (xy 345.287016 -271.782789)
			(xy 345.263418 -271.829093) (xy 345.232867 -271.871137) (xy 345.196117 -271.907884) (xy 345.154071 -271.938431)
			(xy 345.107765 -271.962026) (xy 345.058338 -271.978087) (xy 345.007007 -271.986219) (xy 344.981022 -271.986756)
			(xy 344.967052 -271.986502) (xy 344.952828 -271.98574) (xy 344.92819 -271.999456) (xy 344.782902 -272.249646)
			(xy 344.78341 -272.27784) (xy 344.79103 -272.290032) (xy 344.803061 -272.30989) (xy 344.822045 -272.352259)
			(xy 344.834915 -272.396869) (xy 344.841417 -272.44284) (xy 344.84183 -272.466054) (xy 344.841437 -272.489602)
			(xy 344.834795 -272.536226) (xy 344.821597 -272.581434) (xy 344.802109 -272.624309) (xy 344.78976 -272.644362)
			(xy 344.781886 -272.656554) (xy 344.781378 -272.684748) (xy 344.925396 -272.932906) (xy 344.950034 -272.946368)
			(xy 344.964512 -272.94586) (xy 344.981022 -272.945352) (xy 345.007009 -272.945863) (xy 345.058343 -272.953996)
			(xy 345.107774 -272.970059) (xy 345.154083 -272.993655) (xy 345.196131 -273.024204) (xy 345.232884 -273.060955)
			(xy 345.263436 -273.103002) (xy 345.287034 -273.14931) (xy 345.3031 -273.198739) (xy 345.311235 -273.250073)
			(xy 345.31173 -273.27606) (xy 345.311337 -273.299608) (xy 345.304694 -273.346232) (xy 345.291495 -273.391439)
			(xy 345.272007 -273.434313) (xy 345.25966 -273.454368) (xy 345.251786 -273.46656) (xy 345.251278 -273.494754)
			(xy 345.395296 -273.743166) (xy 345.419934 -273.756628) (xy 345.434412 -273.755866) (xy 345.451176 -273.755358)
			(xy 345.477169 -273.755839) (xy 345.528516 -273.763969) (xy 345.577959 -273.78003) (xy 345.62428 -273.803629)
			(xy 345.666339 -273.834184) (xy 345.7031 -273.870943) (xy 345.733658 -273.913) (xy 345.757261 -273.959319)
			(xy 345.773326 -274.008761) (xy 345.781459 -274.060107) (xy 345.781459 -274.112093) (xy 345.773326 -274.163439)
			(xy 345.757261 -274.212881) (xy 345.733658 -274.259201) (xy 345.7031 -274.301257) (xy 345.666339 -274.338016)
			(xy 345.62428 -274.368571) (xy 345.577959 -274.39217) (xy 345.528516 -274.408231) (xy 345.477169 -274.416361)
			(xy 345.451176 -274.416774) (xy 345.436952 -274.41652) (xy 345.422728 -274.415758) (xy 345.397836 -274.429474)
			(xy 345.252802 -274.679664) (xy 345.25331 -274.707858) (xy 345.26093 -274.719796) (xy 345.272967 -274.739686)
			(xy 345.291959 -274.78212) (xy 345.304834 -274.826793) (xy 345.311337 -274.872827) (xy 345.31173 -274.896072)
			(xy 345.311249 -274.922063) (xy 345.303121 -274.973407) (xy 345.287062 -275.022846) (xy 345.263466 -275.069165)
			(xy 345.232915 -275.111222) (xy 345.19616 -275.147982) (xy 345.154108 -275.17854) (xy 345.107793 -275.202143)
			(xy 345.058355 -275.21821) (xy 345.007013 -275.226345) (xy 344.981022 -275.22678) (xy 344.967052 -275.226526)
			(xy 344.952828 -275.225764) (xy 344.92819 -275.23948) (xy 344.782902 -275.48967) (xy 344.78341 -275.517864)
			(xy 344.79103 -275.530056) (xy 344.803065 -275.549912) (xy 344.822059 -275.592281) (xy 344.834939 -275.63689)
			(xy 344.841452 -275.682862) (xy 344.84183 -275.706078) (xy 344.841435 -275.729625) (xy 344.83479 -275.776249)
			(xy 344.821589 -275.821455) (xy 344.8021 -275.864327) (xy 344.78976 -275.884386) (xy 344.781886 -275.896578)
			(xy 344.781378 -275.924772) (xy 344.925396 -276.17293) (xy 344.950034 -276.186392) (xy 344.964512 -276.185884)
			(xy 344.981022 -276.185376) (xy 345.007009 -276.185887) (xy 345.058341 -276.19402) (xy 345.10777 -276.210083)
			(xy 345.154078 -276.23368) (xy 345.196124 -276.26423) (xy 345.232874 -276.300981) (xy 345.263423 -276.343028)
			(xy 345.287019 -276.389336) (xy 345.303081 -276.438765) (xy 345.311213 -276.490097) (xy 345.31173 -276.516084)
			(xy 345.311335 -276.539631) (xy 345.304689 -276.586254) (xy 345.291487 -276.63146) (xy 345.271997 -276.674331)
			(xy 345.25966 -276.694392) (xy 345.251786 -276.706584) (xy 345.251278 -276.734778) (xy 345.395296 -276.98319)
			(xy 345.419934 -276.996652) (xy 345.434412 -276.99589) (xy 345.451176 -276.995382) (xy 345.477167 -276.995863)
			(xy 345.52851 -277.003992) (xy 345.57795 -277.020052) (xy 345.624267 -277.04365) (xy 345.666324 -277.074202)
			(xy 345.703082 -277.110958) (xy 345.733638 -277.153012) (xy 345.757238 -277.199328) (xy 345.773303 -277.248766)
			(xy 345.781435 -277.300109) (xy 345.781435 -277.352091) (xy 345.773303 -277.403434) (xy 345.757238 -277.452872)
			(xy 345.733638 -277.499188) (xy 345.703082 -277.541242) (xy 345.666324 -277.577998) (xy 345.624267 -277.60855)
			(xy 345.57795 -277.632148) (xy 345.52851 -277.648208) (xy 345.477167 -277.656337) (xy 345.451176 -277.656798)
			(xy 345.436952 -277.656544) (xy 345.422728 -277.655782) (xy 345.397836 -277.669498) (xy 345.252802 -277.919688)
			(xy 345.25331 -277.947882) (xy 345.26093 -277.95982) (xy 345.272965 -277.97971) (xy 345.291955 -278.022145)
			(xy 345.304826 -278.066818) (xy 345.311325 -278.112851) (xy 345.31173 -278.136096) (xy 345.311221 -278.162084)
			(xy 345.303091 -278.21342) (xy 345.287031 -278.262853) (xy 345.263435 -278.309164) (xy 345.232886 -278.351215)
			(xy 345.196135 -278.387969) (xy 345.154087 -278.418522) (xy 345.107777 -278.442121) (xy 345.058346 -278.458185)
			(xy 345.00701 -278.466319) (xy 344.981022 -278.466804) (xy 344.967052 -278.46655) (xy 344.952828 -278.465788)
			(xy 344.92819 -278.479504) (xy 344.782902 -278.729694) (xy 344.78341 -278.757888) (xy 344.79103 -278.77008)
			(xy 344.803064 -278.789937) (xy 344.822055 -278.832306) (xy 344.834932 -278.876915) (xy 344.841441 -278.922887)
			(xy 344.84183 -278.946102) (xy 344.841576 -278.961342) (xy 344.840814 -278.97582) (xy 344.854276 -279.000458)
			(xy 345.701366 -279.486868) (xy 345.72956 -279.486106) (xy 345.741498 -279.478232) (xy 345.761661 -279.465704)
			(xy 345.804815 -279.445929) (xy 345.850354 -279.432528) (xy 345.897341 -279.425778) (xy 345.921076 -279.4254)
			(xy 345.947066 -279.425881) (xy 345.998406 -279.434009) (xy 346.047843 -279.450069) (xy 346.094158 -279.473665)
			(xy 346.136212 -279.504216) (xy 346.172968 -279.54097) (xy 346.203522 -279.583021) (xy 346.227122 -279.629335)
			(xy 346.243185 -279.678771) (xy 346.251317 -279.73011) (xy 346.251317 -279.78209) (xy 346.243185 -279.833429)
			(xy 346.227122 -279.882865) (xy 346.203522 -279.929179) (xy 346.172968 -279.97123) (xy 346.136212 -280.007984)
			(xy 346.094158 -280.038535) (xy 346.047843 -280.062131) (xy 345.998406 -280.078191) (xy 345.947066 -280.086319)
			(xy 345.921076 -280.086816) (xy 345.906852 -280.086562) (xy 345.892628 -280.0858) (xy 345.86799 -280.099516)
			(xy 345.722956 -280.349452) (xy 345.723464 -280.377646) (xy 345.73083 -280.389838) (xy 345.742912 -280.409714)
			(xy 345.761989 -280.452134) (xy 345.774934 -280.49681) (xy 345.781491 -280.542858) (xy 345.781884 -280.566114)
			(xy 345.7814 -280.592102) (xy 345.773267 -280.643437) (xy 345.757203 -280.692868) (xy 345.733604 -280.739178)
			(xy 345.703051 -280.781226) (xy 345.666297 -280.817976) (xy 345.624246 -280.848524) (xy 345.577933 -280.872117)
			(xy 345.5285 -280.888176) (xy 345.477164 -280.896303) (xy 345.451176 -280.896822) (xy 345.436952 -280.896568)
			(xy 345.422728 -280.895806) (xy 345.39809 -280.909522) (xy 345.252802 -281.159712) (xy 345.25331 -281.187906)
			(xy 345.26093 -281.200098) (xy 345.272963 -281.219955) (xy 345.291951 -281.262324) (xy 345.304826 -281.306934)
			(xy 345.311333 -281.352905) (xy 345.31173 -281.3761) (xy 345.615289 -281.3761) (xy 345.619459 -281.325768)
			(xy 345.631857 -281.276808) (xy 345.652144 -281.230557) (xy 345.679766 -281.188275) (xy 345.713971 -281.151116)
			(xy 345.753825 -281.120094) (xy 345.798241 -281.096054) (xy 345.846008 -281.079652) (xy 345.895824 -281.071335)
			(xy 345.921076 -281.070812) (xy 346.86113 -281.070812) (xy 346.886385 -281.071296) (xy 346.936207 -281.079614)
			(xy 346.983979 -281.096019) (xy 347.028401 -281.120062) (xy 347.068259 -281.151089) (xy 347.102467 -281.188252)
			(xy 347.130092 -281.230539) (xy 347.150381 -281.276796) (xy 347.16278 -281.325762) (xy 347.166951 -281.3761)
			(xy 348.43536 -281.3761) (xy 348.439532 -281.325756) (xy 348.451934 -281.276786) (xy 348.472227 -281.230526)
			(xy 348.499859 -281.188237) (xy 348.534075 -281.151073) (xy 348.573942 -281.120048) (xy 348.618371 -281.096009)
			(xy 348.666152 -281.079611) (xy 348.71598 -281.071302) (xy 348.741238 -281.070812) (xy 349.681292 -281.070812)
			(xy 349.706552 -281.071264) (xy 349.756383 -281.079578) (xy 349.804165 -281.095981) (xy 349.848596 -281.120025)
			(xy 349.888464 -281.151054) (xy 349.92268 -281.188222) (xy 349.950312 -281.230515) (xy 349.970606 -281.276779)
			(xy 349.983008 -281.325753) (xy 349.98718 -281.3761) (xy 370.049089 -281.3761) (xy 370.053259 -281.325769)
			(xy 370.065656 -281.276811) (xy 370.085941 -281.230561) (xy 370.113562 -281.18828) (xy 370.147764 -281.151122)
			(xy 370.187616 -281.120099) (xy 370.23203 -281.096058) (xy 370.279795 -281.079655) (xy 370.329608 -281.071337)
			(xy 370.35486 -281.070812) (xy 371.294914 -281.070812) (xy 371.32017 -281.071295) (xy 371.369993 -281.079611)
			(xy 371.417768 -281.096014) (xy 371.462192 -281.120057) (xy 371.502053 -281.151083) (xy 371.536263 -281.188247)
			(xy 371.56389 -281.230535) (xy 371.58418 -281.276793) (xy 371.59658 -281.32576) (xy 371.600751 -281.3761)
			(xy 372.868989 -281.3761) (xy 372.873159 -281.325768) (xy 372.885556 -281.27681) (xy 372.905842 -281.230559)
			(xy 372.933464 -281.188278) (xy 372.967667 -281.151119) (xy 373.00752 -281.120096) (xy 373.051935 -281.096056)
			(xy 373.099702 -281.079653) (xy 373.149516 -281.071336) (xy 373.174768 -281.070812) (xy 374.114822 -281.070812)
			(xy 374.140078 -281.071295) (xy 374.1899 -281.079613) (xy 374.237674 -281.096016) (xy 374.282096 -281.120059)
			(xy 374.321956 -281.151086) (xy 374.356165 -281.18825) (xy 374.383791 -281.230537) (xy 374.404081 -281.276795)
			(xy 374.41648 -281.325761) (xy 374.420651 -281.3761) (xy 374.41648 -281.426439) (xy 374.404081 -281.475405)
			(xy 374.383791 -281.521663) (xy 374.356165 -281.56395) (xy 374.321956 -281.601114) (xy 374.282096 -281.632141)
			(xy 374.237674 -281.656184) (xy 374.1899 -281.672587) (xy 374.140078 -281.680905) (xy 374.114822 -281.681428)
			(xy 373.174768 -281.681428) (xy 373.149516 -281.680864) (xy 373.099702 -281.672547) (xy 373.051935 -281.656144)
			(xy 373.00752 -281.632104) (xy 372.967667 -281.601081) (xy 372.933464 -281.563922) (xy 372.905842 -281.521641)
			(xy 372.885556 -281.47539) (xy 372.873159 -281.426432) (xy 372.868989 -281.3761) (xy 371.600751 -281.3761)
			(xy 371.59658 -281.42644) (xy 371.58418 -281.475407) (xy 371.56389 -281.521665) (xy 371.536263 -281.563953)
			(xy 371.502053 -281.601117) (xy 371.462192 -281.632143) (xy 371.417768 -281.656186) (xy 371.369993 -281.672589)
			(xy 371.32017 -281.680905) (xy 371.294914 -281.681428) (xy 370.35486 -281.681428) (xy 370.329609 -281.680863)
			(xy 370.279795 -281.672545) (xy 370.23203 -281.656142) (xy 370.187616 -281.632101) (xy 370.147764 -281.601078)
			(xy 370.113562 -281.56392) (xy 370.085941 -281.521639) (xy 370.065656 -281.475389) (xy 370.053259 -281.426431)
			(xy 370.049089 -281.3761) (xy 349.98718 -281.3761) (xy 349.983008 -281.426447) (xy 349.970606 -281.475421)
			(xy 349.950312 -281.521685) (xy 349.92268 -281.563978) (xy 349.888464 -281.601146) (xy 349.848596 -281.632175)
			(xy 349.804165 -281.656219) (xy 349.756383 -281.672622) (xy 349.706552 -281.680936) (xy 349.681292 -281.681428)
			(xy 348.741238 -281.681428) (xy 348.71598 -281.680898) (xy 348.666152 -281.672589) (xy 348.618371 -281.656191)
			(xy 348.573941 -281.632152) (xy 348.534075 -281.601127) (xy 348.499859 -281.563963) (xy 348.472227 -281.521674)
			(xy 348.451934 -281.475414) (xy 348.439532 -281.426444) (xy 348.43536 -281.3761) (xy 347.166951 -281.3761)
			(xy 347.16278 -281.426438) (xy 347.150381 -281.475404) (xy 347.130092 -281.521661) (xy 347.102467 -281.563948)
			(xy 347.068259 -281.601111) (xy 347.028401 -281.632138) (xy 346.983979 -281.656181) (xy 346.936207 -281.672586)
			(xy 346.886385 -281.680904) (xy 346.86113 -281.681428) (xy 345.921076 -281.681428) (xy 345.895824 -281.680865)
			(xy 345.846008 -281.672548) (xy 345.798241 -281.656146) (xy 345.753825 -281.632106) (xy 345.713971 -281.601084)
			(xy 345.679766 -281.563925) (xy 345.652144 -281.521643) (xy 345.631857 -281.475392) (xy 345.619459 -281.426432)
			(xy 345.615289 -281.3761) (xy 345.31173 -281.3761) (xy 345.31173 -281.37612) (xy 345.311333 -281.399667)
			(xy 345.304682 -281.446287) (xy 345.291476 -281.49149) (xy 345.271982 -281.534359) (xy 345.25966 -281.554428)
			(xy 345.251786 -281.56662) (xy 345.251278 -281.594814) (xy 345.395296 -281.843226) (xy 345.419934 -281.856688)
			(xy 345.434412 -281.855926) (xy 345.451176 -281.855418) (xy 345.477164 -281.855899) (xy 345.528502 -281.864027)
			(xy 345.577936 -281.880086) (xy 345.624249 -281.90368) (xy 345.6663 -281.93423) (xy 345.703055 -281.970982)
			(xy 345.733607 -282.013031) (xy 345.757205 -282.059342) (xy 345.773268 -282.108775) (xy 345.781399 -282.160112)
			(xy 345.781399 -282.1861) (xy 356.42504 -282.1861) (xy 356.429214 -282.135728) (xy 356.441621 -282.08673)
			(xy 356.461923 -282.040442) (xy 356.489566 -281.998127) (xy 356.523797 -281.960938) (xy 356.563681 -281.92989)
			(xy 356.608132 -281.90583) (xy 356.655936 -281.889414) (xy 356.70579 -281.881089) (xy 356.731062 -281.880564)
			(xy 357.671116 -281.880564) (xy 357.696394 -281.881035) (xy 357.746259 -281.889359) (xy 357.794074 -281.905776)
			(xy 357.838536 -281.929839) (xy 357.87843 -281.960892) (xy 357.912669 -281.998088) (xy 357.940319 -282.040411)
			(xy 357.960627 -282.086709) (xy 357.973037 -282.135717) (xy 357.977212 -282.1861) (xy 362.05874 -282.1861)
			(xy 362.062914 -282.135726) (xy 362.075322 -282.086726) (xy 362.095626 -282.040437) (xy 362.123271 -281.99812)
			(xy 362.157505 -281.960931) (xy 362.197392 -281.929883) (xy 362.241845 -281.905824) (xy 362.289652 -281.88941)
			(xy 362.339509 -281.881087) (xy 362.364782 -281.880564) (xy 363.304836 -281.880564) (xy 363.330113 -281.881037)
			(xy 363.379975 -281.889363) (xy 363.427788 -281.905782) (xy 363.472246 -281.929846) (xy 363.512138 -281.960899)
			(xy 363.546374 -281.998094) (xy 363.574022 -282.040417) (xy 363.594328 -282.086713) (xy 363.606737 -282.135719)
			(xy 363.610912 -282.1861) (xy 363.606737 -282.236481) (xy 363.594328 -282.285487) (xy 363.574022 -282.331783)
			(xy 363.546374 -282.374106) (xy 363.512138 -282.411301) (xy 363.472246 -282.442354) (xy 363.427788 -282.466418)
			(xy 363.379975 -282.482837) (xy 363.330113 -282.491163) (xy 363.304836 -282.491688) (xy 362.364782 -282.491688)
			(xy 362.339509 -282.491113) (xy 362.289652 -282.48279) (xy 362.241845 -282.466376) (xy 362.197392 -282.442317)
			(xy 362.157505 -282.411269) (xy 362.123271 -282.37408) (xy 362.095626 -282.331763) (xy 362.075322 -282.285474)
			(xy 362.062914 -282.236474) (xy 362.05874 -282.1861) (xy 357.977212 -282.1861) (xy 357.973037 -282.236483)
			(xy 357.960627 -282.285491) (xy 357.940319 -282.331789) (xy 357.912669 -282.374112) (xy 357.87843 -282.411308)
			(xy 357.838536 -282.442361) (xy 357.794074 -282.466424) (xy 357.746259 -282.482841) (xy 357.696394 -282.491165)
			(xy 357.671116 -282.491688) (xy 356.731062 -282.491688) (xy 356.70579 -282.491111) (xy 356.655936 -282.482786)
			(xy 356.608132 -282.46637) (xy 356.563681 -282.44231) (xy 356.523797 -282.411262) (xy 356.489566 -282.374073)
			(xy 356.461923 -282.331758) (xy 356.441621 -282.28547) (xy 356.429214 -282.236472) (xy 356.42504 -282.1861)
			(xy 345.781399 -282.1861) (xy 345.781399 -282.212088) (xy 345.773268 -282.263425) (xy 345.757205 -282.312858)
			(xy 345.733607 -282.359169) (xy 345.703055 -282.401218) (xy 345.6663 -282.43797) (xy 345.624249 -282.46852)
			(xy 345.577936 -282.492114) (xy 345.528502 -282.508173) (xy 345.477164 -282.516301) (xy 345.451176 -282.516834)
			(xy 345.436952 -282.51658) (xy 345.422728 -282.515818) (xy 345.397836 -282.529534) (xy 345.252802 -282.779724)
			(xy 345.25331 -282.807918) (xy 345.26093 -282.819856) (xy 345.272969 -282.839745) (xy 345.291967 -282.882179)
			(xy 345.304847 -282.926852) (xy 345.311355 -282.972886) (xy 345.311729 -282.9961) (xy 345.615301 -282.9961)
			(xy 345.619471 -282.94577) (xy 345.631868 -282.896812) (xy 345.652154 -282.850562) (xy 345.679775 -282.808282)
			(xy 345.713979 -282.771125) (xy 345.753831 -282.740104) (xy 345.798246 -282.716065) (xy 345.846011 -282.699663)
			(xy 345.895825 -282.691347) (xy 345.921076 -282.690824) (xy 346.86113 -282.690824) (xy 346.886386 -282.691284)
			(xy 346.936209 -282.699603) (xy 346.983984 -282.716008) (xy 347.028407 -282.740052) (xy 347.068267 -282.77108)
			(xy 347.102477 -282.808245) (xy 347.130103 -282.850534) (xy 347.150393 -282.896792) (xy 347.162792 -282.94576)
			(xy 347.166963 -282.9961) (xy 348.435372 -282.9961) (xy 348.439544 -282.945758) (xy 348.451945 -282.89679)
			(xy 348.472238 -282.850531) (xy 348.499869 -282.808244) (xy 348.534083 -282.771081) (xy 348.573948 -282.740058)
			(xy 348.618376 -282.71602) (xy 348.666155 -282.699622) (xy 348.715981 -282.691314) (xy 348.741238 -282.690824)
			(xy 349.681292 -282.690824) (xy 349.706553 -282.691252) (xy 349.756386 -282.699567) (xy 349.80417 -282.71597)
			(xy 349.848603 -282.740015) (xy 349.888472 -282.771045) (xy 349.92269 -282.808215) (xy 349.950323 -282.850509)
			(xy 349.970617 -282.896775) (xy 349.98302 -282.945751) (xy 349.987192 -282.9961) (xy 351.255272 -282.9961)
			(xy 351.259444 -282.945758) (xy 351.271846 -282.896789) (xy 351.292139 -282.850529) (xy 351.319771 -282.808241)
			(xy 351.353986 -282.771079) (xy 351.393852 -282.740055) (xy 351.438281 -282.716017) (xy 351.486061 -282.699621)
			(xy 351.535888 -282.691313) (xy 351.561146 -282.690824) (xy 352.5012 -282.690824) (xy 352.526458 -282.691282)
			(xy 352.576285 -282.699596) (xy 352.624064 -282.715999) (xy 352.668491 -282.740042) (xy 352.708355 -282.771069)
			(xy 352.742569 -282.808235) (xy 352.770198 -282.850525) (xy 352.79049 -282.896786) (xy 352.802891 -282.945757)
			(xy 352.807063 -282.9961) (xy 354.075301 -282.9961) (xy 354.079471 -282.945772) (xy 354.091867 -282.896816)
			(xy 354.112151 -282.850569) (xy 354.13977 -282.80829) (xy 354.17397 -282.771133) (xy 354.213819 -282.740111)
			(xy 354.258231 -282.716071) (xy 354.305993 -282.699668) (xy 354.355804 -282.691349) (xy 354.381054 -282.690824)
			(xy 355.321108 -282.690824) (xy 355.346366 -282.691282) (xy 355.396191 -282.699598) (xy 355.443969 -282.716001)
			(xy 355.488395 -282.740045) (xy 355.528258 -282.771072) (xy 355.562471 -282.808238) (xy 355.5901 -282.850528)
			(xy 355.610391 -282.896788) (xy 355.622792 -282.945757) (xy 355.626963 -282.9961) (xy 364.409001 -282.9961)
			(xy 364.413172 -282.945768) (xy 364.425569 -282.896809) (xy 364.445856 -282.850559) (xy 364.473479 -282.808278)
			(xy 364.507684 -282.77112) (xy 364.547539 -282.740099) (xy 364.591955 -282.71606) (xy 364.639723 -282.69966)
			(xy 364.689538 -282.691346) (xy 364.71479 -282.690824) (xy 365.654844 -282.690824) (xy 365.6801 -282.691285)
			(xy 365.729921 -282.699605) (xy 365.777694 -282.716012) (xy 365.822115 -282.740057) (xy 365.861972 -282.771085)
			(xy 365.89618 -282.80825) (xy 365.923805 -282.850538) (xy 365.944094 -282.896795) (xy 365.956492 -282.945761)
			(xy 365.960663 -282.9961) (xy 367.228901 -282.9961) (xy 367.233072 -282.945767) (xy 367.24547 -282.896808)
			(xy 367.265758 -282.850556) (xy 367.293381 -282.808275) (xy 367.327587 -282.771117) (xy 367.367443 -282.740096)
			(xy 367.411861 -282.716058) (xy 367.459629 -282.699659) (xy 367.509445 -282.691346) (xy 367.534698 -282.690824)
			(xy 368.474752 -282.690824) (xy 368.500015 -282.691249) (xy 368.549853 -282.699558) (xy 368.597643 -282.715958)
			(xy 368.642082 -282.740001) (xy 368.681956 -282.771031) (xy 368.716179 -282.808201) (xy 368.743817 -282.850498)
			(xy 368.764115 -282.896767) (xy 368.776519 -282.945747) (xy 368.780692 -282.9961) (xy 370.049101 -282.9961)
			(xy 370.053271 -282.945771) (xy 370.065667 -282.896815) (xy 370.085952 -282.850567) (xy 370.113571 -282.808288)
			(xy 370.147772 -282.771131) (xy 370.187623 -282.740109) (xy 370.232035 -282.716069) (xy 370.279798 -282.699667)
			(xy 370.329609 -282.691349) (xy 370.35486 -282.690824) (xy 371.294914 -282.690824) (xy 371.320171 -282.691283)
			(xy 371.369996 -282.699599) (xy 371.417773 -282.716003) (xy 371.462199 -282.740047) (xy 371.502061 -282.771074)
			(xy 371.536273 -282.80824) (xy 371.563901 -282.850529) (xy 371.584191 -282.896789) (xy 371.596592 -282.945758)
			(xy 371.600763 -282.9961) (xy 372.869001 -282.9961) (xy 372.873171 -282.94577) (xy 372.885568 -282.896814)
			(xy 372.905853 -282.850565) (xy 372.933473 -282.808285) (xy 372.967676 -282.771128) (xy 373.007527 -282.740106)
			(xy 373.05194 -282.716067) (xy 373.099705 -282.699665) (xy 373.149517 -282.691348) (xy 373.174768 -282.690824)
			(xy 374.114822 -282.690824) (xy 374.140079 -282.691283) (xy 374.189903 -282.699601) (xy 374.237679 -282.716005)
			(xy 374.282103 -282.740049) (xy 374.321964 -282.771077) (xy 374.356175 -282.808242) (xy 374.383802 -282.850531)
			(xy 374.404092 -282.896791) (xy 374.416492 -282.945759) (xy 374.420663 -282.9961) (xy 374.416492 -283.046441)
			(xy 374.404092 -283.095409) (xy 374.383802 -283.141669) (xy 374.356175 -283.183958) (xy 374.321964 -283.221123)
			(xy 374.282103 -283.252151) (xy 374.237679 -283.276195) (xy 374.189903 -283.292599) (xy 374.140079 -283.300917)
			(xy 374.114822 -283.30144) (xy 373.174768 -283.30144) (xy 373.149517 -283.300852) (xy 373.099705 -283.292535)
			(xy 373.05194 -283.276133) (xy 373.007527 -283.252094) (xy 372.967676 -283.221072) (xy 372.933473 -283.183915)
			(xy 372.905853 -283.141635) (xy 372.885568 -283.095386) (xy 372.873171 -283.04643) (xy 372.869001 -282.9961)
			(xy 371.600763 -282.9961) (xy 371.596592 -283.046442) (xy 371.584191 -283.095411) (xy 371.563901 -283.141671)
			(xy 371.536273 -283.18396) (xy 371.502061 -283.221126) (xy 371.462199 -283.252153) (xy 371.417773 -283.276197)
			(xy 371.369996 -283.292601) (xy 371.320171 -283.300917) (xy 371.294914 -283.30144) (xy 370.35486 -283.30144)
			(xy 370.329609 -283.300851) (xy 370.279798 -283.292533) (xy 370.232035 -283.276131) (xy 370.187623 -283.252091)
			(xy 370.147772 -283.221069) (xy 370.113571 -283.183912) (xy 370.085952 -283.141633) (xy 370.065667 -283.095385)
			(xy 370.053271 -283.046429) (xy 370.049101 -282.9961) (xy 368.780692 -282.9961) (xy 368.776519 -283.046453)
			(xy 368.764115 -283.095433) (xy 368.743817 -283.141702) (xy 368.716179 -283.183999) (xy 368.681956 -283.221169)
			(xy 368.642082 -283.252199) (xy 368.597643 -283.276242) (xy 368.549853 -283.292642) (xy 368.500015 -283.300951)
			(xy 368.474752 -283.30144) (xy 367.534698 -283.30144) (xy 367.509445 -283.300854) (xy 367.459629 -283.292541)
			(xy 367.411861 -283.276142) (xy 367.367443 -283.252104) (xy 367.327587 -283.221083) (xy 367.293381 -283.183925)
			(xy 367.265758 -283.141644) (xy 367.24547 -283.095392) (xy 367.233072 -283.046433) (xy 367.228901 -282.9961)
			(xy 365.960663 -282.9961) (xy 365.956492 -283.046439) (xy 365.944094 -283.095405) (xy 365.923805 -283.141662)
			(xy 365.89618 -283.18395) (xy 365.861972 -283.221115) (xy 365.822115 -283.252143) (xy 365.777694 -283.276188)
			(xy 365.729921 -283.292595) (xy 365.6801 -283.300915) (xy 365.654844 -283.30144) (xy 364.71479 -283.30144)
			(xy 364.689538 -283.300854) (xy 364.639723 -283.29254) (xy 364.591955 -283.27614) (xy 364.547539 -283.252101)
			(xy 364.507684 -283.22108) (xy 364.473479 -283.183922) (xy 364.445856 -283.141641) (xy 364.425569 -283.095391)
			(xy 364.413172 -283.046432) (xy 364.409001 -282.9961) (xy 355.626963 -282.9961) (xy 355.622792 -283.046443)
			(xy 355.610391 -283.095412) (xy 355.5901 -283.141672) (xy 355.562471 -283.183962) (xy 355.528258 -283.221128)
			(xy 355.488395 -283.252155) (xy 355.443969 -283.276199) (xy 355.396191 -283.292602) (xy 355.346366 -283.300918)
			(xy 355.321108 -283.30144) (xy 354.381054 -283.30144) (xy 354.355804 -283.300851) (xy 354.305993 -283.292532)
			(xy 354.258231 -283.276129) (xy 354.213819 -283.252089) (xy 354.17397 -283.221067) (xy 354.13977 -283.18391)
			(xy 354.112151 -283.141631) (xy 354.091867 -283.095384) (xy 354.079471 -283.046428) (xy 354.075301 -282.9961)
			(xy 352.807063 -282.9961) (xy 352.802891 -283.046443) (xy 352.79049 -283.095414) (xy 352.770198 -283.141675)
			(xy 352.742569 -283.183965) (xy 352.708355 -283.221131) (xy 352.668491 -283.252158) (xy 352.624064 -283.276201)
			(xy 352.576285 -283.292604) (xy 352.526458 -283.300918) (xy 352.5012 -283.30144) (xy 351.561146 -283.30144)
			(xy 351.535888 -283.300887) (xy 351.486061 -283.292579) (xy 351.438281 -283.276183) (xy 351.393852 -283.252145)
			(xy 351.353986 -283.221121) (xy 351.319771 -283.183959) (xy 351.292139 -283.141671) (xy 351.271846 -283.095411)
			(xy 351.259444 -283.046442) (xy 351.255272 -282.9961) (xy 349.987192 -282.9961) (xy 349.98302 -283.046449)
			(xy 349.970617 -283.095425) (xy 349.950323 -283.141691) (xy 349.92269 -283.183985) (xy 349.888472 -283.221155)
			(xy 349.848603 -283.252185) (xy 349.80417 -283.27623) (xy 349.756386 -283.292633) (xy 349.706553 -283.300948)
			(xy 349.681292 -283.30144) (xy 348.741238 -283.30144) (xy 348.715981 -283.300886) (xy 348.666155 -283.292578)
			(xy 348.618376 -283.27618) (xy 348.573948 -283.252142) (xy 348.534083 -283.221119) (xy 348.499869 -283.183956)
			(xy 348.472238 -283.141669) (xy 348.451945 -283.09541) (xy 348.439544 -283.046442) (xy 348.435372 -282.9961)
			(xy 347.166963 -282.9961) (xy 347.162792 -283.04644) (xy 347.150393 -283.095408) (xy 347.130103 -283.141666)
			(xy 347.102477 -283.183955) (xy 347.068267 -283.22112) (xy 347.028407 -283.252148) (xy 346.983984 -283.276192)
			(xy 346.936209 -283.292597) (xy 346.886386 -283.300916) (xy 346.86113 -283.30144) (xy 345.921076 -283.30144)
			(xy 345.895825 -283.300853) (xy 345.846011 -283.292537) (xy 345.798246 -283.276135) (xy 345.753831 -283.252096)
			(xy 345.713979 -283.221075) (xy 345.679775 -283.183918) (xy 345.652154 -283.141638) (xy 345.631868 -283.095388)
			(xy 345.619471 -283.04643) (xy 345.615301 -282.9961) (xy 345.311729 -282.9961) (xy 345.31173 -282.996132)
			(xy 345.311218 -283.022118) (xy 345.303084 -283.07345) (xy 345.28702 -283.122878) (xy 345.263423 -283.169184)
			(xy 345.232873 -283.21123) (xy 345.196122 -283.24798) (xy 345.154076 -283.278528) (xy 345.107768 -283.302124)
			(xy 345.05834 -283.318186) (xy 345.007008 -283.326319) (xy 344.981022 -283.32684) (xy 344.967052 -283.326586)
			(xy 344.952828 -283.325824) (xy 344.92819 -283.33954) (xy 344.782902 -283.58973) (xy 344.78341 -283.617924)
			(xy 344.79103 -283.630116) (xy 344.803062 -283.649973) (xy 344.822048 -283.692343) (xy 344.83492 -283.736952)
			(xy 344.841424 -283.782923) (xy 344.841829 -283.8061) (xy 356.425052 -283.8061) (xy 356.429226 -283.75573)
			(xy 356.441632 -283.706734) (xy 356.461934 -283.660448) (xy 356.489576 -283.618134) (xy 356.523805 -283.580947)
			(xy 356.563688 -283.5499) (xy 356.608136 -283.525841) (xy 356.655939 -283.509425) (xy 356.705791 -283.501101)
			(xy 356.731062 -283.500576) (xy 357.671116 -283.500576) (xy 357.696395 -283.501023) (xy 357.746262 -283.509347)
			(xy 357.794079 -283.525765) (xy 357.838542 -283.549829) (xy 357.878438 -283.580883) (xy 357.912679 -283.61808)
			(xy 357.94033 -283.660406) (xy 357.960638 -283.706705) (xy 357.973049 -283.755715) (xy 357.977224 -283.8061)
			(xy 362.058752 -283.8061) (xy 362.062926 -283.755728) (xy 362.075334 -283.70673) (xy 362.095637 -283.660442)
			(xy 362.123281 -283.618128) (xy 362.157513 -283.58094) (xy 362.197398 -283.549894) (xy 362.24185 -283.525835)
			(xy 362.289655 -283.509421) (xy 362.33951 -283.501099) (xy 362.364782 -283.500576) (xy 363.304836 -283.500576)
			(xy 363.330114 -283.501025) (xy 363.379978 -283.509351) (xy 363.427793 -283.525771) (xy 363.472253 -283.549836)
			(xy 363.512146 -283.58089) (xy 363.546384 -283.618087) (xy 363.574033 -283.660411) (xy 363.594339 -283.706709)
			(xy 363.606749 -283.755717) (xy 363.610924 -283.8061) (xy 363.606749 -283.856483) (xy 363.594339 -283.905491)
			(xy 363.574033 -283.951789) (xy 363.546384 -283.994113) (xy 363.512146 -284.03131) (xy 363.472253 -284.062364)
			(xy 363.427793 -284.086429) (xy 363.379978 -284.102849) (xy 363.330114 -284.111175) (xy 363.304836 -284.1117)
			(xy 362.364782 -284.1117) (xy 362.33951 -284.111101) (xy 362.289655 -284.102779) (xy 362.24185 -284.086365)
			(xy 362.197398 -284.062306) (xy 362.157513 -284.03126) (xy 362.123281 -283.994072) (xy 362.095637 -283.951758)
			(xy 362.075334 -283.90547) (xy 362.062926 -283.856472) (xy 362.058752 -283.8061) (xy 357.977224 -283.8061)
			(xy 357.973049 -283.856485) (xy 357.960638 -283.905495) (xy 357.94033 -283.951794) (xy 357.912679 -283.99412)
			(xy 357.878438 -284.031317) (xy 357.838542 -284.062371) (xy 357.794079 -284.086435) (xy 357.746262 -284.102853)
			(xy 357.696395 -284.111177) (xy 357.671116 -284.1117) (xy 356.731062 -284.1117) (xy 356.705791 -284.111099)
			(xy 356.655939 -284.102775) (xy 356.608136 -284.086359) (xy 356.563688 -284.0623) (xy 356.523805 -284.031253)
			(xy 356.489576 -283.994066) (xy 356.461934 -283.951752) (xy 356.441632 -283.905466) (xy 356.429226 -283.85647)
			(xy 356.425052 -283.8061) (xy 344.841829 -283.8061) (xy 344.84183 -283.806138) (xy 344.841438 -283.829686)
			(xy 344.834798 -283.876312) (xy 344.821602 -283.921521) (xy 344.802116 -283.964396) (xy 344.78976 -283.984446)
			(xy 344.781886 -283.996638) (xy 344.781378 -284.024832) (xy 344.925396 -284.27299) (xy 344.950034 -284.286452)
			(xy 344.964512 -284.285944) (xy 344.981022 -284.285436) (xy 345.007009 -284.285921) (xy 345.058342 -284.294055)
			(xy 345.107771 -284.31012) (xy 345.154078 -284.333719) (xy 345.196123 -284.364273) (xy 345.23287 -284.401027)
			(xy 345.263415 -284.443078) (xy 345.287006 -284.48939) (xy 345.30306 -284.538822) (xy 345.311184 -284.590157)
			(xy 345.311729 -284.6161) (xy 345.615313 -284.6161) (xy 345.619483 -284.565772) (xy 345.63188 -284.516816)
			(xy 345.652165 -284.470568) (xy 345.679785 -284.42829) (xy 345.713987 -284.391134) (xy 345.753838 -284.360114)
			(xy 345.798251 -284.336076) (xy 345.846014 -284.319675) (xy 345.895826 -284.311359) (xy 345.921076 -284.310836)
			(xy 346.86113 -284.310836) (xy 346.886387 -284.311272) (xy 346.936213 -284.31959) (xy 346.983989 -284.335996)
			(xy 347.028414 -284.360042) (xy 347.068275 -284.391071) (xy 347.102487 -284.428237) (xy 347.130114 -284.470528)
			(xy 347.150404 -284.516788) (xy 347.162804 -284.565758) (xy 347.166976 -284.6161) (xy 348.435384 -284.6161)
			(xy 348.439556 -284.56576) (xy 348.451957 -284.516794) (xy 348.472249 -284.470537) (xy 348.499878 -284.428251)
			(xy 348.534091 -284.39109) (xy 348.573955 -284.360068) (xy 348.618381 -284.336031) (xy 348.666158 -284.319634)
			(xy 348.715982 -284.311326) (xy 348.741238 -284.310836) (xy 349.681292 -284.310836) (xy 349.706554 -284.31124)
			(xy 349.756388 -284.319555) (xy 349.804175 -284.335959) (xy 349.848609 -284.360005) (xy 349.88848 -284.391036)
			(xy 349.922699 -284.428207) (xy 349.950333 -284.470504) (xy 349.970629 -284.516772) (xy 349.983032 -284.565749)
			(xy 349.987204 -284.6161) (xy 351.255284 -284.6161) (xy 351.259456 -284.56576) (xy 351.271857 -284.516793)
			(xy 351.29215 -284.470535) (xy 351.31978 -284.428249) (xy 351.353994 -284.391087) (xy 351.393859 -284.360065)
			(xy 351.438286 -284.336028) (xy 351.486064 -284.319632) (xy 351.535889 -284.311325) (xy 351.561146 -284.310836)
			(xy 352.5012 -284.310836) (xy 352.526459 -284.311269) (xy 352.576288 -284.319584) (xy 352.624069 -284.335987)
			(xy 352.668498 -284.360031) (xy 352.708364 -284.39106) (xy 352.742579 -284.428227) (xy 352.770209 -284.470519)
			(xy 352.790502 -284.516782) (xy 352.802904 -284.565755) (xy 352.807076 -284.6161) (xy 354.075313 -284.6161)
			(xy 354.079483 -284.565774) (xy 354.091878 -284.51682) (xy 354.112161 -284.470574) (xy 354.139779 -284.428297)
			(xy 354.173978 -284.391142) (xy 354.213826 -284.360121) (xy 354.258236 -284.336082) (xy 354.305996 -284.31968)
			(xy 354.355805 -284.311361) (xy 354.381054 -284.310836) (xy 355.321108 -284.310836) (xy 355.346367 -284.31127)
			(xy 355.396195 -284.319586) (xy 355.443974 -284.33599) (xy 355.488402 -284.360034) (xy 355.528267 -284.391063)
			(xy 355.562481 -284.42823) (xy 355.590111 -284.470522) (xy 355.610403 -284.516784) (xy 355.622804 -284.565755)
			(xy 355.626976 -284.6161) (xy 364.409013 -284.6161) (xy 364.413183 -284.56577) (xy 364.425581 -284.516813)
			(xy 364.445867 -284.470564) (xy 364.473488 -284.428285) (xy 364.507692 -284.391129) (xy 364.547545 -284.360109)
			(xy 364.59196 -284.336071) (xy 364.639726 -284.319672) (xy 364.689539 -284.311358) (xy 364.71479 -284.310836)
			(xy 365.654844 -284.310836) (xy 365.680101 -284.311273) (xy 365.729924 -284.319593) (xy 365.777699 -284.336)
			(xy 365.822121 -284.360047) (xy 365.861981 -284.391076) (xy 365.89619 -284.428242) (xy 365.923816 -284.470532)
			(xy 365.944105 -284.516791) (xy 365.956505 -284.565759) (xy 365.960676 -284.6161) (xy 367.228913 -284.6161)
			(xy 367.233084 -284.565769) (xy 367.245481 -284.516812) (xy 367.265768 -284.470562) (xy 367.293391 -284.428282)
			(xy 367.327595 -284.391126) (xy 367.367449 -284.360106) (xy 367.411865 -284.336069) (xy 367.459632 -284.31967)
			(xy 367.509446 -284.311358) (xy 367.534698 -284.310836) (xy 368.474752 -284.310836) (xy 368.500016 -284.311237)
			(xy 368.549856 -284.319547) (xy 368.597648 -284.335947) (xy 368.642088 -284.359991) (xy 368.681965 -284.391022)
			(xy 368.716189 -284.428194) (xy 368.743827 -284.470492) (xy 368.764126 -284.516764) (xy 368.776531 -284.565745)
			(xy 368.780704 -284.6161) (xy 370.049113 -284.6161) (xy 370.053283 -284.565773) (xy 370.065679 -284.516819)
			(xy 370.085962 -284.470573) (xy 370.113581 -284.428295) (xy 370.147781 -284.391139) (xy 370.187629 -284.360119)
			(xy 370.23204 -284.33608) (xy 370.279801 -284.319678) (xy 370.32961 -284.311361) (xy 370.35486 -284.310836)
			(xy 371.294914 -284.310836) (xy 371.320172 -284.31127) (xy 371.369999 -284.319587) (xy 371.417778 -284.335992)
			(xy 371.462205 -284.360036) (xy 371.502069 -284.391065) (xy 371.536282 -284.428232) (xy 371.563912 -284.470523)
			(xy 371.584203 -284.516785) (xy 371.596604 -284.565756) (xy 371.600776 -284.6161) (xy 372.869013 -284.6161)
			(xy 372.873183 -284.565772) (xy 372.885579 -284.516818) (xy 372.905864 -284.47057) (xy 372.933483 -284.428292)
			(xy 372.967684 -284.391137) (xy 373.007533 -284.360116) (xy 373.051945 -284.336078) (xy 373.099708 -284.319677)
			(xy 373.149518 -284.31136) (xy 373.174768 -284.310836) (xy 374.114822 -284.310836) (xy 374.14008 -284.311271)
			(xy 374.189906 -284.319589) (xy 374.237684 -284.335994) (xy 374.28211 -284.360039) (xy 374.321972 -284.391068)
			(xy 374.356184 -284.428235) (xy 374.383813 -284.470525) (xy 374.404104 -284.516787) (xy 374.416504 -284.565757)
			(xy 374.420676 -284.6161) (xy 374.416504 -284.666443) (xy 374.404104 -284.715413) (xy 374.383813 -284.761675)
			(xy 374.356184 -284.803965) (xy 374.321972 -284.841132) (xy 374.28211 -284.872161) (xy 374.237684 -284.896206)
			(xy 374.189906 -284.912611) (xy 374.14008 -284.920929) (xy 374.114822 -284.921452) (xy 373.174768 -284.921452)
			(xy 373.149518 -284.92084) (xy 373.099708 -284.912523) (xy 373.051945 -284.896122) (xy 373.007533 -284.872084)
			(xy 372.967684 -284.841063) (xy 372.933483 -284.803908) (xy 372.905864 -284.76163) (xy 372.885579 -284.715382)
			(xy 372.873183 -284.666428) (xy 372.869013 -284.6161) (xy 371.600776 -284.6161) (xy 371.596604 -284.666444)
			(xy 371.584203 -284.715415) (xy 371.563912 -284.761677) (xy 371.536282 -284.803968) (xy 371.502069 -284.841135)
			(xy 371.462205 -284.872164) (xy 371.417778 -284.896208) (xy 371.369999 -284.912613) (xy 371.320172 -284.92093)
			(xy 371.294914 -284.921452) (xy 370.35486 -284.921452) (xy 370.32961 -284.920839) (xy 370.279801 -284.912522)
			(xy 370.23204 -284.89612) (xy 370.187629 -284.872081) (xy 370.147781 -284.841061) (xy 370.113581 -284.803905)
			(xy 370.085962 -284.761627) (xy 370.065679 -284.715381) (xy 370.053283 -284.666427) (xy 370.049113 -284.6161)
			(xy 368.780704 -284.6161) (xy 368.776531 -284.666455) (xy 368.764126 -284.715436) (xy 368.743827 -284.761708)
			(xy 368.716189 -284.804006) (xy 368.681965 -284.841178) (xy 368.642088 -284.872209) (xy 368.597648 -284.896253)
			(xy 368.549856 -284.912653) (xy 368.500016 -284.920963) (xy 368.474752 -284.921452) (xy 367.534698 -284.921452)
			(xy 367.509446 -284.920842) (xy 367.459632 -284.91253) (xy 367.411865 -284.896131) (xy 367.367449 -284.872094)
			(xy 367.327595 -284.841074) (xy 367.293391 -284.803918) (xy 367.265768 -284.761638) (xy 367.245481 -284.715388)
			(xy 367.233084 -284.666431) (xy 367.228913 -284.6161) (xy 365.960676 -284.6161) (xy 365.956505 -284.666441)
			(xy 365.944105 -284.715409) (xy 365.923816 -284.761668) (xy 365.89619 -284.803958) (xy 365.861981 -284.841124)
			(xy 365.822121 -284.872153) (xy 365.777699 -284.8962) (xy 365.729924 -284.912607) (xy 365.680101 -284.920927)
			(xy 365.654844 -284.921452) (xy 364.71479 -284.921452) (xy 364.689539 -284.920842) (xy 364.639726 -284.912528)
			(xy 364.59196 -284.896129) (xy 364.547545 -284.872091) (xy 364.507692 -284.841071) (xy 364.473489 -284.803915)
			(xy 364.445867 -284.761636) (xy 364.425581 -284.715387) (xy 364.413183 -284.66643) (xy 364.409013 -284.6161)
			(xy 355.626976 -284.6161) (xy 355.622804 -284.666445) (xy 355.610403 -284.715416) (xy 355.590111 -284.761678)
			(xy 355.562481 -284.80397) (xy 355.528267 -284.841137) (xy 355.488402 -284.872166) (xy 355.443974 -284.89621)
			(xy 355.396195 -284.912614) (xy 355.346367 -284.92093) (xy 355.321108 -284.921452) (xy 354.381054 -284.921452)
			(xy 354.355805 -284.920839) (xy 354.305996 -284.91252) (xy 354.258236 -284.896118) (xy 354.213826 -284.872079)
			(xy 354.173978 -284.841058) (xy 354.139779 -284.803903) (xy 354.112161 -284.761626) (xy 354.091878 -284.71538)
			(xy 354.079483 -284.666426) (xy 354.075313 -284.6161) (xy 352.807076 -284.6161) (xy 352.802904 -284.666445)
			(xy 352.790502 -284.715418) (xy 352.770209 -284.761681) (xy 352.742579 -284.803973) (xy 352.708364 -284.84114)
			(xy 352.668498 -284.872169) (xy 352.624069 -284.896213) (xy 352.576288 -284.912616) (xy 352.526459 -284.920931)
			(xy 352.5012 -284.921452) (xy 351.561146 -284.921452) (xy 351.535889 -284.920875) (xy 351.486064 -284.912568)
			(xy 351.438286 -284.896172) (xy 351.393859 -284.872135) (xy 351.353994 -284.841113) (xy 351.31978 -284.803951)
			(xy 351.29215 -284.761665) (xy 351.271857 -284.715407) (xy 351.259456 -284.66644) (xy 351.255284 -284.6161)
			(xy 349.987204 -284.6161) (xy 349.983032 -284.666451) (xy 349.970629 -284.715428) (xy 349.950333 -284.761696)
			(xy 349.922699 -284.803993) (xy 349.88848 -284.841164) (xy 349.848609 -284.872195) (xy 349.804175 -284.896241)
			(xy 349.756388 -284.912645) (xy 349.706554 -284.92096) (xy 349.681292 -284.921452) (xy 348.741238 -284.921452)
			(xy 348.715982 -284.920874) (xy 348.666158 -284.912566) (xy 348.618381 -284.896169) (xy 348.573955 -284.872132)
			(xy 348.534091 -284.84111) (xy 348.499878 -284.803949) (xy 348.472249 -284.761663) (xy 348.451957 -284.715406)
			(xy 348.439556 -284.66644) (xy 348.435384 -284.6161) (xy 347.166976 -284.6161) (xy 347.162804 -284.666442)
			(xy 347.150404 -284.715412) (xy 347.130114 -284.761672) (xy 347.102487 -284.803963) (xy 347.068275 -284.841129)
			(xy 347.028414 -284.872158) (xy 346.983989 -284.896204) (xy 346.936213 -284.91261) (xy 346.886387 -284.920928)
			(xy 346.86113 -284.921452) (xy 345.921076 -284.921452) (xy 345.895826 -284.920841) (xy 345.846014 -284.912525)
			(xy 345.798251 -284.896124) (xy 345.753838 -284.872086) (xy 345.713987 -284.841066) (xy 345.679785 -284.80391)
			(xy 345.652165 -284.761632) (xy 345.63188 -284.715384) (xy 345.619483 -284.666428) (xy 345.615313 -284.6161)
			(xy 345.311729 -284.6161) (xy 345.31173 -284.616144) (xy 345.311338 -284.639692) (xy 345.304697 -284.686317)
			(xy 345.2915 -284.731526) (xy 345.272014 -284.774401) (xy 345.25966 -284.794452) (xy 345.251786 -284.806644)
			(xy 345.251278 -284.834838) (xy 345.395296 -285.08325) (xy 345.419934 -285.096712) (xy 345.434412 -285.09595)
			(xy 345.451176 -285.095442) (xy 345.477163 -285.095923) (xy 345.528496 -285.10405) (xy 345.577927 -285.120108)
			(xy 345.624236 -285.143701) (xy 345.666285 -285.174248) (xy 345.703036 -285.210997) (xy 345.733587 -285.253043)
			(xy 345.757183 -285.299351) (xy 345.773244 -285.34878) (xy 345.781375 -285.400113) (xy 345.781375 -285.4261)
			(xy 356.425064 -285.4261) (xy 356.429238 -285.375732) (xy 356.441644 -285.326738) (xy 356.461944 -285.280454)
			(xy 356.489585 -285.238142) (xy 356.523813 -285.200956) (xy 356.563694 -285.16991) (xy 356.608141 -285.145852)
			(xy 356.655942 -285.129437) (xy 356.705792 -285.121113) (xy 356.731062 -285.120588) (xy 357.671116 -285.120588)
			(xy 357.696396 -285.121011) (xy 357.746265 -285.129335) (xy 357.794084 -285.145754) (xy 357.838549 -285.169819)
			(xy 357.878446 -285.200875) (xy 357.912688 -285.238073) (xy 357.940341 -285.2804) (xy 357.960649 -285.326701)
			(xy 357.97306 -285.375713) (xy 357.977236 -285.4261) (xy 362.058764 -285.4261) (xy 362.062938 -285.37573)
			(xy 362.075345 -285.326734) (xy 362.095647 -285.280448) (xy 362.12329 -285.238135) (xy 362.157521 -285.200949)
			(xy 362.197405 -285.169904) (xy 362.241855 -285.145846) (xy 362.289658 -285.129433) (xy 362.339511 -285.121111)
			(xy 362.364782 -285.120588) (xy 363.304836 -285.120588) (xy 363.330115 -285.121013) (xy 363.379981 -285.12934)
			(xy 363.427798 -285.14576) (xy 363.472259 -285.169826) (xy 363.512154 -285.200882) (xy 363.546393 -285.23808)
			(xy 363.574044 -285.280406) (xy 363.594351 -285.326705) (xy 363.606761 -285.375716) (xy 363.610936 -285.4261)
			(xy 363.606761 -285.476485) (xy 363.594351 -285.525495) (xy 363.574044 -285.571794) (xy 363.546393 -285.61412)
			(xy 363.512154 -285.651318) (xy 363.472259 -285.682374) (xy 363.427798 -285.70644) (xy 363.379981 -285.72286)
			(xy 363.330115 -285.731187) (xy 363.304836 -285.731712) (xy 362.364782 -285.731712) (xy 362.339511 -285.731089)
			(xy 362.289658 -285.722767) (xy 362.241855 -285.706354) (xy 362.197405 -285.682296) (xy 362.157521 -285.651251)
			(xy 362.12329 -285.614065) (xy 362.095647 -285.571752) (xy 362.075345 -285.525466) (xy 362.062938 -285.47647)
			(xy 362.058764 -285.4261) (xy 357.977236 -285.4261) (xy 357.97306 -285.476487) (xy 357.960649 -285.525499)
			(xy 357.940341 -285.5718) (xy 357.912688 -285.614127) (xy 357.878446 -285.651325) (xy 357.838549 -285.682381)
			(xy 357.794084 -285.706446) (xy 357.746265 -285.722865) (xy 357.696396 -285.731189) (xy 357.671116 -285.731712)
			(xy 356.731062 -285.731712) (xy 356.705792 -285.731087) (xy 356.655942 -285.722763) (xy 356.608141 -285.706348)
			(xy 356.563694 -285.68229) (xy 356.523813 -285.651244) (xy 356.489585 -285.614058) (xy 356.461944 -285.571746)
			(xy 356.441644 -285.525462) (xy 356.429238 -285.476468) (xy 356.425064 -285.4261) (xy 345.781375 -285.4261)
			(xy 345.781375 -285.452087) (xy 345.773244 -285.50342) (xy 345.757183 -285.552849) (xy 345.733587 -285.599157)
			(xy 345.703036 -285.641203) (xy 345.666285 -285.677952) (xy 345.624236 -285.708499) (xy 345.577927 -285.732092)
			(xy 345.528496 -285.74815) (xy 345.477163 -285.756277) (xy 345.451176 -285.756858) (xy 345.436952 -285.756604)
			(xy 345.422728 -285.755842) (xy 345.397836 -285.769558) (xy 345.252802 -286.019748) (xy 345.25331 -286.047942)
			(xy 345.26093 -286.05988) (xy 345.272968 -286.07977) (xy 345.291962 -286.122204) (xy 345.304839 -286.166876)
			(xy 345.311344 -286.21291) (xy 345.31173 -286.236156) (xy 345.311729 -286.2362) (xy 345.615733 -286.2362)
			(xy 345.619898 -286.185941) (xy 345.632277 -286.137052) (xy 345.652535 -286.090868) (xy 345.680117 -286.048648)
			(xy 345.714272 -286.011543) (xy 345.754068 -285.980566) (xy 345.798419 -285.956561) (xy 345.846117 -285.940183)
			(xy 345.89586 -285.931878) (xy 345.921076 -285.931356) (xy 346.86113 -285.931356) (xy 346.886338 -285.931967)
			(xy 346.936066 -285.94027) (xy 346.983749 -285.956643) (xy 347.028087 -285.980642) (xy 347.067871 -286.01161)
			(xy 347.102015 -286.048704) (xy 347.129589 -286.090912) (xy 347.149839 -286.137082) (xy 347.162215 -286.185956)
			(xy 347.166378 -286.2362) (xy 348.435296 -286.2362) (xy 348.439469 -286.185846) (xy 348.451873 -286.136866)
			(xy 348.472171 -286.090595) (xy 348.499809 -286.048297) (xy 348.534032 -286.011126) (xy 348.573906 -285.980094)
			(xy 348.618345 -285.95605) (xy 348.666136 -285.939649) (xy 348.715975 -285.931338) (xy 348.741238 -285.930848)
			(xy 349.681292 -285.930848) (xy 349.706547 -285.931428) (xy 349.756367 -285.93974) (xy 349.804139 -285.956139)
			(xy 349.848561 -285.980178) (xy 349.88842 -286.011201) (xy 349.92263 -286.048361) (xy 349.950256 -286.090645)
			(xy 349.970545 -286.1369) (xy 349.982945 -286.185864) (xy 349.987116 -286.2362) (xy 351.255196 -286.2362)
			(xy 351.259369 -286.185845) (xy 351.271774 -286.136864) (xy 351.292072 -286.090593) (xy 351.319711 -286.048295)
			(xy 351.353935 -286.011123) (xy 351.393811 -285.980092) (xy 351.438251 -285.956048) (xy 351.486043 -285.939647)
			(xy 351.535882 -285.931337) (xy 351.561146 -285.930848) (xy 352.5012 -285.930848) (xy 352.526452 -285.931457)
			(xy 352.576266 -285.93977) (xy 352.624033 -285.956168) (xy 352.66845 -285.980205) (xy 352.708304 -286.011225)
			(xy 352.742509 -286.048382) (xy 352.770132 -286.090661) (xy 352.790419 -286.136911) (xy 352.802816 -286.185869)
			(xy 352.806987 -286.2362) (xy 354.075224 -286.2362) (xy 354.079395 -286.185859) (xy 354.091795 -286.136892)
			(xy 354.112084 -286.090632) (xy 354.139709 -286.048343) (xy 354.173918 -286.011177) (xy 354.213778 -285.980147)
			(xy 354.2582 -285.956101) (xy 354.305974 -285.939694) (xy 354.355797 -285.931373) (xy 354.381054 -285.930848)
			(xy 355.321108 -285.930848) (xy 355.346359 -285.931458) (xy 355.396173 -285.939772) (xy 355.443939 -285.956171)
			(xy 355.488354 -285.980208) (xy 355.528207 -286.011228) (xy 355.562411 -286.048384) (xy 355.590033 -286.090664)
			(xy 355.610319 -286.136913) (xy 355.622717 -286.18587) (xy 355.626887 -286.2362) (xy 364.408924 -286.2362)
			(xy 364.413096 -286.185856) (xy 364.425497 -286.136884) (xy 364.445789 -286.090622) (xy 364.473419 -286.048331)
			(xy 364.507632 -286.011164) (xy 364.547497 -285.980135) (xy 364.591924 -285.95609) (xy 364.639704 -285.939686)
			(xy 364.689532 -285.93137) (xy 364.71479 -285.930848) (xy 365.654844 -285.930848) (xy 365.680093 -285.931461)
			(xy 365.729902 -285.939779) (xy 365.777663 -285.956181) (xy 365.822073 -285.980221) (xy 365.861921 -286.011241)
			(xy 365.89612 -286.048396) (xy 365.923738 -286.090674) (xy 365.944022 -286.13692) (xy 365.956417 -286.185874)
			(xy 365.960587 -286.2362) (xy 367.228824 -286.2362) (xy 367.232996 -286.185855) (xy 367.245398 -286.136883)
			(xy 367.26569 -286.09062) (xy 367.293321 -286.048328) (xy 367.327535 -286.011161) (xy 367.367401 -285.980132)
			(xy 367.41183 -285.956088) (xy 367.45961 -285.939685) (xy 367.509439 -285.931369) (xy 367.534698 -285.930848)
			(xy 368.474752 -285.930848) (xy 368.500009 -285.931425) (xy 368.549834 -285.939732) (xy 368.597612 -285.956128)
			(xy 368.64204 -285.980164) (xy 368.681905 -286.011187) (xy 368.716119 -286.048348) (xy 368.74375 -286.090634)
			(xy 368.764043 -286.136892) (xy 368.776444 -286.185859) (xy 368.780616 -286.2362) (xy 370.049024 -286.2362)
			(xy 370.053196 -286.185859) (xy 370.065595 -286.13689) (xy 370.085885 -286.09063) (xy 370.113511 -286.048341)
			(xy 370.147721 -286.011174) (xy 370.187581 -285.980145) (xy 370.232004 -285.956099) (xy 370.279779 -285.939692)
			(xy 370.329603 -285.931372) (xy 370.35486 -285.930848) (xy 371.294914 -285.930848) (xy 371.320165 -285.931459)
			(xy 371.369978 -285.939773) (xy 371.417743 -285.956173) (xy 371.462157 -285.98021) (xy 371.502009 -286.01123)
			(xy 371.536213 -286.048386) (xy 371.563834 -286.090665) (xy 371.58412 -286.136914) (xy 371.596517 -286.185871)
			(xy 371.600687 -286.2362) (xy 371.596517 -286.286529) (xy 371.58412 -286.335486) (xy 371.563834 -286.381735)
			(xy 371.536213 -286.424014) (xy 371.502009 -286.46117) (xy 371.462157 -286.49219) (xy 371.417743 -286.516227)
			(xy 371.369978 -286.532627) (xy 371.320165 -286.540941) (xy 371.294914 -286.541464) (xy 370.35486 -286.541464)
			(xy 370.329603 -286.541028) (xy 370.279779 -286.532708) (xy 370.232004 -286.516301) (xy 370.187581 -286.492255)
			(xy 370.147721 -286.461226) (xy 370.113511 -286.424059) (xy 370.085884 -286.38177) (xy 370.065595 -286.33551)
			(xy 370.053196 -286.286541) (xy 370.049024 -286.2362) (xy 368.780616 -286.2362) (xy 368.776444 -286.286541)
			(xy 368.764043 -286.335508) (xy 368.74375 -286.381766) (xy 368.716119 -286.424052) (xy 368.681905 -286.461213)
			(xy 368.64204 -286.492236) (xy 368.597612 -286.516272) (xy 368.549834 -286.532668) (xy 368.500009 -286.540975)
			(xy 368.474752 -286.541464) (xy 367.534698 -286.541464) (xy 367.509439 -286.541031) (xy 367.45961 -286.532715)
			(xy 367.41183 -286.516312) (xy 367.367401 -286.492268) (xy 367.327535 -286.461239) (xy 367.293321 -286.424072)
			(xy 367.26569 -286.38178) (xy 367.245398 -286.335517) (xy 367.232996 -286.286545) (xy 367.228824 -286.2362)
			(xy 365.960587 -286.2362) (xy 365.956417 -286.286526) (xy 365.944022 -286.33548) (xy 365.923738 -286.381726)
			(xy 365.89612 -286.424004) (xy 365.861921 -286.461159) (xy 365.822073 -286.492179) (xy 365.777663 -286.516219)
			(xy 365.729902 -286.532621) (xy 365.680093 -286.540939) (xy 365.654844 -286.541464) (xy 364.71479 -286.541464)
			(xy 364.689532 -286.54103) (xy 364.639704 -286.532714) (xy 364.591924 -286.51631) (xy 364.547497 -286.492265)
			(xy 364.507632 -286.461236) (xy 364.473419 -286.424069) (xy 364.445789 -286.381778) (xy 364.425497 -286.335516)
			(xy 364.413096 -286.286544) (xy 364.408924 -286.2362) (xy 355.626887 -286.2362) (xy 355.622717 -286.28653)
			(xy 355.610319 -286.335487) (xy 355.590033 -286.381736) (xy 355.562411 -286.424016) (xy 355.528207 -286.461172)
			(xy 355.488354 -286.492192) (xy 355.443939 -286.516229) (xy 355.396173 -286.532628) (xy 355.346359 -286.540942)
			(xy 355.321108 -286.541464) (xy 354.381054 -286.541464) (xy 354.355797 -286.541027) (xy 354.305974 -286.532706)
			(xy 354.2582 -286.516299) (xy 354.213778 -286.492253) (xy 354.173918 -286.461223) (xy 354.139709 -286.424057)
			(xy 354.112084 -286.381768) (xy 354.091795 -286.335508) (xy 354.079395 -286.286541) (xy 354.075224 -286.2362)
			(xy 352.806987 -286.2362) (xy 352.802816 -286.286531) (xy 352.790419 -286.335489) (xy 352.770132 -286.381739)
			(xy 352.742509 -286.424018) (xy 352.708304 -286.461175) (xy 352.66845 -286.492195) (xy 352.624033 -286.516232)
			(xy 352.576266 -286.53263) (xy 352.526452 -286.540943) (xy 352.5012 -286.541464) (xy 351.561146 -286.541464)
			(xy 351.535882 -286.541063) (xy 351.486043 -286.532753) (xy 351.438251 -286.516352) (xy 351.393811 -286.492309)
			(xy 351.353935 -286.461277) (xy 351.319711 -286.424105) (xy 351.292072 -286.381807) (xy 351.271774 -286.335536)
			(xy 351.259369 -286.286555) (xy 351.255196 -286.2362) (xy 349.987116 -286.2362) (xy 349.982945 -286.286536)
			(xy 349.970545 -286.3355) (xy 349.950256 -286.381755) (xy 349.92263 -286.424039) (xy 349.88842 -286.461199)
			(xy 349.848561 -286.492222) (xy 349.804139 -286.516261) (xy 349.756367 -286.53266) (xy 349.706547 -286.540972)
			(xy 349.681292 -286.541464) (xy 348.741238 -286.541464) (xy 348.715975 -286.541062) (xy 348.666136 -286.532751)
			(xy 348.618345 -286.51635) (xy 348.573907 -286.492306) (xy 348.534032 -286.461274) (xy 348.499809 -286.424103)
			(xy 348.472171 -286.381805) (xy 348.451873 -286.335534) (xy 348.439469 -286.286554) (xy 348.435296 -286.2362)
			(xy 347.166378 -286.2362) (xy 347.162215 -286.286444) (xy 347.149839 -286.335318) (xy 347.129589 -286.381488)
			(xy 347.102015 -286.423696) (xy 347.067871 -286.46079) (xy 347.028087 -286.491758) (xy 346.983749 -286.515757)
			(xy 346.936066 -286.53213) (xy 346.886338 -286.540433) (xy 346.86113 -286.540956) (xy 345.921076 -286.540956)
			(xy 345.89586 -286.540522) (xy 345.846117 -286.532217) (xy 345.798419 -286.515839) (xy 345.754068 -286.491834)
			(xy 345.714272 -286.460857) (xy 345.680117 -286.423752) (xy 345.652535 -286.381532) (xy 345.632277 -286.335348)
			(xy 345.619898 -286.286459) (xy 345.615733 -286.2362) (xy 345.311729 -286.2362) (xy 345.31125 -286.262148)
			(xy 345.303125 -286.313493) (xy 345.287066 -286.362935) (xy 345.263471 -286.409256) (xy 345.23292 -286.451315)
			(xy 345.196166 -286.488077) (xy 345.154112 -286.518637) (xy 345.107796 -286.542241) (xy 345.058358 -286.558309)
			(xy 345.007014 -286.566445) (xy 344.981022 -286.566864) (xy 344.967052 -286.56661) (xy 344.952828 -286.565848)
			(xy 344.92819 -286.579564) (xy 344.783156 -286.8295) (xy 344.783664 -286.857948) (xy 344.79103 -286.869886)
			(xy 344.803063 -286.889743) (xy 344.822054 -286.932112) (xy 344.83493 -286.976721) (xy 344.841438 -287.022693)
			(xy 344.84183 -287.0459) (xy 356.425785 -287.0459) (xy 356.429949 -286.995651) (xy 356.442326 -286.946772)
			(xy 356.462578 -286.900597) (xy 356.490154 -286.858385) (xy 356.524301 -286.821286) (xy 356.564089 -286.790314)
			(xy 356.608431 -286.766312) (xy 356.656119 -286.749936) (xy 356.705851 -286.741631) (xy 356.731062 -286.741108)
			(xy 357.671116 -286.741108) (xy 357.696329 -286.741614) (xy 357.746067 -286.749916) (xy 357.793761 -286.766291)
			(xy 357.838108 -286.790293) (xy 357.877901 -286.821267) (xy 357.912053 -286.858367) (xy 357.939633 -286.900583)
			(xy 357.959888 -286.946763) (xy 357.972266 -286.995646) (xy 357.976431 -287.0459) (xy 357.972266 -287.096154)
			(xy 357.959888 -287.145037) (xy 357.939633 -287.191217) (xy 357.912053 -287.233433) (xy 357.877901 -287.270533)
			(xy 357.838108 -287.301507) (xy 357.793761 -287.325509) (xy 357.746067 -287.341884) (xy 357.696329 -287.350186)
			(xy 357.671116 -287.350708) (xy 356.731062 -287.350708) (xy 356.705851 -287.350169) (xy 356.656119 -287.341864)
			(xy 356.608431 -287.325488) (xy 356.564089 -287.301486) (xy 356.524301 -287.270514) (xy 356.490154 -287.233415)
			(xy 356.462578 -287.191203) (xy 356.442326 -287.145028) (xy 356.429949 -287.096149) (xy 356.425785 -287.0459)
			(xy 344.84183 -287.0459) (xy 344.84183 -287.045908) (xy 344.841392 -287.069462) (xy 344.834668 -287.116089)
			(xy 344.8214 -287.161291) (xy 344.801856 -287.204154) (xy 344.789506 -287.224216) (xy 344.781886 -287.236408)
			(xy 344.781124 -287.264602) (xy 344.925396 -287.513014) (xy 344.950034 -287.526476) (xy 344.964512 -287.525968)
			(xy 344.981022 -287.52546) (xy 345.007009 -287.525971) (xy 345.058343 -287.534104) (xy 345.107772 -287.550167)
			(xy 345.154081 -287.573763) (xy 345.196129 -287.604313) (xy 345.232881 -287.641063) (xy 345.263431 -287.68311)
			(xy 345.287029 -287.729418) (xy 345.303093 -287.778848) (xy 345.311228 -287.830181) (xy 345.31173 -287.856168)
			(xy 345.311729 -287.8562) (xy 345.615745 -287.8562) (xy 345.61991 -287.805943) (xy 345.632289 -287.757056)
			(xy 345.652545 -287.710874) (xy 345.680126 -287.668655) (xy 345.71428 -287.631552) (xy 345.754074 -287.600576)
			(xy 345.798424 -287.576572) (xy 345.84612 -287.560194) (xy 345.895861 -287.55189) (xy 345.921076 -287.551368)
			(xy 346.86113 -287.551368) (xy 346.886339 -287.551955) (xy 346.936069 -287.560258) (xy 346.983754 -287.576632)
			(xy 347.028094 -287.600631) (xy 347.067879 -287.631601) (xy 347.102025 -287.668697) (xy 347.129599 -287.710906)
			(xy 347.149851 -287.757078) (xy 347.162227 -287.805954) (xy 347.166391 -287.8562) (xy 348.435817 -287.8562)
			(xy 348.439983 -287.805932) (xy 348.452366 -287.757035) (xy 348.472629 -287.710843) (xy 348.50022 -287.668617)
			(xy 348.534384 -287.631509) (xy 348.574191 -287.60053) (xy 348.618555 -287.576527) (xy 348.666264 -287.560154)
			(xy 348.716018 -287.551857) (xy 348.741238 -287.551368) (xy 349.681292 -287.551368) (xy 349.706505 -287.551923)
			(xy 349.756245 -287.560222) (xy 349.80394 -287.576595) (xy 349.848289 -287.600594) (xy 349.888084 -287.631567)
			(xy 349.922238 -287.668667) (xy 349.949819 -287.710882) (xy 349.970075 -287.757061) (xy 349.982455 -287.805945)
			(xy 349.986619 -287.8562) (xy 351.255717 -287.8562) (xy 351.259883 -287.805931) (xy 351.272267 -287.757033)
			(xy 351.292531 -287.710841) (xy 351.320122 -287.668615) (xy 351.354288 -287.631506) (xy 351.394096 -287.600528)
			(xy 351.43846 -287.576525) (xy 351.486171 -287.560152) (xy 351.535925 -287.551856) (xy 351.561146 -287.551368)
			(xy 352.5012 -287.551368) (xy 352.526411 -287.551952) (xy 352.576144 -287.560251) (xy 352.623834 -287.576623)
			(xy 352.668178 -287.600621) (xy 352.707968 -287.63159) (xy 352.742117 -287.668687) (xy 352.769695 -287.710898)
			(xy 352.789949 -287.757072) (xy 352.802327 -287.805951) (xy 352.806491 -287.8562) (xy 354.075745 -287.8562)
			(xy 354.079909 -287.805945) (xy 354.092287 -287.757061) (xy 354.112542 -287.71088) (xy 354.14012 -287.668663)
			(xy 354.174271 -287.63156) (xy 354.214063 -287.600583) (xy 354.258409 -287.576578) (xy 354.306102 -287.560199)
			(xy 354.355841 -287.551892) (xy 354.381054 -287.551368) (xy 355.321108 -287.551368) (xy 355.346318 -287.551953)
			(xy 355.396051 -287.560253) (xy 355.443739 -287.576625) (xy 355.488082 -287.600624) (xy 355.527871 -287.631593)
			(xy 355.562019 -287.668689) (xy 355.589596 -287.7109) (xy 355.60985 -287.757074) (xy 355.622227 -287.805952)
			(xy 355.626391 -287.8562) (xy 355.622227 -287.906448) (xy 355.60985 -287.955326) (xy 355.589596 -288.0015)
			(xy 355.562019 -288.043711) (xy 355.527871 -288.080807) (xy 355.488082 -288.111776) (xy 355.443739 -288.135775)
			(xy 355.396051 -288.152147) (xy 355.346318 -288.160447) (xy 355.321108 -288.160968) (xy 354.381054 -288.160968)
			(xy 354.355841 -288.160508) (xy 354.306102 -288.152201) (xy 354.258409 -288.135822) (xy 354.214063 -288.111817)
			(xy 354.174271 -288.08084) (xy 354.14012 -288.043737) (xy 354.112542 -288.00152) (xy 354.092287 -287.955339)
			(xy 354.079909 -287.906455) (xy 354.075745 -287.8562) (xy 352.806491 -287.8562) (xy 352.802327 -287.906449)
			(xy 352.789949 -287.955328) (xy 352.769695 -288.001502) (xy 352.742117 -288.043713) (xy 352.707968 -288.08081)
			(xy 352.668178 -288.111779) (xy 352.623834 -288.135777) (xy 352.576144 -288.152149) (xy 352.526411 -288.160448)
			(xy 352.5012 -288.160968) (xy 351.561146 -288.160968) (xy 351.535925 -288.160544) (xy 351.486171 -288.152248)
			(xy 351.43846 -288.135875) (xy 351.394096 -288.111872) (xy 351.354288 -288.080894) (xy 351.320122 -288.043785)
			(xy 351.292531 -288.001559) (xy 351.272267 -287.955367) (xy 351.259883 -287.906469) (xy 351.255717 -287.8562)
			(xy 349.986619 -287.8562) (xy 349.982455 -287.906455) (xy 349.970075 -287.955339) (xy 349.949819 -288.001518)
			(xy 349.922238 -288.043733) (xy 349.888084 -288.080833) (xy 349.848289 -288.111806) (xy 349.80394 -288.135805)
			(xy 349.756245 -288.152178) (xy 349.706505 -288.160477) (xy 349.681292 -288.160968) (xy 348.741238 -288.160968)
			(xy 348.716018 -288.160543) (xy 348.666264 -288.152246) (xy 348.618555 -288.135873) (xy 348.574191 -288.11187)
			(xy 348.534384 -288.080891) (xy 348.50022 -288.043783) (xy 348.472629 -288.001557) (xy 348.452366 -287.955365)
			(xy 348.439983 -287.906468) (xy 348.435817 -287.8562) (xy 347.166391 -287.8562) (xy 347.162227 -287.906446)
			(xy 347.149851 -287.955322) (xy 347.1296 -288.001494) (xy 347.102025 -288.043703) (xy 347.067879 -288.080799)
			(xy 347.028094 -288.111769) (xy 346.983754 -288.135768) (xy 346.936069 -288.152142) (xy 346.886339 -288.160445)
			(xy 346.86113 -288.160968) (xy 345.921076 -288.160968) (xy 345.895861 -288.16051) (xy 345.84612 -288.152206)
			(xy 345.798424 -288.135828) (xy 345.754074 -288.111824) (xy 345.71428 -288.080848) (xy 345.680126 -288.043745)
			(xy 345.652545 -288.001526) (xy 345.632289 -287.955344) (xy 345.61991 -287.906457) (xy 345.615745 -287.8562)
			(xy 345.311729 -287.8562) (xy 345.311336 -287.879716) (xy 345.304692 -287.926339) (xy 345.291492 -287.971546)
			(xy 345.272004 -288.014419) (xy 345.25966 -288.034476) (xy 345.251786 -288.046668) (xy 345.251278 -288.074862)
			(xy 345.395042 -288.32302) (xy 345.419934 -288.336482) (xy 345.434412 -288.33572) (xy 345.451176 -288.335212)
			(xy 345.477165 -288.335693) (xy 345.528503 -288.343821) (xy 345.577938 -288.35988) (xy 345.624252 -288.383475)
			(xy 345.666304 -288.414025) (xy 345.703059 -288.450778) (xy 345.733612 -288.492828) (xy 345.757211 -288.53914)
			(xy 345.773273 -288.588573) (xy 345.781405 -288.639911) (xy 345.781405 -288.6659) (xy 356.425797 -288.6659)
			(xy 356.429961 -288.615653) (xy 356.442337 -288.566776) (xy 356.462589 -288.520603) (xy 356.490164 -288.478392)
			(xy 356.52431 -288.441295) (xy 356.564095 -288.410324) (xy 356.608436 -288.386323) (xy 356.656122 -288.369948)
			(xy 356.705852 -288.361643) (xy 356.731062 -288.36112) (xy 357.671116 -288.36112) (xy 357.69633 -288.361602)
			(xy 357.74607 -288.369904) (xy 357.793766 -288.38628) (xy 357.838115 -288.410283) (xy 357.877909 -288.441258)
			(xy 357.912062 -288.47836) (xy 357.939643 -288.520577) (xy 357.959899 -288.566759) (xy 357.972278 -288.615644)
			(xy 357.976443 -288.6659) (xy 357.972278 -288.716156) (xy 357.959899 -288.765041) (xy 357.939643 -288.811223)
			(xy 357.912062 -288.85344) (xy 357.877909 -288.890542) (xy 357.838115 -288.921517) (xy 357.793766 -288.94552)
			(xy 357.74607 -288.961896) (xy 357.69633 -288.970198) (xy 357.671116 -288.97072) (xy 356.731062 -288.97072)
			(xy 356.705852 -288.970157) (xy 356.656122 -288.961852) (xy 356.608436 -288.945477) (xy 356.564095 -288.921476)
			(xy 356.52431 -288.890505) (xy 356.490164 -288.853408) (xy 356.462589 -288.811197) (xy 356.442337 -288.765024)
			(xy 356.429961 -288.716147) (xy 356.425797 -288.6659) (xy 345.781405 -288.6659) (xy 345.781405 -288.691889)
			(xy 345.773273 -288.743227) (xy 345.757211 -288.79266) (xy 345.733612 -288.838972) (xy 345.703059 -288.881022)
			(xy 345.666304 -288.917775) (xy 345.624252 -288.948325) (xy 345.577938 -288.97192) (xy 345.528503 -288.987979)
			(xy 345.477165 -288.996107) (xy 345.451176 -288.996628) (xy 345.436952 -288.996374) (xy 345.422982 -288.995612)
			(xy 345.39809 -289.009328) (xy 345.252802 -289.259518) (xy 345.25331 -289.287966) (xy 345.26093 -289.299904)
			(xy 345.272962 -289.319761) (xy 345.29195 -289.362131) (xy 345.304824 -289.40674) (xy 345.31133 -289.452711)
			(xy 345.31173 -289.4759) (xy 345.615803 -289.4759) (xy 345.619967 -289.425652) (xy 345.632344 -289.376775)
			(xy 345.652596 -289.330602) (xy 345.680172 -289.288391) (xy 345.714319 -289.251295) (xy 345.754106 -289.220324)
			(xy 345.798448 -289.196325) (xy 345.846135 -289.17995) (xy 345.895866 -289.171648) (xy 345.921076 -289.171126)
			(xy 346.86113 -289.171126) (xy 346.886344 -289.171597) (xy 346.936083 -289.179901) (xy 346.983777 -289.196279)
			(xy 347.028126 -289.220283) (xy 347.067919 -289.251259) (xy 347.102071 -289.288361) (xy 347.129651 -289.330579)
			(xy 347.149906 -289.376759) (xy 347.162284 -289.425644) (xy 347.166449 -289.4759) (xy 348.435875 -289.4759)
			(xy 348.44004 -289.425641) (xy 348.452421 -289.376754) (xy 348.47268 -289.330571) (xy 348.500266 -289.288353)
			(xy 348.534424 -289.251252) (xy 348.574223 -289.220279) (xy 348.618578 -289.19628) (xy 348.666278 -289.17991)
			(xy 348.716022 -289.171615) (xy 348.741238 -289.171126) (xy 349.681292 -289.171126) (xy 349.70651 -289.171565)
			(xy 349.756259 -289.179866) (xy 349.803963 -289.196242) (xy 349.848321 -289.220246) (xy 349.888123 -289.251224)
			(xy 349.922283 -289.288331) (xy 349.94987 -289.330554) (xy 349.97013 -289.376743) (xy 349.982512 -289.425636)
			(xy 349.986677 -289.4759) (xy 351.255775 -289.4759) (xy 351.25994 -289.42564) (xy 351.272321 -289.376752)
			(xy 351.292582 -289.330569) (xy 351.320168 -289.28835) (xy 351.354327 -289.251249) (xy 351.394127 -289.220276)
			(xy 351.438483 -289.196278) (xy 351.486185 -289.179908) (xy 351.53593 -289.171614) (xy 351.561146 -289.171126)
			(xy 352.5012 -289.171126) (xy 352.526415 -289.171594) (xy 352.576159 -289.179895) (xy 352.623857 -289.19627)
			(xy 352.66821 -289.220272) (xy 352.708007 -289.251248) (xy 352.742163 -289.288351) (xy 352.769746 -289.33057)
			(xy 352.790004 -289.376754) (xy 352.802384 -289.425641) (xy 352.806549 -289.4759) (xy 354.075803 -289.4759)
			(xy 354.079967 -289.425655) (xy 354.092342 -289.37678) (xy 354.112593 -289.330608) (xy 354.140166 -289.288398)
			(xy 354.17431 -289.251302) (xy 354.214094 -289.220332) (xy 354.258433 -289.196331) (xy 354.306117 -289.179955)
			(xy 354.355845 -289.17165) (xy 354.381054 -289.171126) (xy 355.321108 -289.171126) (xy 355.346323 -289.171595)
			(xy 355.396065 -289.179897) (xy 355.443763 -289.196272) (xy 355.488114 -289.220275) (xy 355.52791 -289.251251)
			(xy 355.562065 -289.288354) (xy 355.589647 -289.330572) (xy 355.609904 -289.376755) (xy 355.622284 -289.425642)
			(xy 355.626449 -289.4759) (xy 355.622284 -289.526158) (xy 355.609904 -289.575045) (xy 355.589647 -289.621228)
			(xy 355.562065 -289.663446) (xy 355.52791 -289.700549) (xy 355.488114 -289.731525) (xy 355.443763 -289.755528)
			(xy 355.396065 -289.771903) (xy 355.346323 -289.780205) (xy 355.321108 -289.780726) (xy 354.381054 -289.780726)
			(xy 354.355845 -289.78015) (xy 354.306117 -289.771845) (xy 354.258433 -289.755469) (xy 354.214094 -289.731468)
			(xy 354.17431 -289.700498) (xy 354.140166 -289.663402) (xy 354.112593 -289.621192) (xy 354.092342 -289.57502)
			(xy 354.079967 -289.526145) (xy 354.075803 -289.4759) (xy 352.806549 -289.4759) (xy 352.802384 -289.526159)
			(xy 352.790004 -289.575046) (xy 352.769746 -289.62123) (xy 352.742163 -289.663449) (xy 352.708007 -289.700552)
			(xy 352.66821 -289.731528) (xy 352.623857 -289.75553) (xy 352.576159 -289.771905) (xy 352.526415 -289.780206)
			(xy 352.5012 -289.780726) (xy 351.561146 -289.780726) (xy 351.53593 -289.780186) (xy 351.486185 -289.771892)
			(xy 351.438483 -289.755522) (xy 351.394127 -289.731524) (xy 351.354327 -289.700551) (xy 351.320168 -289.66345)
			(xy 351.292582 -289.621231) (xy 351.272321 -289.575048) (xy 351.25994 -289.52616) (xy 351.255775 -289.4759)
			(xy 349.986677 -289.4759) (xy 349.982512 -289.526164) (xy 349.97013 -289.575057) (xy 349.94987 -289.621246)
			(xy 349.922283 -289.663469) (xy 349.888123 -289.700576) (xy 349.848321 -289.731554) (xy 349.803963 -289.755558)
			(xy 349.756259 -289.771934) (xy 349.70651 -289.780235) (xy 349.681292 -289.780726) (xy 348.741238 -289.780726)
			(xy 348.716022 -289.780185) (xy 348.666278 -289.77189) (xy 348.618578 -289.75552) (xy 348.574223 -289.731521)
			(xy 348.534424 -289.700548) (xy 348.500266 -289.663447) (xy 348.47268 -289.621229) (xy 348.452421 -289.575046)
			(xy 348.44004 -289.526159) (xy 348.435875 -289.4759) (xy 347.166449 -289.4759) (xy 347.162284 -289.526156)
			(xy 347.149906 -289.575041) (xy 347.129651 -289.621221) (xy 347.102071 -289.663439) (xy 347.067919 -289.700541)
			(xy 347.028126 -289.731517) (xy 346.983777 -289.755521) (xy 346.936083 -289.771899) (xy 346.886344 -289.780203)
			(xy 346.86113 -289.780726) (xy 345.921076 -289.780726) (xy 345.895866 -289.780152) (xy 345.846135 -289.77185)
			(xy 345.798448 -289.755475) (xy 345.754106 -289.731476) (xy 345.714319 -289.700505) (xy 345.680172 -289.663409)
			(xy 345.652596 -289.621198) (xy 345.632344 -289.575025) (xy 345.619967 -289.526148) (xy 345.615803 -289.4759)
			(xy 345.31173 -289.4759) (xy 345.31173 -289.475926) (xy 345.311219 -289.501912) (xy 345.303085 -289.553245)
			(xy 345.287022 -289.602674) (xy 345.263425 -289.648981) (xy 345.232875 -289.691027) (xy 345.196124 -289.727778)
			(xy 345.154078 -289.758327) (xy 345.10777 -289.781923) (xy 345.058341 -289.797986) (xy 345.007008 -289.806119)
			(xy 344.981022 -289.806634) (xy 344.967052 -289.80638) (xy 344.953082 -289.805872) (xy 344.92819 -289.819334)
			(xy 344.783156 -290.069524) (xy 344.783664 -290.097972) (xy 344.79103 -290.10991) (xy 344.803062 -290.129767)
			(xy 344.822049 -290.172137) (xy 344.834922 -290.216746) (xy 344.841427 -290.262717) (xy 344.841829 -290.2859)
			(xy 356.425809 -290.2859) (xy 356.429973 -290.235655) (xy 356.442348 -290.18678) (xy 356.462599 -290.140608)
			(xy 356.490173 -290.098399) (xy 356.524318 -290.061304) (xy 356.564102 -290.030334) (xy 356.608441 -290.006334)
			(xy 356.656125 -289.989959) (xy 356.705853 -289.981655) (xy 356.731062 -289.981132) (xy 357.671116 -289.981132)
			(xy 357.696331 -289.98159) (xy 357.746073 -289.989893) (xy 357.79377 -290.006269) (xy 357.838122 -290.030273)
			(xy 357.877917 -290.061249) (xy 357.912072 -290.098353) (xy 357.939654 -290.140572) (xy 357.959911 -290.186755)
			(xy 357.97229 -290.235642) (xy 357.976455 -290.2859) (xy 357.97229 -290.336158) (xy 357.959911 -290.385045)
			(xy 357.939654 -290.431228) (xy 357.912072 -290.473447) (xy 357.877917 -290.510551) (xy 357.838122 -290.541527)
			(xy 357.79377 -290.565531) (xy 357.746073 -290.581907) (xy 357.696331 -290.59021) (xy 357.671116 -290.590732)
			(xy 356.731062 -290.590732) (xy 356.705853 -290.590145) (xy 356.656125 -290.581841) (xy 356.608441 -290.565466)
			(xy 356.564102 -290.541466) (xy 356.524318 -290.510496) (xy 356.490173 -290.473401) (xy 356.462599 -290.431192)
			(xy 356.442348 -290.38502) (xy 356.429973 -290.336145) (xy 356.425809 -290.2859) (xy 344.841829 -290.2859)
			(xy 344.84183 -290.285932) (xy 344.841318 -290.311918) (xy 344.833184 -290.36325) (xy 344.81712 -290.412678)
			(xy 344.793523 -290.458984) (xy 344.762973 -290.50103) (xy 344.726222 -290.53778) (xy 344.684176 -290.568328)
			(xy 344.637868 -290.591924) (xy 344.58844 -290.607986) (xy 344.537108 -290.616119) (xy 344.511122 -290.61664)
			(xy 344.497152 -290.616386) (xy 344.482928 -290.615624) (xy 344.45829 -290.62934) (xy 344.313002 -290.87953)
			(xy 344.31351 -290.907724) (xy 344.32113 -290.919662) (xy 344.333169 -290.939552) (xy 344.352166 -290.981985)
			(xy 344.365045 -291.026658) (xy 344.371552 -291.072692) (xy 344.371929 -291.0959) (xy 345.615816 -291.0959)
			(xy 345.619979 -291.045654) (xy 345.632355 -290.996779) (xy 345.652607 -290.950608) (xy 345.680182 -290.908399)
			(xy 345.714327 -290.871304) (xy 345.754113 -290.840335) (xy 345.798453 -290.816336) (xy 345.846138 -290.799963)
			(xy 345.895867 -290.791661) (xy 345.921076 -290.791138) (xy 346.86113 -290.791138) (xy 346.886345 -290.791585)
			(xy 346.936086 -290.79989) (xy 346.983782 -290.816268) (xy 347.028132 -290.840273) (xy 347.067927 -290.87125)
			(xy 347.10208 -290.908354) (xy 347.129661 -290.950573) (xy 347.149917 -290.996756) (xy 347.162296 -291.045642)
			(xy 347.166461 -291.0959) (xy 348.435887 -291.0959) (xy 348.440052 -291.045643) (xy 348.452432 -290.996757)
			(xy 348.472691 -290.950576) (xy 348.500275 -290.90836) (xy 348.534432 -290.87126) (xy 348.57423 -290.840289)
			(xy 348.618583 -290.816291) (xy 348.666281 -290.799922) (xy 348.716023 -290.791627) (xy 348.741238 -290.791138)
			(xy 349.681292 -290.791138) (xy 349.706511 -290.791553) (xy 349.756262 -290.799854) (xy 349.803968 -290.816231)
			(xy 349.848328 -290.840236) (xy 349.888131 -290.871215) (xy 349.922293 -290.908324) (xy 349.94988 -290.950549)
			(xy 349.970142 -290.996739) (xy 349.982524 -291.045634) (xy 349.986689 -291.0959) (xy 351.255787 -291.0959)
			(xy 351.259952 -291.045642) (xy 351.272333 -290.996756) (xy 351.292592 -290.950574) (xy 351.320177 -290.908358)
			(xy 351.354335 -290.871257) (xy 351.394134 -290.840286) (xy 351.438488 -290.816289) (xy 351.486188 -290.79992)
			(xy 351.535931 -290.791626) (xy 351.561146 -290.791138) (xy 352.5012 -290.791138) (xy 352.526416 -290.791582)
			(xy 352.576162 -290.799883) (xy 352.623862 -290.816259) (xy 352.668216 -290.840262) (xy 352.708015 -290.871239)
			(xy 352.742172 -290.908344) (xy 352.769757 -290.950564) (xy 352.790015 -290.99675) (xy 352.802396 -291.045639)
			(xy 352.806561 -291.0959) (xy 354.075816 -291.0959) (xy 354.079979 -291.045657) (xy 354.092354 -290.996784)
			(xy 354.112604 -290.950614) (xy 354.140176 -290.908406) (xy 354.174319 -290.871312) (xy 354.214101 -290.840342)
			(xy 354.258438 -290.816343) (xy 354.30612 -290.799967) (xy 354.355846 -290.791662) (xy 354.381054 -290.791138)
			(xy 355.321108 -290.791138) (xy 355.346324 -290.791583) (xy 355.396068 -290.799885) (xy 355.443767 -290.816261)
			(xy 355.488121 -290.840265) (xy 355.527918 -290.871242) (xy 355.562074 -290.908346) (xy 355.589658 -290.950567)
			(xy 355.609916 -290.996751) (xy 355.622296 -291.04564) (xy 355.626461 -291.0959) (xy 355.622296 -291.14616)
			(xy 355.609916 -291.195049) (xy 355.589658 -291.241233) (xy 355.562074 -291.283454) (xy 355.527918 -291.320558)
			(xy 355.488121 -291.351535) (xy 355.443767 -291.375539) (xy 355.396068 -291.391915) (xy 355.346324 -291.400217)
			(xy 355.321108 -291.400738) (xy 354.381054 -291.400738) (xy 354.355846 -291.400138) (xy 354.30612 -291.391833)
			(xy 354.258438 -291.375457) (xy 354.214101 -291.351458) (xy 354.174319 -291.320488) (xy 354.140176 -291.283394)
			(xy 354.112604 -291.241186) (xy 354.092354 -291.195016) (xy 354.079979 -291.146143) (xy 354.075816 -291.0959)
			(xy 352.806561 -291.0959) (xy 352.802396 -291.146161) (xy 352.790015 -291.19505) (xy 352.769757 -291.241236)
			(xy 352.742172 -291.283456) (xy 352.708015 -291.320561) (xy 352.668216 -291.351538) (xy 352.623862 -291.375541)
			(xy 352.576162 -291.391917) (xy 352.526416 -291.400218) (xy 352.5012 -291.400738) (xy 351.561146 -291.400738)
			(xy 351.535931 -291.400174) (xy 351.486188 -291.39188) (xy 351.438488 -291.375511) (xy 351.394134 -291.351514)
			(xy 351.354335 -291.320542) (xy 351.320177 -291.283442) (xy 351.292592 -291.241226) (xy 351.272333 -291.195044)
			(xy 351.259952 -291.146158) (xy 351.255787 -291.0959) (xy 349.986689 -291.0959) (xy 349.982524 -291.146166)
			(xy 349.970142 -291.195061) (xy 349.94988 -291.241251) (xy 349.922293 -291.283476) (xy 349.888131 -291.320585)
			(xy 349.848328 -291.351564) (xy 349.803968 -291.375569) (xy 349.756262 -291.391946) (xy 349.706511 -291.400247)
			(xy 349.681292 -291.400738) (xy 348.741238 -291.400738) (xy 348.716023 -291.400173) (xy 348.666281 -291.391878)
			(xy 348.618583 -291.375509) (xy 348.57423 -291.351511) (xy 348.534432 -291.32054) (xy 348.500275 -291.28344)
			(xy 348.472691 -291.241223) (xy 348.452432 -291.195043) (xy 348.440052 -291.146157) (xy 348.435887 -291.0959)
			(xy 347.166461 -291.0959) (xy 347.162296 -291.146158) (xy 347.149917 -291.195044) (xy 347.129661 -291.241227)
			(xy 347.10208 -291.283446) (xy 347.067927 -291.32055) (xy 347.028132 -291.351527) (xy 346.983782 -291.375532)
			(xy 346.936086 -291.39191) (xy 346.886345 -291.400215) (xy 346.86113 -291.400738) (xy 345.921076 -291.400738)
			(xy 345.895867 -291.400139) (xy 345.846138 -291.391837) (xy 345.798453 -291.375464) (xy 345.754113 -291.351465)
			(xy 345.714327 -291.320496) (xy 345.680182 -291.283401) (xy 345.652607 -291.241192) (xy 345.632355 -291.195021)
			(xy 345.619979 -291.146146) (xy 345.615816 -291.0959) (xy 344.371929 -291.0959) (xy 344.37193 -291.095938)
			(xy 344.371418 -291.121924) (xy 344.363282 -291.173255) (xy 344.347218 -291.222682) (xy 344.323621 -291.268988)
			(xy 344.293071 -291.311033) (xy 344.25632 -291.347781) (xy 344.214274 -291.378329) (xy 344.167967 -291.401925)
			(xy 344.118539 -291.417986) (xy 344.067208 -291.426119) (xy 344.041222 -291.426646) (xy 344.026998 -291.426392)
			(xy 344.012774 -291.42563) (xy 343.988136 -291.439346) (xy 343.842848 -291.689536) (xy 343.843356 -291.71773)
			(xy 343.850976 -291.729922) (xy 343.863006 -291.74978) (xy 343.881989 -291.79215) (xy 343.894858 -291.836759)
			(xy 343.901361 -291.88273) (xy 343.901776 -291.905944) (xy 343.901263 -291.931928) (xy 343.893127 -291.983255)
			(xy 343.877062 -292.032678) (xy 343.853463 -292.078979) (xy 343.822912 -292.121018) (xy 343.786161 -292.157761)
			(xy 343.744114 -292.188303) (xy 343.697808 -292.211891) (xy 343.648381 -292.227945) (xy 343.597052 -292.236069)
			(xy 343.571068 -292.236652) (xy 343.557098 -292.236398) (xy 343.542874 -292.235636) (xy 343.517982 -292.249352)
			(xy 343.372948 -292.499542) (xy 343.373456 -292.527736) (xy 343.381076 -292.539674) (xy 343.393113 -292.559564)
			(xy 343.412105 -292.601999) (xy 343.424981 -292.646671) (xy 343.431486 -292.692705) (xy 343.431876 -292.71595)
			(xy 343.431397 -292.741941) (xy 343.423271 -292.793284) (xy 343.407213 -292.842723) (xy 343.383618 -292.889041)
			(xy 343.353066 -292.931096) (xy 343.31631 -292.967854) (xy 343.274256 -292.998408) (xy 343.227939 -293.022006)
			(xy 343.178501 -293.038067) (xy 343.127159 -293.046195) (xy 343.101168 -293.046658) (xy 343.086944 -293.046404)
			(xy 343.07272 -293.045642) (xy 343.048082 -293.059358) (xy 342.902794 -293.309548) (xy 342.903302 -293.337742)
			(xy 342.910922 -293.34968) (xy 342.92296 -293.36957) (xy 342.941955 -293.412004) (xy 342.954832 -293.456676)
			(xy 342.961337 -293.50271) (xy 342.961722 -293.525956) (xy 342.961242 -293.551948) (xy 342.953116 -293.603293)
			(xy 342.937058 -293.652734) (xy 342.913463 -293.699054) (xy 342.882912 -293.741113) (xy 342.846157 -293.777874)
			(xy 342.804104 -293.808433) (xy 342.757788 -293.832036) (xy 342.708349 -293.848103) (xy 342.657006 -293.856238)
			(xy 342.631014 -293.856664) (xy 342.60555 -293.856197) (xy 342.555222 -293.848395) (xy 342.506685 -293.832973)
			(xy 342.461084 -293.810296) (xy 342.419496 -293.7809) (xy 342.382904 -293.745477) (xy 342.352172 -293.704866)
			(xy 342.339676 -293.682674) (xy 342.333072 -293.670228) (xy 342.309196 -293.656004) (xy 342.013032 -293.656004)
			(xy 341.989156 -293.670228) (xy 341.982552 -293.682674) (xy 341.97006 -293.704868) (xy 341.939319 -293.745471)
			(xy 341.902723 -293.780887) (xy 341.861135 -293.810282) (xy 341.815536 -293.832962) (xy 341.767002 -293.848392)
			(xy 341.716678 -293.856208) (xy 341.691214 -293.856664) (xy 341.67699 -293.85641) (xy 341.662766 -293.855648)
			(xy 341.638128 -293.869364) (xy 341.478616 -294.144192) (xy 341.478616 -294.17137) (xy 341.485474 -294.183308)
			(xy 341.498332 -294.206672) (xy 341.516568 -294.256783) (xy 341.525821 -294.309299) (xy 341.526368 -294.335962)
			(xy 341.525925 -294.359956) (xy 341.518422 -294.407354) (xy 341.503597 -294.452994) (xy 341.481813 -294.495752)
			(xy 341.453607 -294.534576) (xy 341.419674 -294.568508) (xy 341.380851 -294.596714) (xy 341.338092 -294.618497)
			(xy 341.292452 -294.633323) (xy 341.245054 -294.640825) (xy 341.22106 -294.64127) (xy 341.206074 -294.64127)
			(xy 341.182452 -294.654732) (xy 341.008716 -294.954198) (xy 341.008716 -294.981376) (xy 341.015574 -294.993314)
			(xy 341.028431 -295.016678) (xy 341.046666 -295.066789) (xy 341.055919 -295.119305) (xy 341.056468 -295.145968)
			(xy 341.056024 -295.169962) (xy 341.048521 -295.217359) (xy 341.033695 -295.262998) (xy 341.011911 -295.305756)
			(xy 340.983705 -295.344578) (xy 340.949772 -295.37851) (xy 340.910949 -295.406715) (xy 340.868191 -295.428498)
			(xy 340.822551 -295.443323) (xy 340.775154 -295.450825) (xy 340.75116 -295.451276) (xy 340.736174 -295.451276)
			(xy 340.712298 -295.464738) (xy 340.552786 -295.739566) (xy 340.553294 -295.76776) (xy 340.560914 -295.779952)
			(xy 340.57295 -295.799808) (xy 340.591946 -295.842176) (xy 340.604827 -295.886786) (xy 340.61134 -295.932758)
			(xy 340.611714 -295.955974) (xy 340.611233 -295.981965) (xy 340.603105 -296.033307) (xy 340.587045 -296.082745)
			(xy 340.563449 -296.129062) (xy 340.532897 -296.171118) (xy 340.496142 -296.207876) (xy 340.45409 -296.238432)
			(xy 340.407775 -296.262033) (xy 340.358338 -296.278097) (xy 340.306997 -296.28623) (xy 340.281006 -296.286682)
			(xy 340.255542 -296.286214) (xy 340.205215 -296.278412) (xy 340.156677 -296.26299) (xy 340.111076 -296.240313)
			(xy 340.069488 -296.210917) (xy 340.032896 -296.175495) (xy 340.002163 -296.134885) (xy 339.989668 -296.112692)
			(xy 339.983064 -296.100246) (xy 339.959188 -296.085768) (xy 339.663024 -296.085768) (xy 339.639148 -296.100246)
			(xy 339.632544 -296.112692) (xy 339.620054 -296.134886) (xy 339.589316 -296.175489) (xy 339.55272 -296.210904)
			(xy 339.51113 -296.240294) (xy 339.46553 -296.262967) (xy 339.416994 -296.278386) (xy 339.366669 -296.286187)
			(xy 339.315743 -296.286187) (xy 339.265418 -296.278386) (xy 339.216882 -296.262967) (xy 339.171282 -296.240294)
			(xy 339.129692 -296.210904) (xy 339.093096 -296.175489) (xy 339.062358 -296.134886) (xy 339.049868 -296.112692)
			(xy 339.043264 -296.100246) (xy 339.019388 -296.085768) (xy 338.72297 -296.085768) (xy 338.699094 -296.100246)
			(xy 338.69249 -296.112692) (xy 338.68 -296.134886) (xy 338.649262 -296.175489) (xy 338.612666 -296.210904)
			(xy 338.571076 -296.240294) (xy 338.525476 -296.262967) (xy 338.47694 -296.278386) (xy 338.426615 -296.286187)
			(xy 338.375689 -296.286187) (xy 338.325364 -296.278386) (xy 338.276828 -296.262967) (xy 338.231228 -296.240294)
			(xy 338.189638 -296.210904) (xy 338.153042 -296.175489) (xy 338.122304 -296.134886) (xy 338.109814 -296.112692)
			(xy 338.10321 -296.100246) (xy 338.079334 -296.085768) (xy 336.842862 -296.085768) (xy 336.818986 -296.100246)
			(xy 336.812382 -296.112692) (xy 336.799892 -296.134886) (xy 336.769154 -296.175489) (xy 336.732558 -296.210904)
			(xy 336.690968 -296.240294) (xy 336.645368 -296.262967) (xy 336.596832 -296.278386) (xy 336.546507 -296.286187)
			(xy 336.495581 -296.286187) (xy 336.445256 -296.278386) (xy 336.39672 -296.262967) (xy 336.35112 -296.240294)
			(xy 336.30953 -296.210904) (xy 336.272934 -296.175489) (xy 336.242196 -296.134886) (xy 336.229706 -296.112692)
			(xy 336.223102 -296.100246) (xy 336.199226 -296.085768) (xy 334.93456 -296.085768) (xy 334.911192 -296.09923)
			(xy 334.904334 -296.110914) (xy 334.891525 -296.131693) (xy 334.860359 -296.169258) (xy 334.823617 -296.20139)
			(xy 334.782234 -296.227272) (xy 334.737262 -296.246243) (xy 334.689845 -296.257823) (xy 334.64119 -296.261716)
			(xy 334.592535 -296.257823) (xy 334.545118 -296.246243) (xy 334.500146 -296.227272) (xy 334.458763 -296.20139)
			(xy 334.422021 -296.169258) (xy 334.390855 -296.131693) (xy 334.378046 -296.110914) (xy 334.371188 -296.09923)
			(xy 334.34782 -296.085768) (xy 334.022954 -296.085768) (xy 333.999078 -296.100246) (xy 333.992474 -296.112692)
			(xy 333.979984 -296.134886) (xy 333.949246 -296.175489) (xy 333.91265 -296.210904) (xy 333.87106 -296.240294)
			(xy 333.82546 -296.262967) (xy 333.776924 -296.278386) (xy 333.726599 -296.286187) (xy 333.675673 -296.286187)
			(xy 333.625348 -296.278386) (xy 333.576812 -296.262967) (xy 333.531212 -296.240294) (xy 333.489622 -296.210904)
			(xy 333.453026 -296.175489) (xy 333.422288 -296.134886) (xy 333.409798 -296.112692) (xy 333.403194 -296.100246)
			(xy 333.379318 -296.085768) (xy 333.0829 -296.085768) (xy 333.059024 -296.100246) (xy 333.05242 -296.112692)
			(xy 333.03993 -296.134886) (xy 333.009192 -296.175489) (xy 332.972596 -296.210904) (xy 332.931006 -296.240294)
			(xy 332.885406 -296.262967) (xy 332.83687 -296.278386) (xy 332.786545 -296.286187) (xy 332.735619 -296.286187)
			(xy 332.685294 -296.278386) (xy 332.636758 -296.262967) (xy 332.591158 -296.240294) (xy 332.549568 -296.210904)
			(xy 332.512972 -296.175489) (xy 332.482234 -296.134886) (xy 332.469744 -296.112692) (xy 332.46314 -296.100246)
			(xy 332.439264 -296.085768) (xy 332.142846 -296.085768) (xy 332.11897 -296.100246) (xy 332.112366 -296.112692)
			(xy 332.099876 -296.134886) (xy 332.069138 -296.175489) (xy 332.032542 -296.210904) (xy 331.990952 -296.240294)
			(xy 331.945352 -296.262967) (xy 331.896816 -296.278386) (xy 331.846491 -296.286187) (xy 331.795565 -296.286187)
			(xy 331.74524 -296.278386) (xy 331.696704 -296.262967) (xy 331.651104 -296.240294) (xy 331.609514 -296.210904)
			(xy 331.572918 -296.175489) (xy 331.54218 -296.134886) (xy 331.52969 -296.112692) (xy 331.523086 -296.100246)
			(xy 331.49921 -296.085768) (xy 331.174598 -296.085768) (xy 331.15123 -296.09923) (xy 331.144372 -296.110914)
			(xy 331.131563 -296.131693) (xy 331.100397 -296.169258) (xy 331.063655 -296.20139) (xy 331.022272 -296.227272)
			(xy 330.9773 -296.246243) (xy 330.929883 -296.257823) (xy 330.881228 -296.261716) (xy 330.832573 -296.257823)
			(xy 330.785156 -296.246243) (xy 330.740184 -296.227272) (xy 330.698801 -296.20139) (xy 330.662059 -296.169258)
			(xy 330.630893 -296.131693) (xy 330.618084 -296.110914) (xy 330.611226 -296.09923) (xy 330.587858 -296.085768)
			(xy 327.44283 -296.085768) (xy 327.418954 -296.100246) (xy 327.41235 -296.112692) (xy 327.399862 -296.13489)
			(xy 327.369125 -296.175502) (xy 327.332531 -296.210927) (xy 327.290943 -296.24033) (xy 327.245343 -296.263015)
			(xy 327.196806 -296.278449) (xy 327.146478 -296.286267) (xy 327.121012 -296.286682) (xy 327.094796 -296.286181)
			(xy 327.043021 -296.277906) (xy 326.993201 -296.261563) (xy 326.946586 -296.23756) (xy 326.925178 -296.22242)
			(xy 326.918479 -296.217838) (xy 326.903064 -296.212794) (xy 326.894952 -296.212514) (xy 317.087504 -296.212514)
			(xy 317.077434 -296.212937) (xy 317.05883 -296.220652) (xy 317.051436 -296.2275) (xy 313.131962 -300.146974)
			(xy 340.219284 -300.146974) (xy 340.219284 -299.130974) (xy 340.21977 -299.103723) (xy 340.227526 -299.049775)
			(xy 340.242881 -298.99748) (xy 340.265523 -298.947903) (xy 340.294989 -298.902053) (xy 340.33068 -298.860862)
			(xy 340.371871 -298.825171) (xy 340.417721 -298.795705) (xy 340.467298 -298.773063) (xy 340.519593 -298.757708)
			(xy 340.573541 -298.749952) (xy 340.628043 -298.749952) (xy 340.681991 -298.757708) (xy 340.734286 -298.773063)
			(xy 340.783863 -298.795705) (xy 340.829713 -298.825171) (xy 340.870904 -298.860862) (xy 340.906595 -298.902053)
			(xy 340.936061 -298.947903) (xy 340.958703 -298.99748) (xy 340.974058 -299.049775) (xy 340.981814 -299.103723)
			(xy 340.9823 -299.130974) (xy 340.9823 -300.146974) (xy 340.981814 -300.174225) (xy 340.974058 -300.228173)
			(xy 340.958703 -300.280468) (xy 340.936061 -300.330045) (xy 340.906595 -300.375895) (xy 340.870904 -300.417086)
			(xy 340.829713 -300.452777) (xy 340.783863 -300.482243) (xy 340.734286 -300.504885) (xy 340.681991 -300.52024)
			(xy 340.628043 -300.527996) (xy 340.573541 -300.527996) (xy 340.519593 -300.52024) (xy 340.467298 -300.504885)
			(xy 340.417721 -300.482243) (xy 340.371871 -300.452777) (xy 340.33068 -300.417086) (xy 340.294989 -300.375895)
			(xy 340.265523 -300.330045) (xy 340.242881 -300.280468) (xy 340.227526 -300.228173) (xy 340.21977 -300.174225)
			(xy 340.219284 -300.146974) (xy 313.131962 -300.146974) (xy 308.498748 -304.780188) (xy 326.752462 -304.780188)
			(xy 326.756491 -304.637867) (xy 326.768566 -304.496002) (xy 326.788647 -304.355048) (xy 326.81667 -304.215455)
			(xy 326.852546 -304.077671) (xy 326.89616 -303.942138) (xy 326.947372 -303.809289) (xy 327.006018 -303.67955)
			(xy 327.071909 -303.553337) (xy 327.144836 -303.431054) (xy 327.224564 -303.313092) (xy 327.310838 -303.19983)
			(xy 327.403382 -303.091631) (xy 327.501898 -302.98884) (xy 327.606073 -302.891788) (xy 327.715571 -302.800784)
			(xy 327.830042 -302.716122) (xy 327.94912 -302.638071) (xy 328.072423 -302.566882) (xy 328.199556 -302.502783)
			(xy 328.330112 -302.445979) (xy 328.463672 -302.396653) (xy 328.599809 -302.354961) (xy 328.738087 -302.321038)
			(xy 328.878062 -302.294993) (xy 329.019287 -302.276908) (xy 329.161308 -302.266843) (xy 329.303672 -302.264828)
			(xy 329.445922 -302.270871) (xy 329.587602 -302.284951) (xy 329.728258 -302.307025) (xy 329.86744 -302.337021)
			(xy 330.004702 -302.374843) (xy 330.139605 -302.420371) (xy 330.271716 -302.473457) (xy 330.400612 -302.533933)
			(xy 330.52588 -302.601604) (xy 330.647119 -302.676254) (xy 330.76394 -302.757643) (xy 330.87597 -302.845511)
			(xy 330.982849 -302.939577) (xy 331.084235 -303.039538) (xy 331.179804 -303.145076) (xy 331.269249 -303.255851)
			(xy 331.352283 -303.371509) (xy 331.428641 -303.491679) (xy 331.498078 -303.615977) (xy 331.560371 -303.744004)
			(xy 331.615322 -303.875351) (xy 331.662754 -304.009596) (xy 331.702515 -304.146309) (xy 331.734477 -304.285053)
			(xy 331.758539 -304.425383) (xy 331.774623 -304.566849) (xy 331.781099 -304.681128) (xy 333.795116 -304.681128)
			(xy 333.795116 -303.817528) (xy 333.795602 -303.790259) (xy 333.803364 -303.736275) (xy 333.818729 -303.683945)
			(xy 333.841386 -303.634335) (xy 333.870872 -303.588454) (xy 333.906587 -303.547237) (xy 333.947804 -303.511522)
			(xy 333.993685 -303.482036) (xy 334.043295 -303.459379) (xy 334.095625 -303.444014) (xy 334.149609 -303.436252)
			(xy 334.204147 -303.436252) (xy 334.258131 -303.444014) (xy 334.310461 -303.459379) (xy 334.360071 -303.482036)
			(xy 334.405952 -303.511522) (xy 334.447169 -303.547237) (xy 334.482884 -303.588454) (xy 334.51237 -303.634335)
			(xy 334.535027 -303.683945) (xy 334.550392 -303.736275) (xy 334.558154 -303.790259) (xy 334.55864 -303.817528)
			(xy 334.55864 -304.681128) (xy 334.558154 -304.708397) (xy 334.550392 -304.762381) (xy 334.535027 -304.814711)
			(xy 334.51237 -304.864321) (xy 334.482884 -304.910202) (xy 334.447169 -304.951419) (xy 334.405952 -304.987134)
			(xy 334.360071 -305.01662) (xy 334.310461 -305.039277) (xy 334.258131 -305.054642) (xy 334.204147 -305.062404)
			(xy 334.149609 -305.062404) (xy 334.095625 -305.054642) (xy 334.043295 -305.039277) (xy 333.993685 -305.01662)
			(xy 333.947804 -304.987134) (xy 333.906587 -304.951419) (xy 333.870872 -304.910202) (xy 333.841386 -304.864321)
			(xy 333.818729 -304.814711) (xy 333.803364 -304.762381) (xy 333.795602 -304.708397) (xy 333.795116 -304.681128)
			(xy 331.781099 -304.681128) (xy 331.782679 -304.708999) (xy 331.783182 -304.780188) (xy 331.782679 -304.851377)
			(xy 331.774623 -304.993527) (xy 331.758539 -305.134993) (xy 331.734477 -305.275323) (xy 331.702515 -305.414067)
			(xy 331.662754 -305.55078) (xy 331.615322 -305.685025) (xy 331.560371 -305.816372) (xy 331.498078 -305.944399)
			(xy 331.428641 -306.068697) (xy 331.352283 -306.188867) (xy 331.269249 -306.304525) (xy 331.179804 -306.4153)
			(xy 331.163807 -306.432966) (xy 340.495636 -306.432966) (xy 340.495636 -305.569366) (xy 340.496122 -305.542115)
			(xy 340.503878 -305.488167) (xy 340.519233 -305.435872) (xy 340.541875 -305.386295) (xy 340.571341 -305.340445)
			(xy 340.607032 -305.299254) (xy 340.648223 -305.263563) (xy 340.694073 -305.234097) (xy 340.74365 -305.211455)
			(xy 340.795945 -305.1961) (xy 340.849893 -305.188344) (xy 340.904395 -305.188344) (xy 340.958343 -305.1961)
			(xy 341.010638 -305.211455) (xy 341.060215 -305.234097) (xy 341.106065 -305.263563) (xy 341.147256 -305.299254)
			(xy 341.182947 -305.340445) (xy 341.212413 -305.386295) (xy 341.235055 -305.435872) (xy 341.25041 -305.488167)
			(xy 341.258166 -305.542115) (xy 341.258652 -305.569366) (xy 341.258652 -306.432966) (xy 341.258166 -306.460217)
			(xy 341.25041 -306.514165) (xy 341.235055 -306.56646) (xy 341.212413 -306.616037) (xy 341.182947 -306.661887)
			(xy 341.147256 -306.703078) (xy 341.106065 -306.738769) (xy 341.060215 -306.768235) (xy 341.010638 -306.790877)
			(xy 340.958343 -306.806232) (xy 340.904395 -306.813988) (xy 340.849893 -306.813988) (xy 340.795945 -306.806232)
			(xy 340.74365 -306.790877) (xy 340.694073 -306.768235) (xy 340.648223 -306.738769) (xy 340.607032 -306.703078)
			(xy 340.571341 -306.661887) (xy 340.541875 -306.616037) (xy 340.519233 -306.56646) (xy 340.503878 -306.514165)
			(xy 340.496122 -306.460217) (xy 340.495636 -306.432966) (xy 331.163807 -306.432966) (xy 331.084235 -306.520838)
			(xy 330.982849 -306.620799) (xy 330.87597 -306.714865) (xy 330.76394 -306.802733) (xy 330.647119 -306.884122)
			(xy 330.52588 -306.958772) (xy 330.400612 -307.026443) (xy 330.271716 -307.086919) (xy 330.139605 -307.140005)
			(xy 330.004702 -307.185533) (xy 329.86744 -307.223355) (xy 329.728258 -307.253351) (xy 329.587602 -307.275425)
			(xy 329.445922 -307.289505) (xy 329.303672 -307.295548) (xy 329.161308 -307.293533) (xy 329.019287 -307.283468)
			(xy 328.878062 -307.265383) (xy 328.738087 -307.239338) (xy 328.599809 -307.205415) (xy 328.463672 -307.163723)
			(xy 328.330112 -307.114397) (xy 328.199556 -307.057593) (xy 328.072423 -306.993494) (xy 327.94912 -306.922305)
			(xy 327.830042 -306.844254) (xy 327.715571 -306.759592) (xy 327.606073 -306.668588) (xy 327.501898 -306.571536)
			(xy 327.403382 -306.468745) (xy 327.310838 -306.360546) (xy 327.224564 -306.247284) (xy 327.144836 -306.129322)
			(xy 327.071909 -306.007039) (xy 327.006018 -305.880826) (xy 326.947372 -305.751087) (xy 326.89616 -305.618238)
			(xy 326.852546 -305.482705) (xy 326.81667 -305.344921) (xy 326.788647 -305.205328) (xy 326.768566 -305.064374)
			(xy 326.756491 -304.922509) (xy 326.752462 -304.780188) (xy 308.498748 -304.780188) (xy 304.129948 -309.148988)
			(xy 304.123095 -309.156384) (xy 304.115348 -309.174982) (xy 304.114962 -309.185056) (xy 304.114962 -309.303166)
			(xy 341.51824 -309.303166) (xy 341.51824 -308.439566) (xy 341.518726 -308.412297) (xy 341.526488 -308.358313)
			(xy 341.541853 -308.305983) (xy 341.56451 -308.256373) (xy 341.593996 -308.210492) (xy 341.629711 -308.169275)
			(xy 341.670928 -308.13356) (xy 341.716809 -308.104074) (xy 341.766419 -308.081417) (xy 341.818749 -308.066052)
			(xy 341.872733 -308.05829) (xy 341.927271 -308.05829) (xy 341.981255 -308.066052) (xy 342.033585 -308.081417)
			(xy 342.083195 -308.104074) (xy 342.129076 -308.13356) (xy 342.170293 -308.169275) (xy 342.206008 -308.210492)
			(xy 342.235494 -308.256373) (xy 342.258151 -308.305983) (xy 342.273516 -308.358313) (xy 342.281278 -308.412297)
			(xy 342.281764 -308.439566) (xy 342.281764 -309.303166) (xy 342.281278 -309.330435) (xy 342.273516 -309.384419)
			(xy 342.258151 -309.436749) (xy 342.235494 -309.486359) (xy 342.206008 -309.53224) (xy 342.170293 -309.573457)
			(xy 342.129076 -309.609172) (xy 342.083195 -309.638658) (xy 342.033585 -309.661315) (xy 341.981255 -309.67668)
			(xy 341.927271 -309.684442) (xy 341.872733 -309.684442) (xy 341.818749 -309.67668) (xy 341.766419 -309.661315)
			(xy 341.716809 -309.638658) (xy 341.670928 -309.609172) (xy 341.629711 -309.573457) (xy 341.593996 -309.53224)
			(xy 341.56451 -309.486359) (xy 341.541853 -309.436749) (xy 341.526488 -309.384419) (xy 341.518726 -309.330435)
			(xy 341.51824 -309.303166) (xy 304.114962 -309.303166) (xy 304.114962 -311.513728) (xy 347.772228 -311.513728)
			(xy 347.772228 -310.650128) (xy 347.772714 -310.622859) (xy 347.780476 -310.568875) (xy 347.795841 -310.516545)
			(xy 347.818498 -310.466935) (xy 347.847984 -310.421054) (xy 347.883699 -310.379837) (xy 347.924916 -310.344122)
			(xy 347.970797 -310.314636) (xy 348.020407 -310.291979) (xy 348.072737 -310.276614) (xy 348.126721 -310.268852)
			(xy 348.181259 -310.268852) (xy 348.235243 -310.276614) (xy 348.287573 -310.291979) (xy 348.337183 -310.314636)
			(xy 348.383064 -310.344122) (xy 348.424281 -310.379837) (xy 348.459996 -310.421054) (xy 348.489482 -310.466935)
			(xy 348.512139 -310.516545) (xy 348.527504 -310.568875) (xy 348.535266 -310.622859) (xy 348.535752 -310.650128)
			(xy 348.535752 -311.513728) (xy 348.535266 -311.540997) (xy 348.527504 -311.594981) (xy 348.512139 -311.647311)
			(xy 348.489482 -311.696921) (xy 348.459996 -311.742802) (xy 348.424281 -311.784019) (xy 348.383064 -311.819734)
			(xy 348.337183 -311.84922) (xy 348.287573 -311.871877) (xy 348.235243 -311.887242) (xy 348.181259 -311.895004)
			(xy 348.126721 -311.895004) (xy 348.072737 -311.887242) (xy 348.020407 -311.871877) (xy 347.970797 -311.84922)
			(xy 347.924916 -311.819734) (xy 347.883699 -311.784019) (xy 347.847984 -311.742802) (xy 347.818498 -311.696921)
			(xy 347.795841 -311.647311) (xy 347.780476 -311.594981) (xy 347.772714 -311.540997) (xy 347.772228 -311.513728)
			(xy 304.114962 -311.513728) (xy 304.114962 -334.78216) (xy 304.115398 -334.792224) (xy 304.123134 -334.810807)
			(xy 304.129948 -334.818228) (xy 304.530252 -335.218532) (xy 304.53765 -335.225378) (xy 304.556249 -335.233104)
			(xy 304.56632 -335.233518)
		)
		(stroke
			(width 0)
			(type solid)
		)
		(fill yes)
		(layer "In9.Cu")
		(net "PVDDCR_CPU1_P0")
	)
	(gr_poly
		(pts
			(xy 255.800098 -33.611058) (xy 255.832245 -33.610555) (xy 255.89599 -33.602163) (xy 255.958093 -33.585522)
			(xy 256.017493 -33.560917) (xy 256.073173 -33.528769) (xy 256.124181 -33.489628) (xy 256.169643 -33.444164)
			(xy 256.208781 -33.393155) (xy 256.240927 -33.337473) (xy 256.265529 -33.278072) (xy 256.282167 -33.215968)
			(xy 256.290557 -33.152223) (xy 256.29108 -33.120076) (xy 256.29108 -11.780012) (xy 256.291564 -11.709629)
			(xy 256.299456 -11.569085) (xy 256.315217 -11.429205) (xy 256.338795 -11.290428) (xy 256.370118 -11.153191)
			(xy 256.409086 -11.017927) (xy 256.455577 -10.885061) (xy 256.509445 -10.75501) (xy 256.570521 -10.628184)
			(xy 256.638611 -10.504983) (xy 256.713502 -10.385793) (xy 256.794959 -10.27099) (xy 256.882724 -10.160934)
			(xy 256.976523 -10.055973) (xy 257.076059 -9.956436) (xy 257.181019 -9.862637) (xy 257.291074 -9.774871)
			(xy 257.405876 -9.693414) (xy 257.525065 -9.618521) (xy 257.648266 -9.55043) (xy 257.775092 -9.489354)
			(xy 257.905142 -9.435484) (xy 258.038008 -9.388992) (xy 258.173272 -9.350023) (xy 258.310508 -9.318699)
			(xy 258.449285 -9.295119) (xy 258.589165 -9.279358) (xy 258.729709 -9.271465) (xy 258.800092 -9.271)
			(xy 383.601976 -9.271) (xy 383.657746 -9.270492) (xy 383.768975 -9.262159) (xy 383.87927 -9.245536)
			(xy 383.988015 -9.220718) (xy 384.094601 -9.187842) (xy 384.198432 -9.147093) (xy 384.298927 -9.098699)
			(xy 384.395525 -9.04293) (xy 384.487685 -8.980099) (xy 384.574892 -8.910555) (xy 384.656659 -8.83469)
			(xy 384.732527 -8.752926) (xy 384.802073 -8.665721) (xy 384.864907 -8.573562) (xy 384.920679 -8.476966)
			(xy 384.969076 -8.376472) (xy 385.009828 -8.272642) (xy 385.042706 -8.166058) (xy 385.067528 -8.057314)
			(xy 385.084154 -7.947019) (xy 385.092491 -7.83579) (xy 385.092956 -7.78002) (xy 385.092956 0.40005)
			(xy 385.093451 0.470432) (xy 385.101346 0.610973) (xy 385.117109 0.750851) (xy 385.14069 0.889625)
			(xy 385.172015 1.026859) (xy 385.210985 1.16212) (xy 385.257478 1.294984) (xy 385.311348 1.425032)
			(xy 385.372424 1.551855) (xy 385.440515 1.675053) (xy 385.515407 1.79424) (xy 385.596863 1.909041)
			(xy 385.684628 2.019094) (xy 385.778426 2.124052) (xy 385.877961 2.223587) (xy 385.98292 2.317383)
			(xy 386.092974 2.405148) (xy 386.207775 2.486603) (xy 386.326962 2.561494) (xy 386.450161 2.629584)
			(xy 386.576985 2.69066) (xy 386.707033 2.744528) (xy 386.839897 2.79102) (xy 386.975158 2.829989)
			(xy 387.112392 2.861313) (xy 387.251166 2.884893) (xy 387.391045 2.900655) (xy 387.531586 2.908549)
			(xy 387.601968 2.909062) (xy 456.202034 2.909062) (xy 456.272416 2.908567) (xy 456.412959 2.900673)
			(xy 456.552838 2.884911) (xy 456.691613 2.861331) (xy 456.828848 2.830006) (xy 456.96411 2.791037)
			(xy 457.096975 2.744544) (xy 457.227024 2.690676) (xy 457.353848 2.6296) (xy 457.477048 2.561509)
			(xy 457.596236 2.486618) (xy 457.711038 2.405161) (xy 457.821092 2.317396) (xy 457.926052 2.223599)
			(xy 458.025588 2.124064) (xy 458.119386 2.019104) (xy 458.207152 1.909051) (xy 458.288609 1.79425)
			(xy 458.363501 1.675062) (xy 458.431592 1.551862) (xy 458.492669 1.425039) (xy 458.546539 1.29499)
			(xy 458.593032 1.162126) (xy 458.632002 1.026863) (xy 458.663327 0.889629) (xy 458.686909 0.750854)
			(xy 458.702672 0.610975) (xy 458.710567 0.470432) (xy 458.711046 0.40005) (xy 458.711046 -4.844596)
			(xy 464.704165 -4.844596) (xy 464.704165 -4.715456) (xy 464.712115 -4.586561) (xy 464.727985 -4.458401)
			(xy 464.751714 -4.33146) (xy 464.783213 -4.206221) (xy 464.822362 -4.083158) (xy 464.869013 -3.962739)
			(xy 464.922988 -3.84542) (xy 464.984083 -3.731646) (xy 465.052066 -3.621849) (xy 465.12668 -3.516446)
			(xy 465.207641 -3.415836) (xy 465.294641 -3.320401) (xy 465.387352 -3.230502) (xy 465.485422 -3.146481)
			(xy 465.588477 -3.068657) (xy 465.696128 -2.997325) (xy 465.807967 -2.932755) (xy 465.923568 -2.875193)
			(xy 466.042493 -2.824856) (xy 466.164292 -2.781936) (xy 466.288502 -2.746595) (xy 466.414651 -2.718968)
			(xy 466.542263 -2.699159) (xy 466.670852 -2.687243) (xy 466.79993 -2.683267) (xy 466.929008 -2.687243)
			(xy 467.057597 -2.699159) (xy 467.185209 -2.718968) (xy 467.311358 -2.746595) (xy 467.435568 -2.781936)
			(xy 467.557367 -2.824856) (xy 467.676292 -2.875193) (xy 467.791893 -2.932755) (xy 467.903732 -2.997325)
			(xy 468.011383 -3.068657) (xy 468.114438 -3.146481) (xy 468.212508 -3.230502) (xy 468.305219 -3.320401)
			(xy 468.392219 -3.415836) (xy 468.47318 -3.516446) (xy 468.547794 -3.621849) (xy 468.615777 -3.731646)
			(xy 468.676872 -3.84542) (xy 468.730847 -3.962739) (xy 468.777498 -4.083158) (xy 468.816647 -4.206221)
			(xy 468.848146 -4.33146) (xy 468.871875 -4.458401) (xy 468.887745 -4.586561) (xy 468.895695 -4.715456)
			(xy 468.896192 -4.780026) (xy 468.895695 -4.844596) (xy 468.887745 -4.973491) (xy 468.871875 -5.101651)
			(xy 468.848146 -5.228592) (xy 468.816647 -5.353831) (xy 468.777498 -5.476894) (xy 468.730847 -5.597313)
			(xy 468.676872 -5.714632) (xy 468.615777 -5.828406) (xy 468.547794 -5.938203) (xy 468.47318 -6.043606)
			(xy 468.392219 -6.144216) (xy 468.305219 -6.239651) (xy 468.212508 -6.32955) (xy 468.114438 -6.413571)
			(xy 468.011383 -6.491395) (xy 467.903732 -6.562727) (xy 467.791893 -6.627297) (xy 467.676292 -6.684859)
			(xy 467.557367 -6.735196) (xy 467.435568 -6.778116) (xy 467.311358 -6.813457) (xy 467.185209 -6.841084)
			(xy 467.057597 -6.860893) (xy 466.929008 -6.872809) (xy 466.79993 -6.876786) (xy 466.670852 -6.872809)
			(xy 466.542263 -6.860893) (xy 466.414651 -6.841084) (xy 466.288502 -6.813457) (xy 466.164292 -6.778116)
			(xy 466.042493 -6.735196) (xy 465.923568 -6.684859) (xy 465.807967 -6.627297) (xy 465.696128 -6.562727)
			(xy 465.588477 -6.491395) (xy 465.485422 -6.413571) (xy 465.387352 -6.32955) (xy 465.294641 -6.239651)
			(xy 465.207641 -6.144216) (xy 465.12668 -6.043606) (xy 465.052066 -5.938203) (xy 464.984083 -5.828406)
			(xy 464.922988 -5.714632) (xy 464.869013 -5.597313) (xy 464.822362 -5.476894) (xy 464.783213 -5.353831)
			(xy 464.751714 -5.228592) (xy 464.727985 -5.101651) (xy 464.712115 -4.973491) (xy 464.704165 -4.844596)
			(xy 458.711046 -4.844596) (xy 458.711046 -7.78002) (xy 458.711555 -7.835789) (xy 458.719892 -7.947014)
			(xy 458.736517 -8.057305) (xy 458.761338 -8.166046) (xy 458.794216 -8.272628) (xy 458.834967 -8.376454)
			(xy 458.883362 -8.476945) (xy 458.939132 -8.573538) (xy 459.001965 -8.665694) (xy 459.071509 -8.752896)
			(xy 459.147375 -8.834658) (xy 459.229138 -8.910521) (xy 459.316343 -8.980062) (xy 459.4085 -9.042892)
			(xy 459.505096 -9.098659) (xy 459.605588 -9.147052) (xy 459.709416 -9.187799) (xy 459.815999 -9.220674)
			(xy 459.92474 -9.245491) (xy 460.035032 -9.262113) (xy 460.146257 -9.270446) (xy 460.202026 -9.271)
			(xy 469.799924 -9.271) (xy 469.855693 -9.270478) (xy 469.966918 -9.262141) (xy 470.07721 -9.245516)
			(xy 470.18595 -9.220695) (xy 470.292532 -9.187817) (xy 470.396359 -9.147067) (xy 470.49685 -9.098672)
			(xy 470.593444 -9.042903) (xy 470.685601 -8.980071) (xy 470.772804 -8.910528) (xy 470.854566 -8.834664)
			(xy 470.930431 -8.752901) (xy 470.999974 -8.665697) (xy 471.062805 -8.573541) (xy 471.118574 -8.476947)
			(xy 471.166969 -8.376455) (xy 471.207719 -8.272628) (xy 471.240596 -8.166046) (xy 471.265416 -8.057306)
			(xy 471.282041 -7.947014) (xy 471.290378 -7.835789) (xy 471.290904 -7.78002) (xy 471.290904 10.40003)
			(xy 471.290381 10.455799) (xy 471.282044 10.567024) (xy 471.265419 10.677315) (xy 471.240598 10.786055)
			(xy 471.20772 10.892637) (xy 471.16697 10.996464) (xy 471.118574 11.096955) (xy 471.062805 11.193548)
			(xy 470.999973 11.285705) (xy 470.930431 11.372908) (xy 470.854566 11.45467) (xy 470.772803 11.530534)
			(xy 470.6856 11.600077) (xy 470.593443 11.662908) (xy 470.49685 11.718677) (xy 470.396358 11.767072)
			(xy 470.292531 11.807822) (xy 470.18595 11.840699) (xy 470.077209 11.86552) (xy 469.966918 11.882145)
			(xy 469.855693 11.890482) (xy 469.799924 11.89101) (xy 1.999996 11.89101) (xy 1.944227 11.890488)
			(xy 1.833001 11.882153) (xy 1.722709 11.865529) (xy 1.613968 11.840709) (xy 1.507385 11.807832) (xy 1.403558 11.767083)
			(xy 1.303066 11.718688) (xy 1.206471 11.662919) (xy 1.114314 11.600087) (xy 1.027111 11.530545) (xy 0.945348 11.454679)
			(xy 0.869483 11.372916) (xy 0.79994 11.285712) (xy 0.737109 11.193555) (xy 0.68134 11.096961) (xy 0.632946 10.996469)
			(xy 0.592196 10.892641) (xy 0.55932 10.786058) (xy 0.534501 10.677317) (xy 0.517877 10.567025) (xy 0.509541 10.455799)
			(xy 0.509016 10.40003) (xy 0.509016 9.916973) (xy 385.651997 9.916973) (xy 385.651997 10.002723)
			(xy 385.659909 10.088106) (xy 385.675665 10.172396) (xy 385.699132 10.254872) (xy 385.730108 10.334831)
			(xy 385.76833 10.411591) (xy 385.813471 10.484497) (xy 385.865147 10.552926) (xy 385.922916 10.616296)
			(xy 385.986286 10.674065) (xy 386.054715 10.725741) (xy 386.127621 10.770882) (xy 386.204381 10.809104)
			(xy 386.28434 10.84008) (xy 386.366816 10.863547) (xy 386.451106 10.879303) (xy 386.536489 10.887215)
			(xy 386.622239 10.887215) (xy 386.707622 10.879303) (xy 386.791912 10.863547) (xy 386.874388 10.84008)
			(xy 386.954347 10.809104) (xy 387.031107 10.770882) (xy 387.104013 10.725741) (xy 387.172442 10.674065)
			(xy 387.235812 10.616296) (xy 387.293581 10.552926) (xy 387.345257 10.484497) (xy 387.390398 10.411591)
			(xy 387.42862 10.334831) (xy 387.459596 10.254872) (xy 387.483063 10.172396) (xy 387.498819 10.088106)
			(xy 387.506731 10.002723) (xy 387.507226 9.959848) (xy 387.506731 9.916973) (xy 392.001997 9.916973)
			(xy 392.001997 10.002723) (xy 392.009909 10.088106) (xy 392.025665 10.172396) (xy 392.049132 10.254872)
			(xy 392.080108 10.334831) (xy 392.11833 10.411591) (xy 392.163471 10.484497) (xy 392.215147 10.552926)
			(xy 392.272916 10.616296) (xy 392.336286 10.674065) (xy 392.404715 10.725741) (xy 392.477621 10.770882)
			(xy 392.554381 10.809104) (xy 392.63434 10.84008) (xy 392.716816 10.863547) (xy 392.801106 10.879303)
			(xy 392.886489 10.887215) (xy 392.972239 10.887215) (xy 393.057622 10.879303) (xy 393.141912 10.863547)
			(xy 393.224388 10.84008) (xy 393.304347 10.809104) (xy 393.381107 10.770882) (xy 393.454013 10.725741)
			(xy 393.522442 10.674065) (xy 393.585812 10.616296) (xy 393.643581 10.552926) (xy 393.695257 10.484497)
			(xy 393.740398 10.411591) (xy 393.77862 10.334831) (xy 393.809596 10.254872) (xy 393.833063 10.172396)
			(xy 393.848819 10.088106) (xy 393.856731 10.002723) (xy 393.857226 9.959848) (xy 393.856731 9.916973)
			(xy 436.390783 9.916973) (xy 436.390783 10.002723) (xy 436.398695 10.088106) (xy 436.414451 10.172396)
			(xy 436.437918 10.254872) (xy 436.468894 10.334831) (xy 436.507116 10.411591) (xy 436.552257 10.484497)
			(xy 436.603933 10.552926) (xy 436.661702 10.616296) (xy 436.725072 10.674065) (xy 436.793501 10.725741)
			(xy 436.866407 10.770882) (xy 436.943167 10.809104) (xy 437.023126 10.84008) (xy 437.105602 10.863547)
			(xy 437.189892 10.879303) (xy 437.275275 10.887215) (xy 437.361025 10.887215) (xy 437.446408 10.879303)
			(xy 437.530698 10.863547) (xy 437.613174 10.84008) (xy 437.693133 10.809104) (xy 437.769893 10.770882)
			(xy 437.842799 10.725741) (xy 437.911228 10.674065) (xy 437.974598 10.616296) (xy 438.032367 10.552926)
			(xy 438.084043 10.484497) (xy 438.129184 10.411591) (xy 438.167406 10.334831) (xy 438.198382 10.254872)
			(xy 438.221849 10.172396) (xy 438.237605 10.088106) (xy 438.245517 10.002723) (xy 438.246012 9.959848)
			(xy 438.245517 9.916973) (xy 442.740783 9.916973) (xy 442.740783 10.002723) (xy 442.748695 10.088106)
			(xy 442.764451 10.172396) (xy 442.787918 10.254872) (xy 442.818894 10.334831) (xy 442.857116 10.411591)
			(xy 442.902257 10.484497) (xy 442.953933 10.552926) (xy 443.011702 10.616296) (xy 443.075072 10.674065)
			(xy 443.143501 10.725741) (xy 443.216407 10.770882) (xy 443.293167 10.809104) (xy 443.373126 10.84008)
			(xy 443.455602 10.863547) (xy 443.539892 10.879303) (xy 443.625275 10.887215) (xy 443.711025 10.887215)
			(xy 443.796408 10.879303) (xy 443.880698 10.863547) (xy 443.963174 10.84008) (xy 444.043133 10.809104)
			(xy 444.119893 10.770882) (xy 444.192799 10.725741) (xy 444.261228 10.674065) (xy 444.324598 10.616296)
			(xy 444.382367 10.552926) (xy 444.434043 10.484497) (xy 444.479184 10.411591) (xy 444.517406 10.334831)
			(xy 444.548382 10.254872) (xy 444.571849 10.172396) (xy 444.587605 10.088106) (xy 444.595517 10.002723)
			(xy 444.596012 9.959848) (xy 444.595517 9.916973) (xy 444.587605 9.83159) (xy 444.571849 9.7473)
			(xy 444.548382 9.664824) (xy 444.517406 9.584865) (xy 444.479184 9.508105) (xy 444.434043 9.435199)
			(xy 444.382367 9.36677) (xy 444.324598 9.3034) (xy 444.261228 9.245631) (xy 444.192799 9.193955)
			(xy 444.119893 9.148814) (xy 444.043133 9.110592) (xy 443.963174 9.079616) (xy 443.880698 9.056149)
			(xy 443.796408 9.040393) (xy 443.711025 9.032481) (xy 443.625275 9.032481) (xy 443.539892 9.040393)
			(xy 443.455602 9.056149) (xy 443.373126 9.079616) (xy 443.293167 9.110592) (xy 443.216407 9.148814)
			(xy 443.143501 9.193955) (xy 443.075072 9.245631) (xy 443.011702 9.3034) (xy 442.953933 9.36677)
			(xy 442.902257 9.435199) (xy 442.857116 9.508105) (xy 442.818894 9.584865) (xy 442.787918 9.664824)
			(xy 442.764451 9.7473) (xy 442.748695 9.83159) (xy 442.740783 9.916973) (xy 438.245517 9.916973)
			(xy 438.237605 9.83159) (xy 438.221849 9.7473) (xy 438.198382 9.664824) (xy 438.167406 9.584865)
			(xy 438.129184 9.508105) (xy 438.084043 9.435199) (xy 438.032367 9.36677) (xy 437.974598 9.3034)
			(xy 437.911228 9.245631) (xy 437.842799 9.193955) (xy 437.769893 9.148814) (xy 437.693133 9.110592)
			(xy 437.613174 9.079616) (xy 437.530698 9.056149) (xy 437.446408 9.040393) (xy 437.361025 9.032481)
			(xy 437.275275 9.032481) (xy 437.189892 9.040393) (xy 437.105602 9.056149) (xy 437.023126 9.079616)
			(xy 436.943167 9.110592) (xy 436.866407 9.148814) (xy 436.793501 9.193955) (xy 436.725072 9.245631)
			(xy 436.661702 9.3034) (xy 436.603933 9.36677) (xy 436.552257 9.435199) (xy 436.507116 9.508105)
			(xy 436.468894 9.584865) (xy 436.437918 9.664824) (xy 436.414451 9.7473) (xy 436.398695 9.83159)
			(xy 436.390783 9.916973) (xy 393.856731 9.916973) (xy 393.848819 9.83159) (xy 393.833063 9.7473)
			(xy 393.809596 9.664824) (xy 393.77862 9.584865) (xy 393.740398 9.508105) (xy 393.695257 9.435199)
			(xy 393.643581 9.36677) (xy 393.585812 9.3034) (xy 393.522442 9.245631) (xy 393.454013 9.193955)
			(xy 393.381107 9.148814) (xy 393.304347 9.110592) (xy 393.224388 9.079616) (xy 393.141912 9.056149)
			(xy 393.057622 9.040393) (xy 392.972239 9.032481) (xy 392.886489 9.032481) (xy 392.801106 9.040393)
			(xy 392.716816 9.056149) (xy 392.63434 9.079616) (xy 392.554381 9.110592) (xy 392.477621 9.148814)
			(xy 392.404715 9.193955) (xy 392.336286 9.245631) (xy 392.272916 9.3034) (xy 392.215147 9.36677)
			(xy 392.163471 9.435199) (xy 392.11833 9.508105) (xy 392.080108 9.584865) (xy 392.049132 9.664824)
			(xy 392.025665 9.7473) (xy 392.009909 9.83159) (xy 392.001997 9.916973) (xy 387.506731 9.916973)
			(xy 387.498819 9.83159) (xy 387.483063 9.7473) (xy 387.459596 9.664824) (xy 387.42862 9.584865) (xy 387.390398 9.508105)
			(xy 387.345257 9.435199) (xy 387.293581 9.36677) (xy 387.235812 9.3034) (xy 387.172442 9.245631)
			(xy 387.104013 9.193955) (xy 387.031107 9.148814) (xy 386.954347 9.110592) (xy 386.874388 9.079616)
			(xy 386.791912 9.056149) (xy 386.707622 9.040393) (xy 386.622239 9.032481) (xy 386.536489 9.032481)
			(xy 386.451106 9.040393) (xy 386.366816 9.056149) (xy 386.28434 9.079616) (xy 386.204381 9.110592)
			(xy 386.127621 9.148814) (xy 386.054715 9.193955) (xy 385.986286 9.245631) (xy 385.922916 9.3034)
			(xy 385.865147 9.36677) (xy 385.813471 9.435199) (xy 385.76833 9.508105) (xy 385.730108 9.584865)
			(xy 385.699132 9.664824) (xy 385.675665 9.7473) (xy 385.659909 9.83159) (xy 385.651997 9.916973)
			(xy 0.509016 9.916973) (xy 0.509016 7.335466) (xy 2.904225 7.335466) (xy 2.904225 7.464606) (xy 2.912175 7.593501)
			(xy 2.928045 7.721661) (xy 2.951774 7.848602) (xy 2.983273 7.973841) (xy 3.022422 8.096904) (xy 3.069073 8.217323)
			(xy 3.123048 8.334642) (xy 3.184143 8.448416) (xy 3.252126 8.558213) (xy 3.32674 8.663616) (xy 3.407701 8.764226)
			(xy 3.494701 8.859661) (xy 3.587412 8.94956) (xy 3.685482 9.033581) (xy 3.788537 9.111405) (xy 3.896188 9.182737)
			(xy 4.008027 9.247307) (xy 4.123628 9.304869) (xy 4.242553 9.355206) (xy 4.364352 9.398126) (xy 4.488562 9.433467)
			(xy 4.614711 9.461094) (xy 4.742323 9.480903) (xy 4.870912 9.492819) (xy 4.99999 9.496796) (xy 5.129068 9.492819)
			(xy 5.257657 9.480903) (xy 5.385269 9.461094) (xy 5.511418 9.433467) (xy 5.635628 9.398126) (xy 5.757427 9.355206)
			(xy 5.876352 9.304869) (xy 5.991953 9.247307) (xy 6.103792 9.182737) (xy 6.211443 9.111405) (xy 6.314498 9.033581)
			(xy 6.412568 8.94956) (xy 6.505279 8.859661) (xy 6.51416 8.849919) (xy 208.661241 8.849919) (xy 208.661241 8.935669)
			(xy 208.669153 9.021052) (xy 208.684909 9.105342) (xy 208.708376 9.187818) (xy 208.739352 9.267777)
			(xy 208.777574 9.344537) (xy 208.822715 9.417443) (xy 208.874391 9.485872) (xy 208.93216 9.549242)
			(xy 208.99553 9.607011) (xy 209.063959 9.658687) (xy 209.136865 9.703828) (xy 209.213625 9.74205)
			(xy 209.293584 9.773026) (xy 209.37606 9.796493) (xy 209.46035 9.812249) (xy 209.545733 9.820161)
			(xy 209.631483 9.820161) (xy 209.716866 9.812249) (xy 209.801156 9.796493) (xy 209.883632 9.773026)
			(xy 209.963591 9.74205) (xy 210.040351 9.703828) (xy 210.113257 9.658687) (xy 210.181686 9.607011)
			(xy 210.245056 9.549242) (xy 210.302825 9.485872) (xy 210.354501 9.417443) (xy 210.399642 9.344537)
			(xy 210.437864 9.267777) (xy 210.46884 9.187818) (xy 210.492307 9.105342) (xy 210.508063 9.021052)
			(xy 210.515975 8.935669) (xy 210.51647 8.892794) (xy 210.515975 8.849919) (xy 215.011241 8.849919)
			(xy 215.011241 8.935669) (xy 215.019153 9.021052) (xy 215.034909 9.105342) (xy 215.058376 9.187818)
			(xy 215.089352 9.267777) (xy 215.127574 9.344537) (xy 215.172715 9.417443) (xy 215.224391 9.485872)
			(xy 215.28216 9.549242) (xy 215.34553 9.607011) (xy 215.413959 9.658687) (xy 215.486865 9.703828)
			(xy 215.563625 9.74205) (xy 215.643584 9.773026) (xy 215.72606 9.796493) (xy 215.81035 9.812249)
			(xy 215.895733 9.820161) (xy 215.981483 9.820161) (xy 216.066866 9.812249) (xy 216.151156 9.796493)
			(xy 216.233632 9.773026) (xy 216.313591 9.74205) (xy 216.390351 9.703828) (xy 216.463257 9.658687)
			(xy 216.531686 9.607011) (xy 216.595056 9.549242) (xy 216.652825 9.485872) (xy 216.704501 9.417443)
			(xy 216.749642 9.344537) (xy 216.787864 9.267777) (xy 216.81884 9.187818) (xy 216.842307 9.105342)
			(xy 216.858063 9.021052) (xy 216.865975 8.935669) (xy 216.86647 8.892794) (xy 216.865975 8.849919)
			(xy 296.143921 8.849919) (xy 296.143921 8.935669) (xy 296.151833 9.021052) (xy 296.167589 9.105342)
			(xy 296.191056 9.187818) (xy 296.222032 9.267777) (xy 296.260254 9.344537) (xy 296.305395 9.417443)
			(xy 296.357071 9.485872) (xy 296.41484 9.549242) (xy 296.47821 9.607011) (xy 296.546639 9.658687)
			(xy 296.619545 9.703828) (xy 296.696305 9.74205) (xy 296.776264 9.773026) (xy 296.85874 9.796493)
			(xy 296.94303 9.812249) (xy 297.028413 9.820161) (xy 297.114163 9.820161) (xy 297.199546 9.812249)
			(xy 297.283836 9.796493) (xy 297.366312 9.773026) (xy 297.446271 9.74205) (xy 297.523031 9.703828)
			(xy 297.595937 9.658687) (xy 297.664366 9.607011) (xy 297.727736 9.549242) (xy 297.785505 9.485872)
			(xy 297.837181 9.417443) (xy 297.882322 9.344537) (xy 297.920544 9.267777) (xy 297.95152 9.187818)
			(xy 297.974987 9.105342) (xy 297.990743 9.021052) (xy 297.998655 8.935669) (xy 297.99915 8.892794)
			(xy 297.998655 8.849919) (xy 302.493921 8.849919) (xy 302.493921 8.935669) (xy 302.501833 9.021052)
			(xy 302.517589 9.105342) (xy 302.541056 9.187818) (xy 302.572032 9.267777) (xy 302.610254 9.344537)
			(xy 302.655395 9.417443) (xy 302.707071 9.485872) (xy 302.76484 9.549242) (xy 302.82821 9.607011)
			(xy 302.896639 9.658687) (xy 302.969545 9.703828) (xy 303.046305 9.74205) (xy 303.126264 9.773026)
			(xy 303.20874 9.796493) (xy 303.29303 9.812249) (xy 303.378413 9.820161) (xy 303.464163 9.820161)
			(xy 303.549546 9.812249) (xy 303.633836 9.796493) (xy 303.716312 9.773026) (xy 303.796271 9.74205)
			(xy 303.873031 9.703828) (xy 303.945937 9.658687) (xy 304.014366 9.607011) (xy 304.077736 9.549242)
			(xy 304.135505 9.485872) (xy 304.187181 9.417443) (xy 304.232322 9.344537) (xy 304.270544 9.267777)
			(xy 304.30152 9.187818) (xy 304.324987 9.105342) (xy 304.340743 9.021052) (xy 304.348655 8.935669)
			(xy 304.34915 8.892794) (xy 304.348655 8.849919) (xy 311.155321 8.849919) (xy 311.155321 8.935669)
			(xy 311.163233 9.021052) (xy 311.178989 9.105342) (xy 311.202456 9.187818) (xy 311.233432 9.267777)
			(xy 311.271654 9.344537) (xy 311.316795 9.417443) (xy 311.368471 9.485872) (xy 311.42624 9.549242)
			(xy 311.48961 9.607011) (xy 311.558039 9.658687) (xy 311.630945 9.703828) (xy 311.707705 9.74205)
			(xy 311.787664 9.773026) (xy 311.87014 9.796493) (xy 311.95443 9.812249) (xy 312.039813 9.820161)
			(xy 312.125563 9.820161) (xy 312.210946 9.812249) (xy 312.295236 9.796493) (xy 312.377712 9.773026)
			(xy 312.457671 9.74205) (xy 312.534431 9.703828) (xy 312.607337 9.658687) (xy 312.675766 9.607011)
			(xy 312.739136 9.549242) (xy 312.796905 9.485872) (xy 312.848581 9.417443) (xy 312.893722 9.344537)
			(xy 312.931944 9.267777) (xy 312.96292 9.187818) (xy 312.986387 9.105342) (xy 313.002143 9.021052)
			(xy 313.010055 8.935669) (xy 313.01055 8.892794) (xy 313.010055 8.849919) (xy 317.505321 8.849919)
			(xy 317.505321 8.935669) (xy 317.513233 9.021052) (xy 317.528989 9.105342) (xy 317.552456 9.187818)
			(xy 317.583432 9.267777) (xy 317.621654 9.344537) (xy 317.666795 9.417443) (xy 317.718471 9.485872)
			(xy 317.77624 9.549242) (xy 317.83961 9.607011) (xy 317.908039 9.658687) (xy 317.980945 9.703828)
			(xy 318.057705 9.74205) (xy 318.137664 9.773026) (xy 318.22014 9.796493) (xy 318.30443 9.812249)
			(xy 318.389813 9.820161) (xy 318.475563 9.820161) (xy 318.560946 9.812249) (xy 318.645236 9.796493)
			(xy 318.727712 9.773026) (xy 318.807671 9.74205) (xy 318.884431 9.703828) (xy 318.957337 9.658687)
			(xy 319.025766 9.607011) (xy 319.089136 9.549242) (xy 319.146905 9.485872) (xy 319.198581 9.417443)
			(xy 319.243722 9.344537) (xy 319.281944 9.267777) (xy 319.31292 9.187818) (xy 319.336387 9.105342)
			(xy 319.352143 9.021052) (xy 319.360055 8.935669) (xy 319.36055 8.892794) (xy 319.360055 8.849919)
			(xy 361.894107 8.849919) (xy 361.894107 8.935669) (xy 361.902019 9.021052) (xy 361.917775 9.105342)
			(xy 361.941242 9.187818) (xy 361.972218 9.267777) (xy 362.01044 9.344537) (xy 362.055581 9.417443)
			(xy 362.107257 9.485872) (xy 362.165026 9.549242) (xy 362.228396 9.607011) (xy 362.296825 9.658687)
			(xy 362.369731 9.703828) (xy 362.446491 9.74205) (xy 362.52645 9.773026) (xy 362.608926 9.796493)
			(xy 362.693216 9.812249) (xy 362.778599 9.820161) (xy 362.864349 9.820161) (xy 362.949732 9.812249)
			(xy 363.034022 9.796493) (xy 363.116498 9.773026) (xy 363.196457 9.74205) (xy 363.273217 9.703828)
			(xy 363.346123 9.658687) (xy 363.414552 9.607011) (xy 363.477922 9.549242) (xy 363.535691 9.485872)
			(xy 363.587367 9.417443) (xy 363.632508 9.344537) (xy 363.67073 9.267777) (xy 363.701706 9.187818)
			(xy 363.725173 9.105342) (xy 363.740929 9.021052) (xy 363.748841 8.935669) (xy 363.749336 8.892794)
			(xy 363.748841 8.849919) (xy 368.244107 8.849919) (xy 368.244107 8.935669) (xy 368.252019 9.021052)
			(xy 368.267775 9.105342) (xy 368.291242 9.187818) (xy 368.322218 9.267777) (xy 368.36044 9.344537)
			(xy 368.405581 9.417443) (xy 368.457257 9.485872) (xy 368.515026 9.549242) (xy 368.578396 9.607011)
			(xy 368.646825 9.658687) (xy 368.719731 9.703828) (xy 368.796491 9.74205) (xy 368.87645 9.773026)
			(xy 368.958926 9.796493) (xy 369.043216 9.812249) (xy 369.128599 9.820161) (xy 369.214349 9.820161)
			(xy 369.299732 9.812249) (xy 369.384022 9.796493) (xy 369.466498 9.773026) (xy 369.546457 9.74205)
			(xy 369.623217 9.703828) (xy 369.696123 9.658687) (xy 369.764552 9.607011) (xy 369.827922 9.549242)
			(xy 369.885691 9.485872) (xy 369.937367 9.417443) (xy 369.982508 9.344537) (xy 370.02073 9.267777)
			(xy 370.051706 9.187818) (xy 370.075173 9.105342) (xy 370.090929 9.021052) (xy 370.098841 8.935669)
			(xy 370.099336 8.892794) (xy 370.098841 8.849919) (xy 370.090929 8.764536) (xy 370.075173 8.680246)
			(xy 370.051706 8.59777) (xy 370.02073 8.517811) (xy 369.982508 8.441051) (xy 369.937367 8.368145)
			(xy 369.885691 8.299716) (xy 369.827922 8.236346) (xy 369.764552 8.178577) (xy 369.696123 8.126901)
			(xy 369.623217 8.08176) (xy 369.546457 8.043538) (xy 369.466498 8.012562) (xy 369.384022 7.989095)
			(xy 369.299732 7.973339) (xy 369.214349 7.965427) (xy 369.128599 7.965427) (xy 369.043216 7.973339)
			(xy 368.958926 7.989095) (xy 368.87645 8.012562) (xy 368.796491 8.043538) (xy 368.719731 8.08176)
			(xy 368.646825 8.126901) (xy 368.578396 8.178577) (xy 368.515026 8.236346) (xy 368.457257 8.299716)
			(xy 368.405581 8.368145) (xy 368.36044 8.441051) (xy 368.322218 8.517811) (xy 368.291242 8.59777)
			(xy 368.267775 8.680246) (xy 368.252019 8.764536) (xy 368.244107 8.849919) (xy 363.748841 8.849919)
			(xy 363.740929 8.764536) (xy 363.725173 8.680246) (xy 363.701706 8.59777) (xy 363.67073 8.517811)
			(xy 363.632508 8.441051) (xy 363.587367 8.368145) (xy 363.535691 8.299716) (xy 363.477922 8.236346)
			(xy 363.414552 8.178577) (xy 363.346123 8.126901) (xy 363.273217 8.08176) (xy 363.196457 8.043538)
			(xy 363.116498 8.012562) (xy 363.034022 7.989095) (xy 362.949732 7.973339) (xy 362.864349 7.965427)
			(xy 362.778599 7.965427) (xy 362.693216 7.973339) (xy 362.608926 7.989095) (xy 362.52645 8.012562)
			(xy 362.446491 8.043538) (xy 362.369731 8.08176) (xy 362.296825 8.126901) (xy 362.228396 8.178577)
			(xy 362.165026 8.236346) (xy 362.107257 8.299716) (xy 362.055581 8.368145) (xy 362.01044 8.441051)
			(xy 361.972218 8.517811) (xy 361.941242 8.59777) (xy 361.917775 8.680246) (xy 361.902019 8.764536)
			(xy 361.894107 8.849919) (xy 319.360055 8.849919) (xy 319.352143 8.764536) (xy 319.336387 8.680246)
			(xy 319.31292 8.59777) (xy 319.281944 8.517811) (xy 319.243722 8.441051) (xy 319.198581 8.368145)
			(xy 319.146905 8.299716) (xy 319.089136 8.236346) (xy 319.025766 8.178577) (xy 318.957337 8.126901)
			(xy 318.884431 8.08176) (xy 318.807671 8.043538) (xy 318.727712 8.012562) (xy 318.645236 7.989095)
			(xy 318.560946 7.973339) (xy 318.475563 7.965427) (xy 318.389813 7.965427) (xy 318.30443 7.973339)
			(xy 318.22014 7.989095) (xy 318.137664 8.012562) (xy 318.057705 8.043538) (xy 317.980945 8.08176)
			(xy 317.908039 8.126901) (xy 317.83961 8.178577) (xy 317.77624 8.236346) (xy 317.718471 8.299716)
			(xy 317.666795 8.368145) (xy 317.621654 8.441051) (xy 317.583432 8.517811) (xy 317.552456 8.59777)
			(xy 317.528989 8.680246) (xy 317.513233 8.764536) (xy 317.505321 8.849919) (xy 313.010055 8.849919)
			(xy 313.002143 8.764536) (xy 312.986387 8.680246) (xy 312.96292 8.59777) (xy 312.931944 8.517811)
			(xy 312.893722 8.441051) (xy 312.848581 8.368145) (xy 312.796905 8.299716) (xy 312.739136 8.236346)
			(xy 312.675766 8.178577) (xy 312.607337 8.126901) (xy 312.534431 8.08176) (xy 312.457671 8.043538)
			(xy 312.377712 8.012562) (xy 312.295236 7.989095) (xy 312.210946 7.973339) (xy 312.125563 7.965427)
			(xy 312.039813 7.965427) (xy 311.95443 7.973339) (xy 311.87014 7.989095) (xy 311.787664 8.012562)
			(xy 311.707705 8.043538) (xy 311.630945 8.08176) (xy 311.558039 8.126901) (xy 311.48961 8.178577)
			(xy 311.42624 8.236346) (xy 311.368471 8.299716) (xy 311.316795 8.368145) (xy 311.271654 8.441051)
			(xy 311.233432 8.517811) (xy 311.202456 8.59777) (xy 311.178989 8.680246) (xy 311.163233 8.764536)
			(xy 311.155321 8.849919) (xy 304.348655 8.849919) (xy 304.340743 8.764536) (xy 304.324987 8.680246)
			(xy 304.30152 8.59777) (xy 304.270544 8.517811) (xy 304.232322 8.441051) (xy 304.187181 8.368145)
			(xy 304.135505 8.299716) (xy 304.077736 8.236346) (xy 304.014366 8.178577) (xy 303.945937 8.126901)
			(xy 303.873031 8.08176) (xy 303.796271 8.043538) (xy 303.716312 8.012562) (xy 303.633836 7.989095)
			(xy 303.549546 7.973339) (xy 303.464163 7.965427) (xy 303.378413 7.965427) (xy 303.29303 7.973339)
			(xy 303.20874 7.989095) (xy 303.126264 8.012562) (xy 303.046305 8.043538) (xy 302.969545 8.08176)
			(xy 302.896639 8.126901) (xy 302.82821 8.178577) (xy 302.76484 8.236346) (xy 302.707071 8.299716)
			(xy 302.655395 8.368145) (xy 302.610254 8.441051) (xy 302.572032 8.517811) (xy 302.541056 8.59777)
			(xy 302.517589 8.680246) (xy 302.501833 8.764536) (xy 302.493921 8.849919) (xy 297.998655 8.849919)
			(xy 297.990743 8.764536) (xy 297.974987 8.680246) (xy 297.95152 8.59777) (xy 297.920544 8.517811)
			(xy 297.882322 8.441051) (xy 297.837181 8.368145) (xy 297.785505 8.299716) (xy 297.727736 8.236346)
			(xy 297.664366 8.178577) (xy 297.595937 8.126901) (xy 297.523031 8.08176) (xy 297.446271 8.043538)
			(xy 297.366312 8.012562) (xy 297.283836 7.989095) (xy 297.199546 7.973339) (xy 297.114163 7.965427)
			(xy 297.028413 7.965427) (xy 296.94303 7.973339) (xy 296.85874 7.989095) (xy 296.776264 8.012562)
			(xy 296.696305 8.043538) (xy 296.619545 8.08176) (xy 296.546639 8.126901) (xy 296.47821 8.178577)
			(xy 296.41484 8.236346) (xy 296.357071 8.299716) (xy 296.305395 8.368145) (xy 296.260254 8.441051)
			(xy 296.222032 8.517811) (xy 296.191056 8.59777) (xy 296.167589 8.680246) (xy 296.151833 8.764536)
			(xy 296.143921 8.849919) (xy 216.865975 8.849919) (xy 216.858063 8.764536) (xy 216.842307 8.680246)
			(xy 216.81884 8.59777) (xy 216.787864 8.517811) (xy 216.749642 8.441051) (xy 216.704501 8.368145)
			(xy 216.652825 8.299716) (xy 216.595056 8.236346) (xy 216.531686 8.178577) (xy 216.463257 8.126901)
			(xy 216.390351 8.08176) (xy 216.313591 8.043538) (xy 216.233632 8.012562) (xy 216.151156 7.989095)
			(xy 216.066866 7.973339) (xy 215.981483 7.965427) (xy 215.895733 7.965427) (xy 215.81035 7.973339)
			(xy 215.72606 7.989095) (xy 215.643584 8.012562) (xy 215.563625 8.043538) (xy 215.486865 8.08176)
			(xy 215.413959 8.126901) (xy 215.34553 8.178577) (xy 215.28216 8.236346) (xy 215.224391 8.299716)
			(xy 215.172715 8.368145) (xy 215.127574 8.441051) (xy 215.089352 8.517811) (xy 215.058376 8.59777)
			(xy 215.034909 8.680246) (xy 215.019153 8.764536) (xy 215.011241 8.849919) (xy 210.515975 8.849919)
			(xy 210.508063 8.764536) (xy 210.492307 8.680246) (xy 210.46884 8.59777) (xy 210.437864 8.517811)
			(xy 210.399642 8.441051) (xy 210.354501 8.368145) (xy 210.302825 8.299716) (xy 210.245056 8.236346)
			(xy 210.181686 8.178577) (xy 210.113257 8.126901) (xy 210.040351 8.08176) (xy 209.963591 8.043538)
			(xy 209.883632 8.012562) (xy 209.801156 7.989095) (xy 209.716866 7.973339) (xy 209.631483 7.965427)
			(xy 209.545733 7.965427) (xy 209.46035 7.973339) (xy 209.37606 7.989095) (xy 209.293584 8.012562)
			(xy 209.213625 8.043538) (xy 209.136865 8.08176) (xy 209.063959 8.126901) (xy 208.99553 8.178577)
			(xy 208.93216 8.236346) (xy 208.874391 8.299716) (xy 208.822715 8.368145) (xy 208.777574 8.441051)
			(xy 208.739352 8.517811) (xy 208.708376 8.59777) (xy 208.684909 8.680246) (xy 208.669153 8.764536)
			(xy 208.661241 8.849919) (xy 6.51416 8.849919) (xy 6.592279 8.764226) (xy 6.67324 8.663616) (xy 6.747854 8.558213)
			(xy 6.815837 8.448416) (xy 6.876932 8.334642) (xy 6.930907 8.217323) (xy 6.977558 8.096904) (xy 7.016707 7.973841)
			(xy 7.048206 7.848602) (xy 7.071935 7.721661) (xy 7.087805 7.593501) (xy 7.095755 7.464606) (xy 7.096252 7.400036)
			(xy 7.095755 7.335466) (xy 7.092973 7.290359) (xy 93.985575 7.290359) (xy 93.985575 7.376109) (xy 93.993487 7.461492)
			(xy 94.009243 7.545782) (xy 94.03271 7.628258) (xy 94.063686 7.708217) (xy 94.101908 7.784977) (xy 94.147049 7.857883)
			(xy 94.198725 7.926312) (xy 94.256494 7.989682) (xy 94.319864 8.047451) (xy 94.388293 8.099127) (xy 94.461199 8.144268)
			(xy 94.537959 8.18249) (xy 94.617918 8.213466) (xy 94.700394 8.236933) (xy 94.784684 8.252689) (xy 94.870067 8.260601)
			(xy 94.955817 8.260601) (xy 95.0412 8.252689) (xy 95.12549 8.236933) (xy 95.207966 8.213466) (xy 95.287925 8.18249)
			(xy 95.364685 8.144268) (xy 95.437591 8.099127) (xy 95.50602 8.047451) (xy 95.56939 7.989682) (xy 95.627159 7.926312)
			(xy 95.678835 7.857883) (xy 95.723976 7.784977) (xy 95.762198 7.708217) (xy 95.793174 7.628258) (xy 95.816641 7.545782)
			(xy 95.832397 7.461492) (xy 95.840309 7.376109) (xy 95.840804 7.333234) (xy 95.840309 7.290359) (xy 100.335575 7.290359)
			(xy 100.335575 7.376109) (xy 100.343487 7.461492) (xy 100.359243 7.545782) (xy 100.38271 7.628258)
			(xy 100.413686 7.708217) (xy 100.451908 7.784977) (xy 100.497049 7.857883) (xy 100.548725 7.926312)
			(xy 100.606494 7.989682) (xy 100.669864 8.047451) (xy 100.738293 8.099127) (xy 100.811199 8.144268)
			(xy 100.887959 8.18249) (xy 100.967918 8.213466) (xy 101.050394 8.236933) (xy 101.134684 8.252689)
			(xy 101.220067 8.260601) (xy 101.305817 8.260601) (xy 101.3912 8.252689) (xy 101.47549 8.236933)
			(xy 101.557966 8.213466) (xy 101.637925 8.18249) (xy 101.714685 8.144268) (xy 101.787591 8.099127)
			(xy 101.85602 8.047451) (xy 101.91939 7.989682) (xy 101.977159 7.926312) (xy 102.028835 7.857883)
			(xy 102.073976 7.784977) (xy 102.112198 7.708217) (xy 102.143174 7.628258) (xy 102.166641 7.545782)
			(xy 102.182397 7.461492) (xy 102.190309 7.376109) (xy 102.190804 7.333234) (xy 102.190309 7.290359)
			(xy 181.468255 7.290359) (xy 181.468255 7.376109) (xy 181.476167 7.461492) (xy 181.491923 7.545782)
			(xy 181.51539 7.628258) (xy 181.546366 7.708217) (xy 181.584588 7.784977) (xy 181.629729 7.857883)
			(xy 181.681405 7.926312) (xy 181.739174 7.989682) (xy 181.802544 8.047451) (xy 181.870973 8.099127)
			(xy 181.943879 8.144268) (xy 182.020639 8.18249) (xy 182.100598 8.213466) (xy 182.183074 8.236933)
			(xy 182.267364 8.252689) (xy 182.352747 8.260601) (xy 182.438497 8.260601) (xy 182.52388 8.252689)
			(xy 182.60817 8.236933) (xy 182.690646 8.213466) (xy 182.770605 8.18249) (xy 182.847365 8.144268)
			(xy 182.920271 8.099127) (xy 182.9887 8.047451) (xy 183.05207 7.989682) (xy 183.109839 7.926312)
			(xy 183.161515 7.857883) (xy 183.206656 7.784977) (xy 183.244878 7.708217) (xy 183.275854 7.628258)
			(xy 183.299321 7.545782) (xy 183.315077 7.461492) (xy 183.322989 7.376109) (xy 183.323484 7.333234)
			(xy 183.322989 7.290359) (xy 187.818255 7.290359) (xy 187.818255 7.376109) (xy 187.826167 7.461492)
			(xy 187.841923 7.545782) (xy 187.86539 7.628258) (xy 187.896366 7.708217) (xy 187.934588 7.784977)
			(xy 187.979729 7.857883) (xy 188.031405 7.926312) (xy 188.089174 7.989682) (xy 188.152544 8.047451)
			(xy 188.220973 8.099127) (xy 188.293879 8.144268) (xy 188.370639 8.18249) (xy 188.450598 8.213466)
			(xy 188.533074 8.236933) (xy 188.617364 8.252689) (xy 188.702747 8.260601) (xy 188.788497 8.260601)
			(xy 188.87388 8.252689) (xy 188.95817 8.236933) (xy 189.040646 8.213466) (xy 189.120605 8.18249)
			(xy 189.197365 8.144268) (xy 189.270271 8.099127) (xy 189.3387 8.047451) (xy 189.40207 7.989682)
			(xy 189.459839 7.926312) (xy 189.511515 7.857883) (xy 189.556656 7.784977) (xy 189.594878 7.708217)
			(xy 189.625854 7.628258) (xy 189.649321 7.545782) (xy 189.665077 7.461492) (xy 189.672989 7.376109)
			(xy 189.673484 7.333234) (xy 189.672989 7.290359) (xy 189.665077 7.204976) (xy 189.649321 7.120686)
			(xy 189.625854 7.03821) (xy 189.594878 6.958251) (xy 189.556656 6.881491) (xy 189.511515 6.808585)
			(xy 189.459839 6.740156) (xy 189.40207 6.676786) (xy 189.3387 6.619017) (xy 189.270271 6.567341)
			(xy 189.197365 6.5222) (xy 189.120605 6.483978) (xy 189.040646 6.453002) (xy 188.95817 6.429535)
			(xy 188.87388 6.413779) (xy 188.788497 6.405867) (xy 188.702747 6.405867) (xy 188.617364 6.413779)
			(xy 188.533074 6.429535) (xy 188.450598 6.453002) (xy 188.370639 6.483978) (xy 188.293879 6.5222)
			(xy 188.220973 6.567341) (xy 188.152544 6.619017) (xy 188.089174 6.676786) (xy 188.031405 6.740156)
			(xy 187.979729 6.808585) (xy 187.934588 6.881491) (xy 187.896366 6.958251) (xy 187.86539 7.03821)
			(xy 187.841923 7.120686) (xy 187.826167 7.204976) (xy 187.818255 7.290359) (xy 183.322989 7.290359)
			(xy 183.315077 7.204976) (xy 183.299321 7.120686) (xy 183.275854 7.03821) (xy 183.244878 6.958251)
			(xy 183.206656 6.881491) (xy 183.161515 6.808585) (xy 183.109839 6.740156) (xy 183.05207 6.676786)
			(xy 182.9887 6.619017) (xy 182.920271 6.567341) (xy 182.847365 6.5222) (xy 182.770605 6.483978) (xy 182.690646 6.453002)
			(xy 182.60817 6.429535) (xy 182.52388 6.413779) (xy 182.438497 6.405867) (xy 182.352747 6.405867)
			(xy 182.267364 6.413779) (xy 182.183074 6.429535) (xy 182.100598 6.453002) (xy 182.020639 6.483978)
			(xy 181.943879 6.5222) (xy 181.870973 6.567341) (xy 181.802544 6.619017) (xy 181.739174 6.676786)
			(xy 181.681405 6.740156) (xy 181.629729 6.808585) (xy 181.584588 6.881491) (xy 181.546366 6.958251)
			(xy 181.51539 7.03821) (xy 181.491923 7.120686) (xy 181.476167 7.204976) (xy 181.468255 7.290359)
			(xy 102.190309 7.290359) (xy 102.182397 7.204976) (xy 102.166641 7.120686) (xy 102.143174 7.03821)
			(xy 102.112198 6.958251) (xy 102.073976 6.881491) (xy 102.028835 6.808585) (xy 101.977159 6.740156)
			(xy 101.91939 6.676786) (xy 101.85602 6.619017) (xy 101.787591 6.567341) (xy 101.714685 6.5222) (xy 101.637925 6.483978)
			(xy 101.557966 6.453002) (xy 101.47549 6.429535) (xy 101.3912 6.413779) (xy 101.305817 6.405867)
			(xy 101.220067 6.405867) (xy 101.134684 6.413779) (xy 101.050394 6.429535) (xy 100.967918 6.453002)
			(xy 100.887959 6.483978) (xy 100.811199 6.5222) (xy 100.738293 6.567341) (xy 100.669864 6.619017)
			(xy 100.606494 6.676786) (xy 100.548725 6.740156) (xy 100.497049 6.808585) (xy 100.451908 6.881491)
			(xy 100.413686 6.958251) (xy 100.38271 7.03821) (xy 100.359243 7.120686) (xy 100.343487 7.204976)
			(xy 100.335575 7.290359) (xy 95.840309 7.290359) (xy 95.832397 7.204976) (xy 95.816641 7.120686)
			(xy 95.793174 7.03821) (xy 95.762198 6.958251) (xy 95.723976 6.881491) (xy 95.678835 6.808585) (xy 95.627159 6.740156)
			(xy 95.56939 6.676786) (xy 95.50602 6.619017) (xy 95.437591 6.567341) (xy 95.364685 6.5222) (xy 95.287925 6.483978)
			(xy 95.207966 6.453002) (xy 95.12549 6.429535) (xy 95.0412 6.413779) (xy 94.955817 6.405867) (xy 94.870067 6.405867)
			(xy 94.784684 6.413779) (xy 94.700394 6.429535) (xy 94.617918 6.453002) (xy 94.537959 6.483978) (xy 94.461199 6.5222)
			(xy 94.388293 6.567341) (xy 94.319864 6.619017) (xy 94.256494 6.676786) (xy 94.198725 6.740156) (xy 94.147049 6.808585)
			(xy 94.101908 6.881491) (xy 94.063686 6.958251) (xy 94.03271 7.03821) (xy 94.009243 7.120686) (xy 93.993487 7.204976)
			(xy 93.985575 7.290359) (xy 7.092973 7.290359) (xy 7.087805 7.206571) (xy 7.071935 7.078411) (xy 7.048206 6.95147)
			(xy 7.016707 6.826231) (xy 6.977558 6.703168) (xy 6.930907 6.582749) (xy 6.876932 6.46543) (xy 6.815837 6.351656)
			(xy 6.747854 6.241859) (xy 6.67324 6.136456) (xy 6.592279 6.035846) (xy 6.505279 5.940411) (xy 6.412568 5.850512)
			(xy 6.314498 5.766491) (xy 6.211443 5.688667) (xy 6.103792 5.617335) (xy 5.991953 5.552765) (xy 5.876352 5.495203)
			(xy 5.757427 5.444866) (xy 5.635628 5.401946) (xy 5.511418 5.366605) (xy 5.385269 5.338978) (xy 5.257657 5.319169)
			(xy 5.129068 5.307253) (xy 4.99999 5.303277) (xy 4.870912 5.307253) (xy 4.742323 5.319169) (xy 4.614711 5.338978)
			(xy 4.488562 5.366605) (xy 4.364352 5.401946) (xy 4.242553 5.444866) (xy 4.123628 5.495203) (xy 4.008027 5.552765)
			(xy 3.896188 5.617335) (xy 3.788537 5.688667) (xy 3.685482 5.766491) (xy 3.587412 5.850512) (xy 3.494701 5.940411)
			(xy 3.407701 6.035846) (xy 3.32674 6.136456) (xy 3.252126 6.241859) (xy 3.184143 6.351656) (xy 3.123048 6.46543)
			(xy 3.069073 6.582749) (xy 3.022422 6.703168) (xy 2.983273 6.826231) (xy 2.951774 6.95147) (xy 2.928045 7.078411)
			(xy 2.912175 7.206571) (xy 2.904225 7.335466) (xy 0.509016 7.335466) (xy 0.509016 4.750359) (xy 93.985575 4.750359)
			(xy 93.985575 4.836109) (xy 93.993487 4.921492) (xy 94.009243 5.005782) (xy 94.03271 5.088258) (xy 94.063686 5.168217)
			(xy 94.101908 5.244977) (xy 94.147049 5.317883) (xy 94.198725 5.386312) (xy 94.256494 5.449682) (xy 94.319864 5.507451)
			(xy 94.388293 5.559127) (xy 94.461199 5.604268) (xy 94.537959 5.64249) (xy 94.617918 5.673466) (xy 94.700394 5.696933)
			(xy 94.784684 5.712689) (xy 94.870067 5.720601) (xy 94.955817 5.720601) (xy 95.0412 5.712689) (xy 95.12549 5.696933)
			(xy 95.207966 5.673466) (xy 95.287925 5.64249) (xy 95.308598 5.632196) (xy 98.842576 5.632196) (xy 98.842576 6.495796)
			(xy 98.84308 6.525332) (xy 98.851124 6.583854) (xy 98.867061 6.640736) (xy 98.890596 6.694918) (xy 98.921289 6.745391)
			(xy 98.958569 6.791214) (xy 99.001741 6.831534) (xy 99.050001 6.8656) (xy 99.102451 6.892777) (xy 99.158112 6.912559)
			(xy 99.215949 6.924578) (xy 99.274884 6.928609) (xy 99.333819 6.924578) (xy 99.391656 6.912559) (xy 99.447317 6.892777)
			(xy 99.499767 6.8656) (xy 99.548027 6.831534) (xy 99.591199 6.791214) (xy 99.628479 6.745391) (xy 99.659172 6.694918)
			(xy 99.682707 6.640736) (xy 99.698644 6.583854) (xy 99.706688 6.525332) (xy 99.707192 6.495796) (xy 99.707192 5.632196)
			(xy 99.706688 5.60266) (xy 99.698644 5.544138) (xy 99.682707 5.487256) (xy 99.659172 5.433074) (xy 99.628479 5.382601)
			(xy 99.591199 5.336778) (xy 99.548027 5.296458) (xy 99.499767 5.262392) (xy 99.447317 5.235215) (xy 99.391656 5.215433)
			(xy 99.333819 5.203414) (xy 99.274884 5.199383) (xy 99.215949 5.203414) (xy 99.158112 5.215433) (xy 99.102451 5.235215)
			(xy 99.050001 5.262392) (xy 99.001741 5.296458) (xy 98.958569 5.336778) (xy 98.921289 5.382601) (xy 98.890596 5.433074)
			(xy 98.867061 5.487256) (xy 98.851124 5.544138) (xy 98.84308 5.60266) (xy 98.842576 5.632196) (xy 95.308598 5.632196)
			(xy 95.364685 5.604268) (xy 95.437591 5.559127) (xy 95.50602 5.507451) (xy 95.56939 5.449682) (xy 95.627159 5.386312)
			(xy 95.678835 5.317883) (xy 95.723976 5.244977) (xy 95.762198 5.168217) (xy 95.793174 5.088258) (xy 95.816641 5.005782)
			(xy 95.832397 4.921492) (xy 95.840309 4.836109) (xy 95.840804 4.793234) (xy 95.840309 4.750359) (xy 100.335575 4.750359)
			(xy 100.335575 4.836109) (xy 100.343487 4.921492) (xy 100.359243 5.005782) (xy 100.38271 5.088258)
			(xy 100.413686 5.168217) (xy 100.451908 5.244977) (xy 100.497049 5.317883) (xy 100.548725 5.386312)
			(xy 100.606494 5.449682) (xy 100.669864 5.507451) (xy 100.738293 5.559127) (xy 100.811199 5.604268)
			(xy 100.887959 5.64249) (xy 100.967918 5.673466) (xy 101.050394 5.696933) (xy 101.134684 5.712689)
			(xy 101.220067 5.720601) (xy 101.305817 5.720601) (xy 101.3912 5.712689) (xy 101.47549 5.696933)
			(xy 101.557966 5.673466) (xy 101.637925 5.64249) (xy 101.714685 5.604268) (xy 101.787591 5.559127)
			(xy 101.85602 5.507451) (xy 101.91939 5.449682) (xy 101.977159 5.386312) (xy 102.028835 5.317883)
			(xy 102.073976 5.244977) (xy 102.112198 5.168217) (xy 102.143174 5.088258) (xy 102.166641 5.005782)
			(xy 102.182397 4.921492) (xy 102.190309 4.836109) (xy 102.190804 4.793234) (xy 102.190309 4.750359)
			(xy 181.468255 4.750359) (xy 181.468255 4.836109) (xy 181.476167 4.921492) (xy 181.491923 5.005782)
			(xy 181.51539 5.088258) (xy 181.546366 5.168217) (xy 181.584588 5.244977) (xy 181.629729 5.317883)
			(xy 181.681405 5.386312) (xy 181.739174 5.449682) (xy 181.802544 5.507451) (xy 181.870973 5.559127)
			(xy 181.943879 5.604268) (xy 182.020639 5.64249) (xy 182.100598 5.673466) (xy 182.183074 5.696933)
			(xy 182.267364 5.712689) (xy 182.352747 5.720601) (xy 182.438497 5.720601) (xy 182.52388 5.712689)
			(xy 182.60817 5.696933) (xy 182.690646 5.673466) (xy 182.770605 5.64249) (xy 182.791278 5.632196)
			(xy 183.953912 5.632196) (xy 183.953912 6.495796) (xy 183.954416 6.525332) (xy 183.96246 6.583854)
			(xy 183.978397 6.640736) (xy 184.001932 6.694918) (xy 184.032625 6.745391) (xy 184.069905 6.791214)
			(xy 184.113077 6.831534) (xy 184.161337 6.8656) (xy 184.213787 6.892777) (xy 184.269448 6.912559)
			(xy 184.327285 6.924578) (xy 184.38622 6.928609) (xy 184.445155 6.924578) (xy 184.502992 6.912559)
			(xy 184.558653 6.892777) (xy 184.611103 6.8656) (xy 184.659363 6.831534) (xy 184.702535 6.791214)
			(xy 184.739815 6.745391) (xy 184.770508 6.694918) (xy 184.794043 6.640736) (xy 184.80998 6.583854)
			(xy 184.818024 6.525332) (xy 184.818528 6.495796) (xy 184.818528 6.309919) (xy 208.661241 6.309919)
			(xy 208.661241 6.395669) (xy 208.669153 6.481052) (xy 208.684909 6.565342) (xy 208.708376 6.647818)
			(xy 208.739352 6.727777) (xy 208.777574 6.804537) (xy 208.822715 6.877443) (xy 208.874391 6.945872)
			(xy 208.93216 7.009242) (xy 208.99553 7.067011) (xy 209.063959 7.118687) (xy 209.136865 7.163828)
			(xy 209.213625 7.20205) (xy 209.293584 7.233026) (xy 209.37606 7.256493) (xy 209.46035 7.272249)
			(xy 209.545733 7.280161) (xy 209.631483 7.280161) (xy 209.716866 7.272249) (xy 209.801156 7.256493)
			(xy 209.883632 7.233026) (xy 209.963591 7.20205) (xy 210.040351 7.163828) (xy 210.113257 7.118687)
			(xy 210.181686 7.067011) (xy 210.245056 7.009242) (xy 210.302825 6.945872) (xy 210.354501 6.877443)
			(xy 210.399642 6.804537) (xy 210.437864 6.727777) (xy 210.46884 6.647818) (xy 210.492307 6.565342)
			(xy 210.508063 6.481052) (xy 210.515975 6.395669) (xy 210.51647 6.352794) (xy 210.515975 6.309919)
			(xy 215.011241 6.309919) (xy 215.011241 6.395669) (xy 215.019153 6.481052) (xy 215.034909 6.565342)
			(xy 215.058376 6.647818) (xy 215.089352 6.727777) (xy 215.127574 6.804537) (xy 215.172715 6.877443)
			(xy 215.224391 6.945872) (xy 215.28216 7.009242) (xy 215.34553 7.067011) (xy 215.413959 7.118687)
			(xy 215.486865 7.163828) (xy 215.563625 7.20205) (xy 215.643584 7.233026) (xy 215.72606 7.256493)
			(xy 215.81035 7.272249) (xy 215.895733 7.280161) (xy 215.981483 7.280161) (xy 216.066866 7.272249)
			(xy 216.151156 7.256493) (xy 216.233632 7.233026) (xy 216.313591 7.20205) (xy 216.390351 7.163828)
			(xy 216.463257 7.118687) (xy 216.531686 7.067011) (xy 216.595056 7.009242) (xy 216.652825 6.945872)
			(xy 216.704501 6.877443) (xy 216.749642 6.804537) (xy 216.787864 6.727777) (xy 216.81884 6.647818)
			(xy 216.842307 6.565342) (xy 216.858063 6.481052) (xy 216.865975 6.395669) (xy 216.86647 6.352794)
			(xy 216.865975 6.309919) (xy 296.143921 6.309919) (xy 296.143921 6.395669) (xy 296.151833 6.481052)
			(xy 296.167589 6.565342) (xy 296.191056 6.647818) (xy 296.222032 6.727777) (xy 296.260254 6.804537)
			(xy 296.305395 6.877443) (xy 296.357071 6.945872) (xy 296.41484 7.009242) (xy 296.47821 7.067011)
			(xy 296.546639 7.118687) (xy 296.619545 7.163828) (xy 296.696305 7.20205) (xy 296.776264 7.233026)
			(xy 296.85874 7.256493) (xy 296.94303 7.272249) (xy 297.028413 7.280161) (xy 297.114163 7.280161)
			(xy 297.199546 7.272249) (xy 297.283836 7.256493) (xy 297.366312 7.233026) (xy 297.446271 7.20205)
			(xy 297.523031 7.163828) (xy 297.595937 7.118687) (xy 297.664366 7.067011) (xy 297.727736 7.009242)
			(xy 297.785505 6.945872) (xy 297.837181 6.877443) (xy 297.882322 6.804537) (xy 297.920544 6.727777)
			(xy 297.95152 6.647818) (xy 297.974987 6.565342) (xy 297.990743 6.481052) (xy 297.998655 6.395669)
			(xy 297.99915 6.352794) (xy 297.998655 6.309919) (xy 302.493921 6.309919) (xy 302.493921 6.395669)
			(xy 302.501833 6.481052) (xy 302.517589 6.565342) (xy 302.541056 6.647818) (xy 302.572032 6.727777)
			(xy 302.610254 6.804537) (xy 302.655395 6.877443) (xy 302.707071 6.945872) (xy 302.76484 7.009242)
			(xy 302.82821 7.067011) (xy 302.896639 7.118687) (xy 302.969545 7.163828) (xy 303.046305 7.20205)
			(xy 303.126264 7.233026) (xy 303.20874 7.256493) (xy 303.29303 7.272249) (xy 303.378413 7.280161)
			(xy 303.464163 7.280161) (xy 303.549546 7.272249) (xy 303.633836 7.256493) (xy 303.716312 7.233026)
			(xy 303.796271 7.20205) (xy 303.873031 7.163828) (xy 303.945937 7.118687) (xy 304.014366 7.067011)
			(xy 304.077736 7.009242) (xy 304.135505 6.945872) (xy 304.187181 6.877443) (xy 304.232322 6.804537)
			(xy 304.270544 6.727777) (xy 304.30152 6.647818) (xy 304.324987 6.565342) (xy 304.340743 6.481052)
			(xy 304.348655 6.395669) (xy 304.34915 6.352794) (xy 304.348655 6.309919) (xy 311.155321 6.309919)
			(xy 311.155321 6.395669) (xy 311.163233 6.481052) (xy 311.178989 6.565342) (xy 311.202456 6.647818)
			(xy 311.233432 6.727777) (xy 311.271654 6.804537) (xy 311.316795 6.877443) (xy 311.368471 6.945872)
			(xy 311.42624 7.009242) (xy 311.48961 7.067011) (xy 311.558039 7.118687) (xy 311.630945 7.163828)
			(xy 311.707705 7.20205) (xy 311.787664 7.233026) (xy 311.87014 7.256493) (xy 311.95443 7.272249)
			(xy 312.039813 7.280161) (xy 312.125563 7.280161) (xy 312.210946 7.272249) (xy 312.295236 7.256493)
			(xy 312.377712 7.233026) (xy 312.457671 7.20205) (xy 312.478344 7.191756) (xy 316.012068 7.191756)
			(xy 316.012068 8.055356) (xy 316.012572 8.08491) (xy 316.020621 8.143466) (xy 316.036567 8.200381)
			(xy 316.060116 8.254595) (xy 316.090827 8.305098) (xy 316.128129 8.350948) (xy 316.171326 8.391291)
			(xy 316.219615 8.425377) (xy 316.272095 8.45257) (xy 316.32779 8.472364) (xy 316.385661 8.48439)
			(xy 316.44463 8.488424) (xy 316.503599 8.48439) (xy 316.56147 8.472364) (xy 316.617165 8.45257) (xy 316.669645 8.425377)
			(xy 316.717934 8.391291) (xy 316.761131 8.350948) (xy 316.798433 8.305098) (xy 316.829144 8.254595)
			(xy 316.852693 8.200381) (xy 316.868639 8.143466) (xy 316.876688 8.08491) (xy 316.877192 8.055356)
			(xy 316.877192 7.191756) (xy 316.876688 7.162202) (xy 316.868639 7.103646) (xy 316.852693 7.046731)
			(xy 316.829144 6.992517) (xy 316.798433 6.942014) (xy 316.761131 6.896164) (xy 316.717934 6.855821)
			(xy 316.669645 6.821735) (xy 316.617165 6.794542) (xy 316.56147 6.774748) (xy 316.503599 6.762722)
			(xy 316.44463 6.758689) (xy 316.385661 6.762722) (xy 316.32779 6.774748) (xy 316.272095 6.794542)
			(xy 316.219615 6.821735) (xy 316.171326 6.855821) (xy 316.128129 6.896164) (xy 316.090827 6.942014)
			(xy 316.060116 6.992517) (xy 316.036567 7.046731) (xy 316.020621 7.103646) (xy 316.012572 7.162202)
			(xy 316.012068 7.191756) (xy 312.478344 7.191756) (xy 312.534431 7.163828) (xy 312.607337 7.118687)
			(xy 312.675766 7.067011) (xy 312.739136 7.009242) (xy 312.796905 6.945872) (xy 312.848581 6.877443)
			(xy 312.893722 6.804537) (xy 312.931944 6.727777) (xy 312.96292 6.647818) (xy 312.986387 6.565342)
			(xy 313.002143 6.481052) (xy 313.010055 6.395669) (xy 313.01055 6.352794) (xy 313.010055 6.309919)
			(xy 317.505321 6.309919) (xy 317.505321 6.395669) (xy 317.513233 6.481052) (xy 317.528989 6.565342)
			(xy 317.552456 6.647818) (xy 317.583432 6.727777) (xy 317.621654 6.804537) (xy 317.666795 6.877443)
			(xy 317.718471 6.945872) (xy 317.77624 7.009242) (xy 317.83961 7.067011) (xy 317.908039 7.118687)
			(xy 317.980945 7.163828) (xy 318.057705 7.20205) (xy 318.137664 7.233026) (xy 318.22014 7.256493)
			(xy 318.30443 7.272249) (xy 318.389813 7.280161) (xy 318.475563 7.280161) (xy 318.560946 7.272249)
			(xy 318.645236 7.256493) (xy 318.727712 7.233026) (xy 318.807671 7.20205) (xy 318.884431 7.163828)
			(xy 318.957337 7.118687) (xy 319.025766 7.067011) (xy 319.089136 7.009242) (xy 319.146905 6.945872)
			(xy 319.198581 6.877443) (xy 319.243722 6.804537) (xy 319.281944 6.727777) (xy 319.31292 6.647818)
			(xy 319.336387 6.565342) (xy 319.352143 6.481052) (xy 319.360055 6.395669) (xy 319.36055 6.352794)
			(xy 319.360055 6.309919) (xy 361.894107 6.309919) (xy 361.894107 6.395669) (xy 361.902019 6.481052)
			(xy 361.917775 6.565342) (xy 361.941242 6.647818) (xy 361.972218 6.727777) (xy 362.01044 6.804537)
			(xy 362.055581 6.877443) (xy 362.107257 6.945872) (xy 362.165026 7.009242) (xy 362.228396 7.067011)
			(xy 362.296825 7.118687) (xy 362.369731 7.163828) (xy 362.446491 7.20205) (xy 362.52645 7.233026)
			(xy 362.608926 7.256493) (xy 362.693216 7.272249) (xy 362.778599 7.280161) (xy 362.864349 7.280161)
			(xy 362.949732 7.272249) (xy 363.034022 7.256493) (xy 363.116498 7.233026) (xy 363.196457 7.20205)
			(xy 363.21713 7.191756) (xy 364.379764 7.191756) (xy 364.379764 8.055356) (xy 364.380268 8.084892)
			(xy 364.388312 8.143414) (xy 364.404249 8.200296) (xy 364.427784 8.254478) (xy 364.458477 8.304951)
			(xy 364.495757 8.350774) (xy 364.538929 8.391094) (xy 364.587189 8.42516) (xy 364.639639 8.452337)
			(xy 364.6953 8.472119) (xy 364.753137 8.484138) (xy 364.812072 8.488169) (xy 364.871007 8.484138)
			(xy 364.928844 8.472119) (xy 364.984505 8.452337) (xy 365.036955 8.42516) (xy 365.085215 8.391094)
			(xy 365.128387 8.350774) (xy 365.165667 8.304951) (xy 365.19636 8.254478) (xy 365.219895 8.200296)
			(xy 365.235832 8.143414) (xy 365.243876 8.084892) (xy 365.24438 8.055356) (xy 365.24438 7.376973)
			(xy 385.651997 7.376973) (xy 385.651997 7.462723) (xy 385.659909 7.548106) (xy 385.675665 7.632396)
			(xy 385.699132 7.714872) (xy 385.730108 7.794831) (xy 385.76833 7.871591) (xy 385.813471 7.944497)
			(xy 385.865147 8.012926) (xy 385.922916 8.076296) (xy 385.986286 8.134065) (xy 386.054715 8.185741)
			(xy 386.127621 8.230882) (xy 386.204381 8.269104) (xy 386.28434 8.30008) (xy 386.366816 8.323547)
			(xy 386.451106 8.339303) (xy 386.536489 8.347215) (xy 386.622239 8.347215) (xy 386.707622 8.339303)
			(xy 386.791912 8.323547) (xy 386.874388 8.30008) (xy 386.954347 8.269104) (xy 386.97502 8.25881)
			(xy 390.508744 8.25881) (xy 390.508744 9.12241) (xy 390.509248 9.151964) (xy 390.517297 9.21052)
			(xy 390.533243 9.267435) (xy 390.556792 9.321649) (xy 390.587503 9.372152) (xy 390.624805 9.418002)
			(xy 390.668002 9.458345) (xy 390.716291 9.492431) (xy 390.768771 9.519624) (xy 390.824466 9.539418)
			(xy 390.882337 9.551444) (xy 390.941306 9.555478) (xy 391.000275 9.551444) (xy 391.058146 9.539418)
			(xy 391.113841 9.519624) (xy 391.166321 9.492431) (xy 391.21461 9.458345) (xy 391.257807 9.418002)
			(xy 391.295109 9.372152) (xy 391.32582 9.321649) (xy 391.349369 9.267435) (xy 391.365315 9.21052)
			(xy 391.373364 9.151964) (xy 391.373868 9.12241) (xy 391.373868 8.25881) (xy 391.373364 8.229256)
			(xy 391.365315 8.1707) (xy 391.349369 8.113785) (xy 391.32582 8.059571) (xy 391.295109 8.009068)
			(xy 391.257807 7.963218) (xy 391.21461 7.922875) (xy 391.166321 7.888789) (xy 391.113841 7.861596)
			(xy 391.058146 7.841802) (xy 391.000275 7.829776) (xy 390.941306 7.825743) (xy 390.882337 7.829776)
			(xy 390.824466 7.841802) (xy 390.768771 7.861596) (xy 390.716291 7.888789) (xy 390.668002 7.922875)
			(xy 390.624805 7.963218) (xy 390.587503 8.009068) (xy 390.556792 8.059571) (xy 390.533243 8.113785)
			(xy 390.517297 8.1707) (xy 390.509248 8.229256) (xy 390.508744 8.25881) (xy 386.97502 8.25881) (xy 387.031107 8.230882)
			(xy 387.104013 8.185741) (xy 387.172442 8.134065) (xy 387.235812 8.076296) (xy 387.293581 8.012926)
			(xy 387.345257 7.944497) (xy 387.390398 7.871591) (xy 387.42862 7.794831) (xy 387.459596 7.714872)
			(xy 387.483063 7.632396) (xy 387.498819 7.548106) (xy 387.506731 7.462723) (xy 387.507226 7.419848)
			(xy 387.506731 7.376973) (xy 392.001997 7.376973) (xy 392.001997 7.462723) (xy 392.009909 7.548106)
			(xy 392.025665 7.632396) (xy 392.049132 7.714872) (xy 392.080108 7.794831) (xy 392.11833 7.871591)
			(xy 392.163471 7.944497) (xy 392.215147 8.012926) (xy 392.272916 8.076296) (xy 392.336286 8.134065)
			(xy 392.404715 8.185741) (xy 392.477621 8.230882) (xy 392.554381 8.269104) (xy 392.63434 8.30008)
			(xy 392.716816 8.323547) (xy 392.801106 8.339303) (xy 392.886489 8.347215) (xy 392.972239 8.347215)
			(xy 393.057622 8.339303) (xy 393.141912 8.323547) (xy 393.224388 8.30008) (xy 393.304347 8.269104)
			(xy 393.381107 8.230882) (xy 393.454013 8.185741) (xy 393.522442 8.134065) (xy 393.585812 8.076296)
			(xy 393.643581 8.012926) (xy 393.695257 7.944497) (xy 393.740398 7.871591) (xy 393.77862 7.794831)
			(xy 393.809596 7.714872) (xy 393.833063 7.632396) (xy 393.848819 7.548106) (xy 393.856731 7.462723)
			(xy 393.857226 7.419848) (xy 393.856731 7.376973) (xy 436.390783 7.376973) (xy 436.390783 7.462723)
			(xy 436.398695 7.548106) (xy 436.414451 7.632396) (xy 436.437918 7.714872) (xy 436.468894 7.794831)
			(xy 436.507116 7.871591) (xy 436.552257 7.944497) (xy 436.603933 8.012926) (xy 436.661702 8.076296)
			(xy 436.725072 8.134065) (xy 436.793501 8.185741) (xy 436.866407 8.230882) (xy 436.943167 8.269104)
			(xy 437.023126 8.30008) (xy 437.105602 8.323547) (xy 437.189892 8.339303) (xy 437.275275 8.347215)
			(xy 437.361025 8.347215) (xy 437.446408 8.339303) (xy 437.530698 8.323547) (xy 437.613174 8.30008)
			(xy 437.693133 8.269104) (xy 437.713806 8.25881) (xy 438.87644 8.25881) (xy 438.87644 9.12241) (xy 438.876944 9.151946)
			(xy 438.884988 9.210468) (xy 438.900925 9.26735) (xy 438.92446 9.321532) (xy 438.955153 9.372005)
			(xy 438.992433 9.417828) (xy 439.035605 9.458148) (xy 439.083865 9.492214) (xy 439.136315 9.519391)
			(xy 439.191976 9.539173) (xy 439.249813 9.551192) (xy 439.308748 9.555223) (xy 439.367683 9.551192)
			(xy 439.42552 9.539173) (xy 439.481181 9.519391) (xy 439.533631 9.492214) (xy 439.581891 9.458148)
			(xy 439.625063 9.417828) (xy 439.662343 9.372005) (xy 439.693036 9.321532) (xy 439.716571 9.26735)
			(xy 439.732508 9.210468) (xy 439.740552 9.151946) (xy 439.741056 9.12241) (xy 439.741056 8.25881)
			(xy 439.740552 8.229274) (xy 439.732508 8.170752) (xy 439.716571 8.11387) (xy 439.693036 8.059688)
			(xy 439.662343 8.009215) (xy 439.625063 7.963392) (xy 439.581891 7.923072) (xy 439.533631 7.889006)
			(xy 439.481181 7.861829) (xy 439.42552 7.842047) (xy 439.367683 7.830028) (xy 439.308748 7.825997)
			(xy 439.249813 7.830028) (xy 439.191976 7.842047) (xy 439.136315 7.861829) (xy 439.083865 7.889006)
			(xy 439.035605 7.923072) (xy 438.992433 7.963392) (xy 438.955153 8.009215) (xy 438.92446 8.059688)
			(xy 438.900925 8.11387) (xy 438.884988 8.170752) (xy 438.876944 8.229274) (xy 438.87644 8.25881)
			(xy 437.713806 8.25881) (xy 437.769893 8.230882) (xy 437.842799 8.185741) (xy 437.911228 8.134065)
			(xy 437.974598 8.076296) (xy 438.032367 8.012926) (xy 438.084043 7.944497) (xy 438.129184 7.871591)
			(xy 438.167406 7.794831) (xy 438.198382 7.714872) (xy 438.221849 7.632396) (xy 438.237605 7.548106)
			(xy 438.245517 7.462723) (xy 438.246012 7.419848) (xy 438.245517 7.376973) (xy 442.740783 7.376973)
			(xy 442.740783 7.462723) (xy 442.748695 7.548106) (xy 442.764451 7.632396) (xy 442.787918 7.714872)
			(xy 442.818894 7.794831) (xy 442.857116 7.871591) (xy 442.902257 7.944497) (xy 442.953933 8.012926)
			(xy 443.011702 8.076296) (xy 443.075072 8.134065) (xy 443.143501 8.185741) (xy 443.216407 8.230882)
			(xy 443.293167 8.269104) (xy 443.373126 8.30008) (xy 443.455602 8.323547) (xy 443.539892 8.339303)
			(xy 443.625275 8.347215) (xy 443.711025 8.347215) (xy 443.796408 8.339303) (xy 443.880698 8.323547)
			(xy 443.963174 8.30008) (xy 444.043133 8.269104) (xy 444.119893 8.230882) (xy 444.192799 8.185741)
			(xy 444.261228 8.134065) (xy 444.324598 8.076296) (xy 444.382367 8.012926) (xy 444.434043 7.944497)
			(xy 444.479184 7.871591) (xy 444.517406 7.794831) (xy 444.548382 7.714872) (xy 444.571849 7.632396)
			(xy 444.587605 7.548106) (xy 444.595517 7.462723) (xy 444.596012 7.419848) (xy 444.595517 7.376973)
			(xy 444.587605 7.29159) (xy 444.571849 7.2073) (xy 444.548382 7.124824) (xy 444.517406 7.044865)
			(xy 444.479184 6.968105) (xy 444.434043 6.895199) (xy 444.382367 6.82677) (xy 444.324598 6.7634)
			(xy 444.261228 6.705631) (xy 444.192799 6.653955) (xy 444.119893 6.608814) (xy 444.043133 6.570592)
			(xy 443.963174 6.539616) (xy 443.880698 6.516149) (xy 443.796408 6.500393) (xy 443.711025 6.492481)
			(xy 443.625275 6.492481) (xy 443.539892 6.500393) (xy 443.455602 6.516149) (xy 443.373126 6.539616)
			(xy 443.293167 6.570592) (xy 443.216407 6.608814) (xy 443.143501 6.653955) (xy 443.075072 6.705631)
			(xy 443.011702 6.7634) (xy 442.953933 6.82677) (xy 442.902257 6.895199) (xy 442.857116 6.968105)
			(xy 442.818894 7.044865) (xy 442.787918 7.124824) (xy 442.764451 7.2073) (xy 442.748695 7.29159)
			(xy 442.740783 7.376973) (xy 438.245517 7.376973) (xy 438.237605 7.29159) (xy 438.221849 7.2073)
			(xy 438.198382 7.124824) (xy 438.167406 7.044865) (xy 438.129184 6.968105) (xy 438.084043 6.895199)
			(xy 438.032367 6.82677) (xy 437.974598 6.7634) (xy 437.911228 6.705631) (xy 437.842799 6.653955)
			(xy 437.769893 6.608814) (xy 437.693133 6.570592) (xy 437.613174 6.539616) (xy 437.530698 6.516149)
			(xy 437.446408 6.500393) (xy 437.361025 6.492481) (xy 437.275275 6.492481) (xy 437.189892 6.500393)
			(xy 437.105602 6.516149) (xy 437.023126 6.539616) (xy 436.943167 6.570592) (xy 436.866407 6.608814)
			(xy 436.793501 6.653955) (xy 436.725072 6.705631) (xy 436.661702 6.7634) (xy 436.603933 6.82677)
			(xy 436.552257 6.895199) (xy 436.507116 6.968105) (xy 436.468894 7.044865) (xy 436.437918 7.124824)
			(xy 436.414451 7.2073) (xy 436.398695 7.29159) (xy 436.390783 7.376973) (xy 393.856731 7.376973)
			(xy 393.848819 7.29159) (xy 393.833063 7.2073) (xy 393.809596 7.124824) (xy 393.77862 7.044865) (xy 393.740398 6.968105)
			(xy 393.695257 6.895199) (xy 393.643581 6.82677) (xy 393.585812 6.7634) (xy 393.522442 6.705631)
			(xy 393.454013 6.653955) (xy 393.381107 6.608814) (xy 393.304347 6.570592) (xy 393.224388 6.539616)
			(xy 393.141912 6.516149) (xy 393.057622 6.500393) (xy 392.972239 6.492481) (xy 392.886489 6.492481)
			(xy 392.801106 6.500393) (xy 392.716816 6.516149) (xy 392.63434 6.539616) (xy 392.554381 6.570592)
			(xy 392.477621 6.608814) (xy 392.404715 6.653955) (xy 392.336286 6.705631) (xy 392.272916 6.7634)
			(xy 392.215147 6.82677) (xy 392.163471 6.895199) (xy 392.11833 6.968105) (xy 392.080108 7.044865)
			(xy 392.049132 7.124824) (xy 392.025665 7.2073) (xy 392.009909 7.29159) (xy 392.001997 7.376973)
			(xy 387.506731 7.376973) (xy 387.498819 7.29159) (xy 387.483063 7.2073) (xy 387.459596 7.124824)
			(xy 387.42862 7.044865) (xy 387.390398 6.968105) (xy 387.345257 6.895199) (xy 387.293581 6.82677)
			(xy 387.235812 6.7634) (xy 387.172442 6.705631) (xy 387.104013 6.653955) (xy 387.031107 6.608814)
			(xy 386.954347 6.570592) (xy 386.874388 6.539616) (xy 386.791912 6.516149) (xy 386.707622 6.500393)
			(xy 386.622239 6.492481) (xy 386.536489 6.492481) (xy 386.451106 6.500393) (xy 386.366816 6.516149)
			(xy 386.28434 6.539616) (xy 386.204381 6.570592) (xy 386.127621 6.608814) (xy 386.054715 6.653955)
			(xy 385.986286 6.705631) (xy 385.922916 6.7634) (xy 385.865147 6.82677) (xy 385.813471 6.895199)
			(xy 385.76833 6.968105) (xy 385.730108 7.044865) (xy 385.699132 7.124824) (xy 385.675665 7.2073)
			(xy 385.659909 7.29159) (xy 385.651997 7.376973) (xy 365.24438 7.376973) (xy 365.24438 7.191756)
			(xy 365.243876 7.16222) (xy 365.235832 7.103698) (xy 365.219895 7.046816) (xy 365.19636 6.992634)
			(xy 365.165667 6.942161) (xy 365.128387 6.896338) (xy 365.085215 6.856018) (xy 365.036955 6.821952)
			(xy 364.984505 6.794775) (xy 364.928844 6.774993) (xy 364.871007 6.762974) (xy 364.812072 6.758943)
			(xy 364.753137 6.762974) (xy 364.6953 6.774993) (xy 364.639639 6.794775) (xy 364.587189 6.821952)
			(xy 364.538929 6.856018) (xy 364.495757 6.896338) (xy 364.458477 6.942161) (xy 364.427784 6.992634)
			(xy 364.404249 7.046816) (xy 364.388312 7.103698) (xy 364.380268 7.16222) (xy 364.379764 7.191756)
			(xy 363.21713 7.191756) (xy 363.273217 7.163828) (xy 363.346123 7.118687) (xy 363.414552 7.067011)
			(xy 363.477922 7.009242) (xy 363.535691 6.945872) (xy 363.587367 6.877443) (xy 363.632508 6.804537)
			(xy 363.67073 6.727777) (xy 363.701706 6.647818) (xy 363.725173 6.565342) (xy 363.740929 6.481052)
			(xy 363.748841 6.395669) (xy 363.749336 6.352794) (xy 363.748841 6.309919) (xy 368.244107 6.309919)
			(xy 368.244107 6.395669) (xy 368.252019 6.481052) (xy 368.267775 6.565342) (xy 368.291242 6.647818)
			(xy 368.322218 6.727777) (xy 368.36044 6.804537) (xy 368.405581 6.877443) (xy 368.457257 6.945872)
			(xy 368.515026 7.009242) (xy 368.578396 7.067011) (xy 368.646825 7.118687) (xy 368.719731 7.163828)
			(xy 368.796491 7.20205) (xy 368.87645 7.233026) (xy 368.958926 7.256493) (xy 369.043216 7.272249)
			(xy 369.128599 7.280161) (xy 369.214349 7.280161) (xy 369.299732 7.272249) (xy 369.384022 7.256493)
			(xy 369.466498 7.233026) (xy 369.546457 7.20205) (xy 369.623217 7.163828) (xy 369.696123 7.118687)
			(xy 369.764552 7.067011) (xy 369.827922 7.009242) (xy 369.885691 6.945872) (xy 369.937367 6.877443)
			(xy 369.982508 6.804537) (xy 370.02073 6.727777) (xy 370.051706 6.647818) (xy 370.075173 6.565342)
			(xy 370.090929 6.481052) (xy 370.098841 6.395669) (xy 370.099336 6.352794) (xy 370.098841 6.309919)
			(xy 370.090929 6.224536) (xy 370.075173 6.140246) (xy 370.051706 6.05777) (xy 370.02073 5.977811)
			(xy 369.982508 5.901051) (xy 369.937367 5.828145) (xy 369.885691 5.759716) (xy 369.827922 5.696346)
			(xy 369.764552 5.638577) (xy 369.696123 5.586901) (xy 369.623217 5.54176) (xy 369.546457 5.503538)
			(xy 369.466498 5.472562) (xy 369.384022 5.449095) (xy 369.299732 5.433339) (xy 369.214349 5.425427)
			(xy 369.128599 5.425427) (xy 369.043216 5.433339) (xy 368.958926 5.449095) (xy 368.87645 5.472562)
			(xy 368.796491 5.503538) (xy 368.719731 5.54176) (xy 368.646825 5.586901) (xy 368.578396 5.638577)
			(xy 368.515026 5.696346) (xy 368.457257 5.759716) (xy 368.405581 5.828145) (xy 368.36044 5.901051)
			(xy 368.322218 5.977811) (xy 368.291242 6.05777) (xy 368.267775 6.140246) (xy 368.252019 6.224536)
			(xy 368.244107 6.309919) (xy 363.748841 6.309919) (xy 363.740929 6.224536) (xy 363.725173 6.140246)
			(xy 363.701706 6.05777) (xy 363.67073 5.977811) (xy 363.632508 5.901051) (xy 363.587367 5.828145)
			(xy 363.535691 5.759716) (xy 363.477922 5.696346) (xy 363.414552 5.638577) (xy 363.346123 5.586901)
			(xy 363.273217 5.54176) (xy 363.196457 5.503538) (xy 363.116498 5.472562) (xy 363.034022 5.449095)
			(xy 362.949732 5.433339) (xy 362.864349 5.425427) (xy 362.778599 5.425427) (xy 362.693216 5.433339)
			(xy 362.608926 5.449095) (xy 362.52645 5.472562) (xy 362.446491 5.503538) (xy 362.369731 5.54176)
			(xy 362.296825 5.586901) (xy 362.228396 5.638577) (xy 362.165026 5.696346) (xy 362.107257 5.759716)
			(xy 362.055581 5.828145) (xy 362.01044 5.901051) (xy 361.972218 5.977811) (xy 361.941242 6.05777)
			(xy 361.917775 6.140246) (xy 361.902019 6.224536) (xy 361.894107 6.309919) (xy 319.360055 6.309919)
			(xy 319.352143 6.224536) (xy 319.336387 6.140246) (xy 319.31292 6.05777) (xy 319.281944 5.977811)
			(xy 319.243722 5.901051) (xy 319.198581 5.828145) (xy 319.146905 5.759716) (xy 319.089136 5.696346)
			(xy 319.025766 5.638577) (xy 318.957337 5.586901) (xy 318.884431 5.54176) (xy 318.807671 5.503538)
			(xy 318.727712 5.472562) (xy 318.645236 5.449095) (xy 318.560946 5.433339) (xy 318.475563 5.425427)
			(xy 318.389813 5.425427) (xy 318.30443 5.433339) (xy 318.22014 5.449095) (xy 318.137664 5.472562)
			(xy 318.057705 5.503538) (xy 317.980945 5.54176) (xy 317.908039 5.586901) (xy 317.83961 5.638577)
			(xy 317.77624 5.696346) (xy 317.718471 5.759716) (xy 317.666795 5.828145) (xy 317.621654 5.901051)
			(xy 317.583432 5.977811) (xy 317.552456 6.05777) (xy 317.528989 6.140246) (xy 317.513233 6.224536)
			(xy 317.505321 6.309919) (xy 313.010055 6.309919) (xy 313.002143 6.224536) (xy 312.986387 6.140246)
			(xy 312.96292 6.05777) (xy 312.931944 5.977811) (xy 312.893722 5.901051) (xy 312.848581 5.828145)
			(xy 312.796905 5.759716) (xy 312.739136 5.696346) (xy 312.675766 5.638577) (xy 312.607337 5.586901)
			(xy 312.534431 5.54176) (xy 312.457671 5.503538) (xy 312.377712 5.472562) (xy 312.295236 5.449095)
			(xy 312.210946 5.433339) (xy 312.125563 5.425427) (xy 312.039813 5.425427) (xy 311.95443 5.433339)
			(xy 311.87014 5.449095) (xy 311.787664 5.472562) (xy 311.707705 5.503538) (xy 311.630945 5.54176)
			(xy 311.558039 5.586901) (xy 311.48961 5.638577) (xy 311.42624 5.696346) (xy 311.368471 5.759716)
			(xy 311.316795 5.828145) (xy 311.271654 5.901051) (xy 311.233432 5.977811) (xy 311.202456 6.05777)
			(xy 311.178989 6.140246) (xy 311.163233 6.224536) (xy 311.155321 6.309919) (xy 304.348655 6.309919)
			(xy 304.340743 6.224536) (xy 304.324987 6.140246) (xy 304.30152 6.05777) (xy 304.270544 5.977811)
			(xy 304.232322 5.901051) (xy 304.187181 5.828145) (xy 304.135505 5.759716) (xy 304.077736 5.696346)
			(xy 304.014366 5.638577) (xy 303.945937 5.586901) (xy 303.873031 5.54176) (xy 303.796271 5.503538)
			(xy 303.716312 5.472562) (xy 303.633836 5.449095) (xy 303.549546 5.433339) (xy 303.464163 5.425427)
			(xy 303.378413 5.425427) (xy 303.29303 5.433339) (xy 303.20874 5.449095) (xy 303.126264 5.472562)
			(xy 303.046305 5.503538) (xy 302.969545 5.54176) (xy 302.896639 5.586901) (xy 302.82821 5.638577)
			(xy 302.76484 5.696346) (xy 302.707071 5.759716) (xy 302.655395 5.828145) (xy 302.610254 5.901051)
			(xy 302.572032 5.977811) (xy 302.541056 6.05777) (xy 302.517589 6.140246) (xy 302.501833 6.224536)
			(xy 302.493921 6.309919) (xy 297.998655 6.309919) (xy 297.990743 6.224536) (xy 297.974987 6.140246)
			(xy 297.95152 6.05777) (xy 297.920544 5.977811) (xy 297.882322 5.901051) (xy 297.837181 5.828145)
			(xy 297.785505 5.759716) (xy 297.727736 5.696346) (xy 297.664366 5.638577) (xy 297.595937 5.586901)
			(xy 297.523031 5.54176) (xy 297.446271 5.503538) (xy 297.366312 5.472562) (xy 297.283836 5.449095)
			(xy 297.199546 5.433339) (xy 297.114163 5.425427) (xy 297.028413 5.425427) (xy 296.94303 5.433339)
			(xy 296.85874 5.449095) (xy 296.776264 5.472562) (xy 296.696305 5.503538) (xy 296.619545 5.54176)
			(xy 296.546639 5.586901) (xy 296.47821 5.638577) (xy 296.41484 5.696346) (xy 296.357071 5.759716)
			(xy 296.305395 5.828145) (xy 296.260254 5.901051) (xy 296.222032 5.977811) (xy 296.191056 6.05777)
			(xy 296.167589 6.140246) (xy 296.151833 6.224536) (xy 296.143921 6.309919) (xy 216.865975 6.309919)
			(xy 216.858063 6.224536) (xy 216.842307 6.140246) (xy 216.81884 6.05777) (xy 216.787864 5.977811)
			(xy 216.749642 5.901051) (xy 216.704501 5.828145) (xy 216.652825 5.759716) (xy 216.595056 5.696346)
			(xy 216.531686 5.638577) (xy 216.463257 5.586901) (xy 216.390351 5.54176) (xy 216.313591 5.503538)
			(xy 216.233632 5.472562) (xy 216.151156 5.449095) (xy 216.066866 5.433339) (xy 215.981483 5.425427)
			(xy 215.895733 5.425427) (xy 215.81035 5.433339) (xy 215.72606 5.449095) (xy 215.643584 5.472562)
			(xy 215.563625 5.503538) (xy 215.486865 5.54176) (xy 215.413959 5.586901) (xy 215.34553 5.638577)
			(xy 215.28216 5.696346) (xy 215.224391 5.759716) (xy 215.172715 5.828145) (xy 215.127574 5.901051)
			(xy 215.089352 5.977811) (xy 215.058376 6.05777) (xy 215.034909 6.140246) (xy 215.019153 6.224536)
			(xy 215.011241 6.309919) (xy 210.515975 6.309919) (xy 210.508063 6.224536) (xy 210.492307 6.140246)
			(xy 210.46884 6.05777) (xy 210.437864 5.977811) (xy 210.399642 5.901051) (xy 210.354501 5.828145)
			(xy 210.302825 5.759716) (xy 210.245056 5.696346) (xy 210.181686 5.638577) (xy 210.113257 5.586901)
			(xy 210.040351 5.54176) (xy 209.963591 5.503538) (xy 209.883632 5.472562) (xy 209.801156 5.449095)
			(xy 209.716866 5.433339) (xy 209.631483 5.425427) (xy 209.545733 5.425427) (xy 209.46035 5.433339)
			(xy 209.37606 5.449095) (xy 209.293584 5.472562) (xy 209.213625 5.503538) (xy 209.136865 5.54176)
			(xy 209.063959 5.586901) (xy 208.99553 5.638577) (xy 208.93216 5.696346) (xy 208.874391 5.759716)
			(xy 208.822715 5.828145) (xy 208.777574 5.901051) (xy 208.739352 5.977811) (xy 208.708376 6.05777)
			(xy 208.684909 6.140246) (xy 208.669153 6.224536) (xy 208.661241 6.309919) (xy 184.818528 6.309919)
			(xy 184.818528 5.632196) (xy 184.818024 5.60266) (xy 184.80998 5.544138) (xy 184.794043 5.487256)
			(xy 184.770508 5.433074) (xy 184.739815 5.382601) (xy 184.702535 5.336778) (xy 184.659363 5.296458)
			(xy 184.611103 5.262392) (xy 184.558653 5.235215) (xy 184.502992 5.215433) (xy 184.445155 5.203414)
			(xy 184.38622 5.199383) (xy 184.327285 5.203414) (xy 184.269448 5.215433) (xy 184.213787 5.235215)
			(xy 184.161337 5.262392) (xy 184.113077 5.296458) (xy 184.069905 5.336778) (xy 184.032625 5.382601)
			(xy 184.001932 5.433074) (xy 183.978397 5.487256) (xy 183.96246 5.544138) (xy 183.954416 5.60266)
			(xy 183.953912 5.632196) (xy 182.791278 5.632196) (xy 182.847365 5.604268) (xy 182.920271 5.559127)
			(xy 182.9887 5.507451) (xy 183.05207 5.449682) (xy 183.109839 5.386312) (xy 183.161515 5.317883)
			(xy 183.206656 5.244977) (xy 183.244878 5.168217) (xy 183.275854 5.088258) (xy 183.299321 5.005782)
			(xy 183.315077 4.921492) (xy 183.322989 4.836109) (xy 183.323484 4.793234) (xy 183.322989 4.750359)
			(xy 187.818255 4.750359) (xy 187.818255 4.836109) (xy 187.826167 4.921492) (xy 187.841923 5.005782)
			(xy 187.86539 5.088258) (xy 187.896366 5.168217) (xy 187.934588 5.244977) (xy 187.979729 5.317883)
			(xy 188.031405 5.386312) (xy 188.089174 5.449682) (xy 188.152544 5.507451) (xy 188.220973 5.559127)
			(xy 188.293879 5.604268) (xy 188.370639 5.64249) (xy 188.450598 5.673466) (xy 188.533074 5.696933)
			(xy 188.617364 5.712689) (xy 188.702747 5.720601) (xy 188.788497 5.720601) (xy 188.87388 5.712689)
			(xy 188.95817 5.696933) (xy 189.040646 5.673466) (xy 189.120605 5.64249) (xy 189.197365 5.604268)
			(xy 189.270271 5.559127) (xy 189.3387 5.507451) (xy 189.40207 5.449682) (xy 189.459839 5.386312)
			(xy 189.511515 5.317883) (xy 189.556656 5.244977) (xy 189.594878 5.168217) (xy 189.625854 5.088258)
			(xy 189.649321 5.005782) (xy 189.665077 4.921492) (xy 189.672989 4.836109) (xy 189.673484 4.793234)
			(xy 189.672989 4.750359) (xy 189.665077 4.664976) (xy 189.649321 4.580686) (xy 189.625854 4.49821)
			(xy 189.594878 4.418251) (xy 189.556656 4.341491) (xy 189.511515 4.268585) (xy 189.459839 4.200156)
			(xy 189.40207 4.136786) (xy 189.3387 4.079017) (xy 189.270271 4.027341) (xy 189.197365 3.9822) (xy 189.120605 3.943978)
			(xy 189.040646 3.913002) (xy 188.95817 3.889535) (xy 188.87388 3.873779) (xy 188.788497 3.865867)
			(xy 188.702747 3.865867) (xy 188.617364 3.873779) (xy 188.533074 3.889535) (xy 188.450598 3.913002)
			(xy 188.370639 3.943978) (xy 188.293879 3.9822) (xy 188.220973 4.027341) (xy 188.152544 4.079017)
			(xy 188.089174 4.136786) (xy 188.031405 4.200156) (xy 187.979729 4.268585) (xy 187.934588 4.341491)
			(xy 187.896366 4.418251) (xy 187.86539 4.49821) (xy 187.841923 4.580686) (xy 187.826167 4.664976)
			(xy 187.818255 4.750359) (xy 183.322989 4.750359) (xy 183.315077 4.664976) (xy 183.299321 4.580686)
			(xy 183.275854 4.49821) (xy 183.244878 4.418251) (xy 183.206656 4.341491) (xy 183.161515 4.268585)
			(xy 183.109839 4.200156) (xy 183.05207 4.136786) (xy 182.9887 4.079017) (xy 182.920271 4.027341)
			(xy 182.847365 3.9822) (xy 182.770605 3.943978) (xy 182.690646 3.913002) (xy 182.60817 3.889535)
			(xy 182.52388 3.873779) (xy 182.438497 3.865867) (xy 182.352747 3.865867) (xy 182.267364 3.873779)
			(xy 182.183074 3.889535) (xy 182.100598 3.913002) (xy 182.020639 3.943978) (xy 181.943879 3.9822)
			(xy 181.870973 4.027341) (xy 181.802544 4.079017) (xy 181.739174 4.136786) (xy 181.681405 4.200156)
			(xy 181.629729 4.268585) (xy 181.584588 4.341491) (xy 181.546366 4.418251) (xy 181.51539 4.49821)
			(xy 181.491923 4.580686) (xy 181.476167 4.664976) (xy 181.468255 4.750359) (xy 102.190309 4.750359)
			(xy 102.182397 4.664976) (xy 102.166641 4.580686) (xy 102.143174 4.49821) (xy 102.112198 4.418251)
			(xy 102.073976 4.341491) (xy 102.028835 4.268585) (xy 101.977159 4.200156) (xy 101.91939 4.136786)
			(xy 101.85602 4.079017) (xy 101.787591 4.027341) (xy 101.714685 3.9822) (xy 101.637925 3.943978)
			(xy 101.557966 3.913002) (xy 101.47549 3.889535) (xy 101.3912 3.873779) (xy 101.305817 3.865867)
			(xy 101.220067 3.865867) (xy 101.134684 3.873779) (xy 101.050394 3.889535) (xy 100.967918 3.913002)
			(xy 100.887959 3.943978) (xy 100.811199 3.9822) (xy 100.738293 4.027341) (xy 100.669864 4.079017)
			(xy 100.606494 4.136786) (xy 100.548725 4.200156) (xy 100.497049 4.268585) (xy 100.451908 4.341491)
			(xy 100.413686 4.418251) (xy 100.38271 4.49821) (xy 100.359243 4.580686) (xy 100.343487 4.664976)
			(xy 100.335575 4.750359) (xy 95.840309 4.750359) (xy 95.832397 4.664976) (xy 95.816641 4.580686)
			(xy 95.793174 4.49821) (xy 95.762198 4.418251) (xy 95.723976 4.341491) (xy 95.678835 4.268585) (xy 95.627159 4.200156)
			(xy 95.56939 4.136786) (xy 95.50602 4.079017) (xy 95.437591 4.027341) (xy 95.364685 3.9822) (xy 95.287925 3.943978)
			(xy 95.207966 3.913002) (xy 95.12549 3.889535) (xy 95.0412 3.873779) (xy 94.955817 3.865867) (xy 94.870067 3.865867)
			(xy 94.784684 3.873779) (xy 94.700394 3.889535) (xy 94.617918 3.913002) (xy 94.537959 3.943978) (xy 94.461199 3.9822)
			(xy 94.388293 4.027341) (xy 94.319864 4.079017) (xy 94.256494 4.136786) (xy 94.198725 4.200156) (xy 94.147049 4.268585)
			(xy 94.101908 4.341491) (xy 94.063686 4.418251) (xy 94.03271 4.49821) (xy 94.009243 4.580686) (xy 93.993487 4.664976)
			(xy 93.985575 4.750359) (xy 0.509016 4.750359) (xy 0.509016 -7.78002) (xy 0.509537 -7.835789) (xy 0.517873 -7.947015)
			(xy 0.534497 -8.057308) (xy 0.559316 -8.166049) (xy 0.592193 -8.272632) (xy 0.632942 -8.37646) (xy 0.681336 -8.476953)
			(xy 0.737105 -8.573548) (xy 0.799937 -8.665705) (xy 0.86948 -8.752909) (xy 0.945345 -8.834672) (xy 1.027108 -8.910538)
			(xy 1.114312 -8.980081) (xy 1.206469 -9.042912) (xy 1.303064 -9.098682) (xy 1.403556 -9.147076) (xy 1.507384 -9.187826)
			(xy 1.613967 -9.220703) (xy 1.722708 -9.245523) (xy 1.833001 -9.262147) (xy 1.944227 -9.270482) (xy 1.999996 -9.271)
			(xy 9.10209 -9.271) (xy 9.15786 -9.270479) (xy 9.269087 -9.262144) (xy 9.37938 -9.245521) (xy 9.488123 -9.220702)
			(xy 9.594707 -9.187826) (xy 9.698536 -9.147077) (xy 9.79903 -9.098683) (xy 9.895626 -9.042915) (xy 9.987784 -8.980083)
			(xy 10.07499 -8.910541) (xy 10.156754 -8.834676) (xy 10.232621 -8.752912) (xy 10.302165 -8.665708)
			(xy 10.364999 -8.573551) (xy 10.420769 -8.476956) (xy 10.469165 -8.376463) (xy 10.509916 -8.272635)
			(xy 10.542794 -8.166052) (xy 10.567616 -8.05731) (xy 10.584241 -7.947017) (xy 10.592578 -7.83579)
			(xy 10.59307 -7.78002) (xy 10.59307 0.40005) (xy 10.593555 0.470432) (xy 10.601447 0.610976) (xy 10.617208 0.750856)
			(xy 10.640787 0.889632) (xy 10.67211 1.026868) (xy 10.711079 1.162131) (xy 10.757571 1.294997) (xy 10.811439 1.425046)
			(xy 10.872515 1.551871) (xy 10.940606 1.675072) (xy 11.015497 1.794261) (xy 11.096954 1.909063) (xy 11.184719 2.019118)
			(xy 11.278518 2.124078) (xy 11.378053 2.223614) (xy 11.483014 2.317412) (xy 11.593068 2.405178) (xy 11.707871 2.486634)
			(xy 11.82706 2.561525) (xy 11.950261 2.629616) (xy 12.077085 2.690692) (xy 12.207135 2.74456) (xy 12.340001 2.791052)
			(xy 12.475264 2.83002) (xy 12.6125 2.861343) (xy 12.751276 2.884922) (xy 12.891156 2.900683) (xy 13.0317 2.908575)
			(xy 13.102082 2.909062) (xy 81.701894 2.909062) (xy 81.772277 2.908568) (xy 81.912821 2.900676) (xy 82.052702 2.884916)
			(xy 82.191479 2.861337) (xy 82.328715 2.830015) (xy 82.46398 2.791046) (xy 82.596846 2.744555) (xy 82.726897 2.690688)
			(xy 82.853723 2.629613) (xy 82.976925 2.561522) (xy 83.096116 2.486632) (xy 83.210919 2.405176) (xy 83.320975 2.317411)
			(xy 83.425937 2.223613) (xy 83.439191 2.210359) (xy 93.985575 2.210359) (xy 93.985575 2.296109) (xy 93.993487 2.381492)
			(xy 94.009243 2.465782) (xy 94.03271 2.548258) (xy 94.063686 2.628217) (xy 94.101908 2.704977) (xy 94.147049 2.777883)
			(xy 94.198725 2.846312) (xy 94.256494 2.909682) (xy 94.319864 2.967451) (xy 94.388293 3.019127) (xy 94.461199 3.064268)
			(xy 94.537959 3.10249) (xy 94.617918 3.133466) (xy 94.700394 3.156933) (xy 94.784684 3.172689) (xy 94.870067 3.180601)
			(xy 94.955817 3.180601) (xy 95.0412 3.172689) (xy 95.12549 3.156933) (xy 95.207966 3.133466) (xy 95.287925 3.10249)
			(xy 95.308598 3.092196) (xy 98.842576 3.092196) (xy 98.842576 3.955796) (xy 98.84308 3.985332) (xy 98.851124 4.043854)
			(xy 98.867061 4.100736) (xy 98.890596 4.154918) (xy 98.921289 4.205391) (xy 98.958569 4.251214) (xy 99.001741 4.291534)
			(xy 99.050001 4.3256) (xy 99.102451 4.352777) (xy 99.158112 4.372559) (xy 99.215949 4.384578) (xy 99.274884 4.388609)
			(xy 99.333819 4.384578) (xy 99.391656 4.372559) (xy 99.447317 4.352777) (xy 99.499767 4.3256) (xy 99.548027 4.291534)
			(xy 99.591199 4.251214) (xy 99.628479 4.205391) (xy 99.659172 4.154918) (xy 99.682707 4.100736) (xy 99.698644 4.043854)
			(xy 99.706688 3.985332) (xy 99.707192 3.955796) (xy 99.707192 3.092196) (xy 99.706688 3.06266) (xy 99.698644 3.004138)
			(xy 99.682707 2.947256) (xy 99.659172 2.893074) (xy 99.628479 2.842601) (xy 99.591199 2.796778) (xy 99.548027 2.756458)
			(xy 99.499767 2.722392) (xy 99.447317 2.695215) (xy 99.391656 2.675433) (xy 99.333819 2.663414) (xy 99.274884 2.659383)
			(xy 99.215949 2.663414) (xy 99.158112 2.675433) (xy 99.102451 2.695215) (xy 99.050001 2.722392) (xy 99.001741 2.756458)
			(xy 98.958569 2.796778) (xy 98.921289 2.842601) (xy 98.890596 2.893074) (xy 98.867061 2.947256) (xy 98.851124 3.004138)
			(xy 98.84308 3.06266) (xy 98.842576 3.092196) (xy 95.308598 3.092196) (xy 95.364685 3.064268) (xy 95.437591 3.019127)
			(xy 95.50602 2.967451) (xy 95.56939 2.909682) (xy 95.627159 2.846312) (xy 95.678835 2.777883) (xy 95.723976 2.704977)
			(xy 95.762198 2.628217) (xy 95.793174 2.548258) (xy 95.816641 2.465782) (xy 95.832397 2.381492) (xy 95.840309 2.296109)
			(xy 95.840804 2.253234) (xy 95.840309 2.210359) (xy 100.335575 2.210359) (xy 100.335575 2.296109)
			(xy 100.343487 2.381492) (xy 100.359243 2.465782) (xy 100.38271 2.548258) (xy 100.413686 2.628217)
			(xy 100.451908 2.704977) (xy 100.497049 2.777883) (xy 100.548725 2.846312) (xy 100.606494 2.909682)
			(xy 100.669864 2.967451) (xy 100.738293 3.019127) (xy 100.811199 3.064268) (xy 100.887959 3.10249)
			(xy 100.967918 3.133466) (xy 101.050394 3.156933) (xy 101.134684 3.172689) (xy 101.220067 3.180601)
			(xy 101.305817 3.180601) (xy 101.3912 3.172689) (xy 101.47549 3.156933) (xy 101.557966 3.133466)
			(xy 101.637925 3.10249) (xy 101.714685 3.064268) (xy 101.787591 3.019127) (xy 101.85602 2.967451)
			(xy 101.91939 2.909682) (xy 101.977159 2.846312) (xy 102.028835 2.777883) (xy 102.073976 2.704977)
			(xy 102.112198 2.628217) (xy 102.143174 2.548258) (xy 102.166641 2.465782) (xy 102.182397 2.381492)
			(xy 102.190309 2.296109) (xy 102.190804 2.253234) (xy 102.190309 2.210359) (xy 181.468255 2.210359)
			(xy 181.468255 2.296109) (xy 181.476167 2.381492) (xy 181.491923 2.465782) (xy 181.51539 2.548258)
			(xy 181.546366 2.628217) (xy 181.584588 2.704977) (xy 181.629729 2.777883) (xy 181.681405 2.846312)
			(xy 181.739174 2.909682) (xy 181.802544 2.967451) (xy 181.870973 3.019127) (xy 181.943879 3.064268)
			(xy 182.020639 3.10249) (xy 182.100598 3.133466) (xy 182.183074 3.156933) (xy 182.267364 3.172689)
			(xy 182.352747 3.180601) (xy 182.438497 3.180601) (xy 182.52388 3.172689) (xy 182.60817 3.156933)
			(xy 182.690646 3.133466) (xy 182.770605 3.10249) (xy 182.791278 3.092196) (xy 183.953912 3.092196)
			(xy 183.953912 3.955796) (xy 183.954416 3.985332) (xy 183.96246 4.043854) (xy 183.978397 4.100736)
			(xy 184.001932 4.154918) (xy 184.032625 4.205391) (xy 184.069905 4.251214) (xy 184.113077 4.291534)
			(xy 184.161337 4.3256) (xy 184.213787 4.352777) (xy 184.269448 4.372559) (xy 184.327285 4.384578)
			(xy 184.38622 4.388609) (xy 184.445155 4.384578) (xy 184.502992 4.372559) (xy 184.558653 4.352777)
			(xy 184.611103 4.3256) (xy 184.659363 4.291534) (xy 184.702535 4.251214) (xy 184.739815 4.205391)
			(xy 184.770508 4.154918) (xy 184.794043 4.100736) (xy 184.80998 4.043854) (xy 184.818024 3.985332)
			(xy 184.818528 3.955796) (xy 184.818528 3.769919) (xy 208.661241 3.769919) (xy 208.661241 3.855669)
			(xy 208.669153 3.941052) (xy 208.684909 4.025342) (xy 208.708376 4.107818) (xy 208.739352 4.187777)
			(xy 208.777574 4.264537) (xy 208.822715 4.337443) (xy 208.874391 4.405872) (xy 208.93216 4.469242)
			(xy 208.99553 4.527011) (xy 209.063959 4.578687) (xy 209.136865 4.623828) (xy 209.213625 4.66205)
			(xy 209.293584 4.693026) (xy 209.37606 4.716493) (xy 209.46035 4.732249) (xy 209.545733 4.740161)
			(xy 209.631483 4.740161) (xy 209.716866 4.732249) (xy 209.801156 4.716493) (xy 209.883632 4.693026)
			(xy 209.963591 4.66205) (xy 209.984264 4.651756) (xy 213.517988 4.651756) (xy 213.517988 5.515356)
			(xy 213.518492 5.54491) (xy 213.526541 5.603466) (xy 213.542487 5.660381) (xy 213.566036 5.714595)
			(xy 213.596747 5.765098) (xy 213.634049 5.810948) (xy 213.677246 5.851291) (xy 213.725535 5.885377)
			(xy 213.778015 5.91257) (xy 213.83371 5.932364) (xy 213.891581 5.94439) (xy 213.95055 5.948424) (xy 214.009519 5.94439)
			(xy 214.06739 5.932364) (xy 214.123085 5.91257) (xy 214.175565 5.885377) (xy 214.223854 5.851291)
			(xy 214.267051 5.810948) (xy 214.304353 5.765098) (xy 214.335064 5.714595) (xy 214.358613 5.660381)
			(xy 214.374559 5.603466) (xy 214.382608 5.54491) (xy 214.383112 5.515356) (xy 214.383112 4.651756)
			(xy 214.382608 4.622202) (xy 214.374559 4.563646) (xy 214.358613 4.506731) (xy 214.335064 4.452517)
			(xy 214.304353 4.402014) (xy 214.267051 4.356164) (xy 214.223854 4.315821) (xy 214.175565 4.281735)
			(xy 214.123085 4.254542) (xy 214.06739 4.234748) (xy 214.009519 4.222722) (xy 213.95055 4.218689)
			(xy 213.891581 4.222722) (xy 213.83371 4.234748) (xy 213.778015 4.254542) (xy 213.725535 4.281735)
			(xy 213.677246 4.315821) (xy 213.634049 4.356164) (xy 213.596747 4.402014) (xy 213.566036 4.452517)
			(xy 213.542487 4.506731) (xy 213.526541 4.563646) (xy 213.518492 4.622202) (xy 213.517988 4.651756)
			(xy 209.984264 4.651756) (xy 210.040351 4.623828) (xy 210.113257 4.578687) (xy 210.181686 4.527011)
			(xy 210.245056 4.469242) (xy 210.302825 4.405872) (xy 210.354501 4.337443) (xy 210.399642 4.264537)
			(xy 210.437864 4.187777) (xy 210.46884 4.107818) (xy 210.492307 4.025342) (xy 210.508063 3.941052)
			(xy 210.515975 3.855669) (xy 210.51647 3.812794) (xy 210.515975 3.769919) (xy 215.011241 3.769919)
			(xy 215.011241 3.855669) (xy 215.019153 3.941052) (xy 215.034909 4.025342) (xy 215.058376 4.107818)
			(xy 215.089352 4.187777) (xy 215.127574 4.264537) (xy 215.172715 4.337443) (xy 215.224391 4.405872)
			(xy 215.28216 4.469242) (xy 215.34553 4.527011) (xy 215.413959 4.578687) (xy 215.486865 4.623828)
			(xy 215.563625 4.66205) (xy 215.643584 4.693026) (xy 215.72606 4.716493) (xy 215.81035 4.732249)
			(xy 215.895733 4.740161) (xy 215.981483 4.740161) (xy 216.066866 4.732249) (xy 216.151156 4.716493)
			(xy 216.233632 4.693026) (xy 216.313591 4.66205) (xy 216.390351 4.623828) (xy 216.463257 4.578687)
			(xy 216.531686 4.527011) (xy 216.595056 4.469242) (xy 216.652825 4.405872) (xy 216.704501 4.337443)
			(xy 216.749642 4.264537) (xy 216.787864 4.187777) (xy 216.81884 4.107818) (xy 216.842307 4.025342)
			(xy 216.858063 3.941052) (xy 216.865975 3.855669) (xy 216.86647 3.812794) (xy 216.865975 3.769919)
			(xy 296.143921 3.769919) (xy 296.143921 3.855669) (xy 296.151833 3.941052) (xy 296.167589 4.025342)
			(xy 296.191056 4.107818) (xy 296.222032 4.187777) (xy 296.260254 4.264537) (xy 296.305395 4.337443)
			(xy 296.357071 4.405872) (xy 296.41484 4.469242) (xy 296.47821 4.527011) (xy 296.546639 4.578687)
			(xy 296.619545 4.623828) (xy 296.696305 4.66205) (xy 296.776264 4.693026) (xy 296.85874 4.716493)
			(xy 296.94303 4.732249) (xy 297.028413 4.740161) (xy 297.114163 4.740161) (xy 297.199546 4.732249)
			(xy 297.283836 4.716493) (xy 297.366312 4.693026) (xy 297.446271 4.66205) (xy 297.466944 4.651756)
			(xy 298.629324 4.651756) (xy 298.629324 5.515356) (xy 298.629828 5.54491) (xy 298.637877 5.603466)
			(xy 298.653823 5.660381) (xy 298.677372 5.714595) (xy 298.708083 5.765098) (xy 298.745385 5.810948)
			(xy 298.788582 5.851291) (xy 298.836871 5.885377) (xy 298.889351 5.91257) (xy 298.945046 5.932364)
			(xy 299.002917 5.94439) (xy 299.061886 5.948424) (xy 299.120855 5.94439) (xy 299.178726 5.932364)
			(xy 299.234421 5.91257) (xy 299.286901 5.885377) (xy 299.33519 5.851291) (xy 299.378387 5.810948)
			(xy 299.415689 5.765098) (xy 299.4464 5.714595) (xy 299.469949 5.660381) (xy 299.485895 5.603466)
			(xy 299.493944 5.54491) (xy 299.494448 5.515356) (xy 299.494448 4.651756) (xy 299.493944 4.622202)
			(xy 299.485895 4.563646) (xy 299.469949 4.506731) (xy 299.4464 4.452517) (xy 299.415689 4.402014)
			(xy 299.378387 4.356164) (xy 299.33519 4.315821) (xy 299.286901 4.281735) (xy 299.234421 4.254542)
			(xy 299.178726 4.234748) (xy 299.120855 4.222722) (xy 299.061886 4.218689) (xy 299.002917 4.222722)
			(xy 298.945046 4.234748) (xy 298.889351 4.254542) (xy 298.836871 4.281735) (xy 298.788582 4.315821)
			(xy 298.745385 4.356164) (xy 298.708083 4.402014) (xy 298.677372 4.452517) (xy 298.653823 4.506731)
			(xy 298.637877 4.563646) (xy 298.629828 4.622202) (xy 298.629324 4.651756) (xy 297.466944 4.651756)
			(xy 297.523031 4.623828) (xy 297.595937 4.578687) (xy 297.664366 4.527011) (xy 297.727736 4.469242)
			(xy 297.785505 4.405872) (xy 297.837181 4.337443) (xy 297.882322 4.264537) (xy 297.920544 4.187777)
			(xy 297.95152 4.107818) (xy 297.974987 4.025342) (xy 297.990743 3.941052) (xy 297.998655 3.855669)
			(xy 297.99915 3.812794) (xy 297.998655 3.769919) (xy 302.493921 3.769919) (xy 302.493921 3.855669)
			(xy 302.501833 3.941052) (xy 302.517589 4.025342) (xy 302.541056 4.107818) (xy 302.572032 4.187777)
			(xy 302.610254 4.264537) (xy 302.655395 4.337443) (xy 302.707071 4.405872) (xy 302.76484 4.469242)
			(xy 302.82821 4.527011) (xy 302.896639 4.578687) (xy 302.969545 4.623828) (xy 303.046305 4.66205)
			(xy 303.126264 4.693026) (xy 303.20874 4.716493) (xy 303.29303 4.732249) (xy 303.378413 4.740161)
			(xy 303.464163 4.740161) (xy 303.549546 4.732249) (xy 303.633836 4.716493) (xy 303.716312 4.693026)
			(xy 303.796271 4.66205) (xy 303.873031 4.623828) (xy 303.945937 4.578687) (xy 304.014366 4.527011)
			(xy 304.077736 4.469242) (xy 304.135505 4.405872) (xy 304.187181 4.337443) (xy 304.232322 4.264537)
			(xy 304.270544 4.187777) (xy 304.30152 4.107818) (xy 304.324987 4.025342) (xy 304.340743 3.941052)
			(xy 304.348655 3.855669) (xy 304.34915 3.812794) (xy 304.348655 3.769919) (xy 311.155321 3.769919)
			(xy 311.155321 3.855669) (xy 311.163233 3.941052) (xy 311.178989 4.025342) (xy 311.202456 4.107818)
			(xy 311.233432 4.187777) (xy 311.271654 4.264537) (xy 311.316795 4.337443) (xy 311.368471 4.405872)
			(xy 311.42624 4.469242) (xy 311.48961 4.527011) (xy 311.558039 4.578687) (xy 311.630945 4.623828)
			(xy 311.707705 4.66205) (xy 311.787664 4.693026) (xy 311.87014 4.716493) (xy 311.95443 4.732249)
			(xy 312.039813 4.740161) (xy 312.125563 4.740161) (xy 312.210946 4.732249) (xy 312.295236 4.716493)
			(xy 312.377712 4.693026) (xy 312.457671 4.66205) (xy 312.478344 4.651756) (xy 316.012068 4.651756)
			(xy 316.012068 5.515356) (xy 316.012572 5.54491) (xy 316.020621 5.603466) (xy 316.036567 5.660381)
			(xy 316.060116 5.714595) (xy 316.090827 5.765098) (xy 316.128129 5.810948) (xy 316.171326 5.851291)
			(xy 316.219615 5.885377) (xy 316.272095 5.91257) (xy 316.32779 5.932364) (xy 316.385661 5.94439)
			(xy 316.44463 5.948424) (xy 316.503599 5.94439) (xy 316.56147 5.932364) (xy 316.617165 5.91257) (xy 316.669645 5.885377)
			(xy 316.717934 5.851291) (xy 316.761131 5.810948) (xy 316.798433 5.765098) (xy 316.829144 5.714595)
			(xy 316.852693 5.660381) (xy 316.868639 5.603466) (xy 316.876688 5.54491) (xy 316.877192 5.515356)
			(xy 316.877192 4.651756) (xy 316.876688 4.622202) (xy 316.868639 4.563646) (xy 316.852693 4.506731)
			(xy 316.829144 4.452517) (xy 316.798433 4.402014) (xy 316.761131 4.356164) (xy 316.717934 4.315821)
			(xy 316.669645 4.281735) (xy 316.617165 4.254542) (xy 316.56147 4.234748) (xy 316.503599 4.222722)
			(xy 316.44463 4.218689) (xy 316.385661 4.222722) (xy 316.32779 4.234748) (xy 316.272095 4.254542)
			(xy 316.219615 4.281735) (xy 316.171326 4.315821) (xy 316.128129 4.356164) (xy 316.090827 4.402014)
			(xy 316.060116 4.452517) (xy 316.036567 4.506731) (xy 316.020621 4.563646) (xy 316.012572 4.622202)
			(xy 316.012068 4.651756) (xy 312.478344 4.651756) (xy 312.534431 4.623828) (xy 312.607337 4.578687)
			(xy 312.675766 4.527011) (xy 312.739136 4.469242) (xy 312.796905 4.405872) (xy 312.848581 4.337443)
			(xy 312.893722 4.264537) (xy 312.931944 4.187777) (xy 312.96292 4.107818) (xy 312.986387 4.025342)
			(xy 313.002143 3.941052) (xy 313.010055 3.855669) (xy 313.01055 3.812794) (xy 313.010055 3.769919)
			(xy 317.505321 3.769919) (xy 317.505321 3.855669) (xy 317.513233 3.941052) (xy 317.528989 4.025342)
			(xy 317.552456 4.107818) (xy 317.583432 4.187777) (xy 317.621654 4.264537) (xy 317.666795 4.337443)
			(xy 317.718471 4.405872) (xy 317.77624 4.469242) (xy 317.83961 4.527011) (xy 317.908039 4.578687)
			(xy 317.980945 4.623828) (xy 318.057705 4.66205) (xy 318.137664 4.693026) (xy 318.22014 4.716493)
			(xy 318.30443 4.732249) (xy 318.389813 4.740161) (xy 318.475563 4.740161) (xy 318.560946 4.732249)
			(xy 318.645236 4.716493) (xy 318.727712 4.693026) (xy 318.807671 4.66205) (xy 318.884431 4.623828)
			(xy 318.957337 4.578687) (xy 319.025766 4.527011) (xy 319.089136 4.469242) (xy 319.146905 4.405872)
			(xy 319.198581 4.337443) (xy 319.243722 4.264537) (xy 319.281944 4.187777) (xy 319.31292 4.107818)
			(xy 319.336387 4.025342) (xy 319.352143 3.941052) (xy 319.360055 3.855669) (xy 319.36055 3.812794)
			(xy 319.360055 3.769919) (xy 361.894107 3.769919) (xy 361.894107 3.855669) (xy 361.902019 3.941052)
			(xy 361.917775 4.025342) (xy 361.941242 4.107818) (xy 361.972218 4.187777) (xy 362.01044 4.264537)
			(xy 362.055581 4.337443) (xy 362.107257 4.405872) (xy 362.165026 4.469242) (xy 362.228396 4.527011)
			(xy 362.296825 4.578687) (xy 362.369731 4.623828) (xy 362.446491 4.66205) (xy 362.52645 4.693026)
			(xy 362.608926 4.716493) (xy 362.693216 4.732249) (xy 362.778599 4.740161) (xy 362.864349 4.740161)
			(xy 362.949732 4.732249) (xy 363.034022 4.716493) (xy 363.116498 4.693026) (xy 363.196457 4.66205)
			(xy 363.21713 4.651756) (xy 364.379764 4.651756) (xy 364.379764 5.515356) (xy 364.380268 5.544892)
			(xy 364.388312 5.603414) (xy 364.404249 5.660296) (xy 364.427784 5.714478) (xy 364.458477 5.764951)
			(xy 364.495757 5.810774) (xy 364.538929 5.851094) (xy 364.587189 5.88516) (xy 364.639639 5.912337)
			(xy 364.6953 5.932119) (xy 364.753137 5.944138) (xy 364.812072 5.948169) (xy 364.871007 5.944138)
			(xy 364.928844 5.932119) (xy 364.984505 5.912337) (xy 365.036955 5.88516) (xy 365.085215 5.851094)
			(xy 365.128387 5.810774) (xy 365.165667 5.764951) (xy 365.19636 5.714478) (xy 365.219895 5.660296)
			(xy 365.235832 5.603414) (xy 365.243876 5.544892) (xy 365.24438 5.515356) (xy 365.24438 4.836973)
			(xy 385.651997 4.836973) (xy 385.651997 4.922723) (xy 385.659909 5.008106) (xy 385.675665 5.092396)
			(xy 385.699132 5.174872) (xy 385.730108 5.254831) (xy 385.76833 5.331591) (xy 385.813471 5.404497)
			(xy 385.865147 5.472926) (xy 385.922916 5.536296) (xy 385.986286 5.594065) (xy 386.054715 5.645741)
			(xy 386.127621 5.690882) (xy 386.204381 5.729104) (xy 386.28434 5.76008) (xy 386.366816 5.783547)
			(xy 386.451106 5.799303) (xy 386.536489 5.807215) (xy 386.622239 5.807215) (xy 386.707622 5.799303)
			(xy 386.791912 5.783547) (xy 386.874388 5.76008) (xy 386.954347 5.729104) (xy 386.97502 5.71881)
			(xy 390.508744 5.71881) (xy 390.508744 6.58241) (xy 390.509248 6.611964) (xy 390.517297 6.67052)
			(xy 390.533243 6.727435) (xy 390.556792 6.781649) (xy 390.587503 6.832152) (xy 390.624805 6.878002)
			(xy 390.668002 6.918345) (xy 390.716291 6.952431) (xy 390.768771 6.979624) (xy 390.824466 6.999418)
			(xy 390.882337 7.011444) (xy 390.941306 7.015478) (xy 391.000275 7.011444) (xy 391.058146 6.999418)
			(xy 391.113841 6.979624) (xy 391.166321 6.952431) (xy 391.21461 6.918345) (xy 391.257807 6.878002)
			(xy 391.295109 6.832152) (xy 391.32582 6.781649) (xy 391.349369 6.727435) (xy 391.365315 6.67052)
			(xy 391.373364 6.611964) (xy 391.373868 6.58241) (xy 391.373868 5.71881) (xy 391.373364 5.689256)
			(xy 391.365315 5.6307) (xy 391.349369 5.573785) (xy 391.32582 5.519571) (xy 391.295109 5.469068)
			(xy 391.257807 5.423218) (xy 391.21461 5.382875) (xy 391.166321 5.348789) (xy 391.113841 5.321596)
			(xy 391.058146 5.301802) (xy 391.000275 5.289776) (xy 390.941306 5.285743) (xy 390.882337 5.289776)
			(xy 390.824466 5.301802) (xy 390.768771 5.321596) (xy 390.716291 5.348789) (xy 390.668002 5.382875)
			(xy 390.624805 5.423218) (xy 390.587503 5.469068) (xy 390.556792 5.519571) (xy 390.533243 5.573785)
			(xy 390.517297 5.6307) (xy 390.509248 5.689256) (xy 390.508744 5.71881) (xy 386.97502 5.71881) (xy 387.031107 5.690882)
			(xy 387.104013 5.645741) (xy 387.172442 5.594065) (xy 387.235812 5.536296) (xy 387.293581 5.472926)
			(xy 387.345257 5.404497) (xy 387.390398 5.331591) (xy 387.42862 5.254831) (xy 387.459596 5.174872)
			(xy 387.483063 5.092396) (xy 387.498819 5.008106) (xy 387.506731 4.922723) (xy 387.507226 4.879848)
			(xy 387.506731 4.836973) (xy 392.001997 4.836973) (xy 392.001997 4.922723) (xy 392.009909 5.008106)
			(xy 392.025665 5.092396) (xy 392.049132 5.174872) (xy 392.080108 5.254831) (xy 392.11833 5.331591)
			(xy 392.163471 5.404497) (xy 392.215147 5.472926) (xy 392.272916 5.536296) (xy 392.336286 5.594065)
			(xy 392.404715 5.645741) (xy 392.477621 5.690882) (xy 392.554381 5.729104) (xy 392.63434 5.76008)
			(xy 392.716816 5.783547) (xy 392.801106 5.799303) (xy 392.886489 5.807215) (xy 392.972239 5.807215)
			(xy 393.057622 5.799303) (xy 393.141912 5.783547) (xy 393.224388 5.76008) (xy 393.304347 5.729104)
			(xy 393.381107 5.690882) (xy 393.454013 5.645741) (xy 393.522442 5.594065) (xy 393.585812 5.536296)
			(xy 393.643581 5.472926) (xy 393.695257 5.404497) (xy 393.740398 5.331591) (xy 393.77862 5.254831)
			(xy 393.809596 5.174872) (xy 393.833063 5.092396) (xy 393.848819 5.008106) (xy 393.856731 4.922723)
			(xy 393.857226 4.879848) (xy 393.856731 4.836973) (xy 436.390783 4.836973) (xy 436.390783 4.922723)
			(xy 436.398695 5.008106) (xy 436.414451 5.092396) (xy 436.437918 5.174872) (xy 436.468894 5.254831)
			(xy 436.507116 5.331591) (xy 436.552257 5.404497) (xy 436.603933 5.472926) (xy 436.661702 5.536296)
			(xy 436.725072 5.594065) (xy 436.793501 5.645741) (xy 436.866407 5.690882) (xy 436.943167 5.729104)
			(xy 437.023126 5.76008) (xy 437.105602 5.783547) (xy 437.189892 5.799303) (xy 437.275275 5.807215)
			(xy 437.361025 5.807215) (xy 437.446408 5.799303) (xy 437.530698 5.783547) (xy 437.613174 5.76008)
			(xy 437.693133 5.729104) (xy 437.713806 5.71881) (xy 438.87644 5.71881) (xy 438.87644 6.58241) (xy 438.876944 6.611946)
			(xy 438.884988 6.670468) (xy 438.900925 6.72735) (xy 438.92446 6.781532) (xy 438.955153 6.832005)
			(xy 438.992433 6.877828) (xy 439.035605 6.918148) (xy 439.083865 6.952214) (xy 439.136315 6.979391)
			(xy 439.191976 6.999173) (xy 439.249813 7.011192) (xy 439.308748 7.015223) (xy 439.367683 7.011192)
			(xy 439.42552 6.999173) (xy 439.481181 6.979391) (xy 439.533631 6.952214) (xy 439.581891 6.918148)
			(xy 439.625063 6.877828) (xy 439.662343 6.832005) (xy 439.693036 6.781532) (xy 439.716571 6.72735)
			(xy 439.732508 6.670468) (xy 439.740552 6.611946) (xy 439.741056 6.58241) (xy 439.741056 5.71881)
			(xy 439.740552 5.689274) (xy 439.732508 5.630752) (xy 439.716571 5.57387) (xy 439.693036 5.519688)
			(xy 439.662343 5.469215) (xy 439.625063 5.423392) (xy 439.581891 5.383072) (xy 439.533631 5.349006)
			(xy 439.481181 5.321829) (xy 439.42552 5.302047) (xy 439.367683 5.290028) (xy 439.308748 5.285997)
			(xy 439.249813 5.290028) (xy 439.191976 5.302047) (xy 439.136315 5.321829) (xy 439.083865 5.349006)
			(xy 439.035605 5.383072) (xy 438.992433 5.423392) (xy 438.955153 5.469215) (xy 438.92446 5.519688)
			(xy 438.900925 5.57387) (xy 438.884988 5.630752) (xy 438.876944 5.689274) (xy 438.87644 5.71881)
			(xy 437.713806 5.71881) (xy 437.769893 5.690882) (xy 437.842799 5.645741) (xy 437.911228 5.594065)
			(xy 437.974598 5.536296) (xy 438.032367 5.472926) (xy 438.084043 5.404497) (xy 438.129184 5.331591)
			(xy 438.167406 5.254831) (xy 438.198382 5.174872) (xy 438.221849 5.092396) (xy 438.237605 5.008106)
			(xy 438.245517 4.922723) (xy 438.246012 4.879848) (xy 438.245517 4.836973) (xy 442.740783 4.836973)
			(xy 442.740783 4.922723) (xy 442.748695 5.008106) (xy 442.764451 5.092396) (xy 442.787918 5.174872)
			(xy 442.818894 5.254831) (xy 442.857116 5.331591) (xy 442.902257 5.404497) (xy 442.953933 5.472926)
			(xy 443.011702 5.536296) (xy 443.075072 5.594065) (xy 443.143501 5.645741) (xy 443.216407 5.690882)
			(xy 443.293167 5.729104) (xy 443.373126 5.76008) (xy 443.455602 5.783547) (xy 443.539892 5.799303)
			(xy 443.625275 5.807215) (xy 443.711025 5.807215) (xy 443.796408 5.799303) (xy 443.880698 5.783547)
			(xy 443.963174 5.76008) (xy 444.043133 5.729104) (xy 444.119893 5.690882) (xy 444.192799 5.645741)
			(xy 444.261228 5.594065) (xy 444.324598 5.536296) (xy 444.382367 5.472926) (xy 444.434043 5.404497)
			(xy 444.479184 5.331591) (xy 444.517406 5.254831) (xy 444.548382 5.174872) (xy 444.571849 5.092396)
			(xy 444.587605 5.008106) (xy 444.595517 4.922723) (xy 444.596012 4.879848) (xy 444.595517 4.836973)
			(xy 444.587605 4.75159) (xy 444.571849 4.6673) (xy 444.548382 4.584824) (xy 444.517406 4.504865)
			(xy 444.479184 4.428105) (xy 444.434043 4.355199) (xy 444.382367 4.28677) (xy 444.324598 4.2234)
			(xy 444.261228 4.165631) (xy 444.192799 4.113955) (xy 444.119893 4.068814) (xy 444.043133 4.030592)
			(xy 443.963174 3.999616) (xy 443.880698 3.976149) (xy 443.796408 3.960393) (xy 443.711025 3.952481)
			(xy 443.625275 3.952481) (xy 443.539892 3.960393) (xy 443.455602 3.976149) (xy 443.373126 3.999616)
			(xy 443.293167 4.030592) (xy 443.216407 4.068814) (xy 443.143501 4.113955) (xy 443.075072 4.165631)
			(xy 443.011702 4.2234) (xy 442.953933 4.28677) (xy 442.902257 4.355199) (xy 442.857116 4.428105)
			(xy 442.818894 4.504865) (xy 442.787918 4.584824) (xy 442.764451 4.6673) (xy 442.748695 4.75159)
			(xy 442.740783 4.836973) (xy 438.245517 4.836973) (xy 438.237605 4.75159) (xy 438.221849 4.6673)
			(xy 438.198382 4.584824) (xy 438.167406 4.504865) (xy 438.129184 4.428105) (xy 438.084043 4.355199)
			(xy 438.032367 4.28677) (xy 437.974598 4.2234) (xy 437.911228 4.165631) (xy 437.842799 4.113955)
			(xy 437.769893 4.068814) (xy 437.693133 4.030592) (xy 437.613174 3.999616) (xy 437.530698 3.976149)
			(xy 437.446408 3.960393) (xy 437.361025 3.952481) (xy 437.275275 3.952481) (xy 437.189892 3.960393)
			(xy 437.105602 3.976149) (xy 437.023126 3.999616) (xy 436.943167 4.030592) (xy 436.866407 4.068814)
			(xy 436.793501 4.113955) (xy 436.725072 4.165631) (xy 436.661702 4.2234) (xy 436.603933 4.28677)
			(xy 436.552257 4.355199) (xy 436.507116 4.428105) (xy 436.468894 4.504865) (xy 436.437918 4.584824)
			(xy 436.414451 4.6673) (xy 436.398695 4.75159) (xy 436.390783 4.836973) (xy 393.856731 4.836973)
			(xy 393.848819 4.75159) (xy 393.833063 4.6673) (xy 393.809596 4.584824) (xy 393.77862 4.504865) (xy 393.740398 4.428105)
			(xy 393.695257 4.355199) (xy 393.643581 4.28677) (xy 393.585812 4.2234) (xy 393.522442 4.165631)
			(xy 393.454013 4.113955) (xy 393.381107 4.068814) (xy 393.304347 4.030592) (xy 393.224388 3.999616)
			(xy 393.141912 3.976149) (xy 393.057622 3.960393) (xy 392.972239 3.952481) (xy 392.886489 3.952481)
			(xy 392.801106 3.960393) (xy 392.716816 3.976149) (xy 392.63434 3.999616) (xy 392.554381 4.030592)
			(xy 392.477621 4.068814) (xy 392.404715 4.113955) (xy 392.336286 4.165631) (xy 392.272916 4.2234)
			(xy 392.215147 4.28677) (xy 392.163471 4.355199) (xy 392.11833 4.428105) (xy 392.080108 4.504865)
			(xy 392.049132 4.584824) (xy 392.025665 4.6673) (xy 392.009909 4.75159) (xy 392.001997 4.836973)
			(xy 387.506731 4.836973) (xy 387.498819 4.75159) (xy 387.483063 4.6673) (xy 387.459596 4.584824)
			(xy 387.42862 4.504865) (xy 387.390398 4.428105) (xy 387.345257 4.355199) (xy 387.293581 4.28677)
			(xy 387.235812 4.2234) (xy 387.172442 4.165631) (xy 387.104013 4.113955) (xy 387.031107 4.068814)
			(xy 386.954347 4.030592) (xy 386.874388 3.999616) (xy 386.791912 3.976149) (xy 386.707622 3.960393)
			(xy 386.622239 3.952481) (xy 386.536489 3.952481) (xy 386.451106 3.960393) (xy 386.366816 3.976149)
			(xy 386.28434 3.999616) (xy 386.204381 4.030592) (xy 386.127621 4.068814) (xy 386.054715 4.113955)
			(xy 385.986286 4.165631) (xy 385.922916 4.2234) (xy 385.865147 4.28677) (xy 385.813471 4.355199)
			(xy 385.76833 4.428105) (xy 385.730108 4.504865) (xy 385.699132 4.584824) (xy 385.675665 4.6673)
			(xy 385.659909 4.75159) (xy 385.651997 4.836973) (xy 365.24438 4.836973) (xy 365.24438 4.651756)
			(xy 365.243876 4.62222) (xy 365.235832 4.563698) (xy 365.219895 4.506816) (xy 365.19636 4.452634)
			(xy 365.165667 4.402161) (xy 365.128387 4.356338) (xy 365.085215 4.316018) (xy 365.036955 4.281952)
			(xy 364.984505 4.254775) (xy 364.928844 4.234993) (xy 364.871007 4.222974) (xy 364.812072 4.218943)
			(xy 364.753137 4.222974) (xy 364.6953 4.234993) (xy 364.639639 4.254775) (xy 364.587189 4.281952)
			(xy 364.538929 4.316018) (xy 364.495757 4.356338) (xy 364.458477 4.402161) (xy 364.427784 4.452634)
			(xy 364.404249 4.506816) (xy 364.388312 4.563698) (xy 364.380268 4.62222) (xy 364.379764 4.651756)
			(xy 363.21713 4.651756) (xy 363.273217 4.623828) (xy 363.346123 4.578687) (xy 363.414552 4.527011)
			(xy 363.477922 4.469242) (xy 363.535691 4.405872) (xy 363.587367 4.337443) (xy 363.632508 4.264537)
			(xy 363.67073 4.187777) (xy 363.701706 4.107818) (xy 363.725173 4.025342) (xy 363.740929 3.941052)
			(xy 363.748841 3.855669) (xy 363.749336 3.812794) (xy 363.748841 3.769919) (xy 368.244107 3.769919)
			(xy 368.244107 3.855669) (xy 368.252019 3.941052) (xy 368.267775 4.025342) (xy 368.291242 4.107818)
			(xy 368.322218 4.187777) (xy 368.36044 4.264537) (xy 368.405581 4.337443) (xy 368.457257 4.405872)
			(xy 368.515026 4.469242) (xy 368.578396 4.527011) (xy 368.646825 4.578687) (xy 368.719731 4.623828)
			(xy 368.796491 4.66205) (xy 368.87645 4.693026) (xy 368.958926 4.716493) (xy 369.043216 4.732249)
			(xy 369.128599 4.740161) (xy 369.214349 4.740161) (xy 369.299732 4.732249) (xy 369.384022 4.716493)
			(xy 369.466498 4.693026) (xy 369.546457 4.66205) (xy 369.623217 4.623828) (xy 369.696123 4.578687)
			(xy 369.764552 4.527011) (xy 369.827922 4.469242) (xy 369.885691 4.405872) (xy 369.937367 4.337443)
			(xy 369.982508 4.264537) (xy 370.02073 4.187777) (xy 370.051706 4.107818) (xy 370.075173 4.025342)
			(xy 370.090929 3.941052) (xy 370.098841 3.855669) (xy 370.099336 3.812794) (xy 370.098841 3.769919)
			(xy 370.090929 3.684536) (xy 370.075173 3.600246) (xy 370.051706 3.51777) (xy 370.02073 3.437811)
			(xy 369.982508 3.361051) (xy 369.937367 3.288145) (xy 369.885691 3.219716) (xy 369.827922 3.156346)
			(xy 369.764552 3.098577) (xy 369.696123 3.046901) (xy 369.623217 3.00176) (xy 369.546457 2.963538)
			(xy 369.466498 2.932562) (xy 369.384022 2.909095) (xy 369.299732 2.893339) (xy 369.214349 2.885427)
			(xy 369.128599 2.885427) (xy 369.043216 2.893339) (xy 368.958926 2.909095) (xy 368.87645 2.932562)
			(xy 368.796491 2.963538) (xy 368.719731 3.00176) (xy 368.646825 3.046901) (xy 368.578396 3.098577)
			(xy 368.515026 3.156346) (xy 368.457257 3.219716) (xy 368.405581 3.288145) (xy 368.36044 3.361051)
			(xy 368.322218 3.437811) (xy 368.291242 3.51777) (xy 368.267775 3.600246) (xy 368.252019 3.684536)
			(xy 368.244107 3.769919) (xy 363.748841 3.769919) (xy 363.740929 3.684536) (xy 363.725173 3.600246)
			(xy 363.701706 3.51777) (xy 363.67073 3.437811) (xy 363.632508 3.361051) (xy 363.587367 3.288145)
			(xy 363.535691 3.219716) (xy 363.477922 3.156346) (xy 363.414552 3.098577) (xy 363.346123 3.046901)
			(xy 363.273217 3.00176) (xy 363.196457 2.963538) (xy 363.116498 2.932562) (xy 363.034022 2.909095)
			(xy 362.949732 2.893339) (xy 362.864349 2.885427) (xy 362.778599 2.885427) (xy 362.693216 2.893339)
			(xy 362.608926 2.909095) (xy 362.52645 2.932562) (xy 362.446491 2.963538) (xy 362.369731 3.00176)
			(xy 362.296825 3.046901) (xy 362.228396 3.098577) (xy 362.165026 3.156346) (xy 362.107257 3.219716)
			(xy 362.055581 3.288145) (xy 362.01044 3.361051) (xy 361.972218 3.437811) (xy 361.941242 3.51777)
			(xy 361.917775 3.600246) (xy 361.902019 3.684536) (xy 361.894107 3.769919) (xy 319.360055 3.769919)
			(xy 319.352143 3.684536) (xy 319.336387 3.600246) (xy 319.31292 3.51777) (xy 319.281944 3.437811)
			(xy 319.243722 3.361051) (xy 319.198581 3.288145) (xy 319.146905 3.219716) (xy 319.089136 3.156346)
			(xy 319.025766 3.098577) (xy 318.957337 3.046901) (xy 318.884431 3.00176) (xy 318.807671 2.963538)
			(xy 318.727712 2.932562) (xy 318.645236 2.909095) (xy 318.560946 2.893339) (xy 318.475563 2.885427)
			(xy 318.389813 2.885427) (xy 318.30443 2.893339) (xy 318.22014 2.909095) (xy 318.137664 2.932562)
			(xy 318.057705 2.963538) (xy 317.980945 3.00176) (xy 317.908039 3.046901) (xy 317.83961 3.098577)
			(xy 317.77624 3.156346) (xy 317.718471 3.219716) (xy 317.666795 3.288145) (xy 317.621654 3.361051)
			(xy 317.583432 3.437811) (xy 317.552456 3.51777) (xy 317.528989 3.600246) (xy 317.513233 3.684536)
			(xy 317.505321 3.769919) (xy 313.010055 3.769919) (xy 313.002143 3.684536) (xy 312.986387 3.600246)
			(xy 312.96292 3.51777) (xy 312.931944 3.437811) (xy 312.893722 3.361051) (xy 312.848581 3.288145)
			(xy 312.796905 3.219716) (xy 312.739136 3.156346) (xy 312.675766 3.098577) (xy 312.607337 3.046901)
			(xy 312.534431 3.00176) (xy 312.457671 2.963538) (xy 312.377712 2.932562) (xy 312.295236 2.909095)
			(xy 312.210946 2.893339) (xy 312.125563 2.885427) (xy 312.039813 2.885427) (xy 311.95443 2.893339)
			(xy 311.87014 2.909095) (xy 311.787664 2.932562) (xy 311.707705 2.963538) (xy 311.630945 3.00176)
			(xy 311.558039 3.046901) (xy 311.48961 3.098577) (xy 311.42624 3.156346) (xy 311.368471 3.219716)
			(xy 311.316795 3.288145) (xy 311.271654 3.361051) (xy 311.233432 3.437811) (xy 311.202456 3.51777)
			(xy 311.178989 3.600246) (xy 311.163233 3.684536) (xy 311.155321 3.769919) (xy 304.348655 3.769919)
			(xy 304.340743 3.684536) (xy 304.324987 3.600246) (xy 304.30152 3.51777) (xy 304.270544 3.437811)
			(xy 304.232322 3.361051) (xy 304.187181 3.288145) (xy 304.135505 3.219716) (xy 304.077736 3.156346)
			(xy 304.014366 3.098577) (xy 303.945937 3.046901) (xy 303.873031 3.00176) (xy 303.796271 2.963538)
			(xy 303.716312 2.932562) (xy 303.633836 2.909095) (xy 303.549546 2.893339) (xy 303.464163 2.885427)
			(xy 303.378413 2.885427) (xy 303.29303 2.893339) (xy 303.20874 2.909095) (xy 303.126264 2.932562)
			(xy 303.046305 2.963538) (xy 302.969545 3.00176) (xy 302.896639 3.046901) (xy 302.82821 3.098577)
			(xy 302.76484 3.156346) (xy 302.707071 3.219716) (xy 302.655395 3.288145) (xy 302.610254 3.361051)
			(xy 302.572032 3.437811) (xy 302.541056 3.51777) (xy 302.517589 3.600246) (xy 302.501833 3.684536)
			(xy 302.493921 3.769919) (xy 297.998655 3.769919) (xy 297.990743 3.684536) (xy 297.974987 3.600246)
			(xy 297.95152 3.51777) (xy 297.920544 3.437811) (xy 297.882322 3.361051) (xy 297.837181 3.288145)
			(xy 297.785505 3.219716) (xy 297.727736 3.156346) (xy 297.664366 3.098577) (xy 297.595937 3.046901)
			(xy 297.523031 3.00176) (xy 297.446271 2.963538) (xy 297.366312 2.932562) (xy 297.283836 2.909095)
			(xy 297.199546 2.893339) (xy 297.114163 2.885427) (xy 297.028413 2.885427) (xy 296.94303 2.893339)
			(xy 296.85874 2.909095) (xy 296.776264 2.932562) (xy 296.696305 2.963538) (xy 296.619545 3.00176)
			(xy 296.546639 3.046901) (xy 296.47821 3.098577) (xy 296.41484 3.156346) (xy 296.357071 3.219716)
			(xy 296.305395 3.288145) (xy 296.260254 3.361051) (xy 296.222032 3.437811) (xy 296.191056 3.51777)
			(xy 296.167589 3.600246) (xy 296.151833 3.684536) (xy 296.143921 3.769919) (xy 216.865975 3.769919)
			(xy 216.858063 3.684536) (xy 216.842307 3.600246) (xy 216.81884 3.51777) (xy 216.787864 3.437811)
			(xy 216.749642 3.361051) (xy 216.704501 3.288145) (xy 216.652825 3.219716) (xy 216.595056 3.156346)
			(xy 216.531686 3.098577) (xy 216.463257 3.046901) (xy 216.390351 3.00176) (xy 216.313591 2.963538)
			(xy 216.233632 2.932562) (xy 216.151156 2.909095) (xy 216.066866 2.893339) (xy 215.981483 2.885427)
			(xy 215.895733 2.885427) (xy 215.81035 2.893339) (xy 215.72606 2.909095) (xy 215.643584 2.932562)
			(xy 215.563625 2.963538) (xy 215.486865 3.00176) (xy 215.413959 3.046901) (xy 215.34553 3.098577)
			(xy 215.28216 3.156346) (xy 215.224391 3.219716) (xy 215.172715 3.288145) (xy 215.127574 3.361051)
			(xy 215.089352 3.437811) (xy 215.058376 3.51777) (xy 215.034909 3.600246) (xy 215.019153 3.684536)
			(xy 215.011241 3.769919) (xy 210.515975 3.769919) (xy 210.508063 3.684536) (xy 210.492307 3.600246)
			(xy 210.46884 3.51777) (xy 210.437864 3.437811) (xy 210.399642 3.361051) (xy 210.354501 3.288145)
			(xy 210.302825 3.219716) (xy 210.245056 3.156346) (xy 210.181686 3.098577) (xy 210.113257 3.046901)
			(xy 210.040351 3.00176) (xy 209.963591 2.963538) (xy 209.883632 2.932562) (xy 209.801156 2.909095)
			(xy 209.716866 2.893339) (xy 209.631483 2.885427) (xy 209.545733 2.885427) (xy 209.46035 2.893339)
			(xy 209.37606 2.909095) (xy 209.293584 2.932562) (xy 209.213625 2.963538) (xy 209.136865 3.00176)
			(xy 209.063959 3.046901) (xy 208.99553 3.098577) (xy 208.93216 3.156346) (xy 208.874391 3.219716)
			(xy 208.822715 3.288145) (xy 208.777574 3.361051) (xy 208.739352 3.437811) (xy 208.708376 3.51777)
			(xy 208.684909 3.600246) (xy 208.669153 3.684536) (xy 208.661241 3.769919) (xy 184.818528 3.769919)
			(xy 184.818528 3.092196) (xy 184.818024 3.06266) (xy 184.80998 3.004138) (xy 184.794043 2.947256)
			(xy 184.770508 2.893074) (xy 184.739815 2.842601) (xy 184.702535 2.796778) (xy 184.659363 2.756458)
			(xy 184.611103 2.722392) (xy 184.558653 2.695215) (xy 184.502992 2.675433) (xy 184.445155 2.663414)
			(xy 184.38622 2.659383) (xy 184.327285 2.663414) (xy 184.269448 2.675433) (xy 184.213787 2.695215)
			(xy 184.161337 2.722392) (xy 184.113077 2.756458) (xy 184.069905 2.796778) (xy 184.032625 2.842601)
			(xy 184.001932 2.893074) (xy 183.978397 2.947256) (xy 183.96246 3.004138) (xy 183.954416 3.06266)
			(xy 183.953912 3.092196) (xy 182.791278 3.092196) (xy 182.847365 3.064268) (xy 182.920271 3.019127)
			(xy 182.9887 2.967451) (xy 183.05207 2.909682) (xy 183.109839 2.846312) (xy 183.161515 2.777883)
			(xy 183.206656 2.704977) (xy 183.244878 2.628217) (xy 183.275854 2.548258) (xy 183.299321 2.465782)
			(xy 183.315077 2.381492) (xy 183.322989 2.296109) (xy 183.323484 2.253234) (xy 183.322989 2.210359)
			(xy 187.818255 2.210359) (xy 187.818255 2.296109) (xy 187.826167 2.381492) (xy 187.841923 2.465782)
			(xy 187.86539 2.548258) (xy 187.896366 2.628217) (xy 187.934588 2.704977) (xy 187.979729 2.777883)
			(xy 188.031405 2.846312) (xy 188.089174 2.909682) (xy 188.152544 2.967451) (xy 188.220973 3.019127)
			(xy 188.293879 3.064268) (xy 188.370639 3.10249) (xy 188.450598 3.133466) (xy 188.533074 3.156933)
			(xy 188.617364 3.172689) (xy 188.702747 3.180601) (xy 188.788497 3.180601) (xy 188.87388 3.172689)
			(xy 188.95817 3.156933) (xy 189.040646 3.133466) (xy 189.120605 3.10249) (xy 189.197365 3.064268)
			(xy 189.270271 3.019127) (xy 189.3387 2.967451) (xy 189.40207 2.909682) (xy 189.459839 2.846312)
			(xy 189.511515 2.777883) (xy 189.556656 2.704977) (xy 189.594878 2.628217) (xy 189.625854 2.548258)
			(xy 189.649321 2.465782) (xy 189.665077 2.381492) (xy 189.672989 2.296109) (xy 189.673484 2.253234)
			(xy 189.672989 2.210359) (xy 189.665077 2.124976) (xy 189.649321 2.040686) (xy 189.625854 1.95821)
			(xy 189.594878 1.878251) (xy 189.556656 1.801491) (xy 189.511515 1.728585) (xy 189.459839 1.660156)
			(xy 189.40207 1.596786) (xy 189.3387 1.539017) (xy 189.270271 1.487341) (xy 189.197365 1.4422) (xy 189.120605 1.403978)
			(xy 189.040646 1.373002) (xy 188.95817 1.349535) (xy 188.87388 1.333779) (xy 188.788497 1.325867)
			(xy 188.702747 1.325867) (xy 188.617364 1.333779) (xy 188.533074 1.349535) (xy 188.450598 1.373002)
			(xy 188.370639 1.403978) (xy 188.293879 1.4422) (xy 188.220973 1.487341) (xy 188.152544 1.539017)
			(xy 188.089174 1.596786) (xy 188.031405 1.660156) (xy 187.979729 1.728585) (xy 187.934588 1.801491)
			(xy 187.896366 1.878251) (xy 187.86539 1.95821) (xy 187.841923 2.040686) (xy 187.826167 2.124976)
			(xy 187.818255 2.210359) (xy 183.322989 2.210359) (xy 183.315077 2.124976) (xy 183.299321 2.040686)
			(xy 183.275854 1.95821) (xy 183.244878 1.878251) (xy 183.206656 1.801491) (xy 183.161515 1.728585)
			(xy 183.109839 1.660156) (xy 183.05207 1.596786) (xy 182.9887 1.539017) (xy 182.920271 1.487341)
			(xy 182.847365 1.4422) (xy 182.770605 1.403978) (xy 182.690646 1.373002) (xy 182.60817 1.349535)
			(xy 182.52388 1.333779) (xy 182.438497 1.325867) (xy 182.352747 1.325867) (xy 182.267364 1.333779)
			(xy 182.183074 1.349535) (xy 182.100598 1.373002) (xy 182.020639 1.403978) (xy 181.943879 1.4422)
			(xy 181.870973 1.487341) (xy 181.802544 1.539017) (xy 181.739174 1.596786) (xy 181.681405 1.660156)
			(xy 181.629729 1.728585) (xy 181.584588 1.801491) (xy 181.546366 1.878251) (xy 181.51539 1.95821)
			(xy 181.491923 2.040686) (xy 181.476167 2.124976) (xy 181.468255 2.210359) (xy 102.190309 2.210359)
			(xy 102.182397 2.124976) (xy 102.166641 2.040686) (xy 102.143174 1.95821) (xy 102.112198 1.878251)
			(xy 102.073976 1.801491) (xy 102.028835 1.728585) (xy 101.977159 1.660156) (xy 101.91939 1.596786)
			(xy 101.85602 1.539017) (xy 101.787591 1.487341) (xy 101.714685 1.4422) (xy 101.637925 1.403978)
			(xy 101.557966 1.373002) (xy 101.47549 1.349535) (xy 101.3912 1.333779) (xy 101.305817 1.325867)
			(xy 101.220067 1.325867) (xy 101.134684 1.333779) (xy 101.050394 1.349535) (xy 100.967918 1.373002)
			(xy 100.887959 1.403978) (xy 100.811199 1.4422) (xy 100.738293 1.487341) (xy 100.669864 1.539017)
			(xy 100.606494 1.596786) (xy 100.548725 1.660156) (xy 100.497049 1.728585) (xy 100.451908 1.801491)
			(xy 100.413686 1.878251) (xy 100.38271 1.95821) (xy 100.359243 2.040686) (xy 100.343487 2.124976)
			(xy 100.335575 2.210359) (xy 95.840309 2.210359) (xy 95.832397 2.124976) (xy 95.816641 2.040686)
			(xy 95.793174 1.95821) (xy 95.762198 1.878251) (xy 95.723976 1.801491) (xy 95.678835 1.728585) (xy 95.627159 1.660156)
			(xy 95.56939 1.596786) (xy 95.50602 1.539017) (xy 95.437591 1.487341) (xy 95.364685 1.4422) (xy 95.287925 1.403978)
			(xy 95.207966 1.373002) (xy 95.12549 1.349535) (xy 95.0412 1.333779) (xy 94.955817 1.325867) (xy 94.870067 1.325867)
			(xy 94.784684 1.333779) (xy 94.700394 1.349535) (xy 94.617918 1.373002) (xy 94.537959 1.403978) (xy 94.461199 1.4422)
			(xy 94.388293 1.487341) (xy 94.319864 1.539017) (xy 94.256494 1.596786) (xy 94.198725 1.660156) (xy 94.147049 1.728585)
			(xy 94.101908 1.801491) (xy 94.063686 1.878251) (xy 94.03271 1.95821) (xy 94.009243 2.040686) (xy 93.993487 2.124976)
			(xy 93.985575 2.210359) (xy 83.439191 2.210359) (xy 83.525475 2.124078) (xy 83.619275 2.019118) (xy 83.707042 1.909064)
			(xy 83.788501 1.794262) (xy 83.863394 1.675073) (xy 83.931487 1.551873) (xy 83.992565 1.425048) (xy 84.046435 1.294999)
			(xy 84.069209 1.229919) (xy 208.661241 1.229919) (xy 208.661241 1.315669) (xy 208.669153 1.401052)
			(xy 208.684909 1.485342) (xy 208.708376 1.567818) (xy 208.739352 1.647777) (xy 208.777574 1.724537)
			(xy 208.822715 1.797443) (xy 208.874391 1.865872) (xy 208.93216 1.929242) (xy 208.99553 1.987011)
			(xy 209.063959 2.038687) (xy 209.136865 2.083828) (xy 209.213625 2.12205) (xy 209.293584 2.153026)
			(xy 209.37606 2.176493) (xy 209.46035 2.192249) (xy 209.545733 2.200161) (xy 209.631483 2.200161)
			(xy 209.716866 2.192249) (xy 209.801156 2.176493) (xy 209.883632 2.153026) (xy 209.963591 2.12205)
			(xy 209.984264 2.111756) (xy 213.517988 2.111756) (xy 213.517988 2.975356) (xy 213.518492 3.00491)
			(xy 213.526541 3.063466) (xy 213.542487 3.120381) (xy 213.566036 3.174595) (xy 213.596747 3.225098)
			(xy 213.634049 3.270948) (xy 213.677246 3.311291) (xy 213.725535 3.345377) (xy 213.778015 3.37257)
			(xy 213.83371 3.392364) (xy 213.891581 3.40439) (xy 213.95055 3.408424) (xy 214.009519 3.40439) (xy 214.06739 3.392364)
			(xy 214.123085 3.37257) (xy 214.175565 3.345377) (xy 214.223854 3.311291) (xy 214.267051 3.270948)
			(xy 214.304353 3.225098) (xy 214.335064 3.174595) (xy 214.358613 3.120381) (xy 214.374559 3.063466)
			(xy 214.382608 3.00491) (xy 214.383112 2.975356) (xy 214.383112 2.111756) (xy 214.382608 2.082202)
			(xy 214.374559 2.023646) (xy 214.358613 1.966731) (xy 214.335064 1.912517) (xy 214.304353 1.862014)
			(xy 214.267051 1.816164) (xy 214.223854 1.775821) (xy 214.175565 1.741735) (xy 214.123085 1.714542)
			(xy 214.06739 1.694748) (xy 214.009519 1.682722) (xy 213.95055 1.678689) (xy 213.891581 1.682722)
			(xy 213.83371 1.694748) (xy 213.778015 1.714542) (xy 213.725535 1.741735) (xy 213.677246 1.775821)
			(xy 213.634049 1.816164) (xy 213.596747 1.862014) (xy 213.566036 1.912517) (xy 213.542487 1.966731)
			(xy 213.526541 2.023646) (xy 213.518492 2.082202) (xy 213.517988 2.111756) (xy 209.984264 2.111756)
			(xy 210.040351 2.083828) (xy 210.113257 2.038687) (xy 210.181686 1.987011) (xy 210.245056 1.929242)
			(xy 210.302825 1.865872) (xy 210.354501 1.797443) (xy 210.399642 1.724537) (xy 210.437864 1.647777)
			(xy 210.46884 1.567818) (xy 210.492307 1.485342) (xy 210.508063 1.401052) (xy 210.515975 1.315669)
			(xy 210.51647 1.272794) (xy 210.515975 1.229919) (xy 215.011241 1.229919) (xy 215.011241 1.315669)
			(xy 215.019153 1.401052) (xy 215.034909 1.485342) (xy 215.058376 1.567818) (xy 215.089352 1.647777)
			(xy 215.127574 1.724537) (xy 215.172715 1.797443) (xy 215.224391 1.865872) (xy 215.28216 1.929242)
			(xy 215.34553 1.987011) (xy 215.413959 2.038687) (xy 215.486865 2.083828) (xy 215.563625 2.12205)
			(xy 215.643584 2.153026) (xy 215.72606 2.176493) (xy 215.81035 2.192249) (xy 215.895733 2.200161)
			(xy 215.981483 2.200161) (xy 216.066866 2.192249) (xy 216.151156 2.176493) (xy 216.233632 2.153026)
			(xy 216.313591 2.12205) (xy 216.390351 2.083828) (xy 216.463257 2.038687) (xy 216.531686 1.987011)
			(xy 216.595056 1.929242) (xy 216.652825 1.865872) (xy 216.704501 1.797443) (xy 216.749642 1.724537)
			(xy 216.787864 1.647777) (xy 216.81884 1.567818) (xy 216.842307 1.485342) (xy 216.858063 1.401052)
			(xy 216.865975 1.315669) (xy 216.86647 1.272794) (xy 216.865975 1.229919) (xy 296.143921 1.229919)
			(xy 296.143921 1.315669) (xy 296.151833 1.401052) (xy 296.167589 1.485342) (xy 296.191056 1.567818)
			(xy 296.222032 1.647777) (xy 296.260254 1.724537) (xy 296.305395 1.797443) (xy 296.357071 1.865872)
			(xy 296.41484 1.929242) (xy 296.47821 1.987011) (xy 296.546639 2.038687) (xy 296.619545 2.083828)
			(xy 296.696305 2.12205) (xy 296.776264 2.153026) (xy 296.85874 2.176493) (xy 296.94303 2.192249)
			(xy 297.028413 2.200161) (xy 297.114163 2.200161) (xy 297.199546 2.192249) (xy 297.283836 2.176493)
			(xy 297.366312 2.153026) (xy 297.446271 2.12205) (xy 297.466944 2.111756) (xy 298.629324 2.111756)
			(xy 298.629324 2.975356) (xy 298.629828 3.00491) (xy 298.637877 3.063466) (xy 298.653823 3.120381)
			(xy 298.677372 3.174595) (xy 298.708083 3.225098) (xy 298.745385 3.270948) (xy 298.788582 3.311291)
			(xy 298.836871 3.345377) (xy 298.889351 3.37257) (xy 298.945046 3.392364) (xy 299.002917 3.40439)
			(xy 299.061886 3.408424) (xy 299.120855 3.40439) (xy 299.178726 3.392364) (xy 299.234421 3.37257)
			(xy 299.286901 3.345377) (xy 299.33519 3.311291) (xy 299.378387 3.270948) (xy 299.415689 3.225098)
			(xy 299.4464 3.174595) (xy 299.469949 3.120381) (xy 299.485895 3.063466) (xy 299.493944 3.00491)
			(xy 299.494448 2.975356) (xy 299.494448 2.111756) (xy 299.493944 2.082202) (xy 299.485895 2.023646)
			(xy 299.469949 1.966731) (xy 299.4464 1.912517) (xy 299.415689 1.862014) (xy 299.378387 1.816164)
			(xy 299.33519 1.775821) (xy 299.286901 1.741735) (xy 299.234421 1.714542) (xy 299.178726 1.694748)
			(xy 299.120855 1.682722) (xy 299.061886 1.678689) (xy 299.002917 1.682722) (xy 298.945046 1.694748)
			(xy 298.889351 1.714542) (xy 298.836871 1.741735) (xy 298.788582 1.775821) (xy 298.745385 1.816164)
			(xy 298.708083 1.862014) (xy 298.677372 1.912517) (xy 298.653823 1.966731) (xy 298.637877 2.023646)
			(xy 298.629828 2.082202) (xy 298.629324 2.111756) (xy 297.466944 2.111756) (xy 297.523031 2.083828)
			(xy 297.595937 2.038687) (xy 297.664366 1.987011) (xy 297.727736 1.929242) (xy 297.785505 1.865872)
			(xy 297.837181 1.797443) (xy 297.882322 1.724537) (xy 297.920544 1.647777) (xy 297.95152 1.567818)
			(xy 297.974987 1.485342) (xy 297.990743 1.401052) (xy 297.998655 1.315669) (xy 297.99915 1.272794)
			(xy 297.998655 1.229919) (xy 302.493921 1.229919) (xy 302.493921 1.315669) (xy 302.501833 1.401052)
			(xy 302.517589 1.485342) (xy 302.541056 1.567818) (xy 302.572032 1.647777) (xy 302.610254 1.724537)
			(xy 302.655395 1.797443) (xy 302.707071 1.865872) (xy 302.76484 1.929242) (xy 302.82821 1.987011)
			(xy 302.896639 2.038687) (xy 302.969545 2.083828) (xy 303.046305 2.12205) (xy 303.126264 2.153026)
			(xy 303.20874 2.176493) (xy 303.29303 2.192249) (xy 303.378413 2.200161) (xy 303.464163 2.200161)
			(xy 303.549546 2.192249) (xy 303.633836 2.176493) (xy 303.716312 2.153026) (xy 303.796271 2.12205)
			(xy 303.873031 2.083828) (xy 303.945937 2.038687) (xy 304.014366 1.987011) (xy 304.077736 1.929242)
			(xy 304.135505 1.865872) (xy 304.187181 1.797443) (xy 304.232322 1.724537) (xy 304.270544 1.647777)
			(xy 304.30152 1.567818) (xy 304.324987 1.485342) (xy 304.340743 1.401052) (xy 304.348655 1.315669)
			(xy 304.34915 1.272794) (xy 304.348655 1.229919) (xy 311.155321 1.229919) (xy 311.155321 1.315669)
			(xy 311.163233 1.401052) (xy 311.178989 1.485342) (xy 311.202456 1.567818) (xy 311.233432 1.647777)
			(xy 311.271654 1.724537) (xy 311.316795 1.797443) (xy 311.368471 1.865872) (xy 311.42624 1.929242)
			(xy 311.48961 1.987011) (xy 311.558039 2.038687) (xy 311.630945 2.083828) (xy 311.707705 2.12205)
			(xy 311.787664 2.153026) (xy 311.87014 2.176493) (xy 311.95443 2.192249) (xy 312.039813 2.200161)
			(xy 312.125563 2.200161) (xy 312.210946 2.192249) (xy 312.295236 2.176493) (xy 312.377712 2.153026)
			(xy 312.457671 2.12205) (xy 312.534431 2.083828) (xy 312.607337 2.038687) (xy 312.675766 1.987011)
			(xy 312.739136 1.929242) (xy 312.796905 1.865872) (xy 312.848581 1.797443) (xy 312.893722 1.724537)
			(xy 312.931944 1.647777) (xy 312.96292 1.567818) (xy 312.986387 1.485342) (xy 313.002143 1.401052)
			(xy 313.010055 1.315669) (xy 313.01055 1.272794) (xy 313.010055 1.229919) (xy 317.505321 1.229919)
			(xy 317.505321 1.315669) (xy 317.513233 1.401052) (xy 317.528989 1.485342) (xy 317.552456 1.567818)
			(xy 317.583432 1.647777) (xy 317.621654 1.724537) (xy 317.666795 1.797443) (xy 317.718471 1.865872)
			(xy 317.77624 1.929242) (xy 317.83961 1.987011) (xy 317.908039 2.038687) (xy 317.980945 2.083828)
			(xy 318.057705 2.12205) (xy 318.137664 2.153026) (xy 318.22014 2.176493) (xy 318.30443 2.192249)
			(xy 318.389813 2.200161) (xy 318.475563 2.200161) (xy 318.560946 2.192249) (xy 318.645236 2.176493)
			(xy 318.727712 2.153026) (xy 318.807671 2.12205) (xy 318.884431 2.083828) (xy 318.957337 2.038687)
			(xy 319.025766 1.987011) (xy 319.089136 1.929242) (xy 319.146905 1.865872) (xy 319.198581 1.797443)
			(xy 319.243722 1.724537) (xy 319.281944 1.647777) (xy 319.31292 1.567818) (xy 319.336387 1.485342)
			(xy 319.352143 1.401052) (xy 319.360055 1.315669) (xy 319.36055 1.272794) (xy 319.360055 1.229919)
			(xy 361.894107 1.229919) (xy 361.894107 1.315669) (xy 361.902019 1.401052) (xy 361.917775 1.485342)
			(xy 361.941242 1.567818) (xy 361.972218 1.647777) (xy 362.01044 1.724537) (xy 362.055581 1.797443)
			(xy 362.107257 1.865872) (xy 362.165026 1.929242) (xy 362.228396 1.987011) (xy 362.296825 2.038687)
			(xy 362.369731 2.083828) (xy 362.446491 2.12205) (xy 362.52645 2.153026) (xy 362.608926 2.176493)
			(xy 362.693216 2.192249) (xy 362.778599 2.200161) (xy 362.864349 2.200161) (xy 362.949732 2.192249)
			(xy 363.034022 2.176493) (xy 363.116498 2.153026) (xy 363.196457 2.12205) (xy 363.273217 2.083828)
			(xy 363.346123 2.038687) (xy 363.414552 1.987011) (xy 363.477922 1.929242) (xy 363.535691 1.865872)
			(xy 363.587367 1.797443) (xy 363.632508 1.724537) (xy 363.67073 1.647777) (xy 363.701706 1.567818)
			(xy 363.725173 1.485342) (xy 363.740929 1.401052) (xy 363.748841 1.315669) (xy 363.749336 1.272794)
			(xy 363.748841 1.229919) (xy 368.244107 1.229919) (xy 368.244107 1.315669) (xy 368.252019 1.401052)
			(xy 368.267775 1.485342) (xy 368.291242 1.567818) (xy 368.322218 1.647777) (xy 368.36044 1.724537)
			(xy 368.405581 1.797443) (xy 368.457257 1.865872) (xy 368.515026 1.929242) (xy 368.578396 1.987011)
			(xy 368.646825 2.038687) (xy 368.719731 2.083828) (xy 368.796491 2.12205) (xy 368.87645 2.153026)
			(xy 368.958926 2.176493) (xy 369.043216 2.192249) (xy 369.128599 2.200161) (xy 369.214349 2.200161)
			(xy 369.299732 2.192249) (xy 369.384022 2.176493) (xy 369.466498 2.153026) (xy 369.546457 2.12205)
			(xy 369.623217 2.083828) (xy 369.696123 2.038687) (xy 369.764552 1.987011) (xy 369.827922 1.929242)
			(xy 369.885691 1.865872) (xy 369.937367 1.797443) (xy 369.982508 1.724537) (xy 370.02073 1.647777)
			(xy 370.051706 1.567818) (xy 370.075173 1.485342) (xy 370.090929 1.401052) (xy 370.098841 1.315669)
			(xy 370.099336 1.272794) (xy 370.098841 1.229919) (xy 370.090929 1.144536) (xy 370.075173 1.060246)
			(xy 370.051706 0.97777) (xy 370.02073 0.897811) (xy 369.982508 0.821051) (xy 369.937367 0.748145)
			(xy 369.885691 0.679716) (xy 369.827922 0.616346) (xy 369.764552 0.558577) (xy 369.696123 0.506901)
			(xy 369.623217 0.46176) (xy 369.546457 0.423538) (xy 369.466498 0.392562) (xy 369.384022 0.369095)
			(xy 369.299732 0.353339) (xy 369.214349 0.345427) (xy 369.128599 0.345427) (xy 369.043216 0.353339)
			(xy 368.958926 0.369095) (xy 368.87645 0.392562) (xy 368.796491 0.423538) (xy 368.719731 0.46176)
			(xy 368.646825 0.506901) (xy 368.578396 0.558577) (xy 368.515026 0.616346) (xy 368.457257 0.679716)
			(xy 368.405581 0.748145) (xy 368.36044 0.821051) (xy 368.322218 0.897811) (xy 368.291242 0.97777)
			(xy 368.267775 1.060246) (xy 368.252019 1.144536) (xy 368.244107 1.229919) (xy 363.748841 1.229919)
			(xy 363.740929 1.144536) (xy 363.725173 1.060246) (xy 363.701706 0.97777) (xy 363.67073 0.897811)
			(xy 363.632508 0.821051) (xy 363.587367 0.748145) (xy 363.535691 0.679716) (xy 363.477922 0.616346)
			(xy 363.414552 0.558577) (xy 363.346123 0.506901) (xy 363.273217 0.46176) (xy 363.196457 0.423538)
			(xy 363.116498 0.392562) (xy 363.034022 0.369095) (xy 362.949732 0.353339) (xy 362.864349 0.345427)
			(xy 362.778599 0.345427) (xy 362.693216 0.353339) (xy 362.608926 0.369095) (xy 362.52645 0.392562)
			(xy 362.446491 0.423538) (xy 362.369731 0.46176) (xy 362.296825 0.506901) (xy 362.228396 0.558577)
			(xy 362.165026 0.616346) (xy 362.107257 0.679716) (xy 362.055581 0.748145) (xy 362.01044 0.821051)
			(xy 361.972218 0.897811) (xy 361.941242 0.97777) (xy 361.917775 1.060246) (xy 361.902019 1.144536)
			(xy 361.894107 1.229919) (xy 319.360055 1.229919) (xy 319.352143 1.144536) (xy 319.336387 1.060246)
			(xy 319.31292 0.97777) (xy 319.281944 0.897811) (xy 319.243722 0.821051) (xy 319.198581 0.748145)
			(xy 319.146905 0.679716) (xy 319.089136 0.616346) (xy 319.025766 0.558577) (xy 318.957337 0.506901)
			(xy 318.884431 0.46176) (xy 318.807671 0.423538) (xy 318.727712 0.392562) (xy 318.645236 0.369095)
			(xy 318.560946 0.353339) (xy 318.475563 0.345427) (xy 318.389813 0.345427) (xy 318.30443 0.353339)
			(xy 318.22014 0.369095) (xy 318.137664 0.392562) (xy 318.057705 0.423538) (xy 317.980945 0.46176)
			(xy 317.908039 0.506901) (xy 317.83961 0.558577) (xy 317.77624 0.616346) (xy 317.718471 0.679716)
			(xy 317.666795 0.748145) (xy 317.621654 0.821051) (xy 317.583432 0.897811) (xy 317.552456 0.97777)
			(xy 317.528989 1.060246) (xy 317.513233 1.144536) (xy 317.505321 1.229919) (xy 313.010055 1.229919)
			(xy 313.002143 1.144536) (xy 312.986387 1.060246) (xy 312.96292 0.97777) (xy 312.931944 0.897811)
			(xy 312.893722 0.821051) (xy 312.848581 0.748145) (xy 312.796905 0.679716) (xy 312.739136 0.616346)
			(xy 312.675766 0.558577) (xy 312.607337 0.506901) (xy 312.534431 0.46176) (xy 312.457671 0.423538)
			(xy 312.377712 0.392562) (xy 312.295236 0.369095) (xy 312.210946 0.353339) (xy 312.125563 0.345427)
			(xy 312.039813 0.345427) (xy 311.95443 0.353339) (xy 311.87014 0.369095) (xy 311.787664 0.392562)
			(xy 311.707705 0.423538) (xy 311.630945 0.46176) (xy 311.558039 0.506901) (xy 311.48961 0.558577)
			(xy 311.42624 0.616346) (xy 311.368471 0.679716) (xy 311.316795 0.748145) (xy 311.271654 0.821051)
			(xy 311.233432 0.897811) (xy 311.202456 0.97777) (xy 311.178989 1.060246) (xy 311.163233 1.144536)
			(xy 311.155321 1.229919) (xy 304.348655 1.229919) (xy 304.340743 1.144536) (xy 304.324987 1.060246)
			(xy 304.30152 0.97777) (xy 304.270544 0.897811) (xy 304.232322 0.821051) (xy 304.187181 0.748145)
			(xy 304.135505 0.679716) (xy 304.077736 0.616346) (xy 304.014366 0.558577) (xy 303.945937 0.506901)
			(xy 303.873031 0.46176) (xy 303.796271 0.423538) (xy 303.716312 0.392562) (xy 303.633836 0.369095)
			(xy 303.549546 0.353339) (xy 303.464163 0.345427) (xy 303.378413 0.345427) (xy 303.29303 0.353339)
			(xy 303.20874 0.369095) (xy 303.126264 0.392562) (xy 303.046305 0.423538) (xy 302.969545 0.46176)
			(xy 302.896639 0.506901) (xy 302.82821 0.558577) (xy 302.76484 0.616346) (xy 302.707071 0.679716)
			(xy 302.655395 0.748145) (xy 302.610254 0.821051) (xy 302.572032 0.897811) (xy 302.541056 0.97777)
			(xy 302.517589 1.060246) (xy 302.501833 1.144536) (xy 302.493921 1.229919) (xy 297.998655 1.229919)
			(xy 297.990743 1.144536) (xy 297.974987 1.060246) (xy 297.95152 0.97777) (xy 297.920544 0.897811)
			(xy 297.882322 0.821051) (xy 297.837181 0.748145) (xy 297.785505 0.679716) (xy 297.727736 0.616346)
			(xy 297.664366 0.558577) (xy 297.595937 0.506901) (xy 297.523031 0.46176) (xy 297.446271 0.423538)
			(xy 297.366312 0.392562) (xy 297.283836 0.369095) (xy 297.199546 0.353339) (xy 297.114163 0.345427)
			(xy 297.028413 0.345427) (xy 296.94303 0.353339) (xy 296.85874 0.369095) (xy 296.776264 0.392562)
			(xy 296.696305 0.423538) (xy 296.619545 0.46176) (xy 296.546639 0.506901) (xy 296.47821 0.558577)
			(xy 296.41484 0.616346) (xy 296.357071 0.679716) (xy 296.305395 0.748145) (xy 296.260254 0.821051)
			(xy 296.222032 0.897811) (xy 296.191056 0.97777) (xy 296.167589 1.060246) (xy 296.151833 1.144536)
			(xy 296.143921 1.229919) (xy 216.865975 1.229919) (xy 216.858063 1.144536) (xy 216.842307 1.060246)
			(xy 216.81884 0.97777) (xy 216.787864 0.897811) (xy 216.749642 0.821051) (xy 216.704501 0.748145)
			(xy 216.652825 0.679716) (xy 216.595056 0.616346) (xy 216.531686 0.558577) (xy 216.463257 0.506901)
			(xy 216.390351 0.46176) (xy 216.313591 0.423538) (xy 216.233632 0.392562) (xy 216.151156 0.369095)
			(xy 216.066866 0.353339) (xy 215.981483 0.345427) (xy 215.895733 0.345427) (xy 215.81035 0.353339)
			(xy 215.72606 0.369095) (xy 215.643584 0.392562) (xy 215.563625 0.423538) (xy 215.486865 0.46176)
			(xy 215.413959 0.506901) (xy 215.34553 0.558577) (xy 215.28216 0.616346) (xy 215.224391 0.679716)
			(xy 215.172715 0.748145) (xy 215.127574 0.821051) (xy 215.089352 0.897811) (xy 215.058376 0.97777)
			(xy 215.034909 1.060246) (xy 215.019153 1.144536) (xy 215.011241 1.229919) (xy 210.515975 1.229919)
			(xy 210.508063 1.144536) (xy 210.492307 1.060246) (xy 210.46884 0.97777) (xy 210.437864 0.897811)
			(xy 210.399642 0.821051) (xy 210.354501 0.748145) (xy 210.302825 0.679716) (xy 210.245056 0.616346)
			(xy 210.181686 0.558577) (xy 210.113257 0.506901) (xy 210.040351 0.46176) (xy 209.963591 0.423538)
			(xy 209.883632 0.392562) (xy 209.801156 0.369095) (xy 209.716866 0.353339) (xy 209.631483 0.345427)
			(xy 209.545733 0.345427) (xy 209.46035 0.353339) (xy 209.37606 0.369095) (xy 209.293584 0.392562)
			(xy 209.213625 0.423538) (xy 209.136865 0.46176) (xy 209.063959 0.506901) (xy 208.99553 0.558577)
			(xy 208.93216 0.616346) (xy 208.874391 0.679716) (xy 208.822715 0.748145) (xy 208.777574 0.821051)
			(xy 208.739352 0.897811) (xy 208.708376 0.97777) (xy 208.684909 1.060246) (xy 208.669153 1.144536)
			(xy 208.661241 1.229919) (xy 84.069209 1.229919) (xy 84.092929 1.162133) (xy 84.131901 1.02687) (xy 84.163226 0.889634)
			(xy 84.186808 0.750857) (xy 84.202571 0.610977) (xy 84.210467 0.470433) (xy 84.210906 0.40005) (xy 84.210906 -1.310081)
			(xy 208.661241 -1.310081) (xy 208.661241 -1.224331) (xy 208.669153 -1.138948) (xy 208.684909 -1.054658)
			(xy 208.708376 -0.972182) (xy 208.739352 -0.892223) (xy 208.777574 -0.815463) (xy 208.822715 -0.742557)
			(xy 208.874391 -0.674128) (xy 208.93216 -0.610758) (xy 208.99553 -0.552989) (xy 209.063959 -0.501313)
			(xy 209.136865 -0.456172) (xy 209.213625 -0.41795) (xy 209.293584 -0.386974) (xy 209.37606 -0.363507)
			(xy 209.46035 -0.347751) (xy 209.545733 -0.339839) (xy 209.631483 -0.339839) (xy 209.716866 -0.347751)
			(xy 209.801156 -0.363507) (xy 209.883632 -0.386974) (xy 209.963591 -0.41795) (xy 210.040351 -0.456172)
			(xy 210.113257 -0.501313) (xy 210.181686 -0.552989) (xy 210.245056 -0.610758) (xy 210.302825 -0.674128)
			(xy 210.354501 -0.742557) (xy 210.399642 -0.815463) (xy 210.437864 -0.892223) (xy 210.46884 -0.972182)
			(xy 210.492307 -1.054658) (xy 210.508063 -1.138948) (xy 210.515975 -1.224331) (xy 210.51647 -1.267206)
			(xy 210.515975 -1.310081) (xy 215.011241 -1.310081) (xy 215.011241 -1.224331) (xy 215.019153 -1.138948)
			(xy 215.034909 -1.054658) (xy 215.058376 -0.972182) (xy 215.089352 -0.892223) (xy 215.127574 -0.815463)
			(xy 215.172715 -0.742557) (xy 215.224391 -0.674128) (xy 215.28216 -0.610758) (xy 215.34553 -0.552989)
			(xy 215.413959 -0.501313) (xy 215.486865 -0.456172) (xy 215.563625 -0.41795) (xy 215.643584 -0.386974)
			(xy 215.72606 -0.363507) (xy 215.81035 -0.347751) (xy 215.895733 -0.339839) (xy 215.981483 -0.339839)
			(xy 216.066866 -0.347751) (xy 216.151156 -0.363507) (xy 216.233632 -0.386974) (xy 216.313591 -0.41795)
			(xy 216.390351 -0.456172) (xy 216.463257 -0.501313) (xy 216.531686 -0.552989) (xy 216.595056 -0.610758)
			(xy 216.652825 -0.674128) (xy 216.704501 -0.742557) (xy 216.749642 -0.815463) (xy 216.787864 -0.892223)
			(xy 216.81884 -0.972182) (xy 216.842307 -1.054658) (xy 216.858063 -1.138948) (xy 216.865975 -1.224331)
			(xy 216.86647 -1.267206) (xy 216.865975 -1.310081) (xy 296.143921 -1.310081) (xy 296.143921 -1.224331)
			(xy 296.151833 -1.138948) (xy 296.167589 -1.054658) (xy 296.191056 -0.972182) (xy 296.222032 -0.892223)
			(xy 296.260254 -0.815463) (xy 296.305395 -0.742557) (xy 296.357071 -0.674128) (xy 296.41484 -0.610758)
			(xy 296.47821 -0.552989) (xy 296.546639 -0.501313) (xy 296.619545 -0.456172) (xy 296.696305 -0.41795)
			(xy 296.776264 -0.386974) (xy 296.85874 -0.363507) (xy 296.94303 -0.347751) (xy 297.028413 -0.339839)
			(xy 297.114163 -0.339839) (xy 297.199546 -0.347751) (xy 297.283836 -0.363507) (xy 297.366312 -0.386974)
			(xy 297.446271 -0.41795) (xy 297.523031 -0.456172) (xy 297.595937 -0.501313) (xy 297.664366 -0.552989)
			(xy 297.727736 -0.610758) (xy 297.785505 -0.674128) (xy 297.837181 -0.742557) (xy 297.882322 -0.815463)
			(xy 297.920544 -0.892223) (xy 297.95152 -0.972182) (xy 297.974987 -1.054658) (xy 297.990743 -1.138948)
			(xy 297.998655 -1.224331) (xy 297.99915 -1.267206) (xy 297.998655 -1.310081) (xy 302.493921 -1.310081)
			(xy 302.493921 -1.224331) (xy 302.501833 -1.138948) (xy 302.517589 -1.054658) (xy 302.541056 -0.972182)
			(xy 302.572032 -0.892223) (xy 302.610254 -0.815463) (xy 302.655395 -0.742557) (xy 302.707071 -0.674128)
			(xy 302.76484 -0.610758) (xy 302.82821 -0.552989) (xy 302.896639 -0.501313) (xy 302.969545 -0.456172)
			(xy 303.046305 -0.41795) (xy 303.126264 -0.386974) (xy 303.20874 -0.363507) (xy 303.29303 -0.347751)
			(xy 303.378413 -0.339839) (xy 303.464163 -0.339839) (xy 303.549546 -0.347751) (xy 303.633836 -0.363507)
			(xy 303.716312 -0.386974) (xy 303.796271 -0.41795) (xy 303.873031 -0.456172) (xy 303.945937 -0.501313)
			(xy 304.014366 -0.552989) (xy 304.077736 -0.610758) (xy 304.135505 -0.674128) (xy 304.187181 -0.742557)
			(xy 304.232322 -0.815463) (xy 304.270544 -0.892223) (xy 304.30152 -0.972182) (xy 304.324987 -1.054658)
			(xy 304.340743 -1.138948) (xy 304.348655 -1.224331) (xy 304.34915 -1.267206) (xy 304.348655 -1.310081)
			(xy 311.155321 -1.310081) (xy 311.155321 -1.224331) (xy 311.163233 -1.138948) (xy 311.178989 -1.054658)
			(xy 311.202456 -0.972182) (xy 311.233432 -0.892223) (xy 311.271654 -0.815463) (xy 311.316795 -0.742557)
			(xy 311.368471 -0.674128) (xy 311.42624 -0.610758) (xy 311.48961 -0.552989) (xy 311.558039 -0.501313)
			(xy 311.630945 -0.456172) (xy 311.707705 -0.41795) (xy 311.787664 -0.386974) (xy 311.87014 -0.363507)
			(xy 311.95443 -0.347751) (xy 312.039813 -0.339839) (xy 312.125563 -0.339839) (xy 312.210946 -0.347751)
			(xy 312.295236 -0.363507) (xy 312.377712 -0.386974) (xy 312.457671 -0.41795) (xy 312.478344 -0.428244)
			(xy 316.012068 -0.428244) (xy 316.012068 0.435356) (xy 316.012572 0.46491) (xy 316.020621 0.523466)
			(xy 316.036567 0.580381) (xy 316.060116 0.634595) (xy 316.090827 0.685098) (xy 316.128129 0.730948)
			(xy 316.171326 0.771291) (xy 316.219615 0.805377) (xy 316.272095 0.83257) (xy 316.32779 0.852364)
			(xy 316.385661 0.86439) (xy 316.44463 0.868424) (xy 316.503599 0.86439) (xy 316.56147 0.852364) (xy 316.617165 0.83257)
			(xy 316.669645 0.805377) (xy 316.717934 0.771291) (xy 316.761131 0.730948) (xy 316.798433 0.685098)
			(xy 316.829144 0.634595) (xy 316.852693 0.580381) (xy 316.868639 0.523466) (xy 316.876688 0.46491)
			(xy 316.877192 0.435356) (xy 316.877192 -0.428244) (xy 316.876688 -0.457798) (xy 316.868639 -0.516354)
			(xy 316.852693 -0.573269) (xy 316.829144 -0.627483) (xy 316.798433 -0.677986) (xy 316.761131 -0.723836)
			(xy 316.717934 -0.764179) (xy 316.669645 -0.798265) (xy 316.617165 -0.825458) (xy 316.56147 -0.845252)
			(xy 316.503599 -0.857278) (xy 316.44463 -0.861312) (xy 316.385661 -0.857278) (xy 316.32779 -0.845252)
			(xy 316.272095 -0.825458) (xy 316.219615 -0.798265) (xy 316.171326 -0.764179) (xy 316.128129 -0.723836)
			(xy 316.090827 -0.677986) (xy 316.060116 -0.627483) (xy 316.036567 -0.573269) (xy 316.020621 -0.516354)
			(xy 316.012572 -0.457798) (xy 316.012068 -0.428244) (xy 312.478344 -0.428244) (xy 312.534431 -0.456172)
			(xy 312.607337 -0.501313) (xy 312.675766 -0.552989) (xy 312.739136 -0.610758) (xy 312.796905 -0.674128)
			(xy 312.848581 -0.742557) (xy 312.893722 -0.815463) (xy 312.931944 -0.892223) (xy 312.96292 -0.972182)
			(xy 312.986387 -1.054658) (xy 313.002143 -1.138948) (xy 313.010055 -1.224331) (xy 313.01055 -1.267206)
			(xy 313.010055 -1.310081) (xy 317.505321 -1.310081) (xy 317.505321 -1.224331) (xy 317.513233 -1.138948)
			(xy 317.528989 -1.054658) (xy 317.552456 -0.972182) (xy 317.583432 -0.892223) (xy 317.621654 -0.815463)
			(xy 317.666795 -0.742557) (xy 317.718471 -0.674128) (xy 317.77624 -0.610758) (xy 317.83961 -0.552989)
			(xy 317.908039 -0.501313) (xy 317.980945 -0.456172) (xy 318.057705 -0.41795) (xy 318.137664 -0.386974)
			(xy 318.22014 -0.363507) (xy 318.30443 -0.347751) (xy 318.389813 -0.339839) (xy 318.475563 -0.339839)
			(xy 318.560946 -0.347751) (xy 318.645236 -0.363507) (xy 318.727712 -0.386974) (xy 318.807671 -0.41795)
			(xy 318.884431 -0.456172) (xy 318.957337 -0.501313) (xy 319.025766 -0.552989) (xy 319.089136 -0.610758)
			(xy 319.146905 -0.674128) (xy 319.198581 -0.742557) (xy 319.243722 -0.815463) (xy 319.281944 -0.892223)
			(xy 319.31292 -0.972182) (xy 319.336387 -1.054658) (xy 319.352143 -1.138948) (xy 319.360055 -1.224331)
			(xy 319.36055 -1.267206) (xy 319.360055 -1.310081) (xy 361.894107 -1.310081) (xy 361.894107 -1.224331)
			(xy 361.902019 -1.138948) (xy 361.917775 -1.054658) (xy 361.941242 -0.972182) (xy 361.972218 -0.892223)
			(xy 362.01044 -0.815463) (xy 362.055581 -0.742557) (xy 362.107257 -0.674128) (xy 362.165026 -0.610758)
			(xy 362.228396 -0.552989) (xy 362.296825 -0.501313) (xy 362.369731 -0.456172) (xy 362.446491 -0.41795)
			(xy 362.52645 -0.386974) (xy 362.608926 -0.363507) (xy 362.693216 -0.347751) (xy 362.778599 -0.339839)
			(xy 362.864349 -0.339839) (xy 362.949732 -0.347751) (xy 363.034022 -0.363507) (xy 363.116498 -0.386974)
			(xy 363.196457 -0.41795) (xy 363.21713 -0.428244) (xy 364.379764 -0.428244) (xy 364.379764 0.435356)
			(xy 364.380268 0.464892) (xy 364.388312 0.523414) (xy 364.404249 0.580296) (xy 364.427784 0.634478)
			(xy 364.458477 0.684951) (xy 364.495757 0.730774) (xy 364.538929 0.771094) (xy 364.587189 0.80516)
			(xy 364.639639 0.832337) (xy 364.6953 0.852119) (xy 364.753137 0.864138) (xy 364.812072 0.868169)
			(xy 364.871007 0.864138) (xy 364.928844 0.852119) (xy 364.984505 0.832337) (xy 365.036955 0.80516)
			(xy 365.085215 0.771094) (xy 365.128387 0.730774) (xy 365.165667 0.684951) (xy 365.19636 0.634478)
			(xy 365.219895 0.580296) (xy 365.235832 0.523414) (xy 365.243876 0.464892) (xy 365.24438 0.435356)
			(xy 365.24438 -0.428244) (xy 365.243876 -0.45778) (xy 365.235832 -0.516302) (xy 365.219895 -0.573184)
			(xy 365.19636 -0.627366) (xy 365.165667 -0.677839) (xy 365.128387 -0.723662) (xy 365.085215 -0.763982)
			(xy 365.036955 -0.798048) (xy 364.984505 -0.825225) (xy 364.928844 -0.845007) (xy 364.871007 -0.857026)
			(xy 364.812072 -0.861057) (xy 364.753137 -0.857026) (xy 364.6953 -0.845007) (xy 364.639639 -0.825225)
			(xy 364.587189 -0.798048) (xy 364.538929 -0.763982) (xy 364.495757 -0.723662) (xy 364.458477 -0.677839)
			(xy 364.427784 -0.627366) (xy 364.404249 -0.573184) (xy 364.388312 -0.516302) (xy 364.380268 -0.45778)
			(xy 364.379764 -0.428244) (xy 363.21713 -0.428244) (xy 363.273217 -0.456172) (xy 363.346123 -0.501313)
			(xy 363.414552 -0.552989) (xy 363.477922 -0.610758) (xy 363.535691 -0.674128) (xy 363.587367 -0.742557)
			(xy 363.632508 -0.815463) (xy 363.67073 -0.892223) (xy 363.701706 -0.972182) (xy 363.725173 -1.054658)
			(xy 363.740929 -1.138948) (xy 363.748841 -1.224331) (xy 363.749336 -1.267206) (xy 363.748841 -1.310081)
			(xy 368.244107 -1.310081) (xy 368.244107 -1.224331) (xy 368.252019 -1.138948) (xy 368.267775 -1.054658)
			(xy 368.291242 -0.972182) (xy 368.322218 -0.892223) (xy 368.36044 -0.815463) (xy 368.405581 -0.742557)
			(xy 368.457257 -0.674128) (xy 368.515026 -0.610758) (xy 368.578396 -0.552989) (xy 368.646825 -0.501313)
			(xy 368.719731 -0.456172) (xy 368.796491 -0.41795) (xy 368.87645 -0.386974) (xy 368.958926 -0.363507)
			(xy 369.043216 -0.347751) (xy 369.128599 -0.339839) (xy 369.214349 -0.339839) (xy 369.299732 -0.347751)
			(xy 369.384022 -0.363507) (xy 369.466498 -0.386974) (xy 369.546457 -0.41795) (xy 369.623217 -0.456172)
			(xy 369.696123 -0.501313) (xy 369.764552 -0.552989) (xy 369.827922 -0.610758) (xy 369.885691 -0.674128)
			(xy 369.937367 -0.742557) (xy 369.982508 -0.815463) (xy 370.02073 -0.892223) (xy 370.051706 -0.972182)
			(xy 370.075173 -1.054658) (xy 370.090929 -1.138948) (xy 370.098841 -1.224331) (xy 370.099336 -1.267206)
			(xy 370.098841 -1.310081) (xy 370.090929 -1.395464) (xy 370.075173 -1.479754) (xy 370.051706 -1.56223)
			(xy 370.02073 -1.642189) (xy 369.982508 -1.718949) (xy 369.937367 -1.791855) (xy 369.885691 -1.860284)
			(xy 369.827922 -1.923654) (xy 369.764552 -1.981423) (xy 369.696123 -2.033099) (xy 369.623217 -2.07824)
			(xy 369.546457 -2.116462) (xy 369.466498 -2.147438) (xy 369.384022 -2.170905) (xy 369.299732 -2.186661)
			(xy 369.214349 -2.194573) (xy 369.128599 -2.194573) (xy 369.043216 -2.186661) (xy 368.958926 -2.170905)
			(xy 368.87645 -2.147438) (xy 368.796491 -2.116462) (xy 368.719731 -2.07824) (xy 368.646825 -2.033099)
			(xy 368.578396 -1.981423) (xy 368.515026 -1.923654) (xy 368.457257 -1.860284) (xy 368.405581 -1.791855)
			(xy 368.36044 -1.718949) (xy 368.322218 -1.642189) (xy 368.291242 -1.56223) (xy 368.267775 -1.479754)
			(xy 368.252019 -1.395464) (xy 368.244107 -1.310081) (xy 363.748841 -1.310081) (xy 363.740929 -1.395464)
			(xy 363.725173 -1.479754) (xy 363.701706 -1.56223) (xy 363.67073 -1.642189) (xy 363.632508 -1.718949)
			(xy 363.587367 -1.791855) (xy 363.535691 -1.860284) (xy 363.477922 -1.923654) (xy 363.414552 -1.981423)
			(xy 363.346123 -2.033099) (xy 363.273217 -2.07824) (xy 363.196457 -2.116462) (xy 363.116498 -2.147438)
			(xy 363.034022 -2.170905) (xy 362.949732 -2.186661) (xy 362.864349 -2.194573) (xy 362.778599 -2.194573)
			(xy 362.693216 -2.186661) (xy 362.608926 -2.170905) (xy 362.52645 -2.147438) (xy 362.446491 -2.116462)
			(xy 362.369731 -2.07824) (xy 362.296825 -2.033099) (xy 362.228396 -1.981423) (xy 362.165026 -1.923654)
			(xy 362.107257 -1.860284) (xy 362.055581 -1.791855) (xy 362.01044 -1.718949) (xy 361.972218 -1.642189)
			(xy 361.941242 -1.56223) (xy 361.917775 -1.479754) (xy 361.902019 -1.395464) (xy 361.894107 -1.310081)
			(xy 319.360055 -1.310081) (xy 319.352143 -1.395464) (xy 319.336387 -1.479754) (xy 319.31292 -1.56223)
			(xy 319.281944 -1.642189) (xy 319.243722 -1.718949) (xy 319.198581 -1.791855) (xy 319.146905 -1.860284)
			(xy 319.089136 -1.923654) (xy 319.025766 -1.981423) (xy 318.957337 -2.033099) (xy 318.884431 -2.07824)
			(xy 318.807671 -2.116462) (xy 318.727712 -2.147438) (xy 318.645236 -2.170905) (xy 318.560946 -2.186661)
			(xy 318.475563 -2.194573) (xy 318.389813 -2.194573) (xy 318.30443 -2.186661) (xy 318.22014 -2.170905)
			(xy 318.137664 -2.147438) (xy 318.057705 -2.116462) (xy 317.980945 -2.07824) (xy 317.908039 -2.033099)
			(xy 317.83961 -1.981423) (xy 317.77624 -1.923654) (xy 317.718471 -1.860284) (xy 317.666795 -1.791855)
			(xy 317.621654 -1.718949) (xy 317.583432 -1.642189) (xy 317.552456 -1.56223) (xy 317.528989 -1.479754)
			(xy 317.513233 -1.395464) (xy 317.505321 -1.310081) (xy 313.010055 -1.310081) (xy 313.002143 -1.395464)
			(xy 312.986387 -1.479754) (xy 312.96292 -1.56223) (xy 312.931944 -1.642189) (xy 312.893722 -1.718949)
			(xy 312.848581 -1.791855) (xy 312.796905 -1.860284) (xy 312.739136 -1.923654) (xy 312.675766 -1.981423)
			(xy 312.607337 -2.033099) (xy 312.534431 -2.07824) (xy 312.457671 -2.116462) (xy 312.377712 -2.147438)
			(xy 312.295236 -2.170905) (xy 312.210946 -2.186661) (xy 312.125563 -2.194573) (xy 312.039813 -2.194573)
			(xy 311.95443 -2.186661) (xy 311.87014 -2.170905) (xy 311.787664 -2.147438) (xy 311.707705 -2.116462)
			(xy 311.630945 -2.07824) (xy 311.558039 -2.033099) (xy 311.48961 -1.981423) (xy 311.42624 -1.923654)
			(xy 311.368471 -1.860284) (xy 311.316795 -1.791855) (xy 311.271654 -1.718949) (xy 311.233432 -1.642189)
			(xy 311.202456 -1.56223) (xy 311.178989 -1.479754) (xy 311.163233 -1.395464) (xy 311.155321 -1.310081)
			(xy 304.348655 -1.310081) (xy 304.340743 -1.395464) (xy 304.324987 -1.479754) (xy 304.30152 -1.56223)
			(xy 304.270544 -1.642189) (xy 304.232322 -1.718949) (xy 304.187181 -1.791855) (xy 304.135505 -1.860284)
			(xy 304.077736 -1.923654) (xy 304.014366 -1.981423) (xy 303.945937 -2.033099) (xy 303.873031 -2.07824)
			(xy 303.796271 -2.116462) (xy 303.716312 -2.147438) (xy 303.633836 -2.170905) (xy 303.549546 -2.186661)
			(xy 303.464163 -2.194573) (xy 303.378413 -2.194573) (xy 303.29303 -2.186661) (xy 303.20874 -2.170905)
			(xy 303.126264 -2.147438) (xy 303.046305 -2.116462) (xy 302.969545 -2.07824) (xy 302.896639 -2.033099)
			(xy 302.82821 -1.981423) (xy 302.76484 -1.923654) (xy 302.707071 -1.860284) (xy 302.655395 -1.791855)
			(xy 302.610254 -1.718949) (xy 302.572032 -1.642189) (xy 302.541056 -1.56223) (xy 302.517589 -1.479754)
			(xy 302.501833 -1.395464) (xy 302.493921 -1.310081) (xy 297.998655 -1.310081) (xy 297.990743 -1.395464)
			(xy 297.974987 -1.479754) (xy 297.95152 -1.56223) (xy 297.920544 -1.642189) (xy 297.882322 -1.718949)
			(xy 297.837181 -1.791855) (xy 297.785505 -1.860284) (xy 297.727736 -1.923654) (xy 297.664366 -1.981423)
			(xy 297.595937 -2.033099) (xy 297.523031 -2.07824) (xy 297.446271 -2.116462) (xy 297.366312 -2.147438)
			(xy 297.283836 -2.170905) (xy 297.199546 -2.186661) (xy 297.114163 -2.194573) (xy 297.028413 -2.194573)
			(xy 296.94303 -2.186661) (xy 296.85874 -2.170905) (xy 296.776264 -2.147438) (xy 296.696305 -2.116462)
			(xy 296.619545 -2.07824) (xy 296.546639 -2.033099) (xy 296.47821 -1.981423) (xy 296.41484 -1.923654)
			(xy 296.357071 -1.860284) (xy 296.305395 -1.791855) (xy 296.260254 -1.718949) (xy 296.222032 -1.642189)
			(xy 296.191056 -1.56223) (xy 296.167589 -1.479754) (xy 296.151833 -1.395464) (xy 296.143921 -1.310081)
			(xy 216.865975 -1.310081) (xy 216.858063 -1.395464) (xy 216.842307 -1.479754) (xy 216.81884 -1.56223)
			(xy 216.787864 -1.642189) (xy 216.749642 -1.718949) (xy 216.704501 -1.791855) (xy 216.652825 -1.860284)
			(xy 216.595056 -1.923654) (xy 216.531686 -1.981423) (xy 216.463257 -2.033099) (xy 216.390351 -2.07824)
			(xy 216.313591 -2.116462) (xy 216.233632 -2.147438) (xy 216.151156 -2.170905) (xy 216.066866 -2.186661)
			(xy 215.981483 -2.194573) (xy 215.895733 -2.194573) (xy 215.81035 -2.186661) (xy 215.72606 -2.170905)
			(xy 215.643584 -2.147438) (xy 215.563625 -2.116462) (xy 215.486865 -2.07824) (xy 215.413959 -2.033099)
			(xy 215.34553 -1.981423) (xy 215.28216 -1.923654) (xy 215.224391 -1.860284) (xy 215.172715 -1.791855)
			(xy 215.127574 -1.718949) (xy 215.089352 -1.642189) (xy 215.058376 -1.56223) (xy 215.034909 -1.479754)
			(xy 215.019153 -1.395464) (xy 215.011241 -1.310081) (xy 210.515975 -1.310081) (xy 210.508063 -1.395464)
			(xy 210.492307 -1.479754) (xy 210.46884 -1.56223) (xy 210.437864 -1.642189) (xy 210.399642 -1.718949)
			(xy 210.354501 -1.791855) (xy 210.302825 -1.860284) (xy 210.245056 -1.923654) (xy 210.181686 -1.981423)
			(xy 210.113257 -2.033099) (xy 210.040351 -2.07824) (xy 209.963591 -2.116462) (xy 209.883632 -2.147438)
			(xy 209.801156 -2.170905) (xy 209.716866 -2.186661) (xy 209.631483 -2.194573) (xy 209.545733 -2.194573)
			(xy 209.46035 -2.186661) (xy 209.37606 -2.170905) (xy 209.293584 -2.147438) (xy 209.213625 -2.116462)
			(xy 209.136865 -2.07824) (xy 209.063959 -2.033099) (xy 208.99553 -1.981423) (xy 208.93216 -1.923654)
			(xy 208.874391 -1.860284) (xy 208.822715 -1.791855) (xy 208.777574 -1.718949) (xy 208.739352 -1.642189)
			(xy 208.708376 -1.56223) (xy 208.684909 -1.479754) (xy 208.669153 -1.395464) (xy 208.661241 -1.310081)
			(xy 84.210906 -1.310081) (xy 84.210906 -7.78002) (xy 84.211428 -7.835789) (xy 84.219765 -7.947014)
			(xy 84.23639 -8.057306) (xy 84.26121 -8.166046) (xy 84.294088 -8.272628) (xy 84.334838 -8.376455)
			(xy 84.383233 -8.476947) (xy 84.439002 -8.573541) (xy 84.501834 -8.665697) (xy 84.571376 -8.7529)
			(xy 84.647241 -8.834663) (xy 84.729004 -8.910527) (xy 84.816208 -8.98007) (xy 84.908364 -9.042901)
			(xy 85.004959 -9.09867) (xy 85.10545 -9.147065) (xy 85.209277 -9.187814) (xy 85.315859 -9.220691)
			(xy 85.4246 -9.245511) (xy 85.534892 -9.262136) (xy 85.646117 -9.270472) (xy 85.701886 -9.271) (xy 122.102118 -9.271)
			(xy 122.157887 -9.270478) (xy 122.269113 -9.262141) (xy 122.379404 -9.245517) (xy 122.488145 -9.220696)
			(xy 122.594728 -9.187819) (xy 122.698555 -9.147069) (xy 122.799047 -9.098674) (xy 122.895641 -9.042905)
			(xy 122.987798 -8.980073) (xy 123.075001 -8.910531) (xy 123.156764 -8.834666) (xy 123.232629 -8.752903)
			(xy 123.302172 -8.665699) (xy 123.365004 -8.573543) (xy 123.420773 -8.476948) (xy 123.469168 -8.376457)
			(xy 123.509918 -8.27263) (xy 123.542796 -8.166047) (xy 123.567616 -8.057306) (xy 123.584241 -7.947015)
			(xy 123.592578 -7.835789) (xy 123.593098 -7.78002) (xy 123.593098 -4.879848) (xy 123.593581 -4.809465)
			(xy 123.601472 -4.66892) (xy 123.61723 -4.529038) (xy 123.640807 -4.39026) (xy 123.672128 -4.253022)
			(xy 123.711095 -4.117757) (xy 123.757586 -3.984889) (xy 123.811453 -3.854837) (xy 123.872528 -3.72801)
			(xy 123.940618 -3.604807) (xy 124.015509 -3.485616) (xy 124.096965 -3.370811) (xy 124.184731 -3.260755)
			(xy 124.278529 -3.155793) (xy 124.378065 -3.056255) (xy 124.483026 -2.962455) (xy 124.593081 -2.874688)
			(xy 124.707884 -2.79323) (xy 124.827074 -2.718337) (xy 124.950276 -2.650245) (xy 125.077102 -2.589169)
			(xy 125.207153 -2.535299) (xy 125.340021 -2.488807) (xy 125.475285 -2.449838) (xy 125.612523 -2.418514)
			(xy 125.7513 -2.394935) (xy 125.891182 -2.379175) (xy 126.031727 -2.371282) (xy 126.10211 -2.370836)
			(xy 194.701922 -2.370836) (xy 194.772304 -2.371321) (xy 194.912845 -2.379215) (xy 195.052723 -2.394977)
			(xy 195.191497 -2.418557) (xy 195.328731 -2.449881) (xy 195.463992 -2.488851) (xy 195.596856 -2.535344)
			(xy 195.726904 -2.589213) (xy 195.853726 -2.650289) (xy 195.976925 -2.71838) (xy 196.096111 -2.793273)
			(xy 196.210911 -2.87473) (xy 196.320963 -2.962495) (xy 196.425921 -3.056294) (xy 196.525454 -3.15583)
			(xy 196.61925 -3.26079) (xy 196.707012 -3.370845) (xy 196.788466 -3.485647) (xy 196.863355 -3.604836)
			(xy 196.931443 -3.728036) (xy 196.990215 -3.850081) (xy 208.661241 -3.850081) (xy 208.661241 -3.764331)
			(xy 208.669153 -3.678948) (xy 208.684909 -3.594658) (xy 208.708376 -3.512182) (xy 208.739352 -3.432223)
			(xy 208.777574 -3.355463) (xy 208.822715 -3.282557) (xy 208.874391 -3.214128) (xy 208.93216 -3.150758)
			(xy 208.99553 -3.092989) (xy 209.063959 -3.041313) (xy 209.136865 -2.996172) (xy 209.213625 -2.95795)
			(xy 209.293584 -2.926974) (xy 209.37606 -2.903507) (xy 209.46035 -2.887751) (xy 209.545733 -2.879839)
			(xy 209.631483 -2.879839) (xy 209.716866 -2.887751) (xy 209.801156 -2.903507) (xy 209.883632 -2.926974)
			(xy 209.963591 -2.95795) (xy 209.984264 -2.968244) (xy 213.517988 -2.968244) (xy 213.517988 -2.104644)
			(xy 213.518492 -2.07509) (xy 213.526541 -2.016534) (xy 213.542487 -1.959619) (xy 213.566036 -1.905405)
			(xy 213.596747 -1.854902) (xy 213.634049 -1.809052) (xy 213.677246 -1.768709) (xy 213.725535 -1.734623)
			(xy 213.778015 -1.70743) (xy 213.83371 -1.687636) (xy 213.891581 -1.67561) (xy 213.95055 -1.671577)
			(xy 214.009519 -1.67561) (xy 214.06739 -1.687636) (xy 214.123085 -1.70743) (xy 214.175565 -1.734623)
			(xy 214.223854 -1.768709) (xy 214.267051 -1.809052) (xy 214.304353 -1.854902) (xy 214.335064 -1.905405)
			(xy 214.358613 -1.959619) (xy 214.374559 -2.016534) (xy 214.382608 -2.07509) (xy 214.383112 -2.104644)
			(xy 214.383112 -2.968244) (xy 214.382608 -2.997798) (xy 214.374559 -3.056354) (xy 214.358613 -3.113269)
			(xy 214.335064 -3.167483) (xy 214.304353 -3.217986) (xy 214.267051 -3.263836) (xy 214.223854 -3.304179)
			(xy 214.175565 -3.338265) (xy 214.123085 -3.365458) (xy 214.06739 -3.385252) (xy 214.009519 -3.397278)
			(xy 213.95055 -3.401312) (xy 213.891581 -3.397278) (xy 213.83371 -3.385252) (xy 213.778015 -3.365458)
			(xy 213.725535 -3.338265) (xy 213.677246 -3.304179) (xy 213.634049 -3.263836) (xy 213.596747 -3.217986)
			(xy 213.566036 -3.167483) (xy 213.542487 -3.113269) (xy 213.526541 -3.056354) (xy 213.518492 -2.997798)
			(xy 213.517988 -2.968244) (xy 209.984264 -2.968244) (xy 210.040351 -2.996172) (xy 210.113257 -3.041313)
			(xy 210.181686 -3.092989) (xy 210.245056 -3.150758) (xy 210.302825 -3.214128) (xy 210.354501 -3.282557)
			(xy 210.399642 -3.355463) (xy 210.437864 -3.432223) (xy 210.46884 -3.512182) (xy 210.492307 -3.594658)
			(xy 210.508063 -3.678948) (xy 210.515975 -3.764331) (xy 210.51647 -3.807206) (xy 210.515975 -3.850081)
			(xy 215.011241 -3.850081) (xy 215.011241 -3.764331) (xy 215.019153 -3.678948) (xy 215.034909 -3.594658)
			(xy 215.058376 -3.512182) (xy 215.089352 -3.432223) (xy 215.127574 -3.355463) (xy 215.172715 -3.282557)
			(xy 215.224391 -3.214128) (xy 215.28216 -3.150758) (xy 215.34553 -3.092989) (xy 215.413959 -3.041313)
			(xy 215.486865 -2.996172) (xy 215.563625 -2.95795) (xy 215.643584 -2.926974) (xy 215.72606 -2.903507)
			(xy 215.81035 -2.887751) (xy 215.895733 -2.879839) (xy 215.981483 -2.879839) (xy 216.066866 -2.887751)
			(xy 216.151156 -2.903507) (xy 216.233632 -2.926974) (xy 216.313591 -2.95795) (xy 216.390351 -2.996172)
			(xy 216.463257 -3.041313) (xy 216.531686 -3.092989) (xy 216.595056 -3.150758) (xy 216.652825 -3.214128)
			(xy 216.704501 -3.282557) (xy 216.749642 -3.355463) (xy 216.787864 -3.432223) (xy 216.81884 -3.512182)
			(xy 216.842307 -3.594658) (xy 216.858063 -3.678948) (xy 216.865975 -3.764331) (xy 216.86647 -3.807206)
			(xy 216.865975 -3.850081) (xy 296.143921 -3.850081) (xy 296.143921 -3.764331) (xy 296.151833 -3.678948)
			(xy 296.167589 -3.594658) (xy 296.191056 -3.512182) (xy 296.222032 -3.432223) (xy 296.260254 -3.355463)
			(xy 296.305395 -3.282557) (xy 296.357071 -3.214128) (xy 296.41484 -3.150758) (xy 296.47821 -3.092989)
			(xy 296.546639 -3.041313) (xy 296.619545 -2.996172) (xy 296.696305 -2.95795) (xy 296.776264 -2.926974)
			(xy 296.85874 -2.903507) (xy 296.94303 -2.887751) (xy 297.028413 -2.879839) (xy 297.114163 -2.879839)
			(xy 297.199546 -2.887751) (xy 297.283836 -2.903507) (xy 297.366312 -2.926974) (xy 297.446271 -2.95795)
			(xy 297.466944 -2.968244) (xy 298.629324 -2.968244) (xy 298.629324 -2.104644) (xy 298.629828 -2.07509)
			(xy 298.637877 -2.016534) (xy 298.653823 -1.959619) (xy 298.677372 -1.905405) (xy 298.708083 -1.854902)
			(xy 298.745385 -1.809052) (xy 298.788582 -1.768709) (xy 298.836871 -1.734623) (xy 298.889351 -1.70743)
			(xy 298.945046 -1.687636) (xy 299.002917 -1.67561) (xy 299.061886 -1.671577) (xy 299.120855 -1.67561)
			(xy 299.178726 -1.687636) (xy 299.234421 -1.70743) (xy 299.286901 -1.734623) (xy 299.33519 -1.768709)
			(xy 299.378387 -1.809052) (xy 299.415689 -1.854902) (xy 299.4464 -1.905405) (xy 299.469949 -1.959619)
			(xy 299.485895 -2.016534) (xy 299.493944 -2.07509) (xy 299.494448 -2.104644) (xy 299.494448 -2.968244)
			(xy 299.493944 -2.997798) (xy 299.485895 -3.056354) (xy 299.469949 -3.113269) (xy 299.4464 -3.167483)
			(xy 299.415689 -3.217986) (xy 299.378387 -3.263836) (xy 299.33519 -3.304179) (xy 299.286901 -3.338265)
			(xy 299.234421 -3.365458) (xy 299.178726 -3.385252) (xy 299.120855 -3.397278) (xy 299.061886 -3.401312)
			(xy 299.002917 -3.397278) (xy 298.945046 -3.385252) (xy 298.889351 -3.365458) (xy 298.836871 -3.338265)
			(xy 298.788582 -3.304179) (xy 298.745385 -3.263836) (xy 298.708083 -3.217986) (xy 298.677372 -3.167483)
			(xy 298.653823 -3.113269) (xy 298.637877 -3.056354) (xy 298.629828 -2.997798) (xy 298.629324 -2.968244)
			(xy 297.466944 -2.968244) (xy 297.523031 -2.996172) (xy 297.595937 -3.041313) (xy 297.664366 -3.092989)
			(xy 297.727736 -3.150758) (xy 297.785505 -3.214128) (xy 297.837181 -3.282557) (xy 297.882322 -3.355463)
			(xy 297.920544 -3.432223) (xy 297.95152 -3.512182) (xy 297.974987 -3.594658) (xy 297.990743 -3.678948)
			(xy 297.998655 -3.764331) (xy 297.99915 -3.807206) (xy 297.998655 -3.850081) (xy 302.493921 -3.850081)
			(xy 302.493921 -3.764331) (xy 302.501833 -3.678948) (xy 302.517589 -3.594658) (xy 302.541056 -3.512182)
			(xy 302.572032 -3.432223) (xy 302.610254 -3.355463) (xy 302.655395 -3.282557) (xy 302.707071 -3.214128)
			(xy 302.76484 -3.150758) (xy 302.82821 -3.092989) (xy 302.896639 -3.041313) (xy 302.969545 -2.996172)
			(xy 303.046305 -2.95795) (xy 303.126264 -2.926974) (xy 303.20874 -2.903507) (xy 303.29303 -2.887751)
			(xy 303.378413 -2.879839) (xy 303.464163 -2.879839) (xy 303.549546 -2.887751) (xy 303.633836 -2.903507)
			(xy 303.716312 -2.926974) (xy 303.796271 -2.95795) (xy 303.873031 -2.996172) (xy 303.945937 -3.041313)
			(xy 304.014366 -3.092989) (xy 304.077736 -3.150758) (xy 304.135505 -3.214128) (xy 304.187181 -3.282557)
			(xy 304.232322 -3.355463) (xy 304.270544 -3.432223) (xy 304.30152 -3.512182) (xy 304.324987 -3.594658)
			(xy 304.340743 -3.678948) (xy 304.348655 -3.764331) (xy 304.34915 -3.807206) (xy 304.348655 -3.850081)
			(xy 311.155321 -3.850081) (xy 311.155321 -3.764331) (xy 311.163233 -3.678948) (xy 311.178989 -3.594658)
			(xy 311.202456 -3.512182) (xy 311.233432 -3.432223) (xy 311.271654 -3.355463) (xy 311.316795 -3.282557)
			(xy 311.368471 -3.214128) (xy 311.42624 -3.150758) (xy 311.48961 -3.092989) (xy 311.558039 -3.041313)
			(xy 311.630945 -2.996172) (xy 311.707705 -2.95795) (xy 311.787664 -2.926974) (xy 311.87014 -2.903507)
			(xy 311.95443 -2.887751) (xy 312.039813 -2.879839) (xy 312.125563 -2.879839) (xy 312.210946 -2.887751)
			(xy 312.295236 -2.903507) (xy 312.377712 -2.926974) (xy 312.457671 -2.95795) (xy 312.478344 -2.968244)
			(xy 316.012068 -2.968244) (xy 316.012068 -2.104644) (xy 316.012572 -2.07509) (xy 316.020621 -2.016534)
			(xy 316.036567 -1.959619) (xy 316.060116 -1.905405) (xy 316.090827 -1.854902) (xy 316.128129 -1.809052)
			(xy 316.171326 -1.768709) (xy 316.219615 -1.734623) (xy 316.272095 -1.70743) (xy 316.32779 -1.687636)
			(xy 316.385661 -1.67561) (xy 316.44463 -1.671577) (xy 316.503599 -1.67561) (xy 316.56147 -1.687636)
			(xy 316.617165 -1.70743) (xy 316.669645 -1.734623) (xy 316.717934 -1.768709) (xy 316.761131 -1.809052)
			(xy 316.798433 -1.854902) (xy 316.829144 -1.905405) (xy 316.852693 -1.959619) (xy 316.868639 -2.016534)
			(xy 316.876688 -2.07509) (xy 316.877192 -2.104644) (xy 316.877192 -2.968244) (xy 316.876688 -2.997798)
			(xy 316.868639 -3.056354) (xy 316.852693 -3.113269) (xy 316.829144 -3.167483) (xy 316.798433 -3.217986)
			(xy 316.761131 -3.263836) (xy 316.717934 -3.304179) (xy 316.669645 -3.338265) (xy 316.617165 -3.365458)
			(xy 316.56147 -3.385252) (xy 316.503599 -3.397278) (xy 316.44463 -3.401312) (xy 316.385661 -3.397278)
			(xy 316.32779 -3.385252) (xy 316.272095 -3.365458) (xy 316.219615 -3.338265) (xy 316.171326 -3.304179)
			(xy 316.128129 -3.263836) (xy 316.090827 -3.217986) (xy 316.060116 -3.167483) (xy 316.036567 -3.113269)
			(xy 316.020621 -3.056354) (xy 316.012572 -2.997798) (xy 316.012068 -2.968244) (xy 312.478344 -2.968244)
			(xy 312.534431 -2.996172) (xy 312.607337 -3.041313) (xy 312.675766 -3.092989) (xy 312.739136 -3.150758)
			(xy 312.796905 -3.214128) (xy 312.848581 -3.282557) (xy 312.893722 -3.355463) (xy 312.931944 -3.432223)
			(xy 312.96292 -3.512182) (xy 312.986387 -3.594658) (xy 313.002143 -3.678948) (xy 313.010055 -3.764331)
			(xy 313.01055 -3.807206) (xy 313.010055 -3.850081) (xy 317.505321 -3.850081) (xy 317.505321 -3.764331)
			(xy 317.513233 -3.678948) (xy 317.528989 -3.594658) (xy 317.552456 -3.512182) (xy 317.583432 -3.432223)
			(xy 317.621654 -3.355463) (xy 317.666795 -3.282557) (xy 317.718471 -3.214128) (xy 317.77624 -3.150758)
			(xy 317.83961 -3.092989) (xy 317.908039 -3.041313) (xy 317.980945 -2.996172) (xy 318.057705 -2.95795)
			(xy 318.137664 -2.926974) (xy 318.22014 -2.903507) (xy 318.30443 -2.887751) (xy 318.389813 -2.879839)
			(xy 318.475563 -2.879839) (xy 318.560946 -2.887751) (xy 318.645236 -2.903507) (xy 318.727712 -2.926974)
			(xy 318.807671 -2.95795) (xy 318.884431 -2.996172) (xy 318.957337 -3.041313) (xy 319.025766 -3.092989)
			(xy 319.089136 -3.150758) (xy 319.146905 -3.214128) (xy 319.198581 -3.282557) (xy 319.243722 -3.355463)
			(xy 319.281944 -3.432223) (xy 319.31292 -3.512182) (xy 319.336387 -3.594658) (xy 319.352143 -3.678948)
			(xy 319.360055 -3.764331) (xy 319.36055 -3.807206) (xy 319.360055 -3.850081) (xy 361.894107 -3.850081)
			(xy 361.894107 -3.764331) (xy 361.902019 -3.678948) (xy 361.917775 -3.594658) (xy 361.941242 -3.512182)
			(xy 361.972218 -3.432223) (xy 362.01044 -3.355463) (xy 362.055581 -3.282557) (xy 362.107257 -3.214128)
			(xy 362.165026 -3.150758) (xy 362.228396 -3.092989) (xy 362.296825 -3.041313) (xy 362.369731 -2.996172)
			(xy 362.446491 -2.95795) (xy 362.52645 -2.926974) (xy 362.608926 -2.903507) (xy 362.693216 -2.887751)
			(xy 362.778599 -2.879839) (xy 362.864349 -2.879839) (xy 362.949732 -2.887751) (xy 363.034022 -2.903507)
			(xy 363.116498 -2.926974) (xy 363.196457 -2.95795) (xy 363.21713 -2.968244) (xy 364.379764 -2.968244)
			(xy 364.379764 -2.104644) (xy 364.380268 -2.075108) (xy 364.388312 -2.016586) (xy 364.404249 -1.959704)
			(xy 364.427784 -1.905522) (xy 364.458477 -1.855049) (xy 364.495757 -1.809226) (xy 364.538929 -1.768906)
			(xy 364.587189 -1.73484) (xy 364.639639 -1.707663) (xy 364.6953 -1.687881) (xy 364.753137 -1.675862)
			(xy 364.812072 -1.671831) (xy 364.871007 -1.675862) (xy 364.928844 -1.687881) (xy 364.984505 -1.707663)
			(xy 365.036955 -1.73484) (xy 365.085215 -1.768906) (xy 365.128387 -1.809226) (xy 365.165667 -1.855049)
			(xy 365.19636 -1.905522) (xy 365.219895 -1.959704) (xy 365.235832 -2.016586) (xy 365.243876 -2.075108)
			(xy 365.24438 -2.104644) (xy 365.24438 -2.968244) (xy 365.243876 -2.99778) (xy 365.235832 -3.056302)
			(xy 365.219895 -3.113184) (xy 365.19636 -3.167366) (xy 365.165667 -3.217839) (xy 365.128387 -3.263662)
			(xy 365.085215 -3.303982) (xy 365.036955 -3.338048) (xy 364.984505 -3.365225) (xy 364.928844 -3.385007)
			(xy 364.871007 -3.397026) (xy 364.812072 -3.401057) (xy 364.753137 -3.397026) (xy 364.6953 -3.385007)
			(xy 364.639639 -3.365225) (xy 364.587189 -3.338048) (xy 364.538929 -3.303982) (xy 364.495757 -3.263662)
			(xy 364.458477 -3.217839) (xy 364.427784 -3.167366) (xy 364.404249 -3.113184) (xy 364.388312 -3.056302)
			(xy 364.380268 -2.99778) (xy 364.379764 -2.968244) (xy 363.21713 -2.968244) (xy 363.273217 -2.996172)
			(xy 363.346123 -3.041313) (xy 363.414552 -3.092989) (xy 363.477922 -3.150758) (xy 363.535691 -3.214128)
			(xy 363.587367 -3.282557) (xy 363.632508 -3.355463) (xy 363.67073 -3.432223) (xy 363.701706 -3.512182)
			(xy 363.725173 -3.594658) (xy 363.740929 -3.678948) (xy 363.748841 -3.764331) (xy 363.749336 -3.807206)
			(xy 363.748841 -3.850081) (xy 368.244107 -3.850081) (xy 368.244107 -3.764331) (xy 368.252019 -3.678948)
			(xy 368.267775 -3.594658) (xy 368.291242 -3.512182) (xy 368.322218 -3.432223) (xy 368.36044 -3.355463)
			(xy 368.405581 -3.282557) (xy 368.457257 -3.214128) (xy 368.515026 -3.150758) (xy 368.578396 -3.092989)
			(xy 368.646825 -3.041313) (xy 368.719731 -2.996172) (xy 368.796491 -2.95795) (xy 368.87645 -2.926974)
			(xy 368.958926 -2.903507) (xy 369.043216 -2.887751) (xy 369.128599 -2.879839) (xy 369.214349 -2.879839)
			(xy 369.299732 -2.887751) (xy 369.384022 -2.903507) (xy 369.466498 -2.926974) (xy 369.546457 -2.95795)
			(xy 369.623217 -2.996172) (xy 369.696123 -3.041313) (xy 369.764552 -3.092989) (xy 369.827922 -3.150758)
			(xy 369.885691 -3.214128) (xy 369.937367 -3.282557) (xy 369.982508 -3.355463) (xy 370.02073 -3.432223)
			(xy 370.051706 -3.512182) (xy 370.075173 -3.594658) (xy 370.090929 -3.678948) (xy 370.098841 -3.764331)
			(xy 370.099336 -3.807206) (xy 370.098841 -3.850081) (xy 370.090929 -3.935464) (xy 370.075173 -4.019754)
			(xy 370.051706 -4.10223) (xy 370.02073 -4.182189) (xy 369.982508 -4.258949) (xy 369.937367 -4.331855)
			(xy 369.885691 -4.400284) (xy 369.827922 -4.463654) (xy 369.764552 -4.521423) (xy 369.696123 -4.573099)
			(xy 369.623217 -4.61824) (xy 369.546457 -4.656462) (xy 369.466498 -4.687438) (xy 369.384022 -4.710905)
			(xy 369.299732 -4.726661) (xy 369.214349 -4.734573) (xy 369.128599 -4.734573) (xy 369.043216 -4.726661)
			(xy 368.958926 -4.710905) (xy 368.87645 -4.687438) (xy 368.796491 -4.656462) (xy 368.719731 -4.61824)
			(xy 368.646825 -4.573099) (xy 368.578396 -4.521423) (xy 368.515026 -4.463654) (xy 368.457257 -4.400284)
			(xy 368.405581 -4.331855) (xy 368.36044 -4.258949) (xy 368.322218 -4.182189) (xy 368.291242 -4.10223)
			(xy 368.267775 -4.019754) (xy 368.252019 -3.935464) (xy 368.244107 -3.850081) (xy 363.748841 -3.850081)
			(xy 363.740929 -3.935464) (xy 363.725173 -4.019754) (xy 363.701706 -4.10223) (xy 363.67073 -4.182189)
			(xy 363.632508 -4.258949) (xy 363.587367 -4.331855) (xy 363.535691 -4.400284) (xy 363.477922 -4.463654)
			(xy 363.414552 -4.521423) (xy 363.346123 -4.573099) (xy 363.273217 -4.61824) (xy 363.196457 -4.656462)
			(xy 363.116498 -4.687438) (xy 363.034022 -4.710905) (xy 362.949732 -4.726661) (xy 362.864349 -4.734573)
			(xy 362.778599 -4.734573) (xy 362.693216 -4.726661) (xy 362.608926 -4.710905) (xy 362.52645 -4.687438)
			(xy 362.446491 -4.656462) (xy 362.369731 -4.61824) (xy 362.296825 -4.573099) (xy 362.228396 -4.521423)
			(xy 362.165026 -4.463654) (xy 362.107257 -4.400284) (xy 362.055581 -4.331855) (xy 362.01044 -4.258949)
			(xy 361.972218 -4.182189) (xy 361.941242 -4.10223) (xy 361.917775 -4.019754) (xy 361.902019 -3.935464)
			(xy 361.894107 -3.850081) (xy 319.360055 -3.850081) (xy 319.352143 -3.935464) (xy 319.336387 -4.019754)
			(xy 319.31292 -4.10223) (xy 319.281944 -4.182189) (xy 319.243722 -4.258949) (xy 319.198581 -4.331855)
			(xy 319.146905 -4.400284) (xy 319.089136 -4.463654) (xy 319.025766 -4.521423) (xy 318.957337 -4.573099)
			(xy 318.884431 -4.61824) (xy 318.807671 -4.656462) (xy 318.727712 -4.687438) (xy 318.645236 -4.710905)
			(xy 318.560946 -4.726661) (xy 318.475563 -4.734573) (xy 318.389813 -4.734573) (xy 318.30443 -4.726661)
			(xy 318.22014 -4.710905) (xy 318.137664 -4.687438) (xy 318.057705 -4.656462) (xy 317.980945 -4.61824)
			(xy 317.908039 -4.573099) (xy 317.83961 -4.521423) (xy 317.77624 -4.463654) (xy 317.718471 -4.400284)
			(xy 317.666795 -4.331855) (xy 317.621654 -4.258949) (xy 317.583432 -4.182189) (xy 317.552456 -4.10223)
			(xy 317.528989 -4.019754) (xy 317.513233 -3.935464) (xy 317.505321 -3.850081) (xy 313.010055 -3.850081)
			(xy 313.002143 -3.935464) (xy 312.986387 -4.019754) (xy 312.96292 -4.10223) (xy 312.931944 -4.182189)
			(xy 312.893722 -4.258949) (xy 312.848581 -4.331855) (xy 312.796905 -4.400284) (xy 312.739136 -4.463654)
			(xy 312.675766 -4.521423) (xy 312.607337 -4.573099) (xy 312.534431 -4.61824) (xy 312.457671 -4.656462)
			(xy 312.377712 -4.687438) (xy 312.295236 -4.710905) (xy 312.210946 -4.726661) (xy 312.125563 -4.734573)
			(xy 312.039813 -4.734573) (xy 311.95443 -4.726661) (xy 311.87014 -4.710905) (xy 311.787664 -4.687438)
			(xy 311.707705 -4.656462) (xy 311.630945 -4.61824) (xy 311.558039 -4.573099) (xy 311.48961 -4.521423)
			(xy 311.42624 -4.463654) (xy 311.368471 -4.400284) (xy 311.316795 -4.331855) (xy 311.271654 -4.258949)
			(xy 311.233432 -4.182189) (xy 311.202456 -4.10223) (xy 311.178989 -4.019754) (xy 311.163233 -3.935464)
			(xy 311.155321 -3.850081) (xy 304.348655 -3.850081) (xy 304.340743 -3.935464) (xy 304.324987 -4.019754)
			(xy 304.30152 -4.10223) (xy 304.270544 -4.182189) (xy 304.232322 -4.258949) (xy 304.187181 -4.331855)
			(xy 304.135505 -4.400284) (xy 304.077736 -4.463654) (xy 304.014366 -4.521423) (xy 303.945937 -4.573099)
			(xy 303.873031 -4.61824) (xy 303.796271 -4.656462) (xy 303.716312 -4.687438) (xy 303.633836 -4.710905)
			(xy 303.549546 -4.726661) (xy 303.464163 -4.734573) (xy 303.378413 -4.734573) (xy 303.29303 -4.726661)
			(xy 303.20874 -4.710905) (xy 303.126264 -4.687438) (xy 303.046305 -4.656462) (xy 302.969545 -4.61824)
			(xy 302.896639 -4.573099) (xy 302.82821 -4.521423) (xy 302.76484 -4.463654) (xy 302.707071 -4.400284)
			(xy 302.655395 -4.331855) (xy 302.610254 -4.258949) (xy 302.572032 -4.182189) (xy 302.541056 -4.10223)
			(xy 302.517589 -4.019754) (xy 302.501833 -3.935464) (xy 302.493921 -3.850081) (xy 297.998655 -3.850081)
			(xy 297.990743 -3.935464) (xy 297.974987 -4.019754) (xy 297.95152 -4.10223) (xy 297.920544 -4.182189)
			(xy 297.882322 -4.258949) (xy 297.837181 -4.331855) (xy 297.785505 -4.400284) (xy 297.727736 -4.463654)
			(xy 297.664366 -4.521423) (xy 297.595937 -4.573099) (xy 297.523031 -4.61824) (xy 297.446271 -4.656462)
			(xy 297.366312 -4.687438) (xy 297.283836 -4.710905) (xy 297.199546 -4.726661) (xy 297.114163 -4.734573)
			(xy 297.028413 -4.734573) (xy 296.94303 -4.726661) (xy 296.85874 -4.710905) (xy 296.776264 -4.687438)
			(xy 296.696305 -4.656462) (xy 296.619545 -4.61824) (xy 296.546639 -4.573099) (xy 296.47821 -4.521423)
			(xy 296.41484 -4.463654) (xy 296.357071 -4.400284) (xy 296.305395 -4.331855) (xy 296.260254 -4.258949)
			(xy 296.222032 -4.182189) (xy 296.191056 -4.10223) (xy 296.167589 -4.019754) (xy 296.151833 -3.935464)
			(xy 296.143921 -3.850081) (xy 216.865975 -3.850081) (xy 216.858063 -3.935464) (xy 216.842307 -4.019754)
			(xy 216.81884 -4.10223) (xy 216.787864 -4.182189) (xy 216.749642 -4.258949) (xy 216.704501 -4.331855)
			(xy 216.652825 -4.400284) (xy 216.595056 -4.463654) (xy 216.531686 -4.521423) (xy 216.463257 -4.573099)
			(xy 216.390351 -4.61824) (xy 216.313591 -4.656462) (xy 216.233632 -4.687438) (xy 216.151156 -4.710905)
			(xy 216.066866 -4.726661) (xy 215.981483 -4.734573) (xy 215.895733 -4.734573) (xy 215.81035 -4.726661)
			(xy 215.72606 -4.710905) (xy 215.643584 -4.687438) (xy 215.563625 -4.656462) (xy 215.486865 -4.61824)
			(xy 215.413959 -4.573099) (xy 215.34553 -4.521423) (xy 215.28216 -4.463654) (xy 215.224391 -4.400284)
			(xy 215.172715 -4.331855) (xy 215.127574 -4.258949) (xy 215.089352 -4.182189) (xy 215.058376 -4.10223)
			(xy 215.034909 -4.019754) (xy 215.019153 -3.935464) (xy 215.011241 -3.850081) (xy 210.515975 -3.850081)
			(xy 210.508063 -3.935464) (xy 210.492307 -4.019754) (xy 210.46884 -4.10223) (xy 210.437864 -4.182189)
			(xy 210.399642 -4.258949) (xy 210.354501 -4.331855) (xy 210.302825 -4.400284) (xy 210.245056 -4.463654)
			(xy 210.181686 -4.521423) (xy 210.113257 -4.573099) (xy 210.040351 -4.61824) (xy 209.963591 -4.656462)
			(xy 209.883632 -4.687438) (xy 209.801156 -4.710905) (xy 209.716866 -4.726661) (xy 209.631483 -4.734573)
			(xy 209.545733 -4.734573) (xy 209.46035 -4.726661) (xy 209.37606 -4.710905) (xy 209.293584 -4.687438)
			(xy 209.213625 -4.656462) (xy 209.136865 -4.61824) (xy 209.063959 -4.573099) (xy 208.99553 -4.521423)
			(xy 208.93216 -4.463654) (xy 208.874391 -4.400284) (xy 208.822715 -4.331855) (xy 208.777574 -4.258949)
			(xy 208.739352 -4.182189) (xy 208.708376 -4.10223) (xy 208.684909 -4.019754) (xy 208.669153 -3.935464)
			(xy 208.661241 -3.850081) (xy 196.990215 -3.850081) (xy 196.992516 -3.85486) (xy 197.046381 -3.984909)
			(xy 197.09287 -4.117774) (xy 197.131836 -4.253037) (xy 197.163157 -4.390271) (xy 197.186733 -4.529046)
			(xy 197.202491 -4.668924) (xy 197.210381 -4.809466) (xy 197.210934 -4.879848) (xy 197.210934 -6.390081)
			(xy 208.661241 -6.390081) (xy 208.661241 -6.304331) (xy 208.669153 -6.218948) (xy 208.684909 -6.134658)
			(xy 208.708376 -6.052182) (xy 208.739352 -5.972223) (xy 208.777574 -5.895463) (xy 208.822715 -5.822557)
			(xy 208.874391 -5.754128) (xy 208.93216 -5.690758) (xy 208.99553 -5.632989) (xy 209.063959 -5.581313)
			(xy 209.136865 -5.536172) (xy 209.213625 -5.49795) (xy 209.293584 -5.466974) (xy 209.37606 -5.443507)
			(xy 209.46035 -5.427751) (xy 209.545733 -5.419839) (xy 209.631483 -5.419839) (xy 209.716866 -5.427751)
			(xy 209.801156 -5.443507) (xy 209.883632 -5.466974) (xy 209.963591 -5.49795) (xy 209.984264 -5.508244)
			(xy 213.517988 -5.508244) (xy 213.517988 -4.644644) (xy 213.518492 -4.61509) (xy 213.526541 -4.556534)
			(xy 213.542487 -4.499619) (xy 213.566036 -4.445405) (xy 213.596747 -4.394902) (xy 213.634049 -4.349052)
			(xy 213.677246 -4.308709) (xy 213.725535 -4.274623) (xy 213.778015 -4.24743) (xy 213.83371 -4.227636)
			(xy 213.891581 -4.21561) (xy 213.95055 -4.211577) (xy 214.009519 -4.21561) (xy 214.06739 -4.227636)
			(xy 214.123085 -4.24743) (xy 214.175565 -4.274623) (xy 214.223854 -4.308709) (xy 214.267051 -4.349052)
			(xy 214.304353 -4.394902) (xy 214.335064 -4.445405) (xy 214.358613 -4.499619) (xy 214.374559 -4.556534)
			(xy 214.382608 -4.61509) (xy 214.383112 -4.644644) (xy 214.383112 -5.508244) (xy 214.382608 -5.537798)
			(xy 214.374559 -5.596354) (xy 214.358613 -5.653269) (xy 214.335064 -5.707483) (xy 214.304353 -5.757986)
			(xy 214.267051 -5.803836) (xy 214.223854 -5.844179) (xy 214.175565 -5.878265) (xy 214.123085 -5.905458)
			(xy 214.06739 -5.925252) (xy 214.009519 -5.937278) (xy 213.95055 -5.941312) (xy 213.891581 -5.937278)
			(xy 213.83371 -5.925252) (xy 213.778015 -5.905458) (xy 213.725535 -5.878265) (xy 213.677246 -5.844179)
			(xy 213.634049 -5.803836) (xy 213.596747 -5.757986) (xy 213.566036 -5.707483) (xy 213.542487 -5.653269)
			(xy 213.526541 -5.596354) (xy 213.518492 -5.537798) (xy 213.517988 -5.508244) (xy 209.984264 -5.508244)
			(xy 210.040351 -5.536172) (xy 210.113257 -5.581313) (xy 210.181686 -5.632989) (xy 210.245056 -5.690758)
			(xy 210.302825 -5.754128) (xy 210.354501 -5.822557) (xy 210.399642 -5.895463) (xy 210.437864 -5.972223)
			(xy 210.46884 -6.052182) (xy 210.492307 -6.134658) (xy 210.508063 -6.218948) (xy 210.515975 -6.304331)
			(xy 210.51647 -6.347206) (xy 210.515975 -6.390081) (xy 215.011241 -6.390081) (xy 215.011241 -6.304331)
			(xy 215.019153 -6.218948) (xy 215.034909 -6.134658) (xy 215.058376 -6.052182) (xy 215.089352 -5.972223)
			(xy 215.127574 -5.895463) (xy 215.172715 -5.822557) (xy 215.224391 -5.754128) (xy 215.28216 -5.690758)
			(xy 215.34553 -5.632989) (xy 215.413959 -5.581313) (xy 215.486865 -5.536172) (xy 215.563625 -5.49795)
			(xy 215.643584 -5.466974) (xy 215.72606 -5.443507) (xy 215.81035 -5.427751) (xy 215.895733 -5.419839)
			(xy 215.981483 -5.419839) (xy 216.066866 -5.427751) (xy 216.151156 -5.443507) (xy 216.233632 -5.466974)
			(xy 216.313591 -5.49795) (xy 216.390351 -5.536172) (xy 216.463257 -5.581313) (xy 216.531686 -5.632989)
			(xy 216.595056 -5.690758) (xy 216.652825 -5.754128) (xy 216.704501 -5.822557) (xy 216.749642 -5.895463)
			(xy 216.787864 -5.972223) (xy 216.81884 -6.052182) (xy 216.842307 -6.134658) (xy 216.858063 -6.218948)
			(xy 216.865975 -6.304331) (xy 216.86647 -6.347206) (xy 216.865975 -6.390081) (xy 296.143921 -6.390081)
			(xy 296.143921 -6.304331) (xy 296.151833 -6.218948) (xy 296.167589 -6.134658) (xy 296.191056 -6.052182)
			(xy 296.222032 -5.972223) (xy 296.260254 -5.895463) (xy 296.305395 -5.822557) (xy 296.357071 -5.754128)
			(xy 296.41484 -5.690758) (xy 296.47821 -5.632989) (xy 296.546639 -5.581313) (xy 296.619545 -5.536172)
			(xy 296.696305 -5.49795) (xy 296.776264 -5.466974) (xy 296.85874 -5.443507) (xy 296.94303 -5.427751)
			(xy 297.028413 -5.419839) (xy 297.114163 -5.419839) (xy 297.199546 -5.427751) (xy 297.283836 -5.443507)
			(xy 297.366312 -5.466974) (xy 297.446271 -5.49795) (xy 297.466944 -5.508244) (xy 298.629324 -5.508244)
			(xy 298.629324 -4.644644) (xy 298.629828 -4.61509) (xy 298.637877 -4.556534) (xy 298.653823 -4.499619)
			(xy 298.677372 -4.445405) (xy 298.708083 -4.394902) (xy 298.745385 -4.349052) (xy 298.788582 -4.308709)
			(xy 298.836871 -4.274623) (xy 298.889351 -4.24743) (xy 298.945046 -4.227636) (xy 299.002917 -4.21561)
			(xy 299.061886 -4.211577) (xy 299.120855 -4.21561) (xy 299.178726 -4.227636) (xy 299.234421 -4.24743)
			(xy 299.286901 -4.274623) (xy 299.33519 -4.308709) (xy 299.378387 -4.349052) (xy 299.415689 -4.394902)
			(xy 299.4464 -4.445405) (xy 299.469949 -4.499619) (xy 299.485895 -4.556534) (xy 299.493944 -4.61509)
			(xy 299.494448 -4.644644) (xy 299.494448 -5.508244) (xy 299.493944 -5.537798) (xy 299.485895 -5.596354)
			(xy 299.469949 -5.653269) (xy 299.4464 -5.707483) (xy 299.415689 -5.757986) (xy 299.378387 -5.803836)
			(xy 299.33519 -5.844179) (xy 299.286901 -5.878265) (xy 299.234421 -5.905458) (xy 299.178726 -5.925252)
			(xy 299.120855 -5.937278) (xy 299.061886 -5.941312) (xy 299.002917 -5.937278) (xy 298.945046 -5.925252)
			(xy 298.889351 -5.905458) (xy 298.836871 -5.878265) (xy 298.788582 -5.844179) (xy 298.745385 -5.803836)
			(xy 298.708083 -5.757986) (xy 298.677372 -5.707483) (xy 298.653823 -5.653269) (xy 298.637877 -5.596354)
			(xy 298.629828 -5.537798) (xy 298.629324 -5.508244) (xy 297.466944 -5.508244) (xy 297.523031 -5.536172)
			(xy 297.595937 -5.581313) (xy 297.664366 -5.632989) (xy 297.727736 -5.690758) (xy 297.785505 -5.754128)
			(xy 297.837181 -5.822557) (xy 297.882322 -5.895463) (xy 297.920544 -5.972223) (xy 297.95152 -6.052182)
			(xy 297.974987 -6.134658) (xy 297.990743 -6.218948) (xy 297.998655 -6.304331) (xy 297.99915 -6.347206)
			(xy 297.998655 -6.390081) (xy 302.493921 -6.390081) (xy 302.493921 -6.304331) (xy 302.501833 -6.218948)
			(xy 302.517589 -6.134658) (xy 302.541056 -6.052182) (xy 302.572032 -5.972223) (xy 302.610254 -5.895463)
			(xy 302.655395 -5.822557) (xy 302.707071 -5.754128) (xy 302.76484 -5.690758) (xy 302.82821 -5.632989)
			(xy 302.896639 -5.581313) (xy 302.969545 -5.536172) (xy 303.046305 -5.49795) (xy 303.126264 -5.466974)
			(xy 303.20874 -5.443507) (xy 303.29303 -5.427751) (xy 303.378413 -5.419839) (xy 303.464163 -5.419839)
			(xy 303.549546 -5.427751) (xy 303.633836 -5.443507) (xy 303.716312 -5.466974) (xy 303.796271 -5.49795)
			(xy 303.873031 -5.536172) (xy 303.945937 -5.581313) (xy 304.014366 -5.632989) (xy 304.077736 -5.690758)
			(xy 304.135505 -5.754128) (xy 304.187181 -5.822557) (xy 304.232322 -5.895463) (xy 304.270544 -5.972223)
			(xy 304.30152 -6.052182) (xy 304.324987 -6.134658) (xy 304.340743 -6.218948) (xy 304.348655 -6.304331)
			(xy 304.34915 -6.347206) (xy 304.348655 -6.390081) (xy 311.155321 -6.390081) (xy 311.155321 -6.304331)
			(xy 311.163233 -6.218948) (xy 311.178989 -6.134658) (xy 311.202456 -6.052182) (xy 311.233432 -5.972223)
			(xy 311.271654 -5.895463) (xy 311.316795 -5.822557) (xy 311.368471 -5.754128) (xy 311.42624 -5.690758)
			(xy 311.48961 -5.632989) (xy 311.558039 -5.581313) (xy 311.630945 -5.536172) (xy 311.707705 -5.49795)
			(xy 311.787664 -5.466974) (xy 311.87014 -5.443507) (xy 311.95443 -5.427751) (xy 312.039813 -5.419839)
			(xy 312.125563 -5.419839) (xy 312.210946 -5.427751) (xy 312.295236 -5.443507) (xy 312.377712 -5.466974)
			(xy 312.457671 -5.49795) (xy 312.534431 -5.536172) (xy 312.607337 -5.581313) (xy 312.675766 -5.632989)
			(xy 312.739136 -5.690758) (xy 312.796905 -5.754128) (xy 312.848581 -5.822557) (xy 312.893722 -5.895463)
			(xy 312.931944 -5.972223) (xy 312.96292 -6.052182) (xy 312.986387 -6.134658) (xy 313.002143 -6.218948)
			(xy 313.010055 -6.304331) (xy 313.01055 -6.347206) (xy 313.010055 -6.390081) (xy 317.505321 -6.390081)
			(xy 317.505321 -6.304331) (xy 317.513233 -6.218948) (xy 317.528989 -6.134658) (xy 317.552456 -6.052182)
			(xy 317.583432 -5.972223) (xy 317.621654 -5.895463) (xy 317.666795 -5.822557) (xy 317.718471 -5.754128)
			(xy 317.77624 -5.690758) (xy 317.83961 -5.632989) (xy 317.908039 -5.581313) (xy 317.980945 -5.536172)
			(xy 318.057705 -5.49795) (xy 318.137664 -5.466974) (xy 318.22014 -5.443507) (xy 318.30443 -5.427751)
			(xy 318.389813 -5.419839) (xy 318.475563 -5.419839) (xy 318.560946 -5.427751) (xy 318.645236 -5.443507)
			(xy 318.727712 -5.466974) (xy 318.807671 -5.49795) (xy 318.884431 -5.536172) (xy 318.957337 -5.581313)
			(xy 319.025766 -5.632989) (xy 319.089136 -5.690758) (xy 319.146905 -5.754128) (xy 319.198581 -5.822557)
			(xy 319.243722 -5.895463) (xy 319.281944 -5.972223) (xy 319.31292 -6.052182) (xy 319.336387 -6.134658)
			(xy 319.352143 -6.218948) (xy 319.360055 -6.304331) (xy 319.36055 -6.347206) (xy 319.360055 -6.390081)
			(xy 361.894107 -6.390081) (xy 361.894107 -6.304331) (xy 361.902019 -6.218948) (xy 361.917775 -6.134658)
			(xy 361.941242 -6.052182) (xy 361.972218 -5.972223) (xy 362.01044 -5.895463) (xy 362.055581 -5.822557)
			(xy 362.107257 -5.754128) (xy 362.165026 -5.690758) (xy 362.228396 -5.632989) (xy 362.296825 -5.581313)
			(xy 362.369731 -5.536172) (xy 362.446491 -5.49795) (xy 362.52645 -5.466974) (xy 362.608926 -5.443507)
			(xy 362.693216 -5.427751) (xy 362.778599 -5.419839) (xy 362.864349 -5.419839) (xy 362.949732 -5.427751)
			(xy 363.034022 -5.443507) (xy 363.116498 -5.466974) (xy 363.196457 -5.49795) (xy 363.273217 -5.536172)
			(xy 363.346123 -5.581313) (xy 363.414552 -5.632989) (xy 363.477922 -5.690758) (xy 363.535691 -5.754128)
			(xy 363.587367 -5.822557) (xy 363.632508 -5.895463) (xy 363.67073 -5.972223) (xy 363.701706 -6.052182)
			(xy 363.725173 -6.134658) (xy 363.740929 -6.218948) (xy 363.748841 -6.304331) (xy 363.749336 -6.347206)
			(xy 363.748841 -6.390081) (xy 368.244107 -6.390081) (xy 368.244107 -6.304331) (xy 368.252019 -6.218948)
			(xy 368.267775 -6.134658) (xy 368.291242 -6.052182) (xy 368.322218 -5.972223) (xy 368.36044 -5.895463)
			(xy 368.405581 -5.822557) (xy 368.457257 -5.754128) (xy 368.515026 -5.690758) (xy 368.578396 -5.632989)
			(xy 368.646825 -5.581313) (xy 368.719731 -5.536172) (xy 368.796491 -5.49795) (xy 368.87645 -5.466974)
			(xy 368.958926 -5.443507) (xy 369.043216 -5.427751) (xy 369.128599 -5.419839) (xy 369.214349 -5.419839)
			(xy 369.299732 -5.427751) (xy 369.384022 -5.443507) (xy 369.466498 -5.466974) (xy 369.546457 -5.49795)
			(xy 369.623217 -5.536172) (xy 369.696123 -5.581313) (xy 369.764552 -5.632989) (xy 369.827922 -5.690758)
			(xy 369.885691 -5.754128) (xy 369.937367 -5.822557) (xy 369.982508 -5.895463) (xy 370.02073 -5.972223)
			(xy 370.051706 -6.052182) (xy 370.075173 -6.134658) (xy 370.090929 -6.218948) (xy 370.098841 -6.304331)
			(xy 370.099336 -6.347206) (xy 370.098841 -6.390081) (xy 370.090929 -6.475464) (xy 370.075173 -6.559754)
			(xy 370.051706 -6.64223) (xy 370.02073 -6.722189) (xy 369.982508 -6.798949) (xy 369.937367 -6.871855)
			(xy 369.885691 -6.940284) (xy 369.827922 -7.003654) (xy 369.764552 -7.061423) (xy 369.696123 -7.113099)
			(xy 369.623217 -7.15824) (xy 369.546457 -7.196462) (xy 369.466498 -7.227438) (xy 369.384022 -7.250905)
			(xy 369.299732 -7.266661) (xy 369.214349 -7.274573) (xy 369.128599 -7.274573) (xy 369.043216 -7.266661)
			(xy 368.958926 -7.250905) (xy 368.87645 -7.227438) (xy 368.796491 -7.196462) (xy 368.719731 -7.15824)
			(xy 368.646825 -7.113099) (xy 368.578396 -7.061423) (xy 368.515026 -7.003654) (xy 368.457257 -6.940284)
			(xy 368.405581 -6.871855) (xy 368.36044 -6.798949) (xy 368.322218 -6.722189) (xy 368.291242 -6.64223)
			(xy 368.267775 -6.559754) (xy 368.252019 -6.475464) (xy 368.244107 -6.390081) (xy 363.748841 -6.390081)
			(xy 363.740929 -6.475464) (xy 363.725173 -6.559754) (xy 363.701706 -6.64223) (xy 363.67073 -6.722189)
			(xy 363.632508 -6.798949) (xy 363.587367 -6.871855) (xy 363.535691 -6.940284) (xy 363.477922 -7.003654)
			(xy 363.414552 -7.061423) (xy 363.346123 -7.113099) (xy 363.273217 -7.15824) (xy 363.196457 -7.196462)
			(xy 363.116498 -7.227438) (xy 363.034022 -7.250905) (xy 362.949732 -7.266661) (xy 362.864349 -7.274573)
			(xy 362.778599 -7.274573) (xy 362.693216 -7.266661) (xy 362.608926 -7.250905) (xy 362.52645 -7.227438)
			(xy 362.446491 -7.196462) (xy 362.369731 -7.15824) (xy 362.296825 -7.113099) (xy 362.228396 -7.061423)
			(xy 362.165026 -7.003654) (xy 362.107257 -6.940284) (xy 362.055581 -6.871855) (xy 362.01044 -6.798949)
			(xy 361.972218 -6.722189) (xy 361.941242 -6.64223) (xy 361.917775 -6.559754) (xy 361.902019 -6.475464)
			(xy 361.894107 -6.390081) (xy 319.360055 -6.390081) (xy 319.352143 -6.475464) (xy 319.336387 -6.559754)
			(xy 319.31292 -6.64223) (xy 319.281944 -6.722189) (xy 319.243722 -6.798949) (xy 319.198581 -6.871855)
			(xy 319.146905 -6.940284) (xy 319.089136 -7.003654) (xy 319.025766 -7.061423) (xy 318.957337 -7.113099)
			(xy 318.884431 -7.15824) (xy 318.807671 -7.196462) (xy 318.727712 -7.227438) (xy 318.645236 -7.250905)
			(xy 318.560946 -7.266661) (xy 318.475563 -7.274573) (xy 318.389813 -7.274573) (xy 318.30443 -7.266661)
			(xy 318.22014 -7.250905) (xy 318.137664 -7.227438) (xy 318.057705 -7.196462) (xy 317.980945 -7.15824)
			(xy 317.908039 -7.113099) (xy 317.83961 -7.061423) (xy 317.77624 -7.003654) (xy 317.718471 -6.940284)
			(xy 317.666795 -6.871855) (xy 317.621654 -6.798949) (xy 317.583432 -6.722189) (xy 317.552456 -6.64223)
			(xy 317.528989 -6.559754) (xy 317.513233 -6.475464) (xy 317.505321 -6.390081) (xy 313.010055 -6.390081)
			(xy 313.002143 -6.475464) (xy 312.986387 -6.559754) (xy 312.96292 -6.64223) (xy 312.931944 -6.722189)
			(xy 312.893722 -6.798949) (xy 312.848581 -6.871855) (xy 312.796905 -6.940284) (xy 312.739136 -7.003654)
			(xy 312.675766 -7.061423) (xy 312.607337 -7.113099) (xy 312.534431 -7.15824) (xy 312.457671 -7.196462)
			(xy 312.377712 -7.227438) (xy 312.295236 -7.250905) (xy 312.210946 -7.266661) (xy 312.125563 -7.274573)
			(xy 312.039813 -7.274573) (xy 311.95443 -7.266661) (xy 311.87014 -7.250905) (xy 311.787664 -7.227438)
			(xy 311.707705 -7.196462) (xy 311.630945 -7.15824) (xy 311.558039 -7.113099) (xy 311.48961 -7.061423)
			(xy 311.42624 -7.003654) (xy 311.368471 -6.940284) (xy 311.316795 -6.871855) (xy 311.271654 -6.798949)
			(xy 311.233432 -6.722189) (xy 311.202456 -6.64223) (xy 311.178989 -6.559754) (xy 311.163233 -6.475464)
			(xy 311.155321 -6.390081) (xy 304.348655 -6.390081) (xy 304.340743 -6.475464) (xy 304.324987 -6.559754)
			(xy 304.30152 -6.64223) (xy 304.270544 -6.722189) (xy 304.232322 -6.798949) (xy 304.187181 -6.871855)
			(xy 304.135505 -6.940284) (xy 304.077736 -7.003654) (xy 304.014366 -7.061423) (xy 303.945937 -7.113099)
			(xy 303.873031 -7.15824) (xy 303.796271 -7.196462) (xy 303.716312 -7.227438) (xy 303.633836 -7.250905)
			(xy 303.549546 -7.266661) (xy 303.464163 -7.274573) (xy 303.378413 -7.274573) (xy 303.29303 -7.266661)
			(xy 303.20874 -7.250905) (xy 303.126264 -7.227438) (xy 303.046305 -7.196462) (xy 302.969545 -7.15824)
			(xy 302.896639 -7.113099) (xy 302.82821 -7.061423) (xy 302.76484 -7.003654) (xy 302.707071 -6.940284)
			(xy 302.655395 -6.871855) (xy 302.610254 -6.798949) (xy 302.572032 -6.722189) (xy 302.541056 -6.64223)
			(xy 302.517589 -6.559754) (xy 302.501833 -6.475464) (xy 302.493921 -6.390081) (xy 297.998655 -6.390081)
			(xy 297.990743 -6.475464) (xy 297.974987 -6.559754) (xy 297.95152 -6.64223) (xy 297.920544 -6.722189)
			(xy 297.882322 -6.798949) (xy 297.837181 -6.871855) (xy 297.785505 -6.940284) (xy 297.727736 -7.003654)
			(xy 297.664366 -7.061423) (xy 297.595937 -7.113099) (xy 297.523031 -7.15824) (xy 297.446271 -7.196462)
			(xy 297.366312 -7.227438) (xy 297.283836 -7.250905) (xy 297.199546 -7.266661) (xy 297.114163 -7.274573)
			(xy 297.028413 -7.274573) (xy 296.94303 -7.266661) (xy 296.85874 -7.250905) (xy 296.776264 -7.227438)
			(xy 296.696305 -7.196462) (xy 296.619545 -7.15824) (xy 296.546639 -7.113099) (xy 296.47821 -7.061423)
			(xy 296.41484 -7.003654) (xy 296.357071 -6.940284) (xy 296.305395 -6.871855) (xy 296.260254 -6.798949)
			(xy 296.222032 -6.722189) (xy 296.191056 -6.64223) (xy 296.167589 -6.559754) (xy 296.151833 -6.475464)
			(xy 296.143921 -6.390081) (xy 216.865975 -6.390081) (xy 216.858063 -6.475464) (xy 216.842307 -6.559754)
			(xy 216.81884 -6.64223) (xy 216.787864 -6.722189) (xy 216.749642 -6.798949) (xy 216.704501 -6.871855)
			(xy 216.652825 -6.940284) (xy 216.595056 -7.003654) (xy 216.531686 -7.061423) (xy 216.463257 -7.113099)
			(xy 216.390351 -7.15824) (xy 216.313591 -7.196462) (xy 216.233632 -7.227438) (xy 216.151156 -7.250905)
			(xy 216.066866 -7.266661) (xy 215.981483 -7.274573) (xy 215.895733 -7.274573) (xy 215.81035 -7.266661)
			(xy 215.72606 -7.250905) (xy 215.643584 -7.227438) (xy 215.563625 -7.196462) (xy 215.486865 -7.15824)
			(xy 215.413959 -7.113099) (xy 215.34553 -7.061423) (xy 215.28216 -7.003654) (xy 215.224391 -6.940284)
			(xy 215.172715 -6.871855) (xy 215.127574 -6.798949) (xy 215.089352 -6.722189) (xy 215.058376 -6.64223)
			(xy 215.034909 -6.559754) (xy 215.019153 -6.475464) (xy 215.011241 -6.390081) (xy 210.515975 -6.390081)
			(xy 210.508063 -6.475464) (xy 210.492307 -6.559754) (xy 210.46884 -6.64223) (xy 210.437864 -6.722189)
			(xy 210.399642 -6.798949) (xy 210.354501 -6.871855) (xy 210.302825 -6.940284) (xy 210.245056 -7.003654)
			(xy 210.181686 -7.061423) (xy 210.113257 -7.113099) (xy 210.040351 -7.15824) (xy 209.963591 -7.196462)
			(xy 209.883632 -7.227438) (xy 209.801156 -7.250905) (xy 209.716866 -7.266661) (xy 209.631483 -7.274573)
			(xy 209.545733 -7.274573) (xy 209.46035 -7.266661) (xy 209.37606 -7.250905) (xy 209.293584 -7.227438)
			(xy 209.213625 -7.196462) (xy 209.136865 -7.15824) (xy 209.063959 -7.113099) (xy 208.99553 -7.061423)
			(xy 208.93216 -7.003654) (xy 208.874391 -6.940284) (xy 208.822715 -6.871855) (xy 208.777574 -6.798949)
			(xy 208.739352 -6.722189) (xy 208.708376 -6.64223) (xy 208.684909 -6.559754) (xy 208.669153 -6.475464)
			(xy 208.661241 -6.390081) (xy 197.210934 -6.390081) (xy 197.210934 -7.78002) (xy 197.211456 -7.835788)
			(xy 197.219793 -7.947013) (xy 197.236418 -8.057304) (xy 197.261239 -8.166044) (xy 197.294116 -8.272625)
			(xy 197.334866 -8.376451) (xy 197.383261 -8.476941) (xy 197.439031 -8.573534) (xy 197.501863 -8.66569)
			(xy 197.571406 -8.752892) (xy 197.647271 -8.834653) (xy 197.729034 -8.910516) (xy 197.816238 -8.980057)
			(xy 197.908394 -9.042887) (xy 198.004989 -9.098654) (xy 198.10548 -9.147047) (xy 198.209307 -9.187795)
			(xy 198.315889 -9.22067) (xy 198.42463 -9.245488) (xy 198.534921 -9.262111) (xy 198.646146 -9.270445)
			(xy 198.701914 -9.271) (xy 223.300036 -9.271) (xy 223.370417 -9.271495) (xy 223.510959 -9.279389)
			(xy 223.650836 -9.295152) (xy 223.78961 -9.318732) (xy 223.926844 -9.350057) (xy 224.062105 -9.389027)
			(xy 224.194968 -9.435519) (xy 224.325015 -9.489388) (xy 224.451838 -9.550465) (xy 224.575036 -9.618556)
			(xy 224.694222 -9.693447) (xy 224.809022 -9.774904) (xy 224.919074 -9.862669) (xy 225.024032 -9.956467)
			(xy 225.123566 -10.056003) (xy 225.217361 -10.160962) (xy 225.305125 -10.271016) (xy 225.386579 -10.385818)
			(xy 225.461469 -10.505006) (xy 225.529557 -10.628205) (xy 225.590631 -10.755029) (xy 225.644498 -10.885077)
			(xy 225.690988 -11.017941) (xy 225.729955 -11.153203) (xy 225.761277 -11.290437) (xy 225.784855 -11.429211)
			(xy 225.800615 -11.569089) (xy 225.808507 -11.709631) (xy 225.809048 -11.780012) (xy 225.809048 -33.120076)
			(xy 225.809549 -33.152224) (xy 225.817939 -33.21597) (xy 225.834578 -33.278076) (xy 225.859182 -33.337478)
			(xy 225.891329 -33.39316) (xy 225.93047 -33.44417) (xy 225.975934 -33.489634) (xy 226.026945 -33.528774)
			(xy 226.082627 -33.560921) (xy 226.14203 -33.585524) (xy 226.204136 -33.602162) (xy 226.267882 -33.610551)
			(xy 226.30003 -33.611058)
		)
		(stroke
			(width 0)
			(type solid)
		)
		(fill yes)
		(layer "In9.Cu")
		(net "DELTA_L_GND_1")
	)
	(gr_poly
		(pts
			(xy 302.008794 -421.868092) (xy 302.020958 -421.867402) (xy 302.042588 -421.85627) (xy 302.050196 -421.846756)
			(xy 302.065728 -421.825873) (xy 302.101857 -421.788414) (xy 302.143054 -421.756613) (xy 302.188442 -421.731147)
			(xy 302.237053 -421.71256) (xy 302.287851 -421.701247) (xy 302.339756 -421.697449) (xy 302.391661 -421.701247)
			(xy 302.442459 -421.71256) (xy 302.49107 -421.731147) (xy 302.536458 -421.756613) (xy 302.577655 -421.788414)
			(xy 302.613784 -421.825873) (xy 302.629316 -421.846756) (xy 302.636927 -421.856276) (xy 302.65855 -421.867444)
			(xy 302.670718 -421.868092) (xy 365.260636 -421.868092) (xy 365.269863 -421.867685) (xy 365.287111 -421.861121)
			(xy 365.300905 -421.848862) (xy 365.309449 -421.832504) (xy 365.310928 -421.823388) (xy 365.310928 -415.898584)
			(xy 365.311359 -415.888368) (xy 365.319187 -415.869493) (xy 365.333644 -415.855053) (xy 365.352527 -415.847247)
			(xy 365.362744 -415.846768) (xy 370.261388 -415.846768) (xy 370.271599 -415.847264) (xy 370.290467 -415.855074)
			(xy 370.304911 -415.86951) (xy 370.312731 -415.888374) (xy 370.313204 -415.898584) (xy 370.313204 -418.439456)
			(xy 372.044623 -418.439456) (xy 372.044623 -418.384944) (xy 372.052381 -418.330986) (xy 372.06774 -418.278682)
			(xy 372.090386 -418.229097) (xy 372.119858 -418.183238) (xy 372.155557 -418.142042) (xy 372.196756 -418.106345)
			(xy 372.242616 -418.076875) (xy 372.292203 -418.054232) (xy 372.344508 -418.038877) (xy 372.398466 -418.031121)
			(xy 372.425722 -418.03066) (xy 373.289322 -418.03066) (xy 373.31657 -418.031212) (xy 373.370511 -418.03897)
			(xy 373.422798 -418.054326) (xy 373.472369 -418.076966) (xy 373.518212 -418.106431) (xy 373.559396 -418.142119)
			(xy 373.595083 -418.183305) (xy 373.624544 -418.229151) (xy 373.647182 -418.278722) (xy 373.662535 -418.331011)
			(xy 373.67029 -418.384952) (xy 373.67029 -418.439448) (xy 373.670289 -418.439452) (xy 375.107946 -418.439452)
			(xy 375.107946 -418.384948) (xy 375.115702 -418.330999) (xy 375.131056 -418.278703) (xy 375.153697 -418.229124)
			(xy 375.183162 -418.183272) (xy 375.218852 -418.142079) (xy 375.260041 -418.106385) (xy 375.305891 -418.076915)
			(xy 375.355468 -418.05427) (xy 375.407762 -418.03891) (xy 375.46171 -418.031148) (xy 375.488962 -418.03066)
			(xy 376.352562 -418.03066) (xy 376.379814 -418.031185) (xy 376.433765 -418.038937) (xy 376.486063 -418.054288)
			(xy 376.535644 -418.076926) (xy 376.581498 -418.106391) (xy 376.622691 -418.142082) (xy 376.658386 -418.183272)
			(xy 376.687855 -418.229123) (xy 376.710499 -418.278701) (xy 376.725855 -418.330998) (xy 376.733613 -418.384948)
			(xy 376.733613 -418.439452) (xy 376.733613 -418.439455) (xy 378.171123 -418.439455) (xy 378.171123 -418.384945)
			(xy 378.178881 -418.330989) (xy 378.194238 -418.278687) (xy 378.216883 -418.229102) (xy 378.246353 -418.183245)
			(xy 378.28205 -418.142049) (xy 378.323247 -418.106352) (xy 378.369104 -418.076882) (xy 378.418688 -418.054237)
			(xy 378.470991 -418.03888) (xy 378.524947 -418.031123) (xy 378.552202 -418.03066) (xy 379.415802 -418.03066)
			(xy 379.443051 -418.03121) (xy 379.496994 -418.038966) (xy 379.549284 -418.05432) (xy 379.598857 -418.07696)
			(xy 379.644703 -418.106424) (xy 379.685889 -418.142112) (xy 379.721578 -418.183299) (xy 379.751041 -418.229145)
			(xy 379.77368 -418.278718) (xy 379.789034 -418.331008) (xy 379.79679 -418.384951) (xy 379.79679 -418.439449)
			(xy 379.796789 -418.439457) (xy 381.234323 -418.439457) (xy 381.234323 -418.384943) (xy 381.242082 -418.330984)
			(xy 381.257441 -418.278678) (xy 381.280089 -418.229091) (xy 381.309563 -418.183232) (xy 381.345264 -418.142035)
			(xy 381.386466 -418.106338) (xy 381.432328 -418.076869) (xy 381.481917 -418.054227) (xy 381.534225 -418.038873)
			(xy 381.588185 -418.03112) (xy 381.615442 -418.03066) (xy 382.479042 -418.03066) (xy 382.506289 -418.031213)
			(xy 382.560228 -418.038974) (xy 382.612513 -418.054331) (xy 382.662081 -418.076973) (xy 382.707922 -418.106438)
			(xy 382.749103 -418.142126) (xy 382.784787 -418.183312) (xy 382.814247 -418.229156) (xy 382.836883 -418.278727)
			(xy 382.852235 -418.331014) (xy 382.85999 -418.384953) (xy 382.85999 -418.439447) (xy 382.859989 -418.439453)
			(xy 384.297646 -418.439453) (xy 384.297646 -418.384947) (xy 384.305403 -418.330997) (xy 384.320758 -418.278699)
			(xy 384.3434 -418.229119) (xy 384.372867 -418.183265) (xy 384.408559 -418.142072) (xy 384.449751 -418.106378)
			(xy 384.495603 -418.076908) (xy 384.545182 -418.054264) (xy 384.597479 -418.038906) (xy 384.651429 -418.031147)
			(xy 384.678682 -418.03066) (xy 385.542282 -418.03066) (xy 385.569533 -418.031186) (xy 385.623482 -418.03894)
			(xy 385.675777 -418.054293) (xy 385.725356 -418.076933) (xy 385.771207 -418.106398) (xy 385.812399 -418.142089)
			(xy 385.848091 -418.183278) (xy 385.877558 -418.229129) (xy 385.9002 -418.278706) (xy 385.915556 -418.331001)
			(xy 385.923313 -418.384949) (xy 385.923313 -418.439451) (xy 385.923312 -418.439456) (xy 387.360823 -418.439456)
			(xy 387.360823 -418.384944) (xy 387.368581 -418.330986) (xy 387.38394 -418.278682) (xy 387.406586 -418.229097)
			(xy 387.436058 -418.183238) (xy 387.471757 -418.142042) (xy 387.512956 -418.106345) (xy 387.558816 -418.076875)
			(xy 387.608403 -418.054232) (xy 387.660708 -418.038877) (xy 387.714666 -418.031121) (xy 387.741922 -418.03066)
			(xy 388.605522 -418.03066) (xy 388.63277 -418.031212) (xy 388.686711 -418.03897) (xy 388.738998 -418.054326)
			(xy 388.788569 -418.076966) (xy 388.834412 -418.106431) (xy 388.875596 -418.142119) (xy 388.911283 -418.183305)
			(xy 388.940744 -418.229151) (xy 388.963382 -418.278722) (xy 388.978735 -418.331011) (xy 388.98649 -418.384952)
			(xy 388.98649 -418.439448) (xy 388.986489 -418.439452) (xy 390.424146 -418.439452) (xy 390.424146 -418.384948)
			(xy 390.431902 -418.330999) (xy 390.447256 -418.278703) (xy 390.469897 -418.229124) (xy 390.499362 -418.183272)
			(xy 390.535052 -418.142079) (xy 390.576241 -418.106385) (xy 390.622091 -418.076915) (xy 390.671668 -418.05427)
			(xy 390.723962 -418.03891) (xy 390.77791 -418.031148) (xy 390.805162 -418.03066) (xy 391.668762 -418.03066)
			(xy 391.696014 -418.031185) (xy 391.749965 -418.038937) (xy 391.802263 -418.054288) (xy 391.851844 -418.076926)
			(xy 391.897698 -418.106391) (xy 391.938891 -418.142082) (xy 391.974586 -418.183272) (xy 392.004055 -418.229123)
			(xy 392.026699 -418.278701) (xy 392.042055 -418.330998) (xy 392.049813 -418.384948) (xy 392.049813 -418.439452)
			(xy 392.049813 -418.439455) (xy 393.487323 -418.439455) (xy 393.487323 -418.384945) (xy 393.495081 -418.330989)
			(xy 393.510438 -418.278687) (xy 393.533083 -418.229102) (xy 393.562553 -418.183245) (xy 393.59825 -418.142049)
			(xy 393.639447 -418.106352) (xy 393.685304 -418.076882) (xy 393.734888 -418.054237) (xy 393.787191 -418.03888)
			(xy 393.841147 -418.031123) (xy 393.868402 -418.03066) (xy 394.732002 -418.03066) (xy 394.759251 -418.03121)
			(xy 394.813194 -418.038966) (xy 394.865484 -418.05432) (xy 394.915057 -418.07696) (xy 394.960903 -418.106424)
			(xy 395.002089 -418.142112) (xy 395.037778 -418.183299) (xy 395.067241 -418.229145) (xy 395.08988 -418.278718)
			(xy 395.105234 -418.331008) (xy 395.11299 -418.384951) (xy 395.11299 -418.439449) (xy 395.112989 -418.439457)
			(xy 396.550523 -418.439457) (xy 396.550523 -418.384943) (xy 396.558282 -418.330984) (xy 396.573641 -418.278678)
			(xy 396.596289 -418.229091) (xy 396.625763 -418.183232) (xy 396.661464 -418.142035) (xy 396.702666 -418.106338)
			(xy 396.748528 -418.076869) (xy 396.798117 -418.054227) (xy 396.850425 -418.038873) (xy 396.904385 -418.03112)
			(xy 396.931642 -418.03066) (xy 397.795242 -418.03066) (xy 397.822489 -418.031213) (xy 397.876428 -418.038974)
			(xy 397.928713 -418.054331) (xy 397.978281 -418.076973) (xy 398.024122 -418.106438) (xy 398.065303 -418.142126)
			(xy 398.100987 -418.183312) (xy 398.130447 -418.229156) (xy 398.153083 -418.278727) (xy 398.168435 -418.331014)
			(xy 398.17619 -418.384953) (xy 398.17619 -418.439447) (xy 398.176189 -418.439453) (xy 399.613846 -418.439453)
			(xy 399.613846 -418.384947) (xy 399.621603 -418.330997) (xy 399.636958 -418.278699) (xy 399.6596 -418.229119)
			(xy 399.689067 -418.183265) (xy 399.724759 -418.142072) (xy 399.765951 -418.106378) (xy 399.811803 -418.076908)
			(xy 399.861382 -418.054264) (xy 399.913679 -418.038906) (xy 399.967629 -418.031147) (xy 399.994882 -418.03066)
			(xy 400.858482 -418.03066) (xy 400.885733 -418.031186) (xy 400.939682 -418.03894) (xy 400.991977 -418.054293)
			(xy 401.041556 -418.076933) (xy 401.087407 -418.106398) (xy 401.128599 -418.142089) (xy 401.164291 -418.183278)
			(xy 401.193758 -418.229129) (xy 401.2164 -418.278706) (xy 401.231756 -418.331001) (xy 401.239513 -418.384949)
			(xy 401.239513 -418.439451) (xy 401.239512 -418.439456) (xy 402.677023 -418.439456) (xy 402.677023 -418.384944)
			(xy 402.684781 -418.330986) (xy 402.70014 -418.278682) (xy 402.722786 -418.229097) (xy 402.752258 -418.183238)
			(xy 402.787957 -418.142042) (xy 402.829156 -418.106345) (xy 402.875016 -418.076875) (xy 402.924603 -418.054232)
			(xy 402.976908 -418.038877) (xy 403.030866 -418.031121) (xy 403.058122 -418.03066) (xy 403.921722 -418.03066)
			(xy 403.94897 -418.031212) (xy 404.002911 -418.03897) (xy 404.055198 -418.054326) (xy 404.104769 -418.076966)
			(xy 404.150612 -418.106431) (xy 404.191796 -418.142119) (xy 404.227483 -418.183305) (xy 404.256944 -418.229151)
			(xy 404.279582 -418.278722) (xy 404.294935 -418.331011) (xy 404.30269 -418.384952) (xy 404.30269 -418.439448)
			(xy 404.302689 -418.439452) (xy 405.740346 -418.439452) (xy 405.740346 -418.384948) (xy 405.748102 -418.330999)
			(xy 405.763456 -418.278703) (xy 405.786097 -418.229124) (xy 405.815562 -418.183272) (xy 405.851252 -418.142079)
			(xy 405.892441 -418.106385) (xy 405.938291 -418.076915) (xy 405.987868 -418.05427) (xy 406.040162 -418.03891)
			(xy 406.09411 -418.031148) (xy 406.121362 -418.03066) (xy 406.984962 -418.03066) (xy 407.012214 -418.031185)
			(xy 407.066165 -418.038937) (xy 407.118463 -418.054288) (xy 407.168044 -418.076926) (xy 407.213898 -418.106391)
			(xy 407.255091 -418.142082) (xy 407.290786 -418.183272) (xy 407.320255 -418.229123) (xy 407.342899 -418.278701)
			(xy 407.358255 -418.330998) (xy 407.366013 -418.384948) (xy 407.366013 -418.439452) (xy 407.366013 -418.439455)
			(xy 408.803523 -418.439455) (xy 408.803523 -418.384945) (xy 408.811281 -418.330989) (xy 408.826638 -418.278687)
			(xy 408.849283 -418.229102) (xy 408.878753 -418.183245) (xy 408.91445 -418.142049) (xy 408.955647 -418.106352)
			(xy 409.001504 -418.076882) (xy 409.051088 -418.054237) (xy 409.103391 -418.03888) (xy 409.157347 -418.031123)
			(xy 409.184602 -418.03066) (xy 410.048202 -418.03066) (xy 410.075451 -418.03121) (xy 410.129394 -418.038966)
			(xy 410.181684 -418.05432) (xy 410.231257 -418.07696) (xy 410.277103 -418.106424) (xy 410.318289 -418.142112)
			(xy 410.353978 -418.183299) (xy 410.383441 -418.229145) (xy 410.40608 -418.278718) (xy 410.421434 -418.331008)
			(xy 410.42919 -418.384951) (xy 410.42919 -418.439449) (xy 410.429189 -418.439457) (xy 411.866723 -418.439457)
			(xy 411.866723 -418.384943) (xy 411.874482 -418.330984) (xy 411.889841 -418.278678) (xy 411.912489 -418.229091)
			(xy 411.941963 -418.183232) (xy 411.977664 -418.142035) (xy 412.018866 -418.106338) (xy 412.064728 -418.076869)
			(xy 412.114317 -418.054227) (xy 412.166625 -418.038873) (xy 412.220585 -418.03112) (xy 412.247842 -418.03066)
			(xy 413.111442 -418.03066) (xy 413.138689 -418.031213) (xy 413.192628 -418.038974) (xy 413.244913 -418.054331)
			(xy 413.294481 -418.076973) (xy 413.340322 -418.106438) (xy 413.381503 -418.142126) (xy 413.417187 -418.183312)
			(xy 413.446647 -418.229156) (xy 413.469283 -418.278727) (xy 413.484635 -418.331014) (xy 413.49239 -418.384953)
			(xy 413.49239 -418.439447) (xy 413.492389 -418.439453) (xy 414.930046 -418.439453) (xy 414.930046 -418.384947)
			(xy 414.937803 -418.330997) (xy 414.953158 -418.278699) (xy 414.9758 -418.229119) (xy 415.005267 -418.183265)
			(xy 415.040959 -418.142072) (xy 415.082151 -418.106378) (xy 415.128003 -418.076908) (xy 415.177582 -418.054264)
			(xy 415.229879 -418.038906) (xy 415.283829 -418.031147) (xy 415.311082 -418.03066) (xy 416.174682 -418.03066)
			(xy 416.201933 -418.031186) (xy 416.255882 -418.03894) (xy 416.308177 -418.054293) (xy 416.357756 -418.076933)
			(xy 416.403607 -418.106398) (xy 416.444799 -418.142089) (xy 416.480491 -418.183278) (xy 416.509958 -418.229129)
			(xy 416.5326 -418.278706) (xy 416.547956 -418.331001) (xy 416.555713 -418.384949) (xy 416.555713 -418.439451)
			(xy 416.555712 -418.439456) (xy 417.993223 -418.439456) (xy 417.993223 -418.384944) (xy 418.000981 -418.330986)
			(xy 418.01634 -418.278682) (xy 418.038986 -418.229097) (xy 418.068458 -418.183238) (xy 418.104157 -418.142042)
			(xy 418.145356 -418.106345) (xy 418.191216 -418.076875) (xy 418.240803 -418.054232) (xy 418.293108 -418.038877)
			(xy 418.347066 -418.031121) (xy 418.374322 -418.03066) (xy 419.237922 -418.03066) (xy 419.26517 -418.031212)
			(xy 419.319111 -418.03897) (xy 419.371398 -418.054326) (xy 419.420969 -418.076966) (xy 419.466812 -418.106431)
			(xy 419.507996 -418.142119) (xy 419.543683 -418.183305) (xy 419.573144 -418.229151) (xy 419.595782 -418.278722)
			(xy 419.611135 -418.331011) (xy 419.61889 -418.384952) (xy 419.61889 -418.439448) (xy 419.611135 -418.493389)
			(xy 419.595782 -418.545678) (xy 419.573144 -418.595249) (xy 419.543683 -418.641095) (xy 419.507996 -418.682281)
			(xy 419.466812 -418.717969) (xy 419.420969 -418.747434) (xy 419.371398 -418.770074) (xy 419.319111 -418.78543)
			(xy 419.26517 -418.793188) (xy 419.237922 -418.793676) (xy 418.374322 -418.793676) (xy 418.347066 -418.793279)
			(xy 418.293108 -418.785523) (xy 418.240803 -418.770168) (xy 418.191216 -418.747525) (xy 418.145356 -418.718055)
			(xy 418.104157 -418.682358) (xy 418.068458 -418.641162) (xy 418.038986 -418.595303) (xy 418.01634 -418.545718)
			(xy 418.000981 -418.493414) (xy 417.993223 -418.439456) (xy 416.555712 -418.439456) (xy 416.547956 -418.493399)
			(xy 416.5326 -418.545694) (xy 416.509958 -418.595271) (xy 416.480491 -418.641122) (xy 416.444799 -418.682311)
			(xy 416.403607 -418.718002) (xy 416.357756 -418.747467) (xy 416.308177 -418.770107) (xy 416.255882 -418.78546)
			(xy 416.201933 -418.793214) (xy 416.174682 -418.793676) (xy 415.311082 -418.793676) (xy 415.283829 -418.793253)
			(xy 415.229879 -418.785494) (xy 415.177582 -418.770136) (xy 415.128003 -418.747492) (xy 415.082151 -418.718022)
			(xy 415.040959 -418.682328) (xy 415.005267 -418.641135) (xy 414.9758 -418.595281) (xy 414.953158 -418.545701)
			(xy 414.937803 -418.493403) (xy 414.930046 -418.439453) (xy 413.492389 -418.439453) (xy 413.484635 -418.493386)
			(xy 413.469283 -418.545673) (xy 413.446647 -418.595244) (xy 413.417187 -418.641088) (xy 413.381503 -418.682274)
			(xy 413.340322 -418.717962) (xy 413.294481 -418.747427) (xy 413.244913 -418.770069) (xy 413.192628 -418.785426)
			(xy 413.138689 -418.793187) (xy 413.111442 -418.793676) (xy 412.247842 -418.793676) (xy 412.220585 -418.79328)
			(xy 412.166625 -418.785527) (xy 412.114317 -418.770173) (xy 412.064728 -418.747531) (xy 412.018866 -418.718062)
			(xy 411.977664 -418.682365) (xy 411.941963 -418.641168) (xy 411.912489 -418.595309) (xy 411.889841 -418.545722)
			(xy 411.874482 -418.493416) (xy 411.866723 -418.439457) (xy 410.429189 -418.439457) (xy 410.421434 -418.493392)
			(xy 410.40608 -418.545682) (xy 410.383441 -418.595255) (xy 410.353978 -418.641101) (xy 410.318289 -418.682288)
			(xy 410.277103 -418.717976) (xy 410.231257 -418.74744) (xy 410.181684 -418.77008) (xy 410.129394 -418.785434)
			(xy 410.075451 -418.79319) (xy 410.048202 -418.793676) (xy 409.184602 -418.793676) (xy 409.157347 -418.793277)
			(xy 409.103391 -418.78552) (xy 409.051088 -418.770163) (xy 409.001504 -418.747518) (xy 408.955647 -418.718048)
			(xy 408.91445 -418.682351) (xy 408.878753 -418.641155) (xy 408.849283 -418.595298) (xy 408.826638 -418.545713)
			(xy 408.811281 -418.493411) (xy 408.803523 -418.439455) (xy 407.366013 -418.439455) (xy 407.358255 -418.493402)
			(xy 407.342899 -418.545699) (xy 407.320255 -418.595277) (xy 407.290786 -418.641128) (xy 407.255091 -418.682318)
			(xy 407.213898 -418.718009) (xy 407.168044 -418.747474) (xy 407.118463 -418.770112) (xy 407.066165 -418.785463)
			(xy 407.012214 -418.793215) (xy 406.984962 -418.793676) (xy 406.121362 -418.793676) (xy 406.09411 -418.793252)
			(xy 406.040162 -418.78549) (xy 405.987868 -418.77013) (xy 405.938291 -418.747485) (xy 405.892441 -418.718015)
			(xy 405.851252 -418.682321) (xy 405.815562 -418.641128) (xy 405.786097 -418.595276) (xy 405.763456 -418.545697)
			(xy 405.748102 -418.493401) (xy 405.740346 -418.439452) (xy 404.302689 -418.439452) (xy 404.294935 -418.493389)
			(xy 404.279582 -418.545678) (xy 404.256944 -418.595249) (xy 404.227483 -418.641095) (xy 404.191796 -418.682281)
			(xy 404.150612 -418.717969) (xy 404.104769 -418.747434) (xy 404.055198 -418.770074) (xy 404.002911 -418.78543)
			(xy 403.94897 -418.793188) (xy 403.921722 -418.793676) (xy 403.058122 -418.793676) (xy 403.030866 -418.793279)
			(xy 402.976908 -418.785523) (xy 402.924603 -418.770168) (xy 402.875016 -418.747525) (xy 402.829156 -418.718055)
			(xy 402.787957 -418.682358) (xy 402.752258 -418.641162) (xy 402.722786 -418.595303) (xy 402.70014 -418.545718)
			(xy 402.684781 -418.493414) (xy 402.677023 -418.439456) (xy 401.239512 -418.439456) (xy 401.231756 -418.493399)
			(xy 401.2164 -418.545694) (xy 401.193758 -418.595271) (xy 401.164291 -418.641122) (xy 401.128599 -418.682311)
			(xy 401.087407 -418.718002) (xy 401.041556 -418.747467) (xy 400.991977 -418.770107) (xy 400.939682 -418.78546)
			(xy 400.885733 -418.793214) (xy 400.858482 -418.793676) (xy 399.994882 -418.793676) (xy 399.967629 -418.793253)
			(xy 399.913679 -418.785494) (xy 399.861382 -418.770136) (xy 399.811803 -418.747492) (xy 399.765951 -418.718022)
			(xy 399.724759 -418.682328) (xy 399.689067 -418.641135) (xy 399.6596 -418.595281) (xy 399.636958 -418.545701)
			(xy 399.621603 -418.493403) (xy 399.613846 -418.439453) (xy 398.176189 -418.439453) (xy 398.168435 -418.493386)
			(xy 398.153083 -418.545673) (xy 398.130447 -418.595244) (xy 398.100987 -418.641088) (xy 398.065303 -418.682274)
			(xy 398.024122 -418.717962) (xy 397.978281 -418.747427) (xy 397.928713 -418.770069) (xy 397.876428 -418.785426)
			(xy 397.822489 -418.793187) (xy 397.795242 -418.793676) (xy 396.931642 -418.793676) (xy 396.904385 -418.79328)
			(xy 396.850425 -418.785527) (xy 396.798117 -418.770173) (xy 396.748528 -418.747531) (xy 396.702666 -418.718062)
			(xy 396.661464 -418.682365) (xy 396.625763 -418.641168) (xy 396.596289 -418.595309) (xy 396.573641 -418.545722)
			(xy 396.558282 -418.493416) (xy 396.550523 -418.439457) (xy 395.112989 -418.439457) (xy 395.105234 -418.493392)
			(xy 395.08988 -418.545682) (xy 395.067241 -418.595255) (xy 395.037778 -418.641101) (xy 395.002089 -418.682288)
			(xy 394.960903 -418.717976) (xy 394.915057 -418.74744) (xy 394.865484 -418.77008) (xy 394.813194 -418.785434)
			(xy 394.759251 -418.79319) (xy 394.732002 -418.793676) (xy 393.868402 -418.793676) (xy 393.841147 -418.793277)
			(xy 393.787191 -418.78552) (xy 393.734888 -418.770163) (xy 393.685304 -418.747518) (xy 393.639447 -418.718048)
			(xy 393.59825 -418.682351) (xy 393.562553 -418.641155) (xy 393.533083 -418.595298) (xy 393.510438 -418.545713)
			(xy 393.495081 -418.493411) (xy 393.487323 -418.439455) (xy 392.049813 -418.439455) (xy 392.042055 -418.493402)
			(xy 392.026699 -418.545699) (xy 392.004055 -418.595277) (xy 391.974586 -418.641128) (xy 391.938891 -418.682318)
			(xy 391.897698 -418.718009) (xy 391.851844 -418.747474) (xy 391.802263 -418.770112) (xy 391.749965 -418.785463)
			(xy 391.696014 -418.793215) (xy 391.668762 -418.793676) (xy 390.805162 -418.793676) (xy 390.77791 -418.793252)
			(xy 390.723962 -418.78549) (xy 390.671668 -418.77013) (xy 390.622091 -418.747485) (xy 390.576241 -418.718015)
			(xy 390.535052 -418.682321) (xy 390.499362 -418.641128) (xy 390.469897 -418.595276) (xy 390.447256 -418.545697)
			(xy 390.431902 -418.493401) (xy 390.424146 -418.439452) (xy 388.986489 -418.439452) (xy 388.978735 -418.493389)
			(xy 388.963382 -418.545678) (xy 388.940744 -418.595249) (xy 388.911283 -418.641095) (xy 388.875596 -418.682281)
			(xy 388.834412 -418.717969) (xy 388.788569 -418.747434) (xy 388.738998 -418.770074) (xy 388.686711 -418.78543)
			(xy 388.63277 -418.793188) (xy 388.605522 -418.793676) (xy 387.741922 -418.793676) (xy 387.714666 -418.793279)
			(xy 387.660708 -418.785523) (xy 387.608403 -418.770168) (xy 387.558816 -418.747525) (xy 387.512956 -418.718055)
			(xy 387.471757 -418.682358) (xy 387.436058 -418.641162) (xy 387.406586 -418.595303) (xy 387.38394 -418.545718)
			(xy 387.368581 -418.493414) (xy 387.360823 -418.439456) (xy 385.923312 -418.439456) (xy 385.915556 -418.493399)
			(xy 385.9002 -418.545694) (xy 385.877558 -418.595271) (xy 385.848091 -418.641122) (xy 385.812399 -418.682311)
			(xy 385.771207 -418.718002) (xy 385.725356 -418.747467) (xy 385.675777 -418.770107) (xy 385.623482 -418.78546)
			(xy 385.569533 -418.793214) (xy 385.542282 -418.793676) (xy 384.678682 -418.793676) (xy 384.651429 -418.793253)
			(xy 384.597479 -418.785494) (xy 384.545182 -418.770136) (xy 384.495603 -418.747492) (xy 384.449751 -418.718022)
			(xy 384.408559 -418.682328) (xy 384.372867 -418.641135) (xy 384.3434 -418.595281) (xy 384.320758 -418.545701)
			(xy 384.305403 -418.493403) (xy 384.297646 -418.439453) (xy 382.859989 -418.439453) (xy 382.852235 -418.493386)
			(xy 382.836883 -418.545673) (xy 382.814247 -418.595244) (xy 382.784787 -418.641088) (xy 382.749103 -418.682274)
			(xy 382.707922 -418.717962) (xy 382.662081 -418.747427) (xy 382.612513 -418.770069) (xy 382.560228 -418.785426)
			(xy 382.506289 -418.793187) (xy 382.479042 -418.793676) (xy 381.615442 -418.793676) (xy 381.588185 -418.79328)
			(xy 381.534225 -418.785527) (xy 381.481917 -418.770173) (xy 381.432328 -418.747531) (xy 381.386466 -418.718062)
			(xy 381.345264 -418.682365) (xy 381.309563 -418.641168) (xy 381.280089 -418.595309) (xy 381.257441 -418.545722)
			(xy 381.242082 -418.493416) (xy 381.234323 -418.439457) (xy 379.796789 -418.439457) (xy 379.789034 -418.493392)
			(xy 379.77368 -418.545682) (xy 379.751041 -418.595255) (xy 379.721578 -418.641101) (xy 379.685889 -418.682288)
			(xy 379.644703 -418.717976) (xy 379.598857 -418.74744) (xy 379.549284 -418.77008) (xy 379.496994 -418.785434)
			(xy 379.443051 -418.79319) (xy 379.415802 -418.793676) (xy 378.552202 -418.793676) (xy 378.524947 -418.793277)
			(xy 378.470991 -418.78552) (xy 378.418688 -418.770163) (xy 378.369104 -418.747518) (xy 378.323247 -418.718048)
			(xy 378.28205 -418.682351) (xy 378.246353 -418.641155) (xy 378.216883 -418.595298) (xy 378.194238 -418.545713)
			(xy 378.178881 -418.493411) (xy 378.171123 -418.439455) (xy 376.733613 -418.439455) (xy 376.725855 -418.493402)
			(xy 376.710499 -418.545699) (xy 376.687855 -418.595277) (xy 376.658386 -418.641128) (xy 376.622691 -418.682318)
			(xy 376.581498 -418.718009) (xy 376.535644 -418.747474) (xy 376.486063 -418.770112) (xy 376.433765 -418.785463)
			(xy 376.379814 -418.793215) (xy 376.352562 -418.793676) (xy 375.488962 -418.793676) (xy 375.46171 -418.793252)
			(xy 375.407762 -418.78549) (xy 375.355468 -418.77013) (xy 375.305891 -418.747485) (xy 375.260041 -418.718015)
			(xy 375.218852 -418.682321) (xy 375.183162 -418.641128) (xy 375.153697 -418.595276) (xy 375.131056 -418.545697)
			(xy 375.115702 -418.493401) (xy 375.107946 -418.439452) (xy 373.670289 -418.439452) (xy 373.662535 -418.493389)
			(xy 373.647182 -418.545678) (xy 373.624544 -418.595249) (xy 373.595083 -418.641095) (xy 373.559396 -418.682281)
			(xy 373.518212 -418.717969) (xy 373.472369 -418.747434) (xy 373.422798 -418.770074) (xy 373.370511 -418.78543)
			(xy 373.31657 -418.793188) (xy 373.289322 -418.793676) (xy 372.425722 -418.793676) (xy 372.398466 -418.793279)
			(xy 372.344508 -418.785523) (xy 372.292203 -418.770168) (xy 372.242616 -418.747525) (xy 372.196756 -418.718055)
			(xy 372.155557 -418.682358) (xy 372.119858 -418.641162) (xy 372.090386 -418.595303) (xy 372.06774 -418.545718)
			(xy 372.052381 -418.493414) (xy 372.044623 -418.439456) (xy 370.313204 -418.439456) (xy 370.313204 -420.739316)
			(xy 370.16182 -420.739316) (xy 370.150196 -420.741249) (xy 370.130459 -420.754067) (xy 370.118529 -420.774354)
			(xy 370.117116 -420.786052) (xy 370.117116 -420.979455) (xy 370.513023 -420.979455) (xy 370.513023 -420.924945)
			(xy 370.520781 -420.870989) (xy 370.536138 -420.818687) (xy 370.558783 -420.769102) (xy 370.588253 -420.723245)
			(xy 370.62395 -420.682049) (xy 370.665147 -420.646352) (xy 370.711004 -420.616882) (xy 370.760588 -420.594237)
			(xy 370.812891 -420.57888) (xy 370.866847 -420.571123) (xy 370.894102 -420.57066) (xy 371.757702 -420.57066)
			(xy 371.784951 -420.57121) (xy 371.838894 -420.578966) (xy 371.891184 -420.59432) (xy 371.940757 -420.61696)
			(xy 371.986603 -420.646424) (xy 372.027789 -420.682112) (xy 372.063478 -420.723299) (xy 372.092941 -420.769145)
			(xy 372.11558 -420.818718) (xy 372.130934 -420.871008) (xy 372.13869 -420.924951) (xy 372.13869 -420.979449)
			(xy 372.138689 -420.979457) (xy 373.576223 -420.979457) (xy 373.576223 -420.924943) (xy 373.583982 -420.870984)
			(xy 373.599341 -420.818678) (xy 373.621989 -420.769091) (xy 373.651463 -420.723232) (xy 373.687164 -420.682035)
			(xy 373.728366 -420.646338) (xy 373.774228 -420.616869) (xy 373.823817 -420.594227) (xy 373.876125 -420.578873)
			(xy 373.930085 -420.57112) (xy 373.957342 -420.57066) (xy 374.820942 -420.57066) (xy 374.848189 -420.571213)
			(xy 374.902128 -420.578974) (xy 374.954413 -420.594331) (xy 375.003981 -420.616973) (xy 375.049822 -420.646438)
			(xy 375.091003 -420.682126) (xy 375.126687 -420.723312) (xy 375.156147 -420.769156) (xy 375.178783 -420.818727)
			(xy 375.194135 -420.871014) (xy 375.20189 -420.924953) (xy 375.20189 -420.979447) (xy 375.201889 -420.979453)
			(xy 376.639546 -420.979453) (xy 376.639546 -420.924947) (xy 376.647303 -420.870997) (xy 376.662658 -420.818699)
			(xy 376.6853 -420.769119) (xy 376.714767 -420.723265) (xy 376.750459 -420.682072) (xy 376.791651 -420.646378)
			(xy 376.837503 -420.616908) (xy 376.887082 -420.594264) (xy 376.939379 -420.578906) (xy 376.993329 -420.571147)
			(xy 377.020582 -420.57066) (xy 377.884182 -420.57066) (xy 377.911433 -420.571186) (xy 377.965382 -420.57894)
			(xy 378.017677 -420.594293) (xy 378.067256 -420.616933) (xy 378.113107 -420.646398) (xy 378.154299 -420.682089)
			(xy 378.189991 -420.723278) (xy 378.219458 -420.769129) (xy 378.2421 -420.818706) (xy 378.257456 -420.871001)
			(xy 378.265213 -420.924949) (xy 378.265213 -420.979451) (xy 378.265212 -420.979456) (xy 379.702723 -420.979456)
			(xy 379.702723 -420.924944) (xy 379.710481 -420.870986) (xy 379.72584 -420.818682) (xy 379.748486 -420.769097)
			(xy 379.777958 -420.723238) (xy 379.813657 -420.682042) (xy 379.854856 -420.646345) (xy 379.900716 -420.616875)
			(xy 379.950303 -420.594232) (xy 380.002608 -420.578877) (xy 380.056566 -420.571121) (xy 380.083822 -420.57066)
			(xy 380.947422 -420.57066) (xy 380.97467 -420.571212) (xy 381.028611 -420.57897) (xy 381.080898 -420.594326)
			(xy 381.130469 -420.616966) (xy 381.176312 -420.646431) (xy 381.217496 -420.682119) (xy 381.253183 -420.723305)
			(xy 381.282644 -420.769151) (xy 381.305282 -420.818722) (xy 381.320635 -420.871011) (xy 381.32839 -420.924952)
			(xy 381.32839 -420.979448) (xy 381.328389 -420.979452) (xy 382.766046 -420.979452) (xy 382.766046 -420.924948)
			(xy 382.773802 -420.870999) (xy 382.789156 -420.818703) (xy 382.811797 -420.769124) (xy 382.841262 -420.723272)
			(xy 382.876952 -420.682079) (xy 382.918141 -420.646385) (xy 382.963991 -420.616915) (xy 383.013568 -420.59427)
			(xy 383.065862 -420.57891) (xy 383.11981 -420.571148) (xy 383.147062 -420.57066) (xy 384.010662 -420.57066)
			(xy 384.037914 -420.571185) (xy 384.091865 -420.578937) (xy 384.144163 -420.594288) (xy 384.193744 -420.616926)
			(xy 384.239598 -420.646391) (xy 384.280791 -420.682082) (xy 384.316486 -420.723272) (xy 384.345955 -420.769123)
			(xy 384.368599 -420.818701) (xy 384.383955 -420.870998) (xy 384.391713 -420.924948) (xy 384.391713 -420.979452)
			(xy 384.391713 -420.979455) (xy 385.829223 -420.979455) (xy 385.829223 -420.924945) (xy 385.836981 -420.870989)
			(xy 385.852338 -420.818687) (xy 385.874983 -420.769102) (xy 385.904453 -420.723245) (xy 385.94015 -420.682049)
			(xy 385.981347 -420.646352) (xy 386.027204 -420.616882) (xy 386.076788 -420.594237) (xy 386.129091 -420.57888)
			(xy 386.183047 -420.571123) (xy 386.210302 -420.57066) (xy 387.073902 -420.57066) (xy 387.101151 -420.57121)
			(xy 387.155094 -420.578966) (xy 387.207384 -420.59432) (xy 387.256957 -420.61696) (xy 387.302803 -420.646424)
			(xy 387.343989 -420.682112) (xy 387.379678 -420.723299) (xy 387.409141 -420.769145) (xy 387.43178 -420.818718)
			(xy 387.447134 -420.871008) (xy 387.45489 -420.924951) (xy 387.45489 -420.979449) (xy 387.454889 -420.979457)
			(xy 388.892423 -420.979457) (xy 388.892423 -420.924943) (xy 388.900182 -420.870984) (xy 388.915541 -420.818678)
			(xy 388.938189 -420.769091) (xy 388.967663 -420.723232) (xy 389.003364 -420.682035) (xy 389.044566 -420.646338)
			(xy 389.090428 -420.616869) (xy 389.140017 -420.594227) (xy 389.192325 -420.578873) (xy 389.246285 -420.57112)
			(xy 389.273542 -420.57066) (xy 390.137142 -420.57066) (xy 390.164389 -420.571213) (xy 390.218328 -420.578974)
			(xy 390.270613 -420.594331) (xy 390.320181 -420.616973) (xy 390.366022 -420.646438) (xy 390.407203 -420.682126)
			(xy 390.442887 -420.723312) (xy 390.472347 -420.769156) (xy 390.494983 -420.818727) (xy 390.510335 -420.871014)
			(xy 390.51809 -420.924953) (xy 390.51809 -420.979447) (xy 390.518089 -420.979453) (xy 391.955746 -420.979453)
			(xy 391.955746 -420.924947) (xy 391.963503 -420.870997) (xy 391.978858 -420.818699) (xy 392.0015 -420.769119)
			(xy 392.030967 -420.723265) (xy 392.066659 -420.682072) (xy 392.107851 -420.646378) (xy 392.153703 -420.616908)
			(xy 392.203282 -420.594264) (xy 392.255579 -420.578906) (xy 392.309529 -420.571147) (xy 392.336782 -420.57066)
			(xy 393.200382 -420.57066) (xy 393.227633 -420.571186) (xy 393.281582 -420.57894) (xy 393.333877 -420.594293)
			(xy 393.383456 -420.616933) (xy 393.429307 -420.646398) (xy 393.470499 -420.682089) (xy 393.506191 -420.723278)
			(xy 393.535658 -420.769129) (xy 393.5583 -420.818706) (xy 393.573656 -420.871001) (xy 393.581413 -420.924949)
			(xy 393.581413 -420.979451) (xy 393.581412 -420.979456) (xy 395.018923 -420.979456) (xy 395.018923 -420.924944)
			(xy 395.026681 -420.870986) (xy 395.04204 -420.818682) (xy 395.064686 -420.769097) (xy 395.094158 -420.723238)
			(xy 395.129857 -420.682042) (xy 395.171056 -420.646345) (xy 395.216916 -420.616875) (xy 395.266503 -420.594232)
			(xy 395.318808 -420.578877) (xy 395.372766 -420.571121) (xy 395.400022 -420.57066) (xy 396.263622 -420.57066)
			(xy 396.29087 -420.571212) (xy 396.344811 -420.57897) (xy 396.397098 -420.594326) (xy 396.446669 -420.616966)
			(xy 396.492512 -420.646431) (xy 396.533696 -420.682119) (xy 396.569383 -420.723305) (xy 396.598844 -420.769151)
			(xy 396.621482 -420.818722) (xy 396.636835 -420.871011) (xy 396.64459 -420.924952) (xy 396.64459 -420.979448)
			(xy 396.644589 -420.979452) (xy 398.082246 -420.979452) (xy 398.082246 -420.924948) (xy 398.090002 -420.870999)
			(xy 398.105356 -420.818703) (xy 398.127997 -420.769124) (xy 398.157462 -420.723272) (xy 398.193152 -420.682079)
			(xy 398.234341 -420.646385) (xy 398.280191 -420.616915) (xy 398.329768 -420.59427) (xy 398.382062 -420.57891)
			(xy 398.43601 -420.571148) (xy 398.463262 -420.57066) (xy 399.326862 -420.57066) (xy 399.354114 -420.571185)
			(xy 399.408065 -420.578937) (xy 399.460363 -420.594288) (xy 399.509944 -420.616926) (xy 399.555798 -420.646391)
			(xy 399.596991 -420.682082) (xy 399.632686 -420.723272) (xy 399.662155 -420.769123) (xy 399.684799 -420.818701)
			(xy 399.700155 -420.870998) (xy 399.707913 -420.924948) (xy 399.707913 -420.979452) (xy 399.707913 -420.979455)
			(xy 401.145423 -420.979455) (xy 401.145423 -420.924945) (xy 401.153181 -420.870989) (xy 401.168538 -420.818687)
			(xy 401.191183 -420.769102) (xy 401.220653 -420.723245) (xy 401.25635 -420.682049) (xy 401.297547 -420.646352)
			(xy 401.343404 -420.616882) (xy 401.392988 -420.594237) (xy 401.445291 -420.57888) (xy 401.499247 -420.571123)
			(xy 401.526502 -420.57066) (xy 402.390102 -420.57066) (xy 402.417351 -420.57121) (xy 402.471294 -420.578966)
			(xy 402.523584 -420.59432) (xy 402.573157 -420.61696) (xy 402.619003 -420.646424) (xy 402.660189 -420.682112)
			(xy 402.695878 -420.723299) (xy 402.725341 -420.769145) (xy 402.74798 -420.818718) (xy 402.763334 -420.871008)
			(xy 402.77109 -420.924951) (xy 402.77109 -420.979449) (xy 402.771089 -420.979457) (xy 404.208623 -420.979457)
			(xy 404.208623 -420.924943) (xy 404.216382 -420.870984) (xy 404.231741 -420.818678) (xy 404.254389 -420.769091)
			(xy 404.283863 -420.723232) (xy 404.319564 -420.682035) (xy 404.360766 -420.646338) (xy 404.406628 -420.616869)
			(xy 404.456217 -420.594227) (xy 404.508525 -420.578873) (xy 404.562485 -420.57112) (xy 404.589742 -420.57066)
			(xy 405.453342 -420.57066) (xy 405.480589 -420.571213) (xy 405.534528 -420.578974) (xy 405.586813 -420.594331)
			(xy 405.636381 -420.616973) (xy 405.682222 -420.646438) (xy 405.723403 -420.682126) (xy 405.759087 -420.723312)
			(xy 405.788547 -420.769156) (xy 405.811183 -420.818727) (xy 405.826535 -420.871014) (xy 405.83429 -420.924953)
			(xy 405.83429 -420.979447) (xy 405.834289 -420.979453) (xy 407.271946 -420.979453) (xy 407.271946 -420.924947)
			(xy 407.279703 -420.870997) (xy 407.295058 -420.818699) (xy 407.3177 -420.769119) (xy 407.347167 -420.723265)
			(xy 407.382859 -420.682072) (xy 407.424051 -420.646378) (xy 407.469903 -420.616908) (xy 407.519482 -420.594264)
			(xy 407.571779 -420.578906) (xy 407.625729 -420.571147) (xy 407.652982 -420.57066) (xy 408.516582 -420.57066)
			(xy 408.543833 -420.571186) (xy 408.597782 -420.57894) (xy 408.650077 -420.594293) (xy 408.699656 -420.616933)
			(xy 408.745507 -420.646398) (xy 408.786699 -420.682089) (xy 408.822391 -420.723278) (xy 408.851858 -420.769129)
			(xy 408.8745 -420.818706) (xy 408.889856 -420.871001) (xy 408.897613 -420.924949) (xy 408.897613 -420.979451)
			(xy 408.897612 -420.979456) (xy 410.335123 -420.979456) (xy 410.335123 -420.924944) (xy 410.342881 -420.870986)
			(xy 410.35824 -420.818682) (xy 410.380886 -420.769097) (xy 410.410358 -420.723238) (xy 410.446057 -420.682042)
			(xy 410.487256 -420.646345) (xy 410.533116 -420.616875) (xy 410.582703 -420.594232) (xy 410.635008 -420.578877)
			(xy 410.688966 -420.571121) (xy 410.716222 -420.57066) (xy 411.579822 -420.57066) (xy 411.60707 -420.571212)
			(xy 411.661011 -420.57897) (xy 411.713298 -420.594326) (xy 411.762869 -420.616966) (xy 411.808712 -420.646431)
			(xy 411.849896 -420.682119) (xy 411.885583 -420.723305) (xy 411.915044 -420.769151) (xy 411.937682 -420.818722)
			(xy 411.953035 -420.871011) (xy 411.96079 -420.924952) (xy 411.96079 -420.979448) (xy 411.960789 -420.979452)
			(xy 413.398446 -420.979452) (xy 413.398446 -420.924948) (xy 413.406202 -420.870999) (xy 413.421556 -420.818703)
			(xy 413.444197 -420.769124) (xy 413.473662 -420.723272) (xy 413.509352 -420.682079) (xy 413.550541 -420.646385)
			(xy 413.596391 -420.616915) (xy 413.645968 -420.59427) (xy 413.698262 -420.57891) (xy 413.75221 -420.571148)
			(xy 413.779462 -420.57066) (xy 414.643062 -420.57066) (xy 414.670314 -420.571185) (xy 414.724265 -420.578937)
			(xy 414.776563 -420.594288) (xy 414.826144 -420.616926) (xy 414.871998 -420.646391) (xy 414.913191 -420.682082)
			(xy 414.948886 -420.723272) (xy 414.978355 -420.769123) (xy 415.000999 -420.818701) (xy 415.016355 -420.870998)
			(xy 415.024113 -420.924948) (xy 415.024113 -420.979452) (xy 415.024113 -420.979455) (xy 416.461623 -420.979455)
			(xy 416.461623 -420.924945) (xy 416.469381 -420.870989) (xy 416.484738 -420.818687) (xy 416.507383 -420.769102)
			(xy 416.536853 -420.723245) (xy 416.57255 -420.682049) (xy 416.613747 -420.646352) (xy 416.659604 -420.616882)
			(xy 416.709188 -420.594237) (xy 416.761491 -420.57888) (xy 416.815447 -420.571123) (xy 416.842702 -420.57066)
			(xy 417.706302 -420.57066) (xy 417.733551 -420.57121) (xy 417.787494 -420.578966) (xy 417.839784 -420.59432)
			(xy 417.889357 -420.61696) (xy 417.935203 -420.646424) (xy 417.976389 -420.682112) (xy 418.012078 -420.723299)
			(xy 418.041541 -420.769145) (xy 418.06418 -420.818718) (xy 418.079534 -420.871008) (xy 418.08729 -420.924951)
			(xy 418.08729 -420.979449) (xy 418.079534 -421.033392) (xy 418.06418 -421.085682) (xy 418.041541 -421.135255)
			(xy 418.012078 -421.181101) (xy 417.976389 -421.222288) (xy 417.935203 -421.257976) (xy 417.889357 -421.28744)
			(xy 417.839784 -421.31008) (xy 417.787494 -421.325434) (xy 417.733551 -421.33319) (xy 417.706302 -421.333676)
			(xy 416.842702 -421.333676) (xy 416.815447 -421.333277) (xy 416.761491 -421.32552) (xy 416.709188 -421.310163)
			(xy 416.659604 -421.287518) (xy 416.613747 -421.258048) (xy 416.57255 -421.222351) (xy 416.536853 -421.181155)
			(xy 416.507383 -421.135298) (xy 416.484738 -421.085713) (xy 416.469381 -421.033411) (xy 416.461623 -420.979455)
			(xy 415.024113 -420.979455) (xy 415.016355 -421.033402) (xy 415.000999 -421.085699) (xy 414.978355 -421.135277)
			(xy 414.948886 -421.181128) (xy 414.913191 -421.222318) (xy 414.871998 -421.258009) (xy 414.826144 -421.287474)
			(xy 414.776563 -421.310112) (xy 414.724265 -421.325463) (xy 414.670314 -421.333215) (xy 414.643062 -421.333676)
			(xy 413.779462 -421.333676) (xy 413.75221 -421.333252) (xy 413.698262 -421.32549) (xy 413.645968 -421.31013)
			(xy 413.596391 -421.287485) (xy 413.550541 -421.258015) (xy 413.509352 -421.222321) (xy 413.473662 -421.181128)
			(xy 413.444197 -421.135276) (xy 413.421556 -421.085697) (xy 413.406202 -421.033401) (xy 413.398446 -420.979452)
			(xy 411.960789 -420.979452) (xy 411.953035 -421.033389) (xy 411.937682 -421.085678) (xy 411.915044 -421.135249)
			(xy 411.885583 -421.181095) (xy 411.849896 -421.222281) (xy 411.808712 -421.257969) (xy 411.762869 -421.287434)
			(xy 411.713298 -421.310074) (xy 411.661011 -421.32543) (xy 411.60707 -421.333188) (xy 411.579822 -421.333676)
			(xy 410.716222 -421.333676) (xy 410.688966 -421.333279) (xy 410.635008 -421.325523) (xy 410.582703 -421.310168)
			(xy 410.533116 -421.287525) (xy 410.487256 -421.258055) (xy 410.446057 -421.222358) (xy 410.410358 -421.181162)
			(xy 410.380886 -421.135303) (xy 410.35824 -421.085718) (xy 410.342881 -421.033414) (xy 410.335123 -420.979456)
			(xy 408.897612 -420.979456) (xy 408.889856 -421.033399) (xy 408.8745 -421.085694) (xy 408.851858 -421.135271)
			(xy 408.822391 -421.181122) (xy 408.786699 -421.222311) (xy 408.745507 -421.258002) (xy 408.699656 -421.287467)
			(xy 408.650077 -421.310107) (xy 408.597782 -421.32546) (xy 408.543833 -421.333214) (xy 408.516582 -421.333676)
			(xy 407.652982 -421.333676) (xy 407.625729 -421.333253) (xy 407.571779 -421.325494) (xy 407.519482 -421.310136)
			(xy 407.469903 -421.287492) (xy 407.424051 -421.258022) (xy 407.382859 -421.222328) (xy 407.347167 -421.181135)
			(xy 407.3177 -421.135281) (xy 407.295058 -421.085701) (xy 407.279703 -421.033403) (xy 407.271946 -420.979453)
			(xy 405.834289 -420.979453) (xy 405.826535 -421.033386) (xy 405.811183 -421.085673) (xy 405.788547 -421.135244)
			(xy 405.759087 -421.181088) (xy 405.723403 -421.222274) (xy 405.682222 -421.257962) (xy 405.636381 -421.287427)
			(xy 405.586813 -421.310069) (xy 405.534528 -421.325426) (xy 405.480589 -421.333187) (xy 405.453342 -421.333676)
			(xy 404.589742 -421.333676) (xy 404.562485 -421.33328) (xy 404.508525 -421.325527) (xy 404.456217 -421.310173)
			(xy 404.406628 -421.287531) (xy 404.360766 -421.258062) (xy 404.319564 -421.222365) (xy 404.283863 -421.181168)
			(xy 404.254389 -421.135309) (xy 404.231741 -421.085722) (xy 404.216382 -421.033416) (xy 404.208623 -420.979457)
			(xy 402.771089 -420.979457) (xy 402.763334 -421.033392) (xy 402.74798 -421.085682) (xy 402.725341 -421.135255)
			(xy 402.695878 -421.181101) (xy 402.660189 -421.222288) (xy 402.619003 -421.257976) (xy 402.573157 -421.28744)
			(xy 402.523584 -421.31008) (xy 402.471294 -421.325434) (xy 402.417351 -421.33319) (xy 402.390102 -421.333676)
			(xy 401.526502 -421.333676) (xy 401.499247 -421.333277) (xy 401.445291 -421.32552) (xy 401.392988 -421.310163)
			(xy 401.343404 -421.287518) (xy 401.297547 -421.258048) (xy 401.25635 -421.222351) (xy 401.220653 -421.181155)
			(xy 401.191183 -421.135298) (xy 401.168538 -421.085713) (xy 401.153181 -421.033411) (xy 401.145423 -420.979455)
			(xy 399.707913 -420.979455) (xy 399.700155 -421.033402) (xy 399.684799 -421.085699) (xy 399.662155 -421.135277)
			(xy 399.632686 -421.181128) (xy 399.596991 -421.222318) (xy 399.555798 -421.258009) (xy 399.509944 -421.287474)
			(xy 399.460363 -421.310112) (xy 399.408065 -421.325463) (xy 399.354114 -421.333215) (xy 399.326862 -421.333676)
			(xy 398.463262 -421.333676) (xy 398.43601 -421.333252) (xy 398.382062 -421.32549) (xy 398.329768 -421.31013)
			(xy 398.280191 -421.287485) (xy 398.234341 -421.258015) (xy 398.193152 -421.222321) (xy 398.157462 -421.181128)
			(xy 398.127997 -421.135276) (xy 398.105356 -421.085697) (xy 398.090002 -421.033401) (xy 398.082246 -420.979452)
			(xy 396.644589 -420.979452) (xy 396.636835 -421.033389) (xy 396.621482 -421.085678) (xy 396.598844 -421.135249)
			(xy 396.569383 -421.181095) (xy 396.533696 -421.222281) (xy 396.492512 -421.257969) (xy 396.446669 -421.287434)
			(xy 396.397098 -421.310074) (xy 396.344811 -421.32543) (xy 396.29087 -421.333188) (xy 396.263622 -421.333676)
			(xy 395.400022 -421.333676) (xy 395.372766 -421.333279) (xy 395.318808 -421.325523) (xy 395.266503 -421.310168)
			(xy 395.216916 -421.287525) (xy 395.171056 -421.258055) (xy 395.129857 -421.222358) (xy 395.094158 -421.181162)
			(xy 395.064686 -421.135303) (xy 395.04204 -421.085718) (xy 395.026681 -421.033414) (xy 395.018923 -420.979456)
			(xy 393.581412 -420.979456) (xy 393.573656 -421.033399) (xy 393.5583 -421.085694) (xy 393.535658 -421.135271)
			(xy 393.506191 -421.181122) (xy 393.470499 -421.222311) (xy 393.429307 -421.258002) (xy 393.383456 -421.287467)
			(xy 393.333877 -421.310107) (xy 393.281582 -421.32546) (xy 393.227633 -421.333214) (xy 393.200382 -421.333676)
			(xy 392.336782 -421.333676) (xy 392.309529 -421.333253) (xy 392.255579 -421.325494) (xy 392.203282 -421.310136)
			(xy 392.153703 -421.287492) (xy 392.107851 -421.258022) (xy 392.066659 -421.222328) (xy 392.030967 -421.181135)
			(xy 392.0015 -421.135281) (xy 391.978858 -421.085701) (xy 391.963503 -421.033403) (xy 391.955746 -420.979453)
			(xy 390.518089 -420.979453) (xy 390.510335 -421.033386) (xy 390.494983 -421.085673) (xy 390.472347 -421.135244)
			(xy 390.442887 -421.181088) (xy 390.407203 -421.222274) (xy 390.366022 -421.257962) (xy 390.320181 -421.287427)
			(xy 390.270613 -421.310069) (xy 390.218328 -421.325426) (xy 390.164389 -421.333187) (xy 390.137142 -421.333676)
			(xy 389.273542 -421.333676) (xy 389.246285 -421.33328) (xy 389.192325 -421.325527) (xy 389.140017 -421.310173)
			(xy 389.090428 -421.287531) (xy 389.044566 -421.258062) (xy 389.003364 -421.222365) (xy 388.967663 -421.181168)
			(xy 388.938189 -421.135309) (xy 388.915541 -421.085722) (xy 388.900182 -421.033416) (xy 388.892423 -420.979457)
			(xy 387.454889 -420.979457) (xy 387.447134 -421.033392) (xy 387.43178 -421.085682) (xy 387.409141 -421.135255)
			(xy 387.379678 -421.181101) (xy 387.343989 -421.222288) (xy 387.302803 -421.257976) (xy 387.256957 -421.28744)
			(xy 387.207384 -421.31008) (xy 387.155094 -421.325434) (xy 387.101151 -421.33319) (xy 387.073902 -421.333676)
			(xy 386.210302 -421.333676) (xy 386.183047 -421.333277) (xy 386.129091 -421.32552) (xy 386.076788 -421.310163)
			(xy 386.027204 -421.287518) (xy 385.981347 -421.258048) (xy 385.94015 -421.222351) (xy 385.904453 -421.181155)
			(xy 385.874983 -421.135298) (xy 385.852338 -421.085713) (xy 385.836981 -421.033411) (xy 385.829223 -420.979455)
			(xy 384.391713 -420.979455) (xy 384.383955 -421.033402) (xy 384.368599 -421.085699) (xy 384.345955 -421.135277)
			(xy 384.316486 -421.181128) (xy 384.280791 -421.222318) (xy 384.239598 -421.258009) (xy 384.193744 -421.287474)
			(xy 384.144163 -421.310112) (xy 384.091865 -421.325463) (xy 384.037914 -421.333215) (xy 384.010662 -421.333676)
			(xy 383.147062 -421.333676) (xy 383.11981 -421.333252) (xy 383.065862 -421.32549) (xy 383.013568 -421.31013)
			(xy 382.963991 -421.287485) (xy 382.918141 -421.258015) (xy 382.876952 -421.222321) (xy 382.841262 -421.181128)
			(xy 382.811797 -421.135276) (xy 382.789156 -421.085697) (xy 382.773802 -421.033401) (xy 382.766046 -420.979452)
			(xy 381.328389 -420.979452) (xy 381.320635 -421.033389) (xy 381.305282 -421.085678) (xy 381.282644 -421.135249)
			(xy 381.253183 -421.181095) (xy 381.217496 -421.222281) (xy 381.176312 -421.257969) (xy 381.130469 -421.287434)
			(xy 381.080898 -421.310074) (xy 381.028611 -421.32543) (xy 380.97467 -421.333188) (xy 380.947422 -421.333676)
			(xy 380.083822 -421.333676) (xy 380.056566 -421.333279) (xy 380.002608 -421.325523) (xy 379.950303 -421.310168)
			(xy 379.900716 -421.287525) (xy 379.854856 -421.258055) (xy 379.813657 -421.222358) (xy 379.777958 -421.181162)
			(xy 379.748486 -421.135303) (xy 379.72584 -421.085718) (xy 379.710481 -421.033414) (xy 379.702723 -420.979456)
			(xy 378.265212 -420.979456) (xy 378.257456 -421.033399) (xy 378.2421 -421.085694) (xy 378.219458 -421.135271)
			(xy 378.189991 -421.181122) (xy 378.154299 -421.222311) (xy 378.113107 -421.258002) (xy 378.067256 -421.287467)
			(xy 378.017677 -421.310107) (xy 377.965382 -421.32546) (xy 377.911433 -421.333214) (xy 377.884182 -421.333676)
			(xy 377.020582 -421.333676) (xy 376.993329 -421.333253) (xy 376.939379 -421.325494) (xy 376.887082 -421.310136)
			(xy 376.837503 -421.287492) (xy 376.791651 -421.258022) (xy 376.750459 -421.222328) (xy 376.714767 -421.181135)
			(xy 376.6853 -421.135281) (xy 376.662658 -421.085701) (xy 376.647303 -421.033403) (xy 376.639546 -420.979453)
			(xy 375.201889 -420.979453) (xy 375.194135 -421.033386) (xy 375.178783 -421.085673) (xy 375.156147 -421.135244)
			(xy 375.126687 -421.181088) (xy 375.091003 -421.222274) (xy 375.049822 -421.257962) (xy 375.003981 -421.287427)
			(xy 374.954413 -421.310069) (xy 374.902128 -421.325426) (xy 374.848189 -421.333187) (xy 374.820942 -421.333676)
			(xy 373.957342 -421.333676) (xy 373.930085 -421.33328) (xy 373.876125 -421.325527) (xy 373.823817 -421.310173)
			(xy 373.774228 -421.287531) (xy 373.728366 -421.258062) (xy 373.687164 -421.222365) (xy 373.651463 -421.181168)
			(xy 373.621989 -421.135309) (xy 373.599341 -421.085722) (xy 373.583982 -421.033416) (xy 373.576223 -420.979457)
			(xy 372.138689 -420.979457) (xy 372.130934 -421.033392) (xy 372.11558 -421.085682) (xy 372.092941 -421.135255)
			(xy 372.063478 -421.181101) (xy 372.027789 -421.222288) (xy 371.986603 -421.257976) (xy 371.940757 -421.28744)
			(xy 371.891184 -421.31008) (xy 371.838894 -421.325434) (xy 371.784951 -421.33319) (xy 371.757702 -421.333676)
			(xy 370.894102 -421.333676) (xy 370.866847 -421.333277) (xy 370.812891 -421.32552) (xy 370.760588 -421.310163)
			(xy 370.711004 -421.287518) (xy 370.665147 -421.258048) (xy 370.62395 -421.222351) (xy 370.588253 -421.181155)
			(xy 370.558783 -421.135298) (xy 370.536138 -421.085713) (xy 370.520781 -421.033411) (xy 370.513023 -420.979455)
			(xy 370.117116 -420.979455) (xy 370.117116 -421.132508) (xy 370.118615 -421.144169) (xy 370.130586 -421.164375)
			(xy 370.150236 -421.177236) (xy 370.16182 -421.179244) (xy 370.313204 -421.179244) (xy 370.313204 -421.823388)
			(xy 370.314668 -421.83251) (xy 370.323191 -421.848883) (xy 370.336996 -421.861137) (xy 370.354265 -421.867657)
			(xy 370.363496 -421.868092) (xy 435.278784 -421.868092) (xy 435.288847 -421.867653) (xy 435.307429 -421.859917)
			(xy 435.314852 -421.853106) (xy 446.82664 -410.341318) (xy 446.828418 -410.339286) (xy 446.853056 -410.314648)
			(xy 446.855088 -410.31287) (xy 448.826636 -408.341322) (xy 448.83332 -408.333912) (xy 448.840904 -408.315476)
			(xy 448.841368 -408.305508) (xy 448.831462 -408.275282) (xy 448.815029 -408.252144) (xy 448.788939 -408.201748)
			(xy 448.771173 -408.147852) (xy 448.76218 -408.09182) (xy 448.761612 -408.063446) (xy 448.762129 -408.035459)
			(xy 448.770879 -407.980173) (xy 448.788171 -407.926937) (xy 448.813579 -407.877062) (xy 448.846478 -407.831776)
			(xy 448.886056 -407.792195) (xy 448.931339 -407.759293) (xy 448.981213 -407.733881) (xy 449.034448 -407.716585)
			(xy 449.089733 -407.707831) (xy 449.11772 -407.707338) (xy 449.146095 -407.70789) (xy 449.202125 -407.716892)
			(xy 449.25602 -407.734666) (xy 449.306414 -407.76076) (xy 449.329556 -407.777188) (xy 449.359782 -407.787094)
			(xy 449.369743 -407.786605) (xy 449.388162 -407.779012) (xy 449.395596 -407.772362) (xy 464.51012 -392.657838)
			(xy 464.516965 -392.65044) (xy 464.52469 -392.631841) (xy 464.525106 -392.62177) (xy 464.525106 -381.559816)
			(xy 464.524668 -381.549752) (xy 464.516933 -381.531169) (xy 464.51012 -381.523748) (xy 464.294982 -381.30861)
			(xy 464.287583 -381.301765) (xy 464.268985 -381.294036) (xy 464.258914 -381.293624) (xy 436.215536 -381.293624)
			(xy 436.205001 -381.294145) (xy 436.185707 -381.302609) (xy 436.17145 -381.318121) (xy 436.16753 -381.327914)
			(xy 436.130954 -381.43434) (xy 436.140098 -381.465074) (xy 436.153052 -381.475234) (xy 436.226304 -381.533079)
			(xy 436.368323 -381.654229) (xy 436.504975 -381.781402) (xy 436.636003 -381.914362) (xy 436.761163 -382.052859)
			(xy 436.880222 -382.196635) (xy 436.992957 -382.345422) (xy 437.099157 -382.498942) (xy 437.198625 -382.656907)
			(xy 437.291173 -382.819022) (xy 437.376629 -382.984986) (xy 437.454835 -383.154487) (xy 437.525642 -383.327209)
			(xy 437.58892 -383.50283) (xy 437.64455 -383.681021) (xy 437.692428 -383.861449) (xy 437.732464 -384.043778)
			(xy 437.764585 -384.227666) (xy 437.788729 -384.412771) (xy 437.804852 -384.598746) (xy 437.812924 -384.785244)
			(xy 437.81345 -384.87858) (xy 437.812937 -384.972789) (xy 437.804719 -385.161026) (xy 437.788298 -385.348727)
			(xy 437.763706 -385.535532) (xy 437.730989 -385.721087) (xy 437.690209 -385.905038) (xy 437.641444 -386.087035)
			(xy 437.584787 -386.266732) (xy 437.520345 -386.443787) (xy 437.448242 -386.617862) (xy 437.368615 -386.788626)
			(xy 437.281615 -386.955755) (xy 437.187407 -387.11893) (xy 437.086172 -387.27784) (xy 436.978102 -387.432183)
			(xy 436.863402 -387.581665) (xy 436.742291 -387.726002) (xy 436.614999 -387.864918) (xy 436.481769 -387.998151)
			(xy 436.342854 -388.125444) (xy 436.198519 -388.246558) (xy 436.049039 -388.36126) (xy 435.894698 -388.469333)
			(xy 435.735789 -388.570571) (xy 435.572616 -388.664781) (xy 435.405489 -388.751784) (xy 435.234726 -388.831414)
			(xy 435.060652 -388.90352) (xy 434.883598 -388.967964) (xy 434.703902 -389.024624) (xy 434.521906 -389.073392)
			(xy 434.337955 -389.114175) (xy 434.152401 -389.146895) (xy 433.965596 -389.171491) (xy 433.777896 -389.187914)
			(xy 433.589659 -389.196135) (xy 433.49545 -389.19658) (xy 433.402878 -389.196089) (xy 433.217903 -389.188156)
			(xy 433.033438 -389.172302) (xy 432.849823 -389.148557) (xy 432.667394 -389.116963) (xy 432.486486 -389.07758)
			(xy 432.307433 -389.030479) (xy 432.130563 -388.975748) (xy 431.956201 -388.913486) (xy 431.784668 -388.843808)
			(xy 431.616279 -388.766843) (xy 431.451344 -388.682731) (xy 431.290165 -388.591627) (xy 431.133038 -388.493699)
			(xy 430.980254 -388.389126) (xy 430.832092 -388.278101) (xy 430.688824 -388.160828) (xy 430.550715 -388.037523)
			(xy 430.484026 -387.973316) (xy 430.47285 -387.962394) (xy 430.443132 -387.956806) (xy 430.342548 -387.999224)
			(xy 430.33358 -388.003534) (xy 430.319585 -388.017651) (xy 430.311993 -388.036022) (xy 430.31156 -388.04596)
			(xy 430.31156 -396.983712) (xy 430.310987 -397.008672) (xy 430.301245 -397.057631) (xy 430.282137 -397.103749)
			(xy 430.254399 -397.145252) (xy 430.237138 -397.16329) (xy 429.478948 -397.92148) (xy 429.460908 -397.938742)
			(xy 429.419416 -397.966505) (xy 429.373298 -397.985622) (xy 429.324332 -397.995355) (xy 429.29937 -397.995902)
			(xy 426.371766 -397.995902) (xy 426.346811 -397.995287) (xy 426.29786 -397.985544) (xy 426.251751 -397.966439)
			(xy 426.210254 -397.938706) (xy 426.192188 -397.92148) (xy 425.605702 -397.334994) (xy 425.59829 -397.32831)
			(xy 425.579857 -397.320713) (xy 425.559919 -397.320713) (xy 425.541486 -397.32831) (xy 425.534074 -397.334994)
			(xy 424.968162 -397.900906) (xy 424.950122 -397.918168) (xy 424.90863 -397.945931) (xy 424.862511 -397.965048)
			(xy 424.813546 -397.974783) (xy 424.788584 -397.975328) (xy 422.305988 -397.975328) (xy 422.28162 -397.974752)
			(xy 422.233786 -397.96542) (xy 422.210992 -397.956786) (xy 422.202102 -397.95323) (xy 422.184068 -397.952722)
			(xy 422.103042 -397.980662) (xy 422.089072 -397.992346) (xy 422.0845 -398.000474) (xy 422.072753 -398.020232)
			(xy 422.044255 -398.056298) (xy 422.010677 -398.087688) (xy 421.972775 -398.113694) (xy 421.931405 -398.133729)
			(xy 421.887501 -398.147341) (xy 421.842053 -398.154222) (xy 421.81907 -398.154652) (xy 421.795499 -398.154212)
			(xy 421.748918 -398.14696) (xy 421.704006 -398.132632) (xy 421.66183 -398.111571) (xy 421.623394 -398.084275)
			(xy 421.589611 -398.051395) (xy 421.561285 -398.013712) (xy 421.54983 -397.993108) (xy 421.549322 -397.992346)
			(xy 421.151558 -397.304006) (xy 421.13966 -397.281338) (xy 421.122784 -397.233007) (xy 421.114223 -397.182536)
			(xy 421.113712 -397.15694) (xy 421.113712 -397.156432) (xy 421.113796 -397.145087) (xy 421.115452 -397.122457)
			(xy 421.117014 -397.11122) (xy 421.118284 -397.10233) (xy 421.114728 -397.085058) (xy 421.071294 -397.013938)
			(xy 421.057324 -397.003016) (xy 421.048942 -396.999968) (xy 421.025093 -396.991429) (xy 420.980398 -396.967595)
			(xy 420.940248 -396.936712) (xy 420.905744 -396.899628) (xy 420.877833 -396.857359) (xy 420.857279 -396.811063)
			(xy 420.844646 -396.76201) (xy 420.841932 -396.736824) (xy 420.84117 -396.727172) (xy 420.832788 -396.710154)
			(xy 420.77513 -396.657322) (xy 420.76793 -396.651159) (xy 420.750309 -396.644219) (xy 420.74084 -396.64386)
			(xy 416.774376 -396.64386) (xy 416.753217 -396.643445) (xy 416.711483 -396.636446) (xy 416.671485 -396.622629)
			(xy 416.63433 -396.602376) (xy 416.601043 -396.576247) (xy 416.572546 -396.544963) (xy 416.549626 -396.509391)
			(xy 416.532917 -396.470512) (xy 416.527488 -396.450058) (xy 416.525202 -396.440152) (xy 416.514026 -396.424404)
			(xy 416.437064 -396.37589) (xy 416.418014 -396.372588) (xy 416.408108 -396.37462) (xy 416.392787 -396.377596)
			(xy 416.361738 -396.380782) (xy 416.346132 -396.38097) (xy 416.322138 -396.380526) (xy 416.274741 -396.373023)
			(xy 416.229102 -396.358197) (xy 416.186344 -396.336413) (xy 416.147521 -396.308207) (xy 416.113589 -396.274275)
			(xy 416.085384 -396.235451) (xy 416.063601 -396.192693) (xy 416.048775 -396.147053) (xy 416.041273 -396.099656)
			(xy 416.040824 -396.075662) (xy 416.041253 -396.052227) (xy 416.048416 -396.005906) (xy 416.062568 -395.961223)
			(xy 416.072574 -395.940026) (xy 416.07994 -395.925294) (xy 416.074606 -395.893036) (xy 415.368232 -395.186662)
			(xy 415.360833 -395.179819) (xy 415.342234 -395.1721) (xy 415.332164 -395.171676) (xy 415.032952 -395.171676)
			(xy 415.022885 -395.172107) (xy 415.004291 -395.179831) (xy 414.996884 -395.186662) (xy 414.239964 -395.943582)
			(xy 414.23336 -395.971014) (xy 414.237424 -395.984476) (xy 414.243932 -396.006709) (xy 414.25095 -396.0525)
			(xy 414.251394 -396.075662) (xy 414.250951 -396.099657) (xy 414.243449 -396.147056) (xy 414.228623 -396.192698)
			(xy 414.20684 -396.235458) (xy 414.178634 -396.274284) (xy 414.144702 -396.308219) (xy 414.105879 -396.336427)
			(xy 414.06312 -396.358214) (xy 414.017479 -396.373043) (xy 413.970081 -396.380549) (xy 413.946086 -396.38097)
			(xy 413.922923 -396.380541) (xy 413.877131 -396.373522) (xy 413.8549 -396.367) (xy 413.841438 -396.362936)
			(xy 413.814006 -396.36954) (xy 413.271716 -396.91183) (xy 413.265035 -396.91924) (xy 413.257461 -396.937677)
			(xy 413.256984 -396.947644) (xy 413.266636 -396.977362) (xy 413.273323 -396.986855) (xy 413.285399 -397.006689)
			(xy 413.290766 -397.016986) (xy 413.291274 -397.018002) (xy 413.37158 -397.15694) (xy 413.91332 -397.15694)
			(xy 413.91332 -397.156432) (xy 413.913769 -397.132426) (xy 413.921279 -397.085004) (xy 413.936121 -397.039343)
			(xy 413.957927 -396.996568) (xy 413.98616 -396.957733) (xy 414.020124 -396.923797) (xy 414.058981 -396.895596)
			(xy 414.101774 -396.873825) (xy 414.147448 -396.859021) (xy 414.194875 -396.851549) (xy 414.218882 -396.851124)
			(xy 414.242819 -396.851537) (xy 414.290108 -396.859001) (xy 414.335653 -396.87375) (xy 414.378341 -396.895422)
			(xy 414.417126 -396.923486) (xy 414.451059 -396.957257) (xy 414.47931 -396.995907) (xy 414.490662 -397.016986)
			(xy 414.49117 -397.018002) (xy 414.571476 -397.15694) (xy 415.113724 -397.15694) (xy 415.113724 -397.156432)
			(xy 415.114168 -397.132438) (xy 415.121671 -397.085041) (xy 415.136497 -397.039401) (xy 415.158281 -396.996643)
			(xy 415.186487 -396.957819) (xy 415.220419 -396.923887) (xy 415.259243 -396.895681) (xy 415.302001 -396.873897)
			(xy 415.347641 -396.859071) (xy 415.395038 -396.851568) (xy 415.419032 -396.851124) (xy 415.442968 -396.851578)
			(xy 415.490254 -396.859034) (xy 415.535799 -396.873775) (xy 415.578487 -396.89544) (xy 415.617272 -396.923499)
			(xy 415.651207 -396.957264) (xy 415.679459 -396.995909) (xy 415.690812 -397.016986) (xy 415.69132 -397.018002)
			(xy 415.771626 -397.15694) (xy 416.31362 -397.15694) (xy 416.31362 -397.156432) (xy 416.314068 -397.132438)
			(xy 416.321571 -397.085041) (xy 416.336397 -397.039402) (xy 416.35818 -396.996644) (xy 416.386386 -396.95782)
			(xy 416.420317 -396.923888) (xy 416.45914 -396.895682) (xy 416.501898 -396.873898) (xy 416.547537 -396.859072)
			(xy 416.594934 -396.851568) (xy 416.618928 -396.851124) (xy 416.642863 -396.851581) (xy 416.69015 -396.859037)
			(xy 416.735695 -396.873777) (xy 416.778382 -396.895442) (xy 416.817168 -396.9235) (xy 416.851103 -396.957265)
			(xy 416.879355 -396.995909) (xy 416.890708 -397.016986) (xy 416.891216 -397.018002) (xy 416.971522 -397.15694)
			(xy 417.513516 -397.15694) (xy 417.513516 -397.156432) (xy 417.513968 -397.132439) (xy 417.521471 -397.085042)
			(xy 417.536296 -397.039403) (xy 417.55808 -396.996645) (xy 417.586284 -396.957822) (xy 417.620216 -396.92389)
			(xy 417.659038 -396.895684) (xy 417.701795 -396.873899) (xy 417.747434 -396.859072) (xy 417.794831 -396.851568)
			(xy 417.818824 -396.851124) (xy 417.842759 -396.851584) (xy 417.890046 -396.859039) (xy 417.93559 -396.873779)
			(xy 417.978278 -396.895444) (xy 418.017064 -396.923501) (xy 418.050998 -396.957265) (xy 418.079251 -396.99591)
			(xy 418.090604 -397.016986) (xy 418.091112 -397.018002) (xy 418.171418 -397.15694) (xy 418.713412 -397.15694)
			(xy 418.713412 -397.156432) (xy 418.713869 -397.132426) (xy 418.721379 -397.085005) (xy 418.73622 -397.039345)
			(xy 418.758025 -396.99657) (xy 418.786257 -396.957736) (xy 418.82022 -396.9238) (xy 418.859077 -396.895599)
			(xy 418.901869 -396.873827) (xy 418.947541 -396.859023) (xy 418.994968 -396.85155) (xy 419.018974 -396.851124)
			(xy 419.042911 -396.851543) (xy 419.090199 -396.859006) (xy 419.135744 -396.873754) (xy 419.178432 -396.895425)
			(xy 419.217218 -396.923488) (xy 419.251151 -396.957258) (xy 419.279402 -396.995907) (xy 419.290754 -397.016986)
			(xy 419.291262 -397.018002) (xy 419.371568 -397.15694) (xy 419.913308 -397.15694) (xy 419.913308 -397.156432)
			(xy 419.913769 -397.132426) (xy 419.921279 -397.085006) (xy 419.93612 -397.039346) (xy 419.957925 -396.996571)
			(xy 419.986156 -396.957737) (xy 420.020119 -396.923801) (xy 420.058975 -396.8956) (xy 420.101766 -396.873828)
			(xy 420.147438 -396.859023) (xy 420.194864 -396.85155) (xy 420.21887 -396.851124) (xy 420.242807 -396.851547)
			(xy 420.290095 -396.859009) (xy 420.33564 -396.873756) (xy 420.378328 -396.895426) (xy 420.417113 -396.923489)
			(xy 420.451047 -396.957259) (xy 420.479298 -396.995907) (xy 420.49065 -397.016986) (xy 420.491158 -397.018002)
			(xy 420.883588 -397.696944) (xy 420.896319 -397.72031) (xy 420.914436 -397.770338) (xy 420.923646 -397.822741)
			(xy 420.924228 -397.849344) (xy 420.923778 -397.873335) (xy 420.916266 -397.920727) (xy 420.901434 -397.96636)
			(xy 420.879647 -398.009111) (xy 420.851441 -398.047928) (xy 420.81751 -398.081856) (xy 420.778691 -398.110059)
			(xy 420.735937 -398.131843) (xy 420.690303 -398.146672) (xy 420.642911 -398.15418) (xy 420.61892 -398.154652)
			(xy 420.595348 -398.154215) (xy 420.548763 -398.146978) (xy 420.503847 -398.132658) (xy 420.46167 -398.111595)
			(xy 420.423236 -398.084293) (xy 420.389462 -398.051402) (xy 420.361153 -398.013704) (xy 420.34968 -397.993108)
			(xy 420.349172 -397.992346) (xy 419.951408 -397.304006) (xy 419.939493 -397.281337) (xy 419.922555 -397.233012)
			(xy 419.913896 -397.182542) (xy 419.913308 -397.15694) (xy 419.371568 -397.15694) (xy 419.683692 -397.696944)
			(xy 419.696424 -397.72031) (xy 419.71454 -397.770338) (xy 419.72375 -397.822741) (xy 419.724332 -397.849344)
			(xy 419.723878 -397.873335) (xy 419.716366 -397.920726) (xy 419.701534 -397.966359) (xy 419.679747 -398.00911)
			(xy 419.651542 -398.047927) (xy 419.617612 -398.081855) (xy 419.578793 -398.110058) (xy 419.53604 -398.131842)
			(xy 419.490407 -398.146671) (xy 419.443015 -398.15418) (xy 419.419024 -398.154652) (xy 419.395452 -398.154211)
			(xy 419.348867 -398.146975) (xy 419.303951 -398.132656) (xy 419.261774 -398.111594) (xy 419.223341 -398.084292)
			(xy 419.189567 -398.051401) (xy 419.161257 -398.013704) (xy 419.149784 -397.993108) (xy 419.149276 -397.992346)
			(xy 418.751512 -397.304006) (xy 418.739598 -397.281337) (xy 418.72266 -397.233012) (xy 418.714 -397.182542)
			(xy 418.713412 -397.15694) (xy 418.171418 -397.15694) (xy 418.483542 -397.696944) (xy 418.496349 -397.720286)
			(xy 418.514576 -397.770304) (xy 418.523843 -397.822727) (xy 418.524436 -397.849344) (xy 418.524002 -397.87335)
			(xy 418.516481 -397.920768) (xy 418.501633 -397.966426) (xy 418.479822 -398.009197) (xy 418.451587 -398.048029)
			(xy 418.417623 -398.081963) (xy 418.378767 -398.110164) (xy 418.335976 -398.131936) (xy 418.290305 -398.146744)
			(xy 418.24288 -398.154223) (xy 418.218874 -398.154652) (xy 418.195301 -398.154252) (xy 418.148714 -398.147008)
			(xy 418.103797 -398.132681) (xy 418.06162 -398.111613) (xy 418.023187 -398.084305) (xy 417.989414 -398.051408)
			(xy 417.961106 -398.013706) (xy 417.949634 -397.993108) (xy 417.949126 -397.992346) (xy 417.551362 -397.304006)
			(xy 417.539486 -397.281329) (xy 417.522635 -397.232996) (xy 417.514062 -397.182533) (xy 417.513516 -397.15694)
			(xy 416.971522 -397.15694) (xy 417.283646 -397.696944) (xy 417.296453 -397.720286) (xy 417.31468 -397.770304)
			(xy 417.323947 -397.822727) (xy 417.32454 -397.849344) (xy 417.324102 -397.873349) (xy 417.316581 -397.920768)
			(xy 417.301733 -397.966425) (xy 417.279923 -398.009196) (xy 417.251688 -398.048027) (xy 417.217725 -398.081961)
			(xy 417.178869 -398.110162) (xy 417.136079 -398.131935) (xy 417.090409 -398.146744) (xy 417.042984 -398.154222)
			(xy 417.018978 -398.154652) (xy 416.995405 -398.154249) (xy 416.948818 -398.147005) (xy 416.903901 -398.132679)
			(xy 416.861724 -398.111611) (xy 416.823291 -398.084304) (xy 416.789518 -398.051408) (xy 416.76121 -398.013706)
			(xy 416.749738 -397.993108) (xy 416.74923 -397.992346) (xy 416.351466 -397.304006) (xy 416.339591 -397.281329)
			(xy 416.322739 -397.232996) (xy 416.314166 -397.182533) (xy 416.31362 -397.15694) (xy 415.771626 -397.15694)
			(xy 416.08375 -397.696944) (xy 416.096557 -397.720285) (xy 416.114784 -397.770304) (xy 416.124051 -397.822726)
			(xy 416.124644 -397.849344) (xy 416.124202 -397.873349) (xy 416.116682 -397.920767) (xy 416.101834 -397.966424)
			(xy 416.080024 -398.009195) (xy 416.05179 -398.048026) (xy 416.017826 -398.08196) (xy 415.978971 -398.110161)
			(xy 415.936182 -398.131934) (xy 415.890512 -398.146743) (xy 415.843088 -398.154222) (xy 415.819082 -398.154652)
			(xy 415.795509 -398.154245) (xy 415.748922 -398.147003) (xy 415.704006 -398.132677) (xy 415.661828 -398.11161)
			(xy 415.623395 -398.084303) (xy 415.589623 -398.051407) (xy 415.561314 -398.013706) (xy 415.549842 -397.993108)
			(xy 415.549334 -397.992346) (xy 415.15157 -397.304006) (xy 415.139695 -397.281329) (xy 415.122843 -397.232996)
			(xy 415.11427 -397.182533) (xy 415.113724 -397.15694) (xy 414.571476 -397.15694) (xy 414.8836 -397.696944)
			(xy 414.896332 -397.72031) (xy 414.914448 -397.770338) (xy 414.923658 -397.822741) (xy 414.92424 -397.849344)
			(xy 414.923778 -397.873335) (xy 414.916266 -397.920725) (xy 414.901435 -397.966357) (xy 414.879649 -398.009107)
			(xy 414.851444 -398.047924) (xy 414.817515 -398.081852) (xy 414.778697 -398.110055) (xy 414.735946 -398.13184)
			(xy 414.690313 -398.146669) (xy 414.642923 -398.154179) (xy 414.618932 -398.154652) (xy 414.59536 -398.154205)
			(xy 414.548776 -398.14697) (xy 414.50386 -398.132651) (xy 414.461683 -398.111591) (xy 414.423249 -398.08429)
			(xy 414.389475 -398.0514) (xy 414.361165 -398.013703) (xy 414.349692 -397.993108) (xy 414.349184 -397.992346)
			(xy 413.95142 -397.304006) (xy 413.939506 -397.281337) (xy 413.922568 -397.233012) (xy 413.913908 -397.182542)
			(xy 413.91332 -397.15694) (xy 413.37158 -397.15694) (xy 413.683704 -397.696944) (xy 413.696464 -397.720252)
			(xy 413.714596 -397.770194) (xy 413.723794 -397.822524) (xy 413.724344 -397.84909) (xy 413.724344 -397.849344)
			(xy 413.72387 -397.873334) (xy 413.716359 -397.920722) (xy 413.701528 -397.966353) (xy 413.679743 -398.009102)
			(xy 413.651539 -398.047918) (xy 413.617612 -398.081844) (xy 413.578795 -398.110047) (xy 413.536046 -398.131831)
			(xy 413.490415 -398.146661) (xy 413.443026 -398.154171) (xy 413.419036 -398.154652) (xy 413.395466 -398.154209)
			(xy 413.348889 -398.146953) (xy 413.30398 -398.132622) (xy 413.261809 -398.111558) (xy 413.223377 -398.084261)
			(xy 413.189598 -398.05138) (xy 413.161276 -398.013698) (xy 413.149796 -397.993108) (xy 413.149288 -397.992346)
			(xy 412.751524 -397.304006) (xy 412.739593 -397.281345) (xy 412.722646 -397.23302) (xy 412.714005 -397.182544)
			(xy 412.713424 -397.15694) (xy 412.713424 -397.156432) (xy 412.715456 -397.122904) (xy 412.716726 -397.111982)
			(xy 412.710122 -397.091662) (xy 412.65221 -397.027146) (xy 412.644643 -397.019529) (xy 412.625084 -397.010733)
			(xy 412.614364 -397.010128) (xy 412.17469 -397.010128) (xy 412.165793 -397.010453) (xy 412.149066 -397.016524)
			(xy 412.135435 -397.027961) (xy 412.130748 -397.035528) (xy 412.123636 -397.047466) (xy 412.12389 -397.07439)
			(xy 412.483554 -397.696944) (xy 412.496336 -397.720295) (xy 412.514527 -397.770318) (xy 412.52381 -397.822731)
			(xy 412.524448 -397.849344) (xy 412.523975 -397.873321) (xy 412.516472 -397.920686) (xy 412.501656 -397.966295)
			(xy 412.479893 -398.009027) (xy 412.451718 -398.047832) (xy 412.417822 -398.081755) (xy 412.379041 -398.109962)
			(xy 412.336326 -398.13176) (xy 412.290729 -398.146613) (xy 412.243371 -398.154155) (xy 412.219394 -398.154652)
			(xy 412.218886 -398.154652) (xy 412.195314 -398.154213) (xy 412.148732 -398.146963) (xy 412.103818 -398.132637)
			(xy 412.06164 -398.111577) (xy 412.023202 -398.084282) (xy 411.989417 -398.051402) (xy 411.961089 -398.013719)
			(xy 411.949646 -397.993108) (xy 411.949138 -397.992346) (xy 411.551374 -397.304006) (xy 411.539475 -397.281338)
			(xy 411.522599 -397.233007) (xy 411.514037 -397.182536) (xy 411.513528 -397.15694) (xy 411.513528 -397.156432)
			(xy 411.515306 -397.122904) (xy 411.516576 -397.111982) (xy 411.509972 -397.091662) (xy 411.45206 -397.027146)
			(xy 411.44449 -397.019537) (xy 411.424931 -397.01076) (xy 411.414214 -397.010128) (xy 410.974794 -397.010128)
			(xy 410.965896 -397.010453) (xy 410.949169 -397.016522) (xy 410.935536 -397.027959) (xy 410.930852 -397.035528)
			(xy 410.92374 -397.047466) (xy 410.923994 -397.07439) (xy 411.283658 -397.696944) (xy 411.29644 -397.720295)
			(xy 411.314631 -397.770318) (xy 411.323913 -397.822731) (xy 411.324552 -397.849344) (xy 411.324079 -397.873322)
			(xy 411.316576 -397.920686) (xy 411.30176 -397.966295) (xy 411.279997 -398.009028) (xy 411.251822 -398.047833)
			(xy 411.217927 -398.081757) (xy 411.179145 -398.109964) (xy 411.13643 -398.131763) (xy 411.090833 -398.146616)
			(xy 411.043475 -398.154159) (xy 411.019498 -398.154652) (xy 411.01899 -398.154652) (xy 410.995418 -398.154213)
			(xy 410.948835 -398.146964) (xy 410.903921 -398.132638) (xy 410.861743 -398.111578) (xy 410.823304 -398.084284)
			(xy 410.789519 -398.051404) (xy 410.76119 -398.013721) (xy 410.74975 -397.993108) (xy 410.749242 -397.992346)
			(xy 410.351478 -397.304006) (xy 410.339579 -397.281338) (xy 410.322702 -397.233007) (xy 410.31414 -397.182536)
			(xy 410.313632 -397.15694) (xy 410.313632 -397.156432) (xy 410.313716 -397.145087) (xy 410.315372 -397.122457)
			(xy 410.316934 -397.11122) (xy 410.318204 -397.10233) (xy 410.314648 -397.085058) (xy 410.271214 -397.013938)
			(xy 410.257244 -397.003016) (xy 410.248862 -396.999968) (xy 410.228034 -396.992348) (xy 410.227526 -396.99184)
			(xy 410.214606 -396.9865) (xy 410.189913 -396.973387) (xy 410.17825 -396.965678) (xy 410.177488 -396.96517)
			(xy 410.158328 -396.951912) (xy 410.123888 -396.920532) (xy 410.108908 -396.902686) (xy 410.105352 -396.898876)
			(xy 409.567888 -396.361412) (xy 409.55063 -396.34337) (xy 409.522877 -396.301876) (xy 409.503769 -396.255758)
			(xy 409.494044 -396.206794) (xy 409.493466 -396.181834) (xy 409.493466 -394.445236) (xy 409.493277 -394.438567)
			(xy 409.489813 -394.425687) (xy 409.486608 -394.419836) (xy 409.151582 -393.839954) (xy 409.139687 -393.817285)
			(xy 409.122818 -393.768954) (xy 409.114265 -393.718483) (xy 409.113736 -393.692888) (xy 409.113736 -393.69238)
			(xy 409.114184 -393.668389) (xy 409.121693 -393.620999) (xy 409.136524 -393.575366) (xy 409.158311 -393.532616)
			(xy 409.186518 -393.493801) (xy 409.22045 -393.459876) (xy 409.259271 -393.431678) (xy 409.302026 -393.4099)
			(xy 409.347661 -393.395078) (xy 409.395053 -393.387579) (xy 409.419044 -393.387072) (xy 409.419806 -393.387072)
			(xy 409.429413 -393.386653) (xy 409.447285 -393.379595) (xy 409.454604 -393.373356) (xy 409.477464 -393.35202)
			(xy 409.48473 -393.344519) (xy 409.492998 -393.325368) (xy 409.493466 -393.314936) (xy 409.493466 -392.081258)
			(xy 409.49297 -392.071258) (xy 409.485302 -392.052787) (xy 409.471149 -392.038655) (xy 409.452666 -392.031015)
			(xy 409.442666 -392.030458) (xy 397.169894 -392.030458) (xy 397.159826 -392.030884) (xy 397.141228 -392.038606)
			(xy 397.133826 -392.045444) (xy 396.515336 -392.663934) (xy 396.508491 -392.671333) (xy 396.500763 -392.689931)
			(xy 396.50035 -392.700002) (xy 396.50035 -393.692888) (xy 403.113748 -393.692888) (xy 403.113748 -393.69238)
			(xy 403.114244 -393.66839) (xy 403.121752 -393.621002) (xy 403.136579 -393.575372) (xy 403.158361 -393.532622)
			(xy 403.186562 -393.493805) (xy 403.220487 -393.459878) (xy 403.259301 -393.431674) (xy 403.302049 -393.409888)
			(xy 403.347679 -393.395057) (xy 403.395066 -393.387546) (xy 403.419056 -393.387072) (xy 403.442991 -393.387534)
			(xy 403.490276 -393.394993) (xy 403.535819 -393.409735) (xy 403.578505 -393.431399) (xy 403.617291 -393.459456)
			(xy 403.651226 -393.493218) (xy 403.679481 -393.531859) (xy 403.690836 -393.552934) (xy 403.691344 -393.55395)
			(xy 403.77165 -393.692888) (xy 404.313644 -393.692888) (xy 404.313644 -393.69238) (xy 404.314144 -393.668391)
			(xy 404.321652 -393.621003) (xy 404.336479 -393.575373) (xy 404.358261 -393.532623) (xy 404.386461 -393.493807)
			(xy 404.420386 -393.459879) (xy 404.459199 -393.431675) (xy 404.501947 -393.40989) (xy 404.547576 -393.395058)
			(xy 404.594963 -393.387546) (xy 404.618952 -393.387072) (xy 404.642887 -393.387537) (xy 404.690171 -393.394995)
			(xy 404.735714 -393.409737) (xy 404.778401 -393.431401) (xy 404.817187 -393.459457) (xy 404.851122 -393.493218)
			(xy 404.879377 -393.531859) (xy 404.890732 -393.552934) (xy 404.89124 -393.55395) (xy 404.971546 -393.692888)
			(xy 405.51354 -393.692888) (xy 405.51354 -393.69238) (xy 405.51392 -393.668384) (xy 405.521431 -393.620983)
			(xy 405.536265 -393.575341) (xy 405.558057 -393.532582) (xy 405.58627 -393.493758) (xy 405.62021 -393.459826)
			(xy 405.65904 -393.431622) (xy 405.701804 -393.409839) (xy 405.747449 -393.395015) (xy 405.794852 -393.387515)
			(xy 405.818848 -393.387072) (xy 405.842783 -393.387541) (xy 405.890067 -393.394998) (xy 405.93561 -393.409739)
			(xy 405.978297 -393.431402) (xy 406.017082 -393.459458) (xy 406.051018 -393.493219) (xy 406.079273 -393.531859)
			(xy 406.090628 -393.552934) (xy 406.091136 -393.55395) (xy 406.171442 -393.692888) (xy 406.713436 -393.692888)
			(xy 406.713436 -393.69238) (xy 406.713821 -393.668371) (xy 406.72134 -393.620947) (xy 406.736189 -393.575283)
			(xy 406.758003 -393.532507) (xy 406.786244 -393.493672) (xy 406.820215 -393.459737) (xy 406.859079 -393.431537)
			(xy 406.901877 -393.409767) (xy 406.947556 -393.394965) (xy 406.994989 -393.387496) (xy 407.018998 -393.387072)
			(xy 407.042934 -393.3875) (xy 407.090221 -393.394965) (xy 407.135764 -393.409713) (xy 407.178451 -393.431383)
			(xy 407.217236 -393.459445) (xy 407.25117 -393.493212) (xy 407.279424 -393.531857) (xy 407.290778 -393.552934)
			(xy 407.291286 -393.55395) (xy 407.371592 -393.692888) (xy 407.913332 -393.692888) (xy 407.913332 -393.69238)
			(xy 407.913721 -393.668372) (xy 407.92124 -393.620947) (xy 407.936089 -393.575284) (xy 407.957902 -393.532508)
			(xy 407.986142 -393.493674) (xy 408.020113 -393.459738) (xy 408.058976 -393.431538) (xy 408.101775 -393.409769)
			(xy 408.147453 -393.394966) (xy 408.194885 -393.387496) (xy 408.218894 -393.387072) (xy 408.24283 -393.387503)
			(xy 408.290116 -393.394968) (xy 408.33566 -393.409715) (xy 408.378347 -393.431385) (xy 408.417132 -393.459446)
			(xy 408.451066 -393.493212) (xy 408.47932 -393.531857) (xy 408.490674 -393.552934) (xy 408.491182 -393.55395)
			(xy 408.883612 -394.232892) (xy 408.896363 -394.256248) (xy 408.914472 -394.306281) (xy 408.923674 -394.358688)
			(xy 408.924252 -394.385292) (xy 408.92373 -394.409281) (xy 408.916227 -394.456668) (xy 408.901403 -394.502298)
			(xy 408.879624 -394.545048) (xy 408.851427 -394.583865) (xy 408.817504 -394.617793) (xy 408.778692 -394.645997)
			(xy 408.735946 -394.667783) (xy 408.690319 -394.682614) (xy 408.642933 -394.690126) (xy 408.618944 -394.6906)
			(xy 408.595371 -394.690171) (xy 408.548785 -394.682936) (xy 408.503867 -394.668616) (xy 408.461689 -394.647554)
			(xy 408.423255 -394.620249) (xy 408.389482 -394.587355) (xy 408.361175 -394.549654) (xy 408.349704 -394.529056)
			(xy 408.349196 -394.528294) (xy 407.951432 -393.839954) (xy 407.9395 -393.817294) (xy 407.922568 -393.768965)
			(xy 407.913915 -393.718491) (xy 407.913332 -393.692888) (xy 407.371592 -393.692888) (xy 407.683716 -394.232892)
			(xy 407.696468 -394.256248) (xy 407.714576 -394.306281) (xy 407.723778 -394.358688) (xy 407.724356 -394.385292)
			(xy 407.72383 -394.409281) (xy 407.716327 -394.456667) (xy 407.701503 -394.502297) (xy 407.679725 -394.545047)
			(xy 407.651528 -394.583863) (xy 407.617606 -394.617791) (xy 407.578794 -394.645996) (xy 407.536049 -394.667782)
			(xy 407.490422 -394.682614) (xy 407.443037 -394.690126) (xy 407.419048 -394.6906) (xy 407.395475 -394.690168)
			(xy 407.348889 -394.682933) (xy 407.303971 -394.668614) (xy 407.261793 -394.647552) (xy 407.223359 -394.620248)
			(xy 407.189586 -394.587354) (xy 407.161279 -394.549654) (xy 407.149808 -394.529056) (xy 407.1493 -394.528294)
			(xy 406.751536 -393.839954) (xy 406.739605 -393.817294) (xy 406.722672 -393.768964) (xy 406.714019 -393.718491)
			(xy 406.713436 -393.692888) (xy 406.171442 -393.692888) (xy 406.483566 -394.232892) (xy 406.496393 -394.256223)
			(xy 406.514612 -394.306247) (xy 406.523871 -394.358673) (xy 406.52446 -394.385292) (xy 406.524053 -394.4093)
			(xy 406.516538 -394.456724) (xy 406.501693 -394.502388) (xy 406.479882 -394.545164) (xy 406.451644 -394.583999)
			(xy 406.417675 -394.617935) (xy 406.378813 -394.646136) (xy 406.336016 -394.667905) (xy 406.290338 -394.682707)
			(xy 406.242906 -394.690176) (xy 406.218898 -394.6906) (xy 406.195324 -394.690208) (xy 406.148736 -394.682966)
			(xy 406.103817 -394.66864) (xy 406.061639 -394.647571) (xy 406.023206 -394.620261) (xy 405.989434 -394.587361)
			(xy 405.961128 -394.549656) (xy 405.949658 -394.529056) (xy 405.94915 -394.528294) (xy 405.551386 -393.839954)
			(xy 405.53953 -393.817267) (xy 405.522671 -393.768939) (xy 405.51409 -393.718479) (xy 405.51354 -393.692888)
			(xy 404.971546 -393.692888) (xy 405.28367 -394.232892) (xy 405.296497 -394.256223) (xy 405.314716 -394.306247)
			(xy 405.323975 -394.358673) (xy 405.324564 -394.385292) (xy 405.324153 -394.4093) (xy 405.316639 -394.456724)
			(xy 405.301793 -394.502387) (xy 405.279983 -394.545163) (xy 405.251745 -394.583998) (xy 405.217777 -394.617934)
			(xy 405.178915 -394.646134) (xy 405.136118 -394.667904) (xy 405.090441 -394.682706) (xy 405.04301 -394.690176)
			(xy 405.019002 -394.6906) (xy 404.995428 -394.690205) (xy 404.94884 -394.682963) (xy 404.903921 -394.668638)
			(xy 404.861743 -394.64757) (xy 404.82331 -394.62026) (xy 404.789538 -394.587361) (xy 404.761233 -394.549656)
			(xy 404.749762 -394.529056) (xy 404.749254 -394.528294) (xy 404.35149 -393.839954) (xy 404.339634 -393.817267)
			(xy 404.322775 -393.768939) (xy 404.314194 -393.718479) (xy 404.313644 -393.692888) (xy 403.77165 -393.692888)
			(xy 404.083774 -394.232892) (xy 404.096601 -394.256223) (xy 404.11482 -394.306247) (xy 404.124079 -394.358673)
			(xy 404.124668 -394.385292) (xy 404.124253 -394.4093) (xy 404.116739 -394.456723) (xy 404.101893 -394.502386)
			(xy 404.080083 -394.545162) (xy 404.051846 -394.583996) (xy 404.017879 -394.617932) (xy 403.979017 -394.646133)
			(xy 403.936221 -394.667903) (xy 403.890545 -394.682706) (xy 403.843114 -394.690176) (xy 403.819106 -394.6906)
			(xy 403.795532 -394.690201) (xy 403.748944 -394.682961) (xy 403.704026 -394.668636) (xy 403.661847 -394.647568)
			(xy 403.623414 -394.620259) (xy 403.589642 -394.58736) (xy 403.561337 -394.549655) (xy 403.549866 -394.529056)
			(xy 403.549358 -394.528294) (xy 403.151594 -393.839954) (xy 403.139738 -393.817267) (xy 403.122879 -393.768939)
			(xy 403.114298 -393.718479) (xy 403.113748 -393.692888) (xy 396.50035 -393.692888) (xy 396.50035 -394.428726)
			(xy 396.499776 -394.453685) (xy 396.490031 -394.502643) (xy 396.470921 -394.548758) (xy 396.44318 -394.590259)
			(xy 396.425928 -394.608304) (xy 394.862558 -396.171674) (xy 396.529052 -396.171674) (xy 396.529052 -395.308074)
			(xy 396.529538 -395.280823) (xy 396.537294 -395.226875) (xy 396.552649 -395.17458) (xy 396.575291 -395.125003)
			(xy 396.604757 -395.079153) (xy 396.640448 -395.037962) (xy 396.681639 -395.002271) (xy 396.727489 -394.972805)
			(xy 396.777066 -394.950163) (xy 396.829361 -394.934808) (xy 396.883309 -394.927052) (xy 396.937811 -394.927052)
			(xy 396.991759 -394.934808) (xy 397.044054 -394.950163) (xy 397.093631 -394.972805) (xy 397.139481 -395.002271)
			(xy 397.180672 -395.037962) (xy 397.216363 -395.079153) (xy 397.245829 -395.125003) (xy 397.268471 -395.17458)
			(xy 397.283826 -395.226875) (xy 397.291582 -395.280823) (xy 397.292068 -395.308074) (xy 397.292068 -396.171674)
			(xy 397.291582 -396.198925) (xy 397.283826 -396.252873) (xy 397.268471 -396.305168) (xy 397.245829 -396.354745)
			(xy 397.216363 -396.400595) (xy 397.180672 -396.441786) (xy 397.139481 -396.477477) (xy 397.093631 -396.506943)
			(xy 397.044054 -396.529585) (xy 396.991759 -396.54494) (xy 396.937811 -396.552696) (xy 396.883309 -396.552696)
			(xy 396.829361 -396.54494) (xy 396.777066 -396.529585) (xy 396.727489 -396.506943) (xy 396.681639 -396.477477)
			(xy 396.640448 -396.441786) (xy 396.604757 -396.400595) (xy 396.575291 -396.354745) (xy 396.552649 -396.305168)
			(xy 396.537294 -396.252873) (xy 396.529538 -396.198925) (xy 396.529052 -396.171674) (xy 394.862558 -396.171674)
			(xy 394.7922 -396.242032) (xy 394.774158 -396.259288) (xy 394.732662 -396.287037) (xy 394.686544 -396.306141)
			(xy 394.637582 -396.315863) (xy 394.612622 -396.316454) (xy 393.015216 -396.316454) (xy 393.005154 -396.316894)
			(xy 392.986577 -396.324636) (xy 392.979148 -396.33144) (xy 392.735562 -396.575026) (xy 392.717522 -396.592287)
			(xy 392.676029 -396.620047) (xy 392.62991 -396.639163) (xy 392.580946 -396.648897) (xy 392.555984 -396.649448)
			(xy 384.32613 -396.649448) (xy 384.301173 -396.64887) (xy 384.25222 -396.639118) (xy 384.20611 -396.620002)
			(xy 384.164616 -396.592257) (xy 384.146552 -396.575026) (xy 383.943352 -396.371826) (xy 383.916682 -396.364968)
			(xy 383.90322 -396.369032) (xy 383.882585 -396.374608) (xy 383.840264 -396.380595) (xy 383.818892 -396.38097)
			(xy 383.818384 -396.38097) (xy 383.794393 -396.380523) (xy 383.747001 -396.373014) (xy 383.701368 -396.358183)
			(xy 383.658617 -396.336396) (xy 383.619801 -396.30819) (xy 383.585875 -396.274258) (xy 383.557675 -396.235437)
			(xy 383.535896 -396.192682) (xy 383.521074 -396.147046) (xy 383.513573 -396.099653) (xy 383.513076 -396.075662)
			(xy 383.513076 -396.075154) (xy 383.513456 -396.053783) (xy 383.519453 -396.011464) (xy 383.525014 -395.990826)
			(xy 383.529078 -395.977364) (xy 383.52222 -395.950694) (xy 382.85039 -395.278864) (xy 382.842994 -395.272012)
			(xy 382.824395 -395.264272) (xy 382.814322 -395.263878) (xy 382.250696 -395.263878) (xy 382.240626 -395.264301)
			(xy 382.22202 -395.272014) (xy 382.214628 -395.278864) (xy 380.702058 -396.791434) (xy 380.695175 -396.798885)
			(xy 380.687442 -396.817619) (xy 380.687072 -396.827756) (xy 380.687834 -396.91056) (xy 380.695962 -396.929102)
			(xy 380.703328 -396.936468) (xy 380.721266 -396.954414) (xy 380.75153 -396.995136) (xy 380.763526 -397.017494)
			(xy 380.764034 -397.018764) (xy 380.830217 -397.133286) (xy 381.385926 -397.133286) (xy 381.393258 -397.085736)
			(xy 381.407951 -397.039923) (xy 381.429644 -396.996979) (xy 381.457799 -396.957966) (xy 381.49172 -396.923847)
			(xy 381.53057 -396.895467) (xy 381.573388 -396.873527) (xy 381.619116 -396.858569) (xy 381.666622 -396.850962)
			(xy 381.714734 -396.850896) (xy 381.762261 -396.858371) (xy 381.80803 -396.873202) (xy 381.850908 -396.895024)
			(xy 381.889837 -396.923297) (xy 381.923853 -396.957321) (xy 381.952115 -396.996256) (xy 381.963422 -397.017494)
			(xy 381.96393 -397.018764) (xy 382.057097 -397.179979) (xy 382.586212 -397.179979) (xy 382.586461 -397.129044)
			(xy 382.595154 -397.078856) (xy 382.612052 -397.030805) (xy 382.636685 -396.986222) (xy 382.668371 -396.946342)
			(xy 382.706233 -396.912271) (xy 382.749222 -396.884951) (xy 382.796147 -396.86514) (xy 382.845708 -396.853387)
			(xy 382.896532 -396.850016) (xy 382.947211 -396.855122) (xy 382.996341 -396.868563) (xy 383.042561 -396.889967)
			(xy 383.084591 -396.91874) (xy 383.121266 -396.954086) (xy 383.151571 -396.995026) (xy 383.163572 -397.017494)
			(xy 383.16408 -397.018764) (xy 383.257246 -397.179978) (xy 383.786116 -397.179978) (xy 383.786365 -397.129044)
			(xy 383.795058 -397.078856) (xy 383.811955 -397.030806) (xy 383.836588 -396.986224) (xy 383.868274 -396.946345)
			(xy 383.906135 -396.912274) (xy 383.949124 -396.884955) (xy 383.996048 -396.865144) (xy 384.045608 -396.85339)
			(xy 384.096431 -396.85002) (xy 384.147109 -396.855125) (xy 384.196238 -396.868566) (xy 384.242458 -396.889969)
			(xy 384.284487 -396.918742) (xy 384.321162 -396.954087) (xy 384.351467 -396.995026) (xy 384.363468 -397.017494)
			(xy 384.363976 -397.018764) (xy 384.457141 -397.179977) (xy 384.986019 -397.179977) (xy 384.986268 -397.129044)
			(xy 384.994961 -397.078857) (xy 385.011858 -397.030807) (xy 385.036491 -396.986226) (xy 385.068176 -396.946348)
			(xy 385.106037 -396.912277) (xy 385.149025 -396.884958) (xy 385.195948 -396.865147) (xy 385.245508 -396.853394)
			(xy 385.29633 -396.850023) (xy 385.347007 -396.855129) (xy 385.396136 -396.868569) (xy 385.442355 -396.889972)
			(xy 385.484384 -396.918744) (xy 385.521058 -396.954088) (xy 385.551363 -396.995026) (xy 385.563364 -397.017494)
			(xy 385.563872 -397.018764) (xy 385.630054 -397.133285) (xy 386.186033 -397.133285) (xy 386.193365 -397.085737)
			(xy 386.208058 -397.039925) (xy 386.22975 -396.996982) (xy 386.257904 -396.95797) (xy 386.291825 -396.923853)
			(xy 386.330673 -396.895474) (xy 386.37349 -396.873534) (xy 386.419216 -396.858576) (xy 386.466721 -396.85097)
			(xy 386.514831 -396.850903) (xy 386.562358 -396.858377) (xy 386.608125 -396.873208) (xy 386.651002 -396.895029)
			(xy 386.68993 -396.9233) (xy 386.723945 -396.957323) (xy 386.752207 -396.996257) (xy 386.763514 -397.017494)
			(xy 386.764022 -397.018764) (xy 386.830204 -397.133285) (xy 387.385937 -397.133285) (xy 387.393268 -397.085737)
			(xy 387.407961 -397.039926) (xy 387.429653 -396.996984) (xy 387.457807 -396.957973) (xy 387.491727 -396.923856)
			(xy 387.530575 -396.895477) (xy 387.573391 -396.873537) (xy 387.619116 -396.85858) (xy 387.666621 -396.850973)
			(xy 387.71473 -396.850906) (xy 387.762256 -396.85838) (xy 387.808023 -396.873211) (xy 387.850899 -396.895031)
			(xy 387.889826 -396.923302) (xy 387.923841 -396.957324) (xy 387.952103 -396.996257) (xy 387.96341 -397.017494)
			(xy 387.963918 -397.018764) (xy 388.057083 -397.179976) (xy 388.586223 -397.179976) (xy 388.586472 -397.129043)
			(xy 388.595165 -397.078858) (xy 388.612062 -397.030809) (xy 388.636694 -396.986228) (xy 388.668379 -396.94635)
			(xy 388.706239 -396.91228) (xy 388.749226 -396.884961) (xy 388.796149 -396.865151) (xy 388.845707 -396.853397)
			(xy 388.896529 -396.850027) (xy 388.947206 -396.855132) (xy 388.996334 -396.868572) (xy 389.042552 -396.889974)
			(xy 389.08458 -396.918746) (xy 389.121255 -396.95409) (xy 389.151559 -396.995027) (xy 389.16356 -397.017494)
			(xy 389.164068 -397.018764) (xy 389.24392 -397.15694) (xy 403.113748 -397.15694) (xy 403.113748 -397.156432)
			(xy 403.114292 -397.132444) (xy 403.121792 -397.085057) (xy 403.136612 -397.039428) (xy 403.158388 -396.996678)
			(xy 403.186583 -396.957861) (xy 403.220503 -396.923933) (xy 403.259313 -396.895728) (xy 403.302057 -396.873941)
			(xy 403.347683 -396.85911) (xy 403.395068 -396.851598) (xy 403.419056 -396.851124) (xy 403.442992 -396.851558)
			(xy 403.49028 -396.859018) (xy 403.535825 -396.873763) (xy 403.578513 -396.895431) (xy 403.617298 -396.923493)
			(xy 403.651232 -396.957261) (xy 403.679483 -396.995908) (xy 403.690836 -397.016986) (xy 403.691344 -397.018002)
			(xy 403.77165 -397.15694) (xy 404.313644 -397.15694) (xy 404.313644 -397.156432) (xy 404.314192 -397.132444)
			(xy 404.321692 -397.085058) (xy 404.336512 -397.039429) (xy 404.358287 -396.996679) (xy 404.386482 -396.957862)
			(xy 404.420401 -396.923934) (xy 404.459211 -396.895729) (xy 404.501955 -396.873943) (xy 404.54758 -396.859111)
			(xy 404.594964 -396.851598) (xy 404.618952 -396.851124) (xy 404.642888 -396.851561) (xy 404.690176 -396.859021)
			(xy 404.735721 -396.873765) (xy 404.778408 -396.895433) (xy 404.817194 -396.923494) (xy 404.851128 -396.957261)
			(xy 404.879379 -396.995908) (xy 404.890732 -397.016986) (xy 404.89124 -397.018002) (xy 404.971546 -397.15694)
			(xy 405.51354 -397.15694) (xy 405.51354 -397.156432) (xy 405.513968 -397.132437) (xy 405.521471 -397.085038)
			(xy 405.536298 -397.039397) (xy 405.558084 -396.996638) (xy 405.586291 -396.957814) (xy 405.620226 -396.923881)
			(xy 405.659051 -396.895676) (xy 405.701812 -396.873892) (xy 405.747454 -396.859068) (xy 405.794853 -396.851567)
			(xy 405.818848 -396.851124) (xy 405.842784 -396.851565) (xy 405.890071 -396.859024) (xy 405.935616 -396.873767)
			(xy 405.978304 -396.895434) (xy 406.01709 -396.923495) (xy 406.051024 -396.957262) (xy 406.079275 -396.995908)
			(xy 406.090628 -397.016986) (xy 406.091136 -397.018002) (xy 406.171442 -397.15694) (xy 406.713436 -397.15694)
			(xy 406.713436 -397.156432) (xy 406.713869 -397.132425) (xy 406.72138 -397.085002) (xy 406.736222 -397.039339)
			(xy 406.75803 -396.996563) (xy 406.786264 -396.957728) (xy 406.82023 -396.923791) (xy 406.85909 -396.89559)
			(xy 406.901885 -396.87382) (xy 406.947561 -396.859018) (xy 406.99499 -396.851548) (xy 407.018998 -396.851124)
			(xy 407.042935 -396.851524) (xy 407.090225 -396.858991) (xy 407.135771 -396.873741) (xy 407.178458 -396.895415)
			(xy 407.217243 -396.923482) (xy 407.251176 -396.957255) (xy 407.279426 -396.995906) (xy 407.290778 -397.016986)
			(xy 407.291286 -397.018002) (xy 407.371592 -397.15694) (xy 407.913332 -397.15694) (xy 407.913332 -397.156432)
			(xy 407.913769 -397.132425) (xy 407.92128 -397.085002) (xy 407.936122 -397.03934) (xy 407.957929 -396.996564)
			(xy 407.986163 -396.957729) (xy 408.020129 -396.923793) (xy 408.058988 -396.895592) (xy 408.101783 -396.873822)
			(xy 408.147458 -396.859019) (xy 408.194887 -396.851548) (xy 408.218894 -396.851124) (xy 408.242831 -396.851527)
			(xy 408.29012 -396.858993) (xy 408.335666 -396.873744) (xy 408.378354 -396.895417) (xy 408.417139 -396.923483)
			(xy 408.451072 -396.957255) (xy 408.479322 -396.995906) (xy 408.490674 -397.016986) (xy 408.491182 -397.018002)
			(xy 408.571488 -397.15694) (xy 409.113736 -397.15694) (xy 409.113736 -397.156432) (xy 409.114168 -397.132438)
			(xy 409.121671 -397.085039) (xy 409.136498 -397.039398) (xy 409.158283 -396.996639) (xy 409.18649 -396.957815)
			(xy 409.220424 -396.923882) (xy 409.259249 -396.895677) (xy 409.302009 -396.873893) (xy 409.347651 -396.859068)
			(xy 409.39505 -396.851567) (xy 409.419044 -396.851124) (xy 409.44298 -396.851568) (xy 409.490267 -396.859026)
			(xy 409.535812 -396.873769) (xy 409.5785 -396.895436) (xy 409.617285 -396.923496) (xy 409.651219 -396.957262)
			(xy 409.679471 -396.995909) (xy 409.690824 -397.016986) (xy 409.691332 -397.018002) (xy 410.083762 -397.696944)
			(xy 410.09657 -397.720285) (xy 410.114796 -397.770304) (xy 410.124063 -397.822726) (xy 410.124656 -397.849344)
			(xy 410.124202 -397.873349) (xy 410.116682 -397.920765) (xy 410.101835 -397.966421) (xy 410.080026 -398.009191)
			(xy 410.051793 -398.048022) (xy 410.017831 -398.081956) (xy 409.978978 -398.110157) (xy 409.93619 -398.131931)
			(xy 409.890522 -398.14674) (xy 409.843099 -398.154221) (xy 409.819094 -398.154652) (xy 409.795521 -398.154236)
			(xy 409.748935 -398.146995) (xy 409.704019 -398.132671) (xy 409.661841 -398.111605) (xy 409.623408 -398.0843)
			(xy 409.589635 -398.051405) (xy 409.561327 -398.013705) (xy 409.549854 -397.993108) (xy 409.549346 -397.992346)
			(xy 409.151582 -397.304006) (xy 409.139708 -397.281328) (xy 409.122856 -397.232996) (xy 409.114282 -397.182533)
			(xy 409.113736 -397.15694) (xy 408.571488 -397.15694) (xy 408.883612 -397.696944) (xy 408.896345 -397.720309)
			(xy 408.91446 -397.770337) (xy 408.92367 -397.822741) (xy 408.924252 -397.849344) (xy 408.923778 -397.873334)
			(xy 408.916267 -397.920723) (xy 408.901436 -397.966354) (xy 408.879651 -398.009104) (xy 408.851448 -398.04792)
			(xy 408.81752 -398.081848) (xy 408.778704 -398.110051) (xy 408.735954 -398.131836) (xy 408.690323 -398.146667)
			(xy 408.642934 -398.154178) (xy 408.618944 -398.154652) (xy 408.595373 -398.154195) (xy 408.548789 -398.146962)
			(xy 408.503873 -398.132645) (xy 408.461696 -398.111586) (xy 408.423262 -398.084287) (xy 408.389488 -398.051398)
			(xy 408.361178 -398.013703) (xy 408.349704 -397.993108) (xy 408.349196 -397.992346) (xy 407.951432 -397.304006)
			(xy 407.939519 -397.281336) (xy 407.92258 -397.233012) (xy 407.91392 -397.182542) (xy 407.913332 -397.15694)
			(xy 407.371592 -397.15694) (xy 407.683716 -397.696944) (xy 407.69645 -397.720309) (xy 407.714565 -397.770337)
			(xy 407.723774 -397.822741) (xy 407.724356 -397.849344) (xy 407.723878 -397.873334) (xy 407.716367 -397.920723)
			(xy 407.701536 -397.966353) (xy 407.679752 -398.009103) (xy 407.651549 -398.047919) (xy 407.617622 -398.081846)
			(xy 407.578806 -398.11005) (xy 407.536057 -398.131835) (xy 407.490427 -398.146666) (xy 407.443038 -398.154178)
			(xy 407.419048 -398.154652) (xy 407.395477 -398.154192) (xy 407.348893 -398.146959) (xy 407.303977 -398.132643)
			(xy 407.2618 -398.111585) (xy 407.223366 -398.084286) (xy 407.189592 -398.051398) (xy 407.161282 -398.013703)
			(xy 407.149808 -397.993108) (xy 407.1493 -397.992346) (xy 406.751536 -397.304006) (xy 406.739623 -397.281336)
			(xy 406.722684 -397.233012) (xy 406.714024 -397.182542) (xy 406.713436 -397.15694) (xy 406.171442 -397.15694)
			(xy 406.483566 -397.696944) (xy 406.496375 -397.720285) (xy 406.5146 -397.770303) (xy 406.523867 -397.822726)
			(xy 406.52446 -397.849344) (xy 406.524101 -397.873353) (xy 406.516579 -397.92078) (xy 406.501726 -397.966444)
			(xy 406.479909 -398.00922) (xy 406.451665 -398.048055) (xy 406.417691 -398.08199) (xy 406.378825 -398.11019)
			(xy 406.336023 -398.131958) (xy 406.290342 -398.146759) (xy 406.242908 -398.154228) (xy 406.218898 -398.154652)
			(xy 406.195325 -398.154232) (xy 406.14874 -398.146992) (xy 406.103823 -398.132669) (xy 406.061646 -398.111604)
			(xy 406.023213 -398.084299) (xy 405.989439 -398.051405) (xy 405.961131 -398.013705) (xy 405.949658 -397.993108)
			(xy 405.94915 -397.992346) (xy 405.551386 -397.304006) (xy 405.539512 -397.281328) (xy 405.52266 -397.232996)
			(xy 405.514086 -397.182533) (xy 405.51354 -397.15694) (xy 404.971546 -397.15694) (xy 405.28367 -397.696944)
			(xy 405.296479 -397.720285) (xy 405.314704 -397.770303) (xy 405.323971 -397.822726) (xy 405.324564 -397.849344)
			(xy 405.324201 -397.873353) (xy 405.316679 -397.920779) (xy 405.301826 -397.966443) (xy 405.280009 -398.009219)
			(xy 405.251766 -398.048053) (xy 405.217793 -398.081989) (xy 405.178927 -398.110188) (xy 405.136126 -398.131957)
			(xy 405.090446 -398.146759) (xy 405.043012 -398.154228) (xy 405.019002 -398.154652) (xy 404.995429 -398.154229)
			(xy 404.948844 -398.14699) (xy 404.903927 -398.132667) (xy 404.86175 -398.111602) (xy 404.823317 -398.084298)
			(xy 404.789544 -398.051404) (xy 404.761235 -398.013705) (xy 404.749762 -397.993108) (xy 404.749254 -397.992346)
			(xy 404.35149 -397.304006) (xy 404.339616 -397.281328) (xy 404.322764 -397.232995) (xy 404.31419 -397.182533)
			(xy 404.313644 -397.15694) (xy 403.77165 -397.15694) (xy 404.083774 -397.696944) (xy 404.096583 -397.720284)
			(xy 404.114808 -397.770303) (xy 404.124075 -397.822726) (xy 404.124668 -397.849344) (xy 404.124301 -397.873353)
			(xy 404.116779 -397.920778) (xy 404.101926 -397.966442) (xy 404.08011 -398.009218) (xy 404.051867 -398.048052)
			(xy 404.017895 -398.081987) (xy 403.979029 -398.110187) (xy 403.936229 -398.131956) (xy 403.890549 -398.146758)
			(xy 403.843116 -398.154228) (xy 403.819106 -398.154652) (xy 403.795534 -398.154226) (xy 403.748948 -398.146987)
			(xy 403.704032 -398.132665) (xy 403.661854 -398.111601) (xy 403.623421 -398.084297) (xy 403.589648 -398.051404)
			(xy 403.561339 -398.013705) (xy 403.549866 -397.993108) (xy 403.549358 -397.992346) (xy 403.151594 -397.304006)
			(xy 403.139721 -397.281328) (xy 403.122868 -397.232995) (xy 403.114294 -397.182532) (xy 403.113748 -397.15694)
			(xy 389.24392 -397.15694) (xy 389.55599 -397.696944) (xy 389.556244 -397.697452) (xy 389.556498 -397.697452)
			(xy 389.557768 -397.699992) (xy 389.570036 -397.722909) (xy 389.587445 -397.771886) (xy 389.59632 -397.823102)
			(xy 389.596884 -397.84909) (xy 389.596884 -397.849344) (xy 389.596501 -397.873352) (xy 389.588979 -397.920776)
			(xy 389.574128 -397.966438) (xy 389.552313 -398.009213) (xy 389.524072 -398.048046) (xy 389.490101 -398.081981)
			(xy 389.451238 -398.110181) (xy 389.40844 -398.131951) (xy 389.362762 -398.146755) (xy 389.315331 -398.154227)
			(xy 389.291322 -398.154652) (xy 389.267658 -398.154195) (xy 389.220898 -398.146888) (xy 389.175823 -398.13246)
			(xy 389.133511 -398.111257) (xy 389.094972 -398.083784) (xy 389.061129 -398.0507) (xy 389.032791 -398.012795)
			(xy 389.02132 -397.992092) (xy 389.021066 -397.99133) (xy 388.62381 -397.304006) (xy 388.611629 -397.280791)
			(xy 388.594516 -397.231239) (xy 388.589774 -397.205454) (xy 388.589774 -397.2052) (xy 388.586223 -397.179976)
			(xy 388.057083 -397.179976) (xy 388.35584 -397.696944) (xy 388.356094 -397.697452) (xy 388.356348 -397.697452)
			(xy 388.357618 -397.699992) (xy 388.369851 -397.722916) (xy 388.387171 -397.771902) (xy 388.395958 -397.823111)
			(xy 388.39648 -397.84909) (xy 388.39648 -397.849344) (xy 388.396078 -397.873338) (xy 388.388564 -397.920734)
			(xy 388.373729 -397.966371) (xy 388.351938 -398.009125) (xy 388.323726 -398.047945) (xy 388.28979 -398.081873)
			(xy 388.250964 -398.110075) (xy 388.208204 -398.131857) (xy 388.162564 -398.146681) (xy 388.115166 -398.154184)
			(xy 388.091172 -398.154652) (xy 388.06751 -398.154155) (xy 388.020751 -398.146855) (xy 387.975677 -398.132434)
			(xy 387.933365 -398.111238) (xy 387.894826 -398.083772) (xy 387.860982 -398.050693) (xy 387.832641 -398.012793)
			(xy 387.82117 -397.992092) (xy 387.820916 -397.99133) (xy 387.42366 -397.304006) (xy 387.411482 -397.280789)
			(xy 387.394366 -397.231239) (xy 387.389624 -397.205454) (xy 387.389624 -397.2052) (xy 387.386148 -397.181394)
			(xy 387.385937 -397.133285) (xy 386.830204 -397.133285) (xy 387.155944 -397.696944) (xy 387.156198 -397.697452)
			(xy 387.156452 -397.697452) (xy 387.157722 -397.699992) (xy 387.169955 -397.722916) (xy 387.187275 -397.771902)
			(xy 387.196062 -397.823111) (xy 387.196584 -397.84909) (xy 387.196584 -397.849344) (xy 387.196178 -397.873338)
			(xy 387.188664 -397.920733) (xy 387.17383 -397.96637) (xy 387.152038 -398.009124) (xy 387.123828 -398.047943)
			(xy 387.089892 -398.081872) (xy 387.051066 -398.110074) (xy 387.008307 -398.131856) (xy 386.962667 -398.14668)
			(xy 386.91527 -398.154183) (xy 386.891276 -398.154652) (xy 386.867611 -398.154232) (xy 386.820849 -398.146918)
			(xy 386.775773 -398.132483) (xy 386.733461 -398.111274) (xy 386.694923 -398.083796) (xy 386.661081 -398.050707)
			(xy 386.632744 -398.012797) (xy 386.621274 -397.992092) (xy 386.62102 -397.99133) (xy 386.223764 -397.304006)
			(xy 386.211586 -397.280789) (xy 386.19447 -397.231239) (xy 386.189728 -397.205454) (xy 386.189728 -397.2052)
			(xy 386.186245 -397.181395) (xy 386.186033 -397.133285) (xy 385.630054 -397.133285) (xy 385.955794 -397.696944)
			(xy 385.956048 -397.697452) (xy 385.956302 -397.697452) (xy 385.957572 -397.699992) (xy 385.969841 -397.722909)
			(xy 385.987249 -397.771886) (xy 385.996124 -397.823102) (xy 385.996688 -397.84909) (xy 385.996688 -397.849344)
			(xy 385.996301 -397.873352) (xy 385.98878 -397.920775) (xy 385.973928 -397.966437) (xy 385.952114 -398.009212)
			(xy 385.923873 -398.048045) (xy 385.889903 -398.08198) (xy 385.85104 -398.11018) (xy 385.808243 -398.13195)
			(xy 385.762566 -398.146754) (xy 385.715134 -398.154226) (xy 385.691126 -398.154652) (xy 385.667462 -398.154192)
			(xy 385.620702 -398.146885) (xy 385.575627 -398.132458) (xy 385.533315 -398.111255) (xy 385.494777 -398.083783)
			(xy 385.460934 -398.0507) (xy 385.432595 -398.012795) (xy 385.421124 -397.992092) (xy 385.42087 -397.99133)
			(xy 385.023614 -397.304006) (xy 385.011433 -397.28079) (xy 384.99432 -397.231239) (xy 384.989578 -397.205454)
			(xy 384.989578 -397.2052) (xy 384.986019 -397.179977) (xy 384.457141 -397.179977) (xy 384.755898 -397.696944)
			(xy 384.756152 -397.697452) (xy 384.756406 -397.697452) (xy 384.757676 -397.699992) (xy 384.769945 -397.722909)
			(xy 384.787353 -397.771886) (xy 384.796228 -397.823102) (xy 384.796792 -397.84909) (xy 384.796792 -397.849344)
			(xy 384.796401 -397.873352) (xy 384.78888 -397.920775) (xy 384.774029 -397.966436) (xy 384.752214 -398.009211)
			(xy 384.723974 -398.048044) (xy 384.690005 -398.081979) (xy 384.651142 -398.110179) (xy 384.608346 -398.131949)
			(xy 384.562669 -398.146753) (xy 384.515238 -398.154226) (xy 384.49123 -398.154652) (xy 384.467566 -398.154188)
			(xy 384.420807 -398.146882) (xy 384.375732 -398.132456) (xy 384.333419 -398.111254) (xy 384.294881 -398.083782)
			(xy 384.261038 -398.050699) (xy 384.232699 -398.012794) (xy 384.221228 -397.992092) (xy 384.220974 -397.99133)
			(xy 383.823718 -397.304006) (xy 383.811537 -397.28079) (xy 383.794424 -397.231239) (xy 383.789682 -397.205454)
			(xy 383.789682 -397.2052) (xy 383.786116 -397.179978) (xy 383.257246 -397.179978) (xy 383.556002 -397.696944)
			(xy 383.556256 -397.697452) (xy 383.55651 -397.697452) (xy 383.55778 -397.699992) (xy 383.570049 -397.722909)
			(xy 383.587457 -397.771886) (xy 383.596332 -397.823102) (xy 383.596896 -397.84909) (xy 383.596896 -397.849344)
			(xy 383.596501 -397.873352) (xy 383.58898 -397.920774) (xy 383.574129 -397.966435) (xy 383.552315 -398.009209)
			(xy 383.524075 -398.048042) (xy 383.490106 -398.081977) (xy 383.451245 -398.110177) (xy 383.408448 -398.131948)
			(xy 383.362772 -398.146752) (xy 383.315342 -398.154226) (xy 383.291334 -398.154652) (xy 383.267671 -398.154185)
			(xy 383.220911 -398.14688) (xy 383.175836 -398.132454) (xy 383.133524 -398.111252) (xy 383.094985 -398.083781)
			(xy 383.061142 -398.050699) (xy 383.032803 -398.012794) (xy 383.021332 -397.992092) (xy 383.021078 -397.99133)
			(xy 382.623822 -397.304006) (xy 382.611641 -397.28079) (xy 382.594528 -397.231239) (xy 382.589786 -397.205454)
			(xy 382.589786 -397.2052) (xy 382.586212 -397.179979) (xy 382.057097 -397.179979) (xy 382.355852 -397.696944)
			(xy 382.356106 -397.697452) (xy 382.35636 -397.697452) (xy 382.35763 -397.699992) (xy 382.369864 -397.722916)
			(xy 382.387183 -397.771902) (xy 382.395971 -397.823111) (xy 382.396492 -397.84909) (xy 382.396492 -397.849344)
			(xy 382.396078 -397.873337) (xy 382.388565 -397.920732) (xy 382.37373 -397.966368) (xy 382.35194 -398.009122)
			(xy 382.32373 -398.047941) (xy 382.289795 -398.081869) (xy 382.250971 -398.110071) (xy 382.208212 -398.131853)
			(xy 382.162574 -398.146679) (xy 382.115177 -398.154183) (xy 382.091184 -398.154652) (xy 382.067519 -398.154226)
			(xy 382.020757 -398.146913) (xy 381.975682 -398.132479) (xy 381.933369 -398.111271) (xy 381.894832 -398.083794)
			(xy 381.860989 -398.050706) (xy 381.832652 -398.012796) (xy 381.821182 -397.992092) (xy 381.820928 -397.99133)
			(xy 381.423672 -397.304006) (xy 381.411495 -397.280788) (xy 381.394379 -397.231238) (xy 381.389636 -397.205454)
			(xy 381.389636 -397.2052) (xy 381.386138 -397.181397) (xy 381.385926 -397.133286) (xy 380.830217 -397.133286)
			(xy 381.155956 -397.696944) (xy 381.15621 -397.697452) (xy 381.156464 -397.697452) (xy 381.157734 -397.699992)
			(xy 381.169965 -397.722918) (xy 381.187296 -397.7719) (xy 381.196081 -397.823111) (xy 381.196596 -397.84909)
			(xy 381.196596 -397.849344) (xy 381.196122 -397.873333) (xy 381.18861 -397.920718) (xy 381.173779 -397.966346)
			(xy 381.151993 -398.009091) (xy 381.123789 -398.047903) (xy 381.08986 -398.081825) (xy 381.051044 -398.110022)
			(xy 381.008294 -398.1318) (xy 380.962664 -398.146624) (xy 380.915277 -398.154126) (xy 380.891288 -398.154652)
			(xy 380.867624 -398.154207) (xy 380.820862 -398.146905) (xy 380.775787 -398.132478) (xy 380.733476 -398.111271)
			(xy 380.694942 -398.083792) (xy 380.661108 -398.050698) (xy 380.632783 -398.012781) (xy 380.621286 -397.992092)
			(xy 380.621032 -397.99133) (xy 380.223776 -397.304006) (xy 380.211588 -397.280794) (xy 380.194479 -397.23124)
			(xy 380.18974 -397.205454) (xy 380.18974 -397.2052) (xy 380.186347 -397.181838) (xy 380.185969 -397.134634)
			(xy 380.188978 -397.11122) (xy 380.190248 -397.10233) (xy 380.186946 -397.085058) (xy 380.143258 -397.013938)
			(xy 380.129542 -397.002762) (xy 380.120906 -396.999968) (xy 380.097985 -396.991718) (xy 380.054902 -396.968989)
			(xy 380.015973 -396.939708) (xy 379.998732 -396.922498) (xy 379.991281 -396.915445) (xy 379.972406 -396.907452)
			(xy 379.962156 -396.907004) (xy 379.617478 -396.907004) (xy 379.608309 -396.907387) (xy 379.591155 -396.913866)
			(xy 379.577417 -396.926011) (xy 379.572774 -396.933928) (xy 379.55855 -396.960598) (xy 379.555749 -396.966167)
			(xy 379.552669 -396.978244) (xy 379.552454 -396.984474) (xy 379.558804 -397.008858) (xy 379.563376 -397.017494)
			(xy 379.563884 -397.018764) (xy 379.955806 -397.696944) (xy 379.95606 -397.697452) (xy 379.956314 -397.697452)
			(xy 379.957584 -397.699992) (xy 379.969852 -397.722909) (xy 379.98726 -397.771885) (xy 379.996127 -397.823102)
			(xy 379.9967 -397.84909) (xy 379.9967 -397.849344) (xy 379.996227 -397.87332) (xy 379.988723 -397.920682)
			(xy 379.973907 -397.966288) (xy 379.952144 -398.009016) (xy 379.923967 -398.047817) (xy 379.890071 -398.081736)
			(xy 379.851289 -398.109938) (xy 379.808574 -398.13173) (xy 379.762978 -398.146576) (xy 379.715622 -398.154111)
			(xy 379.691646 -398.154652) (xy 379.691138 -398.154652) (xy 379.667472 -398.154211) (xy 379.620706 -398.146915)
			(xy 379.575624 -398.132493) (xy 379.533307 -398.11129) (xy 379.494767 -398.083813) (xy 379.460927 -398.05072)
			(xy 379.432597 -398.012803) (xy 379.421136 -397.992092) (xy 379.420882 -397.99133) (xy 379.023626 -397.304006)
			(xy 379.011439 -397.280793) (xy 378.994334 -397.231239) (xy 378.98959 -397.205454) (xy 378.98959 -397.2052)
			(xy 378.986198 -397.181838) (xy 378.985819 -397.134634) (xy 378.988828 -397.11122) (xy 378.990352 -397.10233)
			(xy 378.986796 -397.084804) (xy 378.943362 -397.013938) (xy 378.929392 -397.002762) (xy 378.92101 -396.999968)
			(xy 378.898089 -396.991718) (xy 378.855005 -396.96899) (xy 378.816076 -396.939709) (xy 378.798836 -396.922498)
			(xy 378.791385 -396.915445) (xy 378.77251 -396.90745) (xy 378.76226 -396.907004) (xy 378.417582 -396.907004)
			(xy 378.408413 -396.907386) (xy 378.391258 -396.913865) (xy 378.377518 -396.926009) (xy 378.372878 -396.933928)
			(xy 378.358654 -396.960598) (xy 378.355853 -396.966167) (xy 378.352773 -396.978244) (xy 378.352558 -396.984474)
			(xy 378.358908 -397.008858) (xy 378.36348 -397.017494) (xy 378.363988 -397.018764) (xy 378.75591 -397.696944)
			(xy 378.756164 -397.697452) (xy 378.756418 -397.697452) (xy 378.757688 -397.699992) (xy 378.769956 -397.722909)
			(xy 378.787364 -397.771886) (xy 378.796231 -397.823102) (xy 378.796804 -397.84909) (xy 378.796804 -397.849344)
			(xy 378.796331 -397.87332) (xy 378.788827 -397.920682) (xy 378.774011 -397.966288) (xy 378.752248 -398.009017)
			(xy 378.724071 -398.047818) (xy 378.690175 -398.081737) (xy 378.651393 -398.10994) (xy 378.608679 -398.131733)
			(xy 378.563082 -398.146579) (xy 378.515726 -398.154115) (xy 378.49175 -398.154652) (xy 378.491242 -398.154652)
			(xy 378.467576 -398.154211) (xy 378.420809 -398.146916) (xy 378.375727 -398.132495) (xy 378.33341 -398.111292)
			(xy 378.294869 -398.083815) (xy 378.261029 -398.050721) (xy 378.232698 -398.012804) (xy 378.22124 -397.992092)
			(xy 378.220986 -397.99133) (xy 377.82373 -397.304006) (xy 377.811543 -397.280793) (xy 377.794437 -397.231239)
			(xy 377.789694 -397.205454) (xy 377.789694 -397.2052) (xy 377.786302 -397.181838) (xy 377.785923 -397.134634)
			(xy 377.788932 -397.11122) (xy 377.790202 -397.10233) (xy 377.7869 -397.085058) (xy 377.743212 -397.013938)
			(xy 377.729496 -397.002762) (xy 377.72086 -396.999968) (xy 377.699778 -396.992469) (xy 377.659901 -396.97217)
			(xy 377.623418 -396.946262) (xy 377.591114 -396.915301) (xy 377.577096 -396.89786) (xy 377.558554 -396.882874)
			(xy 377.538837 -396.873095) (xy 377.502825 -396.847801) (xy 377.486926 -396.832582) (xy 377.004072 -396.349728)
			(xy 376.986814 -396.331687) (xy 376.959059 -396.290193) (xy 376.93995 -396.244074) (xy 376.930222 -396.195111)
			(xy 376.92965 -396.17015) (xy 376.92965 -394.382752) (xy 376.92945 -394.376086) (xy 376.925967 -394.363218)
			(xy 376.922792 -394.357352) (xy 376.623834 -393.839954) (xy 376.61194 -393.817284) (xy 376.595075 -393.768953)
			(xy 376.586523 -393.718483) (xy 376.585988 -393.692888) (xy 376.585988 -393.69238) (xy 376.586494 -393.667314)
			(xy 376.594682 -393.617855) (xy 376.610835 -393.570397) (xy 376.634519 -393.526212) (xy 376.665098 -393.486487)
			(xy 376.701753 -393.452288) (xy 376.7435 -393.424531) (xy 376.789218 -393.403963) (xy 376.83768 -393.391134)
			(xy 376.862594 -393.388342) (xy 376.871535 -393.387118) (xy 376.88779 -393.379306) (xy 376.894344 -393.373102)
			(xy 376.915426 -393.351004) (xy 376.921882 -393.34371) (xy 376.929216 -393.325682) (xy 376.92965 -393.315952)
			(xy 376.92965 -392.60526) (xy 376.929218 -392.595194) (xy 376.921488 -392.576605) (xy 376.914664 -392.569192)
			(xy 376.728736 -392.383264) (xy 376.721337 -392.376421) (xy 376.702738 -392.368699) (xy 376.692668 -392.368278)
			(xy 367.482882 -392.368278) (xy 367.445798 -392.384534) (xy 367.427667 -392.403444) (xy 367.387123 -392.436619)
			(xy 367.342424 -392.46394) (xy 367.294409 -392.484892) (xy 367.243979 -392.499082) (xy 367.192084 -392.506244)
			(xy 367.16589 -392.506708) (xy 367.139459 -392.506258) (xy 367.087103 -392.498958) (xy 367.036256 -392.4845)
			(xy 366.987892 -392.463161) (xy 366.942938 -392.435348) (xy 366.922304 -392.418824) (xy 366.915068 -392.413294)
			(xy 366.897882 -392.407308) (xy 366.888776 -392.40714) (xy 366.85855 -392.407902) (xy 366.848819 -392.408574)
			(xy 366.830915 -392.41627) (xy 366.823752 -392.422888) (xy 366.62868 -392.61796) (xy 366.621834 -392.625358)
			(xy 366.614109 -392.643957) (xy 366.613694 -392.654028) (xy 366.613694 -393.692888) (xy 370.586 -393.692888)
			(xy 370.586 -393.69238) (xy 370.586444 -393.668388) (xy 370.593954 -393.620995) (xy 370.608784 -393.57536)
			(xy 370.630571 -393.532606) (xy 370.658777 -393.493788) (xy 370.692709 -393.459859) (xy 370.73153 -393.431656)
			(xy 370.774286 -393.409873) (xy 370.819922 -393.395047) (xy 370.867316 -393.387542) (xy 370.891308 -393.387072)
			(xy 370.915241 -393.387573) (xy 370.962524 -393.395024) (xy 371.008067 -393.409759) (xy 371.050753 -393.431417)
			(xy 371.089539 -393.459468) (xy 371.123476 -393.493224) (xy 371.151732 -393.531861) (xy 371.163088 -393.552934)
			(xy 371.163596 -393.55395) (xy 371.243902 -393.692888) (xy 371.785896 -393.692888) (xy 371.785896 -393.69238)
			(xy 371.786344 -393.668388) (xy 371.793853 -393.620995) (xy 371.808684 -393.575361) (xy 371.83047 -393.532608)
			(xy 371.858676 -393.493789) (xy 371.892607 -393.459861) (xy 371.931428 -393.431658) (xy 371.974183 -393.409875)
			(xy 372.019819 -393.395048) (xy 372.067212 -393.387542) (xy 372.091204 -393.387072) (xy 372.115137 -393.387576)
			(xy 372.16242 -393.395027) (xy 372.207962 -393.409762) (xy 372.250649 -393.431419) (xy 372.289435 -393.459469)
			(xy 372.323372 -393.493225) (xy 372.351628 -393.531861) (xy 372.362984 -393.552934) (xy 372.363492 -393.55395)
			(xy 372.443798 -393.692888) (xy 372.985792 -393.692888) (xy 372.985792 -393.69238) (xy 372.986244 -393.668388)
			(xy 372.993753 -393.620996) (xy 373.008583 -393.575362) (xy 373.030369 -393.532609) (xy 373.058575 -393.49379)
			(xy 373.092506 -393.459862) (xy 373.131326 -393.431659) (xy 373.17408 -393.409876) (xy 373.219715 -393.395049)
			(xy 373.267108 -393.387543) (xy 373.2911 -393.387072) (xy 373.315033 -393.38758) (xy 373.362316 -393.39503)
			(xy 373.407858 -393.409764) (xy 373.450544 -393.43142) (xy 373.489331 -393.45947) (xy 373.523268 -393.493226)
			(xy 373.551524 -393.531862) (xy 373.56288 -393.552934) (xy 373.563388 -393.55395) (xy 373.643694 -393.692888)
			(xy 374.185688 -393.692888) (xy 374.185688 -393.69238) (xy 374.186121 -393.668374) (xy 374.193638 -393.620954)
			(xy 374.208485 -393.575294) (xy 374.230294 -393.532521) (xy 374.25853 -393.493689) (xy 374.292494 -393.459754)
			(xy 374.331352 -393.431553) (xy 374.374144 -393.409781) (xy 374.419817 -393.394975) (xy 374.467243 -393.3875)
			(xy 374.49125 -393.387072) (xy 374.515185 -393.387539) (xy 374.562469 -393.394997) (xy 374.608012 -393.409738)
			(xy 374.650699 -393.431401) (xy 374.689484 -393.459457) (xy 374.72342 -393.493218) (xy 374.751675 -393.531859)
			(xy 374.76303 -393.552934) (xy 374.763538 -393.55395) (xy 374.843844 -393.692888) (xy 375.385584 -393.692888)
			(xy 375.385584 -393.69238) (xy 375.386021 -393.668374) (xy 375.393538 -393.620954) (xy 375.408384 -393.575295)
			(xy 375.430194 -393.532522) (xy 375.458428 -393.49369) (xy 375.492393 -393.459755) (xy 375.53125 -393.431554)
			(xy 375.574041 -393.409782) (xy 375.619713 -393.394976) (xy 375.66714 -393.3875) (xy 375.691146 -393.387072)
			(xy 375.715081 -393.387542) (xy 375.762365 -393.394999) (xy 375.807908 -393.40974) (xy 375.850594 -393.431403)
			(xy 375.88938 -393.459458) (xy 375.923316 -393.493219) (xy 375.951571 -393.531859) (xy 375.962926 -393.552934)
			(xy 375.963434 -393.55395) (xy 376.355864 -394.232892) (xy 376.36862 -394.256246) (xy 376.386726 -394.30628)
			(xy 376.395926 -394.358688) (xy 376.396504 -394.385292) (xy 376.396054 -394.409285) (xy 376.388549 -394.456681)
			(xy 376.373721 -394.502319) (xy 376.351936 -394.545075) (xy 376.323731 -394.583897) (xy 376.2898 -394.617829)
			(xy 376.250978 -394.646034) (xy 376.208222 -394.66782) (xy 376.162585 -394.682648) (xy 376.115189 -394.690154)
			(xy 376.091196 -394.6906) (xy 376.067622 -394.690209) (xy 376.021033 -394.682967) (xy 375.976115 -394.668641)
			(xy 375.933936 -394.647572) (xy 375.895503 -394.620262) (xy 375.861732 -394.587362) (xy 375.833426 -394.549656)
			(xy 375.821956 -394.529056) (xy 375.821448 -394.528294) (xy 375.423684 -393.839954) (xy 375.411748 -393.817296)
			(xy 375.394819 -393.768965) (xy 375.386167 -393.718492) (xy 375.385584 -393.692888) (xy 374.843844 -393.692888)
			(xy 375.155968 -394.232892) (xy 375.168724 -394.256246) (xy 375.18683 -394.30628) (xy 375.19603 -394.358688)
			(xy 375.196608 -394.385292) (xy 375.196154 -394.409285) (xy 375.188649 -394.45668) (xy 375.173821 -394.502318)
			(xy 375.152037 -394.545074) (xy 375.123832 -394.583896) (xy 375.089902 -394.617827) (xy 375.051081 -394.646033)
			(xy 375.008325 -394.667818) (xy 374.962688 -394.682647) (xy 374.915293 -394.690154) (xy 374.8913 -394.6906)
			(xy 374.867726 -394.690206) (xy 374.821138 -394.682965) (xy 374.776219 -394.668639) (xy 374.734041 -394.64757)
			(xy 374.695608 -394.620261) (xy 374.661836 -394.587361) (xy 374.63353 -394.549656) (xy 374.62206 -394.529056)
			(xy 374.621552 -394.528294) (xy 374.223788 -393.839954) (xy 374.211853 -393.817296) (xy 374.194923 -393.768965)
			(xy 374.186271 -393.718491) (xy 374.185688 -393.692888) (xy 373.643694 -393.692888) (xy 373.955818 -394.232892)
			(xy 373.968641 -394.256226) (xy 373.986862 -394.306248) (xy 373.996123 -394.358673) (xy 373.996712 -394.385292)
			(xy 373.996254 -394.409297) (xy 373.98874 -394.456717) (xy 373.973898 -394.502376) (xy 373.952091 -394.545149)
			(xy 373.923859 -394.583981) (xy 373.889897 -394.617917) (xy 373.851042 -394.646118) (xy 373.808252 -394.66789)
			(xy 373.762581 -394.682697) (xy 373.715156 -394.690172) (xy 373.69115 -394.6906) (xy 373.667577 -394.690166)
			(xy 373.620991 -394.682932) (xy 373.576073 -394.668613) (xy 373.533895 -394.647551) (xy 373.495461 -394.620248)
			(xy 373.461688 -394.587354) (xy 373.433381 -394.549653) (xy 373.42191 -394.529056) (xy 373.421402 -394.528294)
			(xy 373.023638 -393.839954) (xy 373.011778 -393.817269) (xy 372.994922 -393.76894) (xy 372.986342 -393.71848)
			(xy 372.985792 -393.692888) (xy 372.443798 -393.692888) (xy 372.755922 -394.232892) (xy 372.768745 -394.256225)
			(xy 372.786966 -394.306248) (xy 372.796227 -394.358673) (xy 372.796816 -394.385292) (xy 372.796354 -394.409297)
			(xy 372.78884 -394.456716) (xy 372.773998 -394.502375) (xy 372.752192 -394.545147) (xy 372.72396 -394.58398)
			(xy 372.689999 -394.617915) (xy 372.651144 -394.646117) (xy 372.608354 -394.667889) (xy 372.562684 -394.682696)
			(xy 372.51526 -394.690172) (xy 372.491254 -394.6906) (xy 372.467682 -394.690163) (xy 372.421095 -394.682929)
			(xy 372.376178 -394.668611) (xy 372.333999 -394.64755) (xy 372.295566 -394.620247) (xy 372.261793 -394.587353)
			(xy 372.233485 -394.549653) (xy 372.222014 -394.529056) (xy 372.221506 -394.528294) (xy 371.823742 -393.839954)
			(xy 371.811882 -393.817269) (xy 371.795026 -393.76894) (xy 371.786446 -393.71848) (xy 371.785896 -393.692888)
			(xy 371.243902 -393.692888) (xy 371.556026 -394.232892) (xy 371.56885 -394.256225) (xy 371.587071 -394.306247)
			(xy 371.596331 -394.358673) (xy 371.59692 -394.385292) (xy 371.596454 -394.409297) (xy 371.588941 -394.456716)
			(xy 371.574098 -394.502374) (xy 371.552293 -394.545146) (xy 371.524062 -394.583979) (xy 371.4901 -394.617914)
			(xy 371.451246 -394.646115) (xy 371.408457 -394.667888) (xy 371.362788 -394.682695) (xy 371.315363 -394.690172)
			(xy 371.291358 -394.6906) (xy 371.267786 -394.690159) (xy 371.2212 -394.682927) (xy 371.176282 -394.668609)
			(xy 371.134104 -394.647548) (xy 371.09567 -394.620246) (xy 371.061897 -394.587353) (xy 371.03359 -394.549653)
			(xy 371.022118 -394.529056) (xy 371.02161 -394.528294) (xy 370.623846 -393.839954) (xy 370.611986 -393.817269)
			(xy 370.59513 -393.76894) (xy 370.58655 -393.71848) (xy 370.586 -393.692888) (xy 366.613694 -393.692888)
			(xy 366.613694 -395.371066) (xy 366.613076 -395.39602) (xy 366.603328 -395.444967) (xy 366.584218 -395.491072)
			(xy 366.556481 -395.532563) (xy 366.539272 -395.550644) (xy 365.9632 -396.126716) (xy 365.945158 -396.143973)
			(xy 365.903663 -396.171724) (xy 365.857545 -396.190829) (xy 365.808582 -396.200552) (xy 365.783622 -396.201138)
			(xy 364.789212 -396.201138) (xy 364.761272 -396.224252) (xy 364.757716 -396.24254) (xy 364.752073 -396.26978)
			(xy 364.733946 -396.322372) (xy 364.708373 -396.371774) (xy 364.675896 -396.416938) (xy 364.637205 -396.456906)
			(xy 364.593119 -396.490832) (xy 364.544573 -396.517994) (xy 364.492597 -396.537818) (xy 364.438293 -396.549883)
			(xy 364.382812 -396.553934) (xy 364.327331 -396.549883) (xy 364.273027 -396.537818) (xy 364.221051 -396.517994)
			(xy 364.172505 -396.490832) (xy 364.128419 -396.456906) (xy 364.089728 -396.416938) (xy 364.057251 -396.371774)
			(xy 364.031678 -396.322372) (xy 364.013551 -396.26978) (xy 364.007908 -396.24254) (xy 364.004352 -396.224252)
			(xy 363.976412 -396.201138) (xy 361.273598 -396.201138) (xy 361.245658 -396.22476) (xy 361.242356 -396.243048)
			(xy 361.236978 -396.270567) (xy 361.219223 -396.32375) (xy 361.193874 -396.373763) (xy 361.161479 -396.419526)
			(xy 361.122734 -396.460055) (xy 361.078474 -396.494477) (xy 361.029653 -396.52205) (xy 360.977322 -396.542181)
			(xy 360.922608 -396.554435) (xy 360.86669 -396.55855) (xy 360.810772 -396.554435) (xy 360.756058 -396.542181)
			(xy 360.703727 -396.52205) (xy 360.654906 -396.494477) (xy 360.610646 -396.460055) (xy 360.571901 -396.419526)
			(xy 360.539506 -396.373763) (xy 360.514157 -396.32375) (xy 360.496402 -396.270567) (xy 360.491024 -396.243048)
			(xy 360.487722 -396.22476) (xy 360.459782 -396.201138) (xy 358.619298 -396.201138) (xy 358.609229 -396.201562)
			(xy 358.590628 -396.209281) (xy 358.58323 -396.216124) (xy 358.26446 -396.534894) (xy 358.246421 -396.552157)
			(xy 358.204928 -396.57992) (xy 358.15881 -396.599038) (xy 358.109844 -396.608773) (xy 358.084882 -396.609316)
			(xy 349.829374 -396.609316) (xy 349.804418 -396.608702) (xy 349.755467 -396.598961) (xy 349.709355 -396.579857)
			(xy 349.667857 -396.552126) (xy 349.649796 -396.534894) (xy 349.449644 -396.334742) (xy 349.415354 -396.33017)
			(xy 349.400368 -396.33906) (xy 349.376776 -396.35221) (xy 349.326104 -396.370892) (xy 349.272939 -396.380384)
			(xy 349.245936 -396.38097) (xy 349.221942 -396.380526) (xy 349.174544 -396.373024) (xy 349.128904 -396.358198)
			(xy 349.086146 -396.336414) (xy 349.047323 -396.308208) (xy 349.01339 -396.274276) (xy 348.985185 -396.235452)
			(xy 348.963401 -396.192694) (xy 348.948576 -396.147054) (xy 348.941073 -396.099656) (xy 348.940628 -396.075662)
			(xy 348.941199 -396.048657) (xy 348.950685 -395.995487) (xy 348.96937 -395.944813) (xy 348.982538 -395.92123)
			(xy 348.991428 -395.906244) (xy 348.986856 -395.871954) (xy 348.35465 -395.239748) (xy 348.347251 -395.232904)
			(xy 348.328652 -395.22518) (xy 348.318582 -395.224762) (xy 347.881448 -395.224762) (xy 347.871383 -395.225196)
			(xy 347.852798 -395.232931) (xy 347.84538 -395.239748) (xy 347.140022 -395.945106) (xy 347.133418 -395.97203)
			(xy 347.137736 -395.985746) (xy 347.144004 -396.007566) (xy 347.150763 -396.052456) (xy 347.151198 -396.075154)
			(xy 347.151198 -396.075662) (xy 347.150755 -396.099657) (xy 347.143253 -396.147056) (xy 347.128427 -396.192698)
			(xy 347.106644 -396.235459) (xy 347.078439 -396.274285) (xy 347.044506 -396.30822) (xy 347.005683 -396.336429)
			(xy 346.962924 -396.358217) (xy 346.917284 -396.373046) (xy 346.869885 -396.380552) (xy 346.84589 -396.38097)
			(xy 346.845382 -396.38097) (xy 346.822684 -396.380538) (xy 346.777792 -396.373783) (xy 346.755974 -396.367508)
			(xy 346.742258 -396.36319) (xy 346.715334 -396.369794) (xy 346.234258 -396.85087) (xy 346.228407 -396.85661)
			(xy 346.216077 -396.867412) (xy 346.20962 -396.87246) (xy 346.202 -396.878302) (xy 346.192602 -396.893796)
			(xy 346.175838 -396.97787) (xy 346.178886 -396.99565) (xy 346.183458 -397.003778) (xy 346.191078 -397.017494)
			(xy 346.191586 -397.018764) (xy 346.284753 -397.179979) (xy 346.813611 -397.179979) (xy 346.813859 -397.129044)
			(xy 346.822553 -397.078855) (xy 346.83945 -397.030804) (xy 346.864083 -396.986221) (xy 346.89577 -396.946341)
			(xy 346.933633 -396.912269) (xy 346.976622 -396.884949) (xy 347.023547 -396.865138) (xy 347.073108 -396.853385)
			(xy 347.123932 -396.850014) (xy 347.174611 -396.85512) (xy 347.223742 -396.868562) (xy 347.269962 -396.889966)
			(xy 347.311992 -396.918739) (xy 347.348668 -396.954086) (xy 347.378973 -396.995025) (xy 347.390974 -397.017494)
			(xy 347.391482 -397.018764) (xy 347.457665 -397.133286) (xy 348.013624 -397.133286) (xy 348.020956 -397.085735)
			(xy 348.03565 -397.039922) (xy 348.057342 -396.996978) (xy 348.085497 -396.957964) (xy 348.119419 -396.923846)
			(xy 348.15827 -396.895466) (xy 348.201088 -396.873525) (xy 348.246815 -396.858567) (xy 348.294322 -396.850961)
			(xy 348.342434 -396.850894) (xy 348.389962 -396.858369) (xy 348.435731 -396.873201) (xy 348.47861 -396.895023)
			(xy 348.517538 -396.923296) (xy 348.551554 -396.95732) (xy 348.579817 -396.996256) (xy 348.591124 -397.017494)
			(xy 348.591632 -397.018764) (xy 348.657814 -397.133285) (xy 349.213528 -397.133285) (xy 349.220859 -397.085736)
			(xy 349.235553 -397.039923) (xy 349.257245 -396.99698) (xy 349.2854 -396.957967) (xy 349.319322 -396.923849)
			(xy 349.358171 -396.895469) (xy 349.400989 -396.873529) (xy 349.446716 -396.858571) (xy 349.494222 -396.850964)
			(xy 349.542333 -396.850898) (xy 349.58986 -396.858372) (xy 349.635629 -396.873204) (xy 349.678507 -396.895025)
			(xy 349.717435 -396.923297) (xy 349.751451 -396.957321) (xy 349.779713 -396.996256) (xy 349.79102 -397.017494)
			(xy 349.791528 -397.018764) (xy 349.85771 -397.133285) (xy 350.413431 -397.133285) (xy 350.420763 -397.085737)
			(xy 350.435456 -397.039924) (xy 350.457148 -396.996982) (xy 350.485303 -396.957969) (xy 350.519224 -396.923851)
			(xy 350.558073 -396.895472) (xy 350.60089 -396.873532) (xy 350.646616 -396.858574) (xy 350.694121 -396.850968)
			(xy 350.742232 -396.850901) (xy 350.789759 -396.858376) (xy 350.835526 -396.873207) (xy 350.878404 -396.895028)
			(xy 350.917331 -396.923299) (xy 350.951347 -396.957323) (xy 350.979609 -396.996257) (xy 350.990916 -397.017494)
			(xy 350.991424 -397.018764) (xy 351.084589 -397.179977) (xy 351.613718 -397.179977) (xy 351.613966 -397.129044)
			(xy 351.62266 -397.078857) (xy 351.639557 -397.030807) (xy 351.664189 -396.986225) (xy 351.695875 -396.946346)
			(xy 351.733736 -396.912275) (xy 351.776724 -396.884956) (xy 351.823648 -396.865145) (xy 351.873208 -396.853392)
			(xy 351.92403 -396.850021) (xy 351.974708 -396.855127) (xy 352.023837 -396.868568) (xy 352.070056 -396.88997)
			(xy 352.112086 -396.918743) (xy 352.14876 -396.954088) (xy 352.179065 -396.995026) (xy 352.191066 -397.017494)
			(xy 352.191574 -397.018764) (xy 352.284739 -397.179976) (xy 352.813621 -397.179976) (xy 352.81387 -397.129044)
			(xy 352.822563 -397.078857) (xy 352.83946 -397.030808) (xy 352.864092 -396.986227) (xy 352.895778 -396.946349)
			(xy 352.933638 -396.912278) (xy 352.976626 -396.88496) (xy 353.023549 -396.865149) (xy 353.073108 -396.853396)
			(xy 353.123929 -396.850025) (xy 353.174606 -396.85513) (xy 353.223735 -396.86857) (xy 353.269953 -396.889973)
			(xy 353.311982 -396.918745) (xy 353.348657 -396.954089) (xy 353.378961 -396.995027) (xy 353.390962 -397.017494)
			(xy 353.39147 -397.018764) (xy 353.457652 -397.133285) (xy 354.013635 -397.133285) (xy 354.020967 -397.085737)
			(xy 354.03566 -397.039926) (xy 354.057351 -396.996983) (xy 354.085505 -396.957971) (xy 354.119426 -396.923854)
			(xy 354.158274 -396.895475) (xy 354.20109 -396.873536) (xy 354.246816 -396.858578) (xy 354.294321 -396.850971)
			(xy 354.342431 -396.850905) (xy 354.389957 -396.858379) (xy 354.435724 -396.873209) (xy 354.478601 -396.89503)
			(xy 354.517528 -396.923301) (xy 354.551543 -396.957324) (xy 354.579805 -396.996257) (xy 354.591112 -397.017494)
			(xy 354.59162 -397.018764) (xy 354.657801 -397.133284) (xy 370.586149 -397.133284) (xy 370.593481 -397.085739)
			(xy 370.608173 -397.03993) (xy 370.629864 -396.996991) (xy 370.658016 -396.957981) (xy 370.691934 -396.923866)
			(xy 370.73078 -396.895488) (xy 370.773594 -396.87355) (xy 370.819317 -396.858592) (xy 370.866819 -396.850986)
			(xy 370.914926 -396.850918) (xy 370.962449 -396.858392) (xy 371.008214 -396.873221) (xy 371.051089 -396.895039)
			(xy 371.090014 -396.923308) (xy 371.124028 -396.957328) (xy 371.15229 -396.996259) (xy 371.163596 -397.017494)
			(xy 371.164104 -397.018764) (xy 371.230285 -397.133284) (xy 371.786053 -397.133284) (xy 371.793384 -397.08574)
			(xy 371.808077 -397.039932) (xy 371.829767 -396.996992) (xy 371.857919 -396.957983) (xy 371.891837 -396.923869)
			(xy 371.930682 -396.895491) (xy 371.973495 -396.873553) (xy 372.019217 -396.858596) (xy 372.066718 -396.850989)
			(xy 372.114825 -396.850922) (xy 372.162347 -396.858395) (xy 372.208111 -396.873224) (xy 372.250986 -396.895042)
			(xy 372.289911 -396.92331) (xy 372.323924 -396.957329) (xy 372.352186 -396.996259) (xy 372.363492 -397.017494)
			(xy 372.364 -397.018764) (xy 372.430181 -397.133284) (xy 372.985956 -397.133284) (xy 372.993288 -397.08574)
			(xy 373.00798 -397.039933) (xy 373.02967 -396.996994) (xy 373.057821 -396.957986) (xy 373.091739 -396.923872)
			(xy 373.130584 -396.895495) (xy 373.173396 -396.873557) (xy 373.219117 -396.858599) (xy 373.266618 -396.850993)
			(xy 373.314724 -396.850925) (xy 373.362246 -396.858398) (xy 373.408009 -396.873226) (xy 373.450883 -396.895044)
			(xy 373.489807 -396.923311) (xy 373.523821 -396.95733) (xy 373.552082 -396.996259) (xy 373.563388 -397.017494)
			(xy 373.563896 -397.018764) (xy 373.630079 -397.133286) (xy 374.186012 -397.133286) (xy 374.193344 -397.085734)
			(xy 374.208038 -397.039918) (xy 374.229732 -396.996971) (xy 374.257888 -396.957956) (xy 374.291812 -396.923836)
			(xy 374.330664 -396.895454) (xy 374.373485 -396.873513) (xy 374.419215 -396.858554) (xy 374.466724 -396.850948)
			(xy 374.514839 -396.850882) (xy 374.562369 -396.858358) (xy 374.60814 -396.873191) (xy 374.65102 -396.895015)
			(xy 374.68995 -396.92329) (xy 374.723968 -396.957317) (xy 374.752231 -396.996255) (xy 374.763538 -397.017494)
			(xy 374.764046 -397.018764) (xy 374.830229 -397.133286) (xy 375.385915 -397.133286) (xy 375.393247 -397.085734)
			(xy 375.407941 -397.039919) (xy 375.429635 -396.996973) (xy 375.457791 -396.957958) (xy 375.491714 -396.923839)
			(xy 375.530566 -396.895457) (xy 375.573385 -396.873516) (xy 375.619115 -396.858558) (xy 375.666624 -396.850952)
			(xy 375.714737 -396.850885) (xy 375.762267 -396.858361) (xy 375.808037 -396.873194) (xy 375.850917 -396.895017)
			(xy 375.889847 -396.923291) (xy 375.923864 -396.957318) (xy 375.952127 -396.996255) (xy 375.963434 -397.017494)
			(xy 375.963942 -397.018764) (xy 376.030123 -397.133284) (xy 376.58616 -397.133284) (xy 376.593491 -397.085741)
			(xy 376.608183 -397.039934) (xy 376.629873 -396.996996) (xy 376.658024 -396.957988) (xy 376.691941 -396.923874)
			(xy 376.730785 -396.895498) (xy 376.773597 -396.87356) (xy 376.819317 -396.858603) (xy 376.866817 -396.850997)
			(xy 376.914922 -396.850929) (xy 376.962444 -396.858401) (xy 377.008207 -396.873229) (xy 377.05108 -396.895046)
			(xy 377.090004 -396.923313) (xy 377.124017 -396.957331) (xy 377.152278 -396.99626) (xy 377.163584 -397.017494)
			(xy 377.164092 -397.018764) (xy 377.556014 -397.696944) (xy 377.556268 -397.697452) (xy 377.556522 -397.697452)
			(xy 377.557792 -397.699992) (xy 377.570062 -397.722908) (xy 377.587469 -397.771886) (xy 377.596344 -397.823101)
			(xy 377.596908 -397.84909) (xy 377.596908 -397.849344) (xy 377.596501 -397.873351) (xy 377.58898 -397.920772)
			(xy 377.57413 -397.966432) (xy 377.552317 -398.009206) (xy 377.524079 -398.048038) (xy 377.490111 -398.081973)
			(xy 377.451251 -398.110173) (xy 377.408457 -398.131944) (xy 377.362782 -398.14675) (xy 377.315353 -398.154225)
			(xy 377.291346 -398.154652) (xy 377.267683 -398.154176) (xy 377.220924 -398.146872) (xy 377.175849 -398.132448)
			(xy 377.133537 -398.111248) (xy 377.094998 -398.083778) (xy 377.061154 -398.050697) (xy 377.032815 -398.012794)
			(xy 377.021344 -397.992092) (xy 377.02109 -397.99133) (xy 376.623834 -397.304006) (xy 376.611654 -397.28079)
			(xy 376.59454 -397.231239) (xy 376.589798 -397.205454) (xy 376.589798 -397.2052) (xy 376.586371 -397.181389)
			(xy 376.58616 -397.133284) (xy 376.030123 -397.133284) (xy 376.355864 -397.696944) (xy 376.356118 -397.697452)
			(xy 376.356372 -397.697452) (xy 376.357642 -397.699992) (xy 376.369877 -397.722915) (xy 376.387196 -397.771902)
			(xy 376.395983 -397.823111) (xy 376.396504 -397.84909) (xy 376.396504 -397.849344) (xy 376.396078 -397.873337)
			(xy 376.388565 -397.92073) (xy 376.373731 -397.966365) (xy 376.351942 -398.009118) (xy 376.323733 -398.047937)
			(xy 376.2898 -398.081865) (xy 376.250977 -398.110067) (xy 376.208221 -398.13185) (xy 376.162583 -398.146676)
			(xy 376.115189 -398.154182) (xy 376.091196 -398.154652) (xy 376.067531 -398.154216) (xy 376.02077 -398.146905)
			(xy 375.975695 -398.132473) (xy 375.933382 -398.111266) (xy 375.894844 -398.083791) (xy 375.861002 -398.050704)
			(xy 375.832664 -398.012796) (xy 375.821194 -397.992092) (xy 375.82094 -397.99133) (xy 375.423684 -397.304006)
			(xy 375.411508 -397.280788) (xy 375.394391 -397.231238) (xy 375.389648 -397.205454) (xy 375.389648 -397.2052)
			(xy 375.386127 -397.181399) (xy 375.385915 -397.133286) (xy 374.830229 -397.133286) (xy 375.155968 -397.696944)
			(xy 375.156222 -397.697452) (xy 375.156476 -397.697452) (xy 375.157746 -397.699992) (xy 375.169981 -397.722915)
			(xy 375.1873 -397.771902) (xy 375.196087 -397.823111) (xy 375.196608 -397.84909) (xy 375.196608 -397.849344)
			(xy 375.196178 -397.873336) (xy 375.188665 -397.92073) (xy 375.173832 -397.966364) (xy 375.152043 -398.009117)
			(xy 375.123835 -398.047935) (xy 375.089902 -398.081863) (xy 375.051079 -398.110066) (xy 375.008324 -398.131849)
			(xy 374.962687 -398.146676) (xy 374.915292 -398.154181) (xy 374.8913 -398.154652) (xy 374.867636 -398.154213)
			(xy 374.820875 -398.146902) (xy 374.775799 -398.132471) (xy 374.733487 -398.111265) (xy 374.694949 -398.08379)
			(xy 374.661106 -398.050703) (xy 374.632768 -398.012796) (xy 374.621298 -397.992092) (xy 374.621044 -397.99133)
			(xy 374.223788 -397.304006) (xy 374.211612 -397.280788) (xy 374.194495 -397.231238) (xy 374.189752 -397.205454)
			(xy 374.189752 -397.2052) (xy 374.186223 -397.1814) (xy 374.186012 -397.133286) (xy 373.630079 -397.133286)
			(xy 373.955818 -397.696944) (xy 373.956072 -397.697452) (xy 373.956326 -397.697452) (xy 373.957596 -397.699992)
			(xy 373.969867 -397.722908) (xy 373.987274 -397.771886) (xy 373.996148 -397.823101) (xy 373.996712 -397.84909)
			(xy 373.996712 -397.849344) (xy 373.996302 -397.873351) (xy 373.98878 -397.920772) (xy 373.973931 -397.966432)
			(xy 373.952118 -398.009205) (xy 373.92388 -398.048037) (xy 373.889913 -398.081971) (xy 373.851053 -398.110172)
			(xy 373.808259 -398.131943) (xy 373.762586 -398.146749) (xy 373.715157 -398.154225) (xy 373.69115 -398.154652)
			(xy 373.667487 -398.154172) (xy 373.620728 -398.146869) (xy 373.575653 -398.132446) (xy 373.533341 -398.111246)
			(xy 373.494802 -398.083777) (xy 373.460959 -398.050696) (xy 373.432619 -398.012793) (xy 373.421148 -397.992092)
			(xy 373.420894 -397.99133) (xy 373.023638 -397.304006) (xy 373.011458 -397.28079) (xy 372.994344 -397.231239)
			(xy 372.989602 -397.205454) (xy 372.989602 -397.2052) (xy 372.986167 -397.181389) (xy 372.985956 -397.133284)
			(xy 372.430181 -397.133284) (xy 372.755922 -397.696944) (xy 372.756176 -397.697452) (xy 372.75643 -397.697452)
			(xy 372.7577 -397.699992) (xy 372.769971 -397.722908) (xy 372.787378 -397.771886) (xy 372.796252 -397.823101)
			(xy 372.796816 -397.84909) (xy 372.796816 -397.849344) (xy 372.796402 -397.873351) (xy 372.788881 -397.920771)
			(xy 372.774031 -397.966431) (xy 372.752219 -398.009203) (xy 372.723981 -398.048036) (xy 372.690015 -398.08197)
			(xy 372.651156 -398.110171) (xy 372.608362 -398.131942) (xy 372.562689 -398.146748) (xy 372.515261 -398.154224)
			(xy 372.491254 -398.154652) (xy 372.467591 -398.154169) (xy 372.420832 -398.146867) (xy 372.375758 -398.132444)
			(xy 372.333445 -398.111245) (xy 372.294907 -398.083776) (xy 372.261063 -398.050696) (xy 372.232723 -398.012793)
			(xy 372.221252 -397.992092) (xy 372.220998 -397.99133) (xy 371.823742 -397.304006) (xy 371.811563 -397.280789)
			(xy 371.794448 -397.231239) (xy 371.789706 -397.205454) (xy 371.789706 -397.2052) (xy 371.786264 -397.18139)
			(xy 371.786053 -397.133284) (xy 371.230285 -397.133284) (xy 371.556026 -397.696944) (xy 371.55628 -397.697452)
			(xy 371.556534 -397.697452) (xy 371.557804 -397.699992) (xy 371.570075 -397.722908) (xy 371.587482 -397.771886)
			(xy 371.596356 -397.823101) (xy 371.59692 -397.84909) (xy 371.59692 -397.849344) (xy 371.596502 -397.87335)
			(xy 371.588981 -397.920771) (xy 371.574131 -397.96643) (xy 371.552319 -398.009202) (xy 371.524082 -398.048034)
			(xy 371.490116 -398.081969) (xy 371.451258 -398.110169) (xy 371.408465 -398.131941) (xy 371.362792 -398.146748)
			(xy 371.315365 -398.154224) (xy 371.291358 -398.154652) (xy 371.267695 -398.154166) (xy 371.220936 -398.146864)
			(xy 371.175862 -398.132442) (xy 371.13355 -398.111243) (xy 371.095011 -398.083775) (xy 371.061167 -398.050695)
			(xy 371.032827 -398.012793) (xy 371.021356 -397.992092) (xy 371.021102 -397.99133) (xy 370.623846 -397.304006)
			(xy 370.611667 -397.280789) (xy 370.594552 -397.231239) (xy 370.58981 -397.205454) (xy 370.58981 -397.2052)
			(xy 370.58636 -397.181391) (xy 370.586149 -397.133284) (xy 354.657801 -397.133284) (xy 354.983542 -397.696944)
			(xy 354.983796 -397.697452) (xy 354.98405 -397.697452) (xy 354.98532 -397.699992) (xy 354.997593 -397.722907)
			(xy 355.014998 -397.771885) (xy 355.023872 -397.823101) (xy 355.024436 -397.84909) (xy 355.024436 -397.849344)
			(xy 355.024002 -397.87335) (xy 355.016481 -397.920768) (xy 355.001633 -397.966426) (xy 354.979822 -398.009197)
			(xy 354.951587 -398.048029) (xy 354.917623 -398.081963) (xy 354.878767 -398.110164) (xy 354.835976 -398.131936)
			(xy 354.790305 -398.146744) (xy 354.74288 -398.154223) (xy 354.718874 -398.154652) (xy 354.695212 -398.154153)
			(xy 354.648453 -398.146854) (xy 354.603379 -398.132433) (xy 354.561067 -398.111237) (xy 354.522528 -398.083771)
			(xy 354.488684 -398.050693) (xy 354.460343 -398.012792) (xy 354.448872 -397.992092) (xy 354.448618 -397.99133)
			(xy 354.051362 -397.304006) (xy 354.039184 -397.280789) (xy 354.022068 -397.231239) (xy 354.017326 -397.205454)
			(xy 354.017326 -397.2052) (xy 354.013846 -397.181395) (xy 354.013635 -397.133285) (xy 353.457652 -397.133285)
			(xy 353.783392 -397.696944) (xy 353.783646 -397.697452) (xy 353.7839 -397.697452) (xy 353.78517 -397.699992)
			(xy 353.797399 -397.722918) (xy 353.814722 -397.771903) (xy 353.82351 -397.823111) (xy 353.824032 -397.84909)
			(xy 353.824032 -397.849344) (xy 353.823578 -397.873335) (xy 353.816066 -397.920726) (xy 353.801234 -397.966359)
			(xy 353.779447 -398.00911) (xy 353.751242 -398.047927) (xy 353.717312 -398.081855) (xy 353.678493 -398.110058)
			(xy 353.63574 -398.131842) (xy 353.590107 -398.146671) (xy 353.542715 -398.15418) (xy 353.518724 -398.154652)
			(xy 353.49506 -398.154193) (xy 353.4483 -398.146886) (xy 353.403225 -398.132459) (xy 353.360913 -398.111256)
			(xy 353.322374 -398.083784) (xy 353.288531 -398.0507) (xy 353.260193 -398.012795) (xy 353.248722 -397.992092)
			(xy 353.248468 -397.99133) (xy 352.851212 -397.304006) (xy 352.839031 -397.28079) (xy 352.821918 -397.231239)
			(xy 352.817176 -397.205454) (xy 352.817176 -397.2052) (xy 352.813621 -397.179976) (xy 352.284739 -397.179976)
			(xy 352.583496 -397.696944) (xy 352.58375 -397.697452) (xy 352.584004 -397.697452) (xy 352.585274 -397.699992)
			(xy 352.597504 -397.722918) (xy 352.614826 -397.771903) (xy 352.623614 -397.823111) (xy 352.624136 -397.84909)
			(xy 352.624136 -397.849344) (xy 352.623678 -397.873335) (xy 352.616166 -397.920726) (xy 352.601335 -397.966358)
			(xy 352.579548 -398.009109) (xy 352.551343 -398.047926) (xy 352.517413 -398.081853) (xy 352.478595 -398.110056)
			(xy 352.435843 -398.131841) (xy 352.39021 -398.14667) (xy 352.342819 -398.154179) (xy 352.318828 -398.154652)
			(xy 352.295164 -398.15419) (xy 352.248404 -398.146884) (xy 352.203329 -398.132457) (xy 352.161017 -398.111254)
			(xy 352.122479 -398.083783) (xy 352.088636 -398.050699) (xy 352.060297 -398.012794) (xy 352.048826 -397.992092)
			(xy 352.048572 -397.99133) (xy 351.651316 -397.304006) (xy 351.639135 -397.28079) (xy 351.622022 -397.231239)
			(xy 351.61728 -397.205454) (xy 351.61728 -397.2052) (xy 351.613718 -397.179977) (xy 351.084589 -397.179977)
			(xy 351.383346 -397.696944) (xy 351.3836 -397.697452) (xy 351.383854 -397.697452) (xy 351.385124 -397.699992)
			(xy 351.397397 -397.722907) (xy 351.414802 -397.771885) (xy 351.423676 -397.823101) (xy 351.42424 -397.84909)
			(xy 351.42424 -397.849344) (xy 351.423802 -397.873349) (xy 351.416281 -397.920768) (xy 351.401433 -397.966425)
			(xy 351.379623 -398.009196) (xy 351.351388 -398.048027) (xy 351.317425 -398.081961) (xy 351.278569 -398.110162)
			(xy 351.235779 -398.131935) (xy 351.190109 -398.146744) (xy 351.142684 -398.154222) (xy 351.118678 -398.154652)
			(xy 351.095013 -398.15423) (xy 351.048251 -398.146916) (xy 351.003175 -398.132482) (xy 350.960863 -398.111273)
			(xy 350.922325 -398.083796) (xy 350.888483 -398.050707) (xy 350.860146 -398.012797) (xy 350.848676 -397.992092)
			(xy 350.848422 -397.99133) (xy 350.451166 -397.304006) (xy 350.438988 -397.280789) (xy 350.421872 -397.231239)
			(xy 350.41713 -397.205454) (xy 350.41713 -397.2052) (xy 350.413643 -397.181396) (xy 350.413431 -397.133285)
			(xy 349.85771 -397.133285) (xy 350.18345 -397.696944) (xy 350.183704 -397.697452) (xy 350.183958 -397.697452)
			(xy 350.185228 -397.699992) (xy 350.197501 -397.722907) (xy 350.214906 -397.771885) (xy 350.22378 -397.823101)
			(xy 350.224344 -397.84909) (xy 350.224344 -397.849344) (xy 350.223902 -397.873349) (xy 350.216382 -397.920767)
			(xy 350.201534 -397.966424) (xy 350.179724 -398.009195) (xy 350.15149 -398.048026) (xy 350.117526 -398.08196)
			(xy 350.078671 -398.110161) (xy 350.035882 -398.131934) (xy 349.990212 -398.146743) (xy 349.942788 -398.154222)
			(xy 349.918782 -398.154652) (xy 349.895117 -398.154227) (xy 349.848355 -398.146914) (xy 349.80328 -398.13248)
			(xy 349.760967 -398.111272) (xy 349.722429 -398.083795) (xy 349.688587 -398.050706) (xy 349.66025 -398.012797)
			(xy 349.64878 -397.992092) (xy 349.648526 -397.99133) (xy 349.25127 -397.304006) (xy 349.239093 -397.280789)
			(xy 349.221977 -397.231238) (xy 349.217234 -397.205454) (xy 349.217234 -397.2052) (xy 349.213739 -397.181396)
			(xy 349.213528 -397.133285) (xy 348.657814 -397.133285) (xy 348.983554 -397.696944) (xy 348.983808 -397.697452)
			(xy 348.984062 -397.697452) (xy 348.985332 -397.699992) (xy 348.997606 -397.722907) (xy 349.015011 -397.771885)
			(xy 349.023884 -397.823101) (xy 349.024448 -397.84909) (xy 349.024448 -397.849344) (xy 349.024002 -397.873349)
			(xy 349.016482 -397.920767) (xy 349.001634 -397.966423) (xy 348.979825 -398.009194) (xy 348.951591 -398.048025)
			(xy 348.917628 -398.081959) (xy 348.878773 -398.11016) (xy 348.835984 -398.131933) (xy 348.790315 -398.146742)
			(xy 348.742891 -398.154222) (xy 348.718886 -398.154652) (xy 348.695221 -398.154224) (xy 348.64846 -398.146911)
			(xy 348.603384 -398.132478) (xy 348.561072 -398.11127) (xy 348.522534 -398.083794) (xy 348.488692 -398.050705)
			(xy 348.460354 -398.012796) (xy 348.448884 -397.992092) (xy 348.44863 -397.99133) (xy 348.051374 -397.304006)
			(xy 348.039197 -397.280788) (xy 348.022081 -397.231238) (xy 348.017338 -397.205454) (xy 348.017338 -397.2052)
			(xy 348.013836 -397.181397) (xy 348.013624 -397.133286) (xy 347.457665 -397.133286) (xy 347.783404 -397.696944)
			(xy 347.783658 -397.697452) (xy 347.783912 -397.697452) (xy 347.785182 -397.699992) (xy 347.797412 -397.722918)
			(xy 347.814734 -397.771903) (xy 347.823522 -397.823111) (xy 347.824044 -397.84909) (xy 347.824044 -397.849344)
			(xy 347.823578 -397.873335) (xy 347.816067 -397.920724) (xy 347.801235 -397.966356) (xy 347.779449 -398.009106)
			(xy 347.751245 -398.047923) (xy 347.717317 -398.08185) (xy 347.678499 -398.110054) (xy 347.635749 -398.131838)
			(xy 347.590117 -398.146668) (xy 347.542727 -398.154179) (xy 347.518736 -398.154652) (xy 347.495073 -398.154184)
			(xy 347.448313 -398.146878) (xy 347.403238 -398.132453) (xy 347.360926 -398.111251) (xy 347.322387 -398.083781)
			(xy 347.288544 -398.050698) (xy 347.260205 -398.012794) (xy 347.248734 -397.992092) (xy 347.24848 -397.99133)
			(xy 346.851224 -397.304006) (xy 346.839044 -397.28079) (xy 346.82193 -397.231239) (xy 346.817188 -397.205454)
			(xy 346.817188 -397.2052) (xy 346.813611 -397.179979) (xy 346.284753 -397.179979) (xy 346.583508 -397.696944)
			(xy 346.583762 -397.697452) (xy 346.584016 -397.697452) (xy 346.585286 -397.699992) (xy 346.597519 -397.722917)
			(xy 346.614853 -397.7719) (xy 346.623639 -397.82311) (xy 346.624148 -397.84909) (xy 346.624148 -397.849344)
			(xy 346.623674 -397.873334) (xy 346.616163 -397.920723) (xy 346.601332 -397.966354) (xy 346.579547 -398.009103)
			(xy 346.551343 -398.047919) (xy 346.517416 -398.081846) (xy 346.4786 -398.110049) (xy 346.43585 -398.131834)
			(xy 346.390219 -398.146664) (xy 346.34283 -398.154174) (xy 346.31884 -398.154652) (xy 346.295174 -398.154211)
			(xy 346.248407 -398.146916) (xy 346.203326 -398.132494) (xy 346.161008 -398.111291) (xy 346.122468 -398.083814)
			(xy 346.088628 -398.050721) (xy 346.060297 -398.012803) (xy 346.048838 -397.992092) (xy 346.048584 -397.99133)
			(xy 345.651328 -397.304006) (xy 345.639141 -397.280793) (xy 345.622036 -397.231239) (xy 345.617292 -397.205454)
			(xy 345.617292 -397.2052) (xy 345.6139 -397.181838) (xy 345.613521 -397.134634) (xy 345.61653 -397.11122)
			(xy 345.6178 -397.10233) (xy 345.614498 -397.085058) (xy 345.57081 -397.013938) (xy 345.557094 -397.002762)
			(xy 345.548458 -396.999968) (xy 345.529062 -396.993077) (xy 345.492179 -396.974804) (xy 345.458095 -396.951727)
			(xy 345.44254 -396.938246) (xy 345.435345 -396.932386) (xy 345.418027 -396.92576) (xy 345.408758 -396.925292)
			(xy 345.02598 -396.925292) (xy 345.015974 -396.925784) (xy 344.997488 -396.933446) (xy 344.98334 -396.947598)
			(xy 344.975681 -396.966086) (xy 344.97518 -396.976092) (xy 344.97518 -396.989808) (xy 344.982292 -397.001746)
			(xy 344.990928 -397.017494) (xy 344.991436 -397.018764) (xy 345.383358 -397.696944) (xy 345.383612 -397.697452)
			(xy 345.383866 -397.697452) (xy 345.385136 -397.699992) (xy 345.397405 -397.722909) (xy 345.414816 -397.771885)
			(xy 345.423685 -397.823101) (xy 345.424252 -397.84909) (xy 345.424252 -397.849344) (xy 345.423779 -397.873322)
			(xy 345.416276 -397.920686) (xy 345.40146 -397.966295) (xy 345.379697 -398.009028) (xy 345.351522 -398.047833)
			(xy 345.317627 -398.081757) (xy 345.278845 -398.109964) (xy 345.23613 -398.131763) (xy 345.190533 -398.146616)
			(xy 345.143175 -398.154159) (xy 345.119198 -398.154652) (xy 345.11869 -398.154652) (xy 345.095026 -398.154207)
			(xy 345.048264 -398.146906) (xy 345.003188 -398.132479) (xy 344.960877 -398.111272) (xy 344.922343 -398.083793)
			(xy 344.888509 -398.050699) (xy 344.860184 -398.012782) (xy 344.848688 -397.992092) (xy 344.848434 -397.99133)
			(xy 344.451178 -397.304006) (xy 344.43899 -397.280794) (xy 344.421881 -397.23124) (xy 344.417142 -397.205454)
			(xy 344.417142 -397.2052) (xy 344.413749 -397.181838) (xy 344.413371 -397.134634) (xy 344.41638 -397.11122)
			(xy 344.417904 -397.10233) (xy 344.414348 -397.084804) (xy 344.370914 -397.013938) (xy 344.356944 -397.002762)
			(xy 344.348562 -396.999968) (xy 344.329166 -396.993078) (xy 344.292283 -396.974804) (xy 344.258198 -396.951727)
			(xy 344.242644 -396.938246) (xy 344.235449 -396.932386) (xy 344.218131 -396.925758) (xy 344.208862 -396.925292)
			(xy 343.826084 -396.925292) (xy 343.816078 -396.925783) (xy 343.79759 -396.933445) (xy 343.78344 -396.947597)
			(xy 343.775781 -396.966086) (xy 343.775284 -396.976092) (xy 343.775284 -396.989808) (xy 343.782396 -397.001746)
			(xy 343.791032 -397.017494) (xy 343.79154 -397.018764) (xy 344.183462 -397.696944) (xy 344.183716 -397.697452)
			(xy 344.18397 -397.697452) (xy 344.18524 -397.699992) (xy 344.197509 -397.722909) (xy 344.21492 -397.771885)
			(xy 344.223788 -397.823101) (xy 344.224356 -397.84909) (xy 344.224356 -397.849344) (xy 344.223883 -397.873322)
			(xy 344.21638 -397.920686) (xy 344.201565 -397.966296) (xy 344.179802 -398.009029) (xy 344.151626 -398.047834)
			(xy 344.117731 -398.081758) (xy 344.078949 -398.109967) (xy 344.036235 -398.131766) (xy 343.990638 -398.146619)
			(xy 343.943279 -398.154163) (xy 343.919302 -398.154652) (xy 343.918794 -398.154652) (xy 343.89513 -398.154207)
			(xy 343.848368 -398.146906) (xy 343.803291 -398.13248) (xy 343.760979 -398.111273) (xy 343.722445 -398.083794)
			(xy 343.68861 -398.0507) (xy 343.660285 -398.012784) (xy 343.648792 -397.992092) (xy 343.648538 -397.99133)
			(xy 343.251282 -397.304006) (xy 343.239093 -397.280794) (xy 343.221985 -397.23124) (xy 343.217246 -397.205454)
			(xy 343.217246 -397.2052) (xy 343.213853 -397.181838) (xy 343.213475 -397.134634) (xy 343.216484 -397.11122)
			(xy 343.217754 -397.10233) (xy 343.214452 -397.085058) (xy 343.170764 -397.013938) (xy 343.157048 -397.002762)
			(xy 343.148412 -396.999968) (xy 343.127556 -396.992527) (xy 343.088081 -396.972464) (xy 343.051934 -396.946887)
			(xy 343.035636 -396.931896) (xy 343.030531 -396.927308) (xy 343.018418 -396.920861) (xy 343.01176 -396.919196)
			(xy 342.988451 -396.913444) (xy 342.944379 -396.894415) (xy 342.904661 -396.867453) (xy 342.8873 -396.85087)
			(xy 342.450674 -396.414244) (xy 342.433414 -396.396203) (xy 342.405657 -396.35471) (xy 342.386545 -396.308591)
			(xy 342.376814 -396.259627) (xy 342.376252 -396.234666) (xy 342.376252 -394.415772) (xy 342.376055 -394.409105)
			(xy 342.372576 -394.396234) (xy 342.369394 -394.390372) (xy 342.051386 -393.839954) (xy 342.039491 -393.817285)
			(xy 342.022622 -393.768954) (xy 342.014069 -393.718483) (xy 342.01354 -393.692888) (xy 342.01354 -393.69238)
			(xy 342.013988 -393.668389) (xy 342.021497 -393.620999) (xy 342.036328 -393.575367) (xy 342.058115 -393.532617)
			(xy 342.086322 -393.493802) (xy 342.120254 -393.459878) (xy 342.159075 -393.43168) (xy 342.20183 -393.409902)
			(xy 342.247465 -393.395081) (xy 342.294857 -393.387582) (xy 342.318848 -393.387072) (xy 342.324436 -393.387072)
			(xy 342.361012 -393.351258) (xy 342.367966 -393.343835) (xy 342.375843 -393.325099) (xy 342.376252 -393.314936)
			(xy 342.376252 -392.652504) (xy 342.375828 -392.642435) (xy 342.368109 -392.623834) (xy 342.361266 -392.616436)
			(xy 342.162638 -392.417808) (xy 342.155237 -392.41097) (xy 342.136638 -392.403257) (xy 342.12657 -392.402822)
			(xy 332.87462 -392.402822) (xy 332.8416 -392.415014) (xy 332.820758 -392.432227) (xy 332.775138 -392.461221)
			(xy 332.725885 -392.483489) (xy 332.673982 -392.498587) (xy 332.620469 -392.506212) (xy 332.566415 -392.506212)
			(xy 332.512902 -392.498587) (xy 332.460999 -392.483489) (xy 332.411746 -392.461221) (xy 332.366126 -392.432227)
			(xy 332.345284 -392.415014) (xy 332.312264 -392.402822) (xy 330.129642 -392.402822) (xy 330.119577 -392.403256)
			(xy 330.10099 -392.410988) (xy 330.093574 -392.417808) (xy 329.571858 -392.939524) (xy 329.565009 -392.946921)
			(xy 329.557274 -392.96552) (xy 329.556872 -392.975592) (xy 329.556872 -393.692888) (xy 336.013552 -393.692888)
			(xy 336.013552 -393.69238) (xy 336.014044 -393.66839) (xy 336.021552 -393.621002) (xy 336.03638 -393.575371)
			(xy 336.058162 -393.532621) (xy 336.086363 -393.493804) (xy 336.120289 -393.459876) (xy 336.159104 -393.431673)
			(xy 336.201852 -393.409887) (xy 336.247482 -393.395057) (xy 336.29487 -393.387546) (xy 336.31886 -393.387072)
			(xy 336.342795 -393.387531) (xy 336.39008 -393.39499) (xy 336.435623 -393.409733) (xy 336.47831 -393.431398)
			(xy 336.517095 -393.459455) (xy 336.551031 -393.493217) (xy 336.579285 -393.531859) (xy 336.59064 -393.552934)
			(xy 336.591148 -393.55395) (xy 336.671454 -393.692888) (xy 337.213448 -393.692888) (xy 337.213448 -393.69238)
			(xy 337.213944 -393.66839) (xy 337.221452 -393.621002) (xy 337.236279 -393.575372) (xy 337.258061 -393.532622)
			(xy 337.286262 -393.493805) (xy 337.320187 -393.459878) (xy 337.359001 -393.431674) (xy 337.401749 -393.409888)
			(xy 337.447379 -393.395057) (xy 337.494766 -393.387546) (xy 337.518756 -393.387072) (xy 337.542691 -393.387534)
			(xy 337.589976 -393.394993) (xy 337.635519 -393.409735) (xy 337.678205 -393.431399) (xy 337.716991 -393.459456)
			(xy 337.750926 -393.493218) (xy 337.779181 -393.531859) (xy 337.790536 -393.552934) (xy 337.791044 -393.55395)
			(xy 337.87135 -393.692888) (xy 338.413344 -393.692888) (xy 338.413344 -393.69238) (xy 338.413844 -393.668391)
			(xy 338.421352 -393.621003) (xy 338.436179 -393.575373) (xy 338.457961 -393.532623) (xy 338.486161 -393.493807)
			(xy 338.520086 -393.459879) (xy 338.558899 -393.431675) (xy 338.601647 -393.40989) (xy 338.647276 -393.395058)
			(xy 338.694663 -393.387546) (xy 338.718652 -393.387072) (xy 338.718906 -393.387072) (xy 338.742839 -393.387575)
			(xy 338.790122 -393.395026) (xy 338.835664 -393.40976) (xy 338.878351 -393.431418) (xy 338.917137 -393.459468)
			(xy 338.951074 -393.493225) (xy 338.97933 -393.531861) (xy 338.990686 -393.552934) (xy 338.991194 -393.55395)
			(xy 339.0715 -393.692888) (xy 339.61324 -393.692888) (xy 339.61324 -393.69238) (xy 339.613621 -393.668371)
			(xy 339.62114 -393.620946) (xy 339.63599 -393.575282) (xy 339.657804 -393.532506) (xy 339.686045 -393.493671)
			(xy 339.720016 -393.459735) (xy 339.758881 -393.431535) (xy 339.80168 -393.409766) (xy 339.84736 -393.394965)
			(xy 339.894793 -393.387496) (xy 339.918802 -393.387072) (xy 339.942735 -393.387578) (xy 339.990018 -393.395028)
			(xy 340.03556 -393.409763) (xy 340.078247 -393.43142) (xy 340.117033 -393.459469) (xy 340.15097 -393.493225)
			(xy 340.179226 -393.531861) (xy 340.190582 -393.552934) (xy 340.19109 -393.55395) (xy 340.271396 -393.692888)
			(xy 340.813136 -393.692888) (xy 340.813136 -393.69238) (xy 340.813521 -393.668371) (xy 340.82104 -393.620947)
			(xy 340.835889 -393.575283) (xy 340.857703 -393.532507) (xy 340.885944 -393.493672) (xy 340.919915 -393.459737)
			(xy 340.958779 -393.431537) (xy 341.001577 -393.409767) (xy 341.047256 -393.394965) (xy 341.094689 -393.387496)
			(xy 341.118698 -393.387072) (xy 341.142634 -393.3875) (xy 341.189921 -393.394965) (xy 341.235464 -393.409713)
			(xy 341.278151 -393.431383) (xy 341.316936 -393.459445) (xy 341.35087 -393.493212) (xy 341.379124 -393.531857)
			(xy 341.390478 -393.552934) (xy 341.390986 -393.55395) (xy 341.783416 -394.232892) (xy 341.796168 -394.256248)
			(xy 341.814276 -394.306281) (xy 341.823478 -394.358688) (xy 341.824056 -394.385292) (xy 341.82353 -394.409281)
			(xy 341.816027 -394.456667) (xy 341.801203 -394.502297) (xy 341.779425 -394.545047) (xy 341.751228 -394.583863)
			(xy 341.717306 -394.617791) (xy 341.678494 -394.645996) (xy 341.635749 -394.667782) (xy 341.590122 -394.682614)
			(xy 341.542737 -394.690126) (xy 341.518748 -394.6906) (xy 341.495175 -394.690168) (xy 341.448589 -394.682933)
			(xy 341.403671 -394.668614) (xy 341.361493 -394.647552) (xy 341.323059 -394.620248) (xy 341.289286 -394.587354)
			(xy 341.260979 -394.549654) (xy 341.249508 -394.529056) (xy 341.249 -394.528294) (xy 340.851236 -393.839954)
			(xy 340.839305 -393.817294) (xy 340.822372 -393.768964) (xy 340.813719 -393.718491) (xy 340.813136 -393.692888)
			(xy 340.271396 -393.692888) (xy 340.58352 -394.232892) (xy 340.596272 -394.256248) (xy 340.61438 -394.306281)
			(xy 340.623582 -394.358688) (xy 340.62416 -394.385292) (xy 340.623754 -394.409287) (xy 340.616247 -394.456687)
			(xy 340.601417 -394.502329) (xy 340.579628 -394.545088) (xy 340.551418 -394.583912) (xy 340.517482 -394.617844)
			(xy 340.478654 -394.646049) (xy 340.435892 -394.667832) (xy 340.390248 -394.682657) (xy 340.342847 -394.690157)
			(xy 340.318852 -394.6906) (xy 340.295279 -394.690164) (xy 340.248693 -394.682931) (xy 340.203776 -394.668612)
			(xy 340.161597 -394.647551) (xy 340.123164 -394.620247) (xy 340.089391 -394.587354) (xy 340.061083 -394.549653)
			(xy 340.049612 -394.529056) (xy 340.049104 -394.528294) (xy 339.65134 -393.839954) (xy 339.639409 -393.817293)
			(xy 339.622476 -393.768964) (xy 339.613823 -393.718491) (xy 339.61324 -393.692888) (xy 339.0715 -393.692888)
			(xy 339.383624 -394.232892) (xy 339.396376 -394.256248) (xy 339.414484 -394.30628) (xy 339.423686 -394.358688)
			(xy 339.424264 -394.385292) (xy 339.423854 -394.409287) (xy 339.416347 -394.456687) (xy 339.401517 -394.502328)
			(xy 339.379729 -394.545087) (xy 339.351519 -394.583911) (xy 339.317583 -394.617843) (xy 339.278756 -394.646048)
			(xy 339.235995 -394.667831) (xy 339.190352 -394.682656) (xy 339.142951 -394.690157) (xy 339.118956 -394.6906)
			(xy 339.118702 -394.6906) (xy 339.095128 -394.690205) (xy 339.04854 -394.682963) (xy 339.003621 -394.668638)
			(xy 338.961443 -394.64757) (xy 338.92301 -394.62026) (xy 338.889238 -394.587361) (xy 338.860933 -394.549656)
			(xy 338.849462 -394.529056) (xy 338.848954 -394.528294) (xy 338.45119 -393.839954) (xy 338.439334 -393.817267)
			(xy 338.422475 -393.768939) (xy 338.413894 -393.718479) (xy 338.413344 -393.692888) (xy 337.87135 -393.692888)
			(xy 338.183474 -394.232892) (xy 338.196301 -394.256223) (xy 338.21452 -394.306247) (xy 338.223779 -394.358673)
			(xy 338.224368 -394.385292) (xy 338.223953 -394.4093) (xy 338.216439 -394.456723) (xy 338.201593 -394.502386)
			(xy 338.179783 -394.545162) (xy 338.151546 -394.583996) (xy 338.117579 -394.617932) (xy 338.078717 -394.646133)
			(xy 338.035921 -394.667903) (xy 337.990245 -394.682706) (xy 337.942814 -394.690176) (xy 337.918806 -394.6906)
			(xy 337.895232 -394.690201) (xy 337.848644 -394.682961) (xy 337.803726 -394.668636) (xy 337.761547 -394.647568)
			(xy 337.723114 -394.620259) (xy 337.689342 -394.58736) (xy 337.661037 -394.549655) (xy 337.649566 -394.529056)
			(xy 337.649058 -394.528294) (xy 337.251294 -393.839954) (xy 337.239438 -393.817267) (xy 337.222579 -393.768939)
			(xy 337.213998 -393.718479) (xy 337.213448 -393.692888) (xy 336.671454 -393.692888) (xy 336.983578 -394.232892)
			(xy 336.996406 -394.256223) (xy 337.014624 -394.306247) (xy 337.023883 -394.358673) (xy 337.024472 -394.385292)
			(xy 337.024053 -394.409299) (xy 337.016539 -394.456723) (xy 337.001694 -394.502385) (xy 336.979884 -394.545161)
			(xy 336.951648 -394.583995) (xy 336.91768 -394.617931) (xy 336.87882 -394.646132) (xy 336.836024 -394.667902)
			(xy 336.790348 -394.682705) (xy 336.742918 -394.690175) (xy 336.71891 -394.6906) (xy 336.695336 -394.690198)
			(xy 336.648748 -394.682958) (xy 336.60383 -394.668634) (xy 336.561652 -394.647566) (xy 336.523218 -394.620258)
			(xy 336.489447 -394.58736) (xy 336.461141 -394.549655) (xy 336.44967 -394.529056) (xy 336.449162 -394.528294)
			(xy 336.051398 -393.839954) (xy 336.039542 -393.817267) (xy 336.022683 -393.768939) (xy 336.014102 -393.718479)
			(xy 336.013552 -393.692888) (xy 329.556872 -393.692888) (xy 329.556872 -394.14196) (xy 329.556295 -394.166918)
			(xy 329.546545 -394.215873) (xy 329.527432 -394.261985) (xy 329.49969 -394.303482) (xy 329.48245 -394.321538)
			(xy 327.906634 -395.897354) (xy 327.888592 -395.914611) (xy 327.847097 -395.942364) (xy 327.800979 -395.961472)
			(xy 327.752016 -395.9712) (xy 327.727056 -395.971776) (xy 325.906384 -395.971776) (xy 325.896315 -395.972201)
			(xy 325.877712 -395.979917) (xy 325.870316 -395.986762) (xy 325.685404 -396.171674) (xy 329.428856 -396.171674)
			(xy 329.428856 -395.308074) (xy 329.429342 -395.280823) (xy 329.437098 -395.226875) (xy 329.452453 -395.17458)
			(xy 329.475095 -395.125003) (xy 329.504561 -395.079153) (xy 329.540252 -395.037962) (xy 329.581443 -395.002271)
			(xy 329.627293 -394.972805) (xy 329.67687 -394.950163) (xy 329.729165 -394.934808) (xy 329.783113 -394.927052)
			(xy 329.837615 -394.927052) (xy 329.891563 -394.934808) (xy 329.943858 -394.950163) (xy 329.993435 -394.972805)
			(xy 330.039285 -395.002271) (xy 330.080476 -395.037962) (xy 330.116167 -395.079153) (xy 330.145633 -395.125003)
			(xy 330.168275 -395.17458) (xy 330.18363 -395.226875) (xy 330.191386 -395.280823) (xy 330.191872 -395.308074)
			(xy 330.191872 -396.171674) (xy 330.191386 -396.198925) (xy 330.18363 -396.252873) (xy 330.168275 -396.305168)
			(xy 330.145633 -396.354745) (xy 330.116167 -396.400595) (xy 330.080476 -396.441786) (xy 330.039285 -396.477477)
			(xy 329.993435 -396.506943) (xy 329.943858 -396.529585) (xy 329.891563 -396.54494) (xy 329.837615 -396.552696)
			(xy 329.783113 -396.552696) (xy 329.729165 -396.54494) (xy 329.67687 -396.529585) (xy 329.627293 -396.506943)
			(xy 329.581443 -396.477477) (xy 329.540252 -396.441786) (xy 329.504561 -396.400595) (xy 329.475095 -396.354745)
			(xy 329.452453 -396.305168) (xy 329.437098 -396.252873) (xy 329.429342 -396.198925) (xy 329.428856 -396.171674)
			(xy 325.685404 -396.171674) (xy 325.362062 -396.495016) (xy 325.344022 -396.512278) (xy 325.302529 -396.540039)
			(xy 325.256411 -396.559155) (xy 325.207446 -396.56889) (xy 325.182484 -396.569438) (xy 317.145416 -396.569438)
			(xy 317.120462 -396.568819) (xy 317.071516 -396.559068) (xy 317.025412 -396.539959) (xy 316.98392 -396.512224)
			(xy 316.965838 -396.495016) (xy 316.842902 -396.37208) (xy 316.816232 -396.365222) (xy 316.80277 -396.369032)
			(xy 316.782072 -396.374618) (xy 316.739623 -396.380611) (xy 316.718188 -396.38097) (xy 316.694197 -396.380523)
			(xy 316.646805 -396.373014) (xy 316.601171 -396.358184) (xy 316.558419 -396.336398) (xy 316.519602 -396.308191)
			(xy 316.485676 -396.274259) (xy 316.457476 -396.235438) (xy 316.435697 -396.192683) (xy 316.420874 -396.147047)
			(xy 316.413373 -396.099654) (xy 316.41288 -396.075662) (xy 316.413244 -396.054227) (xy 316.419238 -396.011779)
			(xy 316.424818 -395.99108) (xy 316.428628 -395.977618) (xy 316.42177 -395.950948) (xy 315.698886 -395.228064)
			(xy 315.69149 -395.221213) (xy 315.672891 -395.213474) (xy 315.662818 -395.213078) (xy 315.214508 -395.213078)
			(xy 315.204437 -395.213499) (xy 315.185828 -395.221209) (xy 315.17844 -395.228064) (xy 314.57265 -395.833854)
			(xy 314.565964 -395.841264) (xy 314.558373 -395.859699) (xy 314.557918 -395.869668) (xy 314.567316 -395.899132)
			(xy 314.58056 -395.918596) (xy 314.601541 -395.960739) (xy 314.615806 -396.005602) (xy 314.62302 -396.052123)
			(xy 314.62345 -396.075662) (xy 314.622982 -396.099656) (xy 314.615481 -396.147055) (xy 314.600658 -396.192697)
			(xy 314.578877 -396.235458) (xy 314.550675 -396.274285) (xy 314.516746 -396.308223) (xy 314.477926 -396.336435)
			(xy 314.435171 -396.358227) (xy 314.389533 -396.373062) (xy 314.342136 -396.380576) (xy 314.318142 -396.38097)
			(xy 314.294605 -396.380533) (xy 314.248088 -396.373309) (xy 314.203227 -396.359042) (xy 314.161083 -396.338067)
			(xy 314.141612 -396.324836) (xy 314.112148 -396.315438) (xy 314.102186 -396.315923) (xy 314.083761 -396.323511)
			(xy 314.076334 -396.33017) (xy 313.608466 -396.798038) (xy 313.601654 -396.805382) (xy 313.593925 -396.823845)
			(xy 313.59348 -396.833852) (xy 313.593226 -396.915894) (xy 313.600846 -396.934182) (xy 313.607958 -396.941548)
			(xy 313.624173 -396.95846) (xy 313.651727 -396.99635) (xy 313.662822 -397.016986) (xy 313.66333 -397.018002)
			(xy 313.743636 -397.15694) (xy 314.285376 -397.15694) (xy 314.285376 -397.156432) (xy 314.285869 -397.132428)
			(xy 314.293378 -397.085011) (xy 314.308217 -397.039353) (xy 314.330019 -396.996581) (xy 314.358247 -396.957748)
			(xy 314.392205 -396.923813) (xy 314.431057 -396.895611) (xy 314.473844 -396.873838) (xy 314.519511 -396.85903)
			(xy 314.566934 -396.851552) (xy 314.590938 -396.851124) (xy 314.614874 -396.851573) (xy 314.662161 -396.85903)
			(xy 314.707705 -396.873772) (xy 314.750393 -396.895438) (xy 314.789179 -396.923498) (xy 314.823113 -396.957263)
			(xy 314.851365 -396.995909) (xy 314.862718 -397.016986) (xy 314.863226 -397.018002) (xy 314.943532 -397.15694)
			(xy 315.48578 -397.15694) (xy 315.48578 -397.156432) (xy 315.486268 -397.13244) (xy 315.493769 -397.085047)
			(xy 315.508593 -397.039411) (xy 315.530373 -396.996656) (xy 315.558574 -396.957834) (xy 315.592501 -396.923902)
			(xy 315.631318 -396.895696) (xy 315.67407 -396.87391) (xy 315.719704 -396.85908) (xy 315.767096 -396.851571)
			(xy 315.791088 -396.851124) (xy 315.815025 -396.851532) (xy 315.862314 -396.858997) (xy 315.90786 -396.873747)
			(xy 315.950547 -396.895419) (xy 315.989333 -396.923485) (xy 316.023266 -396.957256) (xy 316.051516 -396.995907)
			(xy 316.062868 -397.016986) (xy 316.063376 -397.018002) (xy 316.143682 -397.15694) (xy 316.685676 -397.15694)
			(xy 316.685676 -397.156432) (xy 316.686168 -397.132441) (xy 316.693669 -397.085048) (xy 316.708492 -397.039412)
			(xy 316.730272 -396.996657) (xy 316.758473 -396.957836) (xy 316.792399 -396.923904) (xy 316.831216 -396.895697)
			(xy 316.873967 -396.873911) (xy 316.919601 -396.85908) (xy 316.966993 -396.851571) (xy 316.990984 -396.851124)
			(xy 317.014921 -396.851535) (xy 317.06221 -396.859) (xy 317.107755 -396.873749) (xy 317.150443 -396.895421)
			(xy 317.189228 -396.923486) (xy 317.223161 -396.957257) (xy 317.251412 -396.995907) (xy 317.262764 -397.016986)
			(xy 317.263272 -397.018002) (xy 317.343578 -397.15694) (xy 317.885572 -397.15694) (xy 317.885572 -397.156432)
			(xy 317.886068 -397.132441) (xy 317.893569 -397.085048) (xy 317.908392 -397.039413) (xy 317.930172 -396.996658)
			(xy 317.958371 -396.957837) (xy 317.992297 -396.923905) (xy 318.031114 -396.895699) (xy 318.073865 -396.873912)
			(xy 318.119498 -396.859081) (xy 318.166889 -396.851572) (xy 318.19088 -396.851124) (xy 318.214817 -396.851539)
			(xy 318.262105 -396.859002) (xy 318.307651 -396.873751) (xy 318.350339 -396.895422) (xy 318.389124 -396.923487)
			(xy 318.423057 -396.957257) (xy 318.451308 -396.995907) (xy 318.46266 -397.016986) (xy 318.463168 -397.018002)
			(xy 318.543474 -397.15694) (xy 319.085468 -397.15694) (xy 319.085468 -397.156432) (xy 319.085969 -397.132428)
			(xy 319.093478 -397.085012) (xy 319.108316 -397.039355) (xy 319.130117 -396.996583) (xy 319.158345 -396.957751)
			(xy 319.192302 -396.923816) (xy 319.231152 -396.895614) (xy 319.273938 -396.87384) (xy 319.319605 -396.859031)
			(xy 319.367026 -396.851553) (xy 319.39103 -396.851124) (xy 319.414965 -396.851579) (xy 319.462252 -396.859035)
			(xy 319.507797 -396.873776) (xy 319.550484 -396.895441) (xy 319.58927 -396.9235) (xy 319.623205 -396.957264)
			(xy 319.651457 -396.995909) (xy 319.66281 -397.016986) (xy 319.663318 -397.018002) (xy 319.743624 -397.15694)
			(xy 320.285364 -397.15694) (xy 320.285364 -397.156432) (xy 320.285869 -397.132428) (xy 320.293378 -397.085012)
			(xy 320.308215 -397.039356) (xy 320.330017 -396.996584) (xy 320.358243 -396.957753) (xy 320.3922 -396.923817)
			(xy 320.43105 -396.895615) (xy 320.473835 -396.873841) (xy 320.519501 -396.859032) (xy 320.566922 -396.851553)
			(xy 320.590926 -396.851124) (xy 320.614861 -396.851582) (xy 320.662148 -396.859038) (xy 320.707692 -396.873778)
			(xy 320.75038 -396.895443) (xy 320.789166 -396.923501) (xy 320.823101 -396.957265) (xy 320.851353 -396.995909)
			(xy 320.862706 -397.016986) (xy 320.863214 -397.018002) (xy 320.94352 -397.15694) (xy 321.485768 -397.15694)
			(xy 321.485768 -397.156432) (xy 321.486268 -397.132441) (xy 321.493769 -397.085049) (xy 321.508592 -397.039414)
			(xy 321.530371 -396.996659) (xy 321.55857 -396.957838) (xy 321.592496 -396.923907) (xy 321.631311 -396.8957)
			(xy 321.674062 -396.873913) (xy 321.719694 -396.859082) (xy 321.767085 -396.851572) (xy 321.791076 -396.851124)
			(xy 321.815013 -396.851542) (xy 321.862301 -396.859005) (xy 321.907847 -396.873753) (xy 321.950534 -396.895424)
			(xy 321.98932 -396.923488) (xy 322.023253 -396.957258) (xy 322.051504 -396.995907) (xy 322.062856 -397.016986)
			(xy 322.063364 -397.018002) (xy 322.129999 -397.133287) (xy 336.013603 -397.133287) (xy 336.020935 -397.085732)
			(xy 336.035629 -397.039915) (xy 336.057324 -396.996967) (xy 336.085482 -396.95795) (xy 336.119407 -396.923829)
			(xy 336.15826 -396.895446) (xy 336.201082 -396.873504) (xy 336.246814 -396.858545) (xy 336.294325 -396.850939)
			(xy 336.342442 -396.850873) (xy 336.389974 -396.85835) (xy 336.435746 -396.873184) (xy 336.478628 -396.895009)
			(xy 336.517559 -396.923285) (xy 336.551577 -396.957314) (xy 336.579841 -396.996254) (xy 336.591148 -397.017494)
			(xy 336.591656 -397.018764) (xy 336.657839 -397.133287) (xy 337.213506 -397.133287) (xy 337.220838 -397.085733)
			(xy 337.235533 -397.039916) (xy 337.257227 -396.996969) (xy 337.285384 -396.957952) (xy 337.319309 -396.923831)
			(xy 337.358162 -396.895449) (xy 337.400983 -396.873508) (xy 337.446714 -396.858549) (xy 337.494225 -396.850942)
			(xy 337.54234 -396.850877) (xy 337.589872 -396.858353) (xy 337.635644 -396.873187) (xy 337.678525 -396.895011)
			(xy 337.717455 -396.923287) (xy 337.751473 -396.957315) (xy 337.779737 -396.996254) (xy 337.791044 -397.017494)
			(xy 337.791552 -397.018764) (xy 337.857735 -397.133286) (xy 338.41341 -397.133286) (xy 338.420742 -397.085733)
			(xy 338.435436 -397.039917) (xy 338.45713 -396.996971) (xy 338.485287 -396.957955) (xy 338.519211 -396.923834)
			(xy 338.558063 -396.895453) (xy 338.600884 -396.873511) (xy 338.646615 -396.858552) (xy 338.694124 -396.850946)
			(xy 338.742239 -396.85088) (xy 338.78977 -396.858356) (xy 338.835541 -396.87319) (xy 338.878422 -396.895014)
			(xy 338.917352 -396.923289) (xy 338.951369 -396.957316) (xy 338.979633 -396.996254) (xy 338.99094 -397.017494)
			(xy 338.991448 -397.018764) (xy 339.057629 -397.133284) (xy 339.613655 -397.133284) (xy 339.620986 -397.08574)
			(xy 339.635678 -397.039932) (xy 339.657368 -396.996993) (xy 339.68552 -396.957985) (xy 339.719438 -396.92387)
			(xy 339.758283 -396.895493) (xy 339.801095 -396.873555) (xy 339.846817 -396.858598) (xy 339.894318 -396.850991)
			(xy 339.942424 -396.850924) (xy 339.989947 -396.858397) (xy 340.03571 -396.873225) (xy 340.078584 -396.895043)
			(xy 340.117509 -396.923311) (xy 340.151522 -396.95733) (xy 340.179784 -396.996259) (xy 340.19109 -397.017494)
			(xy 340.191598 -397.018764) (xy 340.257779 -397.133284) (xy 340.813558 -397.133284) (xy 340.82089 -397.08574)
			(xy 340.835582 -397.039933) (xy 340.857271 -396.996995) (xy 340.885423 -396.957987) (xy 340.91934 -396.923873)
			(xy 340.958184 -396.895496) (xy 341.000996 -396.873558) (xy 341.046717 -396.858601) (xy 341.094218 -396.850995)
			(xy 341.142323 -396.850927) (xy 341.189845 -396.8584) (xy 341.235608 -396.873228) (xy 341.278481 -396.895045)
			(xy 341.317406 -396.923312) (xy 341.351419 -396.957331) (xy 341.37968 -396.996259) (xy 341.390986 -397.017494)
			(xy 341.391494 -397.018764) (xy 341.457677 -397.133286) (xy 342.013613 -397.133286) (xy 342.020945 -397.085734)
			(xy 342.03564 -397.039918) (xy 342.057333 -396.996972) (xy 342.08549 -396.957957) (xy 342.119413 -396.923837)
			(xy 342.158265 -396.895456) (xy 342.201085 -396.873515) (xy 342.246815 -396.858556) (xy 342.294324 -396.85095)
			(xy 342.342438 -396.850884) (xy 342.389968 -396.858359) (xy 342.435739 -396.873192) (xy 342.478619 -396.895016)
			(xy 342.517549 -396.92329) (xy 342.551566 -396.957317) (xy 342.579829 -396.996255) (xy 342.591136 -397.017494)
			(xy 342.591644 -397.018764) (xy 342.983566 -397.696944) (xy 342.98382 -397.697452) (xy 342.984074 -397.697452)
			(xy 342.985344 -397.699992) (xy 342.997619 -397.722906) (xy 343.015023 -397.771885) (xy 343.023896 -397.823101)
			(xy 343.02446 -397.84909) (xy 343.02446 -397.849344) (xy 343.024101 -397.873353) (xy 343.016579 -397.92078)
			(xy 343.001726 -397.966444) (xy 342.979909 -398.00922) (xy 342.951665 -398.048055) (xy 342.917691 -398.08199)
			(xy 342.878825 -398.11019) (xy 342.836023 -398.131958) (xy 342.790342 -398.146759) (xy 342.742908 -398.154228)
			(xy 342.718898 -398.154652) (xy 342.695234 -398.154214) (xy 342.648472 -398.146903) (xy 342.603397 -398.132472)
			(xy 342.561085 -398.111266) (xy 342.522547 -398.083791) (xy 342.488704 -398.050704) (xy 342.460366 -398.012796)
			(xy 342.448896 -397.992092) (xy 342.448642 -397.99133) (xy 342.051386 -397.304006) (xy 342.03921 -397.280788)
			(xy 342.022093 -397.231238) (xy 342.01735 -397.205454) (xy 342.01735 -397.2052) (xy 342.013825 -397.1814)
			(xy 342.013613 -397.133286) (xy 341.457677 -397.133286) (xy 341.783416 -397.696944) (xy 341.78367 -397.697452)
			(xy 341.783924 -397.697452) (xy 341.785194 -397.699992) (xy 341.797425 -397.722917) (xy 341.814746 -397.771902)
			(xy 341.823534 -397.823111) (xy 341.824056 -397.84909) (xy 341.824056 -397.849344) (xy 341.823578 -397.873334)
			(xy 341.816067 -397.920723) (xy 341.801236 -397.966353) (xy 341.779452 -398.009103) (xy 341.751249 -398.047919)
			(xy 341.717322 -398.081846) (xy 341.678506 -398.11005) (xy 341.635757 -398.131835) (xy 341.590127 -398.146666)
			(xy 341.542738 -398.154178) (xy 341.518748 -398.154652) (xy 341.495085 -398.154174) (xy 341.448326 -398.146871)
			(xy 341.403251 -398.132447) (xy 341.360939 -398.111247) (xy 341.3224 -398.083778) (xy 341.288557 -398.050697)
			(xy 341.260217 -398.012794) (xy 341.248746 -397.992092) (xy 341.248492 -397.99133) (xy 340.851236 -397.304006)
			(xy 340.839056 -397.28079) (xy 340.821942 -397.231239) (xy 340.8172 -397.205454) (xy 340.8172 -397.2052)
			(xy 340.813769 -397.181389) (xy 340.813558 -397.133284) (xy 340.257779 -397.133284) (xy 340.58352 -397.696944)
			(xy 340.583774 -397.697452) (xy 340.584028 -397.697452) (xy 340.585298 -397.699992) (xy 340.597529 -397.722917)
			(xy 340.61485 -397.771902) (xy 340.623638 -397.823111) (xy 340.62416 -397.84909) (xy 340.62416 -397.849344)
			(xy 340.623802 -397.873341) (xy 340.616287 -397.920742) (xy 340.60145 -397.966385) (xy 340.579655 -398.009144)
			(xy 340.551439 -398.047968) (xy 340.517498 -398.081899) (xy 340.478666 -398.110103) (xy 340.4359 -398.131885)
			(xy 340.390253 -398.146709) (xy 340.342849 -398.154209) (xy 340.318852 -398.154652) (xy 340.295189 -398.154171)
			(xy 340.24843 -398.146868) (xy 340.203356 -398.132445) (xy 340.161043 -398.111245) (xy 340.122505 -398.083777)
			(xy 340.088661 -398.050696) (xy 340.060321 -398.012793) (xy 340.04885 -397.992092) (xy 340.048596 -397.99133)
			(xy 339.65134 -397.304006) (xy 339.639161 -397.28079) (xy 339.622046 -397.231239) (xy 339.617304 -397.205454)
			(xy 339.617304 -397.2052) (xy 339.613866 -397.18139) (xy 339.613655 -397.133284) (xy 339.057629 -397.133284)
			(xy 339.38337 -397.696944) (xy 339.383624 -397.697452) (xy 339.383878 -397.697452) (xy 339.385148 -397.699992)
			(xy 339.397423 -397.722906) (xy 339.414827 -397.771885) (xy 339.4237 -397.823101) (xy 339.424264 -397.84909)
			(xy 339.424264 -397.849344) (xy 339.423901 -397.873353) (xy 339.416379 -397.920779) (xy 339.401526 -397.966443)
			(xy 339.379709 -398.009219) (xy 339.351466 -398.048053) (xy 339.317493 -398.081989) (xy 339.278627 -398.110188)
			(xy 339.235826 -398.131957) (xy 339.190146 -398.146759) (xy 339.142712 -398.154228) (xy 339.118702 -398.154652)
			(xy 339.095038 -398.154211) (xy 339.048277 -398.146901) (xy 339.003201 -398.13247) (xy 338.960889 -398.111264)
			(xy 338.922351 -398.08379) (xy 338.888508 -398.050703) (xy 338.86017 -398.012796) (xy 338.8487 -397.992092)
			(xy 338.848446 -397.99133) (xy 338.45119 -397.304006) (xy 338.439014 -397.280788) (xy 338.421897 -397.231238)
			(xy 338.417154 -397.205454) (xy 338.417154 -397.2052) (xy 338.413622 -397.181401) (xy 338.41341 -397.133286)
			(xy 337.857735 -397.133286) (xy 338.183474 -397.696944) (xy 338.183728 -397.697452) (xy 338.183982 -397.697452)
			(xy 338.185252 -397.699992) (xy 338.197527 -397.722906) (xy 338.214931 -397.771885) (xy 338.223804 -397.823101)
			(xy 338.224368 -397.84909) (xy 338.224368 -397.849344) (xy 338.224001 -397.873353) (xy 338.216479 -397.920778)
			(xy 338.201626 -397.966442) (xy 338.17981 -398.009218) (xy 338.151567 -398.048052) (xy 338.117595 -398.081987)
			(xy 338.078729 -398.110187) (xy 338.035929 -398.131956) (xy 337.990249 -398.146758) (xy 337.942816 -398.154228)
			(xy 337.918806 -398.154652) (xy 337.895142 -398.154208) (xy 337.848381 -398.146898) (xy 337.803306 -398.132468)
			(xy 337.760993 -398.111263) (xy 337.722455 -398.083789) (xy 337.688613 -398.050703) (xy 337.660274 -398.012795)
			(xy 337.648804 -397.992092) (xy 337.64855 -397.99133) (xy 337.251294 -397.304006) (xy 337.239112 -397.280791)
			(xy 337.221999 -397.231239) (xy 337.217258 -397.205454) (xy 337.217258 -397.2052) (xy 337.213718 -397.181402)
			(xy 337.213506 -397.133287) (xy 336.657839 -397.133287) (xy 336.983578 -397.696944) (xy 336.983832 -397.697452)
			(xy 336.984086 -397.697452) (xy 336.985356 -397.699992) (xy 336.997631 -397.722906) (xy 337.015035 -397.771885)
			(xy 337.023908 -397.823101) (xy 337.024472 -397.84909) (xy 337.024472 -397.849344) (xy 337.024101 -397.873353)
			(xy 337.016579 -397.920778) (xy 337.001727 -397.966441) (xy 336.979911 -398.009217) (xy 336.951668 -398.048051)
			(xy 336.917696 -398.081986) (xy 336.878831 -398.110185) (xy 336.836032 -398.131955) (xy 336.790352 -398.146757)
			(xy 336.742919 -398.154228) (xy 336.71891 -398.154652) (xy 336.695246 -398.154205) (xy 336.648485 -398.146896)
			(xy 336.60341 -398.132466) (xy 336.561098 -398.111261) (xy 336.522559 -398.083788) (xy 336.488717 -398.050702)
			(xy 336.460378 -398.012795) (xy 336.448908 -397.992092) (xy 336.448654 -397.99133) (xy 336.051398 -397.304006)
			(xy 336.039216 -397.280791) (xy 336.022103 -397.231239) (xy 336.017362 -397.205454) (xy 336.017362 -397.2052)
			(xy 336.013815 -397.181402) (xy 336.013603 -397.133287) (xy 322.129999 -397.133287) (xy 322.455794 -397.696944)
			(xy 322.468605 -397.720283) (xy 322.486829 -397.770303) (xy 322.496095 -397.822726) (xy 322.496688 -397.849344)
			(xy 322.496301 -397.873352) (xy 322.48878 -397.920775) (xy 322.473928 -397.966437) (xy 322.452114 -398.009212)
			(xy 322.423873 -398.048045) (xy 322.389903 -398.08198) (xy 322.35104 -398.11018) (xy 322.308243 -398.13195)
			(xy 322.262566 -398.146754) (xy 322.215134 -398.154226) (xy 322.191126 -398.154652) (xy 322.167554 -398.15421)
			(xy 322.120969 -398.146974) (xy 322.076053 -398.132654) (xy 322.033876 -398.111593) (xy 321.995443 -398.084292)
			(xy 321.961669 -398.051401) (xy 321.933359 -398.013704) (xy 321.921886 -397.993108) (xy 321.921378 -397.992346)
			(xy 321.523614 -397.304006) (xy 321.511735 -397.281331) (xy 321.494886 -397.232997) (xy 321.486314 -397.182533)
			(xy 321.485768 -397.15694) (xy 320.94352 -397.15694) (xy 321.255644 -397.696944) (xy 321.26838 -397.720308)
			(xy 321.286493 -397.770337) (xy 321.295702 -397.822741) (xy 321.296284 -397.849344) (xy 321.295878 -397.873338)
			(xy 321.288364 -397.920733) (xy 321.27353 -397.96637) (xy 321.251738 -398.009124) (xy 321.223528 -398.047943)
			(xy 321.189592 -398.081872) (xy 321.150766 -398.110074) (xy 321.108007 -398.131856) (xy 321.062367 -398.14668)
			(xy 321.01497 -398.154183) (xy 320.990976 -398.154652) (xy 320.967403 -398.15425) (xy 320.920816 -398.147007)
			(xy 320.875899 -398.13268) (xy 320.833722 -398.111612) (xy 320.795289 -398.084305) (xy 320.761516 -398.051408)
			(xy 320.733208 -398.013706) (xy 320.721736 -397.993108) (xy 320.721228 -397.992346) (xy 320.323464 -397.304006)
			(xy 320.311554 -397.281335) (xy 320.294614 -397.233011) (xy 320.285952 -397.182542) (xy 320.285364 -397.15694)
			(xy 319.743624 -397.15694) (xy 320.055748 -397.696944) (xy 320.068484 -397.720308) (xy 320.086597 -397.770337)
			(xy 320.095806 -397.822741) (xy 320.096388 -397.849344) (xy 320.095978 -397.873337) (xy 320.088465 -397.920733)
			(xy 320.07363 -397.966369) (xy 320.051839 -398.009123) (xy 320.023629 -398.047942) (xy 319.989693 -398.08187)
			(xy 319.950868 -398.110073) (xy 319.90811 -398.131854) (xy 319.86247 -398.14668) (xy 319.815074 -398.154183)
			(xy 319.79108 -398.154652) (xy 319.767507 -398.154247) (xy 319.72092 -398.147004) (xy 319.676003 -398.132678)
			(xy 319.633826 -398.111611) (xy 319.595393 -398.084304) (xy 319.561621 -398.051407) (xy 319.533312 -398.013706)
			(xy 319.52184 -397.993108) (xy 319.521332 -397.992346) (xy 319.123568 -397.304006) (xy 319.111658 -397.281335)
			(xy 319.094718 -397.233011) (xy 319.086056 -397.182542) (xy 319.085468 -397.15694) (xy 318.543474 -397.15694)
			(xy 318.855598 -397.696944) (xy 318.868401 -397.720288) (xy 318.88663 -397.770305) (xy 318.895899 -397.822727)
			(xy 318.896492 -397.849344) (xy 318.896101 -397.873352) (xy 318.88858 -397.920775) (xy 318.873729 -397.966436)
			(xy 318.851914 -398.009211) (xy 318.823674 -398.048044) (xy 318.789705 -398.081979) (xy 318.750842 -398.110179)
			(xy 318.708046 -398.131949) (xy 318.662369 -398.146753) (xy 318.614938 -398.154226) (xy 318.59093 -398.154652)
			(xy 318.567358 -398.154207) (xy 318.520774 -398.146971) (xy 318.475858 -398.132652) (xy 318.43368 -398.111592)
			(xy 318.395247 -398.084291) (xy 318.361473 -398.0514) (xy 318.333163 -398.013704) (xy 318.32169 -397.993108)
			(xy 318.321182 -397.992346) (xy 317.923418 -397.304006) (xy 317.911539 -397.281331) (xy 317.89469 -397.232997)
			(xy 317.886118 -397.182533) (xy 317.885572 -397.15694) (xy 317.343578 -397.15694) (xy 317.655702 -397.696944)
			(xy 317.668505 -397.720288) (xy 317.686734 -397.770305) (xy 317.696003 -397.822727) (xy 317.696596 -397.849344)
			(xy 317.696201 -397.873352) (xy 317.68868 -397.920774) (xy 317.673829 -397.966435) (xy 317.652015 -398.009209)
			(xy 317.623775 -398.048042) (xy 317.589806 -398.081977) (xy 317.550945 -398.110177) (xy 317.508148 -398.131948)
			(xy 317.462472 -398.146752) (xy 317.415042 -398.154226) (xy 317.391034 -398.154652) (xy 317.367462 -398.154203)
			(xy 317.320878 -398.146969) (xy 317.275962 -398.13265) (xy 317.233785 -398.11159) (xy 317.195351 -398.08429)
			(xy 317.161577 -398.0514) (xy 317.133267 -398.013703) (xy 317.121794 -397.993108) (xy 317.121286 -397.992346)
			(xy 316.723522 -397.304006) (xy 316.711643 -397.281331) (xy 316.694794 -397.232996) (xy 316.686222 -397.182533)
			(xy 316.685676 -397.15694) (xy 316.143682 -397.15694) (xy 316.455806 -397.696944) (xy 316.46861 -397.720287)
			(xy 316.486838 -397.770304) (xy 316.496107 -397.822727) (xy 316.4967 -397.849344) (xy 316.496301 -397.873351)
			(xy 316.48878 -397.920774) (xy 316.47393 -397.966434) (xy 316.452116 -398.009208) (xy 316.423877 -398.048041)
			(xy 316.389908 -398.081976) (xy 316.351047 -398.110176) (xy 316.308251 -398.131947) (xy 316.262576 -398.146752)
			(xy 316.215146 -398.154225) (xy 316.191138 -398.154652) (xy 316.167566 -398.1542) (xy 316.120982 -398.146966)
			(xy 316.076066 -398.132648) (xy 316.033889 -398.111589) (xy 315.995456 -398.084289) (xy 315.961681 -398.051399)
			(xy 315.933371 -398.013703) (xy 315.921898 -397.993108) (xy 315.92139 -397.992346) (xy 315.523626 -397.304006)
			(xy 315.511747 -397.28133) (xy 315.494898 -397.232996) (xy 315.486326 -397.182533) (xy 315.48578 -397.15694)
			(xy 314.943532 -397.15694) (xy 315.255656 -397.696944) (xy 315.268393 -397.720307) (xy 315.286506 -397.770337)
			(xy 315.295714 -397.822741) (xy 315.296296 -397.849344) (xy 315.295878 -397.873337) (xy 315.288365 -397.920731)
			(xy 315.273531 -397.966367) (xy 315.251741 -398.009121) (xy 315.223531 -398.047939) (xy 315.189597 -398.081868)
			(xy 315.150773 -398.11007) (xy 315.108015 -398.131852) (xy 315.062377 -398.146678) (xy 315.014981 -398.154182)
			(xy 314.990988 -398.154652) (xy 314.967415 -398.154241) (xy 314.920829 -398.146999) (xy 314.875912 -398.132674)
			(xy 314.833735 -398.111608) (xy 314.795302 -398.084301) (xy 314.761529 -398.051406) (xy 314.733221 -398.013705)
			(xy 314.721748 -397.993108) (xy 314.72124 -397.992346) (xy 314.323476 -397.304006) (xy 314.311559 -397.281339)
			(xy 314.294623 -397.233013) (xy 314.285963 -397.182542) (xy 314.285376 -397.15694) (xy 313.743636 -397.15694)
			(xy 314.05576 -397.696944) (xy 314.068521 -397.720252) (xy 314.086657 -397.770193) (xy 314.095856 -397.822524)
			(xy 314.0964 -397.84909) (xy 314.0964 -397.849344) (xy 314.095926 -397.873333) (xy 314.088414 -397.920719)
			(xy 314.073583 -397.966346) (xy 314.051797 -398.009092) (xy 314.023593 -398.047904) (xy 313.989665 -398.081827)
			(xy 313.950848 -398.110024) (xy 313.908098 -398.131803) (xy 313.862468 -398.146627) (xy 313.815081 -398.15413)
			(xy 313.791092 -398.154652) (xy 313.76752 -398.154213) (xy 313.720937 -398.146964) (xy 313.676022 -398.132639)
			(xy 313.633844 -398.111579) (xy 313.595405 -398.084285) (xy 313.56162 -398.051405) (xy 313.533291 -398.013722)
			(xy 313.521852 -397.993108) (xy 313.521344 -397.992346) (xy 313.12358 -397.304006) (xy 313.111647 -397.281345)
			(xy 313.094696 -397.233021) (xy 313.086055 -397.182544) (xy 313.08548 -397.15694) (xy 313.08548 -397.156432)
			(xy 313.085734 -397.145256) (xy 313.086242 -397.135096) (xy 313.078876 -397.115792) (xy 313.020964 -397.055594)
			(xy 313.013515 -397.048536) (xy 312.99464 -397.040532) (xy 312.984388 -397.0401) (xy 312.564018 -397.0401)
			(xy 312.555129 -397.040439) (xy 312.538429 -397.04653) (xy 312.52483 -397.05798) (xy 312.520076 -397.0655)
			(xy 312.513218 -397.077438) (xy 312.513218 -397.104362) (xy 312.85561 -397.696944) (xy 312.868394 -397.720294)
			(xy 312.886587 -397.770317) (xy 312.895871 -397.822731) (xy 312.896504 -397.849344) (xy 312.896031 -397.87332)
			(xy 312.888527 -397.920682) (xy 312.873711 -397.966288) (xy 312.851948 -398.009017) (xy 312.823771 -398.047818)
			(xy 312.789875 -398.081737) (xy 312.751093 -398.10994) (xy 312.708379 -398.131733) (xy 312.662782 -398.146579)
			(xy 312.615426 -398.154115) (xy 312.59145 -398.154652) (xy 312.590942 -398.154652) (xy 312.567372 -398.15421)
			(xy 312.520794 -398.146954) (xy 312.475885 -398.132624) (xy 312.433713 -398.11156) (xy 312.39528 -398.084263)
			(xy 312.3615 -398.051383) (xy 312.333177 -398.0137) (xy 312.321702 -397.993108) (xy 312.321194 -397.992346)
			(xy 311.92343 -397.304006) (xy 311.911533 -397.281337) (xy 311.894659 -397.233007) (xy 311.886098 -397.182536)
			(xy 311.885584 -397.15694) (xy 311.885584 -397.145256) (xy 311.886092 -397.135096) (xy 311.878726 -397.115792)
			(xy 311.820814 -397.055594) (xy 311.813362 -397.048544) (xy 311.794487 -397.040559) (xy 311.784238 -397.0401)
			(xy 311.364122 -397.0401) (xy 311.355233 -397.040438) (xy 311.338531 -397.046529) (xy 311.324932 -397.057978)
			(xy 311.32018 -397.0655) (xy 311.313322 -397.077438) (xy 311.313322 -397.104362) (xy 311.655714 -397.696944)
			(xy 311.668498 -397.720294) (xy 311.686691 -397.770318) (xy 311.695975 -397.822731) (xy 311.696608 -397.849344)
			(xy 311.696135 -397.87332) (xy 311.688631 -397.920682) (xy 311.673816 -397.966289) (xy 311.652052 -398.009018)
			(xy 311.623876 -398.04782) (xy 311.58998 -398.081739) (xy 311.551197 -398.109942) (xy 311.508483 -398.131735)
			(xy 311.462887 -398.146582) (xy 311.41553 -398.154119) (xy 311.391554 -398.154652) (xy 311.391046 -398.154652)
			(xy 311.367476 -398.15421) (xy 311.320897 -398.146955) (xy 311.275988 -398.132625) (xy 311.233815 -398.111561)
			(xy 311.195382 -398.084265) (xy 311.161602 -398.051385) (xy 311.133278 -398.013702) (xy 311.121806 -397.993108)
			(xy 311.121298 -397.992346) (xy 310.723534 -397.304006) (xy 310.711636 -397.281337) (xy 310.694762 -397.233007)
			(xy 310.686202 -397.182536) (xy 310.685688 -397.15694) (xy 310.685688 -397.145256) (xy 310.686196 -397.135096)
			(xy 310.67883 -397.115792) (xy 310.620918 -397.055594) (xy 310.613466 -397.048544) (xy 310.594591 -397.040557)
			(xy 310.584342 -397.0401) (xy 310.572404 -397.0401) (xy 310.547451 -397.039479) (xy 310.498507 -397.029726)
			(xy 310.452406 -397.010613) (xy 310.410919 -396.982874) (xy 310.392826 -396.965678) (xy 309.945786 -396.518638)
			(xy 309.928526 -396.500597) (xy 309.900768 -396.459104) (xy 309.881656 -396.412986) (xy 309.871926 -396.364021)
			(xy 309.871364 -396.33906) (xy 309.871364 -394.978636) (xy 309.87095 -394.968613) (xy 309.863285 -394.95009)
			(xy 309.84911 -394.935915) (xy 309.830587 -394.92825) (xy 309.820564 -394.927836) (xy 309.714646 -394.927836)
			(xy 309.689246 -394.9446) (xy 309.683404 -394.959078) (xy 309.672908 -394.982747) (xy 309.645653 -395.026765)
			(xy 309.611875 -395.066002) (xy 309.572399 -395.0995) (xy 309.528188 -395.126441) (xy 309.480321 -395.146169)
			(xy 309.429965 -395.158201) (xy 309.37835 -395.162245) (xy 309.326735 -395.158201) (xy 309.276379 -395.146169)
			(xy 309.228512 -395.126441) (xy 309.184301 -395.0995) (xy 309.144825 -395.066002) (xy 309.111047 -395.026765)
			(xy 309.083792 -394.982747) (xy 309.073296 -394.959078) (xy 309.067454 -394.9446) (xy 309.042054 -394.927836)
			(xy 308.514496 -394.927836) (xy 308.489096 -394.9446) (xy 308.483254 -394.959078) (xy 308.472758 -394.982747)
			(xy 308.445503 -395.026765) (xy 308.411725 -395.066002) (xy 308.372249 -395.0995) (xy 308.328038 -395.126441)
			(xy 308.280171 -395.146169) (xy 308.229815 -395.158201) (xy 308.1782 -395.162245) (xy 308.126585 -395.158201)
			(xy 308.076229 -395.146169) (xy 308.028362 -395.126441) (xy 307.984151 -395.0995) (xy 307.944675 -395.066002)
			(xy 307.910897 -395.026765) (xy 307.883642 -394.982747) (xy 307.873146 -394.959078) (xy 307.867304 -394.9446)
			(xy 307.841904 -394.927836) (xy 307.3146 -394.927836) (xy 307.2892 -394.9446) (xy 307.283358 -394.959078)
			(xy 307.272862 -394.982747) (xy 307.245607 -395.026765) (xy 307.211829 -395.066002) (xy 307.172353 -395.0995)
			(xy 307.128142 -395.126441) (xy 307.080275 -395.146169) (xy 307.029919 -395.158201) (xy 306.978304 -395.162245)
			(xy 306.926689 -395.158201) (xy 306.876333 -395.146169) (xy 306.828466 -395.126441) (xy 306.784255 -395.0995)
			(xy 306.744779 -395.066002) (xy 306.711001 -395.026765) (xy 306.683746 -394.982747) (xy 306.67325 -394.959078)
			(xy 306.667408 -394.9446) (xy 306.642008 -394.927836) (xy 306.114704 -394.927836) (xy 306.089304 -394.9446)
			(xy 306.083462 -394.959078) (xy 306.072966 -394.982747) (xy 306.045711 -395.026765) (xy 306.011933 -395.066002)
			(xy 305.972457 -395.0995) (xy 305.928246 -395.126441) (xy 305.880379 -395.146169) (xy 305.830023 -395.158201)
			(xy 305.778408 -395.162245) (xy 305.726793 -395.158201) (xy 305.676437 -395.146169) (xy 305.62857 -395.126441)
			(xy 305.584359 -395.0995) (xy 305.544883 -395.066002) (xy 305.511105 -395.026765) (xy 305.48385 -394.982747)
			(xy 305.473354 -394.959078) (xy 305.467512 -394.9446) (xy 305.442112 -394.927836) (xy 304.914554 -394.927836)
			(xy 304.889154 -394.9446) (xy 304.883312 -394.959078) (xy 304.872816 -394.982747) (xy 304.845561 -395.026765)
			(xy 304.811783 -395.066002) (xy 304.772307 -395.0995) (xy 304.728096 -395.126441) (xy 304.680229 -395.146169)
			(xy 304.629873 -395.158201) (xy 304.578258 -395.162245) (xy 304.526643 -395.158201) (xy 304.476287 -395.146169)
			(xy 304.42842 -395.126441) (xy 304.384209 -395.0995) (xy 304.344733 -395.066002) (xy 304.310955 -395.026765)
			(xy 304.2837 -394.982747) (xy 304.273204 -394.959078) (xy 304.267362 -394.9446) (xy 304.241962 -394.927836)
			(xy 303.714658 -394.927836) (xy 303.689258 -394.9446) (xy 303.683416 -394.959078) (xy 303.67292 -394.982747)
			(xy 303.645665 -395.026765) (xy 303.611887 -395.066002) (xy 303.572411 -395.0995) (xy 303.5282 -395.126441)
			(xy 303.480333 -395.146169) (xy 303.429977 -395.158201) (xy 303.378362 -395.162245) (xy 303.326747 -395.158201)
			(xy 303.276391 -395.146169) (xy 303.228524 -395.126441) (xy 303.184313 -395.0995) (xy 303.144837 -395.066002)
			(xy 303.111059 -395.026765) (xy 303.083804 -394.982747) (xy 303.073308 -394.959078) (xy 303.067466 -394.9446)
			(xy 303.042066 -394.927836) (xy 301.404274 -394.927836) (xy 301.377604 -394.947394) (xy 301.372524 -394.963396)
			(xy 301.364814 -394.986285) (xy 301.343199 -395.029475) (xy 301.315055 -395.068724) (xy 301.281085 -395.103056)
			(xy 301.242136 -395.131612) (xy 301.199177 -395.153683) (xy 301.15328 -395.168717) (xy 301.105588 -395.17634)
			(xy 301.08144 -395.176756) (xy 301.072042 -395.176502) (xy 301.061374 -395.176248) (xy 301.041816 -395.184122)
			(xy 299.068998 -397.15694) (xy 303.485804 -397.15694) (xy 303.485804 -397.156432) (xy 303.486268 -397.132439)
			(xy 303.49377 -397.085044) (xy 303.508595 -397.039405) (xy 303.530377 -396.996648) (xy 303.558581 -396.957826)
			(xy 303.592511 -396.923894) (xy 303.631331 -396.895688) (xy 303.674087 -396.873903) (xy 303.719724 -396.859075)
			(xy 303.767119 -396.851569) (xy 303.791112 -396.851124) (xy 303.815047 -396.851594) (xy 303.862333 -396.859047)
			(xy 303.907877 -396.873786) (xy 303.950565 -396.895448) (xy 303.989351 -396.923504) (xy 304.023286 -396.957267)
			(xy 304.051539 -396.99591) (xy 304.062892 -397.016986) (xy 304.0634 -397.018002) (xy 304.143706 -397.15694)
			(xy 304.6857 -397.15694) (xy 304.6857 -397.156432) (xy 304.686168 -397.132439) (xy 304.69367 -397.085044)
			(xy 304.708495 -397.039406) (xy 304.730277 -396.99665) (xy 304.75848 -396.957827) (xy 304.792409 -396.923895)
			(xy 304.831229 -396.895689) (xy 304.873984 -396.873904) (xy 304.919621 -396.859076) (xy 304.967015 -396.85157)
			(xy 304.991008 -396.851124) (xy 305.014943 -396.851597) (xy 305.062229 -396.85905) (xy 305.107773 -396.873788)
			(xy 305.150461 -396.89545) (xy 305.189247 -396.923505) (xy 305.223182 -396.957268) (xy 305.251435 -396.99591)
			(xy 305.262788 -397.016986) (xy 305.263296 -397.018002) (xy 305.343602 -397.15694) (xy 305.885596 -397.15694)
			(xy 305.885596 -397.156432) (xy 305.886068 -397.13244) (xy 305.89357 -397.085045) (xy 305.908394 -397.039407)
			(xy 305.930176 -396.996651) (xy 305.958378 -396.957829) (xy 305.992307 -396.923897) (xy 306.031127 -396.895691)
			(xy 306.073881 -396.873905) (xy 306.119517 -396.859076) (xy 306.166912 -396.85157) (xy 306.190904 -396.851124)
			(xy 306.214839 -396.8516) (xy 306.262124 -396.859053) (xy 306.307668 -396.87379) (xy 306.350356 -396.895451)
			(xy 306.389142 -396.923506) (xy 306.423077 -396.957268) (xy 306.451331 -396.99591) (xy 306.462684 -397.016986)
			(xy 306.463192 -397.018002) (xy 306.543498 -397.15694) (xy 307.085492 -397.15694) (xy 307.085492 -397.156432)
			(xy 307.085969 -397.132427) (xy 307.093478 -397.085008) (xy 307.108318 -397.039349) (xy 307.130122 -396.996576)
			(xy 307.158352 -396.957743) (xy 307.192312 -396.923807) (xy 307.231166 -396.895605) (xy 307.273955 -396.873833)
			(xy 307.319624 -396.859027) (xy 307.367049 -396.851551) (xy 307.391054 -396.851124) (xy 307.41499 -396.85156)
			(xy 307.462278 -396.85902) (xy 307.507823 -396.873764) (xy 307.550511 -396.895432) (xy 307.589296 -396.923493)
			(xy 307.62323 -396.957261) (xy 307.651481 -396.995908) (xy 307.662834 -397.016986) (xy 307.663342 -397.018002)
			(xy 307.743648 -397.15694) (xy 308.285388 -397.15694) (xy 308.285388 -397.156432) (xy 308.285869 -397.132427)
			(xy 308.293378 -397.085009) (xy 308.308218 -397.03935) (xy 308.330021 -396.996577) (xy 308.35825 -396.957744)
			(xy 308.39221 -396.923809) (xy 308.431063 -396.895607) (xy 308.473852 -396.873834) (xy 308.519521 -396.859027)
			(xy 308.566945 -396.851552) (xy 308.59095 -396.851124) (xy 308.614886 -396.851563) (xy 308.662173 -396.859022)
			(xy 308.707718 -396.873766) (xy 308.750406 -396.895434) (xy 308.789192 -396.923494) (xy 308.823126 -396.957262)
			(xy 308.851377 -396.995908) (xy 308.86273 -397.016986) (xy 308.863238 -397.018002) (xy 308.943544 -397.15694)
			(xy 309.485792 -397.15694) (xy 309.485792 -397.156432) (xy 309.486268 -397.13244) (xy 309.49377 -397.085045)
			(xy 309.508594 -397.039408) (xy 309.530375 -396.996652) (xy 309.558577 -396.95783) (xy 309.592506 -396.923898)
			(xy 309.631325 -396.895692) (xy 309.674079 -396.873906) (xy 309.719714 -396.859077) (xy 309.767108 -396.85157)
			(xy 309.7911 -396.851124) (xy 309.815035 -396.851603) (xy 309.86232 -396.859055) (xy 309.907864 -396.873792)
			(xy 309.950552 -396.895453) (xy 309.989338 -396.923507) (xy 310.023273 -396.957269) (xy 310.051526 -396.995911)
			(xy 310.06288 -397.016986) (xy 310.063388 -397.018002) (xy 310.455818 -397.696944) (xy 310.468623 -397.720287)
			(xy 310.486851 -397.770304) (xy 310.496119 -397.822727) (xy 310.496712 -397.849344) (xy 310.496302 -397.873351)
			(xy 310.48878 -397.920772) (xy 310.473931 -397.966432) (xy 310.452118 -398.009205) (xy 310.42388 -398.048037)
			(xy 310.389913 -398.081971) (xy 310.351053 -398.110172) (xy 310.308259 -398.131943) (xy 310.262586 -398.146749)
			(xy 310.215157 -398.154225) (xy 310.19115 -398.154652) (xy 310.167579 -398.154191) (xy 310.120995 -398.146958)
			(xy 310.076079 -398.132642) (xy 310.033902 -398.111584) (xy 309.995468 -398.084286) (xy 309.961694 -398.051397)
			(xy 309.933384 -398.013703) (xy 309.92191 -397.993108) (xy 309.921402 -397.992346) (xy 309.523638 -397.304006)
			(xy 309.51176 -397.28133) (xy 309.494911 -397.232996) (xy 309.486338 -397.182533) (xy 309.485792 -397.15694)
			(xy 308.943544 -397.15694) (xy 309.255668 -397.696944) (xy 309.268406 -397.720307) (xy 309.286518 -397.770336)
			(xy 309.295726 -397.822741) (xy 309.296308 -397.849344) (xy 309.295878 -397.873336) (xy 309.288365 -397.92073)
			(xy 309.273532 -397.966364) (xy 309.251743 -398.009117) (xy 309.223535 -398.047935) (xy 309.189602 -398.081863)
			(xy 309.150779 -398.110066) (xy 309.108024 -398.131849) (xy 309.062387 -398.146676) (xy 309.014992 -398.154181)
			(xy 308.991 -398.154652) (xy 308.967427 -398.154231) (xy 308.920842 -398.146991) (xy 308.875925 -398.132668)
			(xy 308.833748 -398.111603) (xy 308.795315 -398.084298) (xy 308.761542 -398.051404) (xy 308.733233 -398.013705)
			(xy 308.72176 -397.993108) (xy 308.721252 -397.992346) (xy 308.323488 -397.304006) (xy 308.311572 -397.281338)
			(xy 308.294635 -397.233013) (xy 308.285975 -397.182542) (xy 308.285388 -397.15694) (xy 307.743648 -397.15694)
			(xy 308.055772 -397.696944) (xy 308.06851 -397.720307) (xy 308.086622 -397.770336) (xy 308.09583 -397.822741)
			(xy 308.096412 -397.849344) (xy 308.095978 -397.873336) (xy 308.088465 -397.920729) (xy 308.073632 -397.966363)
			(xy 308.051844 -398.009116) (xy 308.023636 -398.047934) (xy 307.989703 -398.081862) (xy 307.950882 -398.110065)
			(xy 307.908126 -398.131848) (xy 307.86249 -398.146675) (xy 307.815096 -398.154181) (xy 307.791104 -398.154652)
			(xy 307.767532 -398.154228) (xy 307.720946 -398.146988) (xy 307.676029 -398.132666) (xy 307.633852 -398.111602)
			(xy 307.595419 -398.084297) (xy 307.561646 -398.051404) (xy 307.533337 -398.013705) (xy 307.521864 -397.993108)
			(xy 307.521356 -397.992346) (xy 307.123592 -397.304006) (xy 307.111676 -397.281338) (xy 307.094739 -397.233012)
			(xy 307.086079 -397.182542) (xy 307.085492 -397.15694) (xy 306.543498 -397.15694) (xy 306.855622 -397.696944)
			(xy 306.868427 -397.720287) (xy 306.886655 -397.770304) (xy 306.895923 -397.822727) (xy 306.896516 -397.849344)
			(xy 306.896102 -397.873351) (xy 306.888581 -397.920771) (xy 306.873731 -397.966431) (xy 306.851919 -398.009203)
			(xy 306.823681 -398.048036) (xy 306.789715 -398.08197) (xy 306.750856 -398.110171) (xy 306.708062 -398.131942)
			(xy 306.662389 -398.146748) (xy 306.614961 -398.154224) (xy 306.590954 -398.154652) (xy 306.567383 -398.154187)
			(xy 306.520799 -398.146955) (xy 306.475884 -398.13264) (xy 306.433706 -398.111583) (xy 306.395273 -398.084285)
			(xy 306.361498 -398.051397) (xy 306.333188 -398.013702) (xy 306.321714 -397.993108) (xy 306.321206 -397.992346)
			(xy 305.923442 -397.304006) (xy 305.911565 -397.28133) (xy 305.894715 -397.232996) (xy 305.886142 -397.182533)
			(xy 305.885596 -397.15694) (xy 305.343602 -397.15694) (xy 305.655726 -397.696944) (xy 305.668531 -397.720286)
			(xy 305.686759 -397.770304) (xy 305.696027 -397.822727) (xy 305.69662 -397.849344) (xy 305.696202 -397.87335)
			(xy 305.688681 -397.920771) (xy 305.673831 -397.96643) (xy 305.652019 -398.009202) (xy 305.623782 -398.048034)
			(xy 305.589816 -398.081969) (xy 305.550958 -398.110169) (xy 305.508165 -398.131941) (xy 305.462492 -398.146748)
			(xy 305.415065 -398.154224) (xy 305.391058 -398.154652) (xy 305.367487 -398.154184) (xy 305.320904 -398.146953)
			(xy 305.275988 -398.132638) (xy 305.233811 -398.111581) (xy 305.195377 -398.084284) (xy 305.161602 -398.051396)
			(xy 305.133292 -398.013702) (xy 305.121818 -397.993108) (xy 305.12131 -397.992346) (xy 304.723546 -397.304006)
			(xy 304.711669 -397.28133) (xy 304.694819 -397.232996) (xy 304.686246 -397.182533) (xy 304.6857 -397.15694)
			(xy 304.143706 -397.15694) (xy 304.45583 -397.696944) (xy 304.468636 -397.720286) (xy 304.486863 -397.770304)
			(xy 304.496131 -397.822727) (xy 304.496724 -397.849344) (xy 304.496302 -397.87335) (xy 304.488781 -397.92077)
			(xy 304.473932 -397.966429) (xy 304.45212 -398.009201) (xy 304.423884 -398.048033) (xy 304.389918 -398.081967)
			(xy 304.35106 -398.110168) (xy 304.308268 -398.13194) (xy 304.262595 -398.146747) (xy 304.215169 -398.154224)
			(xy 304.191162 -398.154652) (xy 304.167591 -398.154181) (xy 304.121008 -398.14695) (xy 304.076092 -398.132636)
			(xy 304.033915 -398.11158) (xy 303.995481 -398.084283) (xy 303.961707 -398.051396) (xy 303.933396 -398.013702)
			(xy 303.921922 -397.993108) (xy 303.921414 -397.992346) (xy 303.52365 -397.304006) (xy 303.511773 -397.281329)
			(xy 303.494923 -397.232996) (xy 303.48635 -397.182533) (xy 303.485804 -397.15694) (xy 299.068998 -397.15694)
			(xy 296.302684 -399.923254) (xy 296.295837 -399.930651) (xy 296.288109 -399.949251) (xy 296.287698 -399.959322)
			(xy 296.287698 -401.674838) (xy 303.434496 -401.674838) (xy 303.434496 -400.811238) (xy 303.434982 -400.783969)
			(xy 303.442744 -400.729985) (xy 303.458109 -400.677655) (xy 303.480766 -400.628045) (xy 303.510252 -400.582164)
			(xy 303.545967 -400.540947) (xy 303.587184 -400.505232) (xy 303.633065 -400.475746) (xy 303.682675 -400.453089)
			(xy 303.735005 -400.437724) (xy 303.788989 -400.429962) (xy 303.843527 -400.429962) (xy 303.897511 -400.437724)
			(xy 303.949841 -400.453089) (xy 303.999451 -400.475746) (xy 304.045332 -400.505232) (xy 304.086549 -400.540947)
			(xy 304.122264 -400.582164) (xy 304.15175 -400.628045) (xy 304.174407 -400.677655) (xy 304.189772 -400.729985)
			(xy 304.197534 -400.783969) (xy 304.19802 -400.811238) (xy 304.19802 -401.674838) (xy 304.634392 -401.674838)
			(xy 304.634392 -400.811238) (xy 304.634878 -400.783969) (xy 304.64264 -400.729985) (xy 304.658005 -400.677655)
			(xy 304.680662 -400.628045) (xy 304.710148 -400.582164) (xy 304.745863 -400.540947) (xy 304.78708 -400.505232)
			(xy 304.832961 -400.475746) (xy 304.882571 -400.453089) (xy 304.934901 -400.437724) (xy 304.988885 -400.429962)
			(xy 305.043423 -400.429962) (xy 305.097407 -400.437724) (xy 305.149737 -400.453089) (xy 305.199347 -400.475746)
			(xy 305.245228 -400.505232) (xy 305.286445 -400.540947) (xy 305.32216 -400.582164) (xy 305.351646 -400.628045)
			(xy 305.374303 -400.677655) (xy 305.389668 -400.729985) (xy 305.39743 -400.783969) (xy 305.397916 -400.811238)
			(xy 305.397916 -401.674838) (xy 305.834796 -401.674838) (xy 305.834796 -400.811238) (xy 305.835282 -400.783987)
			(xy 305.843038 -400.730039) (xy 305.858393 -400.677744) (xy 305.881035 -400.628167) (xy 305.910501 -400.582317)
			(xy 305.946192 -400.541126) (xy 305.987383 -400.505435) (xy 306.033233 -400.475969) (xy 306.08281 -400.453327)
			(xy 306.135105 -400.437972) (xy 306.189053 -400.430216) (xy 306.243555 -400.430216) (xy 306.297503 -400.437972)
			(xy 306.349798 -400.453327) (xy 306.399375 -400.475969) (xy 306.445225 -400.505435) (xy 306.486416 -400.541126)
			(xy 306.522107 -400.582317) (xy 306.551573 -400.628167) (xy 306.574215 -400.677744) (xy 306.58957 -400.730039)
			(xy 306.597326 -400.783987) (xy 306.597812 -400.811238) (xy 306.597812 -401.674838) (xy 307.034692 -401.674838)
			(xy 307.034692 -400.811238) (xy 307.035178 -400.783987) (xy 307.042934 -400.730039) (xy 307.058289 -400.677744)
			(xy 307.080931 -400.628167) (xy 307.110397 -400.582317) (xy 307.146088 -400.541126) (xy 307.187279 -400.505435)
			(xy 307.233129 -400.475969) (xy 307.282706 -400.453327) (xy 307.335001 -400.437972) (xy 307.388949 -400.430216)
			(xy 307.443451 -400.430216) (xy 307.497399 -400.437972) (xy 307.549694 -400.453327) (xy 307.599271 -400.475969)
			(xy 307.645121 -400.505435) (xy 307.686312 -400.541126) (xy 307.722003 -400.582317) (xy 307.751469 -400.628167)
			(xy 307.774111 -400.677744) (xy 307.789466 -400.730039) (xy 307.797222 -400.783987) (xy 307.797708 -400.811238)
			(xy 307.797708 -401.674838) (xy 308.234588 -401.674838) (xy 308.234588 -400.811238) (xy 308.235074 -400.783969)
			(xy 308.242836 -400.729985) (xy 308.258201 -400.677655) (xy 308.280858 -400.628045) (xy 308.310344 -400.582164)
			(xy 308.346059 -400.540947) (xy 308.387276 -400.505232) (xy 308.433157 -400.475746) (xy 308.482767 -400.453089)
			(xy 308.535097 -400.437724) (xy 308.589081 -400.429962) (xy 308.643619 -400.429962) (xy 308.697603 -400.437724)
			(xy 308.749933 -400.453089) (xy 308.799543 -400.475746) (xy 308.845424 -400.505232) (xy 308.886641 -400.540947)
			(xy 308.922356 -400.582164) (xy 308.951842 -400.628045) (xy 308.974499 -400.677655) (xy 308.989864 -400.729985)
			(xy 308.997626 -400.783969) (xy 308.998112 -400.811238) (xy 308.998112 -401.674838) (xy 309.434484 -401.674838)
			(xy 309.434484 -400.811238) (xy 309.43497 -400.783969) (xy 309.442732 -400.729985) (xy 309.458097 -400.677655)
			(xy 309.480754 -400.628045) (xy 309.51024 -400.582164) (xy 309.545955 -400.540947) (xy 309.587172 -400.505232)
			(xy 309.633053 -400.475746) (xy 309.682663 -400.453089) (xy 309.734993 -400.437724) (xy 309.788977 -400.429962)
			(xy 309.843515 -400.429962) (xy 309.897499 -400.437724) (xy 309.949829 -400.453089) (xy 309.999439 -400.475746)
			(xy 310.04532 -400.505232) (xy 310.086537 -400.540947) (xy 310.122252 -400.582164) (xy 310.151738 -400.628045)
			(xy 310.174395 -400.677655) (xy 310.18976 -400.729985) (xy 310.197522 -400.783969) (xy 310.198008 -400.811238)
			(xy 310.198008 -401.674838) (xy 310.634888 -401.674838) (xy 310.634888 -400.811238) (xy 310.635374 -400.783987)
			(xy 310.64313 -400.730039) (xy 310.658485 -400.677744) (xy 310.681127 -400.628167) (xy 310.710593 -400.582317)
			(xy 310.746284 -400.541126) (xy 310.787475 -400.505435) (xy 310.833325 -400.475969) (xy 310.882902 -400.453327)
			(xy 310.935197 -400.437972) (xy 310.989145 -400.430216) (xy 311.043647 -400.430216) (xy 311.097595 -400.437972)
			(xy 311.14989 -400.453327) (xy 311.199467 -400.475969) (xy 311.245317 -400.505435) (xy 311.286508 -400.541126)
			(xy 311.322199 -400.582317) (xy 311.351665 -400.628167) (xy 311.374307 -400.677744) (xy 311.389662 -400.730039)
			(xy 311.397418 -400.783987) (xy 311.397904 -400.811238) (xy 311.397904 -401.674838) (xy 311.834784 -401.674838)
			(xy 311.834784 -400.811238) (xy 311.83527 -400.783987) (xy 311.843026 -400.730039) (xy 311.858381 -400.677744)
			(xy 311.881023 -400.628167) (xy 311.910489 -400.582317) (xy 311.94618 -400.541126) (xy 311.987371 -400.505435)
			(xy 312.033221 -400.475969) (xy 312.082798 -400.453327) (xy 312.135093 -400.437972) (xy 312.189041 -400.430216)
			(xy 312.243543 -400.430216) (xy 312.297491 -400.437972) (xy 312.349786 -400.453327) (xy 312.399363 -400.475969)
			(xy 312.445213 -400.505435) (xy 312.486404 -400.541126) (xy 312.522095 -400.582317) (xy 312.551561 -400.628167)
			(xy 312.574203 -400.677744) (xy 312.589558 -400.730039) (xy 312.597314 -400.783987) (xy 312.5978 -400.811238)
			(xy 312.5978 -401.674838) (xy 313.03468 -401.674838) (xy 313.03468 -400.811238) (xy 313.035166 -400.783969)
			(xy 313.042928 -400.729985) (xy 313.058293 -400.677655) (xy 313.08095 -400.628045) (xy 313.110436 -400.582164)
			(xy 313.146151 -400.540947) (xy 313.187368 -400.505232) (xy 313.233249 -400.475746) (xy 313.282859 -400.453089)
			(xy 313.335189 -400.437724) (xy 313.389173 -400.429962) (xy 313.443711 -400.429962) (xy 313.497695 -400.437724)
			(xy 313.550025 -400.453089) (xy 313.599635 -400.475746) (xy 313.645516 -400.505232) (xy 313.686733 -400.540947)
			(xy 313.722448 -400.582164) (xy 313.751934 -400.628045) (xy 313.774591 -400.677655) (xy 313.789956 -400.729985)
			(xy 313.797718 -400.783969) (xy 313.798204 -400.811238) (xy 313.798204 -401.674838) (xy 314.234576 -401.674838)
			(xy 314.234576 -400.811238) (xy 314.235062 -400.783969) (xy 314.242824 -400.729985) (xy 314.258189 -400.677655)
			(xy 314.280846 -400.628045) (xy 314.310332 -400.582164) (xy 314.346047 -400.540947) (xy 314.387264 -400.505232)
			(xy 314.433145 -400.475746) (xy 314.482755 -400.453089) (xy 314.535085 -400.437724) (xy 314.589069 -400.429962)
			(xy 314.643607 -400.429962) (xy 314.697591 -400.437724) (xy 314.749921 -400.453089) (xy 314.799531 -400.475746)
			(xy 314.845412 -400.505232) (xy 314.886629 -400.540947) (xy 314.922344 -400.582164) (xy 314.95183 -400.628045)
			(xy 314.974487 -400.677655) (xy 314.989852 -400.729985) (xy 314.997614 -400.783969) (xy 314.9981 -400.811238)
			(xy 314.9981 -401.674838) (xy 315.43498 -401.674838) (xy 315.43498 -400.811238) (xy 315.435466 -400.783987)
			(xy 315.443222 -400.730039) (xy 315.458577 -400.677744) (xy 315.481219 -400.628167) (xy 315.510685 -400.582317)
			(xy 315.546376 -400.541126) (xy 315.587567 -400.505435) (xy 315.633417 -400.475969) (xy 315.682994 -400.453327)
			(xy 315.735289 -400.437972) (xy 315.789237 -400.430216) (xy 315.843739 -400.430216) (xy 315.897687 -400.437972)
			(xy 315.949982 -400.453327) (xy 315.999559 -400.475969) (xy 316.045409 -400.505435) (xy 316.0866 -400.541126)
			(xy 316.122291 -400.582317) (xy 316.151757 -400.628167) (xy 316.174399 -400.677744) (xy 316.189754 -400.730039)
			(xy 316.19751 -400.783987) (xy 316.197996 -400.811238) (xy 316.197996 -401.674838) (xy 316.634876 -401.674838)
			(xy 316.634876 -400.811238) (xy 316.635362 -400.783987) (xy 316.643118 -400.730039) (xy 316.658473 -400.677744)
			(xy 316.681115 -400.628167) (xy 316.710581 -400.582317) (xy 316.746272 -400.541126) (xy 316.787463 -400.505435)
			(xy 316.833313 -400.475969) (xy 316.88289 -400.453327) (xy 316.935185 -400.437972) (xy 316.989133 -400.430216)
			(xy 317.043635 -400.430216) (xy 317.097583 -400.437972) (xy 317.149878 -400.453327) (xy 317.199455 -400.475969)
			(xy 317.245305 -400.505435) (xy 317.286496 -400.541126) (xy 317.322187 -400.582317) (xy 317.351653 -400.628167)
			(xy 317.374295 -400.677744) (xy 317.38965 -400.730039) (xy 317.397406 -400.783987) (xy 317.397892 -400.811238)
			(xy 317.397892 -401.674838) (xy 317.834772 -401.674838) (xy 317.834772 -400.811238) (xy 317.835258 -400.783987)
			(xy 317.843014 -400.730039) (xy 317.858369 -400.677744) (xy 317.881011 -400.628167) (xy 317.910477 -400.582317)
			(xy 317.946168 -400.541126) (xy 317.987359 -400.505435) (xy 318.033209 -400.475969) (xy 318.082786 -400.453327)
			(xy 318.135081 -400.437972) (xy 318.189029 -400.430216) (xy 318.243531 -400.430216) (xy 318.297479 -400.437972)
			(xy 318.349774 -400.453327) (xy 318.399351 -400.475969) (xy 318.445201 -400.505435) (xy 318.486392 -400.541126)
			(xy 318.522083 -400.582317) (xy 318.551549 -400.628167) (xy 318.574191 -400.677744) (xy 318.589546 -400.730039)
			(xy 318.597302 -400.783987) (xy 318.597788 -400.811238) (xy 318.597788 -401.674838) (xy 319.034668 -401.674838)
			(xy 319.034668 -400.811238) (xy 319.035154 -400.783987) (xy 319.04291 -400.730039) (xy 319.058265 -400.677744)
			(xy 319.080907 -400.628167) (xy 319.110373 -400.582317) (xy 319.146064 -400.541126) (xy 319.187255 -400.505435)
			(xy 319.233105 -400.475969) (xy 319.282682 -400.453327) (xy 319.334977 -400.437972) (xy 319.388925 -400.430216)
			(xy 319.443427 -400.430216) (xy 319.497375 -400.437972) (xy 319.54967 -400.453327) (xy 319.599247 -400.475969)
			(xy 319.645097 -400.505435) (xy 319.686288 -400.541126) (xy 319.721979 -400.582317) (xy 319.751445 -400.628167)
			(xy 319.774087 -400.677744) (xy 319.789442 -400.730039) (xy 319.797198 -400.783987) (xy 319.797684 -400.811238)
			(xy 319.797684 -401.674838) (xy 320.234564 -401.674838) (xy 320.234564 -400.811238) (xy 320.23505 -400.783969)
			(xy 320.242812 -400.729985) (xy 320.258177 -400.677655) (xy 320.280834 -400.628045) (xy 320.31032 -400.582164)
			(xy 320.346035 -400.540947) (xy 320.387252 -400.505232) (xy 320.433133 -400.475746) (xy 320.482743 -400.453089)
			(xy 320.535073 -400.437724) (xy 320.589057 -400.429962) (xy 320.643595 -400.429962) (xy 320.697579 -400.437724)
			(xy 320.749909 -400.453089) (xy 320.799519 -400.475746) (xy 320.8454 -400.505232) (xy 320.886617 -400.540947)
			(xy 320.922332 -400.582164) (xy 320.951818 -400.628045) (xy 320.974475 -400.677655) (xy 320.98984 -400.729985)
			(xy 320.997602 -400.783969) (xy 320.998088 -400.811238) (xy 320.998088 -401.674838) (xy 321.43446 -401.674838)
			(xy 321.43446 -400.811238) (xy 321.434946 -400.783969) (xy 321.442708 -400.729985) (xy 321.458073 -400.677655)
			(xy 321.48073 -400.628045) (xy 321.510216 -400.582164) (xy 321.545931 -400.540947) (xy 321.587148 -400.505232)
			(xy 321.633029 -400.475746) (xy 321.682639 -400.453089) (xy 321.734969 -400.437724) (xy 321.788953 -400.429962)
			(xy 321.843491 -400.429962) (xy 321.897475 -400.437724) (xy 321.949805 -400.453089) (xy 321.999415 -400.475746)
			(xy 322.045296 -400.505232) (xy 322.086513 -400.540947) (xy 322.122228 -400.582164) (xy 322.151714 -400.628045)
			(xy 322.174371 -400.677655) (xy 322.189736 -400.729985) (xy 322.197498 -400.783969) (xy 322.197984 -400.811238)
			(xy 322.197984 -401.674838) (xy 335.962244 -401.674838) (xy 335.962244 -400.811238) (xy 335.96273 -400.783969)
			(xy 335.970492 -400.729985) (xy 335.985857 -400.677655) (xy 336.008514 -400.628045) (xy 336.038 -400.582164)
			(xy 336.073715 -400.540947) (xy 336.114932 -400.505232) (xy 336.160813 -400.475746) (xy 336.210423 -400.453089)
			(xy 336.262753 -400.437724) (xy 336.316737 -400.429962) (xy 336.371275 -400.429962) (xy 336.425259 -400.437724)
			(xy 336.477589 -400.453089) (xy 336.527199 -400.475746) (xy 336.57308 -400.505232) (xy 336.614297 -400.540947)
			(xy 336.650012 -400.582164) (xy 336.679498 -400.628045) (xy 336.702155 -400.677655) (xy 336.71752 -400.729985)
			(xy 336.725282 -400.783969) (xy 336.725768 -400.811238) (xy 336.725768 -401.674838) (xy 337.16214 -401.674838)
			(xy 337.16214 -400.811238) (xy 337.162626 -400.783969) (xy 337.170388 -400.729985) (xy 337.185753 -400.677655)
			(xy 337.20841 -400.628045) (xy 337.237896 -400.582164) (xy 337.273611 -400.540947) (xy 337.314828 -400.505232)
			(xy 337.360709 -400.475746) (xy 337.410319 -400.453089) (xy 337.462649 -400.437724) (xy 337.516633 -400.429962)
			(xy 337.571171 -400.429962) (xy 337.625155 -400.437724) (xy 337.677485 -400.453089) (xy 337.727095 -400.475746)
			(xy 337.772976 -400.505232) (xy 337.814193 -400.540947) (xy 337.849908 -400.582164) (xy 337.879394 -400.628045)
			(xy 337.902051 -400.677655) (xy 337.917416 -400.729985) (xy 337.925178 -400.783969) (xy 337.925664 -400.811238)
			(xy 337.925664 -401.674838) (xy 338.362544 -401.674838) (xy 338.362544 -400.811238) (xy 338.36303 -400.783987)
			(xy 338.370786 -400.730039) (xy 338.386141 -400.677744) (xy 338.408783 -400.628167) (xy 338.438249 -400.582317)
			(xy 338.47394 -400.541126) (xy 338.515131 -400.505435) (xy 338.560981 -400.475969) (xy 338.610558 -400.453327)
			(xy 338.662853 -400.437972) (xy 338.716801 -400.430216) (xy 338.771303 -400.430216) (xy 338.825251 -400.437972)
			(xy 338.877546 -400.453327) (xy 338.927123 -400.475969) (xy 338.972973 -400.505435) (xy 339.014164 -400.541126)
			(xy 339.049855 -400.582317) (xy 339.079321 -400.628167) (xy 339.101963 -400.677744) (xy 339.117318 -400.730039)
			(xy 339.125074 -400.783987) (xy 339.12556 -400.811238) (xy 339.12556 -401.674838) (xy 339.56244 -401.674838)
			(xy 339.56244 -400.811238) (xy 339.562926 -400.783987) (xy 339.570682 -400.730039) (xy 339.586037 -400.677744)
			(xy 339.608679 -400.628167) (xy 339.638145 -400.582317) (xy 339.673836 -400.541126) (xy 339.715027 -400.505435)
			(xy 339.760877 -400.475969) (xy 339.810454 -400.453327) (xy 339.862749 -400.437972) (xy 339.916697 -400.430216)
			(xy 339.971199 -400.430216) (xy 340.025147 -400.437972) (xy 340.077442 -400.453327) (xy 340.127019 -400.475969)
			(xy 340.172869 -400.505435) (xy 340.21406 -400.541126) (xy 340.249751 -400.582317) (xy 340.279217 -400.628167)
			(xy 340.301859 -400.677744) (xy 340.317214 -400.730039) (xy 340.32497 -400.783987) (xy 340.325456 -400.811238)
			(xy 340.325456 -401.674838) (xy 340.762336 -401.674838) (xy 340.762336 -400.811238) (xy 340.762822 -400.783969)
			(xy 340.770584 -400.729985) (xy 340.785949 -400.677655) (xy 340.808606 -400.628045) (xy 340.838092 -400.582164)
			(xy 340.873807 -400.540947) (xy 340.915024 -400.505232) (xy 340.960905 -400.475746) (xy 341.010515 -400.453089)
			(xy 341.062845 -400.437724) (xy 341.116829 -400.429962) (xy 341.171367 -400.429962) (xy 341.225351 -400.437724)
			(xy 341.277681 -400.453089) (xy 341.327291 -400.475746) (xy 341.373172 -400.505232) (xy 341.414389 -400.540947)
			(xy 341.450104 -400.582164) (xy 341.47959 -400.628045) (xy 341.502247 -400.677655) (xy 341.517612 -400.729985)
			(xy 341.525374 -400.783969) (xy 341.52586 -400.811238) (xy 341.52586 -401.674838) (xy 341.962232 -401.674838)
			(xy 341.962232 -400.811238) (xy 341.962718 -400.783969) (xy 341.97048 -400.729985) (xy 341.985845 -400.677655)
			(xy 342.008502 -400.628045) (xy 342.037988 -400.582164) (xy 342.073703 -400.540947) (xy 342.11492 -400.505232)
			(xy 342.160801 -400.475746) (xy 342.210411 -400.453089) (xy 342.262741 -400.437724) (xy 342.316725 -400.429962)
			(xy 342.371263 -400.429962) (xy 342.425247 -400.437724) (xy 342.477577 -400.453089) (xy 342.527187 -400.475746)
			(xy 342.573068 -400.505232) (xy 342.614285 -400.540947) (xy 342.65 -400.582164) (xy 342.679486 -400.628045)
			(xy 342.702143 -400.677655) (xy 342.717508 -400.729985) (xy 342.72527 -400.783969) (xy 342.725756 -400.811238)
			(xy 342.725756 -401.674838) (xy 343.162636 -401.674838) (xy 343.162636 -400.811238) (xy 343.163122 -400.783987)
			(xy 343.170878 -400.730039) (xy 343.186233 -400.677744) (xy 343.208875 -400.628167) (xy 343.238341 -400.582317)
			(xy 343.274032 -400.541126) (xy 343.315223 -400.505435) (xy 343.361073 -400.475969) (xy 343.41065 -400.453327)
			(xy 343.462945 -400.437972) (xy 343.516893 -400.430216) (xy 343.571395 -400.430216) (xy 343.625343 -400.437972)
			(xy 343.677638 -400.453327) (xy 343.727215 -400.475969) (xy 343.773065 -400.505435) (xy 343.814256 -400.541126)
			(xy 343.849947 -400.582317) (xy 343.879413 -400.628167) (xy 343.902055 -400.677744) (xy 343.91741 -400.730039)
			(xy 343.925166 -400.783987) (xy 343.925652 -400.811238) (xy 343.925652 -401.674838) (xy 344.362532 -401.674838)
			(xy 344.362532 -400.811238) (xy 344.363018 -400.783987) (xy 344.370774 -400.730039) (xy 344.386129 -400.677744)
			(xy 344.408771 -400.628167) (xy 344.438237 -400.582317) (xy 344.473928 -400.541126) (xy 344.515119 -400.505435)
			(xy 344.560969 -400.475969) (xy 344.610546 -400.453327) (xy 344.662841 -400.437972) (xy 344.716789 -400.430216)
			(xy 344.771291 -400.430216) (xy 344.825239 -400.437972) (xy 344.877534 -400.453327) (xy 344.927111 -400.475969)
			(xy 344.972961 -400.505435) (xy 345.014152 -400.541126) (xy 345.049843 -400.582317) (xy 345.079309 -400.628167)
			(xy 345.101951 -400.677744) (xy 345.117306 -400.730039) (xy 345.125062 -400.783987) (xy 345.125548 -400.811238)
			(xy 345.125548 -401.674838) (xy 345.562428 -401.674838) (xy 345.562428 -400.811238) (xy 345.562914 -400.783969)
			(xy 345.570676 -400.729985) (xy 345.586041 -400.677655) (xy 345.608698 -400.628045) (xy 345.638184 -400.582164)
			(xy 345.673899 -400.540947) (xy 345.715116 -400.505232) (xy 345.760997 -400.475746) (xy 345.810607 -400.453089)
			(xy 345.862937 -400.437724) (xy 345.916921 -400.429962) (xy 345.971459 -400.429962) (xy 346.025443 -400.437724)
			(xy 346.077773 -400.453089) (xy 346.127383 -400.475746) (xy 346.173264 -400.505232) (xy 346.214481 -400.540947)
			(xy 346.250196 -400.582164) (xy 346.279682 -400.628045) (xy 346.302339 -400.677655) (xy 346.317704 -400.729985)
			(xy 346.325466 -400.783969) (xy 346.325952 -400.811238) (xy 346.325952 -401.674838) (xy 346.762324 -401.674838)
			(xy 346.762324 -400.811238) (xy 346.76281 -400.783969) (xy 346.770572 -400.729985) (xy 346.785937 -400.677655)
			(xy 346.808594 -400.628045) (xy 346.83808 -400.582164) (xy 346.873795 -400.540947) (xy 346.915012 -400.505232)
			(xy 346.960893 -400.475746) (xy 347.010503 -400.453089) (xy 347.062833 -400.437724) (xy 347.116817 -400.429962)
			(xy 347.171355 -400.429962) (xy 347.225339 -400.437724) (xy 347.277669 -400.453089) (xy 347.327279 -400.475746)
			(xy 347.37316 -400.505232) (xy 347.414377 -400.540947) (xy 347.450092 -400.582164) (xy 347.479578 -400.628045)
			(xy 347.502235 -400.677655) (xy 347.5176 -400.729985) (xy 347.525362 -400.783969) (xy 347.525848 -400.811238)
			(xy 347.525848 -401.674838) (xy 347.962728 -401.674838) (xy 347.962728 -400.811238) (xy 347.963214 -400.783987)
			(xy 347.97097 -400.730039) (xy 347.986325 -400.677744) (xy 348.008967 -400.628167) (xy 348.038433 -400.582317)
			(xy 348.074124 -400.541126) (xy 348.115315 -400.505435) (xy 348.161165 -400.475969) (xy 348.210742 -400.453327)
			(xy 348.263037 -400.437972) (xy 348.316985 -400.430216) (xy 348.371487 -400.430216) (xy 348.425435 -400.437972)
			(xy 348.47773 -400.453327) (xy 348.527307 -400.475969) (xy 348.573157 -400.505435) (xy 348.614348 -400.541126)
			(xy 348.650039 -400.582317) (xy 348.679505 -400.628167) (xy 348.702147 -400.677744) (xy 348.717502 -400.730039)
			(xy 348.725258 -400.783987) (xy 348.725744 -400.811238) (xy 348.725744 -401.674838) (xy 349.162624 -401.674838)
			(xy 349.162624 -400.811238) (xy 349.16311 -400.783987) (xy 349.170866 -400.730039) (xy 349.186221 -400.677744)
			(xy 349.208863 -400.628167) (xy 349.238329 -400.582317) (xy 349.27402 -400.541126) (xy 349.315211 -400.505435)
			(xy 349.361061 -400.475969) (xy 349.410638 -400.453327) (xy 349.462933 -400.437972) (xy 349.516881 -400.430216)
			(xy 349.571383 -400.430216) (xy 349.625331 -400.437972) (xy 349.677626 -400.453327) (xy 349.727203 -400.475969)
			(xy 349.773053 -400.505435) (xy 349.814244 -400.541126) (xy 349.849935 -400.582317) (xy 349.879401 -400.628167)
			(xy 349.902043 -400.677744) (xy 349.917398 -400.730039) (xy 349.925154 -400.783987) (xy 349.92564 -400.811238)
			(xy 349.92564 -401.674838) (xy 350.36252 -401.674838) (xy 350.36252 -400.811238) (xy 350.363006 -400.783987)
			(xy 350.370762 -400.730039) (xy 350.386117 -400.677744) (xy 350.408759 -400.628167) (xy 350.438225 -400.582317)
			(xy 350.473916 -400.541126) (xy 350.515107 -400.505435) (xy 350.560957 -400.475969) (xy 350.610534 -400.453327)
			(xy 350.662829 -400.437972) (xy 350.716777 -400.430216) (xy 350.771279 -400.430216) (xy 350.825227 -400.437972)
			(xy 350.877522 -400.453327) (xy 350.927099 -400.475969) (xy 350.972949 -400.505435) (xy 351.01414 -400.541126)
			(xy 351.049831 -400.582317) (xy 351.079297 -400.628167) (xy 351.101939 -400.677744) (xy 351.117294 -400.730039)
			(xy 351.12505 -400.783987) (xy 351.125536 -400.811238) (xy 351.125536 -401.674838) (xy 351.562416 -401.674838)
			(xy 351.562416 -400.811238) (xy 351.562902 -400.783987) (xy 351.570658 -400.730039) (xy 351.586013 -400.677744)
			(xy 351.608655 -400.628167) (xy 351.638121 -400.582317) (xy 351.673812 -400.541126) (xy 351.715003 -400.505435)
			(xy 351.760853 -400.475969) (xy 351.81043 -400.453327) (xy 351.862725 -400.437972) (xy 351.916673 -400.430216)
			(xy 351.971175 -400.430216) (xy 352.025123 -400.437972) (xy 352.077418 -400.453327) (xy 352.126995 -400.475969)
			(xy 352.172845 -400.505435) (xy 352.214036 -400.541126) (xy 352.249727 -400.582317) (xy 352.279193 -400.628167)
			(xy 352.301835 -400.677744) (xy 352.31719 -400.730039) (xy 352.324946 -400.783987) (xy 352.325432 -400.811238)
			(xy 352.325432 -401.674838) (xy 352.762312 -401.674838) (xy 352.762312 -400.811238) (xy 352.762798 -400.783969)
			(xy 352.77056 -400.729985) (xy 352.785925 -400.677655) (xy 352.808582 -400.628045) (xy 352.838068 -400.582164)
			(xy 352.873783 -400.540947) (xy 352.915 -400.505232) (xy 352.960881 -400.475746) (xy 353.010491 -400.453089)
			(xy 353.062821 -400.437724) (xy 353.116805 -400.429962) (xy 353.171343 -400.429962) (xy 353.225327 -400.437724)
			(xy 353.277657 -400.453089) (xy 353.327267 -400.475746) (xy 353.373148 -400.505232) (xy 353.414365 -400.540947)
			(xy 353.45008 -400.582164) (xy 353.479566 -400.628045) (xy 353.502223 -400.677655) (xy 353.517588 -400.729985)
			(xy 353.52535 -400.783969) (xy 353.525836 -400.811238) (xy 353.525836 -401.674838) (xy 353.962208 -401.674838)
			(xy 353.962208 -400.811238) (xy 353.962694 -400.783969) (xy 353.970456 -400.729985) (xy 353.985821 -400.677655)
			(xy 354.008478 -400.628045) (xy 354.037964 -400.582164) (xy 354.073679 -400.540947) (xy 354.114896 -400.505232)
			(xy 354.160777 -400.475746) (xy 354.210387 -400.453089) (xy 354.262717 -400.437724) (xy 354.316701 -400.429962)
			(xy 354.371239 -400.429962) (xy 354.425223 -400.437724) (xy 354.477553 -400.453089) (xy 354.527163 -400.475746)
			(xy 354.573044 -400.505232) (xy 354.614261 -400.540947) (xy 354.649976 -400.582164) (xy 354.679462 -400.628045)
			(xy 354.702119 -400.677655) (xy 354.717484 -400.729985) (xy 354.725246 -400.783969) (xy 354.725732 -400.811238)
			(xy 354.725732 -401.674838) (xy 370.534692 -401.674838) (xy 370.534692 -400.811238) (xy 370.535178 -400.783969)
			(xy 370.54294 -400.729985) (xy 370.558305 -400.677655) (xy 370.580962 -400.628045) (xy 370.610448 -400.582164)
			(xy 370.646163 -400.540947) (xy 370.68738 -400.505232) (xy 370.733261 -400.475746) (xy 370.782871 -400.453089)
			(xy 370.835201 -400.437724) (xy 370.889185 -400.429962) (xy 370.943723 -400.429962) (xy 370.997707 -400.437724)
			(xy 371.050037 -400.453089) (xy 371.099647 -400.475746) (xy 371.145528 -400.505232) (xy 371.186745 -400.540947)
			(xy 371.22246 -400.582164) (xy 371.251946 -400.628045) (xy 371.274603 -400.677655) (xy 371.289968 -400.729985)
			(xy 371.29773 -400.783969) (xy 371.298216 -400.811238) (xy 371.298216 -401.674838) (xy 371.734588 -401.674838)
			(xy 371.734588 -400.811238) (xy 371.735074 -400.783969) (xy 371.742836 -400.729985) (xy 371.758201 -400.677655)
			(xy 371.780858 -400.628045) (xy 371.810344 -400.582164) (xy 371.846059 -400.540947) (xy 371.887276 -400.505232)
			(xy 371.933157 -400.475746) (xy 371.982767 -400.453089) (xy 372.035097 -400.437724) (xy 372.089081 -400.429962)
			(xy 372.143619 -400.429962) (xy 372.197603 -400.437724) (xy 372.249933 -400.453089) (xy 372.299543 -400.475746)
			(xy 372.345424 -400.505232) (xy 372.386641 -400.540947) (xy 372.422356 -400.582164) (xy 372.451842 -400.628045)
			(xy 372.474499 -400.677655) (xy 372.489864 -400.729985) (xy 372.497626 -400.783969) (xy 372.498112 -400.811238)
			(xy 372.498112 -401.674838) (xy 372.934992 -401.674838) (xy 372.934992 -400.811238) (xy 372.935478 -400.783987)
			(xy 372.943234 -400.730039) (xy 372.958589 -400.677744) (xy 372.981231 -400.628167) (xy 373.010697 -400.582317)
			(xy 373.046388 -400.541126) (xy 373.087579 -400.505435) (xy 373.133429 -400.475969) (xy 373.183006 -400.453327)
			(xy 373.235301 -400.437972) (xy 373.289249 -400.430216) (xy 373.343751 -400.430216) (xy 373.397699 -400.437972)
			(xy 373.449994 -400.453327) (xy 373.499571 -400.475969) (xy 373.545421 -400.505435) (xy 373.586612 -400.541126)
			(xy 373.622303 -400.582317) (xy 373.651769 -400.628167) (xy 373.674411 -400.677744) (xy 373.689766 -400.730039)
			(xy 373.697522 -400.783987) (xy 373.698008 -400.811238) (xy 373.698008 -401.674838) (xy 374.134888 -401.674838)
			(xy 374.134888 -400.811238) (xy 374.135374 -400.783987) (xy 374.14313 -400.730039) (xy 374.158485 -400.677744)
			(xy 374.181127 -400.628167) (xy 374.210593 -400.582317) (xy 374.246284 -400.541126) (xy 374.287475 -400.505435)
			(xy 374.333325 -400.475969) (xy 374.382902 -400.453327) (xy 374.435197 -400.437972) (xy 374.489145 -400.430216)
			(xy 374.543647 -400.430216) (xy 374.597595 -400.437972) (xy 374.64989 -400.453327) (xy 374.699467 -400.475969)
			(xy 374.745317 -400.505435) (xy 374.786508 -400.541126) (xy 374.822199 -400.582317) (xy 374.851665 -400.628167)
			(xy 374.874307 -400.677744) (xy 374.889662 -400.730039) (xy 374.897418 -400.783987) (xy 374.897904 -400.811238)
			(xy 374.897904 -401.674838) (xy 375.334784 -401.674838) (xy 375.334784 -400.811238) (xy 375.33527 -400.783969)
			(xy 375.343032 -400.729985) (xy 375.358397 -400.677655) (xy 375.381054 -400.628045) (xy 375.41054 -400.582164)
			(xy 375.446255 -400.540947) (xy 375.487472 -400.505232) (xy 375.533353 -400.475746) (xy 375.582963 -400.453089)
			(xy 375.635293 -400.437724) (xy 375.689277 -400.429962) (xy 375.743815 -400.429962) (xy 375.797799 -400.437724)
			(xy 375.850129 -400.453089) (xy 375.899739 -400.475746) (xy 375.94562 -400.505232) (xy 375.986837 -400.540947)
			(xy 376.022552 -400.582164) (xy 376.052038 -400.628045) (xy 376.074695 -400.677655) (xy 376.09006 -400.729985)
			(xy 376.097822 -400.783969) (xy 376.098308 -400.811238) (xy 376.098308 -401.674838) (xy 376.53468 -401.674838)
			(xy 376.53468 -400.811238) (xy 376.535166 -400.783969) (xy 376.542928 -400.729985) (xy 376.558293 -400.677655)
			(xy 376.58095 -400.628045) (xy 376.610436 -400.582164) (xy 376.646151 -400.540947) (xy 376.687368 -400.505232)
			(xy 376.733249 -400.475746) (xy 376.782859 -400.453089) (xy 376.835189 -400.437724) (xy 376.889173 -400.429962)
			(xy 376.943711 -400.429962) (xy 376.997695 -400.437724) (xy 377.050025 -400.453089) (xy 377.099635 -400.475746)
			(xy 377.145516 -400.505232) (xy 377.186733 -400.540947) (xy 377.222448 -400.582164) (xy 377.251934 -400.628045)
			(xy 377.274591 -400.677655) (xy 377.289956 -400.729985) (xy 377.297718 -400.783969) (xy 377.298204 -400.811238)
			(xy 377.298204 -401.674838) (xy 377.735084 -401.674838) (xy 377.735084 -400.811238) (xy 377.73557 -400.783987)
			(xy 377.743326 -400.730039) (xy 377.758681 -400.677744) (xy 377.781323 -400.628167) (xy 377.810789 -400.582317)
			(xy 377.84648 -400.541126) (xy 377.887671 -400.505435) (xy 377.933521 -400.475969) (xy 377.983098 -400.453327)
			(xy 378.035393 -400.437972) (xy 378.089341 -400.430216) (xy 378.143843 -400.430216) (xy 378.197791 -400.437972)
			(xy 378.250086 -400.453327) (xy 378.299663 -400.475969) (xy 378.345513 -400.505435) (xy 378.386704 -400.541126)
			(xy 378.422395 -400.582317) (xy 378.451861 -400.628167) (xy 378.474503 -400.677744) (xy 378.489858 -400.730039)
			(xy 378.497614 -400.783987) (xy 378.4981 -400.811238) (xy 378.4981 -401.674838) (xy 378.93498 -401.674838)
			(xy 378.93498 -400.811238) (xy 378.935466 -400.783987) (xy 378.943222 -400.730039) (xy 378.958577 -400.677744)
			(xy 378.981219 -400.628167) (xy 379.010685 -400.582317) (xy 379.046376 -400.541126) (xy 379.087567 -400.505435)
			(xy 379.133417 -400.475969) (xy 379.182994 -400.453327) (xy 379.235289 -400.437972) (xy 379.289237 -400.430216)
			(xy 379.343739 -400.430216) (xy 379.397687 -400.437972) (xy 379.449982 -400.453327) (xy 379.499559 -400.475969)
			(xy 379.545409 -400.505435) (xy 379.5866 -400.541126) (xy 379.622291 -400.582317) (xy 379.651757 -400.628167)
			(xy 379.674399 -400.677744) (xy 379.689754 -400.730039) (xy 379.69751 -400.783987) (xy 379.697996 -400.811238)
			(xy 379.697996 -401.674838) (xy 380.134876 -401.674838) (xy 380.134876 -400.811238) (xy 380.135362 -400.783969)
			(xy 380.143124 -400.729985) (xy 380.158489 -400.677655) (xy 380.181146 -400.628045) (xy 380.210632 -400.582164)
			(xy 380.246347 -400.540947) (xy 380.287564 -400.505232) (xy 380.333445 -400.475746) (xy 380.383055 -400.453089)
			(xy 380.435385 -400.437724) (xy 380.489369 -400.429962) (xy 380.543907 -400.429962) (xy 380.597891 -400.437724)
			(xy 380.650221 -400.453089) (xy 380.699831 -400.475746) (xy 380.745712 -400.505232) (xy 380.786929 -400.540947)
			(xy 380.822644 -400.582164) (xy 380.85213 -400.628045) (xy 380.874787 -400.677655) (xy 380.890152 -400.729985)
			(xy 380.897914 -400.783969) (xy 380.8984 -400.811238) (xy 380.8984 -401.674838) (xy 381.334772 -401.674838)
			(xy 381.334772 -400.811238) (xy 381.335258 -400.783969) (xy 381.34302 -400.729985) (xy 381.358385 -400.677655)
			(xy 381.381042 -400.628045) (xy 381.410528 -400.582164) (xy 381.446243 -400.540947) (xy 381.48746 -400.505232)
			(xy 381.533341 -400.475746) (xy 381.582951 -400.453089) (xy 381.635281 -400.437724) (xy 381.689265 -400.429962)
			(xy 381.743803 -400.429962) (xy 381.797787 -400.437724) (xy 381.850117 -400.453089) (xy 381.899727 -400.475746)
			(xy 381.945608 -400.505232) (xy 381.986825 -400.540947) (xy 382.02254 -400.582164) (xy 382.052026 -400.628045)
			(xy 382.074683 -400.677655) (xy 382.090048 -400.729985) (xy 382.09781 -400.783969) (xy 382.098296 -400.811238)
			(xy 382.098296 -401.674838) (xy 382.535176 -401.674838) (xy 382.535176 -400.811238) (xy 382.535662 -400.783987)
			(xy 382.543418 -400.730039) (xy 382.558773 -400.677744) (xy 382.581415 -400.628167) (xy 382.610881 -400.582317)
			(xy 382.646572 -400.541126) (xy 382.687763 -400.505435) (xy 382.733613 -400.475969) (xy 382.78319 -400.453327)
			(xy 382.835485 -400.437972) (xy 382.889433 -400.430216) (xy 382.943935 -400.430216) (xy 382.997883 -400.437972)
			(xy 383.050178 -400.453327) (xy 383.099755 -400.475969) (xy 383.145605 -400.505435) (xy 383.186796 -400.541126)
			(xy 383.222487 -400.582317) (xy 383.251953 -400.628167) (xy 383.274595 -400.677744) (xy 383.28995 -400.730039)
			(xy 383.297706 -400.783987) (xy 383.298192 -400.811238) (xy 383.298192 -401.674838) (xy 383.735072 -401.674838)
			(xy 383.735072 -400.811238) (xy 383.735558 -400.783987) (xy 383.743314 -400.730039) (xy 383.758669 -400.677744)
			(xy 383.781311 -400.628167) (xy 383.810777 -400.582317) (xy 383.846468 -400.541126) (xy 383.887659 -400.505435)
			(xy 383.933509 -400.475969) (xy 383.983086 -400.453327) (xy 384.035381 -400.437972) (xy 384.089329 -400.430216)
			(xy 384.143831 -400.430216) (xy 384.197779 -400.437972) (xy 384.250074 -400.453327) (xy 384.299651 -400.475969)
			(xy 384.345501 -400.505435) (xy 384.386692 -400.541126) (xy 384.422383 -400.582317) (xy 384.451849 -400.628167)
			(xy 384.474491 -400.677744) (xy 384.489846 -400.730039) (xy 384.497602 -400.783987) (xy 384.498088 -400.811238)
			(xy 384.498088 -401.674838) (xy 384.934968 -401.674838) (xy 384.934968 -400.811238) (xy 384.935454 -400.783987)
			(xy 384.94321 -400.730039) (xy 384.958565 -400.677744) (xy 384.981207 -400.628167) (xy 385.010673 -400.582317)
			(xy 385.046364 -400.541126) (xy 385.087555 -400.505435) (xy 385.133405 -400.475969) (xy 385.182982 -400.453327)
			(xy 385.235277 -400.437972) (xy 385.289225 -400.430216) (xy 385.343727 -400.430216) (xy 385.397675 -400.437972)
			(xy 385.44997 -400.453327) (xy 385.499547 -400.475969) (xy 385.545397 -400.505435) (xy 385.586588 -400.541126)
			(xy 385.622279 -400.582317) (xy 385.651745 -400.628167) (xy 385.674387 -400.677744) (xy 385.689742 -400.730039)
			(xy 385.697498 -400.783987) (xy 385.697984 -400.811238) (xy 385.697984 -401.674838) (xy 386.134864 -401.674838)
			(xy 386.134864 -400.811238) (xy 386.13535 -400.783987) (xy 386.143106 -400.730039) (xy 386.158461 -400.677744)
			(xy 386.181103 -400.628167) (xy 386.210569 -400.582317) (xy 386.24626 -400.541126) (xy 386.287451 -400.505435)
			(xy 386.333301 -400.475969) (xy 386.382878 -400.453327) (xy 386.435173 -400.437972) (xy 386.489121 -400.430216)
			(xy 386.543623 -400.430216) (xy 386.597571 -400.437972) (xy 386.649866 -400.453327) (xy 386.699443 -400.475969)
			(xy 386.745293 -400.505435) (xy 386.786484 -400.541126) (xy 386.822175 -400.582317) (xy 386.851641 -400.628167)
			(xy 386.874283 -400.677744) (xy 386.889638 -400.730039) (xy 386.897394 -400.783987) (xy 386.89788 -400.811238)
			(xy 386.89788 -401.674838) (xy 387.33476 -401.674838) (xy 387.33476 -400.811238) (xy 387.335246 -400.783969)
			(xy 387.343008 -400.729985) (xy 387.358373 -400.677655) (xy 387.38103 -400.628045) (xy 387.410516 -400.582164)
			(xy 387.446231 -400.540947) (xy 387.487448 -400.505232) (xy 387.533329 -400.475746) (xy 387.582939 -400.453089)
			(xy 387.635269 -400.437724) (xy 387.689253 -400.429962) (xy 387.743791 -400.429962) (xy 387.797775 -400.437724)
			(xy 387.850105 -400.453089) (xy 387.899715 -400.475746) (xy 387.945596 -400.505232) (xy 387.986813 -400.540947)
			(xy 388.022528 -400.582164) (xy 388.052014 -400.628045) (xy 388.074671 -400.677655) (xy 388.090036 -400.729985)
			(xy 388.097798 -400.783969) (xy 388.098284 -400.811238) (xy 388.098284 -401.674838) (xy 388.534656 -401.674838)
			(xy 388.534656 -400.811238) (xy 388.535142 -400.783969) (xy 388.542904 -400.729985) (xy 388.558269 -400.677655)
			(xy 388.580926 -400.628045) (xy 388.610412 -400.582164) (xy 388.646127 -400.540947) (xy 388.687344 -400.505232)
			(xy 388.733225 -400.475746) (xy 388.782835 -400.453089) (xy 388.835165 -400.437724) (xy 388.889149 -400.429962)
			(xy 388.943687 -400.429962) (xy 388.997671 -400.437724) (xy 389.050001 -400.453089) (xy 389.099611 -400.475746)
			(xy 389.145492 -400.505232) (xy 389.186709 -400.540947) (xy 389.222424 -400.582164) (xy 389.25191 -400.628045)
			(xy 389.274567 -400.677655) (xy 389.289932 -400.729985) (xy 389.297694 -400.783969) (xy 389.29818 -400.811238)
			(xy 389.29818 -401.674838) (xy 403.06244 -401.674838) (xy 403.06244 -400.811238) (xy 403.062926 -400.783969)
			(xy 403.070688 -400.729985) (xy 403.086053 -400.677655) (xy 403.10871 -400.628045) (xy 403.138196 -400.582164)
			(xy 403.173911 -400.540947) (xy 403.215128 -400.505232) (xy 403.261009 -400.475746) (xy 403.310619 -400.453089)
			(xy 403.362949 -400.437724) (xy 403.416933 -400.429962) (xy 403.471471 -400.429962) (xy 403.525455 -400.437724)
			(xy 403.577785 -400.453089) (xy 403.627395 -400.475746) (xy 403.673276 -400.505232) (xy 403.714493 -400.540947)
			(xy 403.750208 -400.582164) (xy 403.779694 -400.628045) (xy 403.802351 -400.677655) (xy 403.817716 -400.729985)
			(xy 403.825478 -400.783969) (xy 403.825964 -400.811238) (xy 403.825964 -401.674838) (xy 404.262336 -401.674838)
			(xy 404.262336 -400.811238) (xy 404.262822 -400.783969) (xy 404.270584 -400.729985) (xy 404.285949 -400.677655)
			(xy 404.308606 -400.628045) (xy 404.338092 -400.582164) (xy 404.373807 -400.540947) (xy 404.415024 -400.505232)
			(xy 404.460905 -400.475746) (xy 404.510515 -400.453089) (xy 404.562845 -400.437724) (xy 404.616829 -400.429962)
			(xy 404.671367 -400.429962) (xy 404.725351 -400.437724) (xy 404.777681 -400.453089) (xy 404.827291 -400.475746)
			(xy 404.873172 -400.505232) (xy 404.914389 -400.540947) (xy 404.950104 -400.582164) (xy 404.97959 -400.628045)
			(xy 405.002247 -400.677655) (xy 405.017612 -400.729985) (xy 405.025374 -400.783969) (xy 405.02586 -400.811238)
			(xy 405.02586 -401.674838) (xy 405.46274 -401.674838) (xy 405.46274 -400.811238) (xy 405.463226 -400.783987)
			(xy 405.470982 -400.730039) (xy 405.486337 -400.677744) (xy 405.508979 -400.628167) (xy 405.538445 -400.582317)
			(xy 405.574136 -400.541126) (xy 405.615327 -400.505435) (xy 405.661177 -400.475969) (xy 405.710754 -400.453327)
			(xy 405.763049 -400.437972) (xy 405.816997 -400.430216) (xy 405.871499 -400.430216) (xy 405.925447 -400.437972)
			(xy 405.977742 -400.453327) (xy 406.027319 -400.475969) (xy 406.073169 -400.505435) (xy 406.11436 -400.541126)
			(xy 406.150051 -400.582317) (xy 406.179517 -400.628167) (xy 406.202159 -400.677744) (xy 406.217514 -400.730039)
			(xy 406.22527 -400.783987) (xy 406.225756 -400.811238) (xy 406.225756 -401.674838) (xy 406.662636 -401.674838)
			(xy 406.662636 -400.811238) (xy 406.663122 -400.783987) (xy 406.670878 -400.730039) (xy 406.686233 -400.677744)
			(xy 406.708875 -400.628167) (xy 406.738341 -400.582317) (xy 406.774032 -400.541126) (xy 406.815223 -400.505435)
			(xy 406.861073 -400.475969) (xy 406.91065 -400.453327) (xy 406.962945 -400.437972) (xy 407.016893 -400.430216)
			(xy 407.071395 -400.430216) (xy 407.125343 -400.437972) (xy 407.177638 -400.453327) (xy 407.227215 -400.475969)
			(xy 407.273065 -400.505435) (xy 407.314256 -400.541126) (xy 407.349947 -400.582317) (xy 407.379413 -400.628167)
			(xy 407.402055 -400.677744) (xy 407.41741 -400.730039) (xy 407.425166 -400.783987) (xy 407.425652 -400.811238)
			(xy 407.425652 -401.674838) (xy 407.862532 -401.674838) (xy 407.862532 -400.811238) (xy 407.863018 -400.783969)
			(xy 407.87078 -400.729985) (xy 407.886145 -400.677655) (xy 407.908802 -400.628045) (xy 407.938288 -400.582164)
			(xy 407.974003 -400.540947) (xy 408.01522 -400.505232) (xy 408.061101 -400.475746) (xy 408.110711 -400.453089)
			(xy 408.163041 -400.437724) (xy 408.217025 -400.429962) (xy 408.271563 -400.429962) (xy 408.325547 -400.437724)
			(xy 408.377877 -400.453089) (xy 408.427487 -400.475746) (xy 408.473368 -400.505232) (xy 408.514585 -400.540947)
			(xy 408.5503 -400.582164) (xy 408.579786 -400.628045) (xy 408.602443 -400.677655) (xy 408.617808 -400.729985)
			(xy 408.62557 -400.783969) (xy 408.626056 -400.811238) (xy 408.626056 -401.674838) (xy 409.062428 -401.674838)
			(xy 409.062428 -400.811238) (xy 409.062914 -400.783969) (xy 409.070676 -400.729985) (xy 409.086041 -400.677655)
			(xy 409.108698 -400.628045) (xy 409.138184 -400.582164) (xy 409.173899 -400.540947) (xy 409.215116 -400.505232)
			(xy 409.260997 -400.475746) (xy 409.310607 -400.453089) (xy 409.362937 -400.437724) (xy 409.416921 -400.429962)
			(xy 409.471459 -400.429962) (xy 409.525443 -400.437724) (xy 409.577773 -400.453089) (xy 409.627383 -400.475746)
			(xy 409.673264 -400.505232) (xy 409.714481 -400.540947) (xy 409.750196 -400.582164) (xy 409.779682 -400.628045)
			(xy 409.802339 -400.677655) (xy 409.817704 -400.729985) (xy 409.825466 -400.783969) (xy 409.825952 -400.811238)
			(xy 409.825952 -401.674838) (xy 410.262832 -401.674838) (xy 410.262832 -400.811238) (xy 410.263318 -400.783987)
			(xy 410.271074 -400.730039) (xy 410.286429 -400.677744) (xy 410.309071 -400.628167) (xy 410.338537 -400.582317)
			(xy 410.374228 -400.541126) (xy 410.415419 -400.505435) (xy 410.461269 -400.475969) (xy 410.510846 -400.453327)
			(xy 410.563141 -400.437972) (xy 410.617089 -400.430216) (xy 410.671591 -400.430216) (xy 410.725539 -400.437972)
			(xy 410.777834 -400.453327) (xy 410.827411 -400.475969) (xy 410.873261 -400.505435) (xy 410.914452 -400.541126)
			(xy 410.950143 -400.582317) (xy 410.979609 -400.628167) (xy 411.002251 -400.677744) (xy 411.017606 -400.730039)
			(xy 411.025362 -400.783987) (xy 411.025848 -400.811238) (xy 411.025848 -401.674838) (xy 411.462728 -401.674838)
			(xy 411.462728 -400.811238) (xy 411.463214 -400.783987) (xy 411.47097 -400.730039) (xy 411.486325 -400.677744)
			(xy 411.508967 -400.628167) (xy 411.538433 -400.582317) (xy 411.574124 -400.541126) (xy 411.615315 -400.505435)
			(xy 411.661165 -400.475969) (xy 411.710742 -400.453327) (xy 411.763037 -400.437972) (xy 411.816985 -400.430216)
			(xy 411.871487 -400.430216) (xy 411.925435 -400.437972) (xy 411.97773 -400.453327) (xy 412.027307 -400.475969)
			(xy 412.073157 -400.505435) (xy 412.114348 -400.541126) (xy 412.150039 -400.582317) (xy 412.179505 -400.628167)
			(xy 412.202147 -400.677744) (xy 412.217502 -400.730039) (xy 412.225258 -400.783987) (xy 412.225744 -400.811238)
			(xy 412.225744 -401.674838) (xy 412.662624 -401.674838) (xy 412.662624 -400.811238) (xy 412.66311 -400.783969)
			(xy 412.670872 -400.729985) (xy 412.686237 -400.677655) (xy 412.708894 -400.628045) (xy 412.73838 -400.582164)
			(xy 412.774095 -400.540947) (xy 412.815312 -400.505232) (xy 412.861193 -400.475746) (xy 412.910803 -400.453089)
			(xy 412.963133 -400.437724) (xy 413.017117 -400.429962) (xy 413.071655 -400.429962) (xy 413.125639 -400.437724)
			(xy 413.177969 -400.453089) (xy 413.227579 -400.475746) (xy 413.27346 -400.505232) (xy 413.314677 -400.540947)
			(xy 413.350392 -400.582164) (xy 413.379878 -400.628045) (xy 413.402535 -400.677655) (xy 413.4179 -400.729985)
			(xy 413.425662 -400.783969) (xy 413.426148 -400.811238) (xy 413.426148 -401.674838) (xy 413.86252 -401.674838)
			(xy 413.86252 -400.811238) (xy 413.863006 -400.783969) (xy 413.870768 -400.729985) (xy 413.886133 -400.677655)
			(xy 413.90879 -400.628045) (xy 413.938276 -400.582164) (xy 413.973991 -400.540947) (xy 414.015208 -400.505232)
			(xy 414.061089 -400.475746) (xy 414.110699 -400.453089) (xy 414.163029 -400.437724) (xy 414.217013 -400.429962)
			(xy 414.271551 -400.429962) (xy 414.325535 -400.437724) (xy 414.377865 -400.453089) (xy 414.427475 -400.475746)
			(xy 414.473356 -400.505232) (xy 414.514573 -400.540947) (xy 414.550288 -400.582164) (xy 414.579774 -400.628045)
			(xy 414.602431 -400.677655) (xy 414.617796 -400.729985) (xy 414.625558 -400.783969) (xy 414.626044 -400.811238)
			(xy 414.626044 -401.674838) (xy 415.062924 -401.674838) (xy 415.062924 -400.811238) (xy 415.06341 -400.783987)
			(xy 415.071166 -400.730039) (xy 415.086521 -400.677744) (xy 415.109163 -400.628167) (xy 415.138629 -400.582317)
			(xy 415.17432 -400.541126) (xy 415.215511 -400.505435) (xy 415.261361 -400.475969) (xy 415.310938 -400.453327)
			(xy 415.363233 -400.437972) (xy 415.417181 -400.430216) (xy 415.471683 -400.430216) (xy 415.525631 -400.437972)
			(xy 415.577926 -400.453327) (xy 415.627503 -400.475969) (xy 415.673353 -400.505435) (xy 415.714544 -400.541126)
			(xy 415.750235 -400.582317) (xy 415.779701 -400.628167) (xy 415.802343 -400.677744) (xy 415.817698 -400.730039)
			(xy 415.825454 -400.783987) (xy 415.82594 -400.811238) (xy 415.82594 -401.674838) (xy 416.26282 -401.674838)
			(xy 416.26282 -400.811238) (xy 416.263306 -400.783987) (xy 416.271062 -400.730039) (xy 416.286417 -400.677744)
			(xy 416.309059 -400.628167) (xy 416.338525 -400.582317) (xy 416.374216 -400.541126) (xy 416.415407 -400.505435)
			(xy 416.461257 -400.475969) (xy 416.510834 -400.453327) (xy 416.563129 -400.437972) (xy 416.617077 -400.430216)
			(xy 416.671579 -400.430216) (xy 416.725527 -400.437972) (xy 416.777822 -400.453327) (xy 416.827399 -400.475969)
			(xy 416.873249 -400.505435) (xy 416.91444 -400.541126) (xy 416.950131 -400.582317) (xy 416.979597 -400.628167)
			(xy 417.002239 -400.677744) (xy 417.017594 -400.730039) (xy 417.02535 -400.783987) (xy 417.025836 -400.811238)
			(xy 417.025836 -401.674838) (xy 417.462716 -401.674838) (xy 417.462716 -400.811238) (xy 417.463202 -400.783987)
			(xy 417.470958 -400.730039) (xy 417.486313 -400.677744) (xy 417.508955 -400.628167) (xy 417.538421 -400.582317)
			(xy 417.574112 -400.541126) (xy 417.615303 -400.505435) (xy 417.661153 -400.475969) (xy 417.71073 -400.453327)
			(xy 417.763025 -400.437972) (xy 417.816973 -400.430216) (xy 417.871475 -400.430216) (xy 417.925423 -400.437972)
			(xy 417.977718 -400.453327) (xy 418.027295 -400.475969) (xy 418.073145 -400.505435) (xy 418.114336 -400.541126)
			(xy 418.150027 -400.582317) (xy 418.179493 -400.628167) (xy 418.202135 -400.677744) (xy 418.21749 -400.730039)
			(xy 418.225246 -400.783987) (xy 418.225732 -400.811238) (xy 418.225732 -401.674838) (xy 418.662612 -401.674838)
			(xy 418.662612 -400.811238) (xy 418.663098 -400.783987) (xy 418.670854 -400.730039) (xy 418.686209 -400.677744)
			(xy 418.708851 -400.628167) (xy 418.738317 -400.582317) (xy 418.774008 -400.541126) (xy 418.815199 -400.505435)
			(xy 418.861049 -400.475969) (xy 418.910626 -400.453327) (xy 418.962921 -400.437972) (xy 419.016869 -400.430216)
			(xy 419.071371 -400.430216) (xy 419.125319 -400.437972) (xy 419.177614 -400.453327) (xy 419.227191 -400.475969)
			(xy 419.273041 -400.505435) (xy 419.314232 -400.541126) (xy 419.349923 -400.582317) (xy 419.379389 -400.628167)
			(xy 419.402031 -400.677744) (xy 419.417386 -400.730039) (xy 419.425142 -400.783987) (xy 419.425628 -400.811238)
			(xy 419.425628 -401.674838) (xy 419.862508 -401.674838) (xy 419.862508 -400.811238) (xy 419.862994 -400.783969)
			(xy 419.870756 -400.729985) (xy 419.886121 -400.677655) (xy 419.908778 -400.628045) (xy 419.938264 -400.582164)
			(xy 419.973979 -400.540947) (xy 420.015196 -400.505232) (xy 420.061077 -400.475746) (xy 420.110687 -400.453089)
			(xy 420.163017 -400.437724) (xy 420.217001 -400.429962) (xy 420.271539 -400.429962) (xy 420.325523 -400.437724)
			(xy 420.377853 -400.453089) (xy 420.427463 -400.475746) (xy 420.473344 -400.505232) (xy 420.514561 -400.540947)
			(xy 420.550276 -400.582164) (xy 420.579762 -400.628045) (xy 420.602419 -400.677655) (xy 420.617784 -400.729985)
			(xy 420.625546 -400.783969) (xy 420.626032 -400.811238) (xy 420.626032 -401.674838) (xy 421.062404 -401.674838)
			(xy 421.062404 -400.811238) (xy 421.06289 -400.783969) (xy 421.070652 -400.729985) (xy 421.086017 -400.677655)
			(xy 421.108674 -400.628045) (xy 421.13816 -400.582164) (xy 421.173875 -400.540947) (xy 421.215092 -400.505232)
			(xy 421.260973 -400.475746) (xy 421.310583 -400.453089) (xy 421.362913 -400.437724) (xy 421.416897 -400.429962)
			(xy 421.471435 -400.429962) (xy 421.525419 -400.437724) (xy 421.577749 -400.453089) (xy 421.627359 -400.475746)
			(xy 421.67324 -400.505232) (xy 421.714457 -400.540947) (xy 421.750172 -400.582164) (xy 421.779658 -400.628045)
			(xy 421.802315 -400.677655) (xy 421.81768 -400.729985) (xy 421.825442 -400.783969) (xy 421.825928 -400.811238)
			(xy 421.825928 -401.674838) (xy 421.825442 -401.702107) (xy 421.81768 -401.756091) (xy 421.802315 -401.808421)
			(xy 421.779658 -401.858031) (xy 421.750172 -401.903912) (xy 421.714457 -401.945129) (xy 421.67324 -401.980844)
			(xy 421.627359 -402.01033) (xy 421.577749 -402.032987) (xy 421.525419 -402.048352) (xy 421.471435 -402.056114)
			(xy 421.416897 -402.056114) (xy 421.362913 -402.048352) (xy 421.310583 -402.032987) (xy 421.260973 -402.01033)
			(xy 421.215092 -401.980844) (xy 421.173875 -401.945129) (xy 421.13816 -401.903912) (xy 421.108674 -401.858031)
			(xy 421.086017 -401.808421) (xy 421.070652 -401.756091) (xy 421.06289 -401.702107) (xy 421.062404 -401.674838)
			(xy 420.626032 -401.674838) (xy 420.625546 -401.702107) (xy 420.617784 -401.756091) (xy 420.602419 -401.808421)
			(xy 420.579762 -401.858031) (xy 420.550276 -401.903912) (xy 420.514561 -401.945129) (xy 420.473344 -401.980844)
			(xy 420.427463 -402.01033) (xy 420.377853 -402.032987) (xy 420.325523 -402.048352) (xy 420.271539 -402.056114)
			(xy 420.217001 -402.056114) (xy 420.163017 -402.048352) (xy 420.110687 -402.032987) (xy 420.061077 -402.01033)
			(xy 420.015196 -401.980844) (xy 419.973979 -401.945129) (xy 419.938264 -401.903912) (xy 419.908778 -401.858031)
			(xy 419.886121 -401.808421) (xy 419.870756 -401.756091) (xy 419.862994 -401.702107) (xy 419.862508 -401.674838)
			(xy 419.425628 -401.674838) (xy 419.425142 -401.702089) (xy 419.417386 -401.756037) (xy 419.402031 -401.808332)
			(xy 419.379389 -401.857909) (xy 419.349923 -401.903759) (xy 419.314232 -401.94495) (xy 419.273041 -401.980641)
			(xy 419.227191 -402.010107) (xy 419.177614 -402.032749) (xy 419.125319 -402.048104) (xy 419.071371 -402.05586)
			(xy 419.016869 -402.05586) (xy 418.962921 -402.048104) (xy 418.910626 -402.032749) (xy 418.861049 -402.010107)
			(xy 418.815199 -401.980641) (xy 418.774008 -401.94495) (xy 418.738317 -401.903759) (xy 418.708851 -401.857909)
			(xy 418.686209 -401.808332) (xy 418.670854 -401.756037) (xy 418.663098 -401.702089) (xy 418.662612 -401.674838)
			(xy 418.225732 -401.674838) (xy 418.225246 -401.702089) (xy 418.21749 -401.756037) (xy 418.202135 -401.808332)
			(xy 418.179493 -401.857909) (xy 418.150027 -401.903759) (xy 418.114336 -401.94495) (xy 418.073145 -401.980641)
			(xy 418.027295 -402.010107) (xy 417.977718 -402.032749) (xy 417.925423 -402.048104) (xy 417.871475 -402.05586)
			(xy 417.816973 -402.05586) (xy 417.763025 -402.048104) (xy 417.71073 -402.032749) (xy 417.661153 -402.010107)
			(xy 417.615303 -401.980641) (xy 417.574112 -401.94495) (xy 417.538421 -401.903759) (xy 417.508955 -401.857909)
			(xy 417.486313 -401.808332) (xy 417.470958 -401.756037) (xy 417.463202 -401.702089) (xy 417.462716 -401.674838)
			(xy 417.025836 -401.674838) (xy 417.02535 -401.702089) (xy 417.017594 -401.756037) (xy 417.002239 -401.808332)
			(xy 416.979597 -401.857909) (xy 416.950131 -401.903759) (xy 416.91444 -401.94495) (xy 416.873249 -401.980641)
			(xy 416.827399 -402.010107) (xy 416.777822 -402.032749) (xy 416.725527 -402.048104) (xy 416.671579 -402.05586)
			(xy 416.617077 -402.05586) (xy 416.563129 -402.048104) (xy 416.510834 -402.032749) (xy 416.461257 -402.010107)
			(xy 416.415407 -401.980641) (xy 416.374216 -401.94495) (xy 416.338525 -401.903759) (xy 416.309059 -401.857909)
			(xy 416.286417 -401.808332) (xy 416.271062 -401.756037) (xy 416.263306 -401.702089) (xy 416.26282 -401.674838)
			(xy 415.82594 -401.674838) (xy 415.825454 -401.702089) (xy 415.817698 -401.756037) (xy 415.802343 -401.808332)
			(xy 415.779701 -401.857909) (xy 415.750235 -401.903759) (xy 415.714544 -401.94495) (xy 415.673353 -401.980641)
			(xy 415.627503 -402.010107) (xy 415.577926 -402.032749) (xy 415.525631 -402.048104) (xy 415.471683 -402.05586)
			(xy 415.417181 -402.05586) (xy 415.363233 -402.048104) (xy 415.310938 -402.032749) (xy 415.261361 -402.010107)
			(xy 415.215511 -401.980641) (xy 415.17432 -401.94495) (xy 415.138629 -401.903759) (xy 415.109163 -401.857909)
			(xy 415.086521 -401.808332) (xy 415.071166 -401.756037) (xy 415.06341 -401.702089) (xy 415.062924 -401.674838)
			(xy 414.626044 -401.674838) (xy 414.625558 -401.702107) (xy 414.617796 -401.756091) (xy 414.602431 -401.808421)
			(xy 414.579774 -401.858031) (xy 414.550288 -401.903912) (xy 414.514573 -401.945129) (xy 414.473356 -401.980844)
			(xy 414.427475 -402.01033) (xy 414.377865 -402.032987) (xy 414.325535 -402.048352) (xy 414.271551 -402.056114)
			(xy 414.217013 -402.056114) (xy 414.163029 -402.048352) (xy 414.110699 -402.032987) (xy 414.061089 -402.01033)
			(xy 414.015208 -401.980844) (xy 413.973991 -401.945129) (xy 413.938276 -401.903912) (xy 413.90879 -401.858031)
			(xy 413.886133 -401.808421) (xy 413.870768 -401.756091) (xy 413.863006 -401.702107) (xy 413.86252 -401.674838)
			(xy 413.426148 -401.674838) (xy 413.425662 -401.702107) (xy 413.4179 -401.756091) (xy 413.402535 -401.808421)
			(xy 413.379878 -401.858031) (xy 413.350392 -401.903912) (xy 413.314677 -401.945129) (xy 413.27346 -401.980844)
			(xy 413.227579 -402.01033) (xy 413.177969 -402.032987) (xy 413.125639 -402.048352) (xy 413.071655 -402.056114)
			(xy 413.017117 -402.056114) (xy 412.963133 -402.048352) (xy 412.910803 -402.032987) (xy 412.861193 -402.01033)
			(xy 412.815312 -401.980844) (xy 412.774095 -401.945129) (xy 412.73838 -401.903912) (xy 412.708894 -401.858031)
			(xy 412.686237 -401.808421) (xy 412.670872 -401.756091) (xy 412.66311 -401.702107) (xy 412.662624 -401.674838)
			(xy 412.225744 -401.674838) (xy 412.225258 -401.702089) (xy 412.217502 -401.756037) (xy 412.202147 -401.808332)
			(xy 412.179505 -401.857909) (xy 412.150039 -401.903759) (xy 412.114348 -401.94495) (xy 412.073157 -401.980641)
			(xy 412.027307 -402.010107) (xy 411.97773 -402.032749) (xy 411.925435 -402.048104) (xy 411.871487 -402.05586)
			(xy 411.816985 -402.05586) (xy 411.763037 -402.048104) (xy 411.710742 -402.032749) (xy 411.661165 -402.010107)
			(xy 411.615315 -401.980641) (xy 411.574124 -401.94495) (xy 411.538433 -401.903759) (xy 411.508967 -401.857909)
			(xy 411.486325 -401.808332) (xy 411.47097 -401.756037) (xy 411.463214 -401.702089) (xy 411.462728 -401.674838)
			(xy 411.025848 -401.674838) (xy 411.025362 -401.702089) (xy 411.017606 -401.756037) (xy 411.002251 -401.808332)
			(xy 410.979609 -401.857909) (xy 410.950143 -401.903759) (xy 410.914452 -401.94495) (xy 410.873261 -401.980641)
			(xy 410.827411 -402.010107) (xy 410.777834 -402.032749) (xy 410.725539 -402.048104) (xy 410.671591 -402.05586)
			(xy 410.617089 -402.05586) (xy 410.563141 -402.048104) (xy 410.510846 -402.032749) (xy 410.461269 -402.010107)
			(xy 410.415419 -401.980641) (xy 410.374228 -401.94495) (xy 410.338537 -401.903759) (xy 410.309071 -401.857909)
			(xy 410.286429 -401.808332) (xy 410.271074 -401.756037) (xy 410.263318 -401.702089) (xy 410.262832 -401.674838)
			(xy 409.825952 -401.674838) (xy 409.825466 -401.702107) (xy 409.817704 -401.756091) (xy 409.802339 -401.808421)
			(xy 409.779682 -401.858031) (xy 409.750196 -401.903912) (xy 409.714481 -401.945129) (xy 409.673264 -401.980844)
			(xy 409.627383 -402.01033) (xy 409.577773 -402.032987) (xy 409.525443 -402.048352) (xy 409.471459 -402.056114)
			(xy 409.416921 -402.056114) (xy 409.362937 -402.048352) (xy 409.310607 -402.032987) (xy 409.260997 -402.01033)
			(xy 409.215116 -401.980844) (xy 409.173899 -401.945129) (xy 409.138184 -401.903912) (xy 409.108698 -401.858031)
			(xy 409.086041 -401.808421) (xy 409.070676 -401.756091) (xy 409.062914 -401.702107) (xy 409.062428 -401.674838)
			(xy 408.626056 -401.674838) (xy 408.62557 -401.702107) (xy 408.617808 -401.756091) (xy 408.602443 -401.808421)
			(xy 408.579786 -401.858031) (xy 408.5503 -401.903912) (xy 408.514585 -401.945129) (xy 408.473368 -401.980844)
			(xy 408.427487 -402.01033) (xy 408.377877 -402.032987) (xy 408.325547 -402.048352) (xy 408.271563 -402.056114)
			(xy 408.217025 -402.056114) (xy 408.163041 -402.048352) (xy 408.110711 -402.032987) (xy 408.061101 -402.01033)
			(xy 408.01522 -401.980844) (xy 407.974003 -401.945129) (xy 407.938288 -401.903912) (xy 407.908802 -401.858031)
			(xy 407.886145 -401.808421) (xy 407.87078 -401.756091) (xy 407.863018 -401.702107) (xy 407.862532 -401.674838)
			(xy 407.425652 -401.674838) (xy 407.425166 -401.702089) (xy 407.41741 -401.756037) (xy 407.402055 -401.808332)
			(xy 407.379413 -401.857909) (xy 407.349947 -401.903759) (xy 407.314256 -401.94495) (xy 407.273065 -401.980641)
			(xy 407.227215 -402.010107) (xy 407.177638 -402.032749) (xy 407.125343 -402.048104) (xy 407.071395 -402.05586)
			(xy 407.016893 -402.05586) (xy 406.962945 -402.048104) (xy 406.91065 -402.032749) (xy 406.861073 -402.010107)
			(xy 406.815223 -401.980641) (xy 406.774032 -401.94495) (xy 406.738341 -401.903759) (xy 406.708875 -401.857909)
			(xy 406.686233 -401.808332) (xy 406.670878 -401.756037) (xy 406.663122 -401.702089) (xy 406.662636 -401.674838)
			(xy 406.225756 -401.674838) (xy 406.22527 -401.702089) (xy 406.217514 -401.756037) (xy 406.202159 -401.808332)
			(xy 406.179517 -401.857909) (xy 406.150051 -401.903759) (xy 406.11436 -401.94495) (xy 406.073169 -401.980641)
			(xy 406.027319 -402.010107) (xy 405.977742 -402.032749) (xy 405.925447 -402.048104) (xy 405.871499 -402.05586)
			(xy 405.816997 -402.05586) (xy 405.763049 -402.048104) (xy 405.710754 -402.032749) (xy 405.661177 -402.010107)
			(xy 405.615327 -401.980641) (xy 405.574136 -401.94495) (xy 405.538445 -401.903759) (xy 405.508979 -401.857909)
			(xy 405.486337 -401.808332) (xy 405.470982 -401.756037) (xy 405.463226 -401.702089) (xy 405.46274 -401.674838)
			(xy 405.02586 -401.674838) (xy 405.025374 -401.702107) (xy 405.017612 -401.756091) (xy 405.002247 -401.808421)
			(xy 404.97959 -401.858031) (xy 404.950104 -401.903912) (xy 404.914389 -401.945129) (xy 404.873172 -401.980844)
			(xy 404.827291 -402.01033) (xy 404.777681 -402.032987) (xy 404.725351 -402.048352) (xy 404.671367 -402.056114)
			(xy 404.616829 -402.056114) (xy 404.562845 -402.048352) (xy 404.510515 -402.032987) (xy 404.460905 -402.01033)
			(xy 404.415024 -401.980844) (xy 404.373807 -401.945129) (xy 404.338092 -401.903912) (xy 404.308606 -401.858031)
			(xy 404.285949 -401.808421) (xy 404.270584 -401.756091) (xy 404.262822 -401.702107) (xy 404.262336 -401.674838)
			(xy 403.825964 -401.674838) (xy 403.825478 -401.702107) (xy 403.817716 -401.756091) (xy 403.802351 -401.808421)
			(xy 403.779694 -401.858031) (xy 403.750208 -401.903912) (xy 403.714493 -401.945129) (xy 403.673276 -401.980844)
			(xy 403.627395 -402.01033) (xy 403.577785 -402.032987) (xy 403.525455 -402.048352) (xy 403.471471 -402.056114)
			(xy 403.416933 -402.056114) (xy 403.362949 -402.048352) (xy 403.310619 -402.032987) (xy 403.261009 -402.01033)
			(xy 403.215128 -401.980844) (xy 403.173911 -401.945129) (xy 403.138196 -401.903912) (xy 403.10871 -401.858031)
			(xy 403.086053 -401.808421) (xy 403.070688 -401.756091) (xy 403.062926 -401.702107) (xy 403.06244 -401.674838)
			(xy 389.29818 -401.674838) (xy 389.297694 -401.702107) (xy 389.289932 -401.756091) (xy 389.274567 -401.808421)
			(xy 389.25191 -401.858031) (xy 389.222424 -401.903912) (xy 389.186709 -401.945129) (xy 389.145492 -401.980844)
			(xy 389.099611 -402.01033) (xy 389.050001 -402.032987) (xy 388.997671 -402.048352) (xy 388.943687 -402.056114)
			(xy 388.889149 -402.056114) (xy 388.835165 -402.048352) (xy 388.782835 -402.032987) (xy 388.733225 -402.01033)
			(xy 388.687344 -401.980844) (xy 388.646127 -401.945129) (xy 388.610412 -401.903912) (xy 388.580926 -401.858031)
			(xy 388.558269 -401.808421) (xy 388.542904 -401.756091) (xy 388.535142 -401.702107) (xy 388.534656 -401.674838)
			(xy 388.098284 -401.674838) (xy 388.097798 -401.702107) (xy 388.090036 -401.756091) (xy 388.074671 -401.808421)
			(xy 388.052014 -401.858031) (xy 388.022528 -401.903912) (xy 387.986813 -401.945129) (xy 387.945596 -401.980844)
			(xy 387.899715 -402.01033) (xy 387.850105 -402.032987) (xy 387.797775 -402.048352) (xy 387.743791 -402.056114)
			(xy 387.689253 -402.056114) (xy 387.635269 -402.048352) (xy 387.582939 -402.032987) (xy 387.533329 -402.01033)
			(xy 387.487448 -401.980844) (xy 387.446231 -401.945129) (xy 387.410516 -401.903912) (xy 387.38103 -401.858031)
			(xy 387.358373 -401.808421) (xy 387.343008 -401.756091) (xy 387.335246 -401.702107) (xy 387.33476 -401.674838)
			(xy 386.89788 -401.674838) (xy 386.897394 -401.702089) (xy 386.889638 -401.756037) (xy 386.874283 -401.808332)
			(xy 386.851641 -401.857909) (xy 386.822175 -401.903759) (xy 386.786484 -401.94495) (xy 386.745293 -401.980641)
			(xy 386.699443 -402.010107) (xy 386.649866 -402.032749) (xy 386.597571 -402.048104) (xy 386.543623 -402.05586)
			(xy 386.489121 -402.05586) (xy 386.435173 -402.048104) (xy 386.382878 -402.032749) (xy 386.333301 -402.010107)
			(xy 386.287451 -401.980641) (xy 386.24626 -401.94495) (xy 386.210569 -401.903759) (xy 386.181103 -401.857909)
			(xy 386.158461 -401.808332) (xy 386.143106 -401.756037) (xy 386.13535 -401.702089) (xy 386.134864 -401.674838)
			(xy 385.697984 -401.674838) (xy 385.697498 -401.702089) (xy 385.689742 -401.756037) (xy 385.674387 -401.808332)
			(xy 385.651745 -401.857909) (xy 385.622279 -401.903759) (xy 385.586588 -401.94495) (xy 385.545397 -401.980641)
			(xy 385.499547 -402.010107) (xy 385.44997 -402.032749) (xy 385.397675 -402.048104) (xy 385.343727 -402.05586)
			(xy 385.289225 -402.05586) (xy 385.235277 -402.048104) (xy 385.182982 -402.032749) (xy 385.133405 -402.010107)
			(xy 385.087555 -401.980641) (xy 385.046364 -401.94495) (xy 385.010673 -401.903759) (xy 384.981207 -401.857909)
			(xy 384.958565 -401.808332) (xy 384.94321 -401.756037) (xy 384.935454 -401.702089) (xy 384.934968 -401.674838)
			(xy 384.498088 -401.674838) (xy 384.497602 -401.702089) (xy 384.489846 -401.756037) (xy 384.474491 -401.808332)
			(xy 384.451849 -401.857909) (xy 384.422383 -401.903759) (xy 384.386692 -401.94495) (xy 384.345501 -401.980641)
			(xy 384.299651 -402.010107) (xy 384.250074 -402.032749) (xy 384.197779 -402.048104) (xy 384.143831 -402.05586)
			(xy 384.089329 -402.05586) (xy 384.035381 -402.048104) (xy 383.983086 -402.032749) (xy 383.933509 -402.010107)
			(xy 383.887659 -401.980641) (xy 383.846468 -401.94495) (xy 383.810777 -401.903759) (xy 383.781311 -401.857909)
			(xy 383.758669 -401.808332) (xy 383.743314 -401.756037) (xy 383.735558 -401.702089) (xy 383.735072 -401.674838)
			(xy 383.298192 -401.674838) (xy 383.297706 -401.702089) (xy 383.28995 -401.756037) (xy 383.274595 -401.808332)
			(xy 383.251953 -401.857909) (xy 383.222487 -401.903759) (xy 383.186796 -401.94495) (xy 383.145605 -401.980641)
			(xy 383.099755 -402.010107) (xy 383.050178 -402.032749) (xy 382.997883 -402.048104) (xy 382.943935 -402.05586)
			(xy 382.889433 -402.05586) (xy 382.835485 -402.048104) (xy 382.78319 -402.032749) (xy 382.733613 -402.010107)
			(xy 382.687763 -401.980641) (xy 382.646572 -401.94495) (xy 382.610881 -401.903759) (xy 382.581415 -401.857909)
			(xy 382.558773 -401.808332) (xy 382.543418 -401.756037) (xy 382.535662 -401.702089) (xy 382.535176 -401.674838)
			(xy 382.098296 -401.674838) (xy 382.09781 -401.702107) (xy 382.090048 -401.756091) (xy 382.074683 -401.808421)
			(xy 382.052026 -401.858031) (xy 382.02254 -401.903912) (xy 381.986825 -401.945129) (xy 381.945608 -401.980844)
			(xy 381.899727 -402.01033) (xy 381.850117 -402.032987) (xy 381.797787 -402.048352) (xy 381.743803 -402.056114)
			(xy 381.689265 -402.056114) (xy 381.635281 -402.048352) (xy 381.582951 -402.032987) (xy 381.533341 -402.01033)
			(xy 381.48746 -401.980844) (xy 381.446243 -401.945129) (xy 381.410528 -401.903912) (xy 381.381042 -401.858031)
			(xy 381.358385 -401.808421) (xy 381.34302 -401.756091) (xy 381.335258 -401.702107) (xy 381.334772 -401.674838)
			(xy 380.8984 -401.674838) (xy 380.897914 -401.702107) (xy 380.890152 -401.756091) (xy 380.874787 -401.808421)
			(xy 380.85213 -401.858031) (xy 380.822644 -401.903912) (xy 380.786929 -401.945129) (xy 380.745712 -401.980844)
			(xy 380.699831 -402.01033) (xy 380.650221 -402.032987) (xy 380.597891 -402.048352) (xy 380.543907 -402.056114)
			(xy 380.489369 -402.056114) (xy 380.435385 -402.048352) (xy 380.383055 -402.032987) (xy 380.333445 -402.01033)
			(xy 380.287564 -401.980844) (xy 380.246347 -401.945129) (xy 380.210632 -401.903912) (xy 380.181146 -401.858031)
			(xy 380.158489 -401.808421) (xy 380.143124 -401.756091) (xy 380.135362 -401.702107) (xy 380.134876 -401.674838)
			(xy 379.697996 -401.674838) (xy 379.69751 -401.702089) (xy 379.689754 -401.756037) (xy 379.674399 -401.808332)
			(xy 379.651757 -401.857909) (xy 379.622291 -401.903759) (xy 379.5866 -401.94495) (xy 379.545409 -401.980641)
			(xy 379.499559 -402.010107) (xy 379.449982 -402.032749) (xy 379.397687 -402.048104) (xy 379.343739 -402.05586)
			(xy 379.289237 -402.05586) (xy 379.235289 -402.048104) (xy 379.182994 -402.032749) (xy 379.133417 -402.010107)
			(xy 379.087567 -401.980641) (xy 379.046376 -401.94495) (xy 379.010685 -401.903759) (xy 378.981219 -401.857909)
			(xy 378.958577 -401.808332) (xy 378.943222 -401.756037) (xy 378.935466 -401.702089) (xy 378.93498 -401.674838)
			(xy 378.4981 -401.674838) (xy 378.497614 -401.702089) (xy 378.489858 -401.756037) (xy 378.474503 -401.808332)
			(xy 378.451861 -401.857909) (xy 378.422395 -401.903759) (xy 378.386704 -401.94495) (xy 378.345513 -401.980641)
			(xy 378.299663 -402.010107) (xy 378.250086 -402.032749) (xy 378.197791 -402.048104) (xy 378.143843 -402.05586)
			(xy 378.089341 -402.05586) (xy 378.035393 -402.048104) (xy 377.983098 -402.032749) (xy 377.933521 -402.010107)
			(xy 377.887671 -401.980641) (xy 377.84648 -401.94495) (xy 377.810789 -401.903759) (xy 377.781323 -401.857909)
			(xy 377.758681 -401.808332) (xy 377.743326 -401.756037) (xy 377.73557 -401.702089) (xy 377.735084 -401.674838)
			(xy 377.298204 -401.674838) (xy 377.297718 -401.702107) (xy 377.289956 -401.756091) (xy 377.274591 -401.808421)
			(xy 377.251934 -401.858031) (xy 377.222448 -401.903912) (xy 377.186733 -401.945129) (xy 377.145516 -401.980844)
			(xy 377.099635 -402.01033) (xy 377.050025 -402.032987) (xy 376.997695 -402.048352) (xy 376.943711 -402.056114)
			(xy 376.889173 -402.056114) (xy 376.835189 -402.048352) (xy 376.782859 -402.032987) (xy 376.733249 -402.01033)
			(xy 376.687368 -401.980844) (xy 376.646151 -401.945129) (xy 376.610436 -401.903912) (xy 376.58095 -401.858031)
			(xy 376.558293 -401.808421) (xy 376.542928 -401.756091) (xy 376.535166 -401.702107) (xy 376.53468 -401.674838)
			(xy 376.098308 -401.674838) (xy 376.097822 -401.702107) (xy 376.09006 -401.756091) (xy 376.074695 -401.808421)
			(xy 376.052038 -401.858031) (xy 376.022552 -401.903912) (xy 375.986837 -401.945129) (xy 375.94562 -401.980844)
			(xy 375.899739 -402.01033) (xy 375.850129 -402.032987) (xy 375.797799 -402.048352) (xy 375.743815 -402.056114)
			(xy 375.689277 -402.056114) (xy 375.635293 -402.048352) (xy 375.582963 -402.032987) (xy 375.533353 -402.01033)
			(xy 375.487472 -401.980844) (xy 375.446255 -401.945129) (xy 375.41054 -401.903912) (xy 375.381054 -401.858031)
			(xy 375.358397 -401.808421) (xy 375.343032 -401.756091) (xy 375.33527 -401.702107) (xy 375.334784 -401.674838)
			(xy 374.897904 -401.674838) (xy 374.897418 -401.702089) (xy 374.889662 -401.756037) (xy 374.874307 -401.808332)
			(xy 374.851665 -401.857909) (xy 374.822199 -401.903759) (xy 374.786508 -401.94495) (xy 374.745317 -401.980641)
			(xy 374.699467 -402.010107) (xy 374.64989 -402.032749) (xy 374.597595 -402.048104) (xy 374.543647 -402.05586)
			(xy 374.489145 -402.05586) (xy 374.435197 -402.048104) (xy 374.382902 -402.032749) (xy 374.333325 -402.010107)
			(xy 374.287475 -401.980641) (xy 374.246284 -401.94495) (xy 374.210593 -401.903759) (xy 374.181127 -401.857909)
			(xy 374.158485 -401.808332) (xy 374.14313 -401.756037) (xy 374.135374 -401.702089) (xy 374.134888 -401.674838)
			(xy 373.698008 -401.674838) (xy 373.697522 -401.702089) (xy 373.689766 -401.756037) (xy 373.674411 -401.808332)
			(xy 373.651769 -401.857909) (xy 373.622303 -401.903759) (xy 373.586612 -401.94495) (xy 373.545421 -401.980641)
			(xy 373.499571 -402.010107) (xy 373.449994 -402.032749) (xy 373.397699 -402.048104) (xy 373.343751 -402.05586)
			(xy 373.289249 -402.05586) (xy 373.235301 -402.048104) (xy 373.183006 -402.032749) (xy 373.133429 -402.010107)
			(xy 373.087579 -401.980641) (xy 373.046388 -401.94495) (xy 373.010697 -401.903759) (xy 372.981231 -401.857909)
			(xy 372.958589 -401.808332) (xy 372.943234 -401.756037) (xy 372.935478 -401.702089) (xy 372.934992 -401.674838)
			(xy 372.498112 -401.674838) (xy 372.497626 -401.702107) (xy 372.489864 -401.756091) (xy 372.474499 -401.808421)
			(xy 372.451842 -401.858031) (xy 372.422356 -401.903912) (xy 372.386641 -401.945129) (xy 372.345424 -401.980844)
			(xy 372.299543 -402.01033) (xy 372.249933 -402.032987) (xy 372.197603 -402.048352) (xy 372.143619 -402.056114)
			(xy 372.089081 -402.056114) (xy 372.035097 -402.048352) (xy 371.982767 -402.032987) (xy 371.933157 -402.01033)
			(xy 371.887276 -401.980844) (xy 371.846059 -401.945129) (xy 371.810344 -401.903912) (xy 371.780858 -401.858031)
			(xy 371.758201 -401.808421) (xy 371.742836 -401.756091) (xy 371.735074 -401.702107) (xy 371.734588 -401.674838)
			(xy 371.298216 -401.674838) (xy 371.29773 -401.702107) (xy 371.289968 -401.756091) (xy 371.274603 -401.808421)
			(xy 371.251946 -401.858031) (xy 371.22246 -401.903912) (xy 371.186745 -401.945129) (xy 371.145528 -401.980844)
			(xy 371.099647 -402.01033) (xy 371.050037 -402.032987) (xy 370.997707 -402.048352) (xy 370.943723 -402.056114)
			(xy 370.889185 -402.056114) (xy 370.835201 -402.048352) (xy 370.782871 -402.032987) (xy 370.733261 -402.01033)
			(xy 370.68738 -401.980844) (xy 370.646163 -401.945129) (xy 370.610448 -401.903912) (xy 370.580962 -401.858031)
			(xy 370.558305 -401.808421) (xy 370.54294 -401.756091) (xy 370.535178 -401.702107) (xy 370.534692 -401.674838)
			(xy 354.725732 -401.674838) (xy 354.725246 -401.702107) (xy 354.717484 -401.756091) (xy 354.702119 -401.808421)
			(xy 354.679462 -401.858031) (xy 354.649976 -401.903912) (xy 354.614261 -401.945129) (xy 354.573044 -401.980844)
			(xy 354.527163 -402.01033) (xy 354.477553 -402.032987) (xy 354.425223 -402.048352) (xy 354.371239 -402.056114)
			(xy 354.316701 -402.056114) (xy 354.262717 -402.048352) (xy 354.210387 -402.032987) (xy 354.160777 -402.01033)
			(xy 354.114896 -401.980844) (xy 354.073679 -401.945129) (xy 354.037964 -401.903912) (xy 354.008478 -401.858031)
			(xy 353.985821 -401.808421) (xy 353.970456 -401.756091) (xy 353.962694 -401.702107) (xy 353.962208 -401.674838)
			(xy 353.525836 -401.674838) (xy 353.52535 -401.702107) (xy 353.517588 -401.756091) (xy 353.502223 -401.808421)
			(xy 353.479566 -401.858031) (xy 353.45008 -401.903912) (xy 353.414365 -401.945129) (xy 353.373148 -401.980844)
			(xy 353.327267 -402.01033) (xy 353.277657 -402.032987) (xy 353.225327 -402.048352) (xy 353.171343 -402.056114)
			(xy 353.116805 -402.056114) (xy 353.062821 -402.048352) (xy 353.010491 -402.032987) (xy 352.960881 -402.01033)
			(xy 352.915 -401.980844) (xy 352.873783 -401.945129) (xy 352.838068 -401.903912) (xy 352.808582 -401.858031)
			(xy 352.785925 -401.808421) (xy 352.77056 -401.756091) (xy 352.762798 -401.702107) (xy 352.762312 -401.674838)
			(xy 352.325432 -401.674838) (xy 352.324946 -401.702089) (xy 352.31719 -401.756037) (xy 352.301835 -401.808332)
			(xy 352.279193 -401.857909) (xy 352.249727 -401.903759) (xy 352.214036 -401.94495) (xy 352.172845 -401.980641)
			(xy 352.126995 -402.010107) (xy 352.077418 -402.032749) (xy 352.025123 -402.048104) (xy 351.971175 -402.05586)
			(xy 351.916673 -402.05586) (xy 351.862725 -402.048104) (xy 351.81043 -402.032749) (xy 351.760853 -402.010107)
			(xy 351.715003 -401.980641) (xy 351.673812 -401.94495) (xy 351.638121 -401.903759) (xy 351.608655 -401.857909)
			(xy 351.586013 -401.808332) (xy 351.570658 -401.756037) (xy 351.562902 -401.702089) (xy 351.562416 -401.674838)
			(xy 351.125536 -401.674838) (xy 351.12505 -401.702089) (xy 351.117294 -401.756037) (xy 351.101939 -401.808332)
			(xy 351.079297 -401.857909) (xy 351.049831 -401.903759) (xy 351.01414 -401.94495) (xy 350.972949 -401.980641)
			(xy 350.927099 -402.010107) (xy 350.877522 -402.032749) (xy 350.825227 -402.048104) (xy 350.771279 -402.05586)
			(xy 350.716777 -402.05586) (xy 350.662829 -402.048104) (xy 350.610534 -402.032749) (xy 350.560957 -402.010107)
			(xy 350.515107 -401.980641) (xy 350.473916 -401.94495) (xy 350.438225 -401.903759) (xy 350.408759 -401.857909)
			(xy 350.386117 -401.808332) (xy 350.370762 -401.756037) (xy 350.363006 -401.702089) (xy 350.36252 -401.674838)
			(xy 349.92564 -401.674838) (xy 349.925154 -401.702089) (xy 349.917398 -401.756037) (xy 349.902043 -401.808332)
			(xy 349.879401 -401.857909) (xy 349.849935 -401.903759) (xy 349.814244 -401.94495) (xy 349.773053 -401.980641)
			(xy 349.727203 -402.010107) (xy 349.677626 -402.032749) (xy 349.625331 -402.048104) (xy 349.571383 -402.05586)
			(xy 349.516881 -402.05586) (xy 349.462933 -402.048104) (xy 349.410638 -402.032749) (xy 349.361061 -402.010107)
			(xy 349.315211 -401.980641) (xy 349.27402 -401.94495) (xy 349.238329 -401.903759) (xy 349.208863 -401.857909)
			(xy 349.186221 -401.808332) (xy 349.170866 -401.756037) (xy 349.16311 -401.702089) (xy 349.162624 -401.674838)
			(xy 348.725744 -401.674838) (xy 348.725258 -401.702089) (xy 348.717502 -401.756037) (xy 348.702147 -401.808332)
			(xy 348.679505 -401.857909) (xy 348.650039 -401.903759) (xy 348.614348 -401.94495) (xy 348.573157 -401.980641)
			(xy 348.527307 -402.010107) (xy 348.47773 -402.032749) (xy 348.425435 -402.048104) (xy 348.371487 -402.05586)
			(xy 348.316985 -402.05586) (xy 348.263037 -402.048104) (xy 348.210742 -402.032749) (xy 348.161165 -402.010107)
			(xy 348.115315 -401.980641) (xy 348.074124 -401.94495) (xy 348.038433 -401.903759) (xy 348.008967 -401.857909)
			(xy 347.986325 -401.808332) (xy 347.97097 -401.756037) (xy 347.963214 -401.702089) (xy 347.962728 -401.674838)
			(xy 347.525848 -401.674838) (xy 347.525362 -401.702107) (xy 347.5176 -401.756091) (xy 347.502235 -401.808421)
			(xy 347.479578 -401.858031) (xy 347.450092 -401.903912) (xy 347.414377 -401.945129) (xy 347.37316 -401.980844)
			(xy 347.327279 -402.01033) (xy 347.277669 -402.032987) (xy 347.225339 -402.048352) (xy 347.171355 -402.056114)
			(xy 347.116817 -402.056114) (xy 347.062833 -402.048352) (xy 347.010503 -402.032987) (xy 346.960893 -402.01033)
			(xy 346.915012 -401.980844) (xy 346.873795 -401.945129) (xy 346.83808 -401.903912) (xy 346.808594 -401.858031)
			(xy 346.785937 -401.808421) (xy 346.770572 -401.756091) (xy 346.76281 -401.702107) (xy 346.762324 -401.674838)
			(xy 346.325952 -401.674838) (xy 346.325466 -401.702107) (xy 346.317704 -401.756091) (xy 346.302339 -401.808421)
			(xy 346.279682 -401.858031) (xy 346.250196 -401.903912) (xy 346.214481 -401.945129) (xy 346.173264 -401.980844)
			(xy 346.127383 -402.01033) (xy 346.077773 -402.032987) (xy 346.025443 -402.048352) (xy 345.971459 -402.056114)
			(xy 345.916921 -402.056114) (xy 345.862937 -402.048352) (xy 345.810607 -402.032987) (xy 345.760997 -402.01033)
			(xy 345.715116 -401.980844) (xy 345.673899 -401.945129) (xy 345.638184 -401.903912) (xy 345.608698 -401.858031)
			(xy 345.586041 -401.808421) (xy 345.570676 -401.756091) (xy 345.562914 -401.702107) (xy 345.562428 -401.674838)
			(xy 345.125548 -401.674838) (xy 345.125062 -401.702089) (xy 345.117306 -401.756037) (xy 345.101951 -401.808332)
			(xy 345.079309 -401.857909) (xy 345.049843 -401.903759) (xy 345.014152 -401.94495) (xy 344.972961 -401.980641)
			(xy 344.927111 -402.010107) (xy 344.877534 -402.032749) (xy 344.825239 -402.048104) (xy 344.771291 -402.05586)
			(xy 344.716789 -402.05586) (xy 344.662841 -402.048104) (xy 344.610546 -402.032749) (xy 344.560969 -402.010107)
			(xy 344.515119 -401.980641) (xy 344.473928 -401.94495) (xy 344.438237 -401.903759) (xy 344.408771 -401.857909)
			(xy 344.386129 -401.808332) (xy 344.370774 -401.756037) (xy 344.363018 -401.702089) (xy 344.362532 -401.674838)
			(xy 343.925652 -401.674838) (xy 343.925166 -401.702089) (xy 343.91741 -401.756037) (xy 343.902055 -401.808332)
			(xy 343.879413 -401.857909) (xy 343.849947 -401.903759) (xy 343.814256 -401.94495) (xy 343.773065 -401.980641)
			(xy 343.727215 -402.010107) (xy 343.677638 -402.032749) (xy 343.625343 -402.048104) (xy 343.571395 -402.05586)
			(xy 343.516893 -402.05586) (xy 343.462945 -402.048104) (xy 343.41065 -402.032749) (xy 343.361073 -402.010107)
			(xy 343.315223 -401.980641) (xy 343.274032 -401.94495) (xy 343.238341 -401.903759) (xy 343.208875 -401.857909)
			(xy 343.186233 -401.808332) (xy 343.170878 -401.756037) (xy 343.163122 -401.702089) (xy 343.162636 -401.674838)
			(xy 342.725756 -401.674838) (xy 342.72527 -401.702107) (xy 342.717508 -401.756091) (xy 342.702143 -401.808421)
			(xy 342.679486 -401.858031) (xy 342.65 -401.903912) (xy 342.614285 -401.945129) (xy 342.573068 -401.980844)
			(xy 342.527187 -402.01033) (xy 342.477577 -402.032987) (xy 342.425247 -402.048352) (xy 342.371263 -402.056114)
			(xy 342.316725 -402.056114) (xy 342.262741 -402.048352) (xy 342.210411 -402.032987) (xy 342.160801 -402.01033)
			(xy 342.11492 -401.980844) (xy 342.073703 -401.945129) (xy 342.037988 -401.903912) (xy 342.008502 -401.858031)
			(xy 341.985845 -401.808421) (xy 341.97048 -401.756091) (xy 341.962718 -401.702107) (xy 341.962232 -401.674838)
			(xy 341.52586 -401.674838) (xy 341.525374 -401.702107) (xy 341.517612 -401.756091) (xy 341.502247 -401.808421)
			(xy 341.47959 -401.858031) (xy 341.450104 -401.903912) (xy 341.414389 -401.945129) (xy 341.373172 -401.980844)
			(xy 341.327291 -402.01033) (xy 341.277681 -402.032987) (xy 341.225351 -402.048352) (xy 341.171367 -402.056114)
			(xy 341.116829 -402.056114) (xy 341.062845 -402.048352) (xy 341.010515 -402.032987) (xy 340.960905 -402.01033)
			(xy 340.915024 -401.980844) (xy 340.873807 -401.945129) (xy 340.838092 -401.903912) (xy 340.808606 -401.858031)
			(xy 340.785949 -401.808421) (xy 340.770584 -401.756091) (xy 340.762822 -401.702107) (xy 340.762336 -401.674838)
			(xy 340.325456 -401.674838) (xy 340.32497 -401.702089) (xy 340.317214 -401.756037) (xy 340.301859 -401.808332)
			(xy 340.279217 -401.857909) (xy 340.249751 -401.903759) (xy 340.21406 -401.94495) (xy 340.172869 -401.980641)
			(xy 340.127019 -402.010107) (xy 340.077442 -402.032749) (xy 340.025147 -402.048104) (xy 339.971199 -402.05586)
			(xy 339.916697 -402.05586) (xy 339.862749 -402.048104) (xy 339.810454 -402.032749) (xy 339.760877 -402.010107)
			(xy 339.715027 -401.980641) (xy 339.673836 -401.94495) (xy 339.638145 -401.903759) (xy 339.608679 -401.857909)
			(xy 339.586037 -401.808332) (xy 339.570682 -401.756037) (xy 339.562926 -401.702089) (xy 339.56244 -401.674838)
			(xy 339.12556 -401.674838) (xy 339.125074 -401.702089) (xy 339.117318 -401.756037) (xy 339.101963 -401.808332)
			(xy 339.079321 -401.857909) (xy 339.049855 -401.903759) (xy 339.014164 -401.94495) (xy 338.972973 -401.980641)
			(xy 338.927123 -402.010107) (xy 338.877546 -402.032749) (xy 338.825251 -402.048104) (xy 338.771303 -402.05586)
			(xy 338.716801 -402.05586) (xy 338.662853 -402.048104) (xy 338.610558 -402.032749) (xy 338.560981 -402.010107)
			(xy 338.515131 -401.980641) (xy 338.47394 -401.94495) (xy 338.438249 -401.903759) (xy 338.408783 -401.857909)
			(xy 338.386141 -401.808332) (xy 338.370786 -401.756037) (xy 338.36303 -401.702089) (xy 338.362544 -401.674838)
			(xy 337.925664 -401.674838) (xy 337.925178 -401.702107) (xy 337.917416 -401.756091) (xy 337.902051 -401.808421)
			(xy 337.879394 -401.858031) (xy 337.849908 -401.903912) (xy 337.814193 -401.945129) (xy 337.772976 -401.980844)
			(xy 337.727095 -402.01033) (xy 337.677485 -402.032987) (xy 337.625155 -402.048352) (xy 337.571171 -402.056114)
			(xy 337.516633 -402.056114) (xy 337.462649 -402.048352) (xy 337.410319 -402.032987) (xy 337.360709 -402.01033)
			(xy 337.314828 -401.980844) (xy 337.273611 -401.945129) (xy 337.237896 -401.903912) (xy 337.20841 -401.858031)
			(xy 337.185753 -401.808421) (xy 337.170388 -401.756091) (xy 337.162626 -401.702107) (xy 337.16214 -401.674838)
			(xy 336.725768 -401.674838) (xy 336.725282 -401.702107) (xy 336.71752 -401.756091) (xy 336.702155 -401.808421)
			(xy 336.679498 -401.858031) (xy 336.650012 -401.903912) (xy 336.614297 -401.945129) (xy 336.57308 -401.980844)
			(xy 336.527199 -402.01033) (xy 336.477589 -402.032987) (xy 336.425259 -402.048352) (xy 336.371275 -402.056114)
			(xy 336.316737 -402.056114) (xy 336.262753 -402.048352) (xy 336.210423 -402.032987) (xy 336.160813 -402.01033)
			(xy 336.114932 -401.980844) (xy 336.073715 -401.945129) (xy 336.038 -401.903912) (xy 336.008514 -401.858031)
			(xy 335.985857 -401.808421) (xy 335.970492 -401.756091) (xy 335.96273 -401.702107) (xy 335.962244 -401.674838)
			(xy 322.197984 -401.674838) (xy 322.197498 -401.702107) (xy 322.189736 -401.756091) (xy 322.174371 -401.808421)
			(xy 322.151714 -401.858031) (xy 322.122228 -401.903912) (xy 322.086513 -401.945129) (xy 322.045296 -401.980844)
			(xy 321.999415 -402.01033) (xy 321.949805 -402.032987) (xy 321.897475 -402.048352) (xy 321.843491 -402.056114)
			(xy 321.788953 -402.056114) (xy 321.734969 -402.048352) (xy 321.682639 -402.032987) (xy 321.633029 -402.01033)
			(xy 321.587148 -401.980844) (xy 321.545931 -401.945129) (xy 321.510216 -401.903912) (xy 321.48073 -401.858031)
			(xy 321.458073 -401.808421) (xy 321.442708 -401.756091) (xy 321.434946 -401.702107) (xy 321.43446 -401.674838)
			(xy 320.998088 -401.674838) (xy 320.997602 -401.702107) (xy 320.98984 -401.756091) (xy 320.974475 -401.808421)
			(xy 320.951818 -401.858031) (xy 320.922332 -401.903912) (xy 320.886617 -401.945129) (xy 320.8454 -401.980844)
			(xy 320.799519 -402.01033) (xy 320.749909 -402.032987) (xy 320.697579 -402.048352) (xy 320.643595 -402.056114)
			(xy 320.589057 -402.056114) (xy 320.535073 -402.048352) (xy 320.482743 -402.032987) (xy 320.433133 -402.01033)
			(xy 320.387252 -401.980844) (xy 320.346035 -401.945129) (xy 320.31032 -401.903912) (xy 320.280834 -401.858031)
			(xy 320.258177 -401.808421) (xy 320.242812 -401.756091) (xy 320.23505 -401.702107) (xy 320.234564 -401.674838)
			(xy 319.797684 -401.674838) (xy 319.797198 -401.702089) (xy 319.789442 -401.756037) (xy 319.774087 -401.808332)
			(xy 319.751445 -401.857909) (xy 319.721979 -401.903759) (xy 319.686288 -401.94495) (xy 319.645097 -401.980641)
			(xy 319.599247 -402.010107) (xy 319.54967 -402.032749) (xy 319.497375 -402.048104) (xy 319.443427 -402.05586)
			(xy 319.388925 -402.05586) (xy 319.334977 -402.048104) (xy 319.282682 -402.032749) (xy 319.233105 -402.010107)
			(xy 319.187255 -401.980641) (xy 319.146064 -401.94495) (xy 319.110373 -401.903759) (xy 319.080907 -401.857909)
			(xy 319.058265 -401.808332) (xy 319.04291 -401.756037) (xy 319.035154 -401.702089) (xy 319.034668 -401.674838)
			(xy 318.597788 -401.674838) (xy 318.597302 -401.702089) (xy 318.589546 -401.756037) (xy 318.574191 -401.808332)
			(xy 318.551549 -401.857909) (xy 318.522083 -401.903759) (xy 318.486392 -401.94495) (xy 318.445201 -401.980641)
			(xy 318.399351 -402.010107) (xy 318.349774 -402.032749) (xy 318.297479 -402.048104) (xy 318.243531 -402.05586)
			(xy 318.189029 -402.05586) (xy 318.135081 -402.048104) (xy 318.082786 -402.032749) (xy 318.033209 -402.010107)
			(xy 317.987359 -401.980641) (xy 317.946168 -401.94495) (xy 317.910477 -401.903759) (xy 317.881011 -401.857909)
			(xy 317.858369 -401.808332) (xy 317.843014 -401.756037) (xy 317.835258 -401.702089) (xy 317.834772 -401.674838)
			(xy 317.397892 -401.674838) (xy 317.397406 -401.702089) (xy 317.38965 -401.756037) (xy 317.374295 -401.808332)
			(xy 317.351653 -401.857909) (xy 317.322187 -401.903759) (xy 317.286496 -401.94495) (xy 317.245305 -401.980641)
			(xy 317.199455 -402.010107) (xy 317.149878 -402.032749) (xy 317.097583 -402.048104) (xy 317.043635 -402.05586)
			(xy 316.989133 -402.05586) (xy 316.935185 -402.048104) (xy 316.88289 -402.032749) (xy 316.833313 -402.010107)
			(xy 316.787463 -401.980641) (xy 316.746272 -401.94495) (xy 316.710581 -401.903759) (xy 316.681115 -401.857909)
			(xy 316.658473 -401.808332) (xy 316.643118 -401.756037) (xy 316.635362 -401.702089) (xy 316.634876 -401.674838)
			(xy 316.197996 -401.674838) (xy 316.19751 -401.702089) (xy 316.189754 -401.756037) (xy 316.174399 -401.808332)
			(xy 316.151757 -401.857909) (xy 316.122291 -401.903759) (xy 316.0866 -401.94495) (xy 316.045409 -401.980641)
			(xy 315.999559 -402.010107) (xy 315.949982 -402.032749) (xy 315.897687 -402.048104) (xy 315.843739 -402.05586)
			(xy 315.789237 -402.05586) (xy 315.735289 -402.048104) (xy 315.682994 -402.032749) (xy 315.633417 -402.010107)
			(xy 315.587567 -401.980641) (xy 315.546376 -401.94495) (xy 315.510685 -401.903759) (xy 315.481219 -401.857909)
			(xy 315.458577 -401.808332) (xy 315.443222 -401.756037) (xy 315.435466 -401.702089) (xy 315.43498 -401.674838)
			(xy 314.9981 -401.674838) (xy 314.997614 -401.702107) (xy 314.989852 -401.756091) (xy 314.974487 -401.808421)
			(xy 314.95183 -401.858031) (xy 314.922344 -401.903912) (xy 314.886629 -401.945129) (xy 314.845412 -401.980844)
			(xy 314.799531 -402.01033) (xy 314.749921 -402.032987) (xy 314.697591 -402.048352) (xy 314.643607 -402.056114)
			(xy 314.589069 -402.056114) (xy 314.535085 -402.048352) (xy 314.482755 -402.032987) (xy 314.433145 -402.01033)
			(xy 314.387264 -401.980844) (xy 314.346047 -401.945129) (xy 314.310332 -401.903912) (xy 314.280846 -401.858031)
			(xy 314.258189 -401.808421) (xy 314.242824 -401.756091) (xy 314.235062 -401.702107) (xy 314.234576 -401.674838)
			(xy 313.798204 -401.674838) (xy 313.797718 -401.702107) (xy 313.789956 -401.756091) (xy 313.774591 -401.808421)
			(xy 313.751934 -401.858031) (xy 313.722448 -401.903912) (xy 313.686733 -401.945129) (xy 313.645516 -401.980844)
			(xy 313.599635 -402.01033) (xy 313.550025 -402.032987) (xy 313.497695 -402.048352) (xy 313.443711 -402.056114)
			(xy 313.389173 -402.056114) (xy 313.335189 -402.048352) (xy 313.282859 -402.032987) (xy 313.233249 -402.01033)
			(xy 313.187368 -401.980844) (xy 313.146151 -401.945129) (xy 313.110436 -401.903912) (xy 313.08095 -401.858031)
			(xy 313.058293 -401.808421) (xy 313.042928 -401.756091) (xy 313.035166 -401.702107) (xy 313.03468 -401.674838)
			(xy 312.5978 -401.674838) (xy 312.597314 -401.702089) (xy 312.589558 -401.756037) (xy 312.574203 -401.808332)
			(xy 312.551561 -401.857909) (xy 312.522095 -401.903759) (xy 312.486404 -401.94495) (xy 312.445213 -401.980641)
			(xy 312.399363 -402.010107) (xy 312.349786 -402.032749) (xy 312.297491 -402.048104) (xy 312.243543 -402.05586)
			(xy 312.189041 -402.05586) (xy 312.135093 -402.048104) (xy 312.082798 -402.032749) (xy 312.033221 -402.010107)
			(xy 311.987371 -401.980641) (xy 311.94618 -401.94495) (xy 311.910489 -401.903759) (xy 311.881023 -401.857909)
			(xy 311.858381 -401.808332) (xy 311.843026 -401.756037) (xy 311.83527 -401.702089) (xy 311.834784 -401.674838)
			(xy 311.397904 -401.674838) (xy 311.397418 -401.702089) (xy 311.389662 -401.756037) (xy 311.374307 -401.808332)
			(xy 311.351665 -401.857909) (xy 311.322199 -401.903759) (xy 311.286508 -401.94495) (xy 311.245317 -401.980641)
			(xy 311.199467 -402.010107) (xy 311.14989 -402.032749) (xy 311.097595 -402.048104) (xy 311.043647 -402.05586)
			(xy 310.989145 -402.05586) (xy 310.935197 -402.048104) (xy 310.882902 -402.032749) (xy 310.833325 -402.010107)
			(xy 310.787475 -401.980641) (xy 310.746284 -401.94495) (xy 310.710593 -401.903759) (xy 310.681127 -401.857909)
			(xy 310.658485 -401.808332) (xy 310.64313 -401.756037) (xy 310.635374 -401.702089) (xy 310.634888 -401.674838)
			(xy 310.198008 -401.674838) (xy 310.197522 -401.702107) (xy 310.18976 -401.756091) (xy 310.174395 -401.808421)
			(xy 310.151738 -401.858031) (xy 310.122252 -401.903912) (xy 310.086537 -401.945129) (xy 310.04532 -401.980844)
			(xy 309.999439 -402.01033) (xy 309.949829 -402.032987) (xy 309.897499 -402.048352) (xy 309.843515 -402.056114)
			(xy 309.788977 -402.056114) (xy 309.734993 -402.048352) (xy 309.682663 -402.032987) (xy 309.633053 -402.01033)
			(xy 309.587172 -401.980844) (xy 309.545955 -401.945129) (xy 309.51024 -401.903912) (xy 309.480754 -401.858031)
			(xy 309.458097 -401.808421) (xy 309.442732 -401.756091) (xy 309.43497 -401.702107) (xy 309.434484 -401.674838)
			(xy 308.998112 -401.674838) (xy 308.997626 -401.702107) (xy 308.989864 -401.756091) (xy 308.974499 -401.808421)
			(xy 308.951842 -401.858031) (xy 308.922356 -401.903912) (xy 308.886641 -401.945129) (xy 308.845424 -401.980844)
			(xy 308.799543 -402.01033) (xy 308.749933 -402.032987) (xy 308.697603 -402.048352) (xy 308.643619 -402.056114)
			(xy 308.589081 -402.056114) (xy 308.535097 -402.048352) (xy 308.482767 -402.032987) (xy 308.433157 -402.01033)
			(xy 308.387276 -401.980844) (xy 308.346059 -401.945129) (xy 308.310344 -401.903912) (xy 308.280858 -401.858031)
			(xy 308.258201 -401.808421) (xy 308.242836 -401.756091) (xy 308.235074 -401.702107) (xy 308.234588 -401.674838)
			(xy 307.797708 -401.674838) (xy 307.797222 -401.702089) (xy 307.789466 -401.756037) (xy 307.774111 -401.808332)
			(xy 307.751469 -401.857909) (xy 307.722003 -401.903759) (xy 307.686312 -401.94495) (xy 307.645121 -401.980641)
			(xy 307.599271 -402.010107) (xy 307.549694 -402.032749) (xy 307.497399 -402.048104) (xy 307.443451 -402.05586)
			(xy 307.388949 -402.05586) (xy 307.335001 -402.048104) (xy 307.282706 -402.032749) (xy 307.233129 -402.010107)
			(xy 307.187279 -401.980641) (xy 307.146088 -401.94495) (xy 307.110397 -401.903759) (xy 307.080931 -401.857909)
			(xy 307.058289 -401.808332) (xy 307.042934 -401.756037) (xy 307.035178 -401.702089) (xy 307.034692 -401.674838)
			(xy 306.597812 -401.674838) (xy 306.597326 -401.702089) (xy 306.58957 -401.756037) (xy 306.574215 -401.808332)
			(xy 306.551573 -401.857909) (xy 306.522107 -401.903759) (xy 306.486416 -401.94495) (xy 306.445225 -401.980641)
			(xy 306.399375 -402.010107) (xy 306.349798 -402.032749) (xy 306.297503 -402.048104) (xy 306.243555 -402.05586)
			(xy 306.189053 -402.05586) (xy 306.135105 -402.048104) (xy 306.08281 -402.032749) (xy 306.033233 -402.010107)
			(xy 305.987383 -401.980641) (xy 305.946192 -401.94495) (xy 305.910501 -401.903759) (xy 305.881035 -401.857909)
			(xy 305.858393 -401.808332) (xy 305.843038 -401.756037) (xy 305.835282 -401.702089) (xy 305.834796 -401.674838)
			(xy 305.397916 -401.674838) (xy 305.39743 -401.702107) (xy 305.389668 -401.756091) (xy 305.374303 -401.808421)
			(xy 305.351646 -401.858031) (xy 305.32216 -401.903912) (xy 305.286445 -401.945129) (xy 305.245228 -401.980844)
			(xy 305.199347 -402.01033) (xy 305.149737 -402.032987) (xy 305.097407 -402.048352) (xy 305.043423 -402.056114)
			(xy 304.988885 -402.056114) (xy 304.934901 -402.048352) (xy 304.882571 -402.032987) (xy 304.832961 -402.01033)
			(xy 304.78708 -401.980844) (xy 304.745863 -401.945129) (xy 304.710148 -401.903912) (xy 304.680662 -401.858031)
			(xy 304.658005 -401.808421) (xy 304.64264 -401.756091) (xy 304.634878 -401.702107) (xy 304.634392 -401.674838)
			(xy 304.19802 -401.674838) (xy 304.197534 -401.702107) (xy 304.189772 -401.756091) (xy 304.174407 -401.808421)
			(xy 304.15175 -401.858031) (xy 304.122264 -401.903912) (xy 304.086549 -401.945129) (xy 304.045332 -401.980844)
			(xy 303.999451 -402.01033) (xy 303.949841 -402.032987) (xy 303.897511 -402.048352) (xy 303.843527 -402.056114)
			(xy 303.788989 -402.056114) (xy 303.735005 -402.048352) (xy 303.682675 -402.032987) (xy 303.633065 -402.01033)
			(xy 303.587184 -401.980844) (xy 303.545967 -401.945129) (xy 303.510252 -401.903912) (xy 303.480766 -401.858031)
			(xy 303.458109 -401.808421) (xy 303.442744 -401.756091) (xy 303.434982 -401.702107) (xy 303.434496 -401.674838)
			(xy 296.287698 -401.674838) (xy 296.287698 -408.915108) (xy 296.288284 -408.926869) (xy 296.298731 -408.947942)
			(xy 296.307764 -408.955494) (xy 296.381678 -409.011628) (xy 296.404792 -409.0162) (xy 296.416476 -409.012898)
			(xy 296.510172 -408.987549) (xy 296.699411 -408.94427) (xy 296.890404 -408.909537) (xy 297.082765 -408.883422)
			(xy 297.276105 -408.865976) (xy 297.470033 -408.857236) (xy 297.567096 -408.856688) (xy 297.567604 -408.856688)
			(xy 297.660521 -408.857188) (xy 297.846184 -408.865183) (xy 298.031331 -408.881158) (xy 298.21562 -408.905085)
			(xy 298.398708 -408.936917) (xy 298.580257 -408.976597) (xy 298.759931 -409.02405) (xy 298.937397 -409.07919)
			(xy 299.112327 -409.141914) (xy 299.284396 -409.212105) (xy 299.453286 -409.289635) (xy 299.618684 -409.374358)
			(xy 299.780284 -409.466119) (xy 299.937787 -409.564747) (xy 300.090901 -409.67006) (xy 300.239342 -409.781863)
			(xy 300.382835 -409.899949) (xy 300.521116 -410.024098) (xy 300.653927 -410.154082) (xy 300.781023 -410.28966)
			(xy 300.902169 -410.430579) (xy 301.017139 -410.576581) (xy 301.125722 -410.727393) (xy 301.227716 -410.882737)
			(xy 301.322933 -411.042326) (xy 301.411195 -411.205863) (xy 301.49234 -411.373045) (xy 301.566218 -411.543565)
			(xy 301.63269 -411.717104) (xy 301.691636 -411.893343) (xy 301.742944 -412.071954) (xy 301.786521 -412.252608)
			(xy 301.822285 -412.434969) (xy 301.85017 -412.6187) (xy 301.870126 -412.80346) (xy 301.87467 -412.873752)
			(xy 303.412875 -412.873752) (xy 303.412875 -412.819248) (xy 303.420632 -412.7653) (xy 303.435988 -412.713004)
			(xy 303.458629 -412.663426) (xy 303.488096 -412.617575) (xy 303.523789 -412.576384) (xy 303.56498 -412.540693)
			(xy 303.610831 -412.511226) (xy 303.66041 -412.488585) (xy 303.712706 -412.473231) (xy 303.766654 -412.465475)
			(xy 303.793906 -412.465012) (xy 304.657506 -412.465012) (xy 304.684758 -412.465458) (xy 304.738708 -412.473216)
			(xy 304.791005 -412.488572) (xy 304.840584 -412.511215) (xy 304.886436 -412.540683) (xy 304.927628 -412.576376)
			(xy 304.963321 -412.617569) (xy 304.992788 -412.663421) (xy 305.01543 -412.713001) (xy 305.030785 -412.765298)
			(xy 305.038542 -412.819248) (xy 305.038542 -412.873752) (xy 305.038542 -412.873754) (xy 306.476075 -412.873754)
			(xy 306.476075 -412.819246) (xy 306.483833 -412.765294) (xy 306.499191 -412.712996) (xy 306.521835 -412.663415)
			(xy 306.551306 -412.617562) (xy 306.587003 -412.57637) (xy 306.628199 -412.540679) (xy 306.674055 -412.511213)
			(xy 306.723639 -412.488575) (xy 306.775939 -412.473223) (xy 306.829892 -412.465472) (xy 306.857146 -412.465012)
			(xy 307.720746 -412.465012) (xy 307.747997 -412.465461) (xy 307.801942 -412.473223) (xy 307.854234 -412.488583)
			(xy 307.903808 -412.511228) (xy 307.949655 -412.540697) (xy 307.990842 -412.576391) (xy 308.02653 -412.617582)
			(xy 308.055994 -412.663432) (xy 308.078633 -412.713009) (xy 308.093987 -412.765303) (xy 308.101742 -412.819249)
			(xy 308.101742 -412.873749) (xy 309.539398 -412.873749) (xy 309.539398 -412.819251) (xy 309.547154 -412.765307)
			(xy 309.562508 -412.713016) (xy 309.585146 -412.663443) (xy 309.61461 -412.617596) (xy 309.650298 -412.576408)
			(xy 309.691484 -412.540718) (xy 309.73733 -412.511253) (xy 309.786903 -412.488612) (xy 309.839194 -412.473257)
			(xy 309.893137 -412.465499) (xy 309.920386 -412.465012) (xy 310.783986 -412.465012) (xy 310.811241 -412.465434)
			(xy 310.865196 -412.47319) (xy 310.917499 -412.488545) (xy 310.967083 -412.511188) (xy 311.012941 -412.540657)
			(xy 311.054137 -412.576353) (xy 311.089834 -412.617548) (xy 311.119305 -412.663405) (xy 311.14195 -412.712988)
			(xy 311.157307 -412.76529) (xy 311.165065 -412.819245) (xy 311.165065 -412.873753) (xy 312.602575 -412.873753)
			(xy 312.602575 -412.819247) (xy 312.610333 -412.765297) (xy 312.625689 -412.713) (xy 312.648332 -412.663421)
			(xy 312.677801 -412.617569) (xy 312.713496 -412.576377) (xy 312.754689 -412.540686) (xy 312.800543 -412.51122)
			(xy 312.850124 -412.48858) (xy 312.902422 -412.473227) (xy 312.956373 -412.465474) (xy 312.983626 -412.465012)
			(xy 313.847226 -412.465012) (xy 313.874477 -412.46546) (xy 313.928425 -412.47322) (xy 313.98072 -412.488578)
			(xy 314.030296 -412.511222) (xy 314.076146 -412.54069) (xy 314.117335 -412.576383) (xy 314.153026 -412.617575)
			(xy 314.182491 -412.663427) (xy 314.205131 -412.713005) (xy 314.220486 -412.7653) (xy 314.228242 -412.819249)
			(xy 314.228242 -412.873748) (xy 315.665898 -412.873748) (xy 315.665898 -412.819252) (xy 315.673653 -412.76531)
			(xy 315.689006 -412.713021) (xy 315.711643 -412.663448) (xy 315.741105 -412.617602) (xy 315.776791 -412.576415)
			(xy 315.817975 -412.540725) (xy 315.863818 -412.51126) (xy 315.913389 -412.488618) (xy 315.965677 -412.473261)
			(xy 316.019618 -412.465501) (xy 316.046866 -412.465012) (xy 316.910466 -412.465012) (xy 316.937722 -412.465433)
			(xy 316.991679 -412.473186) (xy 317.043984 -412.48854) (xy 317.093571 -412.511182) (xy 317.139431 -412.54065)
			(xy 317.18063 -412.576346) (xy 317.216329 -412.617542) (xy 317.245802 -412.663399) (xy 317.268448 -412.712984)
			(xy 317.283807 -412.765287) (xy 317.291565 -412.819244) (xy 317.291565 -412.873752) (xy 318.729075 -412.873752)
			(xy 318.729075 -412.819248) (xy 318.736832 -412.7653) (xy 318.752188 -412.713004) (xy 318.774829 -412.663426)
			(xy 318.804296 -412.617575) (xy 318.839989 -412.576384) (xy 318.88118 -412.540693) (xy 318.927031 -412.511226)
			(xy 318.97661 -412.488585) (xy 319.028906 -412.473231) (xy 319.082854 -412.465475) (xy 319.110106 -412.465012)
			(xy 319.973706 -412.465012) (xy 320.000958 -412.465458) (xy 320.054908 -412.473216) (xy 320.107205 -412.488572)
			(xy 320.156784 -412.511215) (xy 320.202636 -412.540683) (xy 320.243828 -412.576376) (xy 320.279521 -412.617569)
			(xy 320.308988 -412.663421) (xy 320.33163 -412.713001) (xy 320.346985 -412.765298) (xy 320.354742 -412.819248)
			(xy 320.354742 -412.873752) (xy 320.354742 -412.873754) (xy 321.792275 -412.873754) (xy 321.792275 -412.819246)
			(xy 321.800033 -412.765294) (xy 321.815391 -412.712996) (xy 321.838035 -412.663415) (xy 321.867506 -412.617562)
			(xy 321.903203 -412.57637) (xy 321.944399 -412.540679) (xy 321.990255 -412.511213) (xy 322.039839 -412.488575)
			(xy 322.092139 -412.473223) (xy 322.146092 -412.465472) (xy 322.173346 -412.465012) (xy 323.036946 -412.465012)
			(xy 323.064197 -412.465461) (xy 323.118142 -412.473223) (xy 323.170434 -412.488583) (xy 323.220008 -412.511228)
			(xy 323.265855 -412.540697) (xy 323.307042 -412.576391) (xy 323.34273 -412.617582) (xy 323.372194 -412.663432)
			(xy 323.394833 -412.713009) (xy 323.410187 -412.765303) (xy 323.417942 -412.819249) (xy 323.417942 -412.873749)
			(xy 324.855598 -412.873749) (xy 324.855598 -412.819251) (xy 324.863354 -412.765307) (xy 324.878708 -412.713016)
			(xy 324.901346 -412.663443) (xy 324.93081 -412.617596) (xy 324.966498 -412.576408) (xy 325.007684 -412.540718)
			(xy 325.05353 -412.511253) (xy 325.103103 -412.488612) (xy 325.155394 -412.473257) (xy 325.209337 -412.465499)
			(xy 325.236586 -412.465012) (xy 326.100186 -412.465012) (xy 326.127441 -412.465434) (xy 326.181396 -412.47319)
			(xy 326.233699 -412.488545) (xy 326.283283 -412.511188) (xy 326.329141 -412.540657) (xy 326.370337 -412.576353)
			(xy 326.406034 -412.617548) (xy 326.435505 -412.663405) (xy 326.45815 -412.712988) (xy 326.473507 -412.76529)
			(xy 326.481265 -412.819245) (xy 326.481265 -412.873753) (xy 327.918775 -412.873753) (xy 327.918775 -412.819247)
			(xy 327.926533 -412.765297) (xy 327.941889 -412.713) (xy 327.964532 -412.663421) (xy 327.994001 -412.617569)
			(xy 328.029696 -412.576377) (xy 328.070889 -412.540686) (xy 328.116743 -412.51122) (xy 328.166324 -412.48858)
			(xy 328.218622 -412.473227) (xy 328.272573 -412.465474) (xy 328.299826 -412.465012) (xy 329.163426 -412.465012)
			(xy 329.190677 -412.46546) (xy 329.244625 -412.47322) (xy 329.29692 -412.488578) (xy 329.346496 -412.511222)
			(xy 329.392346 -412.54069) (xy 329.433535 -412.576383) (xy 329.469226 -412.617575) (xy 329.498691 -412.663427)
			(xy 329.521331 -412.713005) (xy 329.536686 -412.7653) (xy 329.544442 -412.819249) (xy 329.544442 -412.873748)
			(xy 330.982098 -412.873748) (xy 330.982098 -412.819252) (xy 330.989853 -412.76531) (xy 331.005206 -412.713021)
			(xy 331.027843 -412.663448) (xy 331.057305 -412.617602) (xy 331.092991 -412.576415) (xy 331.134175 -412.540725)
			(xy 331.180018 -412.51126) (xy 331.229589 -412.488618) (xy 331.281877 -412.473261) (xy 331.335818 -412.465501)
			(xy 331.363066 -412.465012) (xy 332.226666 -412.465012) (xy 332.253922 -412.465433) (xy 332.307879 -412.473186)
			(xy 332.360184 -412.48854) (xy 332.409771 -412.511182) (xy 332.455631 -412.54065) (xy 332.49683 -412.576346)
			(xy 332.532529 -412.617542) (xy 332.562002 -412.663399) (xy 332.584648 -412.712984) (xy 332.600007 -412.765287)
			(xy 332.607765 -412.819244) (xy 332.607765 -412.873752) (xy 334.045275 -412.873752) (xy 334.045275 -412.819248)
			(xy 334.053032 -412.7653) (xy 334.068388 -412.713004) (xy 334.091029 -412.663426) (xy 334.120496 -412.617575)
			(xy 334.156189 -412.576384) (xy 334.19738 -412.540693) (xy 334.243231 -412.511226) (xy 334.29281 -412.488585)
			(xy 334.345106 -412.473231) (xy 334.399054 -412.465475) (xy 334.426306 -412.465012) (xy 335.289906 -412.465012)
			(xy 335.317158 -412.465458) (xy 335.371108 -412.473216) (xy 335.423405 -412.488572) (xy 335.472984 -412.511215)
			(xy 335.518836 -412.540683) (xy 335.560028 -412.576376) (xy 335.595721 -412.617569) (xy 335.625188 -412.663421)
			(xy 335.64783 -412.713001) (xy 335.663185 -412.765298) (xy 335.670942 -412.819248) (xy 335.670942 -412.873752)
			(xy 335.670942 -412.873754) (xy 337.108475 -412.873754) (xy 337.108475 -412.819246) (xy 337.116233 -412.765294)
			(xy 337.131591 -412.712996) (xy 337.154235 -412.663415) (xy 337.183706 -412.617562) (xy 337.219403 -412.57637)
			(xy 337.260599 -412.540679) (xy 337.306455 -412.511213) (xy 337.356039 -412.488575) (xy 337.408339 -412.473223)
			(xy 337.462292 -412.465472) (xy 337.489546 -412.465012) (xy 338.353146 -412.465012) (xy 338.380397 -412.465461)
			(xy 338.434342 -412.473223) (xy 338.486634 -412.488583) (xy 338.536208 -412.511228) (xy 338.582055 -412.540697)
			(xy 338.623242 -412.576391) (xy 338.65893 -412.617582) (xy 338.688394 -412.663432) (xy 338.711033 -412.713009)
			(xy 338.726387 -412.765303) (xy 338.734142 -412.819249) (xy 338.734142 -412.873749) (xy 340.171798 -412.873749)
			(xy 340.171798 -412.819251) (xy 340.179554 -412.765307) (xy 340.194908 -412.713016) (xy 340.217546 -412.663443)
			(xy 340.24701 -412.617596) (xy 340.282698 -412.576408) (xy 340.323884 -412.540718) (xy 340.36973 -412.511253)
			(xy 340.419303 -412.488612) (xy 340.471594 -412.473257) (xy 340.525537 -412.465499) (xy 340.552786 -412.465012)
			(xy 341.416386 -412.465012) (xy 341.443641 -412.465434) (xy 341.497596 -412.47319) (xy 341.549899 -412.488545)
			(xy 341.599483 -412.511188) (xy 341.645341 -412.540657) (xy 341.686537 -412.576353) (xy 341.722234 -412.617548)
			(xy 341.751705 -412.663405) (xy 341.77435 -412.712988) (xy 341.789707 -412.76529) (xy 341.797465 -412.819245)
			(xy 341.797465 -412.873753) (xy 343.234975 -412.873753) (xy 343.234975 -412.819247) (xy 343.242733 -412.765297)
			(xy 343.258089 -412.713) (xy 343.280732 -412.663421) (xy 343.310201 -412.617569) (xy 343.345896 -412.576377)
			(xy 343.387089 -412.540686) (xy 343.432943 -412.51122) (xy 343.482524 -412.48858) (xy 343.534822 -412.473227)
			(xy 343.588773 -412.465474) (xy 343.616026 -412.465012) (xy 344.479626 -412.465012) (xy 344.506877 -412.46546)
			(xy 344.560825 -412.47322) (xy 344.61312 -412.488578) (xy 344.662696 -412.511222) (xy 344.708546 -412.54069)
			(xy 344.749735 -412.576383) (xy 344.785426 -412.617575) (xy 344.814891 -412.663427) (xy 344.837531 -412.713005)
			(xy 344.852886 -412.7653) (xy 344.860642 -412.819249) (xy 344.860642 -412.873748) (xy 346.298298 -412.873748)
			(xy 346.298298 -412.819252) (xy 346.306053 -412.76531) (xy 346.321406 -412.713021) (xy 346.344043 -412.663448)
			(xy 346.373505 -412.617602) (xy 346.409191 -412.576415) (xy 346.450375 -412.540725) (xy 346.496218 -412.51126)
			(xy 346.545789 -412.488618) (xy 346.598077 -412.473261) (xy 346.652018 -412.465501) (xy 346.679266 -412.465012)
			(xy 347.542866 -412.465012) (xy 347.570122 -412.465433) (xy 347.624079 -412.473186) (xy 347.676384 -412.48854)
			(xy 347.725971 -412.511182) (xy 347.771831 -412.54065) (xy 347.81303 -412.576346) (xy 347.848729 -412.617542)
			(xy 347.878202 -412.663399) (xy 347.900848 -412.712984) (xy 347.916207 -412.765287) (xy 347.923965 -412.819244)
			(xy 347.923965 -412.873752) (xy 349.361475 -412.873752) (xy 349.361475 -412.819248) (xy 349.369232 -412.7653)
			(xy 349.384588 -412.713004) (xy 349.407229 -412.663426) (xy 349.436696 -412.617575) (xy 349.472389 -412.576384)
			(xy 349.51358 -412.540693) (xy 349.559431 -412.511226) (xy 349.60901 -412.488585) (xy 349.661306 -412.473231)
			(xy 349.715254 -412.465475) (xy 349.742506 -412.465012) (xy 350.606106 -412.465012) (xy 350.633358 -412.465458)
			(xy 350.687308 -412.473216) (xy 350.739605 -412.488572) (xy 350.789184 -412.511215) (xy 350.835036 -412.540683)
			(xy 350.876228 -412.576376) (xy 350.911921 -412.617569) (xy 350.941388 -412.663421) (xy 350.96403 -412.713001)
			(xy 350.979385 -412.765298) (xy 350.987142 -412.819248) (xy 350.987142 -412.873752) (xy 370.513075 -412.873752)
			(xy 370.513075 -412.819248) (xy 370.520832 -412.7653) (xy 370.536187 -412.713005) (xy 370.558829 -412.663427)
			(xy 370.588295 -412.617576) (xy 370.623987 -412.576386) (xy 370.665178 -412.540694) (xy 370.711029 -412.511228)
			(xy 370.760607 -412.488587) (xy 370.812902 -412.473231) (xy 370.86685 -412.465475) (xy 370.894102 -412.465012)
			(xy 371.757702 -412.465012) (xy 371.784955 -412.465458) (xy 371.838905 -412.473215) (xy 371.891202 -412.488571)
			(xy 371.940782 -412.511214) (xy 371.986634 -412.540682) (xy 372.027826 -412.576375) (xy 372.06352 -412.617567)
			(xy 372.092987 -412.66342) (xy 372.115629 -412.713) (xy 372.130985 -412.765297) (xy 372.138742 -412.819247)
			(xy 372.138742 -412.873753) (xy 373.576275 -412.873753) (xy 373.576275 -412.819247) (xy 373.584033 -412.765295)
			(xy 373.59939 -412.712996) (xy 373.622035 -412.663416) (xy 373.651505 -412.617563) (xy 373.687201 -412.576372)
			(xy 373.728397 -412.54068) (xy 373.774253 -412.511215) (xy 373.823836 -412.488576) (xy 373.876136 -412.473224)
			(xy 373.930089 -412.465472) (xy 373.957342 -412.465012) (xy 374.820942 -412.465012) (xy 374.848193 -412.465461)
			(xy 374.902139 -412.473222) (xy 374.954431 -412.488582) (xy 375.004006 -412.511227) (xy 375.049853 -412.540696)
			(xy 375.091041 -412.576389) (xy 375.126729 -412.61758) (xy 375.156193 -412.663431) (xy 375.178833 -412.713008)
			(xy 375.194186 -412.765302) (xy 375.201942 -412.819249) (xy 375.201942 -412.873749) (xy 376.639598 -412.873749)
			(xy 376.639598 -412.819251) (xy 376.647354 -412.765308) (xy 376.662707 -412.713017) (xy 376.685346 -412.663444)
			(xy 376.714809 -412.617597) (xy 376.750497 -412.576409) (xy 376.791682 -412.54072) (xy 376.837528 -412.511254)
			(xy 376.8871 -412.488613) (xy 376.93939 -412.473258) (xy 376.993333 -412.465499) (xy 377.020582 -412.465012)
			(xy 377.884182 -412.465012) (xy 377.911437 -412.465434) (xy 377.965393 -412.473189) (xy 378.017696 -412.488544)
			(xy 378.067281 -412.511187) (xy 378.113139 -412.540656) (xy 378.154336 -412.576352) (xy 378.190033 -412.617547)
			(xy 378.219504 -412.663403) (xy 378.242149 -412.712987) (xy 378.257507 -412.765289) (xy 378.265265 -412.819245)
			(xy 378.265265 -412.873752) (xy 379.702775 -412.873752) (xy 379.702775 -412.819248) (xy 379.710532 -412.765298)
			(xy 379.725889 -412.713001) (xy 379.748532 -412.663422) (xy 379.778 -412.61757) (xy 379.813694 -412.576379)
			(xy 379.854888 -412.540687) (xy 379.900741 -412.511221) (xy 379.950321 -412.488581) (xy 380.002619 -412.473228)
			(xy 380.05657 -412.465474) (xy 380.083822 -412.465012) (xy 380.947422 -412.465012) (xy 380.974674 -412.465459)
			(xy 381.028622 -412.473219) (xy 381.080917 -412.488577) (xy 381.130494 -412.51122) (xy 381.176344 -412.540689)
			(xy 381.217534 -412.576382) (xy 381.253225 -412.617574) (xy 381.28269 -412.663426) (xy 381.305331 -412.713004)
			(xy 381.320686 -412.7653) (xy 381.328442 -412.819248) (xy 381.328442 -412.873748) (xy 382.766098 -412.873748)
			(xy 382.766098 -412.819252) (xy 382.773853 -412.76531) (xy 382.789206 -412.713022) (xy 382.811843 -412.663449)
			(xy 382.841304 -412.617603) (xy 382.876989 -412.576416) (xy 382.918173 -412.540727) (xy 382.964016 -412.511261)
			(xy 383.013586 -412.488619) (xy 383.065873 -412.473261) (xy 383.119814 -412.465501) (xy 383.147062 -412.465012)
			(xy 384.010662 -412.465012) (xy 384.037918 -412.465432) (xy 384.091876 -412.473185) (xy 384.144181 -412.488539)
			(xy 384.193769 -412.51118) (xy 384.239629 -412.540649) (xy 384.280829 -412.576345) (xy 384.316528 -412.61754)
			(xy 384.346001 -412.663398) (xy 384.368648 -412.712983) (xy 384.384007 -412.765287) (xy 384.391765 -412.819244)
			(xy 384.391765 -412.873752) (xy 385.829275 -412.873752) (xy 385.829275 -412.819248) (xy 385.837032 -412.7653)
			(xy 385.852387 -412.713005) (xy 385.875029 -412.663427) (xy 385.904495 -412.617576) (xy 385.940187 -412.576386)
			(xy 385.981378 -412.540694) (xy 386.027229 -412.511228) (xy 386.076807 -412.488587) (xy 386.129102 -412.473231)
			(xy 386.18305 -412.465475) (xy 386.210302 -412.465012) (xy 387.073902 -412.465012) (xy 387.101155 -412.465458)
			(xy 387.155105 -412.473215) (xy 387.207402 -412.488571) (xy 387.256982 -412.511214) (xy 387.302834 -412.540682)
			(xy 387.344026 -412.576375) (xy 387.37972 -412.617567) (xy 387.409187 -412.66342) (xy 387.431829 -412.713)
			(xy 387.447185 -412.765297) (xy 387.454942 -412.819247) (xy 387.454942 -412.873753) (xy 388.892475 -412.873753)
			(xy 388.892475 -412.819247) (xy 388.900233 -412.765295) (xy 388.91559 -412.712996) (xy 388.938235 -412.663416)
			(xy 388.967705 -412.617563) (xy 389.003401 -412.576372) (xy 389.044597 -412.54068) (xy 389.090453 -412.511215)
			(xy 389.140036 -412.488576) (xy 389.192336 -412.473224) (xy 389.246289 -412.465472) (xy 389.273542 -412.465012)
			(xy 390.137142 -412.465012) (xy 390.164393 -412.465461) (xy 390.218339 -412.473222) (xy 390.270631 -412.488582)
			(xy 390.320206 -412.511227) (xy 390.366053 -412.540696) (xy 390.407241 -412.576389) (xy 390.442929 -412.61758)
			(xy 390.472393 -412.663431) (xy 390.495033 -412.713008) (xy 390.510386 -412.765302) (xy 390.518142 -412.819249)
			(xy 390.518142 -412.873749) (xy 391.955798 -412.873749) (xy 391.955798 -412.819251) (xy 391.963554 -412.765308)
			(xy 391.978907 -412.713017) (xy 392.001546 -412.663444) (xy 392.031009 -412.617597) (xy 392.066697 -412.576409)
			(xy 392.107882 -412.54072) (xy 392.153728 -412.511254) (xy 392.2033 -412.488613) (xy 392.25559 -412.473258)
			(xy 392.309533 -412.465499) (xy 392.336782 -412.465012) (xy 393.200382 -412.465012) (xy 393.227637 -412.465434)
			(xy 393.281593 -412.473189) (xy 393.333896 -412.488544) (xy 393.383481 -412.511187) (xy 393.429339 -412.540656)
			(xy 393.470536 -412.576352) (xy 393.506233 -412.617547) (xy 393.535704 -412.663403) (xy 393.558349 -412.712987)
			(xy 393.573707 -412.765289) (xy 393.581465 -412.819245) (xy 393.581465 -412.873752) (xy 395.018975 -412.873752)
			(xy 395.018975 -412.819248) (xy 395.026732 -412.765298) (xy 395.042089 -412.713001) (xy 395.064732 -412.663422)
			(xy 395.0942 -412.61757) (xy 395.129894 -412.576379) (xy 395.171088 -412.540687) (xy 395.216941 -412.511221)
			(xy 395.266521 -412.488581) (xy 395.318819 -412.473228) (xy 395.37277 -412.465474) (xy 395.400022 -412.465012)
			(xy 396.263622 -412.465012) (xy 396.290874 -412.465459) (xy 396.344822 -412.473219) (xy 396.397117 -412.488577)
			(xy 396.446694 -412.51122) (xy 396.492544 -412.540689) (xy 396.533734 -412.576382) (xy 396.569425 -412.617574)
			(xy 396.59889 -412.663426) (xy 396.621531 -412.713004) (xy 396.636886 -412.7653) (xy 396.644642 -412.819248)
			(xy 396.644642 -412.873748) (xy 398.082298 -412.873748) (xy 398.082298 -412.819252) (xy 398.090053 -412.76531)
			(xy 398.105406 -412.713022) (xy 398.128043 -412.663449) (xy 398.157504 -412.617603) (xy 398.193189 -412.576416)
			(xy 398.234373 -412.540727) (xy 398.280216 -412.511261) (xy 398.329786 -412.488619) (xy 398.382073 -412.473261)
			(xy 398.436014 -412.465501) (xy 398.463262 -412.465012) (xy 399.326862 -412.465012) (xy 399.354118 -412.465432)
			(xy 399.408076 -412.473185) (xy 399.460381 -412.488539) (xy 399.509969 -412.51118) (xy 399.555829 -412.540649)
			(xy 399.597029 -412.576345) (xy 399.632728 -412.61754) (xy 399.662201 -412.663398) (xy 399.684848 -412.712983)
			(xy 399.700207 -412.765287) (xy 399.707965 -412.819244) (xy 399.707965 -412.873752) (xy 401.145475 -412.873752)
			(xy 401.145475 -412.819248) (xy 401.153232 -412.7653) (xy 401.168587 -412.713005) (xy 401.191229 -412.663427)
			(xy 401.220695 -412.617576) (xy 401.256387 -412.576386) (xy 401.297578 -412.540694) (xy 401.343429 -412.511228)
			(xy 401.393007 -412.488587) (xy 401.445302 -412.473231) (xy 401.49925 -412.465475) (xy 401.526502 -412.465012)
			(xy 402.390102 -412.465012) (xy 402.417355 -412.465458) (xy 402.471305 -412.473215) (xy 402.523602 -412.488571)
			(xy 402.573182 -412.511214) (xy 402.619034 -412.540682) (xy 402.660226 -412.576375) (xy 402.69592 -412.617567)
			(xy 402.725387 -412.66342) (xy 402.748029 -412.713) (xy 402.763385 -412.765297) (xy 402.771142 -412.819247)
			(xy 402.771142 -412.873753) (xy 404.208675 -412.873753) (xy 404.208675 -412.819247) (xy 404.216433 -412.765295)
			(xy 404.23179 -412.712996) (xy 404.254435 -412.663416) (xy 404.283905 -412.617563) (xy 404.319601 -412.576372)
			(xy 404.360797 -412.54068) (xy 404.406653 -412.511215) (xy 404.456236 -412.488576) (xy 404.508536 -412.473224)
			(xy 404.562489 -412.465472) (xy 404.589742 -412.465012) (xy 405.453342 -412.465012) (xy 405.480593 -412.465461)
			(xy 405.534539 -412.473222) (xy 405.586831 -412.488582) (xy 405.636406 -412.511227) (xy 405.682253 -412.540696)
			(xy 405.723441 -412.576389) (xy 405.759129 -412.61758) (xy 405.788593 -412.663431) (xy 405.811233 -412.713008)
			(xy 405.826586 -412.765302) (xy 405.834342 -412.819249) (xy 405.834342 -412.873749) (xy 407.271998 -412.873749)
			(xy 407.271998 -412.819251) (xy 407.279754 -412.765308) (xy 407.295107 -412.713017) (xy 407.317746 -412.663444)
			(xy 407.347209 -412.617597) (xy 407.382897 -412.576409) (xy 407.424082 -412.54072) (xy 407.469928 -412.511254)
			(xy 407.5195 -412.488613) (xy 407.57179 -412.473258) (xy 407.625733 -412.465499) (xy 407.652982 -412.465012)
			(xy 408.516582 -412.465012) (xy 408.543837 -412.465434) (xy 408.597793 -412.473189) (xy 408.650096 -412.488544)
			(xy 408.699681 -412.511187) (xy 408.745539 -412.540656) (xy 408.786736 -412.576352) (xy 408.822433 -412.617547)
			(xy 408.851904 -412.663403) (xy 408.874549 -412.712987) (xy 408.889907 -412.765289) (xy 408.897665 -412.819245)
			(xy 408.897665 -412.873752) (xy 410.335175 -412.873752) (xy 410.335175 -412.819248) (xy 410.342932 -412.765298)
			(xy 410.358289 -412.713001) (xy 410.380932 -412.663422) (xy 410.4104 -412.61757) (xy 410.446094 -412.576379)
			(xy 410.487288 -412.540687) (xy 410.533141 -412.511221) (xy 410.582721 -412.488581) (xy 410.635019 -412.473228)
			(xy 410.68897 -412.465474) (xy 410.716222 -412.465012) (xy 411.579822 -412.465012) (xy 411.607074 -412.465459)
			(xy 411.661022 -412.473219) (xy 411.713317 -412.488577) (xy 411.762894 -412.51122) (xy 411.808744 -412.540689)
			(xy 411.849934 -412.576382) (xy 411.885625 -412.617574) (xy 411.91509 -412.663426) (xy 411.937731 -412.713004)
			(xy 411.953086 -412.7653) (xy 411.960842 -412.819248) (xy 411.960842 -412.873748) (xy 413.398498 -412.873748)
			(xy 413.398498 -412.819252) (xy 413.406253 -412.76531) (xy 413.421606 -412.713022) (xy 413.444243 -412.663449)
			(xy 413.473704 -412.617603) (xy 413.509389 -412.576416) (xy 413.550573 -412.540727) (xy 413.596416 -412.511261)
			(xy 413.645986 -412.488619) (xy 413.698273 -412.473261) (xy 413.752214 -412.465501) (xy 413.779462 -412.465012)
			(xy 414.643062 -412.465012) (xy 414.670318 -412.465432) (xy 414.724276 -412.473185) (xy 414.776581 -412.488539)
			(xy 414.826169 -412.51118) (xy 414.872029 -412.540649) (xy 414.913229 -412.576345) (xy 414.948928 -412.61754)
			(xy 414.978401 -412.663398) (xy 415.001048 -412.712983) (xy 415.016407 -412.765287) (xy 415.024165 -412.819244)
			(xy 415.024165 -412.873752) (xy 416.461675 -412.873752) (xy 416.461675 -412.819248) (xy 416.469432 -412.7653)
			(xy 416.484787 -412.713005) (xy 416.507429 -412.663427) (xy 416.536895 -412.617576) (xy 416.572587 -412.576386)
			(xy 416.613778 -412.540694) (xy 416.659629 -412.511228) (xy 416.709207 -412.488587) (xy 416.761502 -412.473231)
			(xy 416.81545 -412.465475) (xy 416.842702 -412.465012) (xy 417.706302 -412.465012) (xy 417.733555 -412.465458)
			(xy 417.787505 -412.473215) (xy 417.839802 -412.488571) (xy 417.889382 -412.511214) (xy 417.935234 -412.540682)
			(xy 417.976426 -412.576375) (xy 418.01212 -412.617567) (xy 418.041587 -412.66342) (xy 418.064229 -412.713)
			(xy 418.079585 -412.765297) (xy 418.087342 -412.819247) (xy 418.087342 -412.873753) (xy 418.079585 -412.927703)
			(xy 418.064229 -412.98) (xy 418.041587 -413.02958) (xy 418.01212 -413.075433) (xy 417.976426 -413.116625)
			(xy 417.935234 -413.152318) (xy 417.889382 -413.181786) (xy 417.839802 -413.204429) (xy 417.787505 -413.219785)
			(xy 417.733555 -413.227542) (xy 417.706302 -413.228028) (xy 416.842702 -413.228028) (xy 416.81545 -413.227525)
			(xy 416.761502 -413.219769) (xy 416.709207 -413.204413) (xy 416.659629 -413.181772) (xy 416.613778 -413.152306)
			(xy 416.572587 -413.116614) (xy 416.536895 -413.075424) (xy 416.507429 -413.029573) (xy 416.484787 -412.979995)
			(xy 416.469432 -412.9277) (xy 416.461675 -412.873752) (xy 415.024165 -412.873752) (xy 415.024165 -412.873756)
			(xy 415.016407 -412.927713) (xy 415.001048 -412.980017) (xy 414.978401 -413.029602) (xy 414.948928 -413.07546)
			(xy 414.913229 -413.116655) (xy 414.872029 -413.152351) (xy 414.826169 -413.18182) (xy 414.776581 -413.204461)
			(xy 414.724276 -413.219815) (xy 414.670318 -413.227568) (xy 414.643062 -413.228028) (xy 413.779462 -413.228028)
			(xy 413.752214 -413.227499) (xy 413.698273 -413.219739) (xy 413.645986 -413.204381) (xy 413.596416 -413.181739)
			(xy 413.550573 -413.152273) (xy 413.509389 -413.116584) (xy 413.473704 -413.075397) (xy 413.444243 -413.029551)
			(xy 413.421606 -412.979978) (xy 413.406253 -412.92769) (xy 413.398498 -412.873748) (xy 411.960842 -412.873748)
			(xy 411.960842 -412.873752) (xy 411.953086 -412.9277) (xy 411.937731 -412.979996) (xy 411.91509 -413.029574)
			(xy 411.885625 -413.075426) (xy 411.849934 -413.116618) (xy 411.808744 -413.152311) (xy 411.762894 -413.18178)
			(xy 411.713317 -413.204423) (xy 411.661022 -413.219781) (xy 411.607074 -413.227541) (xy 411.579822 -413.228028)
			(xy 410.716222 -413.228028) (xy 410.68897 -413.227526) (xy 410.635019 -413.219772) (xy 410.582721 -413.204419)
			(xy 410.533141 -413.181779) (xy 410.487288 -413.152313) (xy 410.446094 -413.116621) (xy 410.4104 -413.07543)
			(xy 410.380932 -413.029578) (xy 410.358289 -412.979999) (xy 410.342932 -412.927702) (xy 410.335175 -412.873752)
			(xy 408.897665 -412.873752) (xy 408.897665 -412.873755) (xy 408.889907 -412.927711) (xy 408.874549 -412.980013)
			(xy 408.851904 -413.029597) (xy 408.822433 -413.075453) (xy 408.786736 -413.116648) (xy 408.745539 -413.152344)
			(xy 408.699681 -413.181813) (xy 408.650096 -413.204456) (xy 408.597793 -413.219811) (xy 408.543837 -413.227566)
			(xy 408.516582 -413.228028) (xy 407.652982 -413.228028) (xy 407.625733 -413.227501) (xy 407.57179 -413.219742)
			(xy 407.5195 -413.204387) (xy 407.469928 -413.181746) (xy 407.424082 -413.15228) (xy 407.382897 -413.116591)
			(xy 407.347209 -413.075403) (xy 407.317746 -413.029556) (xy 407.295107 -412.979983) (xy 407.279754 -412.927692)
			(xy 407.271998 -412.873749) (xy 405.834342 -412.873749) (xy 405.834342 -412.873751) (xy 405.826586 -412.927698)
			(xy 405.811233 -412.979992) (xy 405.788593 -413.029569) (xy 405.759129 -413.07542) (xy 405.723441 -413.116611)
			(xy 405.682253 -413.152304) (xy 405.636406 -413.181773) (xy 405.586831 -413.204418) (xy 405.534539 -413.219778)
			(xy 405.480593 -413.227539) (xy 405.453342 -413.228028) (xy 404.589742 -413.228028) (xy 404.562489 -413.227528)
			(xy 404.508536 -413.219776) (xy 404.456236 -413.204424) (xy 404.406653 -413.181785) (xy 404.360797 -413.15232)
			(xy 404.319601 -413.116628) (xy 404.283905 -413.075437) (xy 404.254435 -413.029584) (xy 404.23179 -412.980004)
			(xy 404.216433 -412.927705) (xy 404.208675 -412.873753) (xy 402.771142 -412.873753) (xy 402.763385 -412.927703)
			(xy 402.748029 -412.98) (xy 402.725387 -413.02958) (xy 402.69592 -413.075433) (xy 402.660226 -413.116625)
			(xy 402.619034 -413.152318) (xy 402.573182 -413.181786) (xy 402.523602 -413.204429) (xy 402.471305 -413.219785)
			(xy 402.417355 -413.227542) (xy 402.390102 -413.228028) (xy 401.526502 -413.228028) (xy 401.49925 -413.227525)
			(xy 401.445302 -413.219769) (xy 401.393007 -413.204413) (xy 401.343429 -413.181772) (xy 401.297578 -413.152306)
			(xy 401.256387 -413.116614) (xy 401.220695 -413.075424) (xy 401.191229 -413.029573) (xy 401.168587 -412.979995)
			(xy 401.153232 -412.9277) (xy 401.145475 -412.873752) (xy 399.707965 -412.873752) (xy 399.707965 -412.873756)
			(xy 399.700207 -412.927713) (xy 399.684848 -412.980017) (xy 399.662201 -413.029602) (xy 399.632728 -413.07546)
			(xy 399.597029 -413.116655) (xy 399.555829 -413.152351) (xy 399.509969 -413.18182) (xy 399.460381 -413.204461)
			(xy 399.408076 -413.219815) (xy 399.354118 -413.227568) (xy 399.326862 -413.228028) (xy 398.463262 -413.228028)
			(xy 398.436014 -413.227499) (xy 398.382073 -413.219739) (xy 398.329786 -413.204381) (xy 398.280216 -413.181739)
			(xy 398.234373 -413.152273) (xy 398.193189 -413.116584) (xy 398.157504 -413.075397) (xy 398.128043 -413.029551)
			(xy 398.105406 -412.979978) (xy 398.090053 -412.92769) (xy 398.082298 -412.873748) (xy 396.644642 -412.873748)
			(xy 396.644642 -412.873752) (xy 396.636886 -412.9277) (xy 396.621531 -412.979996) (xy 396.59889 -413.029574)
			(xy 396.569425 -413.075426) (xy 396.533734 -413.116618) (xy 396.492544 -413.152311) (xy 396.446694 -413.18178)
			(xy 396.397117 -413.204423) (xy 396.344822 -413.219781) (xy 396.290874 -413.227541) (xy 396.263622 -413.228028)
			(xy 395.400022 -413.228028) (xy 395.37277 -413.227526) (xy 395.318819 -413.219772) (xy 395.266521 -413.204419)
			(xy 395.216941 -413.181779) (xy 395.171088 -413.152313) (xy 395.129894 -413.116621) (xy 395.0942 -413.07543)
			(xy 395.064732 -413.029578) (xy 395.042089 -412.979999) (xy 395.026732 -412.927702) (xy 395.018975 -412.873752)
			(xy 393.581465 -412.873752) (xy 393.581465 -412.873755) (xy 393.573707 -412.927711) (xy 393.558349 -412.980013)
			(xy 393.535704 -413.029597) (xy 393.506233 -413.075453) (xy 393.470536 -413.116648) (xy 393.429339 -413.152344)
			(xy 393.383481 -413.181813) (xy 393.333896 -413.204456) (xy 393.281593 -413.219811) (xy 393.227637 -413.227566)
			(xy 393.200382 -413.228028) (xy 392.336782 -413.228028) (xy 392.309533 -413.227501) (xy 392.25559 -413.219742)
			(xy 392.2033 -413.204387) (xy 392.153728 -413.181746) (xy 392.107882 -413.15228) (xy 392.066697 -413.116591)
			(xy 392.031009 -413.075403) (xy 392.001546 -413.029556) (xy 391.978907 -412.979983) (xy 391.963554 -412.927692)
			(xy 391.955798 -412.873749) (xy 390.518142 -412.873749) (xy 390.518142 -412.873751) (xy 390.510386 -412.927698)
			(xy 390.495033 -412.979992) (xy 390.472393 -413.029569) (xy 390.442929 -413.07542) (xy 390.407241 -413.116611)
			(xy 390.366053 -413.152304) (xy 390.320206 -413.181773) (xy 390.270631 -413.204418) (xy 390.218339 -413.219778)
			(xy 390.164393 -413.227539) (xy 390.137142 -413.228028) (xy 389.273542 -413.228028) (xy 389.246289 -413.227528)
			(xy 389.192336 -413.219776) (xy 389.140036 -413.204424) (xy 389.090453 -413.181785) (xy 389.044597 -413.15232)
			(xy 389.003401 -413.116628) (xy 388.967705 -413.075437) (xy 388.938235 -413.029584) (xy 388.91559 -412.980004)
			(xy 388.900233 -412.927705) (xy 388.892475 -412.873753) (xy 387.454942 -412.873753) (xy 387.447185 -412.927703)
			(xy 387.431829 -412.98) (xy 387.409187 -413.02958) (xy 387.37972 -413.075433) (xy 387.344026 -413.116625)
			(xy 387.302834 -413.152318) (xy 387.256982 -413.181786) (xy 387.207402 -413.204429) (xy 387.155105 -413.219785)
			(xy 387.101155 -413.227542) (xy 387.073902 -413.228028) (xy 386.210302 -413.228028) (xy 386.18305 -413.227525)
			(xy 386.129102 -413.219769) (xy 386.076807 -413.204413) (xy 386.027229 -413.181772) (xy 385.981378 -413.152306)
			(xy 385.940187 -413.116614) (xy 385.904495 -413.075424) (xy 385.875029 -413.029573) (xy 385.852387 -412.979995)
			(xy 385.837032 -412.9277) (xy 385.829275 -412.873752) (xy 384.391765 -412.873752) (xy 384.391765 -412.873756)
			(xy 384.384007 -412.927713) (xy 384.368648 -412.980017) (xy 384.346001 -413.029602) (xy 384.316528 -413.07546)
			(xy 384.280829 -413.116655) (xy 384.239629 -413.152351) (xy 384.193769 -413.18182) (xy 384.144181 -413.204461)
			(xy 384.091876 -413.219815) (xy 384.037918 -413.227568) (xy 384.010662 -413.228028) (xy 383.147062 -413.228028)
			(xy 383.119814 -413.227499) (xy 383.065873 -413.219739) (xy 383.013586 -413.204381) (xy 382.964016 -413.181739)
			(xy 382.918173 -413.152273) (xy 382.876989 -413.116584) (xy 382.841304 -413.075397) (xy 382.811843 -413.029551)
			(xy 382.789206 -412.979978) (xy 382.773853 -412.92769) (xy 382.766098 -412.873748) (xy 381.328442 -412.873748)
			(xy 381.328442 -412.873752) (xy 381.320686 -412.9277) (xy 381.305331 -412.979996) (xy 381.28269 -413.029574)
			(xy 381.253225 -413.075426) (xy 381.217534 -413.116618) (xy 381.176344 -413.152311) (xy 381.130494 -413.18178)
			(xy 381.080917 -413.204423) (xy 381.028622 -413.219781) (xy 380.974674 -413.227541) (xy 380.947422 -413.228028)
			(xy 380.083822 -413.228028) (xy 380.05657 -413.227526) (xy 380.002619 -413.219772) (xy 379.950321 -413.204419)
			(xy 379.900741 -413.181779) (xy 379.854888 -413.152313) (xy 379.813694 -413.116621) (xy 379.778 -413.07543)
			(xy 379.748532 -413.029578) (xy 379.725889 -412.979999) (xy 379.710532 -412.927702) (xy 379.702775 -412.873752)
			(xy 378.265265 -412.873752) (xy 378.265265 -412.873755) (xy 378.257507 -412.927711) (xy 378.242149 -412.980013)
			(xy 378.219504 -413.029597) (xy 378.190033 -413.075453) (xy 378.154336 -413.116648) (xy 378.113139 -413.152344)
			(xy 378.067281 -413.181813) (xy 378.017696 -413.204456) (xy 377.965393 -413.219811) (xy 377.911437 -413.227566)
			(xy 377.884182 -413.228028) (xy 377.020582 -413.228028) (xy 376.993333 -413.227501) (xy 376.93939 -413.219742)
			(xy 376.8871 -413.204387) (xy 376.837528 -413.181746) (xy 376.791682 -413.15228) (xy 376.750497 -413.116591)
			(xy 376.714809 -413.075403) (xy 376.685346 -413.029556) (xy 376.662707 -412.979983) (xy 376.647354 -412.927692)
			(xy 376.639598 -412.873749) (xy 375.201942 -412.873749) (xy 375.201942 -412.873751) (xy 375.194186 -412.927698)
			(xy 375.178833 -412.979992) (xy 375.156193 -413.029569) (xy 375.126729 -413.07542) (xy 375.091041 -413.116611)
			(xy 375.049853 -413.152304) (xy 375.004006 -413.181773) (xy 374.954431 -413.204418) (xy 374.902139 -413.219778)
			(xy 374.848193 -413.227539) (xy 374.820942 -413.228028) (xy 373.957342 -413.228028) (xy 373.930089 -413.227528)
			(xy 373.876136 -413.219776) (xy 373.823836 -413.204424) (xy 373.774253 -413.181785) (xy 373.728397 -413.15232)
			(xy 373.687201 -413.116628) (xy 373.651505 -413.075437) (xy 373.622035 -413.029584) (xy 373.59939 -412.980004)
			(xy 373.584033 -412.927705) (xy 373.576275 -412.873753) (xy 372.138742 -412.873753) (xy 372.130985 -412.927703)
			(xy 372.115629 -412.98) (xy 372.092987 -413.02958) (xy 372.06352 -413.075433) (xy 372.027826 -413.116625)
			(xy 371.986634 -413.152318) (xy 371.940782 -413.181786) (xy 371.891202 -413.204429) (xy 371.838905 -413.219785)
			(xy 371.784955 -413.227542) (xy 371.757702 -413.228028) (xy 370.894102 -413.228028) (xy 370.86685 -413.227525)
			(xy 370.812902 -413.219769) (xy 370.760607 -413.204413) (xy 370.711029 -413.181772) (xy 370.665178 -413.152306)
			(xy 370.623987 -413.116614) (xy 370.588295 -413.075424) (xy 370.558829 -413.029573) (xy 370.536187 -412.979995)
			(xy 370.520832 -412.9277) (xy 370.513075 -412.873752) (xy 350.987142 -412.873752) (xy 350.979385 -412.927702)
			(xy 350.96403 -412.979999) (xy 350.941388 -413.029579) (xy 350.911921 -413.075431) (xy 350.876228 -413.116624)
			(xy 350.835036 -413.152317) (xy 350.789184 -413.181785) (xy 350.739605 -413.204428) (xy 350.687308 -413.219784)
			(xy 350.633358 -413.227542) (xy 350.606106 -413.228028) (xy 349.742506 -413.228028) (xy 349.715254 -413.227525)
			(xy 349.661306 -413.219769) (xy 349.60901 -413.204415) (xy 349.559431 -413.181774) (xy 349.51358 -413.152307)
			(xy 349.472389 -413.116616) (xy 349.436696 -413.075425) (xy 349.407229 -413.029574) (xy 349.384588 -412.979996)
			(xy 349.369232 -412.9277) (xy 349.361475 -412.873752) (xy 347.923965 -412.873752) (xy 347.923965 -412.873756)
			(xy 347.916207 -412.927713) (xy 347.900848 -412.980016) (xy 347.878202 -413.029601) (xy 347.848729 -413.075458)
			(xy 347.81303 -413.116654) (xy 347.771831 -413.15235) (xy 347.725971 -413.181818) (xy 347.676384 -413.20446)
			(xy 347.624079 -413.219814) (xy 347.570122 -413.227567) (xy 347.542866 -413.228028) (xy 346.679266 -413.228028)
			(xy 346.652018 -413.227499) (xy 346.598077 -413.219739) (xy 346.545789 -413.204382) (xy 346.496218 -413.18174)
			(xy 346.450375 -413.152275) (xy 346.409191 -413.116585) (xy 346.373505 -413.075398) (xy 346.344043 -413.029552)
			(xy 346.321406 -412.979979) (xy 346.306053 -412.92769) (xy 346.298298 -412.873748) (xy 344.860642 -412.873748)
			(xy 344.860642 -412.873751) (xy 344.852886 -412.9277) (xy 344.837531 -412.979995) (xy 344.814891 -413.029573)
			(xy 344.785426 -413.075425) (xy 344.749735 -413.116617) (xy 344.708546 -413.15231) (xy 344.662696 -413.181778)
			(xy 344.61312 -413.204422) (xy 344.560825 -413.21978) (xy 344.506877 -413.22754) (xy 344.479626 -413.228028)
			(xy 343.616026 -413.228028) (xy 343.588773 -413.227526) (xy 343.534822 -413.219773) (xy 343.482524 -413.20442)
			(xy 343.432943 -413.18178) (xy 343.387089 -413.152314) (xy 343.345896 -413.116623) (xy 343.310201 -413.075431)
			(xy 343.280732 -413.029579) (xy 343.258089 -412.98) (xy 343.242733 -412.927703) (xy 343.234975 -412.873753)
			(xy 341.797465 -412.873753) (xy 341.797465 -412.873755) (xy 341.789707 -412.92771) (xy 341.77435 -412.980012)
			(xy 341.751705 -413.029595) (xy 341.722234 -413.075452) (xy 341.686537 -413.116647) (xy 341.645341 -413.152343)
			(xy 341.599483 -413.181812) (xy 341.549899 -413.204455) (xy 341.497596 -413.21981) (xy 341.443641 -413.227566)
			(xy 341.416386 -413.228028) (xy 340.552786 -413.228028) (xy 340.525537 -413.227501) (xy 340.471594 -413.219743)
			(xy 340.419303 -413.204388) (xy 340.36973 -413.181747) (xy 340.323884 -413.152282) (xy 340.282698 -413.116592)
			(xy 340.24701 -413.075404) (xy 340.217546 -413.029557) (xy 340.194908 -412.979984) (xy 340.179554 -412.927693)
			(xy 340.171798 -412.873749) (xy 338.734142 -412.873749) (xy 338.734142 -412.873751) (xy 338.726387 -412.927697)
			(xy 338.711033 -412.979991) (xy 338.688394 -413.029568) (xy 338.65893 -413.075418) (xy 338.623242 -413.116609)
			(xy 338.582055 -413.152303) (xy 338.536208 -413.181772) (xy 338.486634 -413.204417) (xy 338.434342 -413.219777)
			(xy 338.380397 -413.227539) (xy 338.353146 -413.228028) (xy 337.489546 -413.228028) (xy 337.462292 -413.227528)
			(xy 337.408339 -413.219777) (xy 337.356039 -413.204425) (xy 337.306455 -413.181787) (xy 337.260599 -413.152321)
			(xy 337.219403 -413.11663) (xy 337.183706 -413.075438) (xy 337.154235 -413.029585) (xy 337.131591 -412.980004)
			(xy 337.116233 -412.927706) (xy 337.108475 -412.873754) (xy 335.670942 -412.873754) (xy 335.663185 -412.927702)
			(xy 335.64783 -412.979999) (xy 335.625188 -413.029579) (xy 335.595721 -413.075431) (xy 335.560028 -413.116624)
			(xy 335.518836 -413.152317) (xy 335.472984 -413.181785) (xy 335.423405 -413.204428) (xy 335.371108 -413.219784)
			(xy 335.317158 -413.227542) (xy 335.289906 -413.228028) (xy 334.426306 -413.228028) (xy 334.399054 -413.227525)
			(xy 334.345106 -413.219769) (xy 334.29281 -413.204415) (xy 334.243231 -413.181774) (xy 334.19738 -413.152307)
			(xy 334.156189 -413.116616) (xy 334.120496 -413.075425) (xy 334.091029 -413.029574) (xy 334.068388 -412.979996)
			(xy 334.053032 -412.9277) (xy 334.045275 -412.873752) (xy 332.607765 -412.873752) (xy 332.607765 -412.873756)
			(xy 332.600007 -412.927713) (xy 332.584648 -412.980016) (xy 332.562002 -413.029601) (xy 332.532529 -413.075458)
			(xy 332.49683 -413.116654) (xy 332.455631 -413.15235) (xy 332.409771 -413.181818) (xy 332.360184 -413.20446)
			(xy 332.307879 -413.219814) (xy 332.253922 -413.227567) (xy 332.226666 -413.228028) (xy 331.363066 -413.228028)
			(xy 331.335818 -413.227499) (xy 331.281877 -413.219739) (xy 331.229589 -413.204382) (xy 331.180018 -413.18174)
			(xy 331.134175 -413.152275) (xy 331.092991 -413.116585) (xy 331.057305 -413.075398) (xy 331.027843 -413.029552)
			(xy 331.005206 -412.979979) (xy 330.989853 -412.92769) (xy 330.982098 -412.873748) (xy 329.544442 -412.873748)
			(xy 329.544442 -412.873751) (xy 329.536686 -412.9277) (xy 329.521331 -412.979995) (xy 329.498691 -413.029573)
			(xy 329.469226 -413.075425) (xy 329.433535 -413.116617) (xy 329.392346 -413.15231) (xy 329.346496 -413.181778)
			(xy 329.29692 -413.204422) (xy 329.244625 -413.21978) (xy 329.190677 -413.22754) (xy 329.163426 -413.228028)
			(xy 328.299826 -413.228028) (xy 328.272573 -413.227526) (xy 328.218622 -413.219773) (xy 328.166324 -413.20442)
			(xy 328.116743 -413.18178) (xy 328.070889 -413.152314) (xy 328.029696 -413.116623) (xy 327.994001 -413.075431)
			(xy 327.964532 -413.029579) (xy 327.941889 -412.98) (xy 327.926533 -412.927703) (xy 327.918775 -412.873753)
			(xy 326.481265 -412.873753) (xy 326.481265 -412.873755) (xy 326.473507 -412.92771) (xy 326.45815 -412.980012)
			(xy 326.435505 -413.029595) (xy 326.406034 -413.075452) (xy 326.370337 -413.116647) (xy 326.329141 -413.152343)
			(xy 326.283283 -413.181812) (xy 326.233699 -413.204455) (xy 326.181396 -413.21981) (xy 326.127441 -413.227566)
			(xy 326.100186 -413.228028) (xy 325.236586 -413.228028) (xy 325.209337 -413.227501) (xy 325.155394 -413.219743)
			(xy 325.103103 -413.204388) (xy 325.05353 -413.181747) (xy 325.007684 -413.152282) (xy 324.966498 -413.116592)
			(xy 324.93081 -413.075404) (xy 324.901346 -413.029557) (xy 324.878708 -412.979984) (xy 324.863354 -412.927693)
			(xy 324.855598 -412.873749) (xy 323.417942 -412.873749) (xy 323.417942 -412.873751) (xy 323.410187 -412.927697)
			(xy 323.394833 -412.979991) (xy 323.372194 -413.029568) (xy 323.34273 -413.075418) (xy 323.307042 -413.116609)
			(xy 323.265855 -413.152303) (xy 323.220008 -413.181772) (xy 323.170434 -413.204417) (xy 323.118142 -413.219777)
			(xy 323.064197 -413.227539) (xy 323.036946 -413.228028) (xy 322.173346 -413.228028) (xy 322.146092 -413.227528)
			(xy 322.092139 -413.219777) (xy 322.039839 -413.204425) (xy 321.990255 -413.181787) (xy 321.944399 -413.152321)
			(xy 321.903203 -413.11663) (xy 321.867506 -413.075438) (xy 321.838035 -413.029585) (xy 321.815391 -412.980004)
			(xy 321.800033 -412.927706) (xy 321.792275 -412.873754) (xy 320.354742 -412.873754) (xy 320.346985 -412.927702)
			(xy 320.33163 -412.979999) (xy 320.308988 -413.029579) (xy 320.279521 -413.075431) (xy 320.243828 -413.116624)
			(xy 320.202636 -413.152317) (xy 320.156784 -413.181785) (xy 320.107205 -413.204428) (xy 320.054908 -413.219784)
			(xy 320.000958 -413.227542) (xy 319.973706 -413.228028) (xy 319.110106 -413.228028) (xy 319.082854 -413.227525)
			(xy 319.028906 -413.219769) (xy 318.97661 -413.204415) (xy 318.927031 -413.181774) (xy 318.88118 -413.152307)
			(xy 318.839989 -413.116616) (xy 318.804296 -413.075425) (xy 318.774829 -413.029574) (xy 318.752188 -412.979996)
			(xy 318.736832 -412.9277) (xy 318.729075 -412.873752) (xy 317.291565 -412.873752) (xy 317.291565 -412.873756)
			(xy 317.283807 -412.927713) (xy 317.268448 -412.980016) (xy 317.245802 -413.029601) (xy 317.216329 -413.075458)
			(xy 317.18063 -413.116654) (xy 317.139431 -413.15235) (xy 317.093571 -413.181818) (xy 317.043984 -413.20446)
			(xy 316.991679 -413.219814) (xy 316.937722 -413.227567) (xy 316.910466 -413.228028) (xy 316.046866 -413.228028)
			(xy 316.019618 -413.227499) (xy 315.965677 -413.219739) (xy 315.913389 -413.204382) (xy 315.863818 -413.18174)
			(xy 315.817975 -413.152275) (xy 315.776791 -413.116585) (xy 315.741105 -413.075398) (xy 315.711643 -413.029552)
			(xy 315.689006 -412.979979) (xy 315.673653 -412.92769) (xy 315.665898 -412.873748) (xy 314.228242 -412.873748)
			(xy 314.228242 -412.873751) (xy 314.220486 -412.9277) (xy 314.205131 -412.979995) (xy 314.182491 -413.029573)
			(xy 314.153026 -413.075425) (xy 314.117335 -413.116617) (xy 314.076146 -413.15231) (xy 314.030296 -413.181778)
			(xy 313.98072 -413.204422) (xy 313.928425 -413.21978) (xy 313.874477 -413.22754) (xy 313.847226 -413.228028)
			(xy 312.983626 -413.228028) (xy 312.956373 -413.227526) (xy 312.902422 -413.219773) (xy 312.850124 -413.20442)
			(xy 312.800543 -413.18178) (xy 312.754689 -413.152314) (xy 312.713496 -413.116623) (xy 312.677801 -413.075431)
			(xy 312.648332 -413.029579) (xy 312.625689 -412.98) (xy 312.610333 -412.927703) (xy 312.602575 -412.873753)
			(xy 311.165065 -412.873753) (xy 311.165065 -412.873755) (xy 311.157307 -412.92771) (xy 311.14195 -412.980012)
			(xy 311.119305 -413.029595) (xy 311.089834 -413.075452) (xy 311.054137 -413.116647) (xy 311.012941 -413.152343)
			(xy 310.967083 -413.181812) (xy 310.917499 -413.204455) (xy 310.865196 -413.21981) (xy 310.811241 -413.227566)
			(xy 310.783986 -413.228028) (xy 309.920386 -413.228028) (xy 309.893137 -413.227501) (xy 309.839194 -413.219743)
			(xy 309.786903 -413.204388) (xy 309.73733 -413.181747) (xy 309.691484 -413.152282) (xy 309.650298 -413.116592)
			(xy 309.61461 -413.075404) (xy 309.585146 -413.029557) (xy 309.562508 -412.979984) (xy 309.547154 -412.927693)
			(xy 309.539398 -412.873749) (xy 308.101742 -412.873749) (xy 308.101742 -412.873751) (xy 308.093987 -412.927697)
			(xy 308.078633 -412.979991) (xy 308.055994 -413.029568) (xy 308.02653 -413.075418) (xy 307.990842 -413.116609)
			(xy 307.949655 -413.152303) (xy 307.903808 -413.181772) (xy 307.854234 -413.204417) (xy 307.801942 -413.219777)
			(xy 307.747997 -413.227539) (xy 307.720746 -413.228028) (xy 306.857146 -413.228028) (xy 306.829892 -413.227528)
			(xy 306.775939 -413.219777) (xy 306.723639 -413.204425) (xy 306.674055 -413.181787) (xy 306.628199 -413.152321)
			(xy 306.587003 -413.11663) (xy 306.551306 -413.075438) (xy 306.521835 -413.029585) (xy 306.499191 -412.980004)
			(xy 306.483833 -412.927706) (xy 306.476075 -412.873754) (xy 305.038542 -412.873754) (xy 305.030785 -412.927702)
			(xy 305.01543 -412.979999) (xy 304.992788 -413.029579) (xy 304.963321 -413.075431) (xy 304.927628 -413.116624)
			(xy 304.886436 -413.152317) (xy 304.840584 -413.181785) (xy 304.791005 -413.204428) (xy 304.738708 -413.219784)
			(xy 304.684758 -413.227542) (xy 304.657506 -413.228028) (xy 303.793906 -413.228028) (xy 303.766654 -413.227525)
			(xy 303.712706 -413.219769) (xy 303.66041 -413.204415) (xy 303.610831 -413.181774) (xy 303.56498 -413.152307)
			(xy 303.523789 -413.116616) (xy 303.488096 -413.075425) (xy 303.458629 -413.029574) (xy 303.435988 -412.979996)
			(xy 303.420632 -412.9277) (xy 303.412875 -412.873752) (xy 301.87467 -412.873752) (xy 301.882114 -412.988908)
			(xy 301.886112 -413.1747) (xy 301.884113 -413.267605) (xy 422.67809 -413.267605) (xy 422.67809 -413.081771)
			(xy 422.686085 -412.896108) (xy 422.70206 -412.710962) (xy 422.725986 -412.526674) (xy 422.757818 -412.343586)
			(xy 422.797498 -412.162037) (xy 422.844951 -411.982363) (xy 422.900091 -411.804897) (xy 422.962814 -411.629968)
			(xy 423.033005 -411.457899) (xy 423.110534 -411.28901) (xy 423.195257 -411.123612) (xy 423.287018 -410.962012)
			(xy 423.385646 -410.80451) (xy 423.490959 -410.651396) (xy 423.602761 -410.502956) (xy 423.720846 -410.359462)
			(xy 423.844996 -410.221182) (xy 423.974979 -410.088371) (xy 424.110556 -409.961275) (xy 424.251476 -409.84013)
			(xy 424.397476 -409.725159) (xy 424.548288 -409.616576) (xy 424.703632 -409.514583) (xy 424.86322 -409.419366)
			(xy 425.026757 -409.331104) (xy 425.193939 -409.249959) (xy 425.364458 -409.176082) (xy 425.537997 -409.109609)
			(xy 425.714236 -409.050664) (xy 425.892847 -408.999356) (xy 426.0735 -408.955779) (xy 426.255861 -408.920015)
			(xy 426.439591 -408.892129) (xy 426.624351 -408.872174) (xy 426.809798 -408.860186) (xy 426.99559 -408.856188)
			(xy 427.181382 -408.860186) (xy 427.366829 -408.872174) (xy 427.551589 -408.892129) (xy 427.735319 -408.920015)
			(xy 427.91768 -408.955779) (xy 428.098333 -408.999356) (xy 428.276944 -409.050664) (xy 428.453183 -409.109609)
			(xy 428.626722 -409.176082) (xy 428.797241 -409.249959) (xy 428.964423 -409.331104) (xy 429.12796 -409.419366)
			(xy 429.287548 -409.514583) (xy 429.442892 -409.616576) (xy 429.593704 -409.725159) (xy 429.739704 -409.84013)
			(xy 429.880624 -409.961275) (xy 430.016201 -410.088371) (xy 430.146184 -410.221182) (xy 430.270334 -410.359462)
			(xy 430.388419 -410.502956) (xy 430.500221 -410.651396) (xy 430.605534 -410.80451) (xy 430.704162 -410.962012)
			(xy 430.795923 -411.123612) (xy 430.880646 -411.28901) (xy 430.958175 -411.457899) (xy 431.028366 -411.629968)
			(xy 431.091089 -411.804897) (xy 431.146229 -411.982363) (xy 431.193682 -412.162037) (xy 431.233362 -412.343586)
			(xy 431.265194 -412.526674) (xy 431.28912 -412.710962) (xy 431.305095 -412.896108) (xy 431.31309 -413.081771)
			(xy 431.31359 -413.174688) (xy 431.31309 -413.267605) (xy 431.305095 -413.453268) (xy 431.28912 -413.638414)
			(xy 431.265194 -413.822702) (xy 431.233362 -414.00579) (xy 431.193682 -414.187339) (xy 431.146229 -414.367013)
			(xy 431.091089 -414.544479) (xy 431.028366 -414.719408) (xy 430.958175 -414.891477) (xy 430.880646 -415.060366)
			(xy 430.795923 -415.225764) (xy 430.704162 -415.387364) (xy 430.605534 -415.544866) (xy 430.500221 -415.69798)
			(xy 430.388419 -415.84642) (xy 430.270334 -415.989914) (xy 430.146184 -416.128194) (xy 430.016201 -416.261005)
			(xy 429.880624 -416.388101) (xy 429.739704 -416.509246) (xy 429.593704 -416.624217) (xy 429.442892 -416.7328)
			(xy 429.287548 -416.834793) (xy 429.12796 -416.93001) (xy 428.964423 -417.018272) (xy 428.797241 -417.099417)
			(xy 428.626722 -417.173294) (xy 428.453183 -417.239767) (xy 428.276944 -417.298712) (xy 428.098333 -417.35002)
			(xy 427.91768 -417.393597) (xy 427.735319 -417.429361) (xy 427.551589 -417.457247) (xy 427.366829 -417.477202)
			(xy 427.181382 -417.48919) (xy 426.99559 -417.493188) (xy 426.809798 -417.48919) (xy 426.624351 -417.477202)
			(xy 426.439591 -417.457247) (xy 426.255861 -417.429361) (xy 426.0735 -417.393597) (xy 425.892847 -417.35002)
			(xy 425.714236 -417.298712) (xy 425.537997 -417.239767) (xy 425.364458 -417.173294) (xy 425.193939 -417.099417)
			(xy 425.026757 -417.018272) (xy 424.86322 -416.93001) (xy 424.703632 -416.834793) (xy 424.548288 -416.7328)
			(xy 424.397476 -416.624217) (xy 424.251476 -416.509246) (xy 424.110556 -416.388101) (xy 423.974979 -416.261005)
			(xy 423.844996 -416.128194) (xy 423.720846 -415.989914) (xy 423.602761 -415.84642) (xy 423.490959 -415.69798)
			(xy 423.385646 -415.544866) (xy 423.287018 -415.387364) (xy 423.195257 -415.225764) (xy 423.110534 -415.060366)
			(xy 423.033005 -414.891477) (xy 422.962814 -414.719408) (xy 422.900091 -414.544479) (xy 422.844951 -414.367013)
			(xy 422.797498 -414.187339) (xy 422.757818 -414.00579) (xy 422.725986 -413.822702) (xy 422.70206 -413.638414)
			(xy 422.686085 -413.453268) (xy 422.67809 -413.267605) (xy 301.884113 -413.267605) (xy 301.882114 -413.360492)
			(xy 301.870126 -413.54594) (xy 301.85017 -413.7307) (xy 301.822285 -413.914431) (xy 301.786521 -414.096792)
			(xy 301.742944 -414.277446) (xy 301.691636 -414.456057) (xy 301.63269 -414.632296) (xy 301.566218 -414.805835)
			(xy 301.49234 -414.976355) (xy 301.411195 -415.143537) (xy 301.322933 -415.307074) (xy 301.259284 -415.413753)
			(xy 304.944475 -415.413753) (xy 304.944475 -415.359247) (xy 304.952233 -415.305297) (xy 304.967589 -415.253)
			(xy 304.990232 -415.203421) (xy 305.019701 -415.157569) (xy 305.055396 -415.116377) (xy 305.096589 -415.080686)
			(xy 305.142443 -415.05122) (xy 305.192024 -415.02858) (xy 305.244322 -415.013227) (xy 305.298273 -415.005474)
			(xy 305.325526 -415.005012) (xy 306.189126 -415.005012) (xy 306.216377 -415.00546) (xy 306.270325 -415.01322)
			(xy 306.32262 -415.028578) (xy 306.372196 -415.051222) (xy 306.418046 -415.08069) (xy 306.459235 -415.116383)
			(xy 306.494926 -415.157575) (xy 306.524391 -415.203427) (xy 306.547031 -415.253005) (xy 306.562386 -415.3053)
			(xy 306.570142 -415.359249) (xy 306.570142 -415.413748) (xy 308.007798 -415.413748) (xy 308.007798 -415.359252)
			(xy 308.015553 -415.30531) (xy 308.030906 -415.253021) (xy 308.053543 -415.203448) (xy 308.083005 -415.157602)
			(xy 308.118691 -415.116415) (xy 308.159875 -415.080725) (xy 308.205718 -415.05126) (xy 308.255289 -415.028618)
			(xy 308.307577 -415.013261) (xy 308.361518 -415.005501) (xy 308.388766 -415.005012) (xy 309.252366 -415.005012)
			(xy 309.279622 -415.005433) (xy 309.333579 -415.013186) (xy 309.385884 -415.02854) (xy 309.435471 -415.051182)
			(xy 309.481331 -415.08065) (xy 309.52253 -415.116346) (xy 309.558229 -415.157542) (xy 309.587702 -415.203399)
			(xy 309.610348 -415.252984) (xy 309.625707 -415.305287) (xy 309.633465 -415.359244) (xy 309.633465 -415.413752)
			(xy 311.070975 -415.413752) (xy 311.070975 -415.359248) (xy 311.078732 -415.3053) (xy 311.094088 -415.253004)
			(xy 311.116729 -415.203426) (xy 311.146196 -415.157575) (xy 311.181889 -415.116384) (xy 311.22308 -415.080693)
			(xy 311.268931 -415.051226) (xy 311.31851 -415.028585) (xy 311.370806 -415.013231) (xy 311.424754 -415.005475)
			(xy 311.452006 -415.005012) (xy 312.315606 -415.005012) (xy 312.342858 -415.005458) (xy 312.396808 -415.013216)
			(xy 312.449105 -415.028572) (xy 312.498684 -415.051215) (xy 312.544536 -415.080683) (xy 312.585728 -415.116376)
			(xy 312.621421 -415.157569) (xy 312.650888 -415.203421) (xy 312.67353 -415.253001) (xy 312.688885 -415.305298)
			(xy 312.696642 -415.359248) (xy 312.696642 -415.413752) (xy 312.696642 -415.413754) (xy 314.134175 -415.413754)
			(xy 314.134175 -415.359246) (xy 314.141933 -415.305294) (xy 314.157291 -415.252996) (xy 314.179935 -415.203415)
			(xy 314.209406 -415.157562) (xy 314.245103 -415.11637) (xy 314.286299 -415.080679) (xy 314.332155 -415.051213)
			(xy 314.381739 -415.028575) (xy 314.434039 -415.013223) (xy 314.487992 -415.005472) (xy 314.515246 -415.005012)
			(xy 315.378846 -415.005012) (xy 315.406097 -415.005461) (xy 315.460042 -415.013223) (xy 315.512334 -415.028583)
			(xy 315.561908 -415.051228) (xy 315.607755 -415.080697) (xy 315.648942 -415.116391) (xy 315.68463 -415.157582)
			(xy 315.714094 -415.203432) (xy 315.736733 -415.253009) (xy 315.752087 -415.305303) (xy 315.759842 -415.359249)
			(xy 315.759842 -415.413749) (xy 317.197498 -415.413749) (xy 317.197498 -415.359251) (xy 317.205254 -415.305307)
			(xy 317.220608 -415.253016) (xy 317.243246 -415.203443) (xy 317.27271 -415.157596) (xy 317.308398 -415.116408)
			(xy 317.349584 -415.080718) (xy 317.39543 -415.051253) (xy 317.445003 -415.028612) (xy 317.497294 -415.013257)
			(xy 317.551237 -415.005499) (xy 317.578486 -415.005012) (xy 318.442086 -415.005012) (xy 318.469341 -415.005434)
			(xy 318.523296 -415.01319) (xy 318.575599 -415.028545) (xy 318.625183 -415.051188) (xy 318.671041 -415.080657)
			(xy 318.712237 -415.116353) (xy 318.747934 -415.157548) (xy 318.777405 -415.203405) (xy 318.80005 -415.252988)
			(xy 318.815407 -415.30529) (xy 318.823165 -415.359245) (xy 318.823165 -415.413753) (xy 320.260675 -415.413753)
			(xy 320.260675 -415.359247) (xy 320.268433 -415.305297) (xy 320.283789 -415.253) (xy 320.306432 -415.203421)
			(xy 320.335901 -415.157569) (xy 320.371596 -415.116377) (xy 320.412789 -415.080686) (xy 320.458643 -415.05122)
			(xy 320.508224 -415.02858) (xy 320.560522 -415.013227) (xy 320.614473 -415.005474) (xy 320.641726 -415.005012)
			(xy 321.505326 -415.005012) (xy 321.532577 -415.00546) (xy 321.586525 -415.01322) (xy 321.63882 -415.028578)
			(xy 321.688396 -415.051222) (xy 321.734246 -415.08069) (xy 321.775435 -415.116383) (xy 321.811126 -415.157575)
			(xy 321.840591 -415.203427) (xy 321.863231 -415.253005) (xy 321.878586 -415.3053) (xy 321.886342 -415.359249)
			(xy 321.886342 -415.413748) (xy 323.323998 -415.413748) (xy 323.323998 -415.359252) (xy 323.331753 -415.30531)
			(xy 323.347106 -415.253021) (xy 323.369743 -415.203448) (xy 323.399205 -415.157602) (xy 323.434891 -415.116415)
			(xy 323.476075 -415.080725) (xy 323.521918 -415.05126) (xy 323.571489 -415.028618) (xy 323.623777 -415.013261)
			(xy 323.677718 -415.005501) (xy 323.704966 -415.005012) (xy 324.568566 -415.005012) (xy 324.595822 -415.005433)
			(xy 324.649779 -415.013186) (xy 324.702084 -415.02854) (xy 324.751671 -415.051182) (xy 324.797531 -415.08065)
			(xy 324.83873 -415.116346) (xy 324.874429 -415.157542) (xy 324.903902 -415.203399) (xy 324.926548 -415.252984)
			(xy 324.941907 -415.305287) (xy 324.949665 -415.359244) (xy 324.949665 -415.413752) (xy 326.387175 -415.413752)
			(xy 326.387175 -415.359248) (xy 326.394932 -415.3053) (xy 326.410288 -415.253004) (xy 326.432929 -415.203426)
			(xy 326.462396 -415.157575) (xy 326.498089 -415.116384) (xy 326.53928 -415.080693) (xy 326.585131 -415.051226)
			(xy 326.63471 -415.028585) (xy 326.687006 -415.013231) (xy 326.740954 -415.005475) (xy 326.768206 -415.005012)
			(xy 327.631806 -415.005012) (xy 327.659058 -415.005458) (xy 327.713008 -415.013216) (xy 327.765305 -415.028572)
			(xy 327.814884 -415.051215) (xy 327.860736 -415.080683) (xy 327.901928 -415.116376) (xy 327.937621 -415.157569)
			(xy 327.967088 -415.203421) (xy 327.98973 -415.253001) (xy 328.005085 -415.305298) (xy 328.012842 -415.359248)
			(xy 328.012842 -415.413752) (xy 328.012842 -415.413754) (xy 329.450375 -415.413754) (xy 329.450375 -415.359246)
			(xy 329.458133 -415.305294) (xy 329.473491 -415.252996) (xy 329.496135 -415.203415) (xy 329.525606 -415.157562)
			(xy 329.561303 -415.11637) (xy 329.602499 -415.080679) (xy 329.648355 -415.051213) (xy 329.697939 -415.028575)
			(xy 329.750239 -415.013223) (xy 329.804192 -415.005472) (xy 329.831446 -415.005012) (xy 330.695046 -415.005012)
			(xy 330.722297 -415.005461) (xy 330.776242 -415.013223) (xy 330.828534 -415.028583) (xy 330.878108 -415.051228)
			(xy 330.923955 -415.080697) (xy 330.965142 -415.116391) (xy 331.00083 -415.157582) (xy 331.030294 -415.203432)
			(xy 331.052933 -415.253009) (xy 331.068287 -415.305303) (xy 331.076042 -415.359249) (xy 331.076042 -415.413749)
			(xy 332.513698 -415.413749) (xy 332.513698 -415.359251) (xy 332.521454 -415.305307) (xy 332.536808 -415.253016)
			(xy 332.559446 -415.203443) (xy 332.58891 -415.157596) (xy 332.624598 -415.116408) (xy 332.665784 -415.080718)
			(xy 332.71163 -415.051253) (xy 332.761203 -415.028612) (xy 332.813494 -415.013257) (xy 332.867437 -415.005499)
			(xy 332.894686 -415.005012) (xy 333.758286 -415.005012) (xy 333.785541 -415.005434) (xy 333.839496 -415.01319)
			(xy 333.891799 -415.028545) (xy 333.941383 -415.051188) (xy 333.987241 -415.080657) (xy 334.028437 -415.116353)
			(xy 334.064134 -415.157548) (xy 334.093605 -415.203405) (xy 334.11625 -415.252988) (xy 334.131607 -415.30529)
			(xy 334.139365 -415.359245) (xy 334.139365 -415.413753) (xy 335.576875 -415.413753) (xy 335.576875 -415.359247)
			(xy 335.584633 -415.305297) (xy 335.599989 -415.253) (xy 335.622632 -415.203421) (xy 335.652101 -415.157569)
			(xy 335.687796 -415.116377) (xy 335.728989 -415.080686) (xy 335.774843 -415.05122) (xy 335.824424 -415.02858)
			(xy 335.876722 -415.013227) (xy 335.930673 -415.005474) (xy 335.957926 -415.005012) (xy 336.821526 -415.005012)
			(xy 336.848777 -415.00546) (xy 336.902725 -415.01322) (xy 336.95502 -415.028578) (xy 337.004596 -415.051222)
			(xy 337.050446 -415.08069) (xy 337.091635 -415.116383) (xy 337.127326 -415.157575) (xy 337.156791 -415.203427)
			(xy 337.179431 -415.253005) (xy 337.194786 -415.3053) (xy 337.202542 -415.359249) (xy 337.202542 -415.413748)
			(xy 338.640198 -415.413748) (xy 338.640198 -415.359252) (xy 338.647953 -415.30531) (xy 338.663306 -415.253021)
			(xy 338.685943 -415.203448) (xy 338.715405 -415.157602) (xy 338.751091 -415.116415) (xy 338.792275 -415.080725)
			(xy 338.838118 -415.05126) (xy 338.887689 -415.028618) (xy 338.939977 -415.013261) (xy 338.993918 -415.005501)
			(xy 339.021166 -415.005012) (xy 339.884766 -415.005012) (xy 339.912022 -415.005433) (xy 339.965979 -415.013186)
			(xy 340.018284 -415.02854) (xy 340.067871 -415.051182) (xy 340.113731 -415.08065) (xy 340.15493 -415.116346)
			(xy 340.190629 -415.157542) (xy 340.220102 -415.203399) (xy 340.242748 -415.252984) (xy 340.258107 -415.305287)
			(xy 340.265865 -415.359244) (xy 340.265865 -415.413752) (xy 341.703375 -415.413752) (xy 341.703375 -415.359248)
			(xy 341.711132 -415.3053) (xy 341.726488 -415.253004) (xy 341.749129 -415.203426) (xy 341.778596 -415.157575)
			(xy 341.814289 -415.116384) (xy 341.85548 -415.080693) (xy 341.901331 -415.051226) (xy 341.95091 -415.028585)
			(xy 342.003206 -415.013231) (xy 342.057154 -415.005475) (xy 342.084406 -415.005012) (xy 342.948006 -415.005012)
			(xy 342.975258 -415.005458) (xy 343.029208 -415.013216) (xy 343.081505 -415.028572) (xy 343.131084 -415.051215)
			(xy 343.176936 -415.080683) (xy 343.218128 -415.116376) (xy 343.253821 -415.157569) (xy 343.283288 -415.203421)
			(xy 343.30593 -415.253001) (xy 343.321285 -415.305298) (xy 343.329042 -415.359248) (xy 343.329042 -415.413752)
			(xy 343.329042 -415.413754) (xy 344.766575 -415.413754) (xy 344.766575 -415.359246) (xy 344.774333 -415.305294)
			(xy 344.789691 -415.252996) (xy 344.812335 -415.203415) (xy 344.841806 -415.157562) (xy 344.877503 -415.11637)
			(xy 344.918699 -415.080679) (xy 344.964555 -415.051213) (xy 345.014139 -415.028575) (xy 345.066439 -415.013223)
			(xy 345.120392 -415.005472) (xy 345.147646 -415.005012) (xy 346.011246 -415.005012) (xy 346.038497 -415.005461)
			(xy 346.092442 -415.013223) (xy 346.144734 -415.028583) (xy 346.194308 -415.051228) (xy 346.240155 -415.080697)
			(xy 346.281342 -415.116391) (xy 346.31703 -415.157582) (xy 346.346494 -415.203432) (xy 346.369133 -415.253009)
			(xy 346.384487 -415.305303) (xy 346.392242 -415.359249) (xy 346.392242 -415.413749) (xy 347.829898 -415.413749)
			(xy 347.829898 -415.359251) (xy 347.837654 -415.305307) (xy 347.853008 -415.253016) (xy 347.875646 -415.203443)
			(xy 347.90511 -415.157596) (xy 347.940798 -415.116408) (xy 347.981984 -415.080718) (xy 348.02783 -415.051253)
			(xy 348.077403 -415.028612) (xy 348.129694 -415.013257) (xy 348.183637 -415.005499) (xy 348.210886 -415.005012)
			(xy 349.074486 -415.005012) (xy 349.101741 -415.005434) (xy 349.155696 -415.01319) (xy 349.207999 -415.028545)
			(xy 349.257583 -415.051188) (xy 349.303441 -415.080657) (xy 349.344637 -415.116353) (xy 349.380334 -415.157548)
			(xy 349.409805 -415.203405) (xy 349.43245 -415.252988) (xy 349.447807 -415.30529) (xy 349.455565 -415.359245)
			(xy 349.455565 -415.413753) (xy 350.893075 -415.413753) (xy 350.893075 -415.359247) (xy 350.900833 -415.305297)
			(xy 350.916189 -415.253) (xy 350.938832 -415.203421) (xy 350.968301 -415.157569) (xy 351.003996 -415.116377)
			(xy 351.045189 -415.080686) (xy 351.091043 -415.05122) (xy 351.140624 -415.02858) (xy 351.192922 -415.013227)
			(xy 351.246873 -415.005474) (xy 351.274126 -415.005012) (xy 352.137726 -415.005012) (xy 352.164977 -415.00546)
			(xy 352.218925 -415.01322) (xy 352.27122 -415.028578) (xy 352.320796 -415.051222) (xy 352.366646 -415.08069)
			(xy 352.407835 -415.116383) (xy 352.443526 -415.157575) (xy 352.472991 -415.203427) (xy 352.495631 -415.253005)
			(xy 352.510986 -415.3053) (xy 352.518742 -415.359249) (xy 352.518742 -415.413751) (xy 352.518742 -415.413752)
			(xy 372.044675 -415.413752) (xy 372.044675 -415.359248) (xy 372.052432 -415.305298) (xy 372.067789 -415.253001)
			(xy 372.090432 -415.203422) (xy 372.1199 -415.15757) (xy 372.155594 -415.116379) (xy 372.196788 -415.080687)
			(xy 372.242641 -415.051221) (xy 372.292221 -415.028581) (xy 372.344519 -415.013228) (xy 372.39847 -415.005474)
			(xy 372.425722 -415.005012) (xy 373.289322 -415.005012) (xy 373.316574 -415.005459) (xy 373.370522 -415.013219)
			(xy 373.422817 -415.028577) (xy 373.472394 -415.05122) (xy 373.518244 -415.080689) (xy 373.559434 -415.116382)
			(xy 373.595125 -415.157574) (xy 373.62459 -415.203426) (xy 373.647231 -415.253004) (xy 373.662586 -415.3053)
			(xy 373.670342 -415.359248) (xy 373.670342 -415.413748) (xy 375.107998 -415.413748) (xy 375.107998 -415.359252)
			(xy 375.115753 -415.30531) (xy 375.131106 -415.253022) (xy 375.153743 -415.203449) (xy 375.183204 -415.157603)
			(xy 375.218889 -415.116416) (xy 375.260073 -415.080727) (xy 375.305916 -415.051261) (xy 375.355486 -415.028619)
			(xy 375.407773 -415.013261) (xy 375.461714 -415.005501) (xy 375.488962 -415.005012) (xy 376.352562 -415.005012)
			(xy 376.379818 -415.005432) (xy 376.433776 -415.013185) (xy 376.486081 -415.028539) (xy 376.535669 -415.05118)
			(xy 376.581529 -415.080649) (xy 376.622729 -415.116345) (xy 376.658428 -415.15754) (xy 376.687901 -415.203398)
			(xy 376.710548 -415.252983) (xy 376.725907 -415.305287) (xy 376.733665 -415.359244) (xy 376.733665 -415.413752)
			(xy 378.171175 -415.413752) (xy 378.171175 -415.359248) (xy 378.178932 -415.3053) (xy 378.194287 -415.253005)
			(xy 378.216929 -415.203427) (xy 378.246395 -415.157576) (xy 378.282087 -415.116386) (xy 378.323278 -415.080694)
			(xy 378.369129 -415.051228) (xy 378.418707 -415.028587) (xy 378.471002 -415.013231) (xy 378.52495 -415.005475)
			(xy 378.552202 -415.005012) (xy 379.415802 -415.005012) (xy 379.443055 -415.005458) (xy 379.497005 -415.013215)
			(xy 379.549302 -415.028571) (xy 379.598882 -415.051214) (xy 379.644734 -415.080682) (xy 379.685926 -415.116375)
			(xy 379.72162 -415.157567) (xy 379.751087 -415.20342) (xy 379.773729 -415.253) (xy 379.789085 -415.305297)
			(xy 379.796842 -415.359247) (xy 379.796842 -415.413753) (xy 381.234375 -415.413753) (xy 381.234375 -415.359247)
			(xy 381.242133 -415.305295) (xy 381.25749 -415.252996) (xy 381.280135 -415.203416) (xy 381.309605 -415.157563)
			(xy 381.345301 -415.116372) (xy 381.386497 -415.08068) (xy 381.432353 -415.051215) (xy 381.481936 -415.028576)
			(xy 381.534236 -415.013224) (xy 381.588189 -415.005472) (xy 381.615442 -415.005012) (xy 382.479042 -415.005012)
			(xy 382.506293 -415.005461) (xy 382.560239 -415.013222) (xy 382.612531 -415.028582) (xy 382.662106 -415.051227)
			(xy 382.707953 -415.080696) (xy 382.749141 -415.116389) (xy 382.784829 -415.15758) (xy 382.814293 -415.203431)
			(xy 382.836933 -415.253008) (xy 382.852286 -415.305302) (xy 382.860042 -415.359249) (xy 382.860042 -415.413749)
			(xy 384.297698 -415.413749) (xy 384.297698 -415.359251) (xy 384.305454 -415.305308) (xy 384.320807 -415.253017)
			(xy 384.343446 -415.203444) (xy 384.372909 -415.157597) (xy 384.408597 -415.116409) (xy 384.449782 -415.08072)
			(xy 384.495628 -415.051254) (xy 384.5452 -415.028613) (xy 384.59749 -415.013258) (xy 384.651433 -415.005499)
			(xy 384.678682 -415.005012) (xy 385.542282 -415.005012) (xy 385.569537 -415.005434) (xy 385.623493 -415.013189)
			(xy 385.675796 -415.028544) (xy 385.725381 -415.051187) (xy 385.771239 -415.080656) (xy 385.812436 -415.116352)
			(xy 385.848133 -415.157547) (xy 385.877604 -415.203403) (xy 385.900249 -415.252987) (xy 385.915607 -415.305289)
			(xy 385.923365 -415.359245) (xy 385.923365 -415.413752) (xy 387.360875 -415.413752) (xy 387.360875 -415.359248)
			(xy 387.368632 -415.305298) (xy 387.383989 -415.253001) (xy 387.406632 -415.203422) (xy 387.4361 -415.15757)
			(xy 387.471794 -415.116379) (xy 387.512988 -415.080687) (xy 387.558841 -415.051221) (xy 387.608421 -415.028581)
			(xy 387.660719 -415.013228) (xy 387.71467 -415.005474) (xy 387.741922 -415.005012) (xy 388.605522 -415.005012)
			(xy 388.632774 -415.005459) (xy 388.686722 -415.013219) (xy 388.739017 -415.028577) (xy 388.788594 -415.05122)
			(xy 388.834444 -415.080689) (xy 388.875634 -415.116382) (xy 388.911325 -415.157574) (xy 388.94079 -415.203426)
			(xy 388.963431 -415.253004) (xy 388.978786 -415.3053) (xy 388.986542 -415.359248) (xy 388.986542 -415.413748)
			(xy 390.424198 -415.413748) (xy 390.424198 -415.359252) (xy 390.431953 -415.30531) (xy 390.447306 -415.253022)
			(xy 390.469943 -415.203449) (xy 390.499404 -415.157603) (xy 390.535089 -415.116416) (xy 390.576273 -415.080727)
			(xy 390.622116 -415.051261) (xy 390.671686 -415.028619) (xy 390.723973 -415.013261) (xy 390.777914 -415.005501)
			(xy 390.805162 -415.005012) (xy 391.668762 -415.005012) (xy 391.696018 -415.005432) (xy 391.749976 -415.013185)
			(xy 391.802281 -415.028539) (xy 391.851869 -415.05118) (xy 391.897729 -415.080649) (xy 391.938929 -415.116345)
			(xy 391.974628 -415.15754) (xy 392.004101 -415.203398) (xy 392.026748 -415.252983) (xy 392.042107 -415.305287)
			(xy 392.049865 -415.359244) (xy 392.049865 -415.413752) (xy 393.487375 -415.413752) (xy 393.487375 -415.359248)
			(xy 393.495132 -415.3053) (xy 393.510487 -415.253005) (xy 393.533129 -415.203427) (xy 393.562595 -415.157576)
			(xy 393.598287 -415.116386) (xy 393.639478 -415.080694) (xy 393.685329 -415.051228) (xy 393.734907 -415.028587)
			(xy 393.787202 -415.013231) (xy 393.84115 -415.005475) (xy 393.868402 -415.005012) (xy 394.732002 -415.005012)
			(xy 394.759255 -415.005458) (xy 394.813205 -415.013215) (xy 394.865502 -415.028571) (xy 394.915082 -415.051214)
			(xy 394.960934 -415.080682) (xy 395.002126 -415.116375) (xy 395.03782 -415.157567) (xy 395.067287 -415.20342)
			(xy 395.089929 -415.253) (xy 395.105285 -415.305297) (xy 395.113042 -415.359247) (xy 395.113042 -415.413753)
			(xy 396.550575 -415.413753) (xy 396.550575 -415.359247) (xy 396.558333 -415.305295) (xy 396.57369 -415.252996)
			(xy 396.596335 -415.203416) (xy 396.625805 -415.157563) (xy 396.661501 -415.116372) (xy 396.702697 -415.08068)
			(xy 396.748553 -415.051215) (xy 396.798136 -415.028576) (xy 396.850436 -415.013224) (xy 396.904389 -415.005472)
			(xy 396.931642 -415.005012) (xy 397.795242 -415.005012) (xy 397.822493 -415.005461) (xy 397.876439 -415.013222)
			(xy 397.928731 -415.028582) (xy 397.978306 -415.051227) (xy 398.024153 -415.080696) (xy 398.065341 -415.116389)
			(xy 398.101029 -415.15758) (xy 398.130493 -415.203431) (xy 398.153133 -415.253008) (xy 398.168486 -415.305302)
			(xy 398.176242 -415.359249) (xy 398.176242 -415.413749) (xy 399.613898 -415.413749) (xy 399.613898 -415.359251)
			(xy 399.621654 -415.305308) (xy 399.637007 -415.253017) (xy 399.659646 -415.203444) (xy 399.689109 -415.157597)
			(xy 399.724797 -415.116409) (xy 399.765982 -415.08072) (xy 399.811828 -415.051254) (xy 399.8614 -415.028613)
			(xy 399.91369 -415.013258) (xy 399.967633 -415.005499) (xy 399.994882 -415.005012) (xy 400.858482 -415.005012)
			(xy 400.885737 -415.005434) (xy 400.939693 -415.013189) (xy 400.991996 -415.028544) (xy 401.041581 -415.051187)
			(xy 401.087439 -415.080656) (xy 401.128636 -415.116352) (xy 401.164333 -415.157547) (xy 401.193804 -415.203403)
			(xy 401.216449 -415.252987) (xy 401.231807 -415.305289) (xy 401.239565 -415.359245) (xy 401.239565 -415.413752)
			(xy 402.677075 -415.413752) (xy 402.677075 -415.359248) (xy 402.684832 -415.305298) (xy 402.700189 -415.253001)
			(xy 402.722832 -415.203422) (xy 402.7523 -415.15757) (xy 402.787994 -415.116379) (xy 402.829188 -415.080687)
			(xy 402.875041 -415.051221) (xy 402.924621 -415.028581) (xy 402.976919 -415.013228) (xy 403.03087 -415.005474)
			(xy 403.058122 -415.005012) (xy 403.921722 -415.005012) (xy 403.948974 -415.005459) (xy 404.002922 -415.013219)
			(xy 404.055217 -415.028577) (xy 404.104794 -415.05122) (xy 404.150644 -415.080689) (xy 404.191834 -415.116382)
			(xy 404.227525 -415.157574) (xy 404.25699 -415.203426) (xy 404.279631 -415.253004) (xy 404.294986 -415.3053)
			(xy 404.302742 -415.359248) (xy 404.302742 -415.413748) (xy 405.740398 -415.413748) (xy 405.740398 -415.359252)
			(xy 405.748153 -415.30531) (xy 405.763506 -415.253022) (xy 405.786143 -415.203449) (xy 405.815604 -415.157603)
			(xy 405.851289 -415.116416) (xy 405.892473 -415.080727) (xy 405.938316 -415.051261) (xy 405.987886 -415.028619)
			(xy 406.040173 -415.013261) (xy 406.094114 -415.005501) (xy 406.121362 -415.005012) (xy 406.984962 -415.005012)
			(xy 407.012218 -415.005432) (xy 407.066176 -415.013185) (xy 407.118481 -415.028539) (xy 407.168069 -415.05118)
			(xy 407.213929 -415.080649) (xy 407.255129 -415.116345) (xy 407.290828 -415.15754) (xy 407.320301 -415.203398)
			(xy 407.342948 -415.252983) (xy 407.358307 -415.305287) (xy 407.366065 -415.359244) (xy 407.366065 -415.413752)
			(xy 408.803575 -415.413752) (xy 408.803575 -415.359248) (xy 408.811332 -415.3053) (xy 408.826687 -415.253005)
			(xy 408.849329 -415.203427) (xy 408.878795 -415.157576) (xy 408.914487 -415.116386) (xy 408.955678 -415.080694)
			(xy 409.001529 -415.051228) (xy 409.051107 -415.028587) (xy 409.103402 -415.013231) (xy 409.15735 -415.005475)
			(xy 409.184602 -415.005012) (xy 410.048202 -415.005012) (xy 410.075455 -415.005458) (xy 410.129405 -415.013215)
			(xy 410.181702 -415.028571) (xy 410.231282 -415.051214) (xy 410.277134 -415.080682) (xy 410.318326 -415.116375)
			(xy 410.35402 -415.157567) (xy 410.383487 -415.20342) (xy 410.406129 -415.253) (xy 410.421485 -415.305297)
			(xy 410.429242 -415.359247) (xy 410.429242 -415.413753) (xy 411.866775 -415.413753) (xy 411.866775 -415.359247)
			(xy 411.874533 -415.305295) (xy 411.88989 -415.252996) (xy 411.912535 -415.203416) (xy 411.942005 -415.157563)
			(xy 411.977701 -415.116372) (xy 412.018897 -415.08068) (xy 412.064753 -415.051215) (xy 412.114336 -415.028576)
			(xy 412.166636 -415.013224) (xy 412.220589 -415.005472) (xy 412.247842 -415.005012) (xy 413.111442 -415.005012)
			(xy 413.138693 -415.005461) (xy 413.192639 -415.013222) (xy 413.244931 -415.028582) (xy 413.294506 -415.051227)
			(xy 413.340353 -415.080696) (xy 413.381541 -415.116389) (xy 413.417229 -415.15758) (xy 413.446693 -415.203431)
			(xy 413.469333 -415.253008) (xy 413.484686 -415.305302) (xy 413.492442 -415.359249) (xy 413.492442 -415.413749)
			(xy 414.930098 -415.413749) (xy 414.930098 -415.359251) (xy 414.937854 -415.305308) (xy 414.953207 -415.253017)
			(xy 414.975846 -415.203444) (xy 415.005309 -415.157597) (xy 415.040997 -415.116409) (xy 415.082182 -415.08072)
			(xy 415.128028 -415.051254) (xy 415.1776 -415.028613) (xy 415.22989 -415.013258) (xy 415.283833 -415.005499)
			(xy 415.311082 -415.005012) (xy 416.174682 -415.005012) (xy 416.201937 -415.005434) (xy 416.255893 -415.013189)
			(xy 416.308196 -415.028544) (xy 416.357781 -415.051187) (xy 416.403639 -415.080656) (xy 416.444836 -415.116352)
			(xy 416.480533 -415.157547) (xy 416.510004 -415.203403) (xy 416.532649 -415.252987) (xy 416.548007 -415.305289)
			(xy 416.555765 -415.359245) (xy 416.555765 -415.413752) (xy 417.993275 -415.413752) (xy 417.993275 -415.359248)
			(xy 418.001032 -415.305298) (xy 418.016389 -415.253001) (xy 418.039032 -415.203422) (xy 418.0685 -415.15757)
			(xy 418.104194 -415.116379) (xy 418.145388 -415.080687) (xy 418.191241 -415.051221) (xy 418.240821 -415.028581)
			(xy 418.293119 -415.013228) (xy 418.34707 -415.005474) (xy 418.374322 -415.005012) (xy 419.237922 -415.005012)
			(xy 419.265174 -415.005459) (xy 419.319122 -415.013219) (xy 419.371417 -415.028577) (xy 419.420994 -415.05122)
			(xy 419.466844 -415.080689) (xy 419.508034 -415.116382) (xy 419.543725 -415.157574) (xy 419.57319 -415.203426)
			(xy 419.595831 -415.253004) (xy 419.611186 -415.3053) (xy 419.618942 -415.359248) (xy 419.618942 -415.413752)
			(xy 419.611186 -415.4677) (xy 419.595831 -415.519996) (xy 419.57319 -415.569574) (xy 419.543725 -415.615426)
			(xy 419.508034 -415.656618) (xy 419.466844 -415.692311) (xy 419.420994 -415.72178) (xy 419.371417 -415.744423)
			(xy 419.319122 -415.759781) (xy 419.265174 -415.767541) (xy 419.237922 -415.768028) (xy 418.374322 -415.768028)
			(xy 418.34707 -415.767526) (xy 418.293119 -415.759772) (xy 418.240821 -415.744419) (xy 418.191241 -415.721779)
			(xy 418.145388 -415.692313) (xy 418.104194 -415.656621) (xy 418.0685 -415.61543) (xy 418.039032 -415.569578)
			(xy 418.016389 -415.519999) (xy 418.001032 -415.467702) (xy 417.993275 -415.413752) (xy 416.555765 -415.413752)
			(xy 416.555765 -415.413755) (xy 416.548007 -415.467711) (xy 416.532649 -415.520013) (xy 416.510004 -415.569597)
			(xy 416.480533 -415.615453) (xy 416.444836 -415.656648) (xy 416.403639 -415.692344) (xy 416.357781 -415.721813)
			(xy 416.308196 -415.744456) (xy 416.255893 -415.759811) (xy 416.201937 -415.767566) (xy 416.174682 -415.768028)
			(xy 415.311082 -415.768028) (xy 415.283833 -415.767501) (xy 415.22989 -415.759742) (xy 415.1776 -415.744387)
			(xy 415.128028 -415.721746) (xy 415.082182 -415.69228) (xy 415.040997 -415.656591) (xy 415.005309 -415.615403)
			(xy 414.975846 -415.569556) (xy 414.953207 -415.519983) (xy 414.937854 -415.467692) (xy 414.930098 -415.413749)
			(xy 413.492442 -415.413749) (xy 413.492442 -415.413751) (xy 413.484686 -415.467698) (xy 413.469333 -415.519992)
			(xy 413.446693 -415.569569) (xy 413.417229 -415.61542) (xy 413.381541 -415.656611) (xy 413.340353 -415.692304)
			(xy 413.294506 -415.721773) (xy 413.244931 -415.744418) (xy 413.192639 -415.759778) (xy 413.138693 -415.767539)
			(xy 413.111442 -415.768028) (xy 412.247842 -415.768028) (xy 412.220589 -415.767528) (xy 412.166636 -415.759776)
			(xy 412.114336 -415.744424) (xy 412.064753 -415.721785) (xy 412.018897 -415.69232) (xy 411.977701 -415.656628)
			(xy 411.942005 -415.615437) (xy 411.912535 -415.569584) (xy 411.88989 -415.520004) (xy 411.874533 -415.467705)
			(xy 411.866775 -415.413753) (xy 410.429242 -415.413753) (xy 410.421485 -415.467703) (xy 410.406129 -415.52)
			(xy 410.383487 -415.56958) (xy 410.35402 -415.615433) (xy 410.318326 -415.656625) (xy 410.277134 -415.692318)
			(xy 410.231282 -415.721786) (xy 410.181702 -415.744429) (xy 410.129405 -415.759785) (xy 410.075455 -415.767542)
			(xy 410.048202 -415.768028) (xy 409.184602 -415.768028) (xy 409.15735 -415.767525) (xy 409.103402 -415.759769)
			(xy 409.051107 -415.744413) (xy 409.001529 -415.721772) (xy 408.955678 -415.692306) (xy 408.914487 -415.656614)
			(xy 408.878795 -415.615424) (xy 408.849329 -415.569573) (xy 408.826687 -415.519995) (xy 408.811332 -415.4677)
			(xy 408.803575 -415.413752) (xy 407.366065 -415.413752) (xy 407.366065 -415.413756) (xy 407.358307 -415.467713)
			(xy 407.342948 -415.520017) (xy 407.320301 -415.569602) (xy 407.290828 -415.61546) (xy 407.255129 -415.656655)
			(xy 407.213929 -415.692351) (xy 407.168069 -415.72182) (xy 407.118481 -415.744461) (xy 407.066176 -415.759815)
			(xy 407.012218 -415.767568) (xy 406.984962 -415.768028) (xy 406.121362 -415.768028) (xy 406.094114 -415.767499)
			(xy 406.040173 -415.759739) (xy 405.987886 -415.744381) (xy 405.938316 -415.721739) (xy 405.892473 -415.692273)
			(xy 405.851289 -415.656584) (xy 405.815604 -415.615397) (xy 405.786143 -415.569551) (xy 405.763506 -415.519978)
			(xy 405.748153 -415.46769) (xy 405.740398 -415.413748) (xy 404.302742 -415.413748) (xy 404.302742 -415.413752)
			(xy 404.294986 -415.4677) (xy 404.279631 -415.519996) (xy 404.25699 -415.569574) (xy 404.227525 -415.615426)
			(xy 404.191834 -415.656618) (xy 404.150644 -415.692311) (xy 404.104794 -415.72178) (xy 404.055217 -415.744423)
			(xy 404.002922 -415.759781) (xy 403.948974 -415.767541) (xy 403.921722 -415.768028) (xy 403.058122 -415.768028)
			(xy 403.03087 -415.767526) (xy 402.976919 -415.759772) (xy 402.924621 -415.744419) (xy 402.875041 -415.721779)
			(xy 402.829188 -415.692313) (xy 402.787994 -415.656621) (xy 402.7523 -415.61543) (xy 402.722832 -415.569578)
			(xy 402.700189 -415.519999) (xy 402.684832 -415.467702) (xy 402.677075 -415.413752) (xy 401.239565 -415.413752)
			(xy 401.239565 -415.413755) (xy 401.231807 -415.467711) (xy 401.216449 -415.520013) (xy 401.193804 -415.569597)
			(xy 401.164333 -415.615453) (xy 401.128636 -415.656648) (xy 401.087439 -415.692344) (xy 401.041581 -415.721813)
			(xy 400.991996 -415.744456) (xy 400.939693 -415.759811) (xy 400.885737 -415.767566) (xy 400.858482 -415.768028)
			(xy 399.994882 -415.768028) (xy 399.967633 -415.767501) (xy 399.91369 -415.759742) (xy 399.8614 -415.744387)
			(xy 399.811828 -415.721746) (xy 399.765982 -415.69228) (xy 399.724797 -415.656591) (xy 399.689109 -415.615403)
			(xy 399.659646 -415.569556) (xy 399.637007 -415.519983) (xy 399.621654 -415.467692) (xy 399.613898 -415.413749)
			(xy 398.176242 -415.413749) (xy 398.176242 -415.413751) (xy 398.168486 -415.467698) (xy 398.153133 -415.519992)
			(xy 398.130493 -415.569569) (xy 398.101029 -415.61542) (xy 398.065341 -415.656611) (xy 398.024153 -415.692304)
			(xy 397.978306 -415.721773) (xy 397.928731 -415.744418) (xy 397.876439 -415.759778) (xy 397.822493 -415.767539)
			(xy 397.795242 -415.768028) (xy 396.931642 -415.768028) (xy 396.904389 -415.767528) (xy 396.850436 -415.759776)
			(xy 396.798136 -415.744424) (xy 396.748553 -415.721785) (xy 396.702697 -415.69232) (xy 396.661501 -415.656628)
			(xy 396.625805 -415.615437) (xy 396.596335 -415.569584) (xy 396.57369 -415.520004) (xy 396.558333 -415.467705)
			(xy 396.550575 -415.413753) (xy 395.113042 -415.413753) (xy 395.105285 -415.467703) (xy 395.089929 -415.52)
			(xy 395.067287 -415.56958) (xy 395.03782 -415.615433) (xy 395.002126 -415.656625) (xy 394.960934 -415.692318)
			(xy 394.915082 -415.721786) (xy 394.865502 -415.744429) (xy 394.813205 -415.759785) (xy 394.759255 -415.767542)
			(xy 394.732002 -415.768028) (xy 393.868402 -415.768028) (xy 393.84115 -415.767525) (xy 393.787202 -415.759769)
			(xy 393.734907 -415.744413) (xy 393.685329 -415.721772) (xy 393.639478 -415.692306) (xy 393.598287 -415.656614)
			(xy 393.562595 -415.615424) (xy 393.533129 -415.569573) (xy 393.510487 -415.519995) (xy 393.495132 -415.4677)
			(xy 393.487375 -415.413752) (xy 392.049865 -415.413752) (xy 392.049865 -415.413756) (xy 392.042107 -415.467713)
			(xy 392.026748 -415.520017) (xy 392.004101 -415.569602) (xy 391.974628 -415.61546) (xy 391.938929 -415.656655)
			(xy 391.897729 -415.692351) (xy 391.851869 -415.72182) (xy 391.802281 -415.744461) (xy 391.749976 -415.759815)
			(xy 391.696018 -415.767568) (xy 391.668762 -415.768028) (xy 390.805162 -415.768028) (xy 390.777914 -415.767499)
			(xy 390.723973 -415.759739) (xy 390.671686 -415.744381) (xy 390.622116 -415.721739) (xy 390.576273 -415.692273)
			(xy 390.535089 -415.656584) (xy 390.499404 -415.615397) (xy 390.469943 -415.569551) (xy 390.447306 -415.519978)
			(xy 390.431953 -415.46769) (xy 390.424198 -415.413748) (xy 388.986542 -415.413748) (xy 388.986542 -415.413752)
			(xy 388.978786 -415.4677) (xy 388.963431 -415.519996) (xy 388.94079 -415.569574) (xy 388.911325 -415.615426)
			(xy 388.875634 -415.656618) (xy 388.834444 -415.692311) (xy 388.788594 -415.72178) (xy 388.739017 -415.744423)
			(xy 388.686722 -415.759781) (xy 388.632774 -415.767541) (xy 388.605522 -415.768028) (xy 387.741922 -415.768028)
			(xy 387.71467 -415.767526) (xy 387.660719 -415.759772) (xy 387.608421 -415.744419) (xy 387.558841 -415.721779)
			(xy 387.512988 -415.692313) (xy 387.471794 -415.656621) (xy 387.4361 -415.61543) (xy 387.406632 -415.569578)
			(xy 387.383989 -415.519999) (xy 387.368632 -415.467702) (xy 387.360875 -415.413752) (xy 385.923365 -415.413752)
			(xy 385.923365 -415.413755) (xy 385.915607 -415.467711) (xy 385.900249 -415.520013) (xy 385.877604 -415.569597)
			(xy 385.848133 -415.615453) (xy 385.812436 -415.656648) (xy 385.771239 -415.692344) (xy 385.725381 -415.721813)
			(xy 385.675796 -415.744456) (xy 385.623493 -415.759811) (xy 385.569537 -415.767566) (xy 385.542282 -415.768028)
			(xy 384.678682 -415.768028) (xy 384.651433 -415.767501) (xy 384.59749 -415.759742) (xy 384.5452 -415.744387)
			(xy 384.495628 -415.721746) (xy 384.449782 -415.69228) (xy 384.408597 -415.656591) (xy 384.372909 -415.615403)
			(xy 384.343446 -415.569556) (xy 384.320807 -415.519983) (xy 384.305454 -415.467692) (xy 384.297698 -415.413749)
			(xy 382.860042 -415.413749) (xy 382.860042 -415.413751) (xy 382.852286 -415.467698) (xy 382.836933 -415.519992)
			(xy 382.814293 -415.569569) (xy 382.784829 -415.61542) (xy 382.749141 -415.656611) (xy 382.707953 -415.692304)
			(xy 382.662106 -415.721773) (xy 382.612531 -415.744418) (xy 382.560239 -415.759778) (xy 382.506293 -415.767539)
			(xy 382.479042 -415.768028) (xy 381.615442 -415.768028) (xy 381.588189 -415.767528) (xy 381.534236 -415.759776)
			(xy 381.481936 -415.744424) (xy 381.432353 -415.721785) (xy 381.386497 -415.69232) (xy 381.345301 -415.656628)
			(xy 381.309605 -415.615437) (xy 381.280135 -415.569584) (xy 381.25749 -415.520004) (xy 381.242133 -415.467705)
			(xy 381.234375 -415.413753) (xy 379.796842 -415.413753) (xy 379.789085 -415.467703) (xy 379.773729 -415.52)
			(xy 379.751087 -415.56958) (xy 379.72162 -415.615433) (xy 379.685926 -415.656625) (xy 379.644734 -415.692318)
			(xy 379.598882 -415.721786) (xy 379.549302 -415.744429) (xy 379.497005 -415.759785) (xy 379.443055 -415.767542)
			(xy 379.415802 -415.768028) (xy 378.552202 -415.768028) (xy 378.52495 -415.767525) (xy 378.471002 -415.759769)
			(xy 378.418707 -415.744413) (xy 378.369129 -415.721772) (xy 378.323278 -415.692306) (xy 378.282087 -415.656614)
			(xy 378.246395 -415.615424) (xy 378.216929 -415.569573) (xy 378.194287 -415.519995) (xy 378.178932 -415.4677)
			(xy 378.171175 -415.413752) (xy 376.733665 -415.413752) (xy 376.733665 -415.413756) (xy 376.725907 -415.467713)
			(xy 376.710548 -415.520017) (xy 376.687901 -415.569602) (xy 376.658428 -415.61546) (xy 376.622729 -415.656655)
			(xy 376.581529 -415.692351) (xy 376.535669 -415.72182) (xy 376.486081 -415.744461) (xy 376.433776 -415.759815)
			(xy 376.379818 -415.767568) (xy 376.352562 -415.768028) (xy 375.488962 -415.768028) (xy 375.461714 -415.767499)
			(xy 375.407773 -415.759739) (xy 375.355486 -415.744381) (xy 375.305916 -415.721739) (xy 375.260073 -415.692273)
			(xy 375.218889 -415.656584) (xy 375.183204 -415.615397) (xy 375.153743 -415.569551) (xy 375.131106 -415.519978)
			(xy 375.115753 -415.46769) (xy 375.107998 -415.413748) (xy 373.670342 -415.413748) (xy 373.670342 -415.413752)
			(xy 373.662586 -415.4677) (xy 373.647231 -415.519996) (xy 373.62459 -415.569574) (xy 373.595125 -415.615426)
			(xy 373.559434 -415.656618) (xy 373.518244 -415.692311) (xy 373.472394 -415.72178) (xy 373.422817 -415.744423)
			(xy 373.370522 -415.759781) (xy 373.316574 -415.767541) (xy 373.289322 -415.768028) (xy 372.425722 -415.768028)
			(xy 372.39847 -415.767526) (xy 372.344519 -415.759772) (xy 372.292221 -415.744419) (xy 372.242641 -415.721779)
			(xy 372.196788 -415.692313) (xy 372.155594 -415.656621) (xy 372.1199 -415.61543) (xy 372.090432 -415.569578)
			(xy 372.067789 -415.519999) (xy 372.052432 -415.467702) (xy 372.044675 -415.413752) (xy 352.518742 -415.413752)
			(xy 352.510986 -415.4677) (xy 352.495631 -415.519995) (xy 352.472991 -415.569573) (xy 352.443526 -415.615425)
			(xy 352.407835 -415.656617) (xy 352.366646 -415.69231) (xy 352.320796 -415.721778) (xy 352.27122 -415.744422)
			(xy 352.218925 -415.75978) (xy 352.164977 -415.76754) (xy 352.137726 -415.768028) (xy 351.274126 -415.768028)
			(xy 351.246873 -415.767526) (xy 351.192922 -415.759773) (xy 351.140624 -415.74442) (xy 351.091043 -415.72178)
			(xy 351.045189 -415.692314) (xy 351.003996 -415.656623) (xy 350.968301 -415.615431) (xy 350.938832 -415.569579)
			(xy 350.916189 -415.52) (xy 350.900833 -415.467703) (xy 350.893075 -415.413753) (xy 349.455565 -415.413753)
			(xy 349.455565 -415.413755) (xy 349.447807 -415.46771) (xy 349.43245 -415.520012) (xy 349.409805 -415.569595)
			(xy 349.380334 -415.615452) (xy 349.344637 -415.656647) (xy 349.303441 -415.692343) (xy 349.257583 -415.721812)
			(xy 349.207999 -415.744455) (xy 349.155696 -415.75981) (xy 349.101741 -415.767566) (xy 349.074486 -415.768028)
			(xy 348.210886 -415.768028) (xy 348.183637 -415.767501) (xy 348.129694 -415.759743) (xy 348.077403 -415.744388)
			(xy 348.02783 -415.721747) (xy 347.981984 -415.692282) (xy 347.940798 -415.656592) (xy 347.90511 -415.615404)
			(xy 347.875646 -415.569557) (xy 347.853008 -415.519984) (xy 347.837654 -415.467693) (xy 347.829898 -415.413749)
			(xy 346.392242 -415.413749) (xy 346.392242 -415.413751) (xy 346.384487 -415.467697) (xy 346.369133 -415.519991)
			(xy 346.346494 -415.569568) (xy 346.31703 -415.615418) (xy 346.281342 -415.656609) (xy 346.240155 -415.692303)
			(xy 346.194308 -415.721772) (xy 346.144734 -415.744417) (xy 346.092442 -415.759777) (xy 346.038497 -415.767539)
			(xy 346.011246 -415.768028) (xy 345.147646 -415.768028) (xy 345.120392 -415.767528) (xy 345.066439 -415.759777)
			(xy 345.014139 -415.744425) (xy 344.964555 -415.721787) (xy 344.918699 -415.692321) (xy 344.877503 -415.65663)
			(xy 344.841806 -415.615438) (xy 344.812335 -415.569585) (xy 344.789691 -415.520004) (xy 344.774333 -415.467706)
			(xy 344.766575 -415.413754) (xy 343.329042 -415.413754) (xy 343.321285 -415.467702) (xy 343.30593 -415.519999)
			(xy 343.283288 -415.569579) (xy 343.253821 -415.615431) (xy 343.218128 -415.656624) (xy 343.176936 -415.692317)
			(xy 343.131084 -415.721785) (xy 343.081505 -415.744428) (xy 343.029208 -415.759784) (xy 342.975258 -415.767542)
			(xy 342.948006 -415.768028) (xy 342.084406 -415.768028) (xy 342.057154 -415.767525) (xy 342.003206 -415.759769)
			(xy 341.95091 -415.744415) (xy 341.901331 -415.721774) (xy 341.85548 -415.692307) (xy 341.814289 -415.656616)
			(xy 341.778596 -415.615425) (xy 341.749129 -415.569574) (xy 341.726488 -415.519996) (xy 341.711132 -415.4677)
			(xy 341.703375 -415.413752) (xy 340.265865 -415.413752) (xy 340.265865 -415.413756) (xy 340.258107 -415.467713)
			(xy 340.242748 -415.520016) (xy 340.220102 -415.569601) (xy 340.190629 -415.615458) (xy 340.15493 -415.656654)
			(xy 340.113731 -415.69235) (xy 340.067871 -415.721818) (xy 340.018284 -415.74446) (xy 339.965979 -415.759814)
			(xy 339.912022 -415.767567) (xy 339.884766 -415.768028) (xy 339.021166 -415.768028) (xy 338.993918 -415.767499)
			(xy 338.939977 -415.759739) (xy 338.887689 -415.744382) (xy 338.838118 -415.72174) (xy 338.792275 -415.692275)
			(xy 338.751091 -415.656585) (xy 338.715405 -415.615398) (xy 338.685943 -415.569552) (xy 338.663306 -415.519979)
			(xy 338.647953 -415.46769) (xy 338.640198 -415.413748) (xy 337.202542 -415.413748) (xy 337.202542 -415.413751)
			(xy 337.194786 -415.4677) (xy 337.179431 -415.519995) (xy 337.156791 -415.569573) (xy 337.127326 -415.615425)
			(xy 337.091635 -415.656617) (xy 337.050446 -415.69231) (xy 337.004596 -415.721778) (xy 336.95502 -415.744422)
			(xy 336.902725 -415.75978) (xy 336.848777 -415.76754) (xy 336.821526 -415.768028) (xy 335.957926 -415.768028)
			(xy 335.930673 -415.767526) (xy 335.876722 -415.759773) (xy 335.824424 -415.74442) (xy 335.774843 -415.72178)
			(xy 335.728989 -415.692314) (xy 335.687796 -415.656623) (xy 335.652101 -415.615431) (xy 335.622632 -415.569579)
			(xy 335.599989 -415.52) (xy 335.584633 -415.467703) (xy 335.576875 -415.413753) (xy 334.139365 -415.413753)
			(xy 334.139365 -415.413755) (xy 334.131607 -415.46771) (xy 334.11625 -415.520012) (xy 334.093605 -415.569595)
			(xy 334.064134 -415.615452) (xy 334.028437 -415.656647) (xy 333.987241 -415.692343) (xy 333.941383 -415.721812)
			(xy 333.891799 -415.744455) (xy 333.839496 -415.75981) (xy 333.785541 -415.767566) (xy 333.758286 -415.768028)
			(xy 332.894686 -415.768028) (xy 332.867437 -415.767501) (xy 332.813494 -415.759743) (xy 332.761203 -415.744388)
			(xy 332.71163 -415.721747) (xy 332.665784 -415.692282) (xy 332.624598 -415.656592) (xy 332.58891 -415.615404)
			(xy 332.559446 -415.569557) (xy 332.536808 -415.519984) (xy 332.521454 -415.467693) (xy 332.513698 -415.413749)
			(xy 331.076042 -415.413749) (xy 331.076042 -415.413751) (xy 331.068287 -415.467697) (xy 331.052933 -415.519991)
			(xy 331.030294 -415.569568) (xy 331.00083 -415.615418) (xy 330.965142 -415.656609) (xy 330.923955 -415.692303)
			(xy 330.878108 -415.721772) (xy 330.828534 -415.744417) (xy 330.776242 -415.759777) (xy 330.722297 -415.767539)
			(xy 330.695046 -415.768028) (xy 329.831446 -415.768028) (xy 329.804192 -415.767528) (xy 329.750239 -415.759777)
			(xy 329.697939 -415.744425) (xy 329.648355 -415.721787) (xy 329.602499 -415.692321) (xy 329.561303 -415.65663)
			(xy 329.525606 -415.615438) (xy 329.496135 -415.569585) (xy 329.473491 -415.520004) (xy 329.458133 -415.467706)
			(xy 329.450375 -415.413754) (xy 328.012842 -415.413754) (xy 328.005085 -415.467702) (xy 327.98973 -415.519999)
			(xy 327.967088 -415.569579) (xy 327.937621 -415.615431) (xy 327.901928 -415.656624) (xy 327.860736 -415.692317)
			(xy 327.814884 -415.721785) (xy 327.765305 -415.744428) (xy 327.713008 -415.759784) (xy 327.659058 -415.767542)
			(xy 327.631806 -415.768028) (xy 326.768206 -415.768028) (xy 326.740954 -415.767525) (xy 326.687006 -415.759769)
			(xy 326.63471 -415.744415) (xy 326.585131 -415.721774) (xy 326.53928 -415.692307) (xy 326.498089 -415.656616)
			(xy 326.462396 -415.615425) (xy 326.432929 -415.569574) (xy 326.410288 -415.519996) (xy 326.394932 -415.4677)
			(xy 326.387175 -415.413752) (xy 324.949665 -415.413752) (xy 324.949665 -415.413756) (xy 324.941907 -415.467713)
			(xy 324.926548 -415.520016) (xy 324.903902 -415.569601) (xy 324.874429 -415.615458) (xy 324.83873 -415.656654)
			(xy 324.797531 -415.69235) (xy 324.751671 -415.721818) (xy 324.702084 -415.74446) (xy 324.649779 -415.759814)
			(xy 324.595822 -415.767567) (xy 324.568566 -415.768028) (xy 323.704966 -415.768028) (xy 323.677718 -415.767499)
			(xy 323.623777 -415.759739) (xy 323.571489 -415.744382) (xy 323.521918 -415.72174) (xy 323.476075 -415.692275)
			(xy 323.434891 -415.656585) (xy 323.399205 -415.615398) (xy 323.369743 -415.569552) (xy 323.347106 -415.519979)
			(xy 323.331753 -415.46769) (xy 323.323998 -415.413748) (xy 321.886342 -415.413748) (xy 321.886342 -415.413751)
			(xy 321.878586 -415.4677) (xy 321.863231 -415.519995) (xy 321.840591 -415.569573) (xy 321.811126 -415.615425)
			(xy 321.775435 -415.656617) (xy 321.734246 -415.69231) (xy 321.688396 -415.721778) (xy 321.63882 -415.744422)
			(xy 321.586525 -415.75978) (xy 321.532577 -415.76754) (xy 321.505326 -415.768028) (xy 320.641726 -415.768028)
			(xy 320.614473 -415.767526) (xy 320.560522 -415.759773) (xy 320.508224 -415.74442) (xy 320.458643 -415.72178)
			(xy 320.412789 -415.692314) (xy 320.371596 -415.656623) (xy 320.335901 -415.615431) (xy 320.306432 -415.569579)
			(xy 320.283789 -415.52) (xy 320.268433 -415.467703) (xy 320.260675 -415.413753) (xy 318.823165 -415.413753)
			(xy 318.823165 -415.413755) (xy 318.815407 -415.46771) (xy 318.80005 -415.520012) (xy 318.777405 -415.569595)
			(xy 318.747934 -415.615452) (xy 318.712237 -415.656647) (xy 318.671041 -415.692343) (xy 318.625183 -415.721812)
			(xy 318.575599 -415.744455) (xy 318.523296 -415.75981) (xy 318.469341 -415.767566) (xy 318.442086 -415.768028)
			(xy 317.578486 -415.768028) (xy 317.551237 -415.767501) (xy 317.497294 -415.759743) (xy 317.445003 -415.744388)
			(xy 317.39543 -415.721747) (xy 317.349584 -415.692282) (xy 317.308398 -415.656592) (xy 317.27271 -415.615404)
			(xy 317.243246 -415.569557) (xy 317.220608 -415.519984) (xy 317.205254 -415.467693) (xy 317.197498 -415.413749)
			(xy 315.759842 -415.413749) (xy 315.759842 -415.413751) (xy 315.752087 -415.467697) (xy 315.736733 -415.519991)
			(xy 315.714094 -415.569568) (xy 315.68463 -415.615418) (xy 315.648942 -415.656609) (xy 315.607755 -415.692303)
			(xy 315.561908 -415.721772) (xy 315.512334 -415.744417) (xy 315.460042 -415.759777) (xy 315.406097 -415.767539)
			(xy 315.378846 -415.768028) (xy 314.515246 -415.768028) (xy 314.487992 -415.767528) (xy 314.434039 -415.759777)
			(xy 314.381739 -415.744425) (xy 314.332155 -415.721787) (xy 314.286299 -415.692321) (xy 314.245103 -415.65663)
			(xy 314.209406 -415.615438) (xy 314.179935 -415.569585) (xy 314.157291 -415.520004) (xy 314.141933 -415.467706)
			(xy 314.134175 -415.413754) (xy 312.696642 -415.413754) (xy 312.688885 -415.467702) (xy 312.67353 -415.519999)
			(xy 312.650888 -415.569579) (xy 312.621421 -415.615431) (xy 312.585728 -415.656624) (xy 312.544536 -415.692317)
			(xy 312.498684 -415.721785) (xy 312.449105 -415.744428) (xy 312.396808 -415.759784) (xy 312.342858 -415.767542)
			(xy 312.315606 -415.768028) (xy 311.452006 -415.768028) (xy 311.424754 -415.767525) (xy 311.370806 -415.759769)
			(xy 311.31851 -415.744415) (xy 311.268931 -415.721774) (xy 311.22308 -415.692307) (xy 311.181889 -415.656616)
			(xy 311.146196 -415.615425) (xy 311.116729 -415.569574) (xy 311.094088 -415.519996) (xy 311.078732 -415.4677)
			(xy 311.070975 -415.413752) (xy 309.633465 -415.413752) (xy 309.633465 -415.413756) (xy 309.625707 -415.467713)
			(xy 309.610348 -415.520016) (xy 309.587702 -415.569601) (xy 309.558229 -415.615458) (xy 309.52253 -415.656654)
			(xy 309.481331 -415.69235) (xy 309.435471 -415.721818) (xy 309.385884 -415.74446) (xy 309.333579 -415.759814)
			(xy 309.279622 -415.767567) (xy 309.252366 -415.768028) (xy 308.388766 -415.768028) (xy 308.361518 -415.767499)
			(xy 308.307577 -415.759739) (xy 308.255289 -415.744382) (xy 308.205718 -415.72174) (xy 308.159875 -415.692275)
			(xy 308.118691 -415.656585) (xy 308.083005 -415.615398) (xy 308.053543 -415.569552) (xy 308.030906 -415.519979)
			(xy 308.015553 -415.46769) (xy 308.007798 -415.413748) (xy 306.570142 -415.413748) (xy 306.570142 -415.413751)
			(xy 306.562386 -415.4677) (xy 306.547031 -415.519995) (xy 306.524391 -415.569573) (xy 306.494926 -415.615425)
			(xy 306.459235 -415.656617) (xy 306.418046 -415.69231) (xy 306.372196 -415.721778) (xy 306.32262 -415.744422)
			(xy 306.270325 -415.75978) (xy 306.216377 -415.76754) (xy 306.189126 -415.768028) (xy 305.325526 -415.768028)
			(xy 305.298273 -415.767526) (xy 305.244322 -415.759773) (xy 305.192024 -415.74442) (xy 305.142443 -415.72178)
			(xy 305.096589 -415.692314) (xy 305.055396 -415.656623) (xy 305.019701 -415.615431) (xy 304.990232 -415.569579)
			(xy 304.967589 -415.52) (xy 304.952233 -415.467703) (xy 304.944475 -415.413753) (xy 301.259284 -415.413753)
			(xy 301.227716 -415.466663) (xy 301.125722 -415.622007) (xy 301.017139 -415.772819) (xy 300.902169 -415.918821)
			(xy 300.781023 -416.05974) (xy 300.653927 -416.195318) (xy 300.521116 -416.325302) (xy 300.382835 -416.449451)
			(xy 300.239342 -416.567537) (xy 300.090901 -416.67934) (xy 299.937787 -416.784653) (xy 299.780284 -416.883281)
			(xy 299.618684 -416.975042) (xy 299.453286 -417.059765) (xy 299.284396 -417.137295) (xy 299.112327 -417.207486)
			(xy 298.937397 -417.27021) (xy 298.759931 -417.32535) (xy 298.580257 -417.372803) (xy 298.398708 -417.412483)
			(xy 298.21562 -417.444315) (xy 298.031331 -417.468242) (xy 297.846184 -417.484217) (xy 297.660521 -417.492212)
			(xy 297.567604 -417.492688) (xy 297.567096 -417.492688) (xy 297.470033 -417.492144) (xy 297.276104 -417.483409)
			(xy 297.082764 -417.465966) (xy 296.890402 -417.43985) (xy 296.69941 -417.405115) (xy 296.510171 -417.361829)
			(xy 296.416476 -417.336478) (xy 296.404792 -417.333176) (xy 296.381678 -417.337748) (xy 296.307764 -417.393882)
			(xy 296.298784 -417.401478) (xy 296.288341 -417.422523) (xy 296.287698 -417.434268) (xy 296.287698 -418.439456)
			(xy 304.944423 -418.439456) (xy 304.944423 -418.384944) (xy 304.952181 -418.330986) (xy 304.96754 -418.278681)
			(xy 304.990186 -418.229095) (xy 305.019659 -418.183237) (xy 305.055359 -418.14204) (xy 305.096558 -418.106344)
			(xy 305.142418 -418.076874) (xy 305.192006 -418.054231) (xy 305.244311 -418.038876) (xy 305.29827 -418.031121)
			(xy 305.325526 -418.03066) (xy 306.189126 -418.03066) (xy 306.216374 -418.031212) (xy 306.270314 -418.038971)
			(xy 306.322601 -418.054327) (xy 306.372171 -418.076968) (xy 306.418014 -418.106432) (xy 306.459198 -418.142121)
			(xy 306.494884 -418.183307) (xy 306.524345 -418.229152) (xy 306.546982 -418.278723) (xy 306.562335 -418.331011)
			(xy 306.57009 -418.384952) (xy 306.57009 -418.439448) (xy 306.570089 -418.439452) (xy 308.007746 -418.439452)
			(xy 308.007746 -418.384948) (xy 308.015502 -418.330999) (xy 308.030857 -418.278702) (xy 308.053497 -418.229123)
			(xy 308.082963 -418.183271) (xy 308.118654 -418.142078) (xy 308.159843 -418.106383) (xy 308.205693 -418.076914)
			(xy 308.25527 -418.054269) (xy 308.307565 -418.038909) (xy 308.361514 -418.031148) (xy 308.388766 -418.03066)
			(xy 309.252366 -418.03066) (xy 309.279618 -418.031185) (xy 309.333568 -418.038937) (xy 309.385866 -418.054289)
			(xy 309.435446 -418.076928) (xy 309.4813 -418.106392) (xy 309.522493 -418.142083) (xy 309.558187 -418.183273)
			(xy 309.587656 -418.229124) (xy 309.610299 -418.278702) (xy 309.625655 -418.330999) (xy 309.633413 -418.384948)
			(xy 309.633413 -418.439452) (xy 309.633413 -418.439455) (xy 311.070923 -418.439455) (xy 311.070923 -418.384945)
			(xy 311.078681 -418.330989) (xy 311.094038 -418.278686) (xy 311.116683 -418.229101) (xy 311.146154 -418.183244)
			(xy 311.181852 -418.142047) (xy 311.223049 -418.106351) (xy 311.268906 -418.07688) (xy 311.318491 -418.054236)
			(xy 311.370794 -418.038879) (xy 311.424751 -418.031123) (xy 311.452006 -418.03066) (xy 312.315606 -418.03066)
			(xy 312.342855 -418.031211) (xy 312.396797 -418.038967) (xy 312.449087 -418.054321) (xy 312.498659 -418.076961)
			(xy 312.544505 -418.106425) (xy 312.585691 -418.142113) (xy 312.621379 -418.1833) (xy 312.650842 -418.229146)
			(xy 312.673481 -418.278719) (xy 312.688834 -418.331009) (xy 312.69659 -418.384951) (xy 312.69659 -418.439449)
			(xy 312.696589 -418.439457) (xy 314.134123 -418.439457) (xy 314.134123 -418.384943) (xy 314.141882 -418.330983)
			(xy 314.157242 -418.278677) (xy 314.179889 -418.22909) (xy 314.209364 -418.183231) (xy 314.245066 -418.142033)
			(xy 314.286267 -418.106337) (xy 314.33213 -418.076867) (xy 314.38172 -418.054225) (xy 314.434028 -418.038872)
			(xy 314.487989 -418.03112) (xy 314.515246 -418.03066) (xy 315.378846 -418.03066) (xy 315.406093 -418.031213)
			(xy 315.460031 -418.038975) (xy 315.512316 -418.054332) (xy 315.561883 -418.076974) (xy 315.607724 -418.106439)
			(xy 315.648905 -418.142128) (xy 315.684588 -418.183313) (xy 315.714048 -418.229157) (xy 315.736684 -418.278727)
			(xy 315.752035 -418.331014) (xy 315.75979 -418.384953) (xy 315.75979 -418.439447) (xy 315.759789 -418.439453)
			(xy 317.197446 -418.439453) (xy 317.197446 -418.384947) (xy 317.205203 -418.330996) (xy 317.220558 -418.278698)
			(xy 317.2432 -418.229118) (xy 317.272668 -418.183264) (xy 317.308361 -418.142071) (xy 317.349553 -418.106376)
			(xy 317.395405 -418.076907) (xy 317.444985 -418.054263) (xy 317.497282 -418.038906) (xy 317.551233 -418.031147)
			(xy 317.578486 -418.03066) (xy 318.442086 -418.03066) (xy 318.469337 -418.031186) (xy 318.523285 -418.038941)
			(xy 318.57558 -418.054295) (xy 318.625158 -418.076934) (xy 318.671009 -418.106399) (xy 318.7122 -418.14209)
			(xy 318.747892 -418.18328) (xy 318.777359 -418.22913) (xy 318.800001 -418.278707) (xy 318.815356 -418.331001)
			(xy 318.823113 -418.384949) (xy 318.823113 -418.439451) (xy 318.823112 -418.439456) (xy 320.260623 -418.439456)
			(xy 320.260623 -418.384944) (xy 320.268381 -418.330986) (xy 320.28374 -418.278681) (xy 320.306386 -418.229095)
			(xy 320.335859 -418.183237) (xy 320.371559 -418.14204) (xy 320.412758 -418.106344) (xy 320.458618 -418.076874)
			(xy 320.508206 -418.054231) (xy 320.560511 -418.038876) (xy 320.61447 -418.031121) (xy 320.641726 -418.03066)
			(xy 321.505326 -418.03066) (xy 321.532574 -418.031212) (xy 321.586514 -418.038971) (xy 321.638801 -418.054327)
			(xy 321.688371 -418.076968) (xy 321.734214 -418.106432) (xy 321.775398 -418.142121) (xy 321.811084 -418.183307)
			(xy 321.840545 -418.229152) (xy 321.863182 -418.278723) (xy 321.878535 -418.331011) (xy 321.88629 -418.384952)
			(xy 321.88629 -418.439448) (xy 321.886289 -418.439452) (xy 323.323946 -418.439452) (xy 323.323946 -418.384948)
			(xy 323.331702 -418.330999) (xy 323.347057 -418.278702) (xy 323.369697 -418.229123) (xy 323.399163 -418.183271)
			(xy 323.434854 -418.142078) (xy 323.476043 -418.106383) (xy 323.521893 -418.076914) (xy 323.57147 -418.054269)
			(xy 323.623765 -418.038909) (xy 323.677714 -418.031148) (xy 323.704966 -418.03066) (xy 324.568566 -418.03066)
			(xy 324.595818 -418.031185) (xy 324.649768 -418.038937) (xy 324.702066 -418.054289) (xy 324.751646 -418.076928)
			(xy 324.7975 -418.106392) (xy 324.838693 -418.142083) (xy 324.874387 -418.183273) (xy 324.903856 -418.229124)
			(xy 324.926499 -418.278702) (xy 324.941855 -418.330999) (xy 324.949613 -418.384948) (xy 324.949613 -418.439452)
			(xy 324.949613 -418.439455) (xy 326.387123 -418.439455) (xy 326.387123 -418.384945) (xy 326.394881 -418.330989)
			(xy 326.410238 -418.278686) (xy 326.432883 -418.229101) (xy 326.462354 -418.183244) (xy 326.498052 -418.142047)
			(xy 326.539249 -418.106351) (xy 326.585106 -418.07688) (xy 326.634691 -418.054236) (xy 326.686994 -418.038879)
			(xy 326.740951 -418.031123) (xy 326.768206 -418.03066) (xy 327.631806 -418.03066) (xy 327.659055 -418.031211)
			(xy 327.712997 -418.038967) (xy 327.765287 -418.054321) (xy 327.814859 -418.076961) (xy 327.860705 -418.106425)
			(xy 327.901891 -418.142113) (xy 327.937579 -418.1833) (xy 327.967042 -418.229146) (xy 327.989681 -418.278719)
			(xy 328.005034 -418.331009) (xy 328.01279 -418.384951) (xy 328.01279 -418.439449) (xy 328.012789 -418.439457)
			(xy 329.450323 -418.439457) (xy 329.450323 -418.384943) (xy 329.458082 -418.330983) (xy 329.473442 -418.278677)
			(xy 329.496089 -418.22909) (xy 329.525564 -418.183231) (xy 329.561266 -418.142033) (xy 329.602467 -418.106337)
			(xy 329.64833 -418.076867) (xy 329.69792 -418.054225) (xy 329.750228 -418.038872) (xy 329.804189 -418.03112)
			(xy 329.831446 -418.03066) (xy 330.695046 -418.03066) (xy 330.722293 -418.031213) (xy 330.776231 -418.038975)
			(xy 330.828516 -418.054332) (xy 330.878083 -418.076974) (xy 330.923924 -418.106439) (xy 330.965105 -418.142128)
			(xy 331.000788 -418.183313) (xy 331.030248 -418.229157) (xy 331.052884 -418.278727) (xy 331.068235 -418.331014)
			(xy 331.07599 -418.384953) (xy 331.07599 -418.439447) (xy 331.075989 -418.439453) (xy 332.513646 -418.439453)
			(xy 332.513646 -418.384947) (xy 332.521403 -418.330996) (xy 332.536758 -418.278698) (xy 332.5594 -418.229118)
			(xy 332.588868 -418.183264) (xy 332.624561 -418.142071) (xy 332.665753 -418.106376) (xy 332.711605 -418.076907)
			(xy 332.761185 -418.054263) (xy 332.813482 -418.038906) (xy 332.867433 -418.031147) (xy 332.894686 -418.03066)
			(xy 333.758286 -418.03066) (xy 333.785537 -418.031186) (xy 333.839485 -418.038941) (xy 333.89178 -418.054295)
			(xy 333.941358 -418.076934) (xy 333.987209 -418.106399) (xy 334.0284 -418.14209) (xy 334.064092 -418.18328)
			(xy 334.093559 -418.22913) (xy 334.116201 -418.278707) (xy 334.131556 -418.331001) (xy 334.139313 -418.384949)
			(xy 334.139313 -418.439451) (xy 334.139312 -418.439456) (xy 335.576823 -418.439456) (xy 335.576823 -418.384944)
			(xy 335.584581 -418.330986) (xy 335.59994 -418.278681) (xy 335.622586 -418.229095) (xy 335.652059 -418.183237)
			(xy 335.687759 -418.14204) (xy 335.728958 -418.106344) (xy 335.774818 -418.076874) (xy 335.824406 -418.054231)
			(xy 335.876711 -418.038876) (xy 335.93067 -418.031121) (xy 335.957926 -418.03066) (xy 336.821526 -418.03066)
			(xy 336.848774 -418.031212) (xy 336.902714 -418.038971) (xy 336.955001 -418.054327) (xy 337.004571 -418.076968)
			(xy 337.050414 -418.106432) (xy 337.091598 -418.142121) (xy 337.127284 -418.183307) (xy 337.156745 -418.229152)
			(xy 337.179382 -418.278723) (xy 337.194735 -418.331011) (xy 337.20249 -418.384952) (xy 337.20249 -418.439448)
			(xy 337.202489 -418.439452) (xy 338.640146 -418.439452) (xy 338.640146 -418.384948) (xy 338.647902 -418.330999)
			(xy 338.663257 -418.278702) (xy 338.685897 -418.229123) (xy 338.715363 -418.183271) (xy 338.751054 -418.142078)
			(xy 338.792243 -418.106383) (xy 338.838093 -418.076914) (xy 338.88767 -418.054269) (xy 338.939965 -418.038909)
			(xy 338.993914 -418.031148) (xy 339.021166 -418.03066) (xy 339.884766 -418.03066) (xy 339.912018 -418.031185)
			(xy 339.965968 -418.038937) (xy 340.018266 -418.054289) (xy 340.067846 -418.076928) (xy 340.1137 -418.106392)
			(xy 340.154893 -418.142083) (xy 340.190587 -418.183273) (xy 340.220056 -418.229124) (xy 340.242699 -418.278702)
			(xy 340.258055 -418.330999) (xy 340.265813 -418.384948) (xy 340.265813 -418.439452) (xy 340.265813 -418.439455)
			(xy 341.703323 -418.439455) (xy 341.703323 -418.384945) (xy 341.711081 -418.330989) (xy 341.726438 -418.278686)
			(xy 341.749083 -418.229101) (xy 341.778554 -418.183244) (xy 341.814252 -418.142047) (xy 341.855449 -418.106351)
			(xy 341.901306 -418.07688) (xy 341.950891 -418.054236) (xy 342.003194 -418.038879) (xy 342.057151 -418.031123)
			(xy 342.084406 -418.03066) (xy 342.948006 -418.03066) (xy 342.975255 -418.031211) (xy 343.029197 -418.038967)
			(xy 343.081487 -418.054321) (xy 343.131059 -418.076961) (xy 343.176905 -418.106425) (xy 343.218091 -418.142113)
			(xy 343.253779 -418.1833) (xy 343.283242 -418.229146) (xy 343.305881 -418.278719) (xy 343.321234 -418.331009)
			(xy 343.32899 -418.384951) (xy 343.32899 -418.439449) (xy 343.328989 -418.439457) (xy 344.766523 -418.439457)
			(xy 344.766523 -418.384943) (xy 344.774282 -418.330983) (xy 344.789642 -418.278677) (xy 344.812289 -418.22909)
			(xy 344.841764 -418.183231) (xy 344.877466 -418.142033) (xy 344.918667 -418.106337) (xy 344.96453 -418.076867)
			(xy 345.01412 -418.054225) (xy 345.066428 -418.038872) (xy 345.120389 -418.03112) (xy 345.147646 -418.03066)
			(xy 346.011246 -418.03066) (xy 346.038493 -418.031213) (xy 346.092431 -418.038975) (xy 346.144716 -418.054332)
			(xy 346.194283 -418.076974) (xy 346.240124 -418.106439) (xy 346.281305 -418.142128) (xy 346.316988 -418.183313)
			(xy 346.346448 -418.229157) (xy 346.369084 -418.278727) (xy 346.384435 -418.331014) (xy 346.39219 -418.384953)
			(xy 346.39219 -418.439447) (xy 346.392189 -418.439453) (xy 347.829846 -418.439453) (xy 347.829846 -418.384947)
			(xy 347.837603 -418.330996) (xy 347.852958 -418.278698) (xy 347.8756 -418.229118) (xy 347.905068 -418.183264)
			(xy 347.940761 -418.142071) (xy 347.981953 -418.106376) (xy 348.027805 -418.076907) (xy 348.077385 -418.054263)
			(xy 348.129682 -418.038906) (xy 348.183633 -418.031147) (xy 348.210886 -418.03066) (xy 349.074486 -418.03066)
			(xy 349.101737 -418.031186) (xy 349.155685 -418.038941) (xy 349.20798 -418.054295) (xy 349.257558 -418.076934)
			(xy 349.303409 -418.106399) (xy 349.3446 -418.14209) (xy 349.380292 -418.18328) (xy 349.409759 -418.22913)
			(xy 349.432401 -418.278707) (xy 349.447756 -418.331001) (xy 349.455513 -418.384949) (xy 349.455513 -418.439451)
			(xy 349.455512 -418.439456) (xy 350.893023 -418.439456) (xy 350.893023 -418.384944) (xy 350.900781 -418.330986)
			(xy 350.91614 -418.278681) (xy 350.938786 -418.229095) (xy 350.968259 -418.183237) (xy 351.003959 -418.14204)
			(xy 351.045158 -418.106344) (xy 351.091018 -418.076874) (xy 351.140606 -418.054231) (xy 351.192911 -418.038876)
			(xy 351.24687 -418.031121) (xy 351.274126 -418.03066) (xy 352.137726 -418.03066) (xy 352.164974 -418.031212)
			(xy 352.218914 -418.038971) (xy 352.271201 -418.054327) (xy 352.320771 -418.076968) (xy 352.366614 -418.106432)
			(xy 352.407798 -418.142121) (xy 352.443484 -418.183307) (xy 352.472945 -418.229152) (xy 352.495582 -418.278723)
			(xy 352.510935 -418.331011) (xy 352.51869 -418.384952) (xy 352.51869 -418.439448) (xy 352.510935 -418.493389)
			(xy 352.495582 -418.545677) (xy 352.472945 -418.595248) (xy 352.443484 -418.641093) (xy 352.407798 -418.682279)
			(xy 352.366614 -418.717968) (xy 352.320771 -418.747432) (xy 352.271201 -418.770073) (xy 352.218914 -418.785429)
			(xy 352.164974 -418.793188) (xy 352.137726 -418.793676) (xy 351.274126 -418.793676) (xy 351.24687 -418.793279)
			(xy 351.192911 -418.785524) (xy 351.140606 -418.770169) (xy 351.091018 -418.747526) (xy 351.045158 -418.718056)
			(xy 351.003959 -418.68236) (xy 350.968259 -418.641163) (xy 350.938786 -418.595305) (xy 350.91614 -418.545719)
			(xy 350.900781 -418.493414) (xy 350.893023 -418.439456) (xy 349.455512 -418.439456) (xy 349.447756 -418.493399)
			(xy 349.432401 -418.545693) (xy 349.409759 -418.59527) (xy 349.380292 -418.64112) (xy 349.3446 -418.68231)
			(xy 349.303409 -418.718001) (xy 349.257558 -418.747466) (xy 349.20798 -418.770105) (xy 349.155685 -418.785459)
			(xy 349.101737 -418.793214) (xy 349.074486 -418.793676) (xy 348.210886 -418.793676) (xy 348.183633 -418.793253)
			(xy 348.129682 -418.785494) (xy 348.077385 -418.770137) (xy 348.027805 -418.747493) (xy 347.981953 -418.718024)
			(xy 347.940761 -418.682329) (xy 347.905068 -418.641136) (xy 347.8756 -418.595282) (xy 347.852958 -418.545702)
			(xy 347.837603 -418.493404) (xy 347.829846 -418.439453) (xy 346.392189 -418.439453) (xy 346.384435 -418.493386)
			(xy 346.369084 -418.545673) (xy 346.346448 -418.595243) (xy 346.316988 -418.641087) (xy 346.281305 -418.682272)
			(xy 346.240124 -418.717961) (xy 346.194283 -418.747426) (xy 346.144716 -418.770068) (xy 346.092431 -418.785425)
			(xy 346.038493 -418.793187) (xy 346.011246 -418.793676) (xy 345.147646 -418.793676) (xy 345.120389 -418.79328)
			(xy 345.066428 -418.785528) (xy 345.01412 -418.770175) (xy 344.96453 -418.747533) (xy 344.918667 -418.718063)
			(xy 344.877466 -418.682367) (xy 344.841764 -418.641169) (xy 344.812289 -418.59531) (xy 344.789642 -418.545723)
			(xy 344.774282 -418.493417) (xy 344.766523 -418.439457) (xy 343.328989 -418.439457) (xy 343.321234 -418.493391)
			(xy 343.305881 -418.545681) (xy 343.283242 -418.595254) (xy 343.253779 -418.6411) (xy 343.218091 -418.682287)
			(xy 343.176905 -418.717975) (xy 343.131059 -418.747439) (xy 343.081487 -418.770079) (xy 343.029197 -418.785433)
			(xy 342.975255 -418.793189) (xy 342.948006 -418.793676) (xy 342.084406 -418.793676) (xy 342.057151 -418.793277)
			(xy 342.003194 -418.785521) (xy 341.950891 -418.770164) (xy 341.901306 -418.74752) (xy 341.855449 -418.718049)
			(xy 341.814252 -418.682353) (xy 341.778554 -418.641156) (xy 341.749083 -418.595299) (xy 341.726438 -418.545714)
			(xy 341.711081 -418.493411) (xy 341.703323 -418.439455) (xy 340.265813 -418.439455) (xy 340.258055 -418.493402)
			(xy 340.242699 -418.545698) (xy 340.220056 -418.595276) (xy 340.190587 -418.641127) (xy 340.154893 -418.682317)
			(xy 340.1137 -418.718008) (xy 340.067846 -418.747472) (xy 340.018266 -418.770111) (xy 339.965968 -418.785463)
			(xy 339.912018 -418.793215) (xy 339.884766 -418.793676) (xy 339.021166 -418.793676) (xy 338.993914 -418.793252)
			(xy 338.939965 -418.785491) (xy 338.88767 -418.770131) (xy 338.838093 -418.747486) (xy 338.792243 -418.718017)
			(xy 338.751054 -418.682322) (xy 338.715363 -418.641129) (xy 338.685897 -418.595277) (xy 338.663257 -418.545698)
			(xy 338.647902 -418.493401) (xy 338.640146 -418.439452) (xy 337.202489 -418.439452) (xy 337.194735 -418.493389)
			(xy 337.179382 -418.545677) (xy 337.156745 -418.595248) (xy 337.127284 -418.641093) (xy 337.091598 -418.682279)
			(xy 337.050414 -418.717968) (xy 337.004571 -418.747432) (xy 336.955001 -418.770073) (xy 336.902714 -418.785429)
			(xy 336.848774 -418.793188) (xy 336.821526 -418.793676) (xy 335.957926 -418.793676) (xy 335.93067 -418.793279)
			(xy 335.876711 -418.785524) (xy 335.824406 -418.770169) (xy 335.774818 -418.747526) (xy 335.728958 -418.718056)
			(xy 335.687759 -418.68236) (xy 335.652059 -418.641163) (xy 335.622586 -418.595305) (xy 335.59994 -418.545719)
			(xy 335.584581 -418.493414) (xy 335.576823 -418.439456) (xy 334.139312 -418.439456) (xy 334.131556 -418.493399)
			(xy 334.116201 -418.545693) (xy 334.093559 -418.59527) (xy 334.064092 -418.64112) (xy 334.0284 -418.68231)
			(xy 333.987209 -418.718001) (xy 333.941358 -418.747466) (xy 333.89178 -418.770105) (xy 333.839485 -418.785459)
			(xy 333.785537 -418.793214) (xy 333.758286 -418.793676) (xy 332.894686 -418.793676) (xy 332.867433 -418.793253)
			(xy 332.813482 -418.785494) (xy 332.761185 -418.770137) (xy 332.711605 -418.747493) (xy 332.665753 -418.718024)
			(xy 332.624561 -418.682329) (xy 332.588868 -418.641136) (xy 332.5594 -418.595282) (xy 332.536758 -418.545702)
			(xy 332.521403 -418.493404) (xy 332.513646 -418.439453) (xy 331.075989 -418.439453) (xy 331.068235 -418.493386)
			(xy 331.052884 -418.545673) (xy 331.030248 -418.595243) (xy 331.000788 -418.641087) (xy 330.965105 -418.682272)
			(xy 330.923924 -418.717961) (xy 330.878083 -418.747426) (xy 330.828516 -418.770068) (xy 330.776231 -418.785425)
			(xy 330.722293 -418.793187) (xy 330.695046 -418.793676) (xy 329.831446 -418.793676) (xy 329.804189 -418.79328)
			(xy 329.750228 -418.785528) (xy 329.69792 -418.770175) (xy 329.64833 -418.747533) (xy 329.602467 -418.718063)
			(xy 329.561266 -418.682367) (xy 329.525564 -418.641169) (xy 329.496089 -418.59531) (xy 329.473442 -418.545723)
			(xy 329.458082 -418.493417) (xy 329.450323 -418.439457) (xy 328.012789 -418.439457) (xy 328.005034 -418.493391)
			(xy 327.989681 -418.545681) (xy 327.967042 -418.595254) (xy 327.937579 -418.6411) (xy 327.901891 -418.682287)
			(xy 327.860705 -418.717975) (xy 327.814859 -418.747439) (xy 327.765287 -418.770079) (xy 327.712997 -418.785433)
			(xy 327.659055 -418.793189) (xy 327.631806 -418.793676) (xy 326.768206 -418.793676) (xy 326.740951 -418.793277)
			(xy 326.686994 -418.785521) (xy 326.634691 -418.770164) (xy 326.585106 -418.74752) (xy 326.539249 -418.718049)
			(xy 326.498052 -418.682353) (xy 326.462354 -418.641156) (xy 326.432883 -418.595299) (xy 326.410238 -418.545714)
			(xy 326.394881 -418.493411) (xy 326.387123 -418.439455) (xy 324.949613 -418.439455) (xy 324.941855 -418.493402)
			(xy 324.926499 -418.545698) (xy 324.903856 -418.595276) (xy 324.874387 -418.641127) (xy 324.838693 -418.682317)
			(xy 324.7975 -418.718008) (xy 324.751646 -418.747472) (xy 324.702066 -418.770111) (xy 324.649768 -418.785463)
			(xy 324.595818 -418.793215) (xy 324.568566 -418.793676) (xy 323.704966 -418.793676) (xy 323.677714 -418.793252)
			(xy 323.623765 -418.785491) (xy 323.57147 -418.770131) (xy 323.521893 -418.747486) (xy 323.476043 -418.718017)
			(xy 323.434854 -418.682322) (xy 323.399163 -418.641129) (xy 323.369697 -418.595277) (xy 323.347057 -418.545698)
			(xy 323.331702 -418.493401) (xy 323.323946 -418.439452) (xy 321.886289 -418.439452) (xy 321.878535 -418.493389)
			(xy 321.863182 -418.545677) (xy 321.840545 -418.595248) (xy 321.811084 -418.641093) (xy 321.775398 -418.682279)
			(xy 321.734214 -418.717968) (xy 321.688371 -418.747432) (xy 321.638801 -418.770073) (xy 321.586514 -418.785429)
			(xy 321.532574 -418.793188) (xy 321.505326 -418.793676) (xy 320.641726 -418.793676) (xy 320.61447 -418.793279)
			(xy 320.560511 -418.785524) (xy 320.508206 -418.770169) (xy 320.458618 -418.747526) (xy 320.412758 -418.718056)
			(xy 320.371559 -418.68236) (xy 320.335859 -418.641163) (xy 320.306386 -418.595305) (xy 320.28374 -418.545719)
			(xy 320.268381 -418.493414) (xy 320.260623 -418.439456) (xy 318.823112 -418.439456) (xy 318.815356 -418.493399)
			(xy 318.800001 -418.545693) (xy 318.777359 -418.59527) (xy 318.747892 -418.64112) (xy 318.7122 -418.68231)
			(xy 318.671009 -418.718001) (xy 318.625158 -418.747466) (xy 318.57558 -418.770105) (xy 318.523285 -418.785459)
			(xy 318.469337 -418.793214) (xy 318.442086 -418.793676) (xy 317.578486 -418.793676) (xy 317.551233 -418.793253)
			(xy 317.497282 -418.785494) (xy 317.444985 -418.770137) (xy 317.395405 -418.747493) (xy 317.349553 -418.718024)
			(xy 317.308361 -418.682329) (xy 317.272668 -418.641136) (xy 317.2432 -418.595282) (xy 317.220558 -418.545702)
			(xy 317.205203 -418.493404) (xy 317.197446 -418.439453) (xy 315.759789 -418.439453) (xy 315.752035 -418.493386)
			(xy 315.736684 -418.545673) (xy 315.714048 -418.595243) (xy 315.684588 -418.641087) (xy 315.648905 -418.682272)
			(xy 315.607724 -418.717961) (xy 315.561883 -418.747426) (xy 315.512316 -418.770068) (xy 315.460031 -418.785425)
			(xy 315.406093 -418.793187) (xy 315.378846 -418.793676) (xy 314.515246 -418.793676) (xy 314.487989 -418.79328)
			(xy 314.434028 -418.785528) (xy 314.38172 -418.770175) (xy 314.33213 -418.747533) (xy 314.286267 -418.718063)
			(xy 314.245066 -418.682367) (xy 314.209364 -418.641169) (xy 314.179889 -418.59531) (xy 314.157242 -418.545723)
			(xy 314.141882 -418.493417) (xy 314.134123 -418.439457) (xy 312.696589 -418.439457) (xy 312.688834 -418.493391)
			(xy 312.673481 -418.545681) (xy 312.650842 -418.595254) (xy 312.621379 -418.6411) (xy 312.585691 -418.682287)
			(xy 312.544505 -418.717975) (xy 312.498659 -418.747439) (xy 312.449087 -418.770079) (xy 312.396797 -418.785433)
			(xy 312.342855 -418.793189) (xy 312.315606 -418.793676) (xy 311.452006 -418.793676) (xy 311.424751 -418.793277)
			(xy 311.370794 -418.785521) (xy 311.318491 -418.770164) (xy 311.268906 -418.74752) (xy 311.223049 -418.718049)
			(xy 311.181852 -418.682353) (xy 311.146154 -418.641156) (xy 311.116683 -418.595299) (xy 311.094038 -418.545714)
			(xy 311.078681 -418.493411) (xy 311.070923 -418.439455) (xy 309.633413 -418.439455) (xy 309.625655 -418.493402)
			(xy 309.610299 -418.545698) (xy 309.587656 -418.595276) (xy 309.558187 -418.641127) (xy 309.522493 -418.682317)
			(xy 309.4813 -418.718008) (xy 309.435446 -418.747472) (xy 309.385866 -418.770111) (xy 309.333568 -418.785463)
			(xy 309.279618 -418.793215) (xy 309.252366 -418.793676) (xy 308.388766 -418.793676) (xy 308.361514 -418.793252)
			(xy 308.307565 -418.785491) (xy 308.25527 -418.770131) (xy 308.205693 -418.747486) (xy 308.159843 -418.718017)
			(xy 308.118654 -418.682322) (xy 308.082963 -418.641129) (xy 308.053497 -418.595277) (xy 308.030857 -418.545698)
			(xy 308.015502 -418.493401) (xy 308.007746 -418.439452) (xy 306.570089 -418.439452) (xy 306.562335 -418.493389)
			(xy 306.546982 -418.545677) (xy 306.524345 -418.595248) (xy 306.494884 -418.641093) (xy 306.459198 -418.682279)
			(xy 306.418014 -418.717968) (xy 306.372171 -418.747432) (xy 306.322601 -418.770073) (xy 306.270314 -418.785429)
			(xy 306.216374 -418.793188) (xy 306.189126 -418.793676) (xy 305.325526 -418.793676) (xy 305.29827 -418.793279)
			(xy 305.244311 -418.785524) (xy 305.192006 -418.770169) (xy 305.142418 -418.747526) (xy 305.096558 -418.718056)
			(xy 305.055359 -418.68236) (xy 305.019659 -418.641163) (xy 304.990186 -418.595305) (xy 304.96754 -418.545719)
			(xy 304.952181 -418.493414) (xy 304.944423 -418.439456) (xy 296.287698 -418.439456) (xy 296.287698 -418.60343)
			(xy 296.288127 -418.613498) (xy 296.295849 -418.632094) (xy 296.302684 -418.639498) (xy 298.642641 -420.979455)
			(xy 303.412823 -420.979455) (xy 303.412823 -420.924945) (xy 303.420581 -420.870989) (xy 303.435938 -420.818686)
			(xy 303.458583 -420.769101) (xy 303.488054 -420.723244) (xy 303.523752 -420.682047) (xy 303.564949 -420.646351)
			(xy 303.610806 -420.61688) (xy 303.660391 -420.594236) (xy 303.712694 -420.578879) (xy 303.766651 -420.571123)
			(xy 303.793906 -420.57066) (xy 304.657506 -420.57066) (xy 304.684755 -420.571211) (xy 304.738697 -420.578967)
			(xy 304.790987 -420.594321) (xy 304.840559 -420.616961) (xy 304.886405 -420.646425) (xy 304.927591 -420.682113)
			(xy 304.963279 -420.7233) (xy 304.992742 -420.769146) (xy 305.015381 -420.818719) (xy 305.030734 -420.871009)
			(xy 305.03849 -420.924951) (xy 305.03849 -420.979449) (xy 305.038489 -420.979457) (xy 306.476023 -420.979457)
			(xy 306.476023 -420.924943) (xy 306.483782 -420.870983) (xy 306.499142 -420.818677) (xy 306.521789 -420.76909)
			(xy 306.551264 -420.723231) (xy 306.586966 -420.682033) (xy 306.628167 -420.646337) (xy 306.67403 -420.616867)
			(xy 306.72362 -420.594225) (xy 306.775928 -420.578872) (xy 306.829889 -420.57112) (xy 306.857146 -420.57066)
			(xy 307.720746 -420.57066) (xy 307.747993 -420.571213) (xy 307.801931 -420.578975) (xy 307.854216 -420.594332)
			(xy 307.903783 -420.616974) (xy 307.949624 -420.646439) (xy 307.990805 -420.682128) (xy 308.026488 -420.723313)
			(xy 308.055948 -420.769157) (xy 308.078584 -420.818727) (xy 308.093935 -420.871014) (xy 308.10169 -420.924953)
			(xy 308.10169 -420.979447) (xy 308.101689 -420.979453) (xy 309.539346 -420.979453) (xy 309.539346 -420.924947)
			(xy 309.547103 -420.870996) (xy 309.562458 -420.818698) (xy 309.5851 -420.769118) (xy 309.614568 -420.723264)
			(xy 309.650261 -420.682071) (xy 309.691453 -420.646376) (xy 309.737305 -420.616907) (xy 309.786885 -420.594263)
			(xy 309.839182 -420.578906) (xy 309.893133 -420.571147) (xy 309.920386 -420.57066) (xy 310.783986 -420.57066)
			(xy 310.811237 -420.571186) (xy 310.865185 -420.578941) (xy 310.91748 -420.594295) (xy 310.967058 -420.616934)
			(xy 311.012909 -420.646399) (xy 311.0541 -420.68209) (xy 311.089792 -420.72328) (xy 311.119259 -420.76913)
			(xy 311.141901 -420.818707) (xy 311.157256 -420.871001) (xy 311.165013 -420.924949) (xy 311.165013 -420.979451)
			(xy 311.165012 -420.979456) (xy 312.602523 -420.979456) (xy 312.602523 -420.924944) (xy 312.610281 -420.870986)
			(xy 312.62564 -420.818681) (xy 312.648286 -420.769095) (xy 312.677759 -420.723237) (xy 312.713459 -420.68204)
			(xy 312.754658 -420.646344) (xy 312.800518 -420.616874) (xy 312.850106 -420.594231) (xy 312.902411 -420.578876)
			(xy 312.95637 -420.571121) (xy 312.983626 -420.57066) (xy 313.847226 -420.57066) (xy 313.874474 -420.571212)
			(xy 313.928414 -420.578971) (xy 313.980701 -420.594327) (xy 314.030271 -420.616968) (xy 314.076114 -420.646432)
			(xy 314.117298 -420.682121) (xy 314.152984 -420.723307) (xy 314.182445 -420.769152) (xy 314.205082 -420.818723)
			(xy 314.220435 -420.871011) (xy 314.22819 -420.924952) (xy 314.22819 -420.979448) (xy 314.228189 -420.979452)
			(xy 315.665846 -420.979452) (xy 315.665846 -420.924948) (xy 315.673602 -420.870999) (xy 315.688957 -420.818702)
			(xy 315.711597 -420.769123) (xy 315.741063 -420.723271) (xy 315.776754 -420.682078) (xy 315.817943 -420.646383)
			(xy 315.863793 -420.616914) (xy 315.91337 -420.594269) (xy 315.965665 -420.578909) (xy 316.019614 -420.571148)
			(xy 316.046866 -420.57066) (xy 316.910466 -420.57066) (xy 316.937718 -420.571185) (xy 316.991668 -420.578937)
			(xy 317.043966 -420.594289) (xy 317.093546 -420.616928) (xy 317.1394 -420.646392) (xy 317.180593 -420.682083)
			(xy 317.216287 -420.723273) (xy 317.245756 -420.769124) (xy 317.268399 -420.818702) (xy 317.283755 -420.870999)
			(xy 317.291513 -420.924948) (xy 317.291513 -420.979452) (xy 317.291513 -420.979455) (xy 318.729023 -420.979455)
			(xy 318.729023 -420.924945) (xy 318.736781 -420.870989) (xy 318.752138 -420.818686) (xy 318.774783 -420.769101)
			(xy 318.804254 -420.723244) (xy 318.839952 -420.682047) (xy 318.881149 -420.646351) (xy 318.927006 -420.61688)
			(xy 318.976591 -420.594236) (xy 319.028894 -420.578879) (xy 319.082851 -420.571123) (xy 319.110106 -420.57066)
			(xy 319.973706 -420.57066) (xy 320.000955 -420.571211) (xy 320.054897 -420.578967) (xy 320.107187 -420.594321)
			(xy 320.156759 -420.616961) (xy 320.202605 -420.646425) (xy 320.243791 -420.682113) (xy 320.279479 -420.7233)
			(xy 320.308942 -420.769146) (xy 320.331581 -420.818719) (xy 320.346934 -420.871009) (xy 320.35469 -420.924951)
			(xy 320.35469 -420.979449) (xy 320.354689 -420.979457) (xy 321.792223 -420.979457) (xy 321.792223 -420.924943)
			(xy 321.799982 -420.870983) (xy 321.815342 -420.818677) (xy 321.837989 -420.76909) (xy 321.867464 -420.723231)
			(xy 321.903166 -420.682033) (xy 321.944367 -420.646337) (xy 321.99023 -420.616867) (xy 322.03982 -420.594225)
			(xy 322.092128 -420.578872) (xy 322.146089 -420.57112) (xy 322.173346 -420.57066) (xy 323.036946 -420.57066)
			(xy 323.064193 -420.571213) (xy 323.118131 -420.578975) (xy 323.170416 -420.594332) (xy 323.219983 -420.616974)
			(xy 323.265824 -420.646439) (xy 323.307005 -420.682128) (xy 323.342688 -420.723313) (xy 323.372148 -420.769157)
			(xy 323.394784 -420.818727) (xy 323.410135 -420.871014) (xy 323.41789 -420.924953) (xy 323.41789 -420.979447)
			(xy 323.417889 -420.979453) (xy 324.855546 -420.979453) (xy 324.855546 -420.924947) (xy 324.863303 -420.870996)
			(xy 324.878658 -420.818698) (xy 324.9013 -420.769118) (xy 324.930768 -420.723264) (xy 324.966461 -420.682071)
			(xy 325.007653 -420.646376) (xy 325.053505 -420.616907) (xy 325.103085 -420.594263) (xy 325.155382 -420.578906)
			(xy 325.209333 -420.571147) (xy 325.236586 -420.57066) (xy 326.100186 -420.57066) (xy 326.127437 -420.571186)
			(xy 326.181385 -420.578941) (xy 326.23368 -420.594295) (xy 326.283258 -420.616934) (xy 326.329109 -420.646399)
			(xy 326.3703 -420.68209) (xy 326.405992 -420.72328) (xy 326.435459 -420.76913) (xy 326.458101 -420.818707)
			(xy 326.473456 -420.871001) (xy 326.481213 -420.924949) (xy 326.481213 -420.979451) (xy 326.481212 -420.979456)
			(xy 327.918723 -420.979456) (xy 327.918723 -420.924944) (xy 327.926481 -420.870986) (xy 327.94184 -420.818681)
			(xy 327.964486 -420.769095) (xy 327.993959 -420.723237) (xy 328.029659 -420.68204) (xy 328.070858 -420.646344)
			(xy 328.116718 -420.616874) (xy 328.166306 -420.594231) (xy 328.218611 -420.578876) (xy 328.27257 -420.571121)
			(xy 328.299826 -420.57066) (xy 329.163426 -420.57066) (xy 329.190674 -420.571212) (xy 329.244614 -420.578971)
			(xy 329.296901 -420.594327) (xy 329.346471 -420.616968) (xy 329.392314 -420.646432) (xy 329.433498 -420.682121)
			(xy 329.469184 -420.723307) (xy 329.498645 -420.769152) (xy 329.521282 -420.818723) (xy 329.536635 -420.871011)
			(xy 329.54439 -420.924952) (xy 329.54439 -420.979448) (xy 329.544389 -420.979452) (xy 330.982046 -420.979452)
			(xy 330.982046 -420.924948) (xy 330.989802 -420.870999) (xy 331.005157 -420.818702) (xy 331.027797 -420.769123)
			(xy 331.057263 -420.723271) (xy 331.092954 -420.682078) (xy 331.134143 -420.646383) (xy 331.179993 -420.616914)
			(xy 331.22957 -420.594269) (xy 331.281865 -420.578909) (xy 331.335814 -420.571148) (xy 331.363066 -420.57066)
			(xy 332.226666 -420.57066) (xy 332.253918 -420.571185) (xy 332.307868 -420.578937) (xy 332.360166 -420.594289)
			(xy 332.409746 -420.616928) (xy 332.4556 -420.646392) (xy 332.496793 -420.682083) (xy 332.532487 -420.723273)
			(xy 332.561956 -420.769124) (xy 332.584599 -420.818702) (xy 332.599955 -420.870999) (xy 332.607713 -420.924948)
			(xy 332.607713 -420.979452) (xy 332.607713 -420.979455) (xy 334.045223 -420.979455) (xy 334.045223 -420.924945)
			(xy 334.052981 -420.870989) (xy 334.068338 -420.818686) (xy 334.090983 -420.769101) (xy 334.120454 -420.723244)
			(xy 334.156152 -420.682047) (xy 334.197349 -420.646351) (xy 334.243206 -420.61688) (xy 334.292791 -420.594236)
			(xy 334.345094 -420.578879) (xy 334.399051 -420.571123) (xy 334.426306 -420.57066) (xy 335.289906 -420.57066)
			(xy 335.317155 -420.571211) (xy 335.371097 -420.578967) (xy 335.423387 -420.594321) (xy 335.472959 -420.616961)
			(xy 335.518805 -420.646425) (xy 335.559991 -420.682113) (xy 335.595679 -420.7233) (xy 335.625142 -420.769146)
			(xy 335.647781 -420.818719) (xy 335.663134 -420.871009) (xy 335.67089 -420.924951) (xy 335.67089 -420.979449)
			(xy 335.670889 -420.979457) (xy 337.108423 -420.979457) (xy 337.108423 -420.924943) (xy 337.116182 -420.870983)
			(xy 337.131542 -420.818677) (xy 337.154189 -420.76909) (xy 337.183664 -420.723231) (xy 337.219366 -420.682033)
			(xy 337.260567 -420.646337) (xy 337.30643 -420.616867) (xy 337.35602 -420.594225) (xy 337.408328 -420.578872)
			(xy 337.462289 -420.57112) (xy 337.489546 -420.57066) (xy 338.353146 -420.57066) (xy 338.380393 -420.571213)
			(xy 338.434331 -420.578975) (xy 338.486616 -420.594332) (xy 338.536183 -420.616974) (xy 338.582024 -420.646439)
			(xy 338.623205 -420.682128) (xy 338.658888 -420.723313) (xy 338.688348 -420.769157) (xy 338.710984 -420.818727)
			(xy 338.726335 -420.871014) (xy 338.73409 -420.924953) (xy 338.73409 -420.979447) (xy 338.734089 -420.979453)
			(xy 340.171746 -420.979453) (xy 340.171746 -420.924947) (xy 340.179503 -420.870996) (xy 340.194858 -420.818698)
			(xy 340.2175 -420.769118) (xy 340.246968 -420.723264) (xy 340.282661 -420.682071) (xy 340.323853 -420.646376)
			(xy 340.369705 -420.616907) (xy 340.419285 -420.594263) (xy 340.471582 -420.578906) (xy 340.525533 -420.571147)
			(xy 340.552786 -420.57066) (xy 341.416386 -420.57066) (xy 341.443637 -420.571186) (xy 341.497585 -420.578941)
			(xy 341.54988 -420.594295) (xy 341.599458 -420.616934) (xy 341.645309 -420.646399) (xy 341.6865 -420.68209)
			(xy 341.722192 -420.72328) (xy 341.751659 -420.76913) (xy 341.774301 -420.818707) (xy 341.789656 -420.871001)
			(xy 341.797413 -420.924949) (xy 341.797413 -420.979451) (xy 341.797412 -420.979456) (xy 343.234923 -420.979456)
			(xy 343.234923 -420.924944) (xy 343.242681 -420.870986) (xy 343.25804 -420.818681) (xy 343.280686 -420.769095)
			(xy 343.310159 -420.723237) (xy 343.345859 -420.68204) (xy 343.387058 -420.646344) (xy 343.432918 -420.616874)
			(xy 343.482506 -420.594231) (xy 343.534811 -420.578876) (xy 343.58877 -420.571121) (xy 343.616026 -420.57066)
			(xy 344.479626 -420.57066) (xy 344.506874 -420.571212) (xy 344.560814 -420.578971) (xy 344.613101 -420.594327)
			(xy 344.662671 -420.616968) (xy 344.708514 -420.646432) (xy 344.749698 -420.682121) (xy 344.785384 -420.723307)
			(xy 344.814845 -420.769152) (xy 344.837482 -420.818723) (xy 344.852835 -420.871011) (xy 344.86059 -420.924952)
			(xy 344.86059 -420.979448) (xy 344.860589 -420.979452) (xy 346.298246 -420.979452) (xy 346.298246 -420.924948)
			(xy 346.306002 -420.870999) (xy 346.321357 -420.818702) (xy 346.343997 -420.769123) (xy 346.373463 -420.723271)
			(xy 346.409154 -420.682078) (xy 346.450343 -420.646383) (xy 346.496193 -420.616914) (xy 346.54577 -420.594269)
			(xy 346.598065 -420.578909) (xy 346.652014 -420.571148) (xy 346.679266 -420.57066) (xy 347.542866 -420.57066)
			(xy 347.570118 -420.571185) (xy 347.624068 -420.578937) (xy 347.676366 -420.594289) (xy 347.725946 -420.616928)
			(xy 347.7718 -420.646392) (xy 347.812993 -420.682083) (xy 347.848687 -420.723273) (xy 347.878156 -420.769124)
			(xy 347.900799 -420.818702) (xy 347.916155 -420.870999) (xy 347.923913 -420.924948) (xy 347.923913 -420.979452)
			(xy 347.923913 -420.979455) (xy 349.361423 -420.979455) (xy 349.361423 -420.924945) (xy 349.369181 -420.870989)
			(xy 349.384538 -420.818686) (xy 349.407183 -420.769101) (xy 349.436654 -420.723244) (xy 349.472352 -420.682047)
			(xy 349.513549 -420.646351) (xy 349.559406 -420.61688) (xy 349.608991 -420.594236) (xy 349.661294 -420.578879)
			(xy 349.715251 -420.571123) (xy 349.742506 -420.57066) (xy 350.606106 -420.57066) (xy 350.633355 -420.571211)
			(xy 350.687297 -420.578967) (xy 350.739587 -420.594321) (xy 350.789159 -420.616961) (xy 350.835005 -420.646425)
			(xy 350.876191 -420.682113) (xy 350.911879 -420.7233) (xy 350.941342 -420.769146) (xy 350.963981 -420.818719)
			(xy 350.979334 -420.871009) (xy 350.98709 -420.924951) (xy 350.98709 -420.979449) (xy 350.979334 -421.033391)
			(xy 350.963981 -421.085681) (xy 350.941342 -421.135254) (xy 350.911879 -421.1811) (xy 350.876191 -421.222287)
			(xy 350.835005 -421.257975) (xy 350.789159 -421.287439) (xy 350.739587 -421.310079) (xy 350.687297 -421.325433)
			(xy 350.633355 -421.333189) (xy 350.606106 -421.333676) (xy 349.742506 -421.333676) (xy 349.715251 -421.333277)
			(xy 349.661294 -421.325521) (xy 349.608991 -421.310164) (xy 349.559406 -421.28752) (xy 349.513549 -421.258049)
			(xy 349.472352 -421.222353) (xy 349.436654 -421.181156) (xy 349.407183 -421.135299) (xy 349.384538 -421.085714)
			(xy 349.369181 -421.033411) (xy 349.361423 -420.979455) (xy 347.923913 -420.979455) (xy 347.916155 -421.033402)
			(xy 347.900799 -421.085698) (xy 347.878156 -421.135276) (xy 347.848687 -421.181127) (xy 347.812993 -421.222317)
			(xy 347.7718 -421.258008) (xy 347.725946 -421.287472) (xy 347.676366 -421.310111) (xy 347.624068 -421.325463)
			(xy 347.570118 -421.333215) (xy 347.542866 -421.333676) (xy 346.679266 -421.333676) (xy 346.652014 -421.333252)
			(xy 346.598065 -421.325491) (xy 346.54577 -421.310131) (xy 346.496193 -421.287486) (xy 346.450343 -421.258017)
			(xy 346.409154 -421.222322) (xy 346.373463 -421.181129) (xy 346.343997 -421.135277) (xy 346.321357 -421.085698)
			(xy 346.306002 -421.033401) (xy 346.298246 -420.979452) (xy 344.860589 -420.979452) (xy 344.852835 -421.033389)
			(xy 344.837482 -421.085677) (xy 344.814845 -421.135248) (xy 344.785384 -421.181093) (xy 344.749698 -421.222279)
			(xy 344.708514 -421.257968) (xy 344.662671 -421.287432) (xy 344.613101 -421.310073) (xy 344.560814 -421.325429)
			(xy 344.506874 -421.333188) (xy 344.479626 -421.333676) (xy 343.616026 -421.333676) (xy 343.58877 -421.333279)
			(xy 343.534811 -421.325524) (xy 343.482506 -421.310169) (xy 343.432918 -421.287526) (xy 343.387058 -421.258056)
			(xy 343.345859 -421.22236) (xy 343.310159 -421.181163) (xy 343.280686 -421.135305) (xy 343.25804 -421.085719)
			(xy 343.242681 -421.033414) (xy 343.234923 -420.979456) (xy 341.797412 -420.979456) (xy 341.789656 -421.033399)
			(xy 341.774301 -421.085693) (xy 341.751659 -421.13527) (xy 341.722192 -421.18112) (xy 341.6865 -421.22231)
			(xy 341.645309 -421.258001) (xy 341.599458 -421.287466) (xy 341.54988 -421.310105) (xy 341.497585 -421.325459)
			(xy 341.443637 -421.333214) (xy 341.416386 -421.333676) (xy 340.552786 -421.333676) (xy 340.525533 -421.333253)
			(xy 340.471582 -421.325494) (xy 340.419285 -421.310137) (xy 340.369705 -421.287493) (xy 340.323853 -421.258024)
			(xy 340.282661 -421.222329) (xy 340.246968 -421.181136) (xy 340.2175 -421.135282) (xy 340.194858 -421.085702)
			(xy 340.179503 -421.033404) (xy 340.171746 -420.979453) (xy 338.734089 -420.979453) (xy 338.726335 -421.033386)
			(xy 338.710984 -421.085673) (xy 338.688348 -421.135243) (xy 338.658888 -421.181087) (xy 338.623205 -421.222272)
			(xy 338.582024 -421.257961) (xy 338.536183 -421.287426) (xy 338.486616 -421.310068) (xy 338.434331 -421.325425)
			(xy 338.380393 -421.333187) (xy 338.353146 -421.333676) (xy 337.489546 -421.333676) (xy 337.462289 -421.33328)
			(xy 337.408328 -421.325528) (xy 337.35602 -421.310175) (xy 337.30643 -421.287533) (xy 337.260567 -421.258063)
			(xy 337.219366 -421.222367) (xy 337.183664 -421.181169) (xy 337.154189 -421.13531) (xy 337.131542 -421.085723)
			(xy 337.116182 -421.033417) (xy 337.108423 -420.979457) (xy 335.670889 -420.979457) (xy 335.663134 -421.033391)
			(xy 335.647781 -421.085681) (xy 335.625142 -421.135254) (xy 335.595679 -421.1811) (xy 335.559991 -421.222287)
			(xy 335.518805 -421.257975) (xy 335.472959 -421.287439) (xy 335.423387 -421.310079) (xy 335.371097 -421.325433)
			(xy 335.317155 -421.333189) (xy 335.289906 -421.333676) (xy 334.426306 -421.333676) (xy 334.399051 -421.333277)
			(xy 334.345094 -421.325521) (xy 334.292791 -421.310164) (xy 334.243206 -421.28752) (xy 334.197349 -421.258049)
			(xy 334.156152 -421.222353) (xy 334.120454 -421.181156) (xy 334.090983 -421.135299) (xy 334.068338 -421.085714)
			(xy 334.052981 -421.033411) (xy 334.045223 -420.979455) (xy 332.607713 -420.979455) (xy 332.599955 -421.033402)
			(xy 332.584599 -421.085698) (xy 332.561956 -421.135276) (xy 332.532487 -421.181127) (xy 332.496793 -421.222317)
			(xy 332.4556 -421.258008) (xy 332.409746 -421.287472) (xy 332.360166 -421.310111) (xy 332.307868 -421.325463)
			(xy 332.253918 -421.333215) (xy 332.226666 -421.333676) (xy 331.363066 -421.333676) (xy 331.335814 -421.333252)
			(xy 331.281865 -421.325491) (xy 331.22957 -421.310131) (xy 331.179993 -421.287486) (xy 331.134143 -421.258017)
			(xy 331.092954 -421.222322) (xy 331.057263 -421.181129) (xy 331.027797 -421.135277) (xy 331.005157 -421.085698)
			(xy 330.989802 -421.033401) (xy 330.982046 -420.979452) (xy 329.544389 -420.979452) (xy 329.536635 -421.033389)
			(xy 329.521282 -421.085677) (xy 329.498645 -421.135248) (xy 329.469184 -421.181093) (xy 329.433498 -421.222279)
			(xy 329.392314 -421.257968) (xy 329.346471 -421.287432) (xy 329.296901 -421.310073) (xy 329.244614 -421.325429)
			(xy 329.190674 -421.333188) (xy 329.163426 -421.333676) (xy 328.299826 -421.333676) (xy 328.27257 -421.333279)
			(xy 328.218611 -421.325524) (xy 328.166306 -421.310169) (xy 328.116718 -421.287526) (xy 328.070858 -421.258056)
			(xy 328.029659 -421.22236) (xy 327.993959 -421.181163) (xy 327.964486 -421.135305) (xy 327.94184 -421.085719)
			(xy 327.926481 -421.033414) (xy 327.918723 -420.979456) (xy 326.481212 -420.979456) (xy 326.473456 -421.033399)
			(xy 326.458101 -421.085693) (xy 326.435459 -421.13527) (xy 326.405992 -421.18112) (xy 326.3703 -421.22231)
			(xy 326.329109 -421.258001) (xy 326.283258 -421.287466) (xy 326.23368 -421.310105) (xy 326.181385 -421.325459)
			(xy 326.127437 -421.333214) (xy 326.100186 -421.333676) (xy 325.236586 -421.333676) (xy 325.209333 -421.333253)
			(xy 325.155382 -421.325494) (xy 325.103085 -421.310137) (xy 325.053505 -421.287493) (xy 325.007653 -421.258024)
			(xy 324.966461 -421.222329) (xy 324.930768 -421.181136) (xy 324.9013 -421.135282) (xy 324.878658 -421.085702)
			(xy 324.863303 -421.033404) (xy 324.855546 -420.979453) (xy 323.417889 -420.979453) (xy 323.410135 -421.033386)
			(xy 323.394784 -421.085673) (xy 323.372148 -421.135243) (xy 323.342688 -421.181087) (xy 323.307005 -421.222272)
			(xy 323.265824 -421.257961) (xy 323.219983 -421.287426) (xy 323.170416 -421.310068) (xy 323.118131 -421.325425)
			(xy 323.064193 -421.333187) (xy 323.036946 -421.333676) (xy 322.173346 -421.333676) (xy 322.146089 -421.33328)
			(xy 322.092128 -421.325528) (xy 322.03982 -421.310175) (xy 321.99023 -421.287533) (xy 321.944367 -421.258063)
			(xy 321.903166 -421.222367) (xy 321.867464 -421.181169) (xy 321.837989 -421.13531) (xy 321.815342 -421.085723)
			(xy 321.799982 -421.033417) (xy 321.792223 -420.979457) (xy 320.354689 -420.979457) (xy 320.346934 -421.033391)
			(xy 320.331581 -421.085681) (xy 320.308942 -421.135254) (xy 320.279479 -421.1811) (xy 320.243791 -421.222287)
			(xy 320.202605 -421.257975) (xy 320.156759 -421.287439) (xy 320.107187 -421.310079) (xy 320.054897 -421.325433)
			(xy 320.000955 -421.333189) (xy 319.973706 -421.333676) (xy 319.110106 -421.333676) (xy 319.082851 -421.333277)
			(xy 319.028894 -421.325521) (xy 318.976591 -421.310164) (xy 318.927006 -421.28752) (xy 318.881149 -421.258049)
			(xy 318.839952 -421.222353) (xy 318.804254 -421.181156) (xy 318.774783 -421.135299) (xy 318.752138 -421.085714)
			(xy 318.736781 -421.033411) (xy 318.729023 -420.979455) (xy 317.291513 -420.979455) (xy 317.283755 -421.033402)
			(xy 317.268399 -421.085698) (xy 317.245756 -421.135276) (xy 317.216287 -421.181127) (xy 317.180593 -421.222317)
			(xy 317.1394 -421.258008) (xy 317.093546 -421.287472) (xy 317.043966 -421.310111) (xy 316.991668 -421.325463)
			(xy 316.937718 -421.333215) (xy 316.910466 -421.333676) (xy 316.046866 -421.333676) (xy 316.019614 -421.333252)
			(xy 315.965665 -421.325491) (xy 315.91337 -421.310131) (xy 315.863793 -421.287486) (xy 315.817943 -421.258017)
			(xy 315.776754 -421.222322) (xy 315.741063 -421.181129) (xy 315.711597 -421.135277) (xy 315.688957 -421.085698)
			(xy 315.673602 -421.033401) (xy 315.665846 -420.979452) (xy 314.228189 -420.979452) (xy 314.220435 -421.033389)
			(xy 314.205082 -421.085677) (xy 314.182445 -421.135248) (xy 314.152984 -421.181093) (xy 314.117298 -421.222279)
			(xy 314.076114 -421.257968) (xy 314.030271 -421.287432) (xy 313.980701 -421.310073) (xy 313.928414 -421.325429)
			(xy 313.874474 -421.333188) (xy 313.847226 -421.333676) (xy 312.983626 -421.333676) (xy 312.95637 -421.333279)
			(xy 312.902411 -421.325524) (xy 312.850106 -421.310169) (xy 312.800518 -421.287526) (xy 312.754658 -421.258056)
			(xy 312.713459 -421.22236) (xy 312.677759 -421.181163) (xy 312.648286 -421.135305) (xy 312.62564 -421.085719)
			(xy 312.610281 -421.033414) (xy 312.602523 -420.979456) (xy 311.165012 -420.979456) (xy 311.157256 -421.033399)
			(xy 311.141901 -421.085693) (xy 311.119259 -421.13527) (xy 311.089792 -421.18112) (xy 311.0541 -421.22231)
			(xy 311.012909 -421.258001) (xy 310.967058 -421.287466) (xy 310.91748 -421.310105) (xy 310.865185 -421.325459)
			(xy 310.811237 -421.333214) (xy 310.783986 -421.333676) (xy 309.920386 -421.333676) (xy 309.893133 -421.333253)
			(xy 309.839182 -421.325494) (xy 309.786885 -421.310137) (xy 309.737305 -421.287493) (xy 309.691453 -421.258024)
			(xy 309.650261 -421.222329) (xy 309.614568 -421.181136) (xy 309.5851 -421.135282) (xy 309.562458 -421.085702)
			(xy 309.547103 -421.033404) (xy 309.539346 -420.979453) (xy 308.101689 -420.979453) (xy 308.093935 -421.033386)
			(xy 308.078584 -421.085673) (xy 308.055948 -421.135243) (xy 308.026488 -421.181087) (xy 307.990805 -421.222272)
			(xy 307.949624 -421.257961) (xy 307.903783 -421.287426) (xy 307.854216 -421.310068) (xy 307.801931 -421.325425)
			(xy 307.747993 -421.333187) (xy 307.720746 -421.333676) (xy 306.857146 -421.333676) (xy 306.829889 -421.33328)
			(xy 306.775928 -421.325528) (xy 306.72362 -421.310175) (xy 306.67403 -421.287533) (xy 306.628167 -421.258063)
			(xy 306.586966 -421.222367) (xy 306.551264 -421.181169) (xy 306.521789 -421.13531) (xy 306.499142 -421.085723)
			(xy 306.483782 -421.033417) (xy 306.476023 -420.979457) (xy 305.038489 -420.979457) (xy 305.030734 -421.033391)
			(xy 305.015381 -421.085681) (xy 304.992742 -421.135254) (xy 304.963279 -421.1811) (xy 304.927591 -421.222287)
			(xy 304.886405 -421.257975) (xy 304.840559 -421.287439) (xy 304.790987 -421.310079) (xy 304.738697 -421.325433)
			(xy 304.684755 -421.333189) (xy 304.657506 -421.333676) (xy 303.793906 -421.333676) (xy 303.766651 -421.333277)
			(xy 303.712694 -421.325521) (xy 303.660391 -421.310164) (xy 303.610806 -421.28752) (xy 303.564949 -421.258049)
			(xy 303.523752 -421.222353) (xy 303.488054 -421.181156) (xy 303.458583 -421.135299) (xy 303.435938 -421.085714)
			(xy 303.420581 -421.033411) (xy 303.412823 -420.979455) (xy 298.642641 -420.979455) (xy 299.516292 -421.853106)
			(xy 299.52369 -421.859953) (xy 299.542288 -421.867689) (xy 299.55236 -421.868092)
		)
		(stroke
			(width 0)
			(type solid)
		)
		(fill yes)
		(layer "In9.Cu")
		(net "P0V9_CPU0_RT_2D")
	)
	(gr_poly
		(pts
			(xy 102.608888 -413.510476) (xy 102.615238 -413.497522) (xy 102.628255 -413.47246) (xy 102.660557 -413.426138)
			(xy 102.699336 -413.385085) (xy 102.743744 -413.350198) (xy 102.792811 -413.32224) (xy 102.845463 -413.301822)
			(xy 102.90055 -413.289389) (xy 102.956868 -413.285215) (xy 103.013186 -413.289389) (xy 103.068273 -413.301822)
			(xy 103.120925 -413.32224) (xy 103.169992 -413.350198) (xy 103.2144 -413.385085) (xy 103.253179 -413.426138)
			(xy 103.285481 -413.47246) (xy 103.298498 -413.497522) (xy 103.304848 -413.510476) (xy 103.329486 -413.525716)
			(xy 105.527602 -413.525716) (xy 105.537481 -413.525259) (xy 105.555785 -413.517822) (xy 105.563162 -413.511238)
			(xy 105.621074 -413.454342) (xy 105.628948 -413.436308) (xy 105.629202 -413.426402) (xy 105.630213 -413.399517)
			(xy 105.638859 -413.346416) (xy 105.654881 -413.295057) (xy 105.677959 -413.246458) (xy 105.707636 -413.201584)
			(xy 105.743324 -413.161325) (xy 105.784315 -413.126479) (xy 105.829794 -413.097738) (xy 105.878861 -413.075673)
			(xy 105.930541 -413.06072) (xy 105.98381 -413.053176) (xy 106.01071 -413.052768) (xy 106.87431 -413.052768)
			(xy 106.901206 -413.053229) (xy 106.954466 -413.060784) (xy 107.006137 -413.075744) (xy 107.055196 -413.097811)
			(xy 107.100669 -413.126549) (xy 107.141656 -413.161387) (xy 107.177345 -413.201636) (xy 107.207028 -413.246498)
			(xy 107.230118 -413.295084) (xy 107.246156 -413.346431) (xy 107.254824 -413.39952) (xy 107.255818 -413.426402)
			(xy 107.256072 -413.436308) (xy 107.263946 -413.454342) (xy 107.321858 -413.511238) (xy 107.329239 -413.517821)
			(xy 107.347538 -413.525272) (xy 107.357418 -413.525716) (xy 116.035582 -413.525716) (xy 116.041932 -413.523938)
			(xy 116.065758 -413.518078) (xy 116.114426 -413.511829) (xy 116.13896 -413.511492) (xy 116.163491 -413.511873)
			(xy 116.212155 -413.518114) (xy 116.235988 -413.523938) (xy 116.242338 -413.525716) (xy 163.41979 -413.525716)
			(xy 163.429861 -413.525295) (xy 163.44847 -413.517585) (xy 163.455858 -413.51073) (xy 164.537644 -412.428944)
			(xy 164.543596 -412.42256) (xy 164.551134 -412.406831) (xy 164.552898 -412.389479) (xy 164.551106 -412.380938)
			(xy 164.551106 -412.380684) (xy 164.545875 -412.358122) (xy 164.540275 -412.312147) (xy 164.53993 -412.28899)
			(xy 164.540444 -412.260806) (xy 164.548755 -412.205053) (xy 164.565181 -412.151131) (xy 164.589362 -412.100212)
			(xy 164.620773 -412.053407) (xy 164.65873 -412.011733) (xy 164.702407 -411.976099) (xy 164.750852 -411.94728)
			(xy 164.80301 -411.925904) (xy 164.830252 -411.918658) (xy 164.830506 -411.918658) (xy 164.841284 -411.915329)
			(xy 164.858686 -411.90102) (xy 164.868305 -411.880647) (xy 164.86886 -411.869382) (xy 164.86886 -402.372576)
			(xy 164.868431 -402.362509) (xy 164.860706 -402.343914) (xy 164.853874 -402.336508) (xy 162.454844 -399.937478)
			(xy 162.445494 -399.928984) (xy 162.42136 -399.921632) (xy 162.40887 -399.923508) (xy 162.391714 -399.926717)
			(xy 162.35698 -399.930152) (xy 162.339528 -399.930366) (xy 162.311542 -399.929848) (xy 162.25626 -399.921095)
			(xy 162.203028 -399.903801) (xy 162.153156 -399.878392) (xy 162.107875 -399.845493) (xy 162.068298 -399.805914)
			(xy 162.035401 -399.760632) (xy 162.009994 -399.710759) (xy 161.992702 -399.657526) (xy 161.983951 -399.602244)
			(xy 161.98342 -399.574258) (xy 161.983648 -399.556807) (xy 161.987087 -399.522074) (xy 161.990278 -399.504916)
			(xy 161.992087 -399.492426) (xy 161.984768 -399.468305) (xy 161.976308 -399.458942) (xy 160.570672 -398.053306)
			(xy 160.553416 -398.035264) (xy 160.525665 -397.993769) (xy 160.506559 -397.947651) (xy 160.496836 -397.898688)
			(xy 160.49625 -397.873728) (xy 160.49625 -394.253466) (xy 160.495895 -394.244767) (xy 160.490073 -394.228371)
			(xy 160.47911 -394.214861) (xy 160.471866 -394.210032) (xy 160.451483 -394.197058) (xy 160.414364 -394.166131)
			(xy 160.382141 -394.13013) (xy 160.3555 -394.089823) (xy 160.33501 -394.046069) (xy 160.321105 -393.999798)
			(xy 160.314082 -393.951996) (xy 160.313624 -393.927838) (xy 160.314026 -393.90444) (xy 160.320612 -393.85811)
			(xy 160.333658 -393.813169) (xy 160.352905 -393.770514) (xy 160.377968 -393.730995) (xy 160.392872 -393.712954)
			(xy 160.399222 -393.705334) (xy 160.405572 -393.687046) (xy 160.401 -393.606782) (xy 160.399978 -393.597069)
			(xy 160.39161 -393.579439) (xy 160.384744 -393.572492) (xy 160.365873 -393.554365) (xy 160.332769 -393.513842)
			(xy 160.305507 -393.469178) (xy 160.2846 -393.42121) (xy 160.270439 -393.370836) (xy 160.263289 -393.319001)
			(xy 160.262824 -393.292838) (xy 160.262824 -392.428984) (xy 160.263262 -392.402655) (xy 160.270497 -392.350496)
			(xy 160.28484 -392.29983) (xy 160.30602 -392.251619) (xy 160.333633 -392.206782) (xy 160.367153 -392.166171)
			(xy 160.386268 -392.14806) (xy 160.393126 -392.14171) (xy 160.401508 -392.124946) (xy 160.408874 -392.047476)
			(xy 160.409367 -392.038302) (xy 160.404557 -392.020585) (xy 160.399476 -392.012932) (xy 160.399222 -392.012678)
			(xy 160.385066 -391.992833) (xy 160.362582 -391.949584) (xy 160.347265 -391.903309) (xy 160.339507 -391.855186)
			(xy 160.339024 -391.830814) (xy 160.339524 -391.80591) (xy 160.347624 -391.756764) (xy 160.363594 -391.709585)
			(xy 160.387012 -391.665624) (xy 160.417256 -391.626048) (xy 160.453524 -391.591907) (xy 160.473898 -391.577576)
			(xy 160.483925 -391.570052) (xy 160.49566 -391.547934) (xy 160.49625 -391.535412) (xy 160.49625 -389.18642)
			(xy 160.496058 -389.179751) (xy 160.49259 -389.166874) (xy 160.489392 -389.16102) (xy 160.35147 -388.922006)
			(xy 160.339571 -388.899338) (xy 160.322695 -388.851007) (xy 160.314133 -388.800536) (xy 160.313624 -388.77494)
			(xy 160.313624 -388.774432) (xy 160.314051 -388.751262) (xy 160.321045 -388.705453) (xy 160.334878 -388.661226)
			(xy 160.355232 -388.619596) (xy 160.381641 -388.581518) (xy 160.413498 -388.547865) (xy 160.450072 -388.51941)
			(xy 160.470088 -388.507732) (xy 160.48228 -388.501128) (xy 160.49625 -388.477252) (xy 160.49625 -388.097776)
			(xy 160.495819 -388.086959) (xy 160.487004 -388.067211) (xy 160.479232 -388.059676) (xy 160.422336 -388.00913)
			(xy 160.414031 -388.002375) (xy 160.393642 -387.995912) (xy 160.382966 -387.996684) (xy 160.382458 -387.996684)
			(xy 160.373414 -387.997733) (xy 160.35524 -387.998879) (xy 160.346136 -387.99897) (xy 160.322142 -387.998526)
			(xy 160.274744 -387.991024) (xy 160.229104 -387.976198) (xy 160.186346 -387.954414) (xy 160.147523 -387.926208)
			(xy 160.11359 -387.892276) (xy 160.085385 -387.853452) (xy 160.063601 -387.810694) (xy 160.048776 -387.765054)
			(xy 160.041273 -387.717656) (xy 160.040828 -387.693662) (xy 160.040828 -387.693154) (xy 160.041426 -387.666537)
			(xy 160.050696 -387.614115) (xy 160.068912 -387.564094) (xy 160.081722 -387.540754) (xy 160.08681 -387.530798)
			(xy 160.088749 -387.50855) (xy 160.081105 -387.487567) (xy 160.073594 -387.479286) (xy 159.344106 -386.749798)
			(xy 159.336708 -386.742951) (xy 159.31811 -386.735214) (xy 159.308038 -386.734812) (xy 159.179514 -386.734812)
			(xy 159.167576 -386.73786) (xy 159.161988 -386.740908) (xy 159.137914 -386.75312) (xy 159.086785 -386.770423)
			(xy 159.033528 -386.77921) (xy 159.00654 -386.77977) (xy 159.006286 -386.77977) (xy 158.971234 -386.777992)
			(xy 158.959911 -386.777408) (xy 158.938553 -386.784929) (xy 158.930086 -386.79247) (xy 158.21533 -387.507226)
			(xy 158.21025 -387.539992) (xy 158.21787 -387.55447) (xy 158.228439 -387.576088) (xy 158.243381 -387.621828)
			(xy 158.250945 -387.669349) (xy 158.251398 -387.693408) (xy 158.251398 -387.693662) (xy 158.250955 -387.717657)
			(xy 158.243453 -387.765056) (xy 158.228627 -387.810698) (xy 158.206844 -387.853459) (xy 158.178639 -387.892285)
			(xy 158.144706 -387.92622) (xy 158.105883 -387.954429) (xy 158.063124 -387.976217) (xy 158.017484 -387.991046)
			(xy 157.970085 -387.998552) (xy 157.94609 -387.99897) (xy 157.945836 -387.99897) (xy 157.92178 -387.998494)
			(xy 157.874267 -387.99091) (xy 157.828527 -387.975985) (xy 157.806898 -387.965442) (xy 157.79242 -387.957822)
			(xy 157.759654 -387.962902) (xy 157.223714 -388.498842) (xy 157.22346 -388.499096) (xy 157.220666 -388.50189)
			(xy 157.220666 -388.544054) (xy 157.235398 -388.558786) (xy 157.25177 -388.575866) (xy 157.279576 -388.614142)
			(xy 157.29077 -388.634986) (xy 157.291278 -388.636002) (xy 157.371584 -388.77494) (xy 157.913324 -388.77494)
			(xy 157.913324 -388.774432) (xy 157.913791 -388.750453) (xy 157.921286 -388.703083) (xy 157.936095 -388.657469)
			(xy 157.957855 -388.614731) (xy 157.986031 -388.575922) (xy 158.019929 -388.541996) (xy 158.058714 -388.513788)
			(xy 158.101434 -388.491993) (xy 158.147036 -388.477145) (xy 158.194399 -388.469611) (xy 158.218378 -388.469124)
			(xy 158.218886 -388.469124) (xy 158.242823 -388.469534) (xy 158.290112 -388.476998) (xy 158.335657 -388.491748)
			(xy 158.378345 -388.51342) (xy 158.41713 -388.541485) (xy 158.451064 -388.575256) (xy 158.479314 -388.613907)
			(xy 158.490666 -388.634986) (xy 158.491174 -388.636002) (xy 158.57148 -388.77494) (xy 159.113728 -388.77494)
			(xy 159.113728 -388.774432) (xy 159.114168 -388.750438) (xy 159.121671 -388.70304) (xy 159.136497 -388.6574)
			(xy 159.158282 -388.614641) (xy 159.186488 -388.575818) (xy 159.220421 -388.541885) (xy 159.259245 -388.51368)
			(xy 159.302004 -388.491896) (xy 159.347644 -388.47707) (xy 159.395042 -388.469568) (xy 159.419036 -388.469124)
			(xy 159.442972 -388.469574) (xy 159.490258 -388.477031) (xy 159.535803 -388.491773) (xy 159.578491 -388.513439)
			(xy 159.617277 -388.541498) (xy 159.651211 -388.575264) (xy 159.679463 -388.613909) (xy 159.690816 -388.634986)
			(xy 159.691324 -388.636002) (xy 160.083754 -389.314944) (xy 160.096562 -389.338285) (xy 160.114788 -389.388304)
			(xy 160.124055 -389.440726) (xy 160.124648 -389.467344) (xy 160.124179 -389.491322) (xy 160.116676 -389.538687)
			(xy 160.10186 -389.584296) (xy 160.080097 -389.627029) (xy 160.051921 -389.665835) (xy 160.018025 -389.699758)
			(xy 159.979243 -389.727966) (xy 159.936528 -389.749764) (xy 159.89093 -389.764617) (xy 159.843571 -389.772159)
			(xy 159.819594 -389.772652) (xy 159.819086 -389.772652) (xy 159.795513 -389.772242) (xy 159.748927 -389.765)
			(xy 159.70401 -389.750675) (xy 159.661833 -389.729608) (xy 159.6234 -389.702302) (xy 159.589627 -389.669406)
			(xy 159.561319 -389.631705) (xy 159.549846 -389.611108) (xy 159.549338 -389.610346) (xy 159.151574 -388.922006)
			(xy 159.139699 -388.899329) (xy 159.122848 -388.850996) (xy 159.114274 -388.800533) (xy 159.113728 -388.77494)
			(xy 158.57148 -388.77494) (xy 158.883604 -389.314944) (xy 158.896319 -389.338271) (xy 158.91442 -389.388214)
			(xy 158.923643 -389.44053) (xy 158.924244 -389.46709) (xy 158.924244 -389.467344) (xy 158.923778 -389.491335)
			(xy 158.916267 -389.538724) (xy 158.901435 -389.584356) (xy 158.879649 -389.627106) (xy 158.851445 -389.665923)
			(xy 158.817517 -389.69985) (xy 158.778699 -389.728054) (xy 158.735949 -389.749838) (xy 158.690317 -389.764668)
			(xy 158.642927 -389.772179) (xy 158.618936 -389.772652) (xy 158.595364 -389.772202) (xy 158.54878 -389.764967)
			(xy 158.503864 -389.750649) (xy 158.461687 -389.729589) (xy 158.423253 -389.702289) (xy 158.389479 -389.669399)
			(xy 158.361169 -389.631703) (xy 158.349696 -389.611108) (xy 158.349188 -389.610346) (xy 157.951424 -388.922006)
			(xy 157.939511 -388.899337) (xy 157.922572 -388.851012) (xy 157.913912 -388.800542) (xy 157.913324 -388.77494)
			(xy 157.371584 -388.77494) (xy 157.683708 -389.314944) (xy 157.696467 -389.338252) (xy 157.7146 -389.388194)
			(xy 157.723797 -389.440524) (xy 157.724348 -389.46709) (xy 157.724348 -389.467344) (xy 157.723874 -389.491334)
			(xy 157.716363 -389.538723) (xy 157.701532 -389.584354) (xy 157.679747 -389.627103) (xy 157.651543 -389.665919)
			(xy 157.617616 -389.699846) (xy 157.5788 -389.728049) (xy 157.53605 -389.749834) (xy 157.490419 -389.764664)
			(xy 157.44303 -389.772174) (xy 157.41904 -389.772652) (xy 157.39547 -389.772209) (xy 157.348892 -389.764953)
			(xy 157.303983 -389.750623) (xy 157.261811 -389.729559) (xy 157.223379 -389.702263) (xy 157.1896 -389.669382)
			(xy 157.161277 -389.6317) (xy 157.1498 -389.611108) (xy 157.149292 -389.610346) (xy 156.751528 -388.922006)
			(xy 156.739596 -388.899345) (xy 156.722649 -388.85102) (xy 156.714009 -388.800544) (xy 156.713428 -388.77494)
			(xy 156.713428 -388.774432) (xy 156.713585 -388.763146) (xy 156.715361 -388.740644) (xy 156.716984 -388.729474)
			(xy 156.716984 -388.728966) (xy 156.718254 -388.72033) (xy 156.714698 -388.703312) (xy 156.671264 -388.631938)
			(xy 156.657548 -388.620762) (xy 156.648912 -388.617968) (xy 156.629629 -388.611123) (xy 156.592927 -388.593034)
			(xy 156.57576 -388.5819) (xy 156.569355 -388.577865) (xy 156.554879 -388.573463) (xy 156.547312 -388.573264)
			(xy 156.142944 -388.573264) (xy 156.134052 -388.573598) (xy 156.117341 -388.579681) (xy 156.103729 -388.591125)
			(xy 156.099002 -388.598664) (xy 156.094834 -388.606537) (xy 156.091726 -388.624069) (xy 156.094812 -388.641603)
			(xy 156.099002 -388.649464) (xy 156.483558 -389.314944) (xy 156.49634 -389.338295) (xy 156.514531 -389.388318)
			(xy 156.523813 -389.440731) (xy 156.524452 -389.467344) (xy 156.523979 -389.491322) (xy 156.516476 -389.538686)
			(xy 156.50166 -389.584295) (xy 156.479897 -389.627028) (xy 156.451722 -389.665833) (xy 156.417827 -389.699757)
			(xy 156.379045 -389.727964) (xy 156.33633 -389.749763) (xy 156.290733 -389.764616) (xy 156.243375 -389.772159)
			(xy 156.219398 -389.772652) (xy 156.21889 -389.772652) (xy 156.195318 -389.772213) (xy 156.148735 -389.764964)
			(xy 156.103821 -389.750638) (xy 156.061643 -389.729578) (xy 156.023204 -389.702284) (xy 155.989419 -389.669404)
			(xy 155.96109 -389.631721) (xy 155.94965 -389.611108) (xy 155.949142 -389.610346) (xy 155.551378 -388.922006)
			(xy 155.539479 -388.899338) (xy 155.522602 -388.851007) (xy 155.51404 -388.800536) (xy 155.513532 -388.77494)
			(xy 155.513532 -388.774432) (xy 155.513624 -388.76315) (xy 155.515277 -388.740648) (xy 155.516834 -388.729474)
			(xy 155.516834 -388.728966) (xy 155.517693 -388.720255) (xy 155.514174 -388.70312) (xy 155.509976 -388.695438)
			(xy 155.471114 -388.631938) (xy 155.457398 -388.620762) (xy 155.448762 -388.617968) (xy 155.429543 -388.611114)
			(xy 155.392971 -388.593021) (xy 155.375864 -388.5819) (xy 155.369459 -388.577865) (xy 155.354983 -388.573461)
			(xy 155.347416 -388.573264) (xy 154.943048 -388.573264) (xy 154.934156 -388.573597) (xy 154.917444 -388.579679)
			(xy 154.90383 -388.591123) (xy 154.899106 -388.598664) (xy 154.894937 -388.606537) (xy 154.891829 -388.624069)
			(xy 154.894916 -388.641604) (xy 154.899106 -388.649464) (xy 155.283662 -389.314944) (xy 155.296444 -389.338295)
			(xy 155.314634 -389.388318) (xy 155.323917 -389.440731) (xy 155.324556 -389.467344) (xy 155.324083 -389.491322)
			(xy 155.31658 -389.538686) (xy 155.301765 -389.584296) (xy 155.280002 -389.627029) (xy 155.251826 -389.665834)
			(xy 155.217931 -389.699758) (xy 155.179149 -389.727967) (xy 155.136435 -389.749766) (xy 155.090838 -389.764619)
			(xy 155.043479 -389.772163) (xy 155.019502 -389.772652) (xy 155.018994 -389.772652) (xy 154.995422 -389.772213)
			(xy 154.948839 -389.764964) (xy 154.903924 -389.75064) (xy 154.861745 -389.72958) (xy 154.823306 -389.702285)
			(xy 154.789521 -389.669406) (xy 154.761192 -389.631723) (xy 154.749754 -389.611108) (xy 154.749246 -389.610346)
			(xy 154.351482 -388.922006) (xy 154.339583 -388.899338) (xy 154.322706 -388.851007) (xy 154.314144 -388.800536)
			(xy 154.313636 -388.77494) (xy 154.313636 -388.774432) (xy 154.313728 -388.76315) (xy 154.315381 -388.740648)
			(xy 154.316938 -388.729474) (xy 154.316938 -388.728966) (xy 154.318208 -388.72033) (xy 154.314652 -388.703312)
			(xy 154.271218 -388.631938) (xy 154.257502 -388.620762) (xy 154.248866 -388.617968) (xy 154.225084 -388.609411)
			(xy 154.180492 -388.585624) (xy 154.140422 -388.554826) (xy 154.105963 -388.517855) (xy 154.078056 -388.47572)
			(xy 154.067256 -388.452868) (xy 154.063446 -388.444232) (xy 153.543762 -387.924548) (xy 153.526503 -387.906507)
			(xy 153.498746 -387.865013) (xy 153.479634 -387.818895) (xy 153.469903 -387.769931) (xy 153.46934 -387.74497)
			(xy 153.46934 -386.02158) (xy 153.469143 -386.014913) (xy 153.465666 -386.002041) (xy 153.462482 -385.99618)
			(xy 153.151586 -385.457954) (xy 153.139691 -385.435285) (xy 153.122822 -385.386954) (xy 153.114269 -385.336483)
			(xy 153.11374 -385.310888) (xy 153.11374 -385.31038) (xy 153.114263 -385.284776) (xy 153.122805 -385.234286)
			(xy 153.139647 -385.185927) (xy 153.164318 -385.141053) (xy 153.196125 -385.100922) (xy 153.23418 -385.066657)
			(xy 153.277415 -385.039217) (xy 153.324621 -385.019371) (xy 153.374475 -385.007674) (xy 153.399998 -385.00558)
			(xy 153.409172 -385.004644) (xy 153.425979 -384.997092) (xy 153.432764 -384.990848) (xy 153.454354 -384.969258)
			(xy 153.461199 -384.961859) (xy 153.468925 -384.943261) (xy 153.46934 -384.93319) (xy 153.46934 -383.644394)
			(xy 153.468852 -383.634384) (xy 153.461192 -383.615888) (xy 153.447041 -383.601727) (xy 153.428549 -383.594055)
			(xy 153.41854 -383.593594) (xy 141.145768 -383.593594) (xy 141.1357 -383.594023) (xy 141.117104 -383.601744)
			(xy 141.1097 -383.60858) (xy 140.49121 -384.22707) (xy 140.484374 -384.234472) (xy 140.476663 -384.25307)
			(xy 140.476224 -384.263138) (xy 140.476224 -385.310888) (xy 147.113752 -385.310888) (xy 147.113752 -385.31038)
			(xy 147.114244 -385.28639) (xy 147.121752 -385.239002) (xy 147.13658 -385.193371) (xy 147.158362 -385.150621)
			(xy 147.186563 -385.111804) (xy 147.220489 -385.077876) (xy 147.259304 -385.049673) (xy 147.302052 -385.027887)
			(xy 147.347682 -385.013057) (xy 147.39507 -385.005546) (xy 147.41906 -385.005072) (xy 147.442995 -385.005531)
			(xy 147.49028 -385.01299) (xy 147.535823 -385.027733) (xy 147.57851 -385.049398) (xy 147.617295 -385.077455)
			(xy 147.651231 -385.111217) (xy 147.679485 -385.149859) (xy 147.69084 -385.170934) (xy 147.691348 -385.17195)
			(xy 147.771654 -385.310888) (xy 148.313648 -385.310888) (xy 148.313648 -385.31038) (xy 148.314144 -385.28639)
			(xy 148.321652 -385.239002) (xy 148.336479 -385.193372) (xy 148.358261 -385.150622) (xy 148.386462 -385.111805)
			(xy 148.420387 -385.077878) (xy 148.459201 -385.049674) (xy 148.501949 -385.027888) (xy 148.547579 -385.013057)
			(xy 148.594966 -385.005546) (xy 148.618956 -385.005072) (xy 148.642891 -385.005534) (xy 148.690176 -385.012993)
			(xy 148.735719 -385.027735) (xy 148.778405 -385.049399) (xy 148.817191 -385.077456) (xy 148.851126 -385.111218)
			(xy 148.879381 -385.149859) (xy 148.890736 -385.170934) (xy 148.891244 -385.17195) (xy 148.97155 -385.310888)
			(xy 149.513544 -385.310888) (xy 149.513544 -385.31038) (xy 149.514044 -385.286391) (xy 149.521552 -385.239003)
			(xy 149.536379 -385.193373) (xy 149.558161 -385.150623) (xy 149.586361 -385.111807) (xy 149.620286 -385.077879)
			(xy 149.659099 -385.049675) (xy 149.701847 -385.02789) (xy 149.747476 -385.013058) (xy 149.794863 -385.005546)
			(xy 149.818852 -385.005072) (xy 149.842787 -385.005537) (xy 149.890071 -385.012995) (xy 149.935614 -385.027737)
			(xy 149.978301 -385.049401) (xy 150.017087 -385.077457) (xy 150.051022 -385.111218) (xy 150.079277 -385.149859)
			(xy 150.090632 -385.170934) (xy 150.09114 -385.17195) (xy 150.171446 -385.310888) (xy 150.71344 -385.310888)
			(xy 150.71344 -385.31038) (xy 150.713843 -385.286399) (xy 150.721346 -385.239026) (xy 150.736164 -385.193409)
			(xy 150.757932 -385.15067) (xy 150.786115 -385.111861) (xy 150.820019 -385.077936) (xy 150.858812 -385.049729)
			(xy 150.901537 -385.027935) (xy 150.947145 -385.013089) (xy 150.994513 -385.005558) (xy 151.018494 -385.005072)
			(xy 151.019002 -385.005072) (xy 151.042935 -385.005578) (xy 151.090218 -385.013028) (xy 151.13576 -385.027763)
			(xy 151.178447 -385.04942) (xy 151.217233 -385.077469) (xy 151.25117 -385.111225) (xy 151.279426 -385.149861)
			(xy 151.290782 -385.170934) (xy 151.29129 -385.17195) (xy 151.371596 -385.310888) (xy 151.913336 -385.310888)
			(xy 151.913336 -385.31038) (xy 151.913743 -385.286399) (xy 151.921246 -385.239027) (xy 151.936063 -385.19341)
			(xy 151.957831 -385.150672) (xy 151.986013 -385.111862) (xy 152.019918 -385.077937) (xy 152.058709 -385.04973)
			(xy 152.101434 -385.027936) (xy 152.147041 -385.01309) (xy 152.194409 -385.005558) (xy 152.21839 -385.005072)
			(xy 152.218898 -385.005072) (xy 152.242834 -385.0055) (xy 152.290121 -385.012965) (xy 152.335664 -385.027713)
			(xy 152.378351 -385.049383) (xy 152.417136 -385.077445) (xy 152.45107 -385.111212) (xy 152.479324 -385.149857)
			(xy 152.490678 -385.170934) (xy 152.491186 -385.17195) (xy 152.883616 -385.850892) (xy 152.89635 -385.874209)
			(xy 152.914443 -385.924158) (xy 152.923659 -385.976477) (xy 152.924256 -386.003038) (xy 152.924256 -386.003292)
			(xy 152.92373 -386.027281) (xy 152.916227 -386.074667) (xy 152.901403 -386.120297) (xy 152.879625 -386.163047)
			(xy 152.851428 -386.201863) (xy 152.817506 -386.235791) (xy 152.778694 -386.263996) (xy 152.735949 -386.285782)
			(xy 152.690322 -386.300614) (xy 152.642937 -386.308126) (xy 152.618948 -386.3086) (xy 152.595375 -386.308168)
			(xy 152.548789 -386.300933) (xy 152.503871 -386.286614) (xy 152.461693 -386.265552) (xy 152.423259 -386.238248)
			(xy 152.389486 -386.205354) (xy 152.361179 -386.167654) (xy 152.349708 -386.147056) (xy 152.3492 -386.146294)
			(xy 151.951436 -385.457954) (xy 151.939505 -385.435294) (xy 151.922572 -385.386964) (xy 151.913919 -385.336491)
			(xy 151.913336 -385.310888) (xy 151.371596 -385.310888) (xy 151.68372 -385.850892) (xy 151.696454 -385.874209)
			(xy 151.714548 -385.924158) (xy 151.723763 -385.976476) (xy 151.72436 -386.003038) (xy 151.72436 -386.003292)
			(xy 151.723954 -386.027287) (xy 151.716447 -386.074687) (xy 151.701617 -386.120329) (xy 151.679828 -386.163088)
			(xy 151.651618 -386.201912) (xy 151.617682 -386.235844) (xy 151.578854 -386.264049) (xy 151.536092 -386.285832)
			(xy 151.490448 -386.300657) (xy 151.443047 -386.308157) (xy 151.419052 -386.3086) (xy 151.395479 -386.308164)
			(xy 151.348893 -386.300931) (xy 151.303976 -386.286612) (xy 151.261797 -386.265551) (xy 151.223364 -386.238247)
			(xy 151.189591 -386.205354) (xy 151.161283 -386.167653) (xy 151.149812 -386.147056) (xy 151.149304 -386.146294)
			(xy 150.75154 -385.457954) (xy 150.739609 -385.435293) (xy 150.722676 -385.386964) (xy 150.714023 -385.336491)
			(xy 150.71344 -385.310888) (xy 150.171446 -385.310888) (xy 150.48357 -385.850892) (xy 150.496397 -385.874223)
			(xy 150.514616 -385.924247) (xy 150.523875 -385.976673) (xy 150.524464 -386.003292) (xy 150.524031 -386.027273)
			(xy 150.516533 -386.074644) (xy 150.501719 -386.12026) (xy 150.479955 -386.162998) (xy 150.451775 -386.201808)
			(xy 150.417874 -386.235733) (xy 150.379084 -386.263941) (xy 150.336361 -386.285735) (xy 150.290756 -386.300581)
			(xy 150.24339 -386.308114) (xy 150.21941 -386.3086) (xy 150.218902 -386.3086) (xy 150.195328 -386.308205)
			(xy 150.14874 -386.300963) (xy 150.103821 -386.286638) (xy 150.061643 -386.26557) (xy 150.02321 -386.23826)
			(xy 149.989438 -386.205361) (xy 149.961133 -386.167656) (xy 149.949662 -386.147056) (xy 149.949154 -386.146294)
			(xy 149.55139 -385.457954) (xy 149.539534 -385.435267) (xy 149.522675 -385.386939) (xy 149.514094 -385.336479)
			(xy 149.513544 -385.310888) (xy 148.97155 -385.310888) (xy 149.283674 -385.850892) (xy 149.296501 -385.874223)
			(xy 149.31472 -385.924247) (xy 149.323979 -385.976673) (xy 149.324568 -386.003292) (xy 149.324131 -386.027272)
			(xy 149.316633 -386.074643) (xy 149.301819 -386.120259) (xy 149.280055 -386.162997) (xy 149.251876 -386.201806)
			(xy 149.217975 -386.235732) (xy 149.179187 -386.263939) (xy 149.136464 -386.285734) (xy 149.090859 -386.300581)
			(xy 149.043494 -386.308113) (xy 149.019514 -386.3086) (xy 149.019006 -386.3086) (xy 148.995432 -386.308201)
			(xy 148.948844 -386.300961) (xy 148.903926 -386.286636) (xy 148.861747 -386.265568) (xy 148.823314 -386.238259)
			(xy 148.789542 -386.20536) (xy 148.761237 -386.167655) (xy 148.749766 -386.147056) (xy 148.749258 -386.146294)
			(xy 148.351494 -385.457954) (xy 148.339638 -385.435267) (xy 148.322779 -385.386939) (xy 148.314198 -385.336479)
			(xy 148.313648 -385.310888) (xy 147.771654 -385.310888) (xy 148.083778 -385.850892) (xy 148.096606 -385.874223)
			(xy 148.114824 -385.924247) (xy 148.124083 -385.976673) (xy 148.124672 -386.003292) (xy 148.124231 -386.027272)
			(xy 148.116733 -386.074643) (xy 148.10192 -386.120258) (xy 148.080156 -386.162996) (xy 148.051978 -386.201805)
			(xy 148.018077 -386.235731) (xy 147.979289 -386.263938) (xy 147.936567 -386.285733) (xy 147.890963 -386.30058)
			(xy 147.843598 -386.308113) (xy 147.819618 -386.3086) (xy 147.81911 -386.3086) (xy 147.795536 -386.308198)
			(xy 147.748948 -386.300958) (xy 147.70403 -386.286634) (xy 147.661852 -386.265566) (xy 147.623418 -386.238258)
			(xy 147.589647 -386.20536) (xy 147.561341 -386.167655) (xy 147.54987 -386.147056) (xy 147.549362 -386.146294)
			(xy 147.151598 -385.457954) (xy 147.139742 -385.435267) (xy 147.122883 -385.386939) (xy 147.114302 -385.336479)
			(xy 147.113752 -385.310888) (xy 140.476224 -385.310888) (xy 140.476224 -385.991862) (xy 140.475607 -386.016816)
			(xy 140.46586 -386.065764) (xy 140.446752 -386.111871) (xy 140.419018 -386.153365) (xy 140.401802 -386.17144)
			(xy 138.783568 -387.789674) (xy 140.529056 -387.789674) (xy 140.529056 -386.926074) (xy 140.529542 -386.898823)
			(xy 140.537298 -386.844875) (xy 140.552653 -386.79258) (xy 140.575295 -386.743003) (xy 140.604761 -386.697153)
			(xy 140.640452 -386.655962) (xy 140.681643 -386.620271) (xy 140.727493 -386.590805) (xy 140.77707 -386.568163)
			(xy 140.829365 -386.552808) (xy 140.883313 -386.545052) (xy 140.937815 -386.545052) (xy 140.991763 -386.552808)
			(xy 141.044058 -386.568163) (xy 141.093635 -386.590805) (xy 141.139485 -386.620271) (xy 141.180676 -386.655962)
			(xy 141.216367 -386.697153) (xy 141.245833 -386.743003) (xy 141.268475 -386.79258) (xy 141.28383 -386.844875)
			(xy 141.291586 -386.898823) (xy 141.292072 -386.926074) (xy 141.292072 -387.789674) (xy 141.291586 -387.816925)
			(xy 141.28383 -387.870873) (xy 141.268475 -387.923168) (xy 141.245833 -387.972745) (xy 141.216367 -388.018595)
			(xy 141.180676 -388.059786) (xy 141.139485 -388.095477) (xy 141.093635 -388.124943) (xy 141.044058 -388.147585)
			(xy 140.991763 -388.16294) (xy 140.937815 -388.170696) (xy 140.883313 -388.170696) (xy 140.829365 -388.16294)
			(xy 140.77707 -388.147585) (xy 140.727493 -388.124943) (xy 140.681643 -388.095477) (xy 140.640452 -388.059786)
			(xy 140.604761 -388.018595) (xy 140.575295 -387.972745) (xy 140.552653 -387.923168) (xy 140.537298 -387.870873)
			(xy 140.529542 -387.816925) (xy 140.529056 -387.789674) (xy 138.783568 -387.789674) (xy 138.768074 -387.805168)
			(xy 138.750033 -387.822427) (xy 138.708539 -387.850185) (xy 138.662421 -387.8693) (xy 138.613457 -387.879034)
			(xy 138.588496 -387.87959) (xy 136.99109 -387.87959) (xy 136.98102 -387.880014) (xy 136.962418 -387.88773)
			(xy 136.955022 -387.894576) (xy 136.711436 -388.138162) (xy 136.693394 -388.155419) (xy 136.651899 -388.183171)
			(xy 136.605781 -388.202279) (xy 136.556818 -388.212007) (xy 136.531858 -388.212584) (xy 128.302004 -388.212584)
			(xy 128.277051 -388.211963) (xy 128.228108 -388.202209) (xy 128.182008 -388.183095) (xy 128.140521 -388.155356)
			(xy 128.122426 -388.138162) (xy 127.976376 -387.992112) (xy 127.969239 -387.985617) (xy 127.95151 -387.978035)
			(xy 127.932235 -387.977512) (xy 127.923036 -387.980428) (xy 127.897732 -387.989036) (xy 127.845109 -387.998364)
			(xy 127.818388 -387.99897) (xy 127.794397 -387.998523) (xy 127.747005 -387.991014) (xy 127.701371 -387.976184)
			(xy 127.658619 -387.954398) (xy 127.619802 -387.926191) (xy 127.585876 -387.892259) (xy 127.557676 -387.853438)
			(xy 127.535897 -387.810683) (xy 127.521074 -387.765047) (xy 127.513573 -387.717654) (xy 127.51308 -387.693662)
			(xy 127.513627 -387.666935) (xy 127.522945 -387.614299) (xy 127.531622 -387.589014) (xy 127.534558 -387.579817)
			(xy 127.53405 -387.560533) (xy 127.526448 -387.542804) (xy 127.519938 -387.535674) (xy 126.826264 -386.842)
			(xy 126.818863 -386.835159) (xy 126.800265 -386.827438) (xy 126.790196 -386.827014) (xy 126.22657 -386.827014)
			(xy 126.216503 -386.827443) (xy 126.197907 -386.835167) (xy 126.190502 -386.842) (xy 124.636784 -388.395718)
			(xy 124.633736 -388.398512) (xy 124.625806 -388.407072) (xy 124.617987 -388.429033) (xy 124.61875 -388.440676)
			(xy 124.62256 -388.473188) (xy 124.624387 -388.484863) (xy 124.637103 -388.504746) (xy 124.646944 -388.511288)
			(xy 124.671382 -388.526533) (xy 124.714566 -388.564635) (xy 124.749865 -388.610139) (xy 124.76353 -388.635494)
			(xy 124.764038 -388.636764) (xy 124.830221 -388.751286) (xy 125.385922 -388.751286) (xy 125.393254 -388.703735)
			(xy 125.407948 -388.657921) (xy 125.429641 -388.614977) (xy 125.457796 -388.575963) (xy 125.491718 -388.541844)
			(xy 125.530569 -388.513464) (xy 125.573387 -388.491523) (xy 125.619115 -388.476565) (xy 125.666623 -388.468959)
			(xy 125.714735 -388.468892) (xy 125.762263 -388.476368) (xy 125.808032 -388.4912) (xy 125.850911 -388.513022)
			(xy 125.88984 -388.541295) (xy 125.923856 -388.57532) (xy 125.952119 -388.614256) (xy 125.963426 -388.635494)
			(xy 125.963934 -388.636764) (xy 126.030115 -388.751284) (xy 126.586167 -388.751284) (xy 126.593498 -388.703742)
			(xy 126.60819 -388.657936) (xy 126.629879 -388.615) (xy 126.658029 -388.575993) (xy 126.691945 -388.54188)
			(xy 126.730788 -388.513504) (xy 126.773598 -388.491567) (xy 126.819318 -388.47661) (xy 126.866816 -388.469004)
			(xy 126.91492 -388.468936) (xy 126.96244 -388.476408) (xy 127.008202 -388.491235) (xy 127.051074 -388.513051)
			(xy 127.089997 -388.541317) (xy 127.124009 -388.575333) (xy 127.15227 -388.61426) (xy 127.163576 -388.635494)
			(xy 127.164084 -388.636764) (xy 127.257251 -388.797979) (xy 127.786112 -388.797979) (xy 127.786361 -388.747044)
			(xy 127.795054 -388.696856) (xy 127.811952 -388.648805) (xy 127.836585 -388.604222) (xy 127.868271 -388.564342)
			(xy 127.906133 -388.530271) (xy 127.949122 -388.502951) (xy 127.996047 -388.48314) (xy 128.045608 -388.471387)
			(xy 128.096432 -388.468016) (xy 128.147111 -388.473122) (xy 128.196241 -388.486563) (xy 128.242461 -388.507967)
			(xy 128.284491 -388.53674) (xy 128.321166 -388.572086) (xy 128.351471 -388.613026) (xy 128.363472 -388.635494)
			(xy 128.36398 -388.636764) (xy 128.457146 -388.797978) (xy 128.986016 -388.797978) (xy 128.986265 -388.747044)
			(xy 128.994958 -388.696856) (xy 129.011855 -388.648806) (xy 129.036488 -388.604224) (xy 129.068174 -388.564345)
			(xy 129.106035 -388.530274) (xy 129.149024 -388.502955) (xy 129.195948 -388.483144) (xy 129.245508 -388.47139)
			(xy 129.296331 -388.46802) (xy 129.347009 -388.473125) (xy 129.396138 -388.486566) (xy 129.442358 -388.507969)
			(xy 129.484387 -388.536742) (xy 129.521062 -388.572087) (xy 129.551367 -388.613026) (xy 129.563368 -388.635494)
			(xy 129.563876 -388.636764) (xy 129.630058 -388.751285) (xy 130.18603 -388.751285) (xy 130.193361 -388.703736)
			(xy 130.208055 -388.657924) (xy 130.229747 -388.614981) (xy 130.257901 -388.575968) (xy 130.291823 -388.54185)
			(xy 130.330672 -388.51347) (xy 130.373489 -388.49153) (xy 130.419216 -388.476572) (xy 130.466722 -388.468966)
			(xy 130.514833 -388.468899) (xy 130.56236 -388.476374) (xy 130.608128 -388.491205) (xy 130.651005 -388.513026)
			(xy 130.689933 -388.541298) (xy 130.723949 -388.575322) (xy 130.752211 -388.614256) (xy 130.763518 -388.635494)
			(xy 130.764026 -388.636764) (xy 130.830208 -388.751285) (xy 131.385933 -388.751285) (xy 131.393265 -388.703737)
			(xy 131.407958 -388.657925) (xy 131.42965 -388.614982) (xy 131.457804 -388.57597) (xy 131.491725 -388.541853)
			(xy 131.530573 -388.513474) (xy 131.57339 -388.491534) (xy 131.619116 -388.476576) (xy 131.666621 -388.46897)
			(xy 131.714731 -388.468903) (xy 131.762258 -388.476377) (xy 131.808025 -388.491208) (xy 131.850902 -388.513029)
			(xy 131.88983 -388.5413) (xy 131.923845 -388.575323) (xy 131.952107 -388.614257) (xy 131.963414 -388.635494)
			(xy 131.963922 -388.636764) (xy 132.057087 -388.797977) (xy 132.586219 -388.797977) (xy 132.586468 -388.747044)
			(xy 132.595161 -388.696857) (xy 132.612058 -388.648807) (xy 132.636691 -388.604226) (xy 132.668376 -388.564348)
			(xy 132.706237 -388.530277) (xy 132.749225 -388.502958) (xy 132.796148 -388.483147) (xy 132.845708 -388.471394)
			(xy 132.89653 -388.468023) (xy 132.947207 -388.473129) (xy 132.996336 -388.486569) (xy 133.042555 -388.507972)
			(xy 133.084584 -388.536744) (xy 133.121258 -388.572088) (xy 133.151563 -388.613026) (xy 133.163564 -388.635494)
			(xy 133.164072 -388.636764) (xy 133.243924 -388.77494) (xy 147.113752 -388.77494) (xy 147.113752 -388.774432)
			(xy 147.114292 -388.750444) (xy 147.121792 -388.703057) (xy 147.136613 -388.657427) (xy 147.158389 -388.614677)
			(xy 147.186584 -388.57586) (xy 147.220505 -388.541931) (xy 147.259315 -388.513726) (xy 147.30206 -388.49194)
			(xy 147.347687 -388.477109) (xy 147.395072 -388.469598) (xy 147.41906 -388.469124) (xy 147.442996 -388.469555)
			(xy 147.490284 -388.477016) (xy 147.535829 -388.491761) (xy 147.578517 -388.51343) (xy 147.617303 -388.541492)
			(xy 147.651236 -388.57526) (xy 147.679488 -388.613908) (xy 147.69084 -388.634986) (xy 147.691348 -388.636002)
			(xy 147.771654 -388.77494) (xy 148.313648 -388.77494) (xy 148.313648 -388.774432) (xy 148.314192 -388.750444)
			(xy 148.321692 -388.703057) (xy 148.336512 -388.657428) (xy 148.358288 -388.614678) (xy 148.386483 -388.575861)
			(xy 148.420403 -388.541933) (xy 148.459213 -388.513728) (xy 148.501957 -388.491941) (xy 148.547583 -388.47711)
			(xy 148.594968 -388.469598) (xy 148.618956 -388.469124) (xy 148.642892 -388.469558) (xy 148.69018 -388.477018)
			(xy 148.735725 -388.491763) (xy 148.778413 -388.513431) (xy 148.817198 -388.541493) (xy 148.851132 -388.575261)
			(xy 148.879383 -388.613908) (xy 148.890736 -388.634986) (xy 148.891244 -388.636002) (xy 148.97155 -388.77494)
			(xy 149.513544 -388.77494) (xy 149.513544 -388.774432) (xy 149.514092 -388.750444) (xy 149.521592 -388.703058)
			(xy 149.536412 -388.657429) (xy 149.558187 -388.614679) (xy 149.586382 -388.575862) (xy 149.620301 -388.541934)
			(xy 149.659111 -388.513729) (xy 149.701855 -388.491943) (xy 149.74748 -388.477111) (xy 149.794864 -388.469598)
			(xy 149.818852 -388.469124) (xy 149.842788 -388.469561) (xy 149.890076 -388.477021) (xy 149.935621 -388.491765)
			(xy 149.978308 -388.513433) (xy 150.017094 -388.541494) (xy 150.051028 -388.575261) (xy 150.079279 -388.613908)
			(xy 150.090632 -388.634986) (xy 150.09114 -388.636002) (xy 150.171446 -388.77494) (xy 150.71344 -388.77494)
			(xy 150.71344 -388.774432) (xy 150.713891 -388.750452) (xy 150.721386 -388.703081) (xy 150.736197 -388.657465)
			(xy 150.757958 -388.614726) (xy 150.786136 -388.575917) (xy 150.820035 -388.54199) (xy 150.858823 -388.513783)
			(xy 150.901545 -388.491988) (xy 150.947149 -388.477142) (xy 150.994514 -388.46961) (xy 151.018494 -388.469124)
			(xy 151.019002 -388.469124) (xy 151.042937 -388.469602) (xy 151.090222 -388.477054) (xy 151.135766 -388.491791)
			(xy 151.178454 -388.513452) (xy 151.21724 -388.541507) (xy 151.251175 -388.575268) (xy 151.279429 -388.61391)
			(xy 151.290782 -388.634986) (xy 151.29129 -388.636002) (xy 151.371596 -388.77494) (xy 151.913336 -388.77494)
			(xy 151.913336 -388.774432) (xy 151.913791 -388.750452) (xy 151.921286 -388.703082) (xy 151.936096 -388.657466)
			(xy 151.957858 -388.614728) (xy 151.986034 -388.575918) (xy 152.019934 -388.541992) (xy 152.058721 -388.513784)
			(xy 152.101442 -388.491989) (xy 152.147046 -388.477143) (xy 152.19441 -388.46961) (xy 152.21839 -388.469124)
			(xy 152.218898 -388.469124) (xy 152.242835 -388.469524) (xy 152.290125 -388.476991) (xy 152.335671 -388.491741)
			(xy 152.378358 -388.513415) (xy 152.417143 -388.541482) (xy 152.451076 -388.575255) (xy 152.479326 -388.613906)
			(xy 152.490678 -388.634986) (xy 152.491186 -388.636002) (xy 152.571492 -388.77494) (xy 153.11374 -388.77494)
			(xy 153.11374 -388.774432) (xy 153.114168 -388.750437) (xy 153.121671 -388.703038) (xy 153.136498 -388.657397)
			(xy 153.158284 -388.614638) (xy 153.186491 -388.575814) (xy 153.220426 -388.541881) (xy 153.259251 -388.513676)
			(xy 153.302012 -388.491892) (xy 153.347654 -388.477068) (xy 153.395053 -388.469567) (xy 153.419048 -388.469124)
			(xy 153.442984 -388.469565) (xy 153.490271 -388.477024) (xy 153.535816 -388.491767) (xy 153.578504 -388.513434)
			(xy 153.61729 -388.541495) (xy 153.651224 -388.575262) (xy 153.679475 -388.613908) (xy 153.690828 -388.634986)
			(xy 153.691336 -388.636002) (xy 154.083766 -389.314944) (xy 154.096575 -389.338285) (xy 154.1148 -389.388303)
			(xy 154.124067 -389.440726) (xy 154.12466 -389.467344) (xy 154.124279 -389.491326) (xy 154.116773 -389.5387)
			(xy 154.101952 -389.584317) (xy 154.080181 -389.627055) (xy 154.051995 -389.665865) (xy 154.018088 -389.69979)
			(xy 153.979294 -389.727996) (xy 153.936567 -389.74979) (xy 153.890957 -389.764635) (xy 153.843588 -389.772166)
			(xy 153.819606 -389.772652) (xy 153.819098 -389.772652) (xy 153.795525 -389.772232) (xy 153.74894 -389.764992)
			(xy 153.704023 -389.750669) (xy 153.661846 -389.729604) (xy 153.623413 -389.702299) (xy 153.589639 -389.669405)
			(xy 153.561331 -389.631705) (xy 153.549858 -389.611108) (xy 153.54935 -389.610346) (xy 153.151586 -388.922006)
			(xy 153.139712 -388.899328) (xy 153.12286 -388.850996) (xy 153.114286 -388.800533) (xy 153.11374 -388.77494)
			(xy 152.571492 -388.77494) (xy 152.883616 -389.314944) (xy 152.896332 -389.338271) (xy 152.914432 -389.388214)
			(xy 152.923655 -389.44053) (xy 152.924256 -389.46709) (xy 152.924256 -389.467344) (xy 152.923778 -389.491334)
			(xy 152.916267 -389.538723) (xy 152.901436 -389.584353) (xy 152.879652 -389.627103) (xy 152.851449 -389.665919)
			(xy 152.817522 -389.699846) (xy 152.778706 -389.72805) (xy 152.735957 -389.749835) (xy 152.690327 -389.764666)
			(xy 152.642938 -389.772178) (xy 152.618948 -389.772652) (xy 152.595377 -389.772192) (xy 152.548793 -389.764959)
			(xy 152.503877 -389.750643) (xy 152.4617 -389.729585) (xy 152.423266 -389.702286) (xy 152.389492 -389.669398)
			(xy 152.361182 -389.631703) (xy 152.349708 -389.611108) (xy 152.3492 -389.610346) (xy 151.951436 -388.922006)
			(xy 151.939523 -388.899336) (xy 151.922584 -388.851012) (xy 151.913924 -388.800542) (xy 151.913336 -388.77494)
			(xy 151.371596 -388.77494) (xy 151.68372 -389.314944) (xy 151.696436 -389.33827) (xy 151.714536 -389.388214)
			(xy 151.723759 -389.44053) (xy 151.72436 -389.46709) (xy 151.72436 -389.467344) (xy 151.724002 -389.491341)
			(xy 151.716487 -389.538742) (xy 151.70165 -389.584385) (xy 151.679855 -389.627144) (xy 151.651639 -389.665968)
			(xy 151.617698 -389.699899) (xy 151.578866 -389.728103) (xy 151.5361 -389.749885) (xy 151.490453 -389.764709)
			(xy 151.443049 -389.772209) (xy 151.419052 -389.772652) (xy 151.395481 -389.772189) (xy 151.348897 -389.764957)
			(xy 151.303982 -389.750641) (xy 151.261804 -389.729583) (xy 151.223371 -389.702285) (xy 151.189596 -389.669397)
			(xy 151.161286 -389.631703) (xy 151.149812 -389.611108) (xy 151.149304 -389.610346) (xy 150.75154 -388.922006)
			(xy 150.739628 -388.899336) (xy 150.722688 -388.851012) (xy 150.714028 -388.800542) (xy 150.71344 -388.77494)
			(xy 150.171446 -388.77494) (xy 150.48357 -389.314944) (xy 150.496379 -389.338285) (xy 150.514604 -389.388303)
			(xy 150.523871 -389.440726) (xy 150.524464 -389.467344) (xy 150.524079 -389.491326) (xy 150.516573 -389.538699)
			(xy 150.501752 -389.584316) (xy 150.479981 -389.627054) (xy 150.451796 -389.665863) (xy 150.41789 -389.699788)
			(xy 150.379096 -389.727994) (xy 150.336369 -389.749788) (xy 150.290761 -389.764634) (xy 150.243392 -389.772166)
			(xy 150.21941 -389.772652) (xy 150.218902 -389.772652) (xy 150.195329 -389.772229) (xy 150.148744 -389.76499)
			(xy 150.103827 -389.750667) (xy 150.06165 -389.729602) (xy 150.023217 -389.702298) (xy 149.989444 -389.669404)
			(xy 149.961135 -389.631705) (xy 149.949662 -389.611108) (xy 149.949154 -389.610346) (xy 149.55139 -388.922006)
			(xy 149.539516 -388.899328) (xy 149.522664 -388.850995) (xy 149.51409 -388.800533) (xy 149.513544 -388.77494)
			(xy 148.97155 -388.77494) (xy 149.283674 -389.314944) (xy 149.296483 -389.338284) (xy 149.314708 -389.388303)
			(xy 149.323975 -389.440726) (xy 149.324568 -389.467344) (xy 149.324179 -389.491326) (xy 149.316673 -389.538698)
			(xy 149.301852 -389.584315) (xy 149.280082 -389.627053) (xy 149.251897 -389.665862) (xy 149.217991 -389.699787)
			(xy 149.179198 -389.727993) (xy 149.136472 -389.749787) (xy 149.090864 -389.764633) (xy 149.043495 -389.772165)
			(xy 149.019514 -389.772652) (xy 149.019006 -389.772652) (xy 148.995434 -389.772226) (xy 148.948848 -389.764987)
			(xy 148.903932 -389.750665) (xy 148.861754 -389.729601) (xy 148.823321 -389.702297) (xy 148.789548 -389.669404)
			(xy 148.761239 -389.631705) (xy 148.749766 -389.611108) (xy 148.749258 -389.610346) (xy 148.351494 -388.922006)
			(xy 148.339621 -388.899328) (xy 148.322768 -388.850995) (xy 148.314194 -388.800532) (xy 148.313648 -388.77494)
			(xy 147.771654 -388.77494) (xy 148.083778 -389.314944) (xy 148.096588 -389.338284) (xy 148.114813 -389.388303)
			(xy 148.124079 -389.440726) (xy 148.124672 -389.467344) (xy 148.124279 -389.491326) (xy 148.116773 -389.538698)
			(xy 148.101953 -389.584314) (xy 148.080183 -389.627052) (xy 148.051999 -389.665861) (xy 148.018093 -389.699785)
			(xy 147.9793 -389.727992) (xy 147.936575 -389.749786) (xy 147.890967 -389.764632) (xy 147.843599 -389.772165)
			(xy 147.819618 -389.772652) (xy 147.81911 -389.772652) (xy 147.795538 -389.772223) (xy 147.748952 -389.764984)
			(xy 147.704036 -389.750663) (xy 147.661859 -389.729599) (xy 147.623425 -389.702296) (xy 147.589652 -389.669403)
			(xy 147.561343 -389.631704) (xy 147.54987 -389.611108) (xy 147.549362 -389.610346) (xy 147.151598 -388.922006)
			(xy 147.139725 -388.899328) (xy 147.122872 -388.850995) (xy 147.114298 -388.800532) (xy 147.113752 -388.77494)
			(xy 133.243924 -388.77494) (xy 133.555994 -389.314944) (xy 133.556248 -389.315452) (xy 133.556502 -389.315452)
			(xy 133.557772 -389.317992) (xy 133.570041 -389.340909) (xy 133.587449 -389.389886) (xy 133.596324 -389.441102)
			(xy 133.596888 -389.46709) (xy 133.596888 -389.467344) (xy 133.596479 -389.491325) (xy 133.588974 -389.538695)
			(xy 133.574154 -389.58431) (xy 133.552386 -389.627047) (xy 133.524203 -389.665855) (xy 133.4903 -389.69978)
			(xy 133.451509 -389.727986) (xy 133.408786 -389.749782) (xy 133.36318 -389.764629) (xy 133.315814 -389.772164)
			(xy 133.291834 -389.772652) (xy 133.291326 -389.772652) (xy 133.267662 -389.772192) (xy 133.220902 -389.764885)
			(xy 133.175827 -389.750458) (xy 133.133515 -389.729255) (xy 133.094977 -389.701783) (xy 133.061134 -389.6687)
			(xy 133.032795 -389.630795) (xy 133.021324 -389.610092) (xy 133.02107 -389.60933) (xy 132.623814 -388.922006)
			(xy 132.611606 -388.898734) (xy 132.594491 -388.849053) (xy 132.589778 -388.8232) (xy 132.586219 -388.797977)
			(xy 132.057087 -388.797977) (xy 132.355844 -389.314944) (xy 132.356098 -389.315452) (xy 132.356352 -389.315452)
			(xy 132.357622 -389.317992) (xy 132.369855 -389.340916) (xy 132.387175 -389.389902) (xy 132.395962 -389.441111)
			(xy 132.396484 -389.46709) (xy 132.396484 -389.467344) (xy 132.396078 -389.491338) (xy 132.388564 -389.538733)
			(xy 132.37373 -389.58437) (xy 132.351938 -389.627124) (xy 132.323728 -389.665943) (xy 132.289792 -389.699872)
			(xy 132.250966 -389.728074) (xy 132.208207 -389.749856) (xy 132.162567 -389.76468) (xy 132.11517 -389.772183)
			(xy 132.091176 -389.772652) (xy 132.067511 -389.772232) (xy 132.020749 -389.764918) (xy 131.975673 -389.750483)
			(xy 131.933361 -389.729274) (xy 131.894823 -389.701796) (xy 131.860981 -389.668707) (xy 131.832644 -389.630797)
			(xy 131.821174 -389.610092) (xy 131.82092 -389.60933) (xy 131.423664 -388.922006) (xy 131.411453 -388.898736)
			(xy 131.39434 -388.849053) (xy 131.389628 -388.8232) (xy 131.386145 -388.799395) (xy 131.385933 -388.751285)
			(xy 130.830208 -388.751285) (xy 131.155948 -389.314944) (xy 131.156202 -389.315452) (xy 131.156456 -389.315452)
			(xy 131.157726 -389.317992) (xy 131.16996 -389.340916) (xy 131.187279 -389.389902) (xy 131.196066 -389.441111)
			(xy 131.196588 -389.46709) (xy 131.196588 -389.467344) (xy 131.196178 -389.491337) (xy 131.188665 -389.538733)
			(xy 131.17383 -389.584369) (xy 131.152039 -389.627123) (xy 131.123829 -389.665942) (xy 131.089893 -389.69987)
			(xy 131.051068 -389.728073) (xy 131.00831 -389.749854) (xy 130.96267 -389.76468) (xy 130.915274 -389.772183)
			(xy 130.89128 -389.772652) (xy 130.867615 -389.772229) (xy 130.820853 -389.764915) (xy 130.775777 -389.750481)
			(xy 130.733465 -389.729272) (xy 130.694927 -389.701795) (xy 130.661085 -389.668706) (xy 130.632748 -389.630797)
			(xy 130.621278 -389.610092) (xy 130.621024 -389.60933) (xy 130.223768 -388.922006) (xy 130.211557 -388.898736)
			(xy 130.194444 -388.849053) (xy 130.189732 -388.8232) (xy 130.186241 -388.799396) (xy 130.18603 -388.751285)
			(xy 129.630058 -388.751285) (xy 129.955798 -389.314944) (xy 129.956052 -389.315452) (xy 129.956306 -389.315452)
			(xy 129.957576 -389.317992) (xy 129.969845 -389.340909) (xy 129.987253 -389.389886) (xy 129.996128 -389.441102)
			(xy 129.996692 -389.46709) (xy 129.996692 -389.467344) (xy 129.996279 -389.491325) (xy 129.988774 -389.538695)
			(xy 129.973955 -389.584309) (xy 129.952187 -389.627046) (xy 129.924004 -389.665854) (xy 129.890101 -389.699778)
			(xy 129.851312 -389.727985) (xy 129.808589 -389.74978) (xy 129.762984 -389.764628) (xy 129.715618 -389.772164)
			(xy 129.691638 -389.772652) (xy 129.69113 -389.772652) (xy 129.667466 -389.772188) (xy 129.620707 -389.764882)
			(xy 129.575632 -389.750456) (xy 129.533319 -389.729254) (xy 129.494781 -389.701782) (xy 129.460938 -389.668699)
			(xy 129.432599 -389.630794) (xy 129.421128 -389.610092) (xy 129.420874 -389.60933) (xy 129.023618 -388.922006)
			(xy 129.01141 -388.898734) (xy 128.994295 -388.849053) (xy 128.989582 -388.8232) (xy 128.986016 -388.797978)
			(xy 128.457146 -388.797978) (xy 128.755902 -389.314944) (xy 128.756156 -389.315452) (xy 128.75641 -389.315452)
			(xy 128.75768 -389.317992) (xy 128.769949 -389.340909) (xy 128.787357 -389.389886) (xy 128.796232 -389.441102)
			(xy 128.796796 -389.46709) (xy 128.796796 -389.467344) (xy 128.796379 -389.491324) (xy 128.788874 -389.538694)
			(xy 128.774055 -389.584308) (xy 128.752287 -389.627045) (xy 128.724106 -389.665852) (xy 128.690203 -389.699777)
			(xy 128.651414 -389.727984) (xy 128.608692 -389.749779) (xy 128.563087 -389.764628) (xy 128.515722 -389.772163)
			(xy 128.491742 -389.772652) (xy 128.491234 -389.772652) (xy 128.467571 -389.772185) (xy 128.420811 -389.76488)
			(xy 128.375736 -389.750454) (xy 128.333424 -389.729252) (xy 128.294885 -389.701781) (xy 128.261042 -389.668699)
			(xy 128.232703 -389.630794) (xy 128.221232 -389.610092) (xy 128.220978 -389.60933) (xy 127.823722 -388.922006)
			(xy 127.811515 -388.898734) (xy 127.794399 -388.849053) (xy 127.789686 -388.8232) (xy 127.786112 -388.797979)
			(xy 127.257251 -388.797979) (xy 127.556006 -389.314944) (xy 127.55626 -389.315452) (xy 127.556514 -389.315452)
			(xy 127.557784 -389.317992) (xy 127.570054 -389.340909) (xy 127.587461 -389.389886) (xy 127.596336 -389.441101)
			(xy 127.5969 -389.46709) (xy 127.5969 -389.467344) (xy 127.596479 -389.491324) (xy 127.588974 -389.538694)
			(xy 127.574156 -389.584307) (xy 127.552388 -389.627044) (xy 127.524207 -389.665851) (xy 127.490305 -389.699775)
			(xy 127.451516 -389.727982) (xy 127.408794 -389.749778) (xy 127.36319 -389.764627) (xy 127.315826 -389.772163)
			(xy 127.291846 -389.772652) (xy 127.291338 -389.772652) (xy 127.267675 -389.772182) (xy 127.220915 -389.764877)
			(xy 127.17584 -389.750452) (xy 127.133528 -389.729251) (xy 127.094989 -389.70178) (xy 127.061146 -389.668698)
			(xy 127.032807 -389.630794) (xy 127.021336 -389.610092) (xy 127.021082 -389.60933) (xy 126.623826 -388.922006)
			(xy 126.611619 -388.898734) (xy 126.594503 -388.849053) (xy 126.58979 -388.8232) (xy 126.586378 -388.799387)
			(xy 126.586167 -388.751284) (xy 126.030115 -388.751284) (xy 126.355856 -389.314944) (xy 126.35611 -389.315452)
			(xy 126.356364 -389.315452) (xy 126.357634 -389.317992) (xy 126.369868 -389.340915) (xy 126.387188 -389.389902)
			(xy 126.395975 -389.441111) (xy 126.396496 -389.46709) (xy 126.396496 -389.467344) (xy 126.396078 -389.491337)
			(xy 126.388565 -389.538731) (xy 126.373731 -389.584367) (xy 126.351941 -389.627121) (xy 126.323731 -389.665939)
			(xy 126.289797 -389.699868) (xy 126.250973 -389.72807) (xy 126.208215 -389.749852) (xy 126.162577 -389.764678)
			(xy 126.115181 -389.772182) (xy 126.091188 -389.772652) (xy 126.067523 -389.772222) (xy 126.020762 -389.76491)
			(xy 125.975686 -389.750477) (xy 125.933374 -389.729269) (xy 125.894836 -389.701793) (xy 125.860994 -389.668705)
			(xy 125.832656 -389.630796) (xy 125.821186 -389.610092) (xy 125.820932 -389.60933) (xy 125.423676 -388.922006)
			(xy 125.411466 -388.898736) (xy 125.394352 -388.849053) (xy 125.38964 -388.8232) (xy 125.386134 -388.799398)
			(xy 125.385922 -388.751286) (xy 124.830221 -388.751286) (xy 125.15596 -389.314944) (xy 125.156214 -389.315452)
			(xy 125.156468 -389.315452) (xy 125.157738 -389.317992) (xy 125.169973 -389.340917) (xy 125.187309 -389.389899)
			(xy 125.196097 -389.44111) (xy 125.1966 -389.46709) (xy 125.1966 -389.467344) (xy 125.196126 -389.491333)
			(xy 125.188614 -389.538719) (xy 125.173783 -389.584346) (xy 125.151997 -389.627092) (xy 125.123793 -389.665904)
			(xy 125.089865 -389.699827) (xy 125.051048 -389.728024) (xy 125.008298 -389.749803) (xy 124.962668 -389.764627)
			(xy 124.915281 -389.77213) (xy 124.891292 -389.772652) (xy 124.867628 -389.772207) (xy 124.820866 -389.764906)
			(xy 124.77579 -389.750479) (xy 124.733478 -389.729273) (xy 124.694944 -389.701793) (xy 124.661109 -389.6687)
			(xy 124.632784 -389.630783) (xy 124.62129 -389.610092) (xy 124.621036 -389.60933) (xy 124.22378 -388.922006)
			(xy 124.211581 -388.89873) (xy 124.19446 -388.849052) (xy 124.189744 -388.8232) (xy 124.186351 -388.799838)
			(xy 124.185973 -388.752634) (xy 124.188982 -388.72922) (xy 124.190252 -388.72033) (xy 124.18695 -388.702804)
			(xy 124.143262 -388.631938) (xy 124.129546 -388.620762) (xy 124.12091 -388.617968) (xy 124.096643 -388.609214)
			(xy 124.051228 -388.584754) (xy 124.01056 -388.553022) (xy 123.975792 -388.514916) (xy 123.961398 -388.493508)
			(xy 123.95654 -388.486553) (xy 123.943213 -388.47607) (xy 123.927203 -388.470488) (xy 123.918726 -388.47014)
			(xy 123.644152 -388.47014) (xy 123.635258 -388.470472) (xy 123.618543 -388.476551) (xy 123.604924 -388.487992)
			(xy 123.60021 -388.49554) (xy 123.556268 -388.57174) (xy 123.552189 -388.579583) (xy 123.549083 -388.596973)
			(xy 123.552035 -388.61439) (xy 123.556014 -388.622286) (xy 123.56338 -388.635494) (xy 123.563888 -388.636764)
			(xy 123.95581 -389.314944) (xy 123.956064 -389.315452) (xy 123.956318 -389.315452) (xy 123.957588 -389.317992)
			(xy 123.969856 -389.340909) (xy 123.987264 -389.389886) (xy 123.996131 -389.441102) (xy 123.996704 -389.46709)
			(xy 123.996704 -389.467344) (xy 123.996231 -389.49132) (xy 123.988727 -389.538682) (xy 123.973911 -389.584288)
			(xy 123.952148 -389.627017) (xy 123.923971 -389.665818) (xy 123.890075 -389.699737) (xy 123.851293 -389.72794)
			(xy 123.808579 -389.749733) (xy 123.762982 -389.764579) (xy 123.715626 -389.772115) (xy 123.69165 -389.772652)
			(xy 123.691142 -389.772652) (xy 123.667476 -389.772211) (xy 123.620709 -389.764916) (xy 123.575627 -389.750495)
			(xy 123.53331 -389.729292) (xy 123.494769 -389.701815) (xy 123.460929 -389.668721) (xy 123.432598 -389.630804)
			(xy 123.42114 -389.610092) (xy 123.420886 -389.60933) (xy 123.02363 -388.922006) (xy 123.011433 -388.89873)
			(xy 122.994315 -388.849051) (xy 122.989594 -388.8232) (xy 122.986202 -388.799838) (xy 122.985823 -388.752634)
			(xy 122.988832 -388.72922) (xy 122.990102 -388.72033) (xy 122.9868 -388.702804) (xy 122.943112 -388.631938)
			(xy 122.929396 -388.620762) (xy 122.921014 -388.617968) (xy 122.896747 -388.609215) (xy 122.851331 -388.584755)
			(xy 122.810663 -388.553023) (xy 122.775895 -388.514917) (xy 122.761502 -388.493508) (xy 122.756644 -388.486553)
			(xy 122.743318 -388.476068) (xy 122.727307 -388.470485) (xy 122.71883 -388.47014) (xy 122.444256 -388.47014)
			(xy 122.435362 -388.470471) (xy 122.418646 -388.47655) (xy 122.405026 -388.48799) (xy 122.400314 -388.49554)
			(xy 122.356372 -388.57174) (xy 122.352292 -388.579583) (xy 122.349187 -388.596973) (xy 122.352139 -388.61439)
			(xy 122.356118 -388.622286) (xy 122.363484 -388.635494) (xy 122.363992 -388.636764) (xy 122.755914 -389.314944)
			(xy 122.756168 -389.315452) (xy 122.756422 -389.315452) (xy 122.757692 -389.317992) (xy 122.76996 -389.340909)
			(xy 122.787368 -389.389886) (xy 122.796234 -389.441102) (xy 122.796808 -389.46709) (xy 122.796808 -389.467344)
			(xy 122.796335 -389.49132) (xy 122.788831 -389.538682) (xy 122.774016 -389.584289) (xy 122.752252 -389.627018)
			(xy 122.724076 -389.66582) (xy 122.69018 -389.699739) (xy 122.651397 -389.727942) (xy 122.608683 -389.749735)
			(xy 122.563087 -389.764582) (xy 122.51573 -389.772119) (xy 122.491754 -389.772652) (xy 122.491246 -389.772652)
			(xy 122.46758 -389.772211) (xy 122.420812 -389.764917) (xy 122.37573 -389.750496) (xy 122.333412 -389.729293)
			(xy 122.294871 -389.701816) (xy 122.26103 -389.668723) (xy 122.232699 -389.630806) (xy 122.221244 -389.610092)
			(xy 122.22099 -389.60933) (xy 121.823734 -388.922006) (xy 121.811537 -388.89873) (xy 121.794419 -388.849051)
			(xy 121.789698 -388.8232) (xy 121.786306 -388.799838) (xy 121.785927 -388.752634) (xy 121.788936 -388.72922)
			(xy 121.790206 -388.72033) (xy 121.786904 -388.702804) (xy 121.743216 -388.631938) (xy 121.7295 -388.620762)
			(xy 121.720864 -388.617968) (xy 121.698073 -388.609814) (xy 121.655207 -388.587337) (xy 121.616424 -388.558378)
			(xy 121.582696 -388.523663) (xy 121.554868 -388.48406) (xy 121.543826 -388.46252) (xy 121.54009 -388.455482)
			(xy 121.529102 -388.443955) (xy 121.522236 -388.439914) (xy 121.506022 -388.430811) (xy 121.476184 -388.408626)
			(xy 121.4628 -388.395718) (xy 120.979946 -387.912864) (xy 120.962686 -387.894823) (xy 120.934929 -387.853329)
			(xy 120.915815 -387.807211) (xy 120.906082 -387.758247) (xy 120.905524 -387.733286) (xy 120.905524 -385.959096)
			(xy 120.905329 -385.952429) (xy 120.901854 -385.939555) (xy 120.898666 -385.933696) (xy 120.623838 -385.457954)
			(xy 120.611944 -385.435284) (xy 120.595078 -385.386953) (xy 120.586526 -385.336483) (xy 120.585992 -385.310888)
			(xy 120.585992 -385.31038) (xy 120.586487 -385.285456) (xy 120.594583 -385.236269) (xy 120.610556 -385.18905)
			(xy 120.633984 -385.145049) (xy 120.664244 -385.105436) (xy 120.700534 -385.071262) (xy 120.74189 -385.043432)
			(xy 120.787216 -385.022685) (xy 120.835309 -385.009571) (xy 120.860058 -385.006596) (xy 120.879616 -385.004564)
			(xy 120.905524 -384.975608) (xy 120.905524 -384.168396) (xy 120.905101 -384.158326) (xy 120.897388 -384.13972)
			(xy 120.890538 -384.132328) (xy 120.70461 -383.9464) (xy 120.697212 -383.939552) (xy 120.678614 -383.931814)
			(xy 120.668542 -383.931414) (xy 111.526066 -383.931414) (xy 111.513442 -383.932006) (xy 111.491163 -383.943862)
			(xy 111.483648 -383.95402) (xy 111.468449 -383.976163) (xy 111.43282 -384.016349) (xy 111.391898 -384.051132)
			(xy 111.346496 -384.07982) (xy 111.297514 -384.101846) (xy 111.245923 -384.116772) (xy 111.192747 -384.124302)
			(xy 111.165894 -384.124708) (xy 111.137047 -384.124179) (xy 111.080012 -384.115491) (xy 111.024935 -384.098314)
			(xy 110.973073 -384.07304) (xy 110.925607 -384.040246) (xy 110.904274 -384.020822) (xy 110.896908 -384.013964)
			(xy 110.87862 -384.006852) (xy 110.797848 -384.008122) (xy 110.788075 -384.008704) (xy 110.770037 -384.016267)
			(xy 110.762796 -384.022854) (xy 110.604554 -384.181096) (xy 110.597701 -384.188492) (xy 110.589957 -384.20709)
			(xy 110.589568 -384.217164) (xy 110.589568 -385.310888) (xy 114.586004 -385.310888) (xy 114.586004 -385.31038)
			(xy 114.586444 -385.286388) (xy 114.593954 -385.238994) (xy 114.608785 -385.193359) (xy 114.630572 -385.150605)
			(xy 114.658779 -385.111786) (xy 114.692711 -385.077858) (xy 114.731533 -385.049655) (xy 114.774288 -385.027872)
			(xy 114.819925 -385.013046) (xy 114.86732 -385.005542) (xy 114.891312 -385.005072) (xy 114.915246 -385.00557)
			(xy 114.962529 -385.013022) (xy 115.008071 -385.027757) (xy 115.050758 -385.049416) (xy 115.089544 -385.077467)
			(xy 115.12348 -385.111224) (xy 115.151736 -385.149861) (xy 115.163092 -385.170934) (xy 115.1636 -385.17195)
			(xy 115.243906 -385.310888) (xy 115.7859 -385.310888) (xy 115.7859 -385.31038) (xy 115.786344 -385.286388)
			(xy 115.793854 -385.238995) (xy 115.808684 -385.19336) (xy 115.830471 -385.150606) (xy 115.858677 -385.111788)
			(xy 115.892609 -385.077859) (xy 115.93143 -385.049656) (xy 115.974186 -385.027873) (xy 116.019822 -385.013047)
			(xy 116.067216 -385.005542) (xy 116.091208 -385.005072) (xy 116.115141 -385.005573) (xy 116.162424 -385.013024)
			(xy 116.207967 -385.027759) (xy 116.250653 -385.049417) (xy 116.289439 -385.077468) (xy 116.323376 -385.111224)
			(xy 116.351632 -385.149861) (xy 116.362988 -385.170934) (xy 116.363496 -385.17195) (xy 116.443802 -385.310888)
			(xy 116.985796 -385.310888) (xy 116.985796 -385.31038) (xy 116.986244 -385.286388) (xy 116.993753 -385.238995)
			(xy 117.008584 -385.193361) (xy 117.03037 -385.150608) (xy 117.058576 -385.111789) (xy 117.092507 -385.077861)
			(xy 117.131328 -385.049658) (xy 117.174083 -385.027875) (xy 117.219719 -385.013048) (xy 117.267112 -385.005542)
			(xy 117.291104 -385.005072) (xy 117.315037 -385.005576) (xy 117.36232 -385.013027) (xy 117.407862 -385.027762)
			(xy 117.450549 -385.049419) (xy 117.489335 -385.077469) (xy 117.523272 -385.111225) (xy 117.551528 -385.149861)
			(xy 117.562884 -385.170934) (xy 117.563392 -385.17195) (xy 117.643698 -385.310888) (xy 118.185692 -385.310888)
			(xy 118.185692 -385.31038) (xy 118.186143 -385.286401) (xy 118.193644 -385.239033) (xy 118.208459 -385.19342)
			(xy 118.230223 -385.150685) (xy 118.258401 -385.111877) (xy 118.292299 -385.077953) (xy 118.331085 -385.049745)
			(xy 118.373804 -385.027949) (xy 118.419405 -385.013099) (xy 118.466767 -385.005562) (xy 118.490746 -385.005072)
			(xy 118.491254 -385.005072) (xy 118.515189 -385.005536) (xy 118.562474 -385.012994) (xy 118.608017 -385.027736)
			(xy 118.650703 -385.0494) (xy 118.689489 -385.077456) (xy 118.723424 -385.111218) (xy 118.751679 -385.149859)
			(xy 118.763034 -385.170934) (xy 118.763542 -385.17195) (xy 118.843848 -385.310888) (xy 119.385588 -385.310888)
			(xy 119.385588 -385.31038) (xy 119.386043 -385.286401) (xy 119.393544 -385.239034) (xy 119.408359 -385.193421)
			(xy 119.430122 -385.150686) (xy 119.458299 -385.111879) (xy 119.492198 -385.077954) (xy 119.530983 -385.049747)
			(xy 119.573701 -385.02795) (xy 119.619302 -385.0131) (xy 119.666663 -385.005562) (xy 119.690642 -385.005072)
			(xy 119.69115 -385.005072) (xy 119.715085 -385.005539) (xy 119.762369 -385.012997) (xy 119.807912 -385.027738)
			(xy 119.850599 -385.049401) (xy 119.889384 -385.077457) (xy 119.92332 -385.111218) (xy 119.951575 -385.149859)
			(xy 119.96293 -385.170934) (xy 119.963438 -385.17195) (xy 120.355868 -385.850892) (xy 120.368606 -385.874207)
			(xy 120.386697 -385.924157) (xy 120.395912 -385.976476) (xy 120.396508 -386.003038) (xy 120.396508 -386.003292)
			(xy 120.396054 -386.027285) (xy 120.388549 -386.07468) (xy 120.373721 -386.120318) (xy 120.351937 -386.163074)
			(xy 120.323732 -386.201896) (xy 120.289802 -386.235827) (xy 120.250981 -386.264033) (xy 120.208225 -386.285818)
			(xy 120.162588 -386.300647) (xy 120.115193 -386.308154) (xy 120.0912 -386.3086) (xy 120.067626 -386.308206)
			(xy 120.021038 -386.300965) (xy 119.976119 -386.286639) (xy 119.933941 -386.26557) (xy 119.895508 -386.238261)
			(xy 119.861736 -386.205361) (xy 119.83343 -386.167656) (xy 119.82196 -386.147056) (xy 119.821452 -386.146294)
			(xy 119.423688 -385.457954) (xy 119.411753 -385.435296) (xy 119.394823 -385.386965) (xy 119.386171 -385.336491)
			(xy 119.385588 -385.310888) (xy 118.843848 -385.310888) (xy 119.155972 -385.850892) (xy 119.168711 -385.874207)
			(xy 119.186801 -385.924157) (xy 119.196016 -385.976476) (xy 119.196612 -386.003038) (xy 119.196612 -386.003292)
			(xy 119.196154 -386.027285) (xy 119.188649 -386.07468) (xy 119.173822 -386.120317) (xy 119.152038 -386.163073)
			(xy 119.123834 -386.201894) (xy 119.089903 -386.235826) (xy 119.051083 -386.264032) (xy 119.008328 -386.285817)
			(xy 118.962691 -386.300646) (xy 118.915297 -386.308154) (xy 118.891304 -386.3086) (xy 118.86773 -386.308203)
			(xy 118.821142 -386.300962) (xy 118.776223 -386.286637) (xy 118.734045 -386.265569) (xy 118.695612 -386.23826)
			(xy 118.66184 -386.205361) (xy 118.633535 -386.167656) (xy 118.622064 -386.147056) (xy 118.621556 -386.146294)
			(xy 118.223792 -385.457954) (xy 118.211857 -385.435295) (xy 118.194927 -385.386965) (xy 118.186275 -385.336491)
			(xy 118.185692 -385.310888) (xy 117.643698 -385.310888) (xy 117.955822 -385.850892) (xy 117.968645 -385.874225)
			(xy 117.986866 -385.924248) (xy 117.996127 -385.976673) (xy 117.996716 -386.003292) (xy 117.996231 -386.02727)
			(xy 117.988734 -386.074636) (xy 117.973924 -386.120248) (xy 117.952164 -386.162983) (xy 117.92399 -386.20179)
			(xy 117.890096 -386.235715) (xy 117.851313 -386.263923) (xy 117.808598 -386.28572) (xy 117.762999 -386.300571)
			(xy 117.71564 -386.30811) (xy 117.691662 -386.3086) (xy 117.691154 -386.3086) (xy 117.667582 -386.308163)
			(xy 117.620995 -386.300929) (xy 117.576078 -386.286611) (xy 117.533899 -386.26555) (xy 117.495466 -386.238247)
			(xy 117.461693 -386.205353) (xy 117.433385 -386.167653) (xy 117.421914 -386.147056) (xy 117.421406 -386.146294)
			(xy 117.023642 -385.457954) (xy 117.011782 -385.435269) (xy 116.994926 -385.38694) (xy 116.986346 -385.33648)
			(xy 116.985796 -385.310888) (xy 116.443802 -385.310888) (xy 116.755926 -385.850892) (xy 116.76875 -385.874225)
			(xy 116.786971 -385.924247) (xy 116.796231 -385.976673) (xy 116.79682 -386.003292) (xy 116.796331 -386.02727)
			(xy 116.788835 -386.074636) (xy 116.774024 -386.120247) (xy 116.752265 -386.162982) (xy 116.724092 -386.201789)
			(xy 116.690197 -386.235713) (xy 116.651416 -386.263922) (xy 116.6087 -386.285719) (xy 116.563102 -386.30057)
			(xy 116.515743 -386.30811) (xy 116.491766 -386.3086) (xy 116.491258 -386.3086) (xy 116.467686 -386.308159)
			(xy 116.4211 -386.300927) (xy 116.376182 -386.286609) (xy 116.334004 -386.265548) (xy 116.29557 -386.238246)
			(xy 116.261797 -386.205353) (xy 116.23349 -386.167653) (xy 116.222018 -386.147056) (xy 116.22151 -386.146294)
			(xy 115.823746 -385.457954) (xy 115.811886 -385.435269) (xy 115.79503 -385.38694) (xy 115.78645 -385.33648)
			(xy 115.7859 -385.310888) (xy 115.243906 -385.310888) (xy 115.55603 -385.850892) (xy 115.568854 -385.874225)
			(xy 115.587075 -385.924247) (xy 115.596335 -385.976673) (xy 115.596924 -386.003292) (xy 115.596431 -386.02727)
			(xy 115.588935 -386.074635) (xy 115.574125 -386.120246) (xy 115.552366 -386.16298) (xy 115.524193 -386.201787)
			(xy 115.490299 -386.235712) (xy 115.451518 -386.26392) (xy 115.408803 -386.285718) (xy 115.363206 -386.30057)
			(xy 115.315847 -386.308109) (xy 115.29187 -386.3086) (xy 115.291362 -386.3086) (xy 115.26779 -386.308156)
			(xy 115.221204 -386.300924) (xy 115.176286 -386.286607) (xy 115.134108 -386.265547) (xy 115.095674 -386.238245)
			(xy 115.061901 -386.205352) (xy 115.033594 -386.167653) (xy 115.022122 -386.147056) (xy 115.021614 -386.146294)
			(xy 114.62385 -385.457954) (xy 114.611991 -385.435269) (xy 114.595134 -385.38694) (xy 114.586554 -385.33648)
			(xy 114.586004 -385.310888) (xy 110.589568 -385.310888) (xy 110.589568 -386.934202) (xy 110.588996 -386.959162)
			(xy 110.579256 -387.008123) (xy 110.56015 -387.054242) (xy 110.532413 -387.095748) (xy 110.515146 -387.11378)
			(xy 109.939074 -387.689852) (xy 109.921033 -387.707112) (xy 109.87954 -387.734872) (xy 109.833422 -387.753988)
			(xy 109.784458 -387.763723) (xy 109.759496 -387.764274) (xy 108.794296 -387.764274) (xy 108.765086 -387.79196)
			(xy 108.763816 -387.812026) (xy 108.761727 -387.839446) (xy 108.75066 -387.893313) (xy 108.731978 -387.945034)
			(xy 108.706066 -387.993537) (xy 108.67346 -388.03782) (xy 108.634837 -388.076965) (xy 108.590996 -388.110161)
			(xy 108.542844 -388.136721) (xy 108.491378 -388.156096) (xy 108.437665 -388.167883) (xy 108.382816 -388.17184)
			(xy 108.327967 -388.167883) (xy 108.274254 -388.156096) (xy 108.222788 -388.136721) (xy 108.174636 -388.110161)
			(xy 108.130795 -388.076965) (xy 108.092172 -388.03782) (xy 108.059566 -387.993537) (xy 108.033654 -387.945034)
			(xy 108.014972 -387.893313) (xy 108.003905 -387.839446) (xy 108.001816 -387.812026) (xy 108.000546 -387.79196)
			(xy 107.971336 -387.764274) (xy 102.595172 -387.764274) (xy 102.585103 -387.764702) (xy 102.566504 -387.77242)
			(xy 102.559104 -387.77926) (xy 102.240334 -388.09803) (xy 102.222293 -388.115289) (xy 102.180799 -388.143044)
			(xy 102.134681 -388.162154) (xy 102.085717 -388.171883) (xy 102.060756 -388.172452) (xy 93.805248 -388.172452)
			(xy 93.78029 -388.171876) (xy 93.731335 -388.162127) (xy 93.685223 -388.143013) (xy 93.643726 -388.11527)
			(xy 93.62567 -388.09803) (xy 93.467936 -387.940296) (xy 93.431614 -387.93674) (xy 93.416628 -387.9469)
			(xy 93.397642 -387.959198) (xy 93.356808 -387.978659) (xy 93.313548 -387.99188) (xy 93.268811 -387.99857)
			(xy 93.246194 -387.99897) (xy 93.222202 -387.998523) (xy 93.17481 -387.991016) (xy 93.129175 -387.976186)
			(xy 93.086423 -387.9544) (xy 93.047605 -387.926193) (xy 93.013678 -387.892261) (xy 92.985477 -387.85344)
			(xy 92.963697 -387.810684) (xy 92.948874 -387.765047) (xy 92.941373 -387.717654) (xy 92.940886 -387.693662)
			(xy 92.941293 -387.671044) (xy 92.947967 -387.626302) (xy 92.961178 -387.583038) (xy 92.980637 -387.542201)
			(xy 92.992956 -387.523228) (xy 93.003116 -387.508242) (xy 92.99956 -387.47192) (xy 92.330524 -386.802884)
			(xy 92.323125 -386.79604) (xy 92.304526 -386.78832) (xy 92.294456 -386.787898) (xy 91.857322 -386.787898)
			(xy 91.847258 -386.788336) (xy 91.828674 -386.79607) (xy 91.821254 -386.802884) (xy 91.127834 -387.496304)
			(xy 91.120696 -387.504248) (xy 91.113049 -387.524162) (xy 91.114112 -387.545468) (xy 91.118436 -387.555232)
			(xy 91.118436 -387.555486) (xy 91.128833 -387.577021) (xy 91.143545 -387.622519) (xy 91.150986 -387.669753)
			(xy 91.151456 -387.693662) (xy 91.150988 -387.717657) (xy 91.143487 -387.765056) (xy 91.128664 -387.810698)
			(xy 91.106883 -387.853459) (xy 91.078681 -387.892287) (xy 91.044753 -387.926225) (xy 91.005933 -387.954438)
			(xy 90.963177 -387.976231) (xy 90.917539 -387.991067) (xy 90.870142 -387.998581) (xy 90.846148 -387.99897)
			(xy 90.82224 -387.998503) (xy 90.775008 -387.99105) (xy 90.729513 -387.976333) (xy 90.707972 -387.96595)
			(xy 90.707718 -387.96595) (xy 90.697983 -387.961498) (xy 90.676625 -387.960383) (xy 90.656683 -387.968113)
			(xy 90.64879 -387.975348) (xy 90.210132 -388.414006) (xy 90.202175 -388.421754) (xy 90.185131 -388.435996)
			(xy 90.176096 -388.442454) (xy 90.175334 -388.442962) (xy 90.171016 -388.446264) (xy 90.160348 -388.464044)
			(xy 90.148918 -388.546848) (xy 90.147954 -388.557041) (xy 90.153208 -388.576812) (xy 90.159078 -388.585202)
			(xy 90.168205 -388.597062) (xy 90.184362 -388.622253) (xy 90.191336 -388.635494) (xy 90.191844 -388.636764)
			(xy 90.258027 -388.751286) (xy 90.813717 -388.751286) (xy 90.821049 -388.703734) (xy 90.835743 -388.65792)
			(xy 90.857436 -388.614974) (xy 90.885592 -388.57596) (xy 90.919515 -388.54184) (xy 90.958366 -388.513459)
			(xy 91.001186 -388.491518) (xy 91.046915 -388.47656) (xy 91.094423 -388.468953) (xy 91.142537 -388.468887)
			(xy 91.190066 -388.476363) (xy 91.235836 -388.491195) (xy 91.278716 -388.513018) (xy 91.317645 -388.541292)
			(xy 91.351662 -388.575318) (xy 91.379925 -388.614255) (xy 91.391232 -388.635494) (xy 91.39174 -388.636764)
			(xy 91.457921 -388.751284) (xy 92.013962 -388.751284) (xy 92.021293 -388.703741) (xy 92.035985 -388.657935)
			(xy 92.057674 -388.614997) (xy 92.085825 -388.575989) (xy 92.119742 -388.541876) (xy 92.158586 -388.5135)
			(xy 92.201397 -388.491562) (xy 92.247118 -388.476605) (xy 92.294617 -388.468999) (xy 92.342722 -388.468931)
			(xy 92.390243 -388.476403) (xy 92.436005 -388.491231) (xy 92.478878 -388.513048) (xy 92.517802 -388.541314)
			(xy 92.551815 -388.575332) (xy 92.580076 -388.61426) (xy 92.591382 -388.635494) (xy 92.59189 -388.636764)
			(xy 92.658071 -388.751284) (xy 93.213865 -388.751284) (xy 93.221197 -388.703741) (xy 93.235888 -388.657936)
			(xy 93.257577 -388.614999) (xy 93.285728 -388.575992) (xy 93.319644 -388.541879) (xy 93.358487 -388.513503)
			(xy 93.401298 -388.491565) (xy 93.447018 -388.476609) (xy 93.494517 -388.469002) (xy 93.542621 -388.468934)
			(xy 93.590141 -388.476406) (xy 93.635903 -388.491234) (xy 93.678775 -388.51305) (xy 93.717699 -388.541316)
			(xy 93.751711 -388.575333) (xy 93.779972 -388.61426) (xy 93.791278 -388.635494) (xy 93.791786 -388.636764)
			(xy 93.884953 -388.797979) (xy 94.413811 -388.797979) (xy 94.414059 -388.747044) (xy 94.422753 -388.696855)
			(xy 94.43965 -388.648804) (xy 94.464283 -388.604221) (xy 94.49597 -388.564341) (xy 94.533833 -388.530269)
			(xy 94.576822 -388.502949) (xy 94.623747 -388.483138) (xy 94.673308 -388.471385) (xy 94.724132 -388.468014)
			(xy 94.774811 -388.47312) (xy 94.823942 -388.486562) (xy 94.870162 -388.507966) (xy 94.912192 -388.536739)
			(xy 94.948868 -388.572086) (xy 94.979173 -388.613025) (xy 94.991174 -388.635494) (xy 94.991682 -388.636764)
			(xy 95.057865 -388.751286) (xy 95.613824 -388.751286) (xy 95.621156 -388.703735) (xy 95.63585 -388.657922)
			(xy 95.657542 -388.614978) (xy 95.685697 -388.575964) (xy 95.719619 -388.541846) (xy 95.75847 -388.513466)
			(xy 95.801288 -388.491525) (xy 95.847015 -388.476567) (xy 95.894522 -388.468961) (xy 95.942634 -388.468894)
			(xy 95.990162 -388.476369) (xy 96.035931 -388.491201) (xy 96.07881 -388.513023) (xy 96.117738 -388.541296)
			(xy 96.151754 -388.57532) (xy 96.180017 -388.614256) (xy 96.191324 -388.635494) (xy 96.191832 -388.636764)
			(xy 96.258014 -388.751285) (xy 96.813728 -388.751285) (xy 96.821059 -388.703736) (xy 96.835753 -388.657923)
			(xy 96.857445 -388.61498) (xy 96.8856 -388.575967) (xy 96.919522 -388.541849) (xy 96.958371 -388.513469)
			(xy 97.001189 -388.491529) (xy 97.046916 -388.476571) (xy 97.094422 -388.468964) (xy 97.142533 -388.468898)
			(xy 97.19006 -388.476372) (xy 97.235829 -388.491204) (xy 97.278707 -388.513025) (xy 97.317635 -388.541297)
			(xy 97.351651 -388.575321) (xy 97.379913 -388.614256) (xy 97.39122 -388.635494) (xy 97.391728 -388.636764)
			(xy 97.484894 -388.797978) (xy 98.014014 -388.797978) (xy 98.014263 -388.747044) (xy 98.022956 -388.696856)
			(xy 98.039853 -388.648805) (xy 98.064486 -388.604223) (xy 98.096173 -388.564344) (xy 98.134034 -388.530272)
			(xy 98.177023 -388.502953) (xy 98.223948 -388.483142) (xy 98.273508 -388.471388) (xy 98.324331 -388.468018)
			(xy 98.37501 -388.473124) (xy 98.424139 -388.486565) (xy 98.470359 -388.507968) (xy 98.512389 -388.536741)
			(xy 98.549064 -388.572087) (xy 98.579369 -388.613026) (xy 98.59137 -388.635494) (xy 98.591878 -388.636764)
			(xy 98.65806 -388.751285) (xy 114.586146 -388.751285) (xy 114.593477 -388.703739) (xy 114.60817 -388.657929)
			(xy 114.629861 -388.614989) (xy 114.658013 -388.575979) (xy 114.691932 -388.541863) (xy 114.730779 -388.513485)
			(xy 114.773593 -388.491546) (xy 114.819317 -388.476589) (xy 114.866819 -388.468982) (xy 114.914927 -388.468915)
			(xy 114.962451 -388.476388) (xy 115.008216 -388.491218) (xy 115.051092 -388.513037) (xy 115.090018 -388.541306)
			(xy 115.124032 -388.575327) (xy 115.152294 -388.614258) (xy 115.1636 -388.635494) (xy 115.164108 -388.636764)
			(xy 115.230289 -388.751284) (xy 115.786049 -388.751284) (xy 115.793381 -388.703739) (xy 115.808073 -388.65793)
			(xy 115.829764 -388.614991) (xy 115.857916 -388.575981) (xy 115.891834 -388.541866) (xy 115.93068 -388.513488)
			(xy 115.973494 -388.49155) (xy 116.019217 -388.476592) (xy 116.066719 -388.468986) (xy 116.114826 -388.468918)
			(xy 116.162349 -388.476392) (xy 116.208114 -388.491221) (xy 116.250989 -388.513039) (xy 116.289914 -388.541308)
			(xy 116.323928 -388.575328) (xy 116.35219 -388.614259) (xy 116.363496 -388.635494) (xy 116.364004 -388.636764)
			(xy 116.430185 -388.751284) (xy 116.985953 -388.751284) (xy 116.993284 -388.70374) (xy 117.007977 -388.657932)
			(xy 117.029667 -388.614992) (xy 117.057819 -388.575983) (xy 117.091737 -388.541869) (xy 117.130582 -388.513491)
			(xy 117.173395 -388.491553) (xy 117.219117 -388.476596) (xy 117.266618 -388.468989) (xy 117.314725 -388.468922)
			(xy 117.362247 -388.476395) (xy 117.408011 -388.491224) (xy 117.450886 -388.513042) (xy 117.489811 -388.54131)
			(xy 117.523824 -388.575329) (xy 117.552086 -388.614259) (xy 117.563392 -388.635494) (xy 117.5639 -388.636764)
			(xy 117.630083 -388.751286) (xy 118.186008 -388.751286) (xy 118.19334 -388.703733) (xy 118.208035 -388.657917)
			(xy 118.229728 -388.61497) (xy 118.257886 -388.575954) (xy 118.29181 -388.541833) (xy 118.330663 -388.513451)
			(xy 118.373484 -388.491509) (xy 118.419215 -388.476551) (xy 118.466725 -388.468944) (xy 118.51484 -388.468878)
			(xy 118.562371 -388.476355) (xy 118.608142 -388.491188) (xy 118.651023 -388.513012) (xy 118.689954 -388.541288)
			(xy 118.723971 -388.575315) (xy 118.752235 -388.614254) (xy 118.763542 -388.635494) (xy 118.76405 -388.636764)
			(xy 118.830233 -388.751286) (xy 119.385912 -388.751286) (xy 119.393244 -388.703734) (xy 119.407938 -388.657918)
			(xy 119.429632 -388.614971) (xy 119.457788 -388.575956) (xy 119.491712 -388.541836) (xy 119.530564 -388.513454)
			(xy 119.573385 -388.491513) (xy 119.619115 -388.476554) (xy 119.666624 -388.468948) (xy 119.714739 -388.468882)
			(xy 119.762269 -388.476358) (xy 119.80804 -388.491191) (xy 119.85092 -388.513015) (xy 119.88985 -388.54129)
			(xy 119.923868 -388.575317) (xy 119.952131 -388.614255) (xy 119.963438 -388.635494) (xy 119.963946 -388.636764)
			(xy 120.030127 -388.751284) (xy 120.586156 -388.751284) (xy 120.593488 -388.70374) (xy 120.60818 -388.657933)
			(xy 120.62987 -388.614994) (xy 120.658021 -388.575986) (xy 120.691939 -388.541872) (xy 120.730784 -388.513495)
			(xy 120.773596 -388.491557) (xy 120.819317 -388.476599) (xy 120.866818 -388.468993) (xy 120.914924 -388.468925)
			(xy 120.962446 -388.476398) (xy 121.008209 -388.491226) (xy 121.051083 -388.513044) (xy 121.090007 -388.541311)
			(xy 121.124021 -388.57533) (xy 121.152282 -388.614259) (xy 121.163588 -388.635494) (xy 121.164096 -388.636764)
			(xy 121.556018 -389.314944) (xy 121.556272 -389.315452) (xy 121.556526 -389.315452) (xy 121.557796 -389.317992)
			(xy 121.570067 -389.340908) (xy 121.587474 -389.389886) (xy 121.596348 -389.441101) (xy 121.596912 -389.46709)
			(xy 121.596912 -389.467344) (xy 121.596479 -389.491324) (xy 121.588974 -389.538692) (xy 121.574157 -389.584305)
			(xy 121.55239 -389.62704) (xy 121.52421 -389.665847) (xy 121.49031 -389.699771) (xy 121.451523 -389.727978)
			(xy 121.408803 -389.749775) (xy 121.3632 -389.764624) (xy 121.315837 -389.772162) (xy 121.291858 -389.772652)
			(xy 121.29135 -389.772652) (xy 121.267687 -389.772172) (xy 121.220928 -389.764869) (xy 121.175853 -389.750446)
			(xy 121.133541 -389.729246) (xy 121.095002 -389.701777) (xy 121.061159 -389.668696) (xy 121.032819 -389.630793)
			(xy 121.021348 -389.610092) (xy 121.021094 -389.60933) (xy 120.623838 -388.922006) (xy 120.611625 -388.898737)
			(xy 120.594514 -388.849054) (xy 120.589802 -388.8232) (xy 120.586367 -388.799389) (xy 120.586156 -388.751284)
			(xy 120.030127 -388.751284) (xy 120.355868 -389.314944) (xy 120.356122 -389.315452) (xy 120.356376 -389.315452)
			(xy 120.357646 -389.317992) (xy 120.369881 -389.340915) (xy 120.3872 -389.389902) (xy 120.395987 -389.441111)
			(xy 120.396508 -389.46709) (xy 120.396508 -389.467344) (xy 120.396078 -389.491336) (xy 120.388565 -389.53873)
			(xy 120.373732 -389.584364) (xy 120.351943 -389.627117) (xy 120.323735 -389.665935) (xy 120.289802 -389.699863)
			(xy 120.250979 -389.728066) (xy 120.208224 -389.749849) (xy 120.162587 -389.764676) (xy 120.115192 -389.772181)
			(xy 120.0912 -389.772652) (xy 120.067536 -389.772213) (xy 120.020775 -389.764902) (xy 119.975699 -389.750471)
			(xy 119.933387 -389.729265) (xy 119.894849 -389.70179) (xy 119.861006 -389.668703) (xy 119.832668 -389.630796)
			(xy 119.821198 -389.610092) (xy 119.820944 -389.60933) (xy 119.423688 -388.922006) (xy 119.411479 -388.898735)
			(xy 119.394364 -388.849053) (xy 119.389652 -388.8232) (xy 119.386123 -388.7994) (xy 119.385912 -388.751286)
			(xy 118.830233 -388.751286) (xy 119.155972 -389.314944) (xy 119.156226 -389.315452) (xy 119.15648 -389.315452)
			(xy 119.15775 -389.317992) (xy 119.169986 -389.340915) (xy 119.187304 -389.389901) (xy 119.196091 -389.441111)
			(xy 119.196612 -389.46709) (xy 119.196612 -389.467344) (xy 119.196178 -389.491336) (xy 119.188665 -389.538729)
			(xy 119.173832 -389.584363) (xy 119.152044 -389.627116) (xy 119.123836 -389.665934) (xy 119.089903 -389.699862)
			(xy 119.051082 -389.728065) (xy 119.008326 -389.749848) (xy 118.96269 -389.764675) (xy 118.915296 -389.772181)
			(xy 118.891304 -389.772652) (xy 118.86764 -389.772209) (xy 118.820879 -389.764899) (xy 118.775803 -389.750469)
			(xy 118.733491 -389.729263) (xy 118.694953 -389.701789) (xy 118.66111 -389.668703) (xy 118.632772 -389.630796)
			(xy 118.621302 -389.610092) (xy 118.621048 -389.60933) (xy 118.223792 -388.922006) (xy 118.211583 -388.898735)
			(xy 118.194468 -388.849053) (xy 118.189756 -388.8232) (xy 118.18622 -388.799401) (xy 118.186008 -388.751286)
			(xy 117.630083 -388.751286) (xy 117.955822 -389.314944) (xy 117.956076 -389.315452) (xy 117.95633 -389.315452)
			(xy 117.9576 -389.317992) (xy 117.969871 -389.340908) (xy 117.987278 -389.389886) (xy 117.996152 -389.441101)
			(xy 117.996716 -389.46709) (xy 117.996716 -389.467344) (xy 117.996279 -389.491323) (xy 117.988775 -389.538691)
			(xy 117.973957 -389.584304) (xy 117.952191 -389.627039) (xy 117.924011 -389.665846) (xy 117.890112 -389.69977)
			(xy 117.851325 -389.727977) (xy 117.808605 -389.749773) (xy 117.763004 -389.764624) (xy 117.715641 -389.772162)
			(xy 117.691662 -389.772652) (xy 117.691154 -389.772652) (xy 117.667491 -389.772169) (xy 117.620732 -389.764867)
			(xy 117.575658 -389.750444) (xy 117.533345 -389.729245) (xy 117.494807 -389.701776) (xy 117.460963 -389.668696)
			(xy 117.432623 -389.630793) (xy 117.421152 -389.610092) (xy 117.420898 -389.60933) (xy 117.023642 -388.922006)
			(xy 117.011429 -388.898737) (xy 116.994318 -388.849054) (xy 116.989606 -388.8232) (xy 116.986164 -388.79939)
			(xy 116.985953 -388.751284) (xy 116.430185 -388.751284) (xy 116.755926 -389.314944) (xy 116.75618 -389.315452)
			(xy 116.756434 -389.315452) (xy 116.757704 -389.317992) (xy 116.769975 -389.340908) (xy 116.787382 -389.389886)
			(xy 116.796256 -389.441101) (xy 116.79682 -389.46709) (xy 116.79682 -389.467344) (xy 116.796379 -389.491323)
			(xy 116.788875 -389.538691) (xy 116.774057 -389.584303) (xy 116.752292 -389.627038) (xy 116.724113 -389.665844)
			(xy 116.690213 -389.699768) (xy 116.651427 -389.727975) (xy 116.608708 -389.749772) (xy 116.563107 -389.764623)
			(xy 116.515745 -389.772162) (xy 116.491766 -389.772652) (xy 116.491258 -389.772652) (xy 116.467595 -389.772166)
			(xy 116.420836 -389.764864) (xy 116.375762 -389.750442) (xy 116.33345 -389.729243) (xy 116.294911 -389.701775)
			(xy 116.261067 -389.668695) (xy 116.232727 -389.630793) (xy 116.221256 -389.610092) (xy 116.221002 -389.60933)
			(xy 115.823746 -388.922006) (xy 115.811534 -388.898737) (xy 115.794422 -388.849054) (xy 115.78971 -388.8232)
			(xy 115.78626 -388.799391) (xy 115.786049 -388.751284) (xy 115.230289 -388.751284) (xy 115.55603 -389.314944)
			(xy 115.556284 -389.315452) (xy 115.556538 -389.315452) (xy 115.557808 -389.317992) (xy 115.57008 -389.340908)
			(xy 115.587486 -389.389886) (xy 115.59636 -389.441101) (xy 115.596924 -389.46709) (xy 115.596924 -389.467344)
			(xy 115.596479 -389.491323) (xy 115.588975 -389.53869) (xy 115.574158 -389.584302) (xy 115.552392 -389.627036)
			(xy 115.524214 -389.665843) (xy 115.490315 -389.699767) (xy 115.451529 -389.727974) (xy 115.408811 -389.749771)
			(xy 115.36321 -389.764622) (xy 115.315849 -389.772161) (xy 115.29187 -389.772652) (xy 115.291362 -389.772652)
			(xy 115.267699 -389.772163) (xy 115.220941 -389.764861) (xy 115.175866 -389.750439) (xy 115.133554 -389.729241)
			(xy 115.095015 -389.701774) (xy 115.061171 -389.668695) (xy 115.032831 -389.630793) (xy 115.02136 -389.610092)
			(xy 115.021106 -389.60933) (xy 114.62385 -388.922006) (xy 114.611638 -388.898736) (xy 114.594526 -388.849054)
			(xy 114.589814 -388.8232) (xy 114.586357 -388.799392) (xy 114.586146 -388.751285) (xy 98.65806 -388.751285)
			(xy 98.9838 -389.314944) (xy 98.984054 -389.315452) (xy 98.984308 -389.315452) (xy 98.985578 -389.317992)
			(xy 98.997808 -389.340918) (xy 99.01513 -389.389903) (xy 99.023918 -389.441111) (xy 99.02444 -389.46709)
			(xy 99.02444 -389.467344) (xy 99.023978 -389.491335) (xy 99.016466 -389.538725) (xy 99.001635 -389.584357)
			(xy 98.979849 -389.627107) (xy 98.951644 -389.665924) (xy 98.917715 -389.699852) (xy 98.878897 -389.728055)
			(xy 98.836146 -389.74984) (xy 98.790513 -389.764669) (xy 98.743123 -389.772179) (xy 98.719132 -389.772652)
			(xy 98.695469 -389.772187) (xy 98.648709 -389.764881) (xy 98.603634 -389.750455) (xy 98.561321 -389.729253)
			(xy 98.522783 -389.701782) (xy 98.48894 -389.668699) (xy 98.460601 -389.630794) (xy 98.44913 -389.610092)
			(xy 98.448876 -389.60933) (xy 98.05162 -388.922006) (xy 98.039413 -388.898734) (xy 98.022297 -388.849053)
			(xy 98.017584 -388.8232) (xy 98.014014 -388.797978) (xy 97.484894 -388.797978) (xy 97.78365 -389.314944)
			(xy 97.783904 -389.315452) (xy 97.784158 -389.315452) (xy 97.785428 -389.317992) (xy 97.797701 -389.340907)
			(xy 97.815106 -389.389885) (xy 97.82398 -389.441101) (xy 97.824544 -389.46709) (xy 97.824544 -389.467344)
			(xy 97.824079 -389.491322) (xy 97.816576 -389.538687) (xy 97.80176 -389.584297) (xy 97.779996 -389.62703)
			(xy 97.75182 -389.665836) (xy 97.717923 -389.69976) (xy 97.67914 -389.727967) (xy 97.636425 -389.749765)
			(xy 97.590827 -389.764618) (xy 97.543468 -389.77216) (xy 97.51949 -389.772652) (xy 97.518982 -389.772652)
			(xy 97.495317 -389.772227) (xy 97.448555 -389.764914) (xy 97.40348 -389.75048) (xy 97.361167 -389.729272)
			(xy 97.322629 -389.701795) (xy 97.288787 -389.668706) (xy 97.26045 -389.630797) (xy 97.24898 -389.610092)
			(xy 97.248726 -389.60933) (xy 96.85147 -388.922006) (xy 96.839259 -388.898736) (xy 96.822146 -388.849053)
			(xy 96.817434 -388.8232) (xy 96.813939 -388.799396) (xy 96.813728 -388.751285) (xy 96.258014 -388.751285)
			(xy 96.583754 -389.314944) (xy 96.584008 -389.315452) (xy 96.584262 -389.315452) (xy 96.585532 -389.317992)
			(xy 96.597806 -389.340907) (xy 96.615211 -389.389885) (xy 96.624084 -389.441101) (xy 96.624648 -389.46709)
			(xy 96.624648 -389.467344) (xy 96.624179 -389.491322) (xy 96.616676 -389.538687) (xy 96.60186 -389.584296)
			(xy 96.580097 -389.627029) (xy 96.551921 -389.665835) (xy 96.518025 -389.699758) (xy 96.479243 -389.727966)
			(xy 96.436528 -389.749764) (xy 96.39093 -389.764617) (xy 96.343571 -389.772159) (xy 96.319594 -389.772652)
			(xy 96.319086 -389.772652) (xy 96.295421 -389.772224) (xy 96.24866 -389.764911) (xy 96.203584 -389.750478)
			(xy 96.161272 -389.72927) (xy 96.122734 -389.701794) (xy 96.088892 -389.668705) (xy 96.060554 -389.630796)
			(xy 96.049084 -389.610092) (xy 96.04883 -389.60933) (xy 95.651574 -388.922006) (xy 95.639364 -388.898736)
			(xy 95.62225 -388.849053) (xy 95.617538 -388.8232) (xy 95.614036 -388.799397) (xy 95.613824 -388.751286)
			(xy 95.057865 -388.751286) (xy 95.383604 -389.314944) (xy 95.383858 -389.315452) (xy 95.384112 -389.315452)
			(xy 95.385382 -389.317992) (xy 95.397612 -389.340918) (xy 95.414934 -389.389903) (xy 95.423722 -389.441111)
			(xy 95.424244 -389.46709) (xy 95.424244 -389.467344) (xy 95.423778 -389.491335) (xy 95.416267 -389.538724)
			(xy 95.401435 -389.584356) (xy 95.379649 -389.627106) (xy 95.351445 -389.665923) (xy 95.317517 -389.69985)
			(xy 95.278699 -389.728054) (xy 95.235949 -389.749838) (xy 95.190317 -389.764668) (xy 95.142927 -389.772179)
			(xy 95.118936 -389.772652) (xy 95.095273 -389.772184) (xy 95.048513 -389.764878) (xy 95.003438 -389.750453)
			(xy 94.961126 -389.729251) (xy 94.922587 -389.701781) (xy 94.888744 -389.668698) (xy 94.860405 -389.630794)
			(xy 94.848934 -389.610092) (xy 94.84868 -389.60933) (xy 94.451424 -388.922006) (xy 94.439217 -388.898734)
			(xy 94.422101 -388.849053) (xy 94.417388 -388.8232) (xy 94.413811 -388.797979) (xy 93.884953 -388.797979)
			(xy 94.183708 -389.314944) (xy 94.183962 -389.315452) (xy 94.184216 -389.315452) (xy 94.185486 -389.317992)
			(xy 94.197717 -389.340917) (xy 94.215038 -389.389902) (xy 94.223826 -389.441111) (xy 94.224348 -389.46709)
			(xy 94.224348 -389.467344) (xy 94.223878 -389.491334) (xy 94.216367 -389.538724) (xy 94.201536 -389.584355)
			(xy 94.17975 -389.627105) (xy 94.151546 -389.665922) (xy 94.117618 -389.699849) (xy 94.078802 -389.728052)
			(xy 94.036051 -389.749837) (xy 93.99042 -389.764668) (xy 93.94303 -389.772178) (xy 93.91904 -389.772652)
			(xy 93.895377 -389.77218) (xy 93.848617 -389.764876) (xy 93.803542 -389.750451) (xy 93.76123 -389.72925)
			(xy 93.722692 -389.70178) (xy 93.688848 -389.668698) (xy 93.660509 -389.630794) (xy 93.649038 -389.610092)
			(xy 93.648784 -389.60933) (xy 93.251528 -388.922006) (xy 93.239321 -388.898734) (xy 93.222205 -388.849053)
			(xy 93.217492 -388.8232) (xy 93.214076 -388.799387) (xy 93.213865 -388.751284) (xy 92.658071 -388.751284)
			(xy 92.983812 -389.314944) (xy 92.984066 -389.315452) (xy 92.98432 -389.315452) (xy 92.98559 -389.317992)
			(xy 92.997821 -389.340917) (xy 93.015142 -389.389902) (xy 93.02393 -389.441111) (xy 93.024452 -389.46709)
			(xy 93.024452 -389.467344) (xy 93.023978 -389.491334) (xy 93.016467 -389.538723) (xy 93.001636 -389.584354)
			(xy 92.979851 -389.627104) (xy 92.951648 -389.66592) (xy 92.91772 -389.699848) (xy 92.878904 -389.728051)
			(xy 92.836154 -389.749836) (xy 92.790523 -389.764667) (xy 92.743134 -389.772178) (xy 92.719144 -389.772652)
			(xy 92.695481 -389.772177) (xy 92.648721 -389.764873) (xy 92.603647 -389.750449) (xy 92.561334 -389.729248)
			(xy 92.522796 -389.701779) (xy 92.488952 -389.668697) (xy 92.460613 -389.630794) (xy 92.449142 -389.610092)
			(xy 92.448888 -389.60933) (xy 92.051632 -388.922006) (xy 92.039425 -388.898734) (xy 92.022309 -388.849053)
			(xy 92.017596 -388.8232) (xy 92.014173 -388.799388) (xy 92.013962 -388.751284) (xy 91.457921 -388.751284)
			(xy 91.783662 -389.314944) (xy 91.783916 -389.315452) (xy 91.78417 -389.315452) (xy 91.78544 -389.317992)
			(xy 91.797714 -389.340906) (xy 91.815119 -389.389885) (xy 91.823992 -389.441101) (xy 91.824556 -389.46709)
			(xy 91.824556 -389.467344) (xy 91.824079 -389.491321) (xy 91.816576 -389.538686) (xy 91.801761 -389.584295)
			(xy 91.779998 -389.627027) (xy 91.751823 -389.665832) (xy 91.717928 -389.699755) (xy 91.679147 -389.727963)
			(xy 91.636433 -389.749762) (xy 91.590837 -389.764616) (xy 91.543479 -389.772159) (xy 91.519502 -389.772652)
			(xy 91.518994 -389.772652) (xy 91.495329 -389.772217) (xy 91.448568 -389.764906) (xy 91.403493 -389.750474)
			(xy 91.36118 -389.729267) (xy 91.322642 -389.701792) (xy 91.2888 -389.668704) (xy 91.260462 -389.630796)
			(xy 91.248992 -389.610092) (xy 91.248738 -389.60933) (xy 90.851482 -388.922006) (xy 90.839272 -388.898735)
			(xy 90.822158 -388.849053) (xy 90.817446 -388.8232) (xy 90.813929 -388.799399) (xy 90.813717 -388.751286)
			(xy 90.258027 -388.751286) (xy 90.583766 -389.314944) (xy 90.58402 -389.315452) (xy 90.584274 -389.315452)
			(xy 90.585544 -389.317992) (xy 90.597813 -389.340909) (xy 90.615224 -389.389885) (xy 90.624092 -389.441101)
			(xy 90.62466 -389.46709) (xy 90.62466 -389.467344) (xy 90.624187 -389.491319) (xy 90.616683 -389.538678)
			(xy 90.601867 -389.584281) (xy 90.580102 -389.627007) (xy 90.551925 -389.665805) (xy 90.518028 -389.69972)
			(xy 90.479246 -389.727917) (xy 90.436531 -389.749705) (xy 90.390936 -389.764545) (xy 90.343581 -389.772074)
			(xy 90.319606 -389.772652) (xy 90.319098 -389.772652) (xy 90.295434 -389.772208) (xy 90.248671 -389.764907)
			(xy 90.203594 -389.750481) (xy 90.161282 -389.729275) (xy 90.122747 -389.701796) (xy 90.088912 -389.668702)
			(xy 90.060586 -389.630785) (xy 90.049096 -389.610092) (xy 90.048842 -389.60933) (xy 89.651586 -388.922006)
			(xy 89.639387 -388.89873) (xy 89.622266 -388.849052) (xy 89.61755 -388.8232) (xy 89.614157 -388.799838)
			(xy 89.613779 -388.752634) (xy 89.616788 -388.72922) (xy 89.618058 -388.72033) (xy 89.614756 -388.702804)
			(xy 89.571068 -388.631938) (xy 89.557352 -388.620762) (xy 89.548716 -388.617968) (xy 89.526685 -388.610094)
			(xy 89.485155 -388.588558) (xy 89.4474 -388.560932) (xy 89.414308 -388.527863) (xy 89.400126 -388.509256)
			(xy 89.392523 -388.499991) (xy 89.371196 -388.489121) (xy 89.359232 -388.488428) (xy 89.01938 -388.488428)
			(xy 89.009634 -388.488858) (xy 88.991558 -388.496146) (xy 88.977538 -388.509685) (xy 88.973152 -388.5184)
			(xy 88.961214 -388.544562) (xy 88.957972 -388.55285) (xy 88.956752 -388.57059) (xy 88.961636 -388.587688)
			(xy 88.966548 -388.595108) (xy 88.97339 -388.604772) (xy 88.985725 -388.624987) (xy 88.991186 -388.635494)
			(xy 88.991694 -388.636764) (xy 89.383616 -389.314944) (xy 89.38387 -389.315452) (xy 89.384124 -389.315452)
			(xy 89.385394 -389.317992) (xy 89.397627 -389.340917) (xy 89.41496 -389.3899) (xy 89.423746 -389.44111)
			(xy 89.424256 -389.46709) (xy 89.424256 -389.467344) (xy 89.423782 -389.491334) (xy 89.416271 -389.538724)
			(xy 89.40144 -389.584355) (xy 89.379655 -389.627105) (xy 89.351452 -389.665921) (xy 89.317524 -389.699849)
			(xy 89.278708 -389.728053) (xy 89.235958 -389.749839) (xy 89.190327 -389.76467) (xy 89.142938 -389.772182)
			(xy 89.118948 -389.772652) (xy 89.095282 -389.772211) (xy 89.048514 -389.764917) (xy 89.003432 -389.750496)
			(xy 88.961113 -389.729294) (xy 88.922572 -389.701817) (xy 88.888731 -389.668724) (xy 88.860399 -389.630807)
			(xy 88.848946 -389.610092) (xy 88.848692 -389.60933) (xy 88.451436 -388.922006) (xy 88.439239 -388.89873)
			(xy 88.42212 -388.849051) (xy 88.4174 -388.8232) (xy 88.414008 -388.799838) (xy 88.413629 -388.752634)
			(xy 88.416638 -388.72922) (xy 88.417908 -388.72033) (xy 88.414606 -388.702804) (xy 88.370918 -388.631938)
			(xy 88.357202 -388.620762) (xy 88.34882 -388.617968) (xy 88.326789 -388.610095) (xy 88.285258 -388.588559)
			(xy 88.247503 -388.560933) (xy 88.214411 -388.527864) (xy 88.20023 -388.509256) (xy 88.192627 -388.499991)
			(xy 88.171301 -388.489119) (xy 88.159336 -388.488428) (xy 87.819484 -388.488428) (xy 87.809738 -388.488858)
			(xy 87.79166 -388.496144) (xy 87.777639 -388.509683) (xy 87.773256 -388.5184) (xy 87.761318 -388.544562)
			(xy 87.758076 -388.552849) (xy 87.756856 -388.57059) (xy 87.76174 -388.587688) (xy 87.766652 -388.595108)
			(xy 87.773494 -388.604772) (xy 87.785829 -388.624987) (xy 87.79129 -388.635494) (xy 87.791798 -388.636764)
			(xy 88.18372 -389.314944) (xy 88.183974 -389.315452) (xy 88.184228 -389.315452) (xy 88.185498 -389.317992)
			(xy 88.197731 -389.340917) (xy 88.215064 -389.3899) (xy 88.223849 -389.44111) (xy 88.22436 -389.46709)
			(xy 88.22436 -389.467344) (xy 88.22391 -389.491334) (xy 88.216398 -389.538721) (xy 88.201565 -389.58435)
			(xy 88.179777 -389.627096) (xy 88.151569 -389.665908) (xy 88.117638 -389.699829) (xy 88.078818 -389.728025)
			(xy 88.036064 -389.7498) (xy 87.990431 -389.76462) (xy 87.943042 -389.772118) (xy 87.919052 -389.772652)
			(xy 87.895385 -389.772212) (xy 87.848618 -389.764918) (xy 87.803535 -389.750498) (xy 87.761216 -389.729295)
			(xy 87.722674 -389.701819) (xy 87.688832 -389.668726) (xy 87.6605 -389.630809) (xy 87.64905 -389.610092)
			(xy 87.648796 -389.60933) (xy 87.25154 -388.922006) (xy 87.239343 -388.89873) (xy 87.222224 -388.849051)
			(xy 87.217504 -388.8232) (xy 87.214112 -388.799838) (xy 87.213733 -388.752634) (xy 87.216742 -388.72922)
			(xy 87.218012 -388.72033) (xy 87.21471 -388.702804) (xy 87.171022 -388.631938) (xy 87.157306 -388.620762)
			(xy 87.14867 -388.617968) (xy 87.124787 -388.60942) (xy 87.080029 -388.585553) (xy 87.039828 -388.554619)
			(xy 87.00529 -388.51747) (xy 86.990936 -388.496556) (xy 86.98595 -388.489578) (xy 86.972319 -388.479186)
			(xy 86.964266 -388.476236) (xy 86.945401 -388.469644) (xy 86.909836 -388.451428) (xy 86.877548 -388.427888)
			(xy 86.863174 -388.414006) (xy 86.426548 -387.97738) (xy 86.409287 -387.959339) (xy 86.381527 -387.917846)
			(xy 86.36241 -387.871728) (xy 86.352673 -387.822764) (xy 86.352126 -387.797802) (xy 86.352126 -385.991608)
			(xy 86.351933 -385.98494) (xy 86.34846 -385.972065) (xy 86.345268 -385.966208) (xy 86.051644 -385.457954)
			(xy 86.039708 -385.435294) (xy 86.022753 -385.38697) (xy 86.014104 -385.336493) (xy 86.013544 -385.310888)
			(xy 86.013544 -385.31038) (xy 86.014031 -385.285559) (xy 86.022064 -385.236572) (xy 86.037915 -385.18953)
			(xy 86.061167 -385.145671) (xy 86.091206 -385.10615) (xy 86.127243 -385.072009) (xy 86.168328 -385.044147)
			(xy 86.213379 -385.023298) (xy 86.261209 -385.01001) (xy 86.285832 -385.00685) (xy 86.294737 -385.005559)
			(xy 86.310876 -384.997628) (xy 86.317328 -384.991356) (xy 86.338156 -384.969258) (xy 86.344535 -384.961936)
			(xy 86.351712 -384.943909) (xy 86.352126 -384.934206) (xy 86.352126 -384.21564) (xy 86.351693 -384.205574)
			(xy 86.343966 -384.186983) (xy 86.33714 -384.179572) (xy 86.138512 -383.980944) (xy 86.131116 -383.974091)
			(xy 86.112518 -383.966345) (xy 86.102444 -383.965958) (xy 76.928472 -383.965958) (xy 76.917185 -383.966566)
			(xy 76.896759 -383.976185) (xy 76.889102 -383.9845) (xy 76.870896 -384.00601) (xy 76.82923 -384.043952)
			(xy 76.782433 -384.075347) (xy 76.731525 -384.099512) (xy 76.677615 -384.115921) (xy 76.621876 -384.124215)
			(xy 76.565524 -384.124215) (xy 76.509785 -384.115921) (xy 76.455875 -384.099512) (xy 76.404967 -384.075347)
			(xy 76.35817 -384.043952) (xy 76.316504 -384.00601) (xy 76.298298 -383.9845) (xy 76.290676 -383.976133)
			(xy 76.270232 -383.966495) (xy 76.258928 -383.965958) (xy 74.105516 -383.965958) (xy 74.095454 -383.966398)
			(xy 74.076877 -383.97414) (xy 74.069448 -383.980944) (xy 73.547732 -384.50266) (xy 73.540892 -384.51006)
			(xy 73.533174 -384.528659) (xy 73.532746 -384.538728) (xy 73.532746 -385.310888) (xy 80.013556 -385.310888)
			(xy 80.013556 -385.31038) (xy 80.014043 -385.286403) (xy 80.021543 -385.239038) (xy 80.036355 -385.193429)
			(xy 80.058116 -385.150695) (xy 80.08629 -385.11189) (xy 80.120184 -385.077966) (xy 80.158965 -385.049758)
			(xy 80.201679 -385.027959) (xy 80.247275 -385.013106) (xy 80.294633 -385.005564) (xy 80.31861 -385.005072)
			(xy 80.319118 -385.005072) (xy 80.343052 -385.005565) (xy 80.390335 -385.013018) (xy 80.435877 -385.027754)
			(xy 80.478564 -385.049413) (xy 80.51735 -385.077465) (xy 80.551287 -385.111223) (xy 80.579542 -385.149861)
			(xy 80.590898 -385.170934) (xy 80.591406 -385.17195) (xy 80.671712 -385.310888) (xy 81.213452 -385.310888)
			(xy 81.213452 -385.31038) (xy 81.213943 -385.286403) (xy 81.221443 -385.239039) (xy 81.236255 -385.193429)
			(xy 81.258015 -385.150697) (xy 81.286189 -385.111891) (xy 81.320082 -385.077967) (xy 81.358863 -385.049759)
			(xy 81.401576 -385.02796) (xy 81.447172 -385.013107) (xy 81.494529 -385.005565) (xy 81.518506 -385.005072)
			(xy 81.519014 -385.005072) (xy 81.542948 -385.005568) (xy 81.590231 -385.013021) (xy 81.635773 -385.027756)
			(xy 81.67846 -385.049415) (xy 81.717246 -385.077466) (xy 81.751182 -385.111224) (xy 81.779438 -385.149861)
			(xy 81.790794 -385.170934) (xy 81.791302 -385.17195) (xy 81.871608 -385.310888) (xy 82.413348 -385.310888)
			(xy 82.413348 -385.31038) (xy 82.413843 -385.286403) (xy 82.421343 -385.239039) (xy 82.436155 -385.19343)
			(xy 82.457915 -385.150698) (xy 82.486088 -385.111892) (xy 82.519981 -385.077969) (xy 82.55876 -385.04976)
			(xy 82.601473 -385.027961) (xy 82.647069 -385.013108) (xy 82.694426 -385.005565) (xy 82.718402 -385.005072)
			(xy 82.71891 -385.005072) (xy 82.742843 -385.005571) (xy 82.790127 -385.013023) (xy 82.835669 -385.027758)
			(xy 82.878355 -385.049416) (xy 82.917142 -385.077467) (xy 82.951078 -385.111224) (xy 82.979334 -385.149861)
			(xy 82.99069 -385.170934) (xy 82.991198 -385.17195) (xy 83.071504 -385.310888) (xy 83.613752 -385.310888)
			(xy 83.613752 -385.31038) (xy 83.614244 -385.28639) (xy 83.621752 -385.239002) (xy 83.63658 -385.193371)
			(xy 83.658362 -385.150621) (xy 83.686563 -385.111804) (xy 83.720489 -385.077876) (xy 83.759304 -385.049673)
			(xy 83.802052 -385.027887) (xy 83.847682 -385.013057) (xy 83.89507 -385.005546) (xy 83.91906 -385.005072)
			(xy 83.942995 -385.005531) (xy 83.99028 -385.01299) (xy 84.035823 -385.027733) (xy 84.07851 -385.049398)
			(xy 84.117295 -385.077455) (xy 84.151231 -385.111217) (xy 84.179485 -385.149859) (xy 84.19084 -385.170934)
			(xy 84.191348 -385.17195) (xy 84.271654 -385.310888) (xy 84.813648 -385.310888) (xy 84.813648 -385.31038)
			(xy 84.814144 -385.28639) (xy 84.821652 -385.239002) (xy 84.836479 -385.193372) (xy 84.858261 -385.150622)
			(xy 84.886462 -385.111805) (xy 84.920387 -385.077878) (xy 84.959201 -385.049674) (xy 85.001949 -385.027888)
			(xy 85.047579 -385.013057) (xy 85.094966 -385.005546) (xy 85.118956 -385.005072) (xy 85.142891 -385.005534)
			(xy 85.190176 -385.012993) (xy 85.235719 -385.027735) (xy 85.278405 -385.049399) (xy 85.317191 -385.077456)
			(xy 85.351126 -385.111218) (xy 85.379381 -385.149859) (xy 85.390736 -385.170934) (xy 85.391244 -385.17195)
			(xy 85.783674 -385.850892) (xy 85.796501 -385.874223) (xy 85.81472 -385.924247) (xy 85.823979 -385.976673)
			(xy 85.824568 -386.003292) (xy 85.824131 -386.027272) (xy 85.816633 -386.074643) (xy 85.801819 -386.120259)
			(xy 85.780055 -386.162997) (xy 85.751876 -386.201806) (xy 85.717975 -386.235732) (xy 85.679187 -386.263939)
			(xy 85.636464 -386.285734) (xy 85.590859 -386.300581) (xy 85.543494 -386.308113) (xy 85.519514 -386.3086)
			(xy 85.519006 -386.3086) (xy 85.495432 -386.308201) (xy 85.448844 -386.300961) (xy 85.403926 -386.286636)
			(xy 85.361747 -386.265568) (xy 85.323314 -386.238259) (xy 85.289542 -386.20536) (xy 85.261237 -386.167655)
			(xy 85.249766 -386.147056) (xy 85.249258 -386.146294) (xy 84.851494 -385.457954) (xy 84.839638 -385.435267)
			(xy 84.822779 -385.386939) (xy 84.814198 -385.336479) (xy 84.813648 -385.310888) (xy 84.271654 -385.310888)
			(xy 84.583778 -385.850892) (xy 84.596606 -385.874223) (xy 84.614824 -385.924247) (xy 84.624083 -385.976673)
			(xy 84.624672 -386.003292) (xy 84.624231 -386.027272) (xy 84.616733 -386.074643) (xy 84.60192 -386.120258)
			(xy 84.580156 -386.162996) (xy 84.551978 -386.201805) (xy 84.518077 -386.235731) (xy 84.479289 -386.263938)
			(xy 84.436567 -386.285733) (xy 84.390963 -386.30058) (xy 84.343598 -386.308113) (xy 84.319618 -386.3086)
			(xy 84.31911 -386.3086) (xy 84.295536 -386.308198) (xy 84.248948 -386.300958) (xy 84.20403 -386.286634)
			(xy 84.161852 -386.265566) (xy 84.123418 -386.238258) (xy 84.089647 -386.20536) (xy 84.061341 -386.167655)
			(xy 84.04987 -386.147056) (xy 84.049362 -386.146294) (xy 83.651598 -385.457954) (xy 83.639742 -385.435267)
			(xy 83.622883 -385.386939) (xy 83.614302 -385.336479) (xy 83.613752 -385.310888) (xy 83.071504 -385.310888)
			(xy 83.383628 -385.850892) (xy 83.396363 -385.874209) (xy 83.414456 -385.924157) (xy 83.423671 -385.976476)
			(xy 83.424268 -386.003038) (xy 83.424268 -386.003292) (xy 83.423854 -386.027287) (xy 83.416348 -386.074686)
			(xy 83.401518 -386.120327) (xy 83.37973 -386.163086) (xy 83.351521 -386.201909) (xy 83.317585 -386.235841)
			(xy 83.278758 -386.264047) (xy 83.235997 -386.28583) (xy 83.190355 -386.300655) (xy 83.142955 -386.308157)
			(xy 83.11896 -386.3086) (xy 83.095388 -386.308158) (xy 83.048802 -386.300925) (xy 83.003884 -386.286608)
			(xy 82.961706 -386.265548) (xy 82.923272 -386.238245) (xy 82.889499 -386.205353) (xy 82.861192 -386.167653)
			(xy 82.84972 -386.147056) (xy 82.849212 -386.146294) (xy 82.451448 -385.457954) (xy 82.439517 -385.435293)
			(xy 82.422585 -385.386964) (xy 82.413931 -385.336491) (xy 82.413348 -385.310888) (xy 81.871608 -385.310888)
			(xy 82.183732 -385.850892) (xy 82.196467 -385.874209) (xy 82.21456 -385.924157) (xy 82.223775 -385.976476)
			(xy 82.224372 -386.003038) (xy 82.224372 -386.003292) (xy 82.223954 -386.027287) (xy 82.216448 -386.074685)
			(xy 82.201618 -386.120326) (xy 82.179831 -386.163085) (xy 82.151622 -386.201908) (xy 82.117687 -386.23584)
			(xy 82.078861 -386.264045) (xy 82.0361 -386.285829) (xy 81.990458 -386.300654) (xy 81.943059 -386.308156)
			(xy 81.919064 -386.3086) (xy 81.895492 -386.308155) (xy 81.848906 -386.300923) (xy 81.803989 -386.286606)
			(xy 81.76181 -386.265546) (xy 81.723376 -386.238244) (xy 81.689603 -386.205352) (xy 81.661296 -386.167653)
			(xy 81.649824 -386.147056) (xy 81.649316 -386.146294) (xy 81.251552 -385.457954) (xy 81.239622 -385.435293)
			(xy 81.222689 -385.386964) (xy 81.214035 -385.336491) (xy 81.213452 -385.310888) (xy 80.671712 -385.310888)
			(xy 80.983836 -385.850892) (xy 80.996572 -385.874209) (xy 81.014664 -385.924157) (xy 81.023879 -385.976476)
			(xy 81.024476 -386.003038) (xy 81.024476 -386.003292) (xy 81.024054 -386.027287) (xy 81.016548 -386.074685)
			(xy 81.001718 -386.120325) (xy 80.979931 -386.163083) (xy 80.951723 -386.201907) (xy 80.917788 -386.235839)
			(xy 80.878963 -386.264044) (xy 80.836203 -386.285828) (xy 80.790561 -386.300653) (xy 80.743163 -386.308156)
			(xy 80.719168 -386.3086) (xy 80.695596 -386.308151) (xy 80.64901 -386.30092) (xy 80.604093 -386.286604)
			(xy 80.561915 -386.265545) (xy 80.523481 -386.238243) (xy 80.489707 -386.205351) (xy 80.4614 -386.167653)
			(xy 80.449928 -386.147056) (xy 80.44942 -386.146294) (xy 80.051656 -385.457954) (xy 80.039726 -385.435293)
			(xy 80.022793 -385.386964) (xy 80.014139 -385.336491) (xy 80.013556 -385.310888) (xy 73.532746 -385.310888)
			(xy 73.532746 -385.705096) (xy 73.532165 -385.730052) (xy 73.522409 -385.779002) (xy 73.50329 -385.825109)
			(xy 73.475543 -385.866598) (xy 73.458324 -385.884674) (xy 71.882508 -387.46049) (xy 71.864467 -387.477749)
			(xy 71.822973 -387.505504) (xy 71.776855 -387.524613) (xy 71.727891 -387.534338) (xy 71.70293 -387.534912)
			(xy 69.882258 -387.534912) (xy 69.872191 -387.535343) (xy 69.853599 -387.54307) (xy 69.84619 -387.549898)
			(xy 69.606414 -387.789674) (xy 73.42886 -387.789674) (xy 73.42886 -386.926074) (xy 73.429346 -386.898805)
			(xy 73.437108 -386.844821) (xy 73.452473 -386.792491) (xy 73.47513 -386.742881) (xy 73.504616 -386.697)
			(xy 73.540331 -386.655783) (xy 73.581548 -386.620068) (xy 73.627429 -386.590582) (xy 73.677039 -386.567925)
			(xy 73.729369 -386.55256) (xy 73.783353 -386.544798) (xy 73.837891 -386.544798) (xy 73.891875 -386.55256)
			(xy 73.944205 -386.567925) (xy 73.993815 -386.590582) (xy 74.039696 -386.620068) (xy 74.080913 -386.655783)
			(xy 74.116628 -386.697) (xy 74.146114 -386.742881) (xy 74.168771 -386.792491) (xy 74.184136 -386.844821)
			(xy 74.191898 -386.898805) (xy 74.192384 -386.926074) (xy 74.192384 -387.789674) (xy 74.191898 -387.816943)
			(xy 74.184136 -387.870927) (xy 74.168771 -387.923257) (xy 74.146114 -387.972867) (xy 74.116628 -388.018748)
			(xy 74.080913 -388.059965) (xy 74.039696 -388.09568) (xy 73.993815 -388.125166) (xy 73.944205 -388.147823)
			(xy 73.891875 -388.163188) (xy 73.837891 -388.17095) (xy 73.783353 -388.17095) (xy 73.729369 -388.163188)
			(xy 73.677039 -388.147823) (xy 73.627429 -388.125166) (xy 73.581548 -388.09568) (xy 73.540331 -388.059965)
			(xy 73.504616 -388.018748) (xy 73.47513 -387.972867) (xy 73.452473 -387.923257) (xy 73.437108 -387.870927)
			(xy 73.429346 -387.816943) (xy 73.42886 -387.789674) (xy 69.606414 -387.789674) (xy 69.337936 -388.058152)
			(xy 69.319894 -388.07541) (xy 69.2784 -388.103163) (xy 69.232282 -388.122272) (xy 69.183318 -388.132)
			(xy 69.158358 -388.132574) (xy 61.12129 -388.132574) (xy 61.09633 -388.132002) (xy 61.04737 -388.12226)
			(xy 61.001251 -388.103153) (xy 60.959747 -388.075416) (xy 60.941712 -388.058152) (xy 60.865512 -387.981952)
			(xy 60.836556 -387.975602) (xy 60.82284 -387.980682) (xy 60.797715 -387.989192) (xy 60.745475 -387.998384)
			(xy 60.718954 -387.99897) (xy 60.718446 -387.99897) (xy 60.694452 -387.998527) (xy 60.647053 -387.991026)
			(xy 60.601411 -387.976201) (xy 60.558652 -387.954417) (xy 60.519827 -387.926212) (xy 60.485893 -387.892279)
			(xy 60.457687 -387.853455) (xy 60.435902 -387.810696) (xy 60.421076 -387.765055) (xy 60.413573 -387.717656)
			(xy 60.413138 -387.693662) (xy 60.413138 -387.693154) (xy 60.413732 -387.666634) (xy 60.422932 -387.614398)
			(xy 60.431426 -387.589268) (xy 60.436506 -387.575552) (xy 60.430156 -387.546596) (xy 59.67476 -386.7912)
			(xy 59.667359 -386.78436) (xy 59.648761 -386.77664) (xy 59.638692 -386.776214) (xy 59.42711 -386.776214)
			(xy 59.423554 -386.776722) (xy 59.412369 -386.778149) (xy 59.389871 -386.779672) (xy 59.378596 -386.77977)
			(xy 59.36732 -386.779688) (xy 59.344821 -386.778166) (xy 59.333638 -386.776722) (xy 59.330082 -386.776214)
			(xy 59.190382 -386.776214) (xy 59.180314 -386.776641) (xy 59.161715 -386.784361) (xy 59.154314 -386.7912)
			(xy 57.56656 -388.378954) (xy 57.559252 -388.387039) (xy 57.55161 -388.407429) (xy 57.551828 -388.418324)
			(xy 57.55767 -388.505446) (xy 57.56783 -388.52475) (xy 57.57672 -388.531354) (xy 57.594583 -388.545532)
			(xy 57.626315 -388.578285) (xy 57.652843 -388.615378) (xy 57.663588 -388.635494) (xy 57.664096 -388.636764)
			(xy 57.730277 -388.751284) (xy 58.28606 -388.751284) (xy 58.293391 -388.703741) (xy 58.308083 -388.657934)
			(xy 58.329773 -388.614996) (xy 58.357924 -388.575988) (xy 58.391841 -388.541874) (xy 58.430685 -388.513498)
			(xy 58.473497 -388.49156) (xy 58.519217 -388.476603) (xy 58.566717 -388.468997) (xy 58.614822 -388.468929)
			(xy 58.662344 -388.476401) (xy 58.708107 -388.491229) (xy 58.75098 -388.513046) (xy 58.789904 -388.541313)
			(xy 58.823917 -388.575331) (xy 58.852178 -388.61426) (xy 58.863484 -388.635494) (xy 58.863992 -388.636764)
			(xy 58.930175 -388.751286) (xy 59.486115 -388.751286) (xy 59.493447 -388.703734) (xy 59.508141 -388.657919)
			(xy 59.529835 -388.614973) (xy 59.557991 -388.575958) (xy 59.591914 -388.541839) (xy 59.630766 -388.513457)
			(xy 59.673585 -388.491516) (xy 59.719315 -388.476558) (xy 59.766824 -388.468952) (xy 59.814937 -388.468885)
			(xy 59.862467 -388.476361) (xy 59.908237 -388.491194) (xy 59.951117 -388.513017) (xy 59.990047 -388.541291)
			(xy 60.024064 -388.575318) (xy 60.052327 -388.614255) (xy 60.063634 -388.635494) (xy 60.064142 -388.636764)
			(xy 60.130325 -388.751286) (xy 60.686019 -388.751286) (xy 60.693351 -388.703735) (xy 60.708045 -388.65792)
			(xy 60.729738 -388.614975) (xy 60.757893 -388.575961) (xy 60.791816 -388.541841) (xy 60.830667 -388.513461)
			(xy 60.873486 -388.49152) (xy 60.919215 -388.476561) (xy 60.966723 -388.468955) (xy 61.014836 -388.468889)
			(xy 61.062365 -388.476364) (xy 61.108135 -388.491197) (xy 61.151014 -388.513019) (xy 61.189943 -388.541293)
			(xy 61.22396 -388.575319) (xy 61.252223 -388.614255) (xy 61.26353 -388.635494) (xy 61.264038 -388.636764)
			(xy 61.330221 -388.751286) (xy 61.885922 -388.751286) (xy 61.893254 -388.703735) (xy 61.907948 -388.657921)
			(xy 61.929641 -388.614977) (xy 61.957796 -388.575963) (xy 61.991718 -388.541844) (xy 62.030569 -388.513464)
			(xy 62.073387 -388.491523) (xy 62.119115 -388.476565) (xy 62.166623 -388.468959) (xy 62.214735 -388.468892)
			(xy 62.262263 -388.476368) (xy 62.308032 -388.4912) (xy 62.350911 -388.513022) (xy 62.38984 -388.541295)
			(xy 62.423856 -388.57532) (xy 62.452119 -388.614256) (xy 62.463426 -388.635494) (xy 62.463934 -388.636764)
			(xy 62.530115 -388.751284) (xy 63.086167 -388.751284) (xy 63.093498 -388.703742) (xy 63.10819 -388.657936)
			(xy 63.129879 -388.615) (xy 63.158029 -388.575993) (xy 63.191945 -388.54188) (xy 63.230788 -388.513504)
			(xy 63.273598 -388.491567) (xy 63.319318 -388.47661) (xy 63.366816 -388.469004) (xy 63.41492 -388.468936)
			(xy 63.46244 -388.476408) (xy 63.508202 -388.491235) (xy 63.551074 -388.513051) (xy 63.589997 -388.541317)
			(xy 63.624009 -388.575333) (xy 63.65227 -388.61426) (xy 63.663576 -388.635494) (xy 63.664084 -388.636764)
			(xy 63.757251 -388.797979) (xy 64.286112 -388.797979) (xy 64.286361 -388.747044) (xy 64.295054 -388.696856)
			(xy 64.311952 -388.648805) (xy 64.336585 -388.604222) (xy 64.368271 -388.564342) (xy 64.406133 -388.530271)
			(xy 64.449122 -388.502951) (xy 64.496047 -388.48314) (xy 64.545608 -388.471387) (xy 64.596432 -388.468016)
			(xy 64.647111 -388.473122) (xy 64.696241 -388.486563) (xy 64.742461 -388.507967) (xy 64.784491 -388.53674)
			(xy 64.821166 -388.572086) (xy 64.851471 -388.613026) (xy 64.863472 -388.635494) (xy 64.86398 -388.636764)
			(xy 64.930163 -388.751286) (xy 65.486126 -388.751286) (xy 65.493458 -388.703736) (xy 65.508151 -388.657923)
			(xy 65.529844 -388.614979) (xy 65.557999 -388.575966) (xy 65.59192 -388.541847) (xy 65.63077 -388.513467)
			(xy 65.673588 -388.491527) (xy 65.719316 -388.476569) (xy 65.766822 -388.468962) (xy 65.814934 -388.468896)
			(xy 65.862461 -388.476371) (xy 65.90823 -388.491202) (xy 65.951108 -388.513024) (xy 65.990037 -388.541297)
			(xy 66.024053 -388.575321) (xy 66.052315 -388.614256) (xy 66.063622 -388.635494) (xy 66.06413 -388.636764)
			(xy 66.130312 -388.751285) (xy 80.01394 -388.751285) (xy 80.021272 -388.703738) (xy 80.035965 -388.657927)
			(xy 80.057656 -388.614986) (xy 80.085809 -388.575975) (xy 80.119729 -388.541859) (xy 80.158577 -388.51348)
			(xy 80.201392 -388.491541) (xy 80.247116 -388.476583) (xy 80.29462 -388.468977) (xy 80.342729 -388.46891)
			(xy 80.390254 -388.476384) (xy 80.43602 -388.491214) (xy 80.478896 -388.513033) (xy 80.517823 -388.541304)
			(xy 80.551837 -388.575325) (xy 80.5801 -388.614258) (xy 80.591406 -388.635494) (xy 80.591914 -388.636764)
			(xy 80.658096 -388.751285) (xy 81.213844 -388.751285) (xy 81.221175 -388.703738) (xy 81.235868 -388.657929)
			(xy 81.257559 -388.614988) (xy 81.285712 -388.575977) (xy 81.319631 -388.541862) (xy 81.358478 -388.513483)
			(xy 81.401293 -388.491544) (xy 81.447017 -388.476587) (xy 81.49452 -388.46898) (xy 81.542628 -388.468913)
			(xy 81.590152 -388.476387) (xy 81.635918 -388.491217) (xy 81.678793 -388.513036) (xy 81.717719 -388.541305)
			(xy 81.751734 -388.575326) (xy 81.779996 -388.614258) (xy 81.791302 -388.635494) (xy 81.79181 -388.636764)
			(xy 81.857992 -388.751285) (xy 82.413748 -388.751285) (xy 82.421079 -388.703739) (xy 82.435771 -388.65793)
			(xy 82.457462 -388.61499) (xy 82.485615 -388.57598) (xy 82.519533 -388.541864) (xy 82.55838 -388.513487)
			(xy 82.601194 -388.491548) (xy 82.646917 -388.47659) (xy 82.694419 -388.468984) (xy 82.742527 -388.468917)
			(xy 82.79005 -388.47639) (xy 82.835815 -388.491219) (xy 82.87869 -388.513038) (xy 82.917616 -388.541307)
			(xy 82.95163 -388.575327) (xy 82.979892 -388.614258) (xy 82.991198 -388.635494) (xy 82.991706 -388.636764)
			(xy 83.057889 -388.751287) (xy 83.613803 -388.751287) (xy 83.621135 -388.703732) (xy 83.635829 -388.657915)
			(xy 83.657524 -388.614967) (xy 83.685682 -388.57595) (xy 83.719607 -388.541829) (xy 83.75846 -388.513446)
			(xy 83.801282 -388.491504) (xy 83.847014 -388.476545) (xy 83.894525 -388.468939) (xy 83.942642 -388.468873)
			(xy 83.990174 -388.47635) (xy 84.035946 -388.491184) (xy 84.078828 -388.513009) (xy 84.117759 -388.541285)
			(xy 84.151777 -388.575314) (xy 84.180041 -388.614254) (xy 84.191348 -388.635494) (xy 84.191856 -388.636764)
			(xy 84.258039 -388.751287) (xy 84.813706 -388.751287) (xy 84.821038 -388.703733) (xy 84.835733 -388.657916)
			(xy 84.857427 -388.614969) (xy 84.885584 -388.575952) (xy 84.919509 -388.541831) (xy 84.958362 -388.513449)
			(xy 85.001183 -388.491508) (xy 85.046914 -388.476549) (xy 85.094425 -388.468942) (xy 85.14254 -388.468877)
			(xy 85.190072 -388.476353) (xy 85.235844 -388.491187) (xy 85.278725 -388.513011) (xy 85.317655 -388.541287)
			(xy 85.351673 -388.575315) (xy 85.379937 -388.614254) (xy 85.391244 -388.635494) (xy 85.391752 -388.636764)
			(xy 85.457933 -388.751284) (xy 86.013951 -388.751284) (xy 86.021282 -388.703739) (xy 86.035975 -388.657931)
			(xy 86.057665 -388.614992) (xy 86.085817 -388.575982) (xy 86.119735 -388.541867) (xy 86.158581 -388.51349)
			(xy 86.201394 -388.491551) (xy 86.247117 -388.476594) (xy 86.294619 -388.468988) (xy 86.342725 -388.46892)
			(xy 86.390248 -388.476393) (xy 86.436013 -388.491222) (xy 86.478887 -388.513041) (xy 86.517813 -388.541309)
			(xy 86.551826 -388.575329) (xy 86.580088 -388.614259) (xy 86.591394 -388.635494) (xy 86.591902 -388.636764)
			(xy 86.983824 -389.314944) (xy 86.984078 -389.315452) (xy 86.984332 -389.315452) (xy 86.985602 -389.317992)
			(xy 86.997834 -389.340917) (xy 87.015155 -389.389902) (xy 87.023942 -389.441111) (xy 87.024464 -389.46709)
			(xy 87.024464 -389.467344) (xy 87.024078 -389.491339) (xy 87.016564 -389.538736) (xy 87.001728 -389.584375)
			(xy 86.979935 -389.62713) (xy 86.951722 -389.66595) (xy 86.917783 -389.699879) (xy 86.878955 -389.728081)
			(xy 86.836193 -389.749861) (xy 86.79055 -389.764684) (xy 86.743151 -389.772185) (xy 86.719156 -389.772652)
			(xy 86.695493 -389.772167) (xy 86.648734 -389.764865) (xy 86.60366 -389.750443) (xy 86.561348 -389.729244)
			(xy 86.522809 -389.701776) (xy 86.488965 -389.668695) (xy 86.460625 -389.630793) (xy 86.449154 -389.610092)
			(xy 86.4489 -389.60933) (xy 86.051644 -388.922006) (xy 86.039432 -388.898737) (xy 86.02232 -388.849054)
			(xy 86.017608 -388.8232) (xy 86.014162 -388.799391) (xy 86.013951 -388.751284) (xy 85.457933 -388.751284)
			(xy 85.783674 -389.314944) (xy 85.783928 -389.315452) (xy 85.784182 -389.315452) (xy 85.785452 -389.317992)
			(xy 85.797727 -389.340906) (xy 85.815131 -389.389885) (xy 85.824004 -389.441101) (xy 85.824568 -389.46709)
			(xy 85.824568 -389.467344) (xy 85.824179 -389.491326) (xy 85.816673 -389.538698) (xy 85.801852 -389.584315)
			(xy 85.780082 -389.627053) (xy 85.751897 -389.665862) (xy 85.717991 -389.699787) (xy 85.679198 -389.727993)
			(xy 85.636472 -389.749787) (xy 85.590864 -389.764633) (xy 85.543495 -389.772165) (xy 85.519514 -389.772652)
			(xy 85.519006 -389.772652) (xy 85.495342 -389.772208) (xy 85.448581 -389.764898) (xy 85.403506 -389.750468)
			(xy 85.361193 -389.729263) (xy 85.322655 -389.701789) (xy 85.288813 -389.668703) (xy 85.260474 -389.630795)
			(xy 85.249004 -389.610092) (xy 85.24875 -389.60933) (xy 84.851494 -388.922006) (xy 84.839285 -388.898735)
			(xy 84.822171 -388.849053) (xy 84.817458 -388.8232) (xy 84.813918 -388.799402) (xy 84.813706 -388.751287)
			(xy 84.258039 -388.751287) (xy 84.583778 -389.314944) (xy 84.584032 -389.315452) (xy 84.584286 -389.315452)
			(xy 84.585556 -389.317992) (xy 84.597831 -389.340906) (xy 84.615235 -389.389885) (xy 84.624108 -389.441101)
			(xy 84.624672 -389.46709) (xy 84.624672 -389.467344) (xy 84.624279 -389.491326) (xy 84.616773 -389.538698)
			(xy 84.601953 -389.584314) (xy 84.580183 -389.627052) (xy 84.551999 -389.665861) (xy 84.518093 -389.699785)
			(xy 84.4793 -389.727992) (xy 84.436575 -389.749786) (xy 84.390967 -389.764632) (xy 84.343599 -389.772165)
			(xy 84.319618 -389.772652) (xy 84.31911 -389.772652) (xy 84.295446 -389.772205) (xy 84.248685 -389.764896)
			(xy 84.20361 -389.750466) (xy 84.161298 -389.729261) (xy 84.122759 -389.701788) (xy 84.088917 -389.668702)
			(xy 84.060578 -389.630795) (xy 84.049108 -389.610092) (xy 84.048854 -389.60933) (xy 83.651598 -388.922006)
			(xy 83.639389 -388.898735) (xy 83.622275 -388.849053) (xy 83.617562 -388.8232) (xy 83.614015 -388.799402)
			(xy 83.613803 -388.751287) (xy 83.057889 -388.751287) (xy 83.383628 -389.314944) (xy 83.383882 -389.315452)
			(xy 83.384136 -389.315452) (xy 83.385406 -389.317992) (xy 83.397638 -389.340917) (xy 83.414959 -389.389902)
			(xy 83.423746 -389.441111) (xy 83.424268 -389.46709) (xy 83.424268 -389.467344) (xy 83.423878 -389.491338)
			(xy 83.416364 -389.538735) (xy 83.401528 -389.584374) (xy 83.379736 -389.627129) (xy 83.351523 -389.665949)
			(xy 83.317585 -389.699878) (xy 83.278757 -389.728079) (xy 83.235996 -389.74986) (xy 83.190354 -389.764684)
			(xy 83.142955 -389.772184) (xy 83.11896 -389.772652) (xy 83.095297 -389.772164) (xy 83.048539 -389.764863)
			(xy 83.003464 -389.75044) (xy 82.961152 -389.729242) (xy 82.922613 -389.701775) (xy 82.888769 -389.668695)
			(xy 82.860429 -389.630793) (xy 82.848958 -389.610092) (xy 82.848704 -389.60933) (xy 82.451448 -388.922006)
			(xy 82.439236 -388.898737) (xy 82.422124 -388.849054) (xy 82.417412 -388.8232) (xy 82.413959 -388.799392)
			(xy 82.413748 -388.751285) (xy 81.857992 -388.751285) (xy 82.183732 -389.314944) (xy 82.183986 -389.315452)
			(xy 82.18424 -389.315452) (xy 82.18551 -389.317992) (xy 82.197742 -389.340916) (xy 82.215063 -389.389902)
			(xy 82.22385 -389.441111) (xy 82.224372 -389.46709) (xy 82.224372 -389.467344) (xy 82.223978 -389.491338)
			(xy 82.216464 -389.538735) (xy 82.201628 -389.584373) (xy 82.179836 -389.627128) (xy 82.151624 -389.665948)
			(xy 82.117687 -389.699876) (xy 82.078859 -389.728078) (xy 82.036099 -389.749859) (xy 81.990457 -389.764683)
			(xy 81.943058 -389.772184) (xy 81.919064 -389.772652) (xy 81.895401 -389.772161) (xy 81.848643 -389.76486)
			(xy 81.803569 -389.750438) (xy 81.761256 -389.729241) (xy 81.722717 -389.701774) (xy 81.688873 -389.668694)
			(xy 81.660533 -389.630793) (xy 81.649062 -389.610092) (xy 81.648808 -389.60933) (xy 81.251552 -388.922006)
			(xy 81.23934 -388.898736) (xy 81.222228 -388.849054) (xy 81.217516 -388.8232) (xy 81.214055 -388.799392)
			(xy 81.213844 -388.751285) (xy 80.658096 -388.751285) (xy 80.983836 -389.314944) (xy 80.98409 -389.315452)
			(xy 80.984344 -389.315452) (xy 80.985614 -389.317992) (xy 80.997847 -389.340916) (xy 81.015167 -389.389902)
			(xy 81.023954 -389.441111) (xy 81.024476 -389.46709) (xy 81.024476 -389.467344) (xy 81.024078 -389.491338)
			(xy 81.016564 -389.538734) (xy 81.001729 -389.584372) (xy 80.979937 -389.627127) (xy 80.951725 -389.665946)
			(xy 80.917788 -389.699875) (xy 80.878962 -389.728077) (xy 80.836201 -389.749858) (xy 80.79056 -389.764682)
			(xy 80.743162 -389.772184) (xy 80.719168 -389.772652) (xy 80.695506 -389.772158) (xy 80.648747 -389.764857)
			(xy 80.603673 -389.750436) (xy 80.561361 -389.729239) (xy 80.522822 -389.701773) (xy 80.488978 -389.668694)
			(xy 80.460637 -389.630793) (xy 80.449166 -389.610092) (xy 80.448912 -389.60933) (xy 80.051656 -388.922006)
			(xy 80.039444 -388.898736) (xy 80.022332 -388.849054) (xy 80.01762 -388.8232) (xy 80.014152 -388.799393)
			(xy 80.01394 -388.751285) (xy 66.130312 -388.751285) (xy 66.456052 -389.314944) (xy 66.456306 -389.315452)
			(xy 66.45656 -389.315452) (xy 66.45783 -389.317992) (xy 66.470064 -389.340916) (xy 66.487383 -389.389902)
			(xy 66.496171 -389.441111) (xy 66.496692 -389.46709) (xy 66.496692 -389.467344) (xy 66.496278 -389.491337)
			(xy 66.488765 -389.538732) (xy 66.47393 -389.584368) (xy 66.45214 -389.627122) (xy 66.42393 -389.665941)
			(xy 66.389995 -389.699869) (xy 66.351171 -389.728071) (xy 66.308412 -389.749853) (xy 66.262774 -389.764679)
			(xy 66.215377 -389.772183) (xy 66.191384 -389.772652) (xy 66.167719 -389.772226) (xy 66.120957 -389.764913)
			(xy 66.075882 -389.750479) (xy 66.033569 -389.729271) (xy 65.995032 -389.701794) (xy 65.961189 -389.668706)
			(xy 65.932852 -389.630796) (xy 65.921382 -389.610092) (xy 65.921128 -389.60933) (xy 65.523872 -388.922006)
			(xy 65.511661 -388.898736) (xy 65.494548 -388.849053) (xy 65.489836 -388.8232) (xy 65.486338 -388.799397)
			(xy 65.486126 -388.751286) (xy 64.930163 -388.751286) (xy 65.255902 -389.314944) (xy 65.256156 -389.315452)
			(xy 65.25641 -389.315452) (xy 65.25768 -389.317992) (xy 65.269949 -389.340909) (xy 65.287357 -389.389886)
			(xy 65.296232 -389.441102) (xy 65.296796 -389.46709) (xy 65.296796 -389.467344) (xy 65.296379 -389.491324)
			(xy 65.288874 -389.538694) (xy 65.274055 -389.584308) (xy 65.252287 -389.627045) (xy 65.224106 -389.665852)
			(xy 65.190203 -389.699777) (xy 65.151414 -389.727984) (xy 65.108692 -389.749779) (xy 65.063087 -389.764628)
			(xy 65.015722 -389.772163) (xy 64.991742 -389.772652) (xy 64.991234 -389.772652) (xy 64.967571 -389.772185)
			(xy 64.920811 -389.76488) (xy 64.875736 -389.750454) (xy 64.833424 -389.729252) (xy 64.794885 -389.701781)
			(xy 64.761042 -389.668699) (xy 64.732703 -389.630794) (xy 64.721232 -389.610092) (xy 64.720978 -389.60933)
			(xy 64.323722 -388.922006) (xy 64.311515 -388.898734) (xy 64.294399 -388.849053) (xy 64.289686 -388.8232)
			(xy 64.286112 -388.797979) (xy 63.757251 -388.797979) (xy 64.056006 -389.314944) (xy 64.05626 -389.315452)
			(xy 64.056514 -389.315452) (xy 64.057784 -389.317992) (xy 64.070054 -389.340909) (xy 64.087461 -389.389886)
			(xy 64.096336 -389.441101) (xy 64.0969 -389.46709) (xy 64.0969 -389.467344) (xy 64.096479 -389.491324)
			(xy 64.088974 -389.538694) (xy 64.074156 -389.584307) (xy 64.052388 -389.627044) (xy 64.024207 -389.665851)
			(xy 63.990305 -389.699775) (xy 63.951516 -389.727982) (xy 63.908794 -389.749778) (xy 63.86319 -389.764627)
			(xy 63.815826 -389.772163) (xy 63.791846 -389.772652) (xy 63.791338 -389.772652) (xy 63.767675 -389.772182)
			(xy 63.720915 -389.764877) (xy 63.67584 -389.750452) (xy 63.633528 -389.729251) (xy 63.594989 -389.70178)
			(xy 63.561146 -389.668698) (xy 63.532807 -389.630794) (xy 63.521336 -389.610092) (xy 63.521082 -389.60933)
			(xy 63.123826 -388.922006) (xy 63.111619 -388.898734) (xy 63.094503 -388.849053) (xy 63.08979 -388.8232)
			(xy 63.086378 -388.799387) (xy 63.086167 -388.751284) (xy 62.530115 -388.751284) (xy 62.855856 -389.314944)
			(xy 62.85611 -389.315452) (xy 62.856364 -389.315452) (xy 62.857634 -389.317992) (xy 62.869868 -389.340915)
			(xy 62.887188 -389.389902) (xy 62.895975 -389.441111) (xy 62.896496 -389.46709) (xy 62.896496 -389.467344)
			(xy 62.896078 -389.491337) (xy 62.888565 -389.538731) (xy 62.873731 -389.584367) (xy 62.851941 -389.627121)
			(xy 62.823731 -389.665939) (xy 62.789797 -389.699868) (xy 62.750973 -389.72807) (xy 62.708215 -389.749852)
			(xy 62.662577 -389.764678) (xy 62.615181 -389.772182) (xy 62.591188 -389.772652) (xy 62.567523 -389.772222)
			(xy 62.520762 -389.76491) (xy 62.475686 -389.750477) (xy 62.433374 -389.729269) (xy 62.394836 -389.701793)
			(xy 62.360994 -389.668705) (xy 62.332656 -389.630796) (xy 62.321186 -389.610092) (xy 62.320932 -389.60933)
			(xy 61.923676 -388.922006) (xy 61.911466 -388.898736) (xy 61.894352 -388.849053) (xy 61.88964 -388.8232)
			(xy 61.886134 -388.799398) (xy 61.885922 -388.751286) (xy 61.330221 -388.751286) (xy 61.65596 -389.314944)
			(xy 61.656214 -389.315452) (xy 61.656468 -389.315452) (xy 61.657738 -389.317992) (xy 61.669973 -389.340915)
			(xy 61.687292 -389.389902) (xy 61.696079 -389.441111) (xy 61.6966 -389.46709) (xy 61.6966 -389.467344)
			(xy 61.696178 -389.491337) (xy 61.688665 -389.538731) (xy 61.673831 -389.584366) (xy 61.652041 -389.627119)
			(xy 61.623832 -389.665938) (xy 61.589898 -389.699866) (xy 61.551075 -389.728069) (xy 61.508318 -389.749851)
			(xy 61.46268 -389.764677) (xy 61.415285 -389.772182) (xy 61.391292 -389.772652) (xy 61.367627 -389.772219)
			(xy 61.320866 -389.764907) (xy 61.27579 -389.750475) (xy 61.233478 -389.729268) (xy 61.19494 -389.701792)
			(xy 61.161098 -389.668705) (xy 61.13276 -389.630796) (xy 61.12129 -389.610092) (xy 61.121036 -389.60933)
			(xy 60.72378 -388.922006) (xy 60.71157 -388.898735) (xy 60.694456 -388.849053) (xy 60.689744 -388.8232)
			(xy 60.686231 -388.799399) (xy 60.686019 -388.751286) (xy 60.130325 -388.751286) (xy 60.456064 -389.314944)
			(xy 60.456318 -389.315452) (xy 60.456572 -389.315452) (xy 60.457842 -389.317992) (xy 60.470077 -389.340915)
			(xy 60.487396 -389.389902) (xy 60.496183 -389.441111) (xy 60.496704 -389.46709) (xy 60.496704 -389.467344)
			(xy 60.496278 -389.491337) (xy 60.488765 -389.53873) (xy 60.473931 -389.584365) (xy 60.452142 -389.627118)
			(xy 60.423933 -389.665937) (xy 60.39 -389.699865) (xy 60.351177 -389.728067) (xy 60.308421 -389.74985)
			(xy 60.262783 -389.764676) (xy 60.215389 -389.772182) (xy 60.191396 -389.772652) (xy 60.167731 -389.772216)
			(xy 60.12097 -389.764905) (xy 60.075895 -389.750473) (xy 60.033582 -389.729266) (xy 59.995044 -389.701791)
			(xy 59.961202 -389.668704) (xy 59.932864 -389.630796) (xy 59.921394 -389.610092) (xy 59.92114 -389.60933)
			(xy 59.523884 -388.922006) (xy 59.511674 -388.898735) (xy 59.49456 -388.849053) (xy 59.489848 -388.8232)
			(xy 59.486327 -388.799399) (xy 59.486115 -388.751286) (xy 58.930175 -388.751286) (xy 59.255914 -389.314944)
			(xy 59.256168 -389.315452) (xy 59.256422 -389.315452) (xy 59.257692 -389.317992) (xy 59.269962 -389.340908)
			(xy 59.287369 -389.389886) (xy 59.296244 -389.441101) (xy 59.296808 -389.46709) (xy 59.296808 -389.467344)
			(xy 59.296379 -389.491324) (xy 59.288874 -389.538693) (xy 59.274056 -389.584306) (xy 59.252289 -389.627041)
			(xy 59.224109 -389.665848) (xy 59.190208 -389.699772) (xy 59.15142 -389.72798) (xy 59.1087 -389.749776)
			(xy 59.063097 -389.764625) (xy 59.015733 -389.772162) (xy 58.991754 -389.772652) (xy 58.991246 -389.772652)
			(xy 58.967583 -389.772176) (xy 58.920824 -389.764872) (xy 58.875749 -389.750448) (xy 58.833437 -389.729248)
			(xy 58.794898 -389.701778) (xy 58.761054 -389.668697) (xy 58.732715 -389.630794) (xy 58.721244 -389.610092)
			(xy 58.72099 -389.60933) (xy 58.323734 -388.922006) (xy 58.311528 -388.898734) (xy 58.294411 -388.849053)
			(xy 58.289698 -388.8232) (xy 58.286271 -388.799389) (xy 58.28606 -388.751284) (xy 57.730277 -388.751284)
			(xy 58.056018 -389.314944) (xy 58.056272 -389.315452) (xy 58.056526 -389.315452) (xy 58.057796 -389.317992)
			(xy 58.070064 -389.340909) (xy 58.087471 -389.389886) (xy 58.096338 -389.441102) (xy 58.096912 -389.46709)
			(xy 58.096912 -389.467344) (xy 58.096439 -389.49132) (xy 58.088935 -389.538683) (xy 58.07412 -389.584289)
			(xy 58.052356 -389.627019) (xy 58.02418 -389.665821) (xy 57.990284 -389.699741) (xy 57.951502 -389.727944)
			(xy 57.908787 -389.749738) (xy 57.863191 -389.764585) (xy 57.815834 -389.772122) (xy 57.791858 -389.772652)
			(xy 57.79135 -389.772652) (xy 57.767683 -389.772212) (xy 57.720916 -389.764918) (xy 57.675833 -389.750497)
			(xy 57.633515 -389.729295) (xy 57.594973 -389.701818) (xy 57.561132 -389.668725) (xy 57.5328 -389.630808)
			(xy 57.521348 -389.610092) (xy 57.521094 -389.60933) (xy 57.123838 -388.922006) (xy 57.111641 -388.89873)
			(xy 57.094522 -388.849051) (xy 57.089802 -388.8232) (xy 57.08641 -388.799838) (xy 57.086031 -388.752634)
			(xy 57.08904 -388.72922) (xy 57.09031 -388.72033) (xy 57.087008 -388.702804) (xy 57.04332 -388.631938)
			(xy 57.029604 -388.620762) (xy 57.020968 -388.617968) (xy 56.994552 -388.607554) (xy 56.984646 -388.603236)
			(xy 56.532526 -388.603236) (xy 56.523635 -388.603572) (xy 56.506925 -388.609657) (xy 56.493313 -388.621099)
			(xy 56.488584 -388.628636) (xy 56.48443 -388.636509) (xy 56.481347 -388.654031) (xy 56.484451 -388.67155)
			(xy 56.488584 -388.679436) (xy 56.855868 -389.314944) (xy 56.856122 -389.315452) (xy 56.856376 -389.315452)
			(xy 56.857646 -389.317992) (xy 56.869881 -389.340917) (xy 56.887216 -389.389899) (xy 56.896004 -389.44111)
			(xy 56.896508 -389.46709) (xy 56.896508 -389.467344) (xy 56.896034 -389.491333) (xy 56.888523 -389.538719)
			(xy 56.873691 -389.584347) (xy 56.851905 -389.627094) (xy 56.823701 -389.665907) (xy 56.789773 -389.69983)
			(xy 56.750956 -389.728028) (xy 56.708207 -389.749808) (xy 56.662576 -389.764633) (xy 56.615189 -389.772138)
			(xy 56.5912 -389.772652) (xy 56.567535 -389.772208) (xy 56.520773 -389.764908) (xy 56.475696 -389.750482)
			(xy 56.433383 -389.729276) (xy 56.394848 -389.701797) (xy 56.361012 -389.668703) (xy 56.332686 -389.630786)
			(xy 56.321198 -389.610092) (xy 56.320944 -389.60933) (xy 55.923688 -388.922006) (xy 55.911489 -388.89873)
			(xy 55.894368 -388.849052) (xy 55.889652 -388.8232) (xy 55.886259 -388.799838) (xy 55.885881 -388.752634)
			(xy 55.88889 -388.72922) (xy 55.89016 -388.72033) (xy 55.886858 -388.702804) (xy 55.84317 -388.631938)
			(xy 55.829454 -388.620762) (xy 55.821072 -388.617968) (xy 55.794656 -388.607554) (xy 55.78475 -388.603236)
			(xy 55.33263 -388.603236) (xy 55.323738 -388.603571) (xy 55.307028 -388.609655) (xy 55.293415 -388.621097)
			(xy 55.288688 -388.628636) (xy 55.284533 -388.636509) (xy 55.28145 -388.654031) (xy 55.284555 -388.67155)
			(xy 55.288688 -388.679436) (xy 55.655972 -389.314944) (xy 55.656226 -389.315452) (xy 55.65648 -389.315452)
			(xy 55.65775 -389.317992) (xy 55.669984 -389.340917) (xy 55.68732 -389.389899) (xy 55.696107 -389.44111)
			(xy 55.696612 -389.46709) (xy 55.696612 -389.467344) (xy 55.696138 -389.491333) (xy 55.688627 -389.53872)
			(xy 55.673795 -389.584348) (xy 55.652009 -389.627095) (xy 55.623805 -389.665908) (xy 55.589877 -389.699831)
			(xy 55.551061 -389.72803) (xy 55.508311 -389.749811) (xy 55.462681 -389.764636) (xy 55.415293 -389.772141)
			(xy 55.391304 -389.772652) (xy 55.367639 -389.772208) (xy 55.320876 -389.764908) (xy 55.275799 -389.750483)
			(xy 55.233486 -389.729277) (xy 55.19495 -389.701799) (xy 55.161114 -389.668705) (xy 55.132787 -389.630788)
			(xy 55.121302 -389.610092) (xy 55.121048 -389.60933) (xy 54.723792 -388.922006) (xy 54.711593 -388.89873)
			(xy 54.694471 -388.849052) (xy 54.689756 -388.8232) (xy 54.686363 -388.799838) (xy 54.685985 -388.752634)
			(xy 54.688994 -388.72922) (xy 54.690264 -388.72033) (xy 54.686962 -388.702804) (xy 54.643274 -388.631938)
			(xy 54.629558 -388.620762) (xy 54.620922 -388.617968) (xy 54.594506 -388.607554) (xy 54.5846 -388.603236)
			(xy 54.548278 -388.603236) (xy 54.523322 -388.602623) (xy 54.474369 -388.592882) (xy 54.428257 -388.573781)
			(xy 54.386756 -388.546051) (xy 54.3687 -388.528814) (xy 53.92166 -388.081774) (xy 53.904399 -388.063733)
			(xy 53.876638 -388.02224) (xy 53.857522 -387.976122) (xy 53.847786 -387.927158) (xy 53.847238 -387.902196)
			(xy 53.847238 -386.031232) (xy 53.847048 -386.024563) (xy 53.843582 -386.011684) (xy 53.84038 -386.005832)
			(xy 53.523896 -385.457954) (xy 53.511962 -385.435293) (xy 53.495009 -385.386969) (xy 53.486362 -385.336493)
			(xy 53.485796 -385.310888) (xy 53.485796 -385.31038) (xy 53.486245 -385.286375) (xy 53.493762 -385.238958)
			(xy 53.508608 -385.193302) (xy 53.530416 -385.150531) (xy 53.55865 -385.111702) (xy 53.592613 -385.077769)
			(xy 53.631469 -385.049571) (xy 53.674259 -385.027801) (xy 53.719929 -385.012997) (xy 53.767353 -385.005523)
			(xy 53.791358 -385.005072) (xy 53.795676 -385.005072) (xy 53.831998 -384.969258) (xy 53.838954 -384.961835)
			(xy 53.846833 -384.943099) (xy 53.847238 -384.932936) (xy 53.847238 -384.033776) (xy 53.847812 -384.008817)
			(xy 53.857556 -383.959858) (xy 53.876665 -383.913742) (xy 53.904405 -383.872241) (xy 53.92166 -383.854198)
			(xy 54.17058 -383.605278) (xy 54.177425 -383.597879) (xy 54.185155 -383.579281) (xy 54.185566 -383.56921)
			(xy 54.185566 -375.978674) (xy 54.185137 -375.968607) (xy 54.177413 -375.950012) (xy 54.17058 -375.942606)
			(xy 51.999642 -373.771668) (xy 51.992244 -373.764823) (xy 51.973645 -373.757099) (xy 51.963574 -373.756682)
			(xy 49.455832 -373.756682) (xy 49.444411 -373.757308) (xy 49.423822 -373.767197) (xy 49.416208 -373.775732)
			(xy 49.366678 -373.837454) (xy 49.36002 -373.846781) (xy 49.354876 -373.869078) (xy 49.356772 -373.88038)
			(xy 49.361028 -373.900752) (xy 49.365607 -373.94212) (xy 49.365916 -373.96293) (xy 49.36545 -373.990198)
			(xy 49.357685 -374.04418) (xy 49.342315 -374.096506) (xy 49.319655 -374.146112) (xy 49.290166 -374.191989)
			(xy 49.254448 -374.233202) (xy 49.213228 -374.268912) (xy 49.167346 -374.298392) (xy 49.117735 -374.321042)
			(xy 49.065405 -374.336401) (xy 49.011423 -374.344156) (xy 48.984154 -374.344692) (xy 48.120554 -374.344692)
			(xy 48.093286 -374.344202) (xy 48.039306 -374.336436) (xy 47.98698 -374.321067) (xy 47.937374 -374.298408)
			(xy 47.891496 -374.268922) (xy 47.850282 -374.233207) (xy 47.814569 -374.191991) (xy 47.785084 -374.146112)
			(xy 47.762428 -374.096505) (xy 47.747061 -374.044179) (xy 47.739296 -373.990198) (xy 47.738792 -373.96293)
			(xy 47.739094 -373.94212) (xy 47.743671 -373.900751) (xy 47.747936 -373.88038) (xy 47.749835 -373.869078)
			(xy 47.744691 -373.846779) (xy 47.73803 -373.837454) (xy 47.6885 -373.775732) (xy 47.680867 -373.767221)
			(xy 47.66029 -373.757334) (xy 47.648876 -373.756682) (xy 38.613334 -373.756682) (xy 38.603995 -373.75716)
			(xy 38.586585 -373.763944) (xy 38.572735 -373.776487) (xy 38.568122 -373.784622) (xy 38.518846 -373.88292)
			(xy 38.519354 -373.88927) (xy 38.520211 -373.896258) (xy 38.525228 -373.909407) (xy 38.52926 -373.915178)
			(xy 38.584001 -373.989411) (xy 38.687856 -374.141862) (xy 38.785106 -374.29861) (xy 38.875573 -374.459367)
			(xy 38.959093 -374.623841) (xy 39.035513 -374.791732) (xy 39.104694 -374.962733) (xy 39.166509 -375.136532)
			(xy 39.220846 -375.312812) (xy 39.267606 -375.491252) (xy 39.306702 -375.671526) (xy 39.338065 -375.853306)
			(xy 39.361636 -376.036258) (xy 39.377373 -376.220051) (xy 39.385247 -376.404348) (xy 39.385748 -376.49658)
			(xy 39.385248 -376.589497) (xy 39.377253 -376.77516) (xy 39.372361 -376.83186) (xy 41.04894 -376.83186)
			(xy 41.04894 -375.96826) (xy 41.049426 -375.940991) (xy 41.057188 -375.887007) (xy 41.072553 -375.834677)
			(xy 41.09521 -375.785067) (xy 41.124696 -375.739186) (xy 41.160411 -375.697969) (xy 41.201628 -375.662254)
			(xy 41.247509 -375.632768) (xy 41.297119 -375.610111) (xy 41.349449 -375.594746) (xy 41.403433 -375.586984)
			(xy 41.457971 -375.586984) (xy 41.511955 -375.594746) (xy 41.564285 -375.610111) (xy 41.613895 -375.632768)
			(xy 41.659776 -375.662254) (xy 41.700993 -375.697969) (xy 41.736708 -375.739186) (xy 41.766194 -375.785067)
			(xy 41.788851 -375.834677) (xy 41.804216 -375.887007) (xy 41.811978 -375.940991) (xy 41.812464 -375.96826)
			(xy 41.812464 -376.83186) (xy 41.811978 -376.859129) (xy 41.804216 -376.913113) (xy 41.788851 -376.965443)
			(xy 41.766194 -377.015053) (xy 41.736708 -377.060934) (xy 41.700993 -377.102151) (xy 41.659776 -377.137866)
			(xy 41.613895 -377.167352) (xy 41.564285 -377.190009) (xy 41.511955 -377.205374) (xy 41.457971 -377.213136)
			(xy 41.403433 -377.213136) (xy 41.349449 -377.205374) (xy 41.297119 -377.190009) (xy 41.247509 -377.167352)
			(xy 41.201628 -377.137866) (xy 41.160411 -377.102151) (xy 41.124696 -377.060934) (xy 41.09521 -377.015053)
			(xy 41.072553 -376.965443) (xy 41.057188 -376.913113) (xy 41.049426 -376.859129) (xy 41.04894 -376.83186)
			(xy 39.372361 -376.83186) (xy 39.361278 -376.960306) (xy 39.337352 -377.144594) (xy 39.30552 -377.327682)
			(xy 39.26584 -377.509231) (xy 39.218387 -377.688905) (xy 39.163247 -377.866371) (xy 39.100524 -378.0413)
			(xy 39.030333 -378.213369) (xy 38.952804 -378.382258) (xy 38.868081 -378.547656) (xy 38.77632 -378.709256)
			(xy 38.677692 -378.866758) (xy 38.572379 -379.019872) (xy 38.460577 -379.168312) (xy 38.342492 -379.311806)
			(xy 38.218342 -379.450086) (xy 38.088359 -379.582897) (xy 37.952782 -379.709993) (xy 37.811862 -379.831138)
			(xy 37.665862 -379.946109) (xy 37.51505 -380.054692) (xy 37.359706 -380.156685) (xy 37.200118 -380.251902)
			(xy 37.036581 -380.340164) (xy 36.869399 -380.421309) (xy 36.69888 -380.495186) (xy 36.525341 -380.561659)
			(xy 36.349102 -380.620604) (xy 36.170491 -380.671912) (xy 35.989838 -380.715489) (xy 35.807477 -380.751253)
			(xy 35.623747 -380.779139) (xy 35.438987 -380.799094) (xy 35.25354 -380.811082) (xy 35.067748 -380.81508)
			(xy 34.881956 -380.811082) (xy 34.696509 -380.799094) (xy 34.511749 -380.779139) (xy 34.328019 -380.751253)
			(xy 34.145658 -380.715489) (xy 33.965005 -380.671912) (xy 33.786394 -380.620604) (xy 33.610155 -380.561659)
			(xy 33.436616 -380.495186) (xy 33.266097 -380.421309) (xy 33.098915 -380.340164) (xy 32.935378 -380.251902)
			(xy 32.77579 -380.156685) (xy 32.620446 -380.054692) (xy 32.469634 -379.946109) (xy 32.323634 -379.831138)
			(xy 32.182714 -379.709993) (xy 32.047137 -379.582897) (xy 31.917154 -379.450086) (xy 31.793004 -379.311806)
			(xy 31.674919 -379.168312) (xy 31.563117 -379.019872) (xy 31.457804 -378.866758) (xy 31.359176 -378.709256)
			(xy 31.267415 -378.547656) (xy 31.182692 -378.382258) (xy 31.105163 -378.213369) (xy 31.034972 -378.0413)
			(xy 30.972249 -377.866371) (xy 30.917109 -377.688905) (xy 30.869656 -377.509231) (xy 30.829976 -377.327682)
			(xy 30.798144 -377.144594) (xy 30.774218 -376.960306) (xy 30.758243 -376.77516) (xy 30.750248 -376.589497)
			(xy 30.749748 -376.49658) (xy 30.750244 -376.403871) (xy 30.758204 -376.218623) (xy 30.774108 -376.033887)
			(xy 30.797928 -375.850004) (xy 30.829619 -375.667314) (xy 30.869123 -375.486152) (xy 30.916367 -375.306853)
			(xy 30.971264 -375.129747) (xy 31.033713 -374.955161) (xy 31.103599 -374.783416) (xy 31.180792 -374.61483)
			(xy 31.265151 -374.449712) (xy 31.35652 -374.288368) (xy 31.45473 -374.131095) (xy 31.559601 -373.978182)
			(xy 31.614872 -373.903748) (xy 31.61665 -373.88292) (xy 31.567374 -373.784622) (xy 31.562804 -373.776448)
			(xy 31.548962 -373.76386) (xy 31.531516 -373.757101) (xy 31.522162 -373.756682) (xy 8.497062 -373.756682)
			(xy 8.486994 -373.757111) (xy 8.468398 -373.764834) (xy 8.460994 -373.771668) (xy 7.408164 -374.824498)
			(xy 7.40131 -374.831893) (xy 7.393565 -374.850492) (xy 7.393178 -374.860566) (xy 7.393178 -379.238256)
			(xy 7.393611 -379.248322) (xy 7.401337 -379.266914) (xy 7.408164 -379.274324) (xy 10.5029 -382.36906)
			(xy 41.04894 -382.36906) (xy 41.04894 -381.50546) (xy 41.049426 -381.478191) (xy 41.057188 -381.424207)
			(xy 41.072553 -381.371877) (xy 41.09521 -381.322267) (xy 41.124696 -381.276386) (xy 41.160411 -381.235169)
			(xy 41.201628 -381.199454) (xy 41.247509 -381.169968) (xy 41.297119 -381.147311) (xy 41.349449 -381.131946)
			(xy 41.403433 -381.124184) (xy 41.457971 -381.124184) (xy 41.511955 -381.131946) (xy 41.564285 -381.147311)
			(xy 41.613895 -381.169968) (xy 41.659776 -381.199454) (xy 41.700993 -381.235169) (xy 41.736708 -381.276386)
			(xy 41.766194 -381.322267) (xy 41.788851 -381.371877) (xy 41.804216 -381.424207) (xy 41.811978 -381.478191)
			(xy 41.812464 -381.50546) (xy 41.812464 -382.36906) (xy 41.811978 -382.396329) (xy 41.804216 -382.450313)
			(xy 41.788851 -382.502643) (xy 41.766194 -382.552253) (xy 41.736708 -382.598134) (xy 41.700993 -382.639351)
			(xy 41.659776 -382.675066) (xy 41.613895 -382.704552) (xy 41.564285 -382.727209) (xy 41.511955 -382.742574)
			(xy 41.457971 -382.750336) (xy 41.403433 -382.750336) (xy 41.349449 -382.742574) (xy 41.297119 -382.727209)
			(xy 41.247509 -382.704552) (xy 41.201628 -382.675066) (xy 41.160411 -382.639351) (xy 41.124696 -382.598134)
			(xy 41.09521 -382.552253) (xy 41.072553 -382.502643) (xy 41.057188 -382.450313) (xy 41.049426 -382.396329)
			(xy 41.04894 -382.36906) (xy 10.5029 -382.36906) (xy 12.091162 -383.957322) (xy 12.10183 -383.961132)
			(xy 12.128078 -383.971075) (xy 12.177565 -383.997561) (xy 12.222637 -384.03101) (xy 12.262323 -384.070702)
			(xy 12.295767 -384.115778) (xy 12.322246 -384.165268) (xy 12.332208 -384.19151) (xy 12.336018 -384.202178)
			(xy 12.513056 -384.379216) (xy 12.532106 -384.386836) (xy 12.542266 -384.386582) (xy 12.54887 -384.386582)
			(xy 12.576125 -384.387043) (xy 12.630079 -384.394796) (xy 12.682381 -384.41015) (xy 12.731966 -384.43279)
			(xy 12.777824 -384.462257) (xy 12.819021 -384.497951) (xy 12.854719 -384.539144) (xy 12.884191 -384.584999)
			(xy 12.906836 -384.634581) (xy 12.922195 -384.686882) (xy 12.929954 -384.740836) (xy 12.930378 -384.76809)
			(xy 12.930378 -384.774694) (xy 12.930124 -384.784854) (xy 12.937744 -384.803904) (xy 13.444728 -385.310888)
			(xy 47.485808 -385.310888) (xy 47.485808 -385.31038) (xy 47.486243 -385.2864) (xy 47.493745 -385.239031)
			(xy 47.508561 -385.193417) (xy 47.530326 -385.15068) (xy 47.558505 -385.111872) (xy 47.592406 -385.077947)
			(xy 47.631194 -385.04974) (xy 47.673915 -385.027944) (xy 47.719518 -385.013096) (xy 47.766882 -385.00556)
			(xy 47.790862 -385.005072) (xy 47.79137 -385.005072) (xy 47.815305 -385.005523) (xy 47.862591 -385.012984)
			(xy 47.908134 -385.027728) (xy 47.950821 -385.049394) (xy 47.989606 -385.077452) (xy 48.023541 -385.111216)
			(xy 48.051795 -385.149858) (xy 48.06315 -385.170934) (xy 48.063658 -385.17195) (xy 48.143964 -385.310888)
			(xy 48.685704 -385.310888) (xy 48.685704 -385.31038) (xy 48.686143 -385.2864) (xy 48.693645 -385.239031)
			(xy 48.70846 -385.193417) (xy 48.730225 -385.150681) (xy 48.758404 -385.111873) (xy 48.792304 -385.077949)
			(xy 48.831092 -385.049741) (xy 48.873812 -385.027945) (xy 48.919415 -385.013097) (xy 48.966779 -385.005561)
			(xy 48.990758 -385.005072) (xy 48.991266 -385.005072) (xy 49.015201 -385.005526) (xy 49.062486 -385.012986)
			(xy 49.10803 -385.02773) (xy 49.150716 -385.049395) (xy 49.189502 -385.077453) (xy 49.223437 -385.111216)
			(xy 49.251691 -385.149859) (xy 49.263046 -385.170934) (xy 49.263554 -385.17195) (xy 49.34386 -385.310888)
			(xy 49.8856 -385.310888) (xy 49.8856 -385.31038) (xy 49.886043 -385.286401) (xy 49.893545 -385.239032)
			(xy 49.90836 -385.193418) (xy 49.930124 -385.150682) (xy 49.958303 -385.111875) (xy 49.992203 -385.07795)
			(xy 50.030989 -385.049743) (xy 50.073709 -385.027946) (xy 50.119312 -385.013097) (xy 50.166675 -385.005561)
			(xy 50.190654 -385.005072) (xy 50.191162 -385.005072) (xy 50.215097 -385.005529) (xy 50.262382 -385.012989)
			(xy 50.307925 -385.027732) (xy 50.350612 -385.049397) (xy 50.389397 -385.077454) (xy 50.423333 -385.111217)
			(xy 50.451587 -385.149859) (xy 50.462942 -385.170934) (xy 50.46345 -385.17195) (xy 50.543756 -385.310888)
			(xy 51.086004 -385.310888) (xy 51.086004 -385.31038) (xy 51.086444 -385.286388) (xy 51.093954 -385.238994)
			(xy 51.108785 -385.193359) (xy 51.130572 -385.150605) (xy 51.158779 -385.111786) (xy 51.192711 -385.077858)
			(xy 51.231533 -385.049655) (xy 51.274288 -385.027872) (xy 51.319925 -385.013046) (xy 51.36732 -385.005542)
			(xy 51.391312 -385.005072) (xy 51.415246 -385.00557) (xy 51.462529 -385.013022) (xy 51.508071 -385.027757)
			(xy 51.550758 -385.049416) (xy 51.589544 -385.077467) (xy 51.62348 -385.111224) (xy 51.651736 -385.149861)
			(xy 51.663092 -385.170934) (xy 51.6636 -385.17195) (xy 51.743906 -385.310888) (xy 52.2859 -385.310888)
			(xy 52.2859 -385.31038) (xy 52.286344 -385.286388) (xy 52.293854 -385.238995) (xy 52.308684 -385.19336)
			(xy 52.330471 -385.150606) (xy 52.358677 -385.111788) (xy 52.392609 -385.077859) (xy 52.43143 -385.049656)
			(xy 52.474186 -385.027873) (xy 52.519822 -385.013047) (xy 52.567216 -385.005542) (xy 52.591208 -385.005072)
			(xy 52.615141 -385.005573) (xy 52.662424 -385.013024) (xy 52.707967 -385.027759) (xy 52.750653 -385.049417)
			(xy 52.789439 -385.077468) (xy 52.823376 -385.111224) (xy 52.851632 -385.149861) (xy 52.862988 -385.170934)
			(xy 52.863496 -385.17195) (xy 53.255926 -385.850892) (xy 53.26875 -385.874225) (xy 53.286971 -385.924247)
			(xy 53.296231 -385.976673) (xy 53.29682 -386.003292) (xy 53.296331 -386.02727) (xy 53.288835 -386.074636)
			(xy 53.274024 -386.120247) (xy 53.252265 -386.162982) (xy 53.224092 -386.201789) (xy 53.190197 -386.235713)
			(xy 53.151416 -386.263922) (xy 53.1087 -386.285719) (xy 53.063102 -386.30057) (xy 53.015743 -386.30811)
			(xy 52.991766 -386.3086) (xy 52.991258 -386.3086) (xy 52.967686 -386.308159) (xy 52.9211 -386.300927)
			(xy 52.876182 -386.286609) (xy 52.834004 -386.265548) (xy 52.79557 -386.238246) (xy 52.761797 -386.205353)
			(xy 52.73349 -386.167653) (xy 52.722018 -386.147056) (xy 52.72151 -386.146294) (xy 52.323746 -385.457954)
			(xy 52.311886 -385.435269) (xy 52.29503 -385.38694) (xy 52.28645 -385.33648) (xy 52.2859 -385.310888)
			(xy 51.743906 -385.310888) (xy 52.05603 -385.850892) (xy 52.068854 -385.874225) (xy 52.087075 -385.924247)
			(xy 52.096335 -385.976673) (xy 52.096924 -386.003292) (xy 52.096431 -386.02727) (xy 52.088935 -386.074635)
			(xy 52.074125 -386.120246) (xy 52.052366 -386.16298) (xy 52.024193 -386.201787) (xy 51.990299 -386.235712)
			(xy 51.951518 -386.26392) (xy 51.908803 -386.285718) (xy 51.863206 -386.30057) (xy 51.815847 -386.308109)
			(xy 51.79187 -386.3086) (xy 51.791362 -386.3086) (xy 51.76779 -386.308156) (xy 51.721204 -386.300924)
			(xy 51.676286 -386.286607) (xy 51.634108 -386.265547) (xy 51.595674 -386.238245) (xy 51.561901 -386.205352)
			(xy 51.533594 -386.167653) (xy 51.522122 -386.147056) (xy 51.521614 -386.146294) (xy 51.12385 -385.457954)
			(xy 51.111991 -385.435269) (xy 51.095134 -385.38694) (xy 51.086554 -385.33648) (xy 51.086004 -385.310888)
			(xy 50.543756 -385.310888) (xy 50.85588 -385.850892) (xy 50.868619 -385.874207) (xy 50.886709 -385.924157)
			(xy 50.895924 -385.976476) (xy 50.89652 -386.003038) (xy 50.89652 -386.003292) (xy 50.89603 -386.027282)
			(xy 50.888526 -386.074673) (xy 50.8737 -386.120306) (xy 50.851918 -386.163057) (xy 50.823717 -386.201876)
			(xy 50.789791 -386.235804) (xy 50.750974 -386.264008) (xy 50.708224 -386.285792) (xy 50.662592 -386.300621)
			(xy 50.615202 -386.308128) (xy 50.591212 -386.3086) (xy 50.567638 -386.308197) (xy 50.521051 -386.300957)
			(xy 50.476132 -386.286633) (xy 50.433954 -386.265566) (xy 50.395521 -386.238258) (xy 50.361749 -386.205359)
			(xy 50.333443 -386.167655) (xy 50.321972 -386.147056) (xy 50.321464 -386.146294) (xy 49.9237 -385.457954)
			(xy 49.911766 -385.435295) (xy 49.894835 -385.386965) (xy 49.886183 -385.336491) (xy 49.8856 -385.310888)
			(xy 49.34386 -385.310888) (xy 49.655984 -385.850892) (xy 49.668715 -385.874211) (xy 49.68681 -385.924158)
			(xy 49.696027 -385.976477) (xy 49.696624 -386.003038) (xy 49.696624 -386.003292) (xy 49.69613 -386.027282)
			(xy 49.688626 -386.074672) (xy 49.6738 -386.120305) (xy 49.652019 -386.163056) (xy 49.623818 -386.201874)
			(xy 49.589892 -386.235803) (xy 49.551077 -386.264007) (xy 49.508327 -386.285791) (xy 49.462695 -386.30062)
			(xy 49.415306 -386.308128) (xy 49.391316 -386.3086) (xy 49.367742 -386.308193) (xy 49.321155 -386.300954)
			(xy 49.276236 -386.286631) (xy 49.234058 -386.265564) (xy 49.195625 -386.238257) (xy 49.161853 -386.205359)
			(xy 49.133547 -386.167655) (xy 49.122076 -386.147056) (xy 49.121568 -386.146294) (xy 48.723804 -385.457954)
			(xy 48.71187 -385.435295) (xy 48.694939 -385.386965) (xy 48.686287 -385.336491) (xy 48.685704 -385.310888)
			(xy 48.143964 -385.310888) (xy 48.456088 -385.850892) (xy 48.46882 -385.874211) (xy 48.486915 -385.924158)
			(xy 48.496131 -385.976477) (xy 48.496728 -386.003038) (xy 48.496728 -386.003292) (xy 48.49623 -386.027282)
			(xy 48.488726 -386.074672) (xy 48.473901 -386.120304) (xy 48.45212 -386.163055) (xy 48.42392 -386.201873)
			(xy 48.389994 -386.235801) (xy 48.351179 -386.264005) (xy 48.30843 -386.28579) (xy 48.262799 -386.300619)
			(xy 48.21541 -386.308128) (xy 48.19142 -386.3086) (xy 48.167847 -386.30819) (xy 48.121259 -386.300952)
			(xy 48.076341 -386.286629) (xy 48.034162 -386.265563) (xy 47.995729 -386.238256) (xy 47.961957 -386.205358)
			(xy 47.933651 -386.167655) (xy 47.92218 -386.147056) (xy 47.921672 -386.146294) (xy 47.523908 -385.457954)
			(xy 47.511974 -385.435295) (xy 47.495043 -385.386965) (xy 47.486391 -385.336491) (xy 47.485808 -385.310888)
			(xy 13.444728 -385.310888) (xy 14.714728 -386.580888) (xy 14.721586 -386.584444) (xy 14.746548 -386.598055)
			(xy 14.792392 -386.63168) (xy 14.832595 -386.67188) (xy 14.866225 -386.71772) (xy 14.879828 -386.742686)
			(xy 14.883384 -386.749544) (xy 15.923514 -387.789674) (xy 40.901112 -387.789674) (xy 40.901112 -386.926074)
			(xy 40.901598 -386.898805) (xy 40.90936 -386.844821) (xy 40.924725 -386.792491) (xy 40.947382 -386.742881)
			(xy 40.976868 -386.697) (xy 41.012583 -386.655783) (xy 41.0538 -386.620068) (xy 41.099681 -386.590582)
			(xy 41.149291 -386.567925) (xy 41.201621 -386.55256) (xy 41.255605 -386.544798) (xy 41.310143 -386.544798)
			(xy 41.364127 -386.55256) (xy 41.416457 -386.567925) (xy 41.466067 -386.590582) (xy 41.511948 -386.620068)
			(xy 41.553165 -386.655783) (xy 41.58888 -386.697) (xy 41.618366 -386.742881) (xy 41.641023 -386.792491)
			(xy 41.656388 -386.844821) (xy 41.66415 -386.898805) (xy 41.664636 -386.926074) (xy 41.664636 -387.789674)
			(xy 41.66415 -387.816943) (xy 41.656388 -387.870927) (xy 41.641023 -387.923257) (xy 41.618366 -387.972867)
			(xy 41.58888 -388.018748) (xy 41.553165 -388.059965) (xy 41.511948 -388.09568) (xy 41.466067 -388.125166)
			(xy 41.416457 -388.147823) (xy 41.364127 -388.163188) (xy 41.310143 -388.17095) (xy 41.255605 -388.17095)
			(xy 41.201621 -388.163188) (xy 41.149291 -388.147823) (xy 41.099681 -388.125166) (xy 41.0538 -388.09568)
			(xy 41.012583 -388.059965) (xy 40.976868 -388.018748) (xy 40.947382 -387.972867) (xy 40.924725 -387.923257)
			(xy 40.90936 -387.870927) (xy 40.901598 -387.816943) (xy 40.901112 -387.789674) (xy 15.923514 -387.789674)
			(xy 16.31061 -388.17677) (xy 16.319287 -388.18461) (xy 16.341407 -388.192121) (xy 16.364571 -388.189104)
			(xy 16.374618 -388.18312) (xy 16.374872 -388.18312) (xy 16.397919 -388.16834) (xy 16.447434 -388.144974)
			(xy 16.499837 -388.129115) (xy 16.553999 -388.121104) (xy 16.581374 -388.120636) (xy 16.607993 -388.121109)
			(xy 16.660689 -388.128681) (xy 16.71177 -388.143676) (xy 16.760199 -388.165787) (xy 16.804987 -388.194566)
			(xy 16.845224 -388.229425) (xy 16.880091 -388.269655) (xy 16.908878 -388.314438) (xy 16.930999 -388.362862)
			(xy 16.946003 -388.413941) (xy 16.953586 -388.466635) (xy 16.953992 -388.493254) (xy 16.953505 -388.520628)
			(xy 16.945486 -388.574784) (xy 16.929628 -388.627185) (xy 16.906272 -388.6767) (xy 16.891508 -388.699756)
			(xy 16.891508 -388.70001) (xy 16.885482 -388.710051) (xy 16.882414 -388.733239) (xy 16.889953 -388.755381)
			(xy 16.897858 -388.764018) (xy 16.931816 -388.797976) (xy 47.486325 -388.797976) (xy 47.486573 -388.747043)
			(xy 47.495267 -388.696858) (xy 47.512163 -388.648809) (xy 47.536795 -388.604229) (xy 47.56848 -388.564351)
			(xy 47.60634 -388.530281) (xy 47.649327 -388.502963) (xy 47.696249 -388.483153) (xy 47.745807 -388.471399)
			(xy 47.796628 -388.468029) (xy 47.847305 -388.473134) (xy 47.896432 -388.486573) (xy 47.942651 -388.507975)
			(xy 47.984679 -388.536747) (xy 48.021353 -388.57209) (xy 48.051657 -388.613027) (xy 48.063658 -388.635494)
			(xy 48.064166 -388.636764) (xy 48.15733 -388.797975) (xy 48.686228 -388.797975) (xy 48.686477 -388.747043)
			(xy 48.69517 -388.696859) (xy 48.712067 -388.648811) (xy 48.736698 -388.604231) (xy 48.768383 -388.564354)
			(xy 48.806242 -388.530284) (xy 48.849228 -388.502966) (xy 48.89615 -388.483156) (xy 48.945707 -388.471403)
			(xy 48.996528 -388.468032) (xy 49.047203 -388.473137) (xy 49.09633 -388.486576) (xy 49.142548 -388.507978)
			(xy 49.184575 -388.536748) (xy 49.221249 -388.572091) (xy 49.251553 -388.613027) (xy 49.263554 -388.635494)
			(xy 49.264062 -388.636764) (xy 49.330245 -388.751287) (xy 49.885901 -388.751287) (xy 49.893233 -388.703732)
			(xy 49.907928 -388.657914) (xy 49.929622 -388.614966) (xy 49.95778 -388.575949) (xy 49.991706 -388.541827)
			(xy 50.03056 -388.513445) (xy 50.073382 -388.491502) (xy 50.119114 -388.476543) (xy 50.166626 -388.468937)
			(xy 50.214742 -388.468871) (xy 50.262274 -388.476348) (xy 50.308047 -388.491183) (xy 50.350929 -388.513008)
			(xy 50.389861 -388.541284) (xy 50.423879 -388.575313) (xy 50.452143 -388.614254) (xy 50.46345 -388.635494)
			(xy 50.463958 -388.636764) (xy 50.53014 -388.751285) (xy 51.086146 -388.751285) (xy 51.093477 -388.703739)
			(xy 51.10817 -388.657929) (xy 51.129861 -388.614989) (xy 51.158013 -388.575979) (xy 51.191932 -388.541863)
			(xy 51.230779 -388.513485) (xy 51.273593 -388.491546) (xy 51.319317 -388.476589) (xy 51.366819 -388.468982)
			(xy 51.414927 -388.468915) (xy 51.462451 -388.476388) (xy 51.508216 -388.491218) (xy 51.551092 -388.513037)
			(xy 51.590018 -388.541306) (xy 51.624032 -388.575327) (xy 51.652294 -388.614258) (xy 51.6636 -388.635494)
			(xy 51.664108 -388.636764) (xy 51.730289 -388.751284) (xy 52.286049 -388.751284) (xy 52.293381 -388.703739)
			(xy 52.308073 -388.65793) (xy 52.329764 -388.614991) (xy 52.357916 -388.575981) (xy 52.391834 -388.541866)
			(xy 52.43068 -388.513488) (xy 52.473494 -388.49155) (xy 52.519217 -388.476592) (xy 52.566719 -388.468986)
			(xy 52.614826 -388.468918) (xy 52.662349 -388.476392) (xy 52.708114 -388.491221) (xy 52.750989 -388.513039)
			(xy 52.789914 -388.541308) (xy 52.823928 -388.575328) (xy 52.85219 -388.614259) (xy 52.863496 -388.635494)
			(xy 52.864004 -388.636764) (xy 52.930187 -388.751287) (xy 53.486104 -388.751287) (xy 53.493436 -388.703733)
			(xy 53.508131 -388.657915) (xy 53.529825 -388.614968) (xy 53.557983 -388.575951) (xy 53.591908 -388.54183)
			(xy 53.630761 -388.513448) (xy 53.673583 -388.491506) (xy 53.719314 -388.476547) (xy 53.766825 -388.468941)
			(xy 53.814941 -388.468875) (xy 53.862473 -388.476351) (xy 53.908245 -388.491185) (xy 53.951126 -388.51301)
			(xy 53.990057 -388.541286) (xy 54.024075 -388.575314) (xy 54.052339 -388.614254) (xy 54.063646 -388.635494)
			(xy 54.064154 -388.636764) (xy 54.456076 -389.314944) (xy 54.45633 -389.315452) (xy 54.456584 -389.315452)
			(xy 54.457854 -389.317992) (xy 54.47009 -389.340915) (xy 54.487408 -389.389901) (xy 54.496195 -389.441111)
			(xy 54.496716 -389.46709) (xy 54.496716 -389.467344) (xy 54.496278 -389.491336) (xy 54.488766 -389.538728)
			(xy 54.473933 -389.584362) (xy 54.452144 -389.627115) (xy 54.423937 -389.665932) (xy 54.390005 -389.69986)
			(xy 54.351184 -389.728063) (xy 54.308429 -389.749846) (xy 54.262793 -389.764674) (xy 54.2154 -389.772181)
			(xy 54.191408 -389.772652) (xy 54.167744 -389.772206) (xy 54.120983 -389.764897) (xy 54.075908 -389.750467)
			(xy 54.033595 -389.729262) (xy 53.995057 -389.701788) (xy 53.961215 -389.668702) (xy 53.932876 -389.630795)
			(xy 53.921406 -389.610092) (xy 53.921152 -389.60933) (xy 53.523896 -388.922006) (xy 53.511687 -388.898735)
			(xy 53.494573 -388.849053) (xy 53.48986 -388.8232) (xy 53.486316 -388.799402) (xy 53.486104 -388.751287)
			(xy 52.930187 -388.751287) (xy 53.255926 -389.314944) (xy 53.25618 -389.315452) (xy 53.256434 -389.315452)
			(xy 53.257704 -389.317992) (xy 53.269975 -389.340908) (xy 53.287382 -389.389886) (xy 53.296256 -389.441101)
			(xy 53.29682 -389.46709) (xy 53.29682 -389.467344) (xy 53.296379 -389.491323) (xy 53.288875 -389.538691)
			(xy 53.274057 -389.584303) (xy 53.252292 -389.627038) (xy 53.224113 -389.665844) (xy 53.190213 -389.699768)
			(xy 53.151427 -389.727975) (xy 53.108708 -389.749772) (xy 53.063107 -389.764623) (xy 53.015745 -389.772162)
			(xy 52.991766 -389.772652) (xy 52.991258 -389.772652) (xy 52.967595 -389.772166) (xy 52.920836 -389.764864)
			(xy 52.875762 -389.750442) (xy 52.83345 -389.729243) (xy 52.794911 -389.701775) (xy 52.761067 -389.668695)
			(xy 52.732727 -389.630793) (xy 52.721256 -389.610092) (xy 52.721002 -389.60933) (xy 52.323746 -388.922006)
			(xy 52.311534 -388.898737) (xy 52.294422 -388.849054) (xy 52.28971 -388.8232) (xy 52.28626 -388.799391)
			(xy 52.286049 -388.751284) (xy 51.730289 -388.751284) (xy 52.05603 -389.314944) (xy 52.056284 -389.315452)
			(xy 52.056538 -389.315452) (xy 52.057808 -389.317992) (xy 52.07008 -389.340908) (xy 52.087486 -389.389886)
			(xy 52.09636 -389.441101) (xy 52.096924 -389.46709) (xy 52.096924 -389.467344) (xy 52.096479 -389.491323)
			(xy 52.088975 -389.53869) (xy 52.074158 -389.584302) (xy 52.052392 -389.627036) (xy 52.024214 -389.665843)
			(xy 51.990315 -389.699767) (xy 51.951529 -389.727974) (xy 51.908811 -389.749771) (xy 51.86321 -389.764622)
			(xy 51.815849 -389.772161) (xy 51.79187 -389.772652) (xy 51.791362 -389.772652) (xy 51.767699 -389.772163)
			(xy 51.720941 -389.764861) (xy 51.675866 -389.750439) (xy 51.633554 -389.729241) (xy 51.595015 -389.701774)
			(xy 51.561171 -389.668695) (xy 51.532831 -389.630793) (xy 51.52136 -389.610092) (xy 51.521106 -389.60933)
			(xy 51.12385 -388.922006) (xy 51.111638 -388.898736) (xy 51.094526 -388.849054) (xy 51.089814 -388.8232)
			(xy 51.086357 -388.799392) (xy 51.086146 -388.751285) (xy 50.53014 -388.751285) (xy 50.85588 -389.314944)
			(xy 50.856134 -389.315452) (xy 50.856388 -389.315452) (xy 50.857658 -389.317992) (xy 50.869894 -389.340914)
			(xy 50.887212 -389.389901) (xy 50.895999 -389.441111) (xy 50.89652 -389.46709) (xy 50.89652 -389.467344)
			(xy 50.896078 -389.491336) (xy 50.888566 -389.538728) (xy 50.873733 -389.584362) (xy 50.851945 -389.627113)
			(xy 50.823738 -389.665931) (xy 50.789807 -389.699859) (xy 50.750986 -389.728062) (xy 50.708232 -389.749845)
			(xy 50.662597 -389.764673) (xy 50.615204 -389.772181) (xy 50.591212 -389.772652) (xy 50.567548 -389.772203)
			(xy 50.520787 -389.764894) (xy 50.475712 -389.750465) (xy 50.4334 -389.72926) (xy 50.394862 -389.701787)
			(xy 50.361019 -389.668702) (xy 50.33268 -389.630795) (xy 50.32121 -389.610092) (xy 50.320956 -389.60933)
			(xy 49.9237 -388.922006) (xy 49.911491 -388.898735) (xy 49.894377 -388.849053) (xy 49.889664 -388.8232)
			(xy 49.886113 -388.799403) (xy 49.885901 -388.751287) (xy 49.330245 -388.751287) (xy 49.655984 -389.314944)
			(xy 49.656238 -389.315452) (xy 49.656492 -389.315452) (xy 49.657762 -389.317992) (xy 49.669999 -389.340914)
			(xy 49.687316 -389.389901) (xy 49.696103 -389.441111) (xy 49.696624 -389.46709) (xy 49.696624 -389.467344)
			(xy 49.696178 -389.491336) (xy 49.688666 -389.538727) (xy 49.673833 -389.584361) (xy 49.652046 -389.627112)
			(xy 49.623839 -389.66593) (xy 49.589908 -389.699858) (xy 49.551088 -389.72806) (xy 49.508335 -389.749844)
			(xy 49.4627 -389.764672) (xy 49.415308 -389.77218) (xy 49.391316 -389.772652) (xy 49.367652 -389.7722)
			(xy 49.320892 -389.764892) (xy 49.275816 -389.750463) (xy 49.233504 -389.729259) (xy 49.194966 -389.701786)
			(xy 49.161123 -389.668701) (xy 49.132784 -389.630795) (xy 49.121314 -389.610092) (xy 49.12106 -389.60933)
			(xy 48.723804 -388.922006) (xy 48.711596 -388.898735) (xy 48.694481 -388.849053) (xy 48.689768 -388.8232)
			(xy 48.686228 -388.797975) (xy 48.15733 -388.797975) (xy 48.456088 -389.314944) (xy 48.456342 -389.315452)
			(xy 48.456596 -389.315452) (xy 48.457866 -389.317992) (xy 48.470103 -389.340914) (xy 48.48742 -389.389901)
			(xy 48.496207 -389.441111) (xy 48.496728 -389.46709) (xy 48.496728 -389.467344) (xy 48.496278 -389.491335)
			(xy 48.488766 -389.538727) (xy 48.473934 -389.58436) (xy 48.452147 -389.627111) (xy 48.423941 -389.665928)
			(xy 48.39001 -389.699856) (xy 48.351191 -389.728059) (xy 48.308437 -389.749843) (xy 48.262803 -389.764672)
			(xy 48.215411 -389.77218) (xy 48.19142 -389.772652) (xy 48.167756 -389.772196) (xy 48.120996 -389.764889)
			(xy 48.075921 -389.750461) (xy 48.033608 -389.729257) (xy 47.99507 -389.701785) (xy 47.961227 -389.668701)
			(xy 47.932888 -389.630795) (xy 47.921418 -389.610092) (xy 47.921164 -389.60933) (xy 47.523908 -388.922006)
			(xy 47.5117 -388.898735) (xy 47.494585 -388.849053) (xy 47.489872 -388.8232) (xy 47.486325 -388.797976)
			(xy 16.931816 -388.797976) (xy 19.609816 -391.475976) (xy 19.644106 -391.480548) (xy 19.658838 -391.471912)
			(xy 19.685972 -391.457099) (xy 19.744089 -391.436045) (xy 19.80497 -391.425346) (xy 19.835876 -391.424668)
			(xy 19.836384 -391.424668) (xy 19.864369 -391.425216) (xy 19.919649 -391.433969) (xy 19.97288 -391.451261)
			(xy 20.02275 -391.476668) (xy 20.068032 -391.509564) (xy 20.10761 -391.549138) (xy 20.140511 -391.594416)
			(xy 20.165923 -391.644283) (xy 20.183222 -391.697512) (xy 20.191981 -391.752791) (xy 20.192492 -391.780776)
			(xy 20.192492 -391.781284) (xy 20.191808 -391.812189) (xy 20.181099 -391.873067) (xy 20.160053 -391.931185)
			(xy 20.145248 -391.958322) (xy 20.136612 -391.973054) (xy 20.141184 -392.007344) (xy 21.426678 -393.292838)
			(xy 47.435008 -393.292838) (xy 47.435008 -392.429238) (xy 47.435494 -392.401987) (xy 47.44325 -392.348039)
			(xy 47.458605 -392.295744) (xy 47.481247 -392.246167) (xy 47.510713 -392.200317) (xy 47.546404 -392.159126)
			(xy 47.587595 -392.123435) (xy 47.633445 -392.093969) (xy 47.683022 -392.071327) (xy 47.735317 -392.055972)
			(xy 47.789265 -392.048216) (xy 47.843767 -392.048216) (xy 47.897715 -392.055972) (xy 47.95001 -392.071327)
			(xy 47.999587 -392.093969) (xy 48.045437 -392.123435) (xy 48.086628 -392.159126) (xy 48.122319 -392.200317)
			(xy 48.151785 -392.246167) (xy 48.174427 -392.295744) (xy 48.189782 -392.348039) (xy 48.197538 -392.401987)
			(xy 48.198024 -392.429238) (xy 48.198024 -393.292838) (xy 48.634904 -393.292838) (xy 48.634904 -392.429238)
			(xy 48.63539 -392.401987) (xy 48.643146 -392.348039) (xy 48.658501 -392.295744) (xy 48.681143 -392.246167)
			(xy 48.710609 -392.200317) (xy 48.7463 -392.159126) (xy 48.787491 -392.123435) (xy 48.833341 -392.093969)
			(xy 48.882918 -392.071327) (xy 48.935213 -392.055972) (xy 48.989161 -392.048216) (xy 49.043663 -392.048216)
			(xy 49.097611 -392.055972) (xy 49.149906 -392.071327) (xy 49.199483 -392.093969) (xy 49.245333 -392.123435)
			(xy 49.286524 -392.159126) (xy 49.322215 -392.200317) (xy 49.351681 -392.246167) (xy 49.374323 -392.295744)
			(xy 49.389678 -392.348039) (xy 49.397434 -392.401987) (xy 49.39792 -392.429238) (xy 49.39792 -393.292838)
			(xy 49.8348 -393.292838) (xy 49.8348 -392.429238) (xy 49.835286 -392.401969) (xy 49.843048 -392.347985)
			(xy 49.858413 -392.295655) (xy 49.88107 -392.246045) (xy 49.910556 -392.200164) (xy 49.946271 -392.158947)
			(xy 49.987488 -392.123232) (xy 50.033369 -392.093746) (xy 50.082979 -392.071089) (xy 50.135309 -392.055724)
			(xy 50.189293 -392.047962) (xy 50.243831 -392.047962) (xy 50.297815 -392.055724) (xy 50.350145 -392.071089)
			(xy 50.399755 -392.093746) (xy 50.445636 -392.123232) (xy 50.486853 -392.158947) (xy 50.522568 -392.200164)
			(xy 50.552054 -392.246045) (xy 50.574711 -392.295655) (xy 50.590076 -392.347985) (xy 50.597838 -392.401969)
			(xy 50.598324 -392.429238) (xy 50.598324 -393.292838) (xy 51.034696 -393.292838) (xy 51.034696 -392.429238)
			(xy 51.035182 -392.401969) (xy 51.042944 -392.347985) (xy 51.058309 -392.295655) (xy 51.080966 -392.246045)
			(xy 51.110452 -392.200164) (xy 51.146167 -392.158947) (xy 51.187384 -392.123232) (xy 51.233265 -392.093746)
			(xy 51.282875 -392.071089) (xy 51.335205 -392.055724) (xy 51.389189 -392.047962) (xy 51.443727 -392.047962)
			(xy 51.497711 -392.055724) (xy 51.550041 -392.071089) (xy 51.599651 -392.093746) (xy 51.645532 -392.123232)
			(xy 51.686749 -392.158947) (xy 51.722464 -392.200164) (xy 51.75195 -392.246045) (xy 51.774607 -392.295655)
			(xy 51.789972 -392.347985) (xy 51.797734 -392.401969) (xy 51.79822 -392.429238) (xy 51.79822 -393.292838)
			(xy 52.2351 -393.292838) (xy 52.2351 -392.429238) (xy 52.235586 -392.401987) (xy 52.243342 -392.348039)
			(xy 52.258697 -392.295744) (xy 52.281339 -392.246167) (xy 52.310805 -392.200317) (xy 52.346496 -392.159126)
			(xy 52.387687 -392.123435) (xy 52.433537 -392.093969) (xy 52.483114 -392.071327) (xy 52.535409 -392.055972)
			(xy 52.589357 -392.048216) (xy 52.643859 -392.048216) (xy 52.697807 -392.055972) (xy 52.750102 -392.071327)
			(xy 52.799679 -392.093969) (xy 52.845529 -392.123435) (xy 52.88672 -392.159126) (xy 52.922411 -392.200317)
			(xy 52.951877 -392.246167) (xy 52.974519 -392.295744) (xy 52.989874 -392.348039) (xy 52.99763 -392.401987)
			(xy 52.998116 -392.429238) (xy 52.998116 -393.292838) (xy 53.434996 -393.292838) (xy 53.434996 -392.429238)
			(xy 53.435482 -392.401987) (xy 53.443238 -392.348039) (xy 53.458593 -392.295744) (xy 53.481235 -392.246167)
			(xy 53.510701 -392.200317) (xy 53.546392 -392.159126) (xy 53.587583 -392.123435) (xy 53.633433 -392.093969)
			(xy 53.68301 -392.071327) (xy 53.735305 -392.055972) (xy 53.789253 -392.048216) (xy 53.843755 -392.048216)
			(xy 53.897703 -392.055972) (xy 53.949998 -392.071327) (xy 53.999575 -392.093969) (xy 54.045425 -392.123435)
			(xy 54.086616 -392.159126) (xy 54.122307 -392.200317) (xy 54.151773 -392.246167) (xy 54.174415 -392.295744)
			(xy 54.18977 -392.348039) (xy 54.197526 -392.401987) (xy 54.198012 -392.429238) (xy 54.198012 -393.292838)
			(xy 54.634892 -393.292838) (xy 54.634892 -392.429238) (xy 54.635378 -392.401969) (xy 54.64314 -392.347985)
			(xy 54.658505 -392.295655) (xy 54.681162 -392.246045) (xy 54.710648 -392.200164) (xy 54.746363 -392.158947)
			(xy 54.78758 -392.123232) (xy 54.833461 -392.093746) (xy 54.883071 -392.071089) (xy 54.935401 -392.055724)
			(xy 54.989385 -392.047962) (xy 55.043923 -392.047962) (xy 55.097907 -392.055724) (xy 55.150237 -392.071089)
			(xy 55.199847 -392.093746) (xy 55.245728 -392.123232) (xy 55.286945 -392.158947) (xy 55.32266 -392.200164)
			(xy 55.352146 -392.246045) (xy 55.374803 -392.295655) (xy 55.390168 -392.347985) (xy 55.39793 -392.401969)
			(xy 55.398416 -392.429238) (xy 55.398416 -393.292838) (xy 55.834788 -393.292838) (xy 55.834788 -392.429238)
			(xy 55.835274 -392.401969) (xy 55.843036 -392.347985) (xy 55.858401 -392.295655) (xy 55.881058 -392.246045)
			(xy 55.910544 -392.200164) (xy 55.946259 -392.158947) (xy 55.987476 -392.123232) (xy 56.033357 -392.093746)
			(xy 56.082967 -392.071089) (xy 56.135297 -392.055724) (xy 56.189281 -392.047962) (xy 56.243819 -392.047962)
			(xy 56.297803 -392.055724) (xy 56.350133 -392.071089) (xy 56.399743 -392.093746) (xy 56.445624 -392.123232)
			(xy 56.486841 -392.158947) (xy 56.522556 -392.200164) (xy 56.552042 -392.246045) (xy 56.574699 -392.295655)
			(xy 56.590064 -392.347985) (xy 56.597826 -392.401969) (xy 56.598312 -392.429238) (xy 56.598312 -393.292838)
			(xy 57.035192 -393.292838) (xy 57.035192 -392.429238) (xy 57.035678 -392.401987) (xy 57.043434 -392.348039)
			(xy 57.058789 -392.295744) (xy 57.081431 -392.246167) (xy 57.110897 -392.200317) (xy 57.146588 -392.159126)
			(xy 57.187779 -392.123435) (xy 57.233629 -392.093969) (xy 57.283206 -392.071327) (xy 57.335501 -392.055972)
			(xy 57.389449 -392.048216) (xy 57.443951 -392.048216) (xy 57.497899 -392.055972) (xy 57.550194 -392.071327)
			(xy 57.599771 -392.093969) (xy 57.645621 -392.123435) (xy 57.686812 -392.159126) (xy 57.722503 -392.200317)
			(xy 57.751969 -392.246167) (xy 57.774611 -392.295744) (xy 57.789966 -392.348039) (xy 57.797722 -392.401987)
			(xy 57.798208 -392.429238) (xy 57.798208 -393.292838) (xy 58.235088 -393.292838) (xy 58.235088 -392.429238)
			(xy 58.235574 -392.401987) (xy 58.24333 -392.348039) (xy 58.258685 -392.295744) (xy 58.281327 -392.246167)
			(xy 58.310793 -392.200317) (xy 58.346484 -392.159126) (xy 58.387675 -392.123435) (xy 58.433525 -392.093969)
			(xy 58.483102 -392.071327) (xy 58.535397 -392.055972) (xy 58.589345 -392.048216) (xy 58.643847 -392.048216)
			(xy 58.697795 -392.055972) (xy 58.75009 -392.071327) (xy 58.799667 -392.093969) (xy 58.845517 -392.123435)
			(xy 58.886708 -392.159126) (xy 58.922399 -392.200317) (xy 58.951865 -392.246167) (xy 58.974507 -392.295744)
			(xy 58.989862 -392.348039) (xy 58.997618 -392.401987) (xy 58.998104 -392.429238) (xy 58.998104 -393.292838)
			(xy 59.434984 -393.292838) (xy 59.434984 -392.429238) (xy 59.43547 -392.401969) (xy 59.443232 -392.347985)
			(xy 59.458597 -392.295655) (xy 59.481254 -392.246045) (xy 59.51074 -392.200164) (xy 59.546455 -392.158947)
			(xy 59.587672 -392.123232) (xy 59.633553 -392.093746) (xy 59.683163 -392.071089) (xy 59.735493 -392.055724)
			(xy 59.789477 -392.047962) (xy 59.844015 -392.047962) (xy 59.897999 -392.055724) (xy 59.950329 -392.071089)
			(xy 59.999939 -392.093746) (xy 60.04582 -392.123232) (xy 60.087037 -392.158947) (xy 60.122752 -392.200164)
			(xy 60.152238 -392.246045) (xy 60.174895 -392.295655) (xy 60.19026 -392.347985) (xy 60.198022 -392.401969)
			(xy 60.198508 -392.429238) (xy 60.198508 -393.292838) (xy 60.63488 -393.292838) (xy 60.63488 -392.429238)
			(xy 60.635366 -392.401969) (xy 60.643128 -392.347985) (xy 60.658493 -392.295655) (xy 60.68115 -392.246045)
			(xy 60.710636 -392.200164) (xy 60.746351 -392.158947) (xy 60.787568 -392.123232) (xy 60.833449 -392.093746)
			(xy 60.883059 -392.071089) (xy 60.935389 -392.055724) (xy 60.989373 -392.047962) (xy 61.043911 -392.047962)
			(xy 61.097895 -392.055724) (xy 61.150225 -392.071089) (xy 61.199835 -392.093746) (xy 61.245716 -392.123232)
			(xy 61.286933 -392.158947) (xy 61.322648 -392.200164) (xy 61.352134 -392.246045) (xy 61.374791 -392.295655)
			(xy 61.390156 -392.347985) (xy 61.397918 -392.401969) (xy 61.398404 -392.429238) (xy 61.398404 -393.292838)
			(xy 61.834776 -393.292838) (xy 61.834776 -392.429238) (xy 61.835262 -392.401969) (xy 61.843024 -392.347985)
			(xy 61.858389 -392.295655) (xy 61.881046 -392.246045) (xy 61.910532 -392.200164) (xy 61.946247 -392.158947)
			(xy 61.987464 -392.123232) (xy 62.033345 -392.093746) (xy 62.082955 -392.071089) (xy 62.135285 -392.055724)
			(xy 62.189269 -392.047962) (xy 62.243807 -392.047962) (xy 62.297791 -392.055724) (xy 62.350121 -392.071089)
			(xy 62.399731 -392.093746) (xy 62.445612 -392.123232) (xy 62.486829 -392.158947) (xy 62.522544 -392.200164)
			(xy 62.55203 -392.246045) (xy 62.574687 -392.295655) (xy 62.590052 -392.347985) (xy 62.597814 -392.401969)
			(xy 62.5983 -392.429238) (xy 62.5983 -393.292838) (xy 63.034672 -393.292838) (xy 63.034672 -392.429238)
			(xy 63.035158 -392.401969) (xy 63.04292 -392.347985) (xy 63.058285 -392.295655) (xy 63.080942 -392.246045)
			(xy 63.110428 -392.200164) (xy 63.146143 -392.158947) (xy 63.18736 -392.123232) (xy 63.233241 -392.093746)
			(xy 63.282851 -392.071089) (xy 63.335181 -392.055724) (xy 63.389165 -392.047962) (xy 63.443703 -392.047962)
			(xy 63.497687 -392.055724) (xy 63.550017 -392.071089) (xy 63.599627 -392.093746) (xy 63.645508 -392.123232)
			(xy 63.686725 -392.158947) (xy 63.72244 -392.200164) (xy 63.751926 -392.246045) (xy 63.774583 -392.295655)
			(xy 63.789948 -392.347985) (xy 63.79771 -392.401969) (xy 63.798196 -392.429238) (xy 63.798196 -393.292838)
			(xy 64.235076 -393.292838) (xy 64.235076 -392.429238) (xy 64.235562 -392.401987) (xy 64.243318 -392.348039)
			(xy 64.258673 -392.295744) (xy 64.281315 -392.246167) (xy 64.310781 -392.200317) (xy 64.346472 -392.159126)
			(xy 64.387663 -392.123435) (xy 64.433513 -392.093969) (xy 64.48309 -392.071327) (xy 64.535385 -392.055972)
			(xy 64.589333 -392.048216) (xy 64.643835 -392.048216) (xy 64.697783 -392.055972) (xy 64.750078 -392.071327)
			(xy 64.799655 -392.093969) (xy 64.845505 -392.123435) (xy 64.886696 -392.159126) (xy 64.922387 -392.200317)
			(xy 64.951853 -392.246167) (xy 64.974495 -392.295744) (xy 64.98985 -392.348039) (xy 64.997606 -392.401987)
			(xy 64.998092 -392.429238) (xy 64.998092 -393.292838) (xy 65.434972 -393.292838) (xy 65.434972 -392.429238)
			(xy 65.435458 -392.401987) (xy 65.443214 -392.348039) (xy 65.458569 -392.295744) (xy 65.481211 -392.246167)
			(xy 65.510677 -392.200317) (xy 65.546368 -392.159126) (xy 65.587559 -392.123435) (xy 65.633409 -392.093969)
			(xy 65.682986 -392.071327) (xy 65.735281 -392.055972) (xy 65.789229 -392.048216) (xy 65.843731 -392.048216)
			(xy 65.897679 -392.055972) (xy 65.949974 -392.071327) (xy 65.999551 -392.093969) (xy 66.045401 -392.123435)
			(xy 66.086592 -392.159126) (xy 66.122283 -392.200317) (xy 66.151749 -392.246167) (xy 66.174391 -392.295744)
			(xy 66.189746 -392.348039) (xy 66.197502 -392.401987) (xy 66.197988 -392.429238) (xy 66.197988 -393.292838)
			(xy 79.962756 -393.292838) (xy 79.962756 -392.429238) (xy 79.963242 -392.401987) (xy 79.970998 -392.348039)
			(xy 79.986353 -392.295744) (xy 80.008995 -392.246167) (xy 80.038461 -392.200317) (xy 80.074152 -392.159126)
			(xy 80.115343 -392.123435) (xy 80.161193 -392.093969) (xy 80.21077 -392.071327) (xy 80.263065 -392.055972)
			(xy 80.317013 -392.048216) (xy 80.371515 -392.048216) (xy 80.425463 -392.055972) (xy 80.477758 -392.071327)
			(xy 80.527335 -392.093969) (xy 80.573185 -392.123435) (xy 80.614376 -392.159126) (xy 80.650067 -392.200317)
			(xy 80.679533 -392.246167) (xy 80.702175 -392.295744) (xy 80.71753 -392.348039) (xy 80.725286 -392.401987)
			(xy 80.725772 -392.429238) (xy 80.725772 -393.292838) (xy 81.162652 -393.292838) (xy 81.162652 -392.429238)
			(xy 81.163138 -392.401987) (xy 81.170894 -392.348039) (xy 81.186249 -392.295744) (xy 81.208891 -392.246167)
			(xy 81.238357 -392.200317) (xy 81.274048 -392.159126) (xy 81.315239 -392.123435) (xy 81.361089 -392.093969)
			(xy 81.410666 -392.071327) (xy 81.462961 -392.055972) (xy 81.516909 -392.048216) (xy 81.571411 -392.048216)
			(xy 81.625359 -392.055972) (xy 81.677654 -392.071327) (xy 81.727231 -392.093969) (xy 81.773081 -392.123435)
			(xy 81.814272 -392.159126) (xy 81.849963 -392.200317) (xy 81.879429 -392.246167) (xy 81.902071 -392.295744)
			(xy 81.917426 -392.348039) (xy 81.925182 -392.401987) (xy 81.925668 -392.429238) (xy 81.925668 -393.292838)
			(xy 82.362548 -393.292838) (xy 82.362548 -392.429238) (xy 82.363034 -392.401969) (xy 82.370796 -392.347985)
			(xy 82.386161 -392.295655) (xy 82.408818 -392.246045) (xy 82.438304 -392.200164) (xy 82.474019 -392.158947)
			(xy 82.515236 -392.123232) (xy 82.561117 -392.093746) (xy 82.610727 -392.071089) (xy 82.663057 -392.055724)
			(xy 82.717041 -392.047962) (xy 82.771579 -392.047962) (xy 82.825563 -392.055724) (xy 82.877893 -392.071089)
			(xy 82.927503 -392.093746) (xy 82.973384 -392.123232) (xy 83.014601 -392.158947) (xy 83.050316 -392.200164)
			(xy 83.079802 -392.246045) (xy 83.102459 -392.295655) (xy 83.117824 -392.347985) (xy 83.125586 -392.401969)
			(xy 83.126072 -392.429238) (xy 83.126072 -393.292838) (xy 83.562444 -393.292838) (xy 83.562444 -392.429238)
			(xy 83.56293 -392.401969) (xy 83.570692 -392.347985) (xy 83.586057 -392.295655) (xy 83.608714 -392.246045)
			(xy 83.6382 -392.200164) (xy 83.673915 -392.158947) (xy 83.715132 -392.123232) (xy 83.761013 -392.093746)
			(xy 83.810623 -392.071089) (xy 83.862953 -392.055724) (xy 83.916937 -392.047962) (xy 83.971475 -392.047962)
			(xy 84.025459 -392.055724) (xy 84.077789 -392.071089) (xy 84.127399 -392.093746) (xy 84.17328 -392.123232)
			(xy 84.214497 -392.158947) (xy 84.250212 -392.200164) (xy 84.279698 -392.246045) (xy 84.302355 -392.295655)
			(xy 84.31772 -392.347985) (xy 84.325482 -392.401969) (xy 84.325968 -392.429238) (xy 84.325968 -393.292838)
			(xy 84.762848 -393.292838) (xy 84.762848 -392.429238) (xy 84.763334 -392.401987) (xy 84.77109 -392.348039)
			(xy 84.786445 -392.295744) (xy 84.809087 -392.246167) (xy 84.838553 -392.200317) (xy 84.874244 -392.159126)
			(xy 84.915435 -392.123435) (xy 84.961285 -392.093969) (xy 85.010862 -392.071327) (xy 85.063157 -392.055972)
			(xy 85.117105 -392.048216) (xy 85.171607 -392.048216) (xy 85.225555 -392.055972) (xy 85.27785 -392.071327)
			(xy 85.327427 -392.093969) (xy 85.373277 -392.123435) (xy 85.414468 -392.159126) (xy 85.450159 -392.200317)
			(xy 85.479625 -392.246167) (xy 85.502267 -392.295744) (xy 85.517622 -392.348039) (xy 85.525378 -392.401987)
			(xy 85.525864 -392.429238) (xy 85.525864 -393.292838) (xy 85.962744 -393.292838) (xy 85.962744 -392.429238)
			(xy 85.96323 -392.401987) (xy 85.970986 -392.348039) (xy 85.986341 -392.295744) (xy 86.008983 -392.246167)
			(xy 86.038449 -392.200317) (xy 86.07414 -392.159126) (xy 86.115331 -392.123435) (xy 86.161181 -392.093969)
			(xy 86.210758 -392.071327) (xy 86.263053 -392.055972) (xy 86.317001 -392.048216) (xy 86.371503 -392.048216)
			(xy 86.425451 -392.055972) (xy 86.477746 -392.071327) (xy 86.527323 -392.093969) (xy 86.573173 -392.123435)
			(xy 86.614364 -392.159126) (xy 86.650055 -392.200317) (xy 86.679521 -392.246167) (xy 86.702163 -392.295744)
			(xy 86.717518 -392.348039) (xy 86.725274 -392.401987) (xy 86.72576 -392.429238) (xy 86.72576 -393.292838)
			(xy 87.16264 -393.292838) (xy 87.16264 -392.429238) (xy 87.163126 -392.401969) (xy 87.170888 -392.347985)
			(xy 87.186253 -392.295655) (xy 87.20891 -392.246045) (xy 87.238396 -392.200164) (xy 87.274111 -392.158947)
			(xy 87.315328 -392.123232) (xy 87.361209 -392.093746) (xy 87.410819 -392.071089) (xy 87.463149 -392.055724)
			(xy 87.517133 -392.047962) (xy 87.571671 -392.047962) (xy 87.625655 -392.055724) (xy 87.677985 -392.071089)
			(xy 87.727595 -392.093746) (xy 87.773476 -392.123232) (xy 87.814693 -392.158947) (xy 87.850408 -392.200164)
			(xy 87.879894 -392.246045) (xy 87.902551 -392.295655) (xy 87.917916 -392.347985) (xy 87.925678 -392.401969)
			(xy 87.926164 -392.429238) (xy 87.926164 -393.292838) (xy 88.362536 -393.292838) (xy 88.362536 -392.429238)
			(xy 88.363022 -392.401969) (xy 88.370784 -392.347985) (xy 88.386149 -392.295655) (xy 88.408806 -392.246045)
			(xy 88.438292 -392.200164) (xy 88.474007 -392.158947) (xy 88.515224 -392.123232) (xy 88.561105 -392.093746)
			(xy 88.610715 -392.071089) (xy 88.663045 -392.055724) (xy 88.717029 -392.047962) (xy 88.771567 -392.047962)
			(xy 88.825551 -392.055724) (xy 88.877881 -392.071089) (xy 88.927491 -392.093746) (xy 88.973372 -392.123232)
			(xy 89.014589 -392.158947) (xy 89.050304 -392.200164) (xy 89.07979 -392.246045) (xy 89.102447 -392.295655)
			(xy 89.117812 -392.347985) (xy 89.125574 -392.401969) (xy 89.12606 -392.429238) (xy 89.12606 -393.292838)
			(xy 89.56294 -393.292838) (xy 89.56294 -392.429238) (xy 89.563426 -392.401987) (xy 89.571182 -392.348039)
			(xy 89.586537 -392.295744) (xy 89.609179 -392.246167) (xy 89.638645 -392.200317) (xy 89.674336 -392.159126)
			(xy 89.715527 -392.123435) (xy 89.761377 -392.093969) (xy 89.810954 -392.071327) (xy 89.863249 -392.055972)
			(xy 89.917197 -392.048216) (xy 89.971699 -392.048216) (xy 90.025647 -392.055972) (xy 90.077942 -392.071327)
			(xy 90.127519 -392.093969) (xy 90.173369 -392.123435) (xy 90.21456 -392.159126) (xy 90.250251 -392.200317)
			(xy 90.279717 -392.246167) (xy 90.302359 -392.295744) (xy 90.317714 -392.348039) (xy 90.32547 -392.401987)
			(xy 90.325956 -392.429238) (xy 90.325956 -393.292838) (xy 90.762836 -393.292838) (xy 90.762836 -392.429238)
			(xy 90.763322 -392.401987) (xy 90.771078 -392.348039) (xy 90.786433 -392.295744) (xy 90.809075 -392.246167)
			(xy 90.838541 -392.200317) (xy 90.874232 -392.159126) (xy 90.915423 -392.123435) (xy 90.961273 -392.093969)
			(xy 91.01085 -392.071327) (xy 91.063145 -392.055972) (xy 91.117093 -392.048216) (xy 91.171595 -392.048216)
			(xy 91.225543 -392.055972) (xy 91.277838 -392.071327) (xy 91.327415 -392.093969) (xy 91.373265 -392.123435)
			(xy 91.414456 -392.159126) (xy 91.450147 -392.200317) (xy 91.479613 -392.246167) (xy 91.502255 -392.295744)
			(xy 91.51761 -392.348039) (xy 91.525366 -392.401987) (xy 91.525852 -392.429238) (xy 91.525852 -393.292838)
			(xy 91.962732 -393.292838) (xy 91.962732 -392.429238) (xy 91.963218 -392.401969) (xy 91.97098 -392.347985)
			(xy 91.986345 -392.295655) (xy 92.009002 -392.246045) (xy 92.038488 -392.200164) (xy 92.074203 -392.158947)
			(xy 92.11542 -392.123232) (xy 92.161301 -392.093746) (xy 92.210911 -392.071089) (xy 92.263241 -392.055724)
			(xy 92.317225 -392.047962) (xy 92.371763 -392.047962) (xy 92.425747 -392.055724) (xy 92.478077 -392.071089)
			(xy 92.527687 -392.093746) (xy 92.573568 -392.123232) (xy 92.614785 -392.158947) (xy 92.6505 -392.200164)
			(xy 92.679986 -392.246045) (xy 92.702643 -392.295655) (xy 92.718008 -392.347985) (xy 92.72577 -392.401969)
			(xy 92.726256 -392.429238) (xy 92.726256 -393.292838) (xy 93.162628 -393.292838) (xy 93.162628 -392.429238)
			(xy 93.163114 -392.401969) (xy 93.170876 -392.347985) (xy 93.186241 -392.295655) (xy 93.208898 -392.246045)
			(xy 93.238384 -392.200164) (xy 93.274099 -392.158947) (xy 93.315316 -392.123232) (xy 93.361197 -392.093746)
			(xy 93.410807 -392.071089) (xy 93.463137 -392.055724) (xy 93.517121 -392.047962) (xy 93.571659 -392.047962)
			(xy 93.625643 -392.055724) (xy 93.677973 -392.071089) (xy 93.727583 -392.093746) (xy 93.773464 -392.123232)
			(xy 93.814681 -392.158947) (xy 93.850396 -392.200164) (xy 93.879882 -392.246045) (xy 93.902539 -392.295655)
			(xy 93.917904 -392.347985) (xy 93.925666 -392.401969) (xy 93.926152 -392.429238) (xy 93.926152 -393.292838)
			(xy 94.362524 -393.292838) (xy 94.362524 -392.429238) (xy 94.36301 -392.401969) (xy 94.370772 -392.347985)
			(xy 94.386137 -392.295655) (xy 94.408794 -392.246045) (xy 94.43828 -392.200164) (xy 94.473995 -392.158947)
			(xy 94.515212 -392.123232) (xy 94.561093 -392.093746) (xy 94.610703 -392.071089) (xy 94.663033 -392.055724)
			(xy 94.717017 -392.047962) (xy 94.771555 -392.047962) (xy 94.825539 -392.055724) (xy 94.877869 -392.071089)
			(xy 94.927479 -392.093746) (xy 94.97336 -392.123232) (xy 95.014577 -392.158947) (xy 95.050292 -392.200164)
			(xy 95.079778 -392.246045) (xy 95.102435 -392.295655) (xy 95.1178 -392.347985) (xy 95.125562 -392.401969)
			(xy 95.126048 -392.429238) (xy 95.126048 -393.292838) (xy 95.56242 -393.292838) (xy 95.56242 -392.429238)
			(xy 95.562906 -392.401969) (xy 95.570668 -392.347985) (xy 95.586033 -392.295655) (xy 95.60869 -392.246045)
			(xy 95.638176 -392.200164) (xy 95.673891 -392.158947) (xy 95.715108 -392.123232) (xy 95.760989 -392.093746)
			(xy 95.810599 -392.071089) (xy 95.862929 -392.055724) (xy 95.916913 -392.047962) (xy 95.971451 -392.047962)
			(xy 96.025435 -392.055724) (xy 96.077765 -392.071089) (xy 96.127375 -392.093746) (xy 96.173256 -392.123232)
			(xy 96.214473 -392.158947) (xy 96.250188 -392.200164) (xy 96.279674 -392.246045) (xy 96.302331 -392.295655)
			(xy 96.317696 -392.347985) (xy 96.325458 -392.401969) (xy 96.325944 -392.429238) (xy 96.325944 -393.292838)
			(xy 96.762824 -393.292838) (xy 96.762824 -392.429238) (xy 96.76331 -392.401987) (xy 96.771066 -392.348039)
			(xy 96.786421 -392.295744) (xy 96.809063 -392.246167) (xy 96.838529 -392.200317) (xy 96.87422 -392.159126)
			(xy 96.915411 -392.123435) (xy 96.961261 -392.093969) (xy 97.010838 -392.071327) (xy 97.063133 -392.055972)
			(xy 97.117081 -392.048216) (xy 97.171583 -392.048216) (xy 97.225531 -392.055972) (xy 97.277826 -392.071327)
			(xy 97.327403 -392.093969) (xy 97.373253 -392.123435) (xy 97.414444 -392.159126) (xy 97.450135 -392.200317)
			(xy 97.479601 -392.246167) (xy 97.502243 -392.295744) (xy 97.517598 -392.348039) (xy 97.525354 -392.401987)
			(xy 97.52584 -392.429238) (xy 97.52584 -393.292838) (xy 97.96272 -393.292838) (xy 97.96272 -392.429238)
			(xy 97.963206 -392.401987) (xy 97.970962 -392.348039) (xy 97.986317 -392.295744) (xy 98.008959 -392.246167)
			(xy 98.038425 -392.200317) (xy 98.074116 -392.159126) (xy 98.115307 -392.123435) (xy 98.161157 -392.093969)
			(xy 98.210734 -392.071327) (xy 98.263029 -392.055972) (xy 98.316977 -392.048216) (xy 98.371479 -392.048216)
			(xy 98.425427 -392.055972) (xy 98.477722 -392.071327) (xy 98.527299 -392.093969) (xy 98.573149 -392.123435)
			(xy 98.61434 -392.159126) (xy 98.650031 -392.200317) (xy 98.679497 -392.246167) (xy 98.702139 -392.295744)
			(xy 98.717494 -392.348039) (xy 98.72525 -392.401987) (xy 98.725736 -392.429238) (xy 98.725736 -393.292838)
			(xy 114.534696 -393.292838) (xy 114.534696 -392.429238) (xy 114.535182 -392.401969) (xy 114.542944 -392.347985)
			(xy 114.558309 -392.295655) (xy 114.580966 -392.246045) (xy 114.610452 -392.200164) (xy 114.646167 -392.158947)
			(xy 114.687384 -392.123232) (xy 114.733265 -392.093746) (xy 114.782875 -392.071089) (xy 114.835205 -392.055724)
			(xy 114.889189 -392.047962) (xy 114.943727 -392.047962) (xy 114.997711 -392.055724) (xy 115.050041 -392.071089)
			(xy 115.099651 -392.093746) (xy 115.145532 -392.123232) (xy 115.186749 -392.158947) (xy 115.222464 -392.200164)
			(xy 115.25195 -392.246045) (xy 115.274607 -392.295655) (xy 115.289972 -392.347985) (xy 115.297734 -392.401969)
			(xy 115.29822 -392.429238) (xy 115.29822 -393.292838) (xy 115.734592 -393.292838) (xy 115.734592 -392.429238)
			(xy 115.735078 -392.401969) (xy 115.74284 -392.347985) (xy 115.758205 -392.295655) (xy 115.780862 -392.246045)
			(xy 115.810348 -392.200164) (xy 115.846063 -392.158947) (xy 115.88728 -392.123232) (xy 115.933161 -392.093746)
			(xy 115.982771 -392.071089) (xy 116.035101 -392.055724) (xy 116.089085 -392.047962) (xy 116.143623 -392.047962)
			(xy 116.197607 -392.055724) (xy 116.249937 -392.071089) (xy 116.299547 -392.093746) (xy 116.345428 -392.123232)
			(xy 116.386645 -392.158947) (xy 116.42236 -392.200164) (xy 116.451846 -392.246045) (xy 116.474503 -392.295655)
			(xy 116.489868 -392.347985) (xy 116.49763 -392.401969) (xy 116.498116 -392.429238) (xy 116.498116 -393.292838)
			(xy 116.934996 -393.292838) (xy 116.934996 -392.429238) (xy 116.935482 -392.401987) (xy 116.943238 -392.348039)
			(xy 116.958593 -392.295744) (xy 116.981235 -392.246167) (xy 117.010701 -392.200317) (xy 117.046392 -392.159126)
			(xy 117.087583 -392.123435) (xy 117.133433 -392.093969) (xy 117.18301 -392.071327) (xy 117.235305 -392.055972)
			(xy 117.289253 -392.048216) (xy 117.343755 -392.048216) (xy 117.397703 -392.055972) (xy 117.449998 -392.071327)
			(xy 117.499575 -392.093969) (xy 117.545425 -392.123435) (xy 117.586616 -392.159126) (xy 117.622307 -392.200317)
			(xy 117.651773 -392.246167) (xy 117.674415 -392.295744) (xy 117.68977 -392.348039) (xy 117.697526 -392.401987)
			(xy 117.698012 -392.429238) (xy 117.698012 -393.292838) (xy 118.134892 -393.292838) (xy 118.134892 -392.429238)
			(xy 118.135378 -392.401987) (xy 118.143134 -392.348039) (xy 118.158489 -392.295744) (xy 118.181131 -392.246167)
			(xy 118.210597 -392.200317) (xy 118.246288 -392.159126) (xy 118.287479 -392.123435) (xy 118.333329 -392.093969)
			(xy 118.382906 -392.071327) (xy 118.435201 -392.055972) (xy 118.489149 -392.048216) (xy 118.543651 -392.048216)
			(xy 118.597599 -392.055972) (xy 118.649894 -392.071327) (xy 118.699471 -392.093969) (xy 118.745321 -392.123435)
			(xy 118.786512 -392.159126) (xy 118.822203 -392.200317) (xy 118.851669 -392.246167) (xy 118.874311 -392.295744)
			(xy 118.889666 -392.348039) (xy 118.897422 -392.401987) (xy 118.897908 -392.429238) (xy 118.897908 -393.292838)
			(xy 119.334788 -393.292838) (xy 119.334788 -392.429238) (xy 119.335274 -392.401969) (xy 119.343036 -392.347985)
			(xy 119.358401 -392.295655) (xy 119.381058 -392.246045) (xy 119.410544 -392.200164) (xy 119.446259 -392.158947)
			(xy 119.487476 -392.123232) (xy 119.533357 -392.093746) (xy 119.582967 -392.071089) (xy 119.635297 -392.055724)
			(xy 119.689281 -392.047962) (xy 119.743819 -392.047962) (xy 119.797803 -392.055724) (xy 119.850133 -392.071089)
			(xy 119.899743 -392.093746) (xy 119.945624 -392.123232) (xy 119.986841 -392.158947) (xy 120.022556 -392.200164)
			(xy 120.052042 -392.246045) (xy 120.074699 -392.295655) (xy 120.090064 -392.347985) (xy 120.097826 -392.401969)
			(xy 120.098312 -392.429238) (xy 120.098312 -393.292838) (xy 120.534684 -393.292838) (xy 120.534684 -392.429238)
			(xy 120.53517 -392.401969) (xy 120.542932 -392.347985) (xy 120.558297 -392.295655) (xy 120.580954 -392.246045)
			(xy 120.61044 -392.200164) (xy 120.646155 -392.158947) (xy 120.687372 -392.123232) (xy 120.733253 -392.093746)
			(xy 120.782863 -392.071089) (xy 120.835193 -392.055724) (xy 120.889177 -392.047962) (xy 120.943715 -392.047962)
			(xy 120.997699 -392.055724) (xy 121.050029 -392.071089) (xy 121.099639 -392.093746) (xy 121.14552 -392.123232)
			(xy 121.186737 -392.158947) (xy 121.222452 -392.200164) (xy 121.251938 -392.246045) (xy 121.274595 -392.295655)
			(xy 121.28996 -392.347985) (xy 121.297722 -392.401969) (xy 121.298208 -392.429238) (xy 121.298208 -393.292838)
			(xy 121.735088 -393.292838) (xy 121.735088 -392.429238) (xy 121.735574 -392.401987) (xy 121.74333 -392.348039)
			(xy 121.758685 -392.295744) (xy 121.781327 -392.246167) (xy 121.810793 -392.200317) (xy 121.846484 -392.159126)
			(xy 121.887675 -392.123435) (xy 121.933525 -392.093969) (xy 121.983102 -392.071327) (xy 122.035397 -392.055972)
			(xy 122.089345 -392.048216) (xy 122.143847 -392.048216) (xy 122.197795 -392.055972) (xy 122.25009 -392.071327)
			(xy 122.299667 -392.093969) (xy 122.345517 -392.123435) (xy 122.386708 -392.159126) (xy 122.422399 -392.200317)
			(xy 122.451865 -392.246167) (xy 122.474507 -392.295744) (xy 122.489862 -392.348039) (xy 122.497618 -392.401987)
			(xy 122.498104 -392.429238) (xy 122.498104 -393.292838) (xy 122.934984 -393.292838) (xy 122.934984 -392.429238)
			(xy 122.93547 -392.401987) (xy 122.943226 -392.348039) (xy 122.958581 -392.295744) (xy 122.981223 -392.246167)
			(xy 123.010689 -392.200317) (xy 123.04638 -392.159126) (xy 123.087571 -392.123435) (xy 123.133421 -392.093969)
			(xy 123.182998 -392.071327) (xy 123.235293 -392.055972) (xy 123.289241 -392.048216) (xy 123.343743 -392.048216)
			(xy 123.397691 -392.055972) (xy 123.449986 -392.071327) (xy 123.499563 -392.093969) (xy 123.545413 -392.123435)
			(xy 123.586604 -392.159126) (xy 123.622295 -392.200317) (xy 123.651761 -392.246167) (xy 123.674403 -392.295744)
			(xy 123.689758 -392.348039) (xy 123.697514 -392.401987) (xy 123.698 -392.429238) (xy 123.698 -393.292838)
			(xy 124.13488 -393.292838) (xy 124.13488 -392.429238) (xy 124.135366 -392.401969) (xy 124.143128 -392.347985)
			(xy 124.158493 -392.295655) (xy 124.18115 -392.246045) (xy 124.210636 -392.200164) (xy 124.246351 -392.158947)
			(xy 124.287568 -392.123232) (xy 124.333449 -392.093746) (xy 124.383059 -392.071089) (xy 124.435389 -392.055724)
			(xy 124.489373 -392.047962) (xy 124.543911 -392.047962) (xy 124.597895 -392.055724) (xy 124.650225 -392.071089)
			(xy 124.699835 -392.093746) (xy 124.745716 -392.123232) (xy 124.786933 -392.158947) (xy 124.822648 -392.200164)
			(xy 124.852134 -392.246045) (xy 124.874791 -392.295655) (xy 124.890156 -392.347985) (xy 124.897918 -392.401969)
			(xy 124.898404 -392.429238) (xy 124.898404 -393.292838) (xy 125.334776 -393.292838) (xy 125.334776 -392.429238)
			(xy 125.335262 -392.401969) (xy 125.343024 -392.347985) (xy 125.358389 -392.295655) (xy 125.381046 -392.246045)
			(xy 125.410532 -392.200164) (xy 125.446247 -392.158947) (xy 125.487464 -392.123232) (xy 125.533345 -392.093746)
			(xy 125.582955 -392.071089) (xy 125.635285 -392.055724) (xy 125.689269 -392.047962) (xy 125.743807 -392.047962)
			(xy 125.797791 -392.055724) (xy 125.850121 -392.071089) (xy 125.899731 -392.093746) (xy 125.945612 -392.123232)
			(xy 125.986829 -392.158947) (xy 126.022544 -392.200164) (xy 126.05203 -392.246045) (xy 126.074687 -392.295655)
			(xy 126.090052 -392.347985) (xy 126.097814 -392.401969) (xy 126.0983 -392.429238) (xy 126.0983 -393.292838)
			(xy 126.53518 -393.292838) (xy 126.53518 -392.429238) (xy 126.535666 -392.401987) (xy 126.543422 -392.348039)
			(xy 126.558777 -392.295744) (xy 126.581419 -392.246167) (xy 126.610885 -392.200317) (xy 126.646576 -392.159126)
			(xy 126.687767 -392.123435) (xy 126.733617 -392.093969) (xy 126.783194 -392.071327) (xy 126.835489 -392.055972)
			(xy 126.889437 -392.048216) (xy 126.943939 -392.048216) (xy 126.997887 -392.055972) (xy 127.050182 -392.071327)
			(xy 127.099759 -392.093969) (xy 127.145609 -392.123435) (xy 127.1868 -392.159126) (xy 127.222491 -392.200317)
			(xy 127.251957 -392.246167) (xy 127.274599 -392.295744) (xy 127.289954 -392.348039) (xy 127.29771 -392.401987)
			(xy 127.298196 -392.429238) (xy 127.298196 -393.292838) (xy 127.735076 -393.292838) (xy 127.735076 -392.429238)
			(xy 127.735562 -392.401987) (xy 127.743318 -392.348039) (xy 127.758673 -392.295744) (xy 127.781315 -392.246167)
			(xy 127.810781 -392.200317) (xy 127.846472 -392.159126) (xy 127.887663 -392.123435) (xy 127.933513 -392.093969)
			(xy 127.98309 -392.071327) (xy 128.035385 -392.055972) (xy 128.089333 -392.048216) (xy 128.143835 -392.048216)
			(xy 128.197783 -392.055972) (xy 128.250078 -392.071327) (xy 128.299655 -392.093969) (xy 128.345505 -392.123435)
			(xy 128.386696 -392.159126) (xy 128.422387 -392.200317) (xy 128.451853 -392.246167) (xy 128.474495 -392.295744)
			(xy 128.48985 -392.348039) (xy 128.497606 -392.401987) (xy 128.498092 -392.429238) (xy 128.498092 -393.292838)
			(xy 128.934972 -393.292838) (xy 128.934972 -392.429238) (xy 128.935458 -392.401987) (xy 128.943214 -392.348039)
			(xy 128.958569 -392.295744) (xy 128.981211 -392.246167) (xy 129.010677 -392.200317) (xy 129.046368 -392.159126)
			(xy 129.087559 -392.123435) (xy 129.133409 -392.093969) (xy 129.182986 -392.071327) (xy 129.235281 -392.055972)
			(xy 129.289229 -392.048216) (xy 129.343731 -392.048216) (xy 129.397679 -392.055972) (xy 129.449974 -392.071327)
			(xy 129.499551 -392.093969) (xy 129.545401 -392.123435) (xy 129.586592 -392.159126) (xy 129.622283 -392.200317)
			(xy 129.651749 -392.246167) (xy 129.674391 -392.295744) (xy 129.689746 -392.348039) (xy 129.697502 -392.401987)
			(xy 129.697988 -392.429238) (xy 129.697988 -393.292838) (xy 130.134868 -393.292838) (xy 130.134868 -392.429238)
			(xy 130.135354 -392.401987) (xy 130.14311 -392.348039) (xy 130.158465 -392.295744) (xy 130.181107 -392.246167)
			(xy 130.210573 -392.200317) (xy 130.246264 -392.159126) (xy 130.287455 -392.123435) (xy 130.333305 -392.093969)
			(xy 130.382882 -392.071327) (xy 130.435177 -392.055972) (xy 130.489125 -392.048216) (xy 130.543627 -392.048216)
			(xy 130.597575 -392.055972) (xy 130.64987 -392.071327) (xy 130.699447 -392.093969) (xy 130.745297 -392.123435)
			(xy 130.786488 -392.159126) (xy 130.822179 -392.200317) (xy 130.851645 -392.246167) (xy 130.874287 -392.295744)
			(xy 130.889642 -392.348039) (xy 130.897398 -392.401987) (xy 130.897884 -392.429238) (xy 130.897884 -393.292838)
			(xy 131.334764 -393.292838) (xy 131.334764 -392.429238) (xy 131.33525 -392.401969) (xy 131.343012 -392.347985)
			(xy 131.358377 -392.295655) (xy 131.381034 -392.246045) (xy 131.41052 -392.200164) (xy 131.446235 -392.158947)
			(xy 131.487452 -392.123232) (xy 131.533333 -392.093746) (xy 131.582943 -392.071089) (xy 131.635273 -392.055724)
			(xy 131.689257 -392.047962) (xy 131.743795 -392.047962) (xy 131.797779 -392.055724) (xy 131.850109 -392.071089)
			(xy 131.899719 -392.093746) (xy 131.9456 -392.123232) (xy 131.986817 -392.158947) (xy 132.022532 -392.200164)
			(xy 132.052018 -392.246045) (xy 132.074675 -392.295655) (xy 132.09004 -392.347985) (xy 132.097802 -392.401969)
			(xy 132.098288 -392.429238) (xy 132.098288 -393.292838) (xy 132.53466 -393.292838) (xy 132.53466 -392.429238)
			(xy 132.535146 -392.401969) (xy 132.542908 -392.347985) (xy 132.558273 -392.295655) (xy 132.58093 -392.246045)
			(xy 132.610416 -392.200164) (xy 132.646131 -392.158947) (xy 132.687348 -392.123232) (xy 132.733229 -392.093746)
			(xy 132.782839 -392.071089) (xy 132.835169 -392.055724) (xy 132.889153 -392.047962) (xy 132.943691 -392.047962)
			(xy 132.997675 -392.055724) (xy 133.050005 -392.071089) (xy 133.099615 -392.093746) (xy 133.145496 -392.123232)
			(xy 133.186713 -392.158947) (xy 133.222428 -392.200164) (xy 133.251914 -392.246045) (xy 133.274571 -392.295655)
			(xy 133.289936 -392.347985) (xy 133.297698 -392.401969) (xy 133.298184 -392.429238) (xy 133.298184 -393.292838)
			(xy 147.062444 -393.292838) (xy 147.062444 -392.429238) (xy 147.06293 -392.401969) (xy 147.070692 -392.347985)
			(xy 147.086057 -392.295655) (xy 147.108714 -392.246045) (xy 147.1382 -392.200164) (xy 147.173915 -392.158947)
			(xy 147.215132 -392.123232) (xy 147.261013 -392.093746) (xy 147.310623 -392.071089) (xy 147.362953 -392.055724)
			(xy 147.416937 -392.047962) (xy 147.471475 -392.047962) (xy 147.525459 -392.055724) (xy 147.577789 -392.071089)
			(xy 147.627399 -392.093746) (xy 147.67328 -392.123232) (xy 147.714497 -392.158947) (xy 147.750212 -392.200164)
			(xy 147.779698 -392.246045) (xy 147.802355 -392.295655) (xy 147.81772 -392.347985) (xy 147.825482 -392.401969)
			(xy 147.825968 -392.429238) (xy 147.825968 -393.292838) (xy 148.26234 -393.292838) (xy 148.26234 -392.429238)
			(xy 148.262826 -392.401969) (xy 148.270588 -392.347985) (xy 148.285953 -392.295655) (xy 148.30861 -392.246045)
			(xy 148.338096 -392.200164) (xy 148.373811 -392.158947) (xy 148.415028 -392.123232) (xy 148.460909 -392.093746)
			(xy 148.510519 -392.071089) (xy 148.562849 -392.055724) (xy 148.616833 -392.047962) (xy 148.671371 -392.047962)
			(xy 148.725355 -392.055724) (xy 148.777685 -392.071089) (xy 148.827295 -392.093746) (xy 148.873176 -392.123232)
			(xy 148.914393 -392.158947) (xy 148.950108 -392.200164) (xy 148.979594 -392.246045) (xy 149.002251 -392.295655)
			(xy 149.017616 -392.347985) (xy 149.025378 -392.401969) (xy 149.025864 -392.429238) (xy 149.025864 -393.292838)
			(xy 149.462744 -393.292838) (xy 149.462744 -392.429238) (xy 149.46323 -392.401987) (xy 149.470986 -392.348039)
			(xy 149.486341 -392.295744) (xy 149.508983 -392.246167) (xy 149.538449 -392.200317) (xy 149.57414 -392.159126)
			(xy 149.615331 -392.123435) (xy 149.661181 -392.093969) (xy 149.710758 -392.071327) (xy 149.763053 -392.055972)
			(xy 149.817001 -392.048216) (xy 149.871503 -392.048216) (xy 149.925451 -392.055972) (xy 149.977746 -392.071327)
			(xy 150.027323 -392.093969) (xy 150.073173 -392.123435) (xy 150.114364 -392.159126) (xy 150.150055 -392.200317)
			(xy 150.179521 -392.246167) (xy 150.202163 -392.295744) (xy 150.217518 -392.348039) (xy 150.225274 -392.401987)
			(xy 150.22576 -392.429238) (xy 150.22576 -393.292838) (xy 150.66264 -393.292838) (xy 150.66264 -392.429238)
			(xy 150.663126 -392.401987) (xy 150.670882 -392.348039) (xy 150.686237 -392.295744) (xy 150.708879 -392.246167)
			(xy 150.738345 -392.200317) (xy 150.774036 -392.159126) (xy 150.815227 -392.123435) (xy 150.861077 -392.093969)
			(xy 150.910654 -392.071327) (xy 150.962949 -392.055972) (xy 151.016897 -392.048216) (xy 151.071399 -392.048216)
			(xy 151.125347 -392.055972) (xy 151.177642 -392.071327) (xy 151.227219 -392.093969) (xy 151.273069 -392.123435)
			(xy 151.31426 -392.159126) (xy 151.349951 -392.200317) (xy 151.379417 -392.246167) (xy 151.402059 -392.295744)
			(xy 151.417414 -392.348039) (xy 151.42517 -392.401987) (xy 151.425656 -392.429238) (xy 151.425656 -393.292838)
			(xy 151.862536 -393.292838) (xy 151.862536 -392.429238) (xy 151.863022 -392.401969) (xy 151.870784 -392.347985)
			(xy 151.886149 -392.295655) (xy 151.908806 -392.246045) (xy 151.938292 -392.200164) (xy 151.974007 -392.158947)
			(xy 152.015224 -392.123232) (xy 152.061105 -392.093746) (xy 152.110715 -392.071089) (xy 152.163045 -392.055724)
			(xy 152.217029 -392.047962) (xy 152.271567 -392.047962) (xy 152.325551 -392.055724) (xy 152.377881 -392.071089)
			(xy 152.427491 -392.093746) (xy 152.473372 -392.123232) (xy 152.514589 -392.158947) (xy 152.550304 -392.200164)
			(xy 152.57979 -392.246045) (xy 152.602447 -392.295655) (xy 152.617812 -392.347985) (xy 152.625574 -392.401969)
			(xy 152.62606 -392.429238) (xy 152.62606 -393.292838) (xy 153.062432 -393.292838) (xy 153.062432 -392.429238)
			(xy 153.062918 -392.401969) (xy 153.07068 -392.347985) (xy 153.086045 -392.295655) (xy 153.108702 -392.246045)
			(xy 153.138188 -392.200164) (xy 153.173903 -392.158947) (xy 153.21512 -392.123232) (xy 153.261001 -392.093746)
			(xy 153.310611 -392.071089) (xy 153.362941 -392.055724) (xy 153.416925 -392.047962) (xy 153.471463 -392.047962)
			(xy 153.525447 -392.055724) (xy 153.577777 -392.071089) (xy 153.627387 -392.093746) (xy 153.673268 -392.123232)
			(xy 153.714485 -392.158947) (xy 153.7502 -392.200164) (xy 153.779686 -392.246045) (xy 153.802343 -392.295655)
			(xy 153.817708 -392.347985) (xy 153.82547 -392.401969) (xy 153.825956 -392.429238) (xy 153.825956 -393.292838)
			(xy 154.262836 -393.292838) (xy 154.262836 -392.429238) (xy 154.263322 -392.401987) (xy 154.271078 -392.348039)
			(xy 154.286433 -392.295744) (xy 154.309075 -392.246167) (xy 154.338541 -392.200317) (xy 154.374232 -392.159126)
			(xy 154.415423 -392.123435) (xy 154.461273 -392.093969) (xy 154.51085 -392.071327) (xy 154.563145 -392.055972)
			(xy 154.617093 -392.048216) (xy 154.671595 -392.048216) (xy 154.725543 -392.055972) (xy 154.777838 -392.071327)
			(xy 154.827415 -392.093969) (xy 154.873265 -392.123435) (xy 154.914456 -392.159126) (xy 154.950147 -392.200317)
			(xy 154.979613 -392.246167) (xy 155.002255 -392.295744) (xy 155.01761 -392.348039) (xy 155.025366 -392.401987)
			(xy 155.025852 -392.429238) (xy 155.025852 -393.292838) (xy 155.462732 -393.292838) (xy 155.462732 -392.429238)
			(xy 155.463218 -392.401987) (xy 155.470974 -392.348039) (xy 155.486329 -392.295744) (xy 155.508971 -392.246167)
			(xy 155.538437 -392.200317) (xy 155.574128 -392.159126) (xy 155.615319 -392.123435) (xy 155.661169 -392.093969)
			(xy 155.710746 -392.071327) (xy 155.763041 -392.055972) (xy 155.816989 -392.048216) (xy 155.871491 -392.048216)
			(xy 155.925439 -392.055972) (xy 155.977734 -392.071327) (xy 156.027311 -392.093969) (xy 156.073161 -392.123435)
			(xy 156.114352 -392.159126) (xy 156.150043 -392.200317) (xy 156.179509 -392.246167) (xy 156.202151 -392.295744)
			(xy 156.217506 -392.348039) (xy 156.225262 -392.401987) (xy 156.225748 -392.429238) (xy 156.225748 -393.292838)
			(xy 156.662628 -393.292838) (xy 156.662628 -392.429238) (xy 156.663114 -392.401969) (xy 156.670876 -392.347985)
			(xy 156.686241 -392.295655) (xy 156.708898 -392.246045) (xy 156.738384 -392.200164) (xy 156.774099 -392.158947)
			(xy 156.815316 -392.123232) (xy 156.861197 -392.093746) (xy 156.910807 -392.071089) (xy 156.963137 -392.055724)
			(xy 157.017121 -392.047962) (xy 157.071659 -392.047962) (xy 157.125643 -392.055724) (xy 157.177973 -392.071089)
			(xy 157.227583 -392.093746) (xy 157.273464 -392.123232) (xy 157.314681 -392.158947) (xy 157.350396 -392.200164)
			(xy 157.379882 -392.246045) (xy 157.402539 -392.295655) (xy 157.417904 -392.347985) (xy 157.425666 -392.401969)
			(xy 157.426152 -392.429238) (xy 157.426152 -393.292838) (xy 157.862524 -393.292838) (xy 157.862524 -392.429238)
			(xy 157.86301 -392.401969) (xy 157.870772 -392.347985) (xy 157.886137 -392.295655) (xy 157.908794 -392.246045)
			(xy 157.93828 -392.200164) (xy 157.973995 -392.158947) (xy 158.015212 -392.123232) (xy 158.061093 -392.093746)
			(xy 158.110703 -392.071089) (xy 158.163033 -392.055724) (xy 158.217017 -392.047962) (xy 158.271555 -392.047962)
			(xy 158.325539 -392.055724) (xy 158.377869 -392.071089) (xy 158.427479 -392.093746) (xy 158.47336 -392.123232)
			(xy 158.514577 -392.158947) (xy 158.550292 -392.200164) (xy 158.579778 -392.246045) (xy 158.602435 -392.295655)
			(xy 158.6178 -392.347985) (xy 158.625562 -392.401969) (xy 158.626048 -392.429238) (xy 158.626048 -393.292838)
			(xy 159.062928 -393.292838) (xy 159.062928 -392.429238) (xy 159.063414 -392.401987) (xy 159.07117 -392.348039)
			(xy 159.086525 -392.295744) (xy 159.109167 -392.246167) (xy 159.138633 -392.200317) (xy 159.174324 -392.159126)
			(xy 159.215515 -392.123435) (xy 159.261365 -392.093969) (xy 159.310942 -392.071327) (xy 159.363237 -392.055972)
			(xy 159.417185 -392.048216) (xy 159.471687 -392.048216) (xy 159.525635 -392.055972) (xy 159.57793 -392.071327)
			(xy 159.627507 -392.093969) (xy 159.673357 -392.123435) (xy 159.714548 -392.159126) (xy 159.750239 -392.200317)
			(xy 159.779705 -392.246167) (xy 159.802347 -392.295744) (xy 159.817702 -392.348039) (xy 159.825458 -392.401987)
			(xy 159.825944 -392.429238) (xy 159.825944 -393.292838) (xy 159.825458 -393.320089) (xy 159.817702 -393.374037)
			(xy 159.802347 -393.426332) (xy 159.779705 -393.475909) (xy 159.750239 -393.521759) (xy 159.714548 -393.56295)
			(xy 159.673357 -393.598641) (xy 159.627507 -393.628107) (xy 159.57793 -393.650749) (xy 159.525635 -393.666104)
			(xy 159.471687 -393.67386) (xy 159.417185 -393.67386) (xy 159.363237 -393.666104) (xy 159.310942 -393.650749)
			(xy 159.261365 -393.628107) (xy 159.215515 -393.598641) (xy 159.174324 -393.56295) (xy 159.138633 -393.521759)
			(xy 159.109167 -393.475909) (xy 159.086525 -393.426332) (xy 159.07117 -393.374037) (xy 159.063414 -393.320089)
			(xy 159.062928 -393.292838) (xy 158.626048 -393.292838) (xy 158.625562 -393.320107) (xy 158.6178 -393.374091)
			(xy 158.602435 -393.426421) (xy 158.579778 -393.476031) (xy 158.550292 -393.521912) (xy 158.514577 -393.563129)
			(xy 158.47336 -393.598844) (xy 158.427479 -393.62833) (xy 158.377869 -393.650987) (xy 158.325539 -393.666352)
			(xy 158.271555 -393.674114) (xy 158.217017 -393.674114) (xy 158.163033 -393.666352) (xy 158.110703 -393.650987)
			(xy 158.061093 -393.62833) (xy 158.015212 -393.598844) (xy 157.973995 -393.563129) (xy 157.93828 -393.521912)
			(xy 157.908794 -393.476031) (xy 157.886137 -393.426421) (xy 157.870772 -393.374091) (xy 157.86301 -393.320107)
			(xy 157.862524 -393.292838) (xy 157.426152 -393.292838) (xy 157.425666 -393.320107) (xy 157.417904 -393.374091)
			(xy 157.402539 -393.426421) (xy 157.379882 -393.476031) (xy 157.350396 -393.521912) (xy 157.314681 -393.563129)
			(xy 157.273464 -393.598844) (xy 157.227583 -393.62833) (xy 157.177973 -393.650987) (xy 157.125643 -393.666352)
			(xy 157.071659 -393.674114) (xy 157.017121 -393.674114) (xy 156.963137 -393.666352) (xy 156.910807 -393.650987)
			(xy 156.861197 -393.62833) (xy 156.815316 -393.598844) (xy 156.774099 -393.563129) (xy 156.738384 -393.521912)
			(xy 156.708898 -393.476031) (xy 156.686241 -393.426421) (xy 156.670876 -393.374091) (xy 156.663114 -393.320107)
			(xy 156.662628 -393.292838) (xy 156.225748 -393.292838) (xy 156.225262 -393.320089) (xy 156.217506 -393.374037)
			(xy 156.202151 -393.426332) (xy 156.179509 -393.475909) (xy 156.150043 -393.521759) (xy 156.114352 -393.56295)
			(xy 156.073161 -393.598641) (xy 156.027311 -393.628107) (xy 155.977734 -393.650749) (xy 155.925439 -393.666104)
			(xy 155.871491 -393.67386) (xy 155.816989 -393.67386) (xy 155.763041 -393.666104) (xy 155.710746 -393.650749)
			(xy 155.661169 -393.628107) (xy 155.615319 -393.598641) (xy 155.574128 -393.56295) (xy 155.538437 -393.521759)
			(xy 155.508971 -393.475909) (xy 155.486329 -393.426332) (xy 155.470974 -393.374037) (xy 155.463218 -393.320089)
			(xy 155.462732 -393.292838) (xy 155.025852 -393.292838) (xy 155.025366 -393.320089) (xy 155.01761 -393.374037)
			(xy 155.002255 -393.426332) (xy 154.979613 -393.475909) (xy 154.950147 -393.521759) (xy 154.914456 -393.56295)
			(xy 154.873265 -393.598641) (xy 154.827415 -393.628107) (xy 154.777838 -393.650749) (xy 154.725543 -393.666104)
			(xy 154.671595 -393.67386) (xy 154.617093 -393.67386) (xy 154.563145 -393.666104) (xy 154.51085 -393.650749)
			(xy 154.461273 -393.628107) (xy 154.415423 -393.598641) (xy 154.374232 -393.56295) (xy 154.338541 -393.521759)
			(xy 154.309075 -393.475909) (xy 154.286433 -393.426332) (xy 154.271078 -393.374037) (xy 154.263322 -393.320089)
			(xy 154.262836 -393.292838) (xy 153.825956 -393.292838) (xy 153.82547 -393.320107) (xy 153.817708 -393.374091)
			(xy 153.802343 -393.426421) (xy 153.779686 -393.476031) (xy 153.7502 -393.521912) (xy 153.714485 -393.563129)
			(xy 153.673268 -393.598844) (xy 153.627387 -393.62833) (xy 153.577777 -393.650987) (xy 153.525447 -393.666352)
			(xy 153.471463 -393.674114) (xy 153.416925 -393.674114) (xy 153.362941 -393.666352) (xy 153.310611 -393.650987)
			(xy 153.261001 -393.62833) (xy 153.21512 -393.598844) (xy 153.173903 -393.563129) (xy 153.138188 -393.521912)
			(xy 153.108702 -393.476031) (xy 153.086045 -393.426421) (xy 153.07068 -393.374091) (xy 153.062918 -393.320107)
			(xy 153.062432 -393.292838) (xy 152.62606 -393.292838) (xy 152.625574 -393.320107) (xy 152.617812 -393.374091)
			(xy 152.602447 -393.426421) (xy 152.57979 -393.476031) (xy 152.550304 -393.521912) (xy 152.514589 -393.563129)
			(xy 152.473372 -393.598844) (xy 152.427491 -393.62833) (xy 152.377881 -393.650987) (xy 152.325551 -393.666352)
			(xy 152.271567 -393.674114) (xy 152.217029 -393.674114) (xy 152.163045 -393.666352) (xy 152.110715 -393.650987)
			(xy 152.061105 -393.62833) (xy 152.015224 -393.598844) (xy 151.974007 -393.563129) (xy 151.938292 -393.521912)
			(xy 151.908806 -393.476031) (xy 151.886149 -393.426421) (xy 151.870784 -393.374091) (xy 151.863022 -393.320107)
			(xy 151.862536 -393.292838) (xy 151.425656 -393.292838) (xy 151.42517 -393.320089) (xy 151.417414 -393.374037)
			(xy 151.402059 -393.426332) (xy 151.379417 -393.475909) (xy 151.349951 -393.521759) (xy 151.31426 -393.56295)
			(xy 151.273069 -393.598641) (xy 151.227219 -393.628107) (xy 151.177642 -393.650749) (xy 151.125347 -393.666104)
			(xy 151.071399 -393.67386) (xy 151.016897 -393.67386) (xy 150.962949 -393.666104) (xy 150.910654 -393.650749)
			(xy 150.861077 -393.628107) (xy 150.815227 -393.598641) (xy 150.774036 -393.56295) (xy 150.738345 -393.521759)
			(xy 150.708879 -393.475909) (xy 150.686237 -393.426332) (xy 150.670882 -393.374037) (xy 150.663126 -393.320089)
			(xy 150.66264 -393.292838) (xy 150.22576 -393.292838) (xy 150.225274 -393.320089) (xy 150.217518 -393.374037)
			(xy 150.202163 -393.426332) (xy 150.179521 -393.475909) (xy 150.150055 -393.521759) (xy 150.114364 -393.56295)
			(xy 150.073173 -393.598641) (xy 150.027323 -393.628107) (xy 149.977746 -393.650749) (xy 149.925451 -393.666104)
			(xy 149.871503 -393.67386) (xy 149.817001 -393.67386) (xy 149.763053 -393.666104) (xy 149.710758 -393.650749)
			(xy 149.661181 -393.628107) (xy 149.615331 -393.598641) (xy 149.57414 -393.56295) (xy 149.538449 -393.521759)
			(xy 149.508983 -393.475909) (xy 149.486341 -393.426332) (xy 149.470986 -393.374037) (xy 149.46323 -393.320089)
			(xy 149.462744 -393.292838) (xy 149.025864 -393.292838) (xy 149.025378 -393.320107) (xy 149.017616 -393.374091)
			(xy 149.002251 -393.426421) (xy 148.979594 -393.476031) (xy 148.950108 -393.521912) (xy 148.914393 -393.563129)
			(xy 148.873176 -393.598844) (xy 148.827295 -393.62833) (xy 148.777685 -393.650987) (xy 148.725355 -393.666352)
			(xy 148.671371 -393.674114) (xy 148.616833 -393.674114) (xy 148.562849 -393.666352) (xy 148.510519 -393.650987)
			(xy 148.460909 -393.62833) (xy 148.415028 -393.598844) (xy 148.373811 -393.563129) (xy 148.338096 -393.521912)
			(xy 148.30861 -393.476031) (xy 148.285953 -393.426421) (xy 148.270588 -393.374091) (xy 148.262826 -393.320107)
			(xy 148.26234 -393.292838) (xy 147.825968 -393.292838) (xy 147.825482 -393.320107) (xy 147.81772 -393.374091)
			(xy 147.802355 -393.426421) (xy 147.779698 -393.476031) (xy 147.750212 -393.521912) (xy 147.714497 -393.563129)
			(xy 147.67328 -393.598844) (xy 147.627399 -393.62833) (xy 147.577789 -393.650987) (xy 147.525459 -393.666352)
			(xy 147.471475 -393.674114) (xy 147.416937 -393.674114) (xy 147.362953 -393.666352) (xy 147.310623 -393.650987)
			(xy 147.261013 -393.62833) (xy 147.215132 -393.598844) (xy 147.173915 -393.563129) (xy 147.1382 -393.521912)
			(xy 147.108714 -393.476031) (xy 147.086057 -393.426421) (xy 147.070692 -393.374091) (xy 147.06293 -393.320107)
			(xy 147.062444 -393.292838) (xy 133.298184 -393.292838) (xy 133.297698 -393.320107) (xy 133.289936 -393.374091)
			(xy 133.274571 -393.426421) (xy 133.251914 -393.476031) (xy 133.222428 -393.521912) (xy 133.186713 -393.563129)
			(xy 133.145496 -393.598844) (xy 133.099615 -393.62833) (xy 133.050005 -393.650987) (xy 132.997675 -393.666352)
			(xy 132.943691 -393.674114) (xy 132.889153 -393.674114) (xy 132.835169 -393.666352) (xy 132.782839 -393.650987)
			(xy 132.733229 -393.62833) (xy 132.687348 -393.598844) (xy 132.646131 -393.563129) (xy 132.610416 -393.521912)
			(xy 132.58093 -393.476031) (xy 132.558273 -393.426421) (xy 132.542908 -393.374091) (xy 132.535146 -393.320107)
			(xy 132.53466 -393.292838) (xy 132.098288 -393.292838) (xy 132.097802 -393.320107) (xy 132.09004 -393.374091)
			(xy 132.074675 -393.426421) (xy 132.052018 -393.476031) (xy 132.022532 -393.521912) (xy 131.986817 -393.563129)
			(xy 131.9456 -393.598844) (xy 131.899719 -393.62833) (xy 131.850109 -393.650987) (xy 131.797779 -393.666352)
			(xy 131.743795 -393.674114) (xy 131.689257 -393.674114) (xy 131.635273 -393.666352) (xy 131.582943 -393.650987)
			(xy 131.533333 -393.62833) (xy 131.487452 -393.598844) (xy 131.446235 -393.563129) (xy 131.41052 -393.521912)
			(xy 131.381034 -393.476031) (xy 131.358377 -393.426421) (xy 131.343012 -393.374091) (xy 131.33525 -393.320107)
			(xy 131.334764 -393.292838) (xy 130.897884 -393.292838) (xy 130.897398 -393.320089) (xy 130.889642 -393.374037)
			(xy 130.874287 -393.426332) (xy 130.851645 -393.475909) (xy 130.822179 -393.521759) (xy 130.786488 -393.56295)
			(xy 130.745297 -393.598641) (xy 130.699447 -393.628107) (xy 130.64987 -393.650749) (xy 130.597575 -393.666104)
			(xy 130.543627 -393.67386) (xy 130.489125 -393.67386) (xy 130.435177 -393.666104) (xy 130.382882 -393.650749)
			(xy 130.333305 -393.628107) (xy 130.287455 -393.598641) (xy 130.246264 -393.56295) (xy 130.210573 -393.521759)
			(xy 130.181107 -393.475909) (xy 130.158465 -393.426332) (xy 130.14311 -393.374037) (xy 130.135354 -393.320089)
			(xy 130.134868 -393.292838) (xy 129.697988 -393.292838) (xy 129.697502 -393.320089) (xy 129.689746 -393.374037)
			(xy 129.674391 -393.426332) (xy 129.651749 -393.475909) (xy 129.622283 -393.521759) (xy 129.586592 -393.56295)
			(xy 129.545401 -393.598641) (xy 129.499551 -393.628107) (xy 129.449974 -393.650749) (xy 129.397679 -393.666104)
			(xy 129.343731 -393.67386) (xy 129.289229 -393.67386) (xy 129.235281 -393.666104) (xy 129.182986 -393.650749)
			(xy 129.133409 -393.628107) (xy 129.087559 -393.598641) (xy 129.046368 -393.56295) (xy 129.010677 -393.521759)
			(xy 128.981211 -393.475909) (xy 128.958569 -393.426332) (xy 128.943214 -393.374037) (xy 128.935458 -393.320089)
			(xy 128.934972 -393.292838) (xy 128.498092 -393.292838) (xy 128.497606 -393.320089) (xy 128.48985 -393.374037)
			(xy 128.474495 -393.426332) (xy 128.451853 -393.475909) (xy 128.422387 -393.521759) (xy 128.386696 -393.56295)
			(xy 128.345505 -393.598641) (xy 128.299655 -393.628107) (xy 128.250078 -393.650749) (xy 128.197783 -393.666104)
			(xy 128.143835 -393.67386) (xy 128.089333 -393.67386) (xy 128.035385 -393.666104) (xy 127.98309 -393.650749)
			(xy 127.933513 -393.628107) (xy 127.887663 -393.598641) (xy 127.846472 -393.56295) (xy 127.810781 -393.521759)
			(xy 127.781315 -393.475909) (xy 127.758673 -393.426332) (xy 127.743318 -393.374037) (xy 127.735562 -393.320089)
			(xy 127.735076 -393.292838) (xy 127.298196 -393.292838) (xy 127.29771 -393.320089) (xy 127.289954 -393.374037)
			(xy 127.274599 -393.426332) (xy 127.251957 -393.475909) (xy 127.222491 -393.521759) (xy 127.1868 -393.56295)
			(xy 127.145609 -393.598641) (xy 127.099759 -393.628107) (xy 127.050182 -393.650749) (xy 126.997887 -393.666104)
			(xy 126.943939 -393.67386) (xy 126.889437 -393.67386) (xy 126.835489 -393.666104) (xy 126.783194 -393.650749)
			(xy 126.733617 -393.628107) (xy 126.687767 -393.598641) (xy 126.646576 -393.56295) (xy 126.610885 -393.521759)
			(xy 126.581419 -393.475909) (xy 126.558777 -393.426332) (xy 126.543422 -393.374037) (xy 126.535666 -393.320089)
			(xy 126.53518 -393.292838) (xy 126.0983 -393.292838) (xy 126.097814 -393.320107) (xy 126.090052 -393.374091)
			(xy 126.074687 -393.426421) (xy 126.05203 -393.476031) (xy 126.022544 -393.521912) (xy 125.986829 -393.563129)
			(xy 125.945612 -393.598844) (xy 125.899731 -393.62833) (xy 125.850121 -393.650987) (xy 125.797791 -393.666352)
			(xy 125.743807 -393.674114) (xy 125.689269 -393.674114) (xy 125.635285 -393.666352) (xy 125.582955 -393.650987)
			(xy 125.533345 -393.62833) (xy 125.487464 -393.598844) (xy 125.446247 -393.563129) (xy 125.410532 -393.521912)
			(xy 125.381046 -393.476031) (xy 125.358389 -393.426421) (xy 125.343024 -393.374091) (xy 125.335262 -393.320107)
			(xy 125.334776 -393.292838) (xy 124.898404 -393.292838) (xy 124.897918 -393.320107) (xy 124.890156 -393.374091)
			(xy 124.874791 -393.426421) (xy 124.852134 -393.476031) (xy 124.822648 -393.521912) (xy 124.786933 -393.563129)
			(xy 124.745716 -393.598844) (xy 124.699835 -393.62833) (xy 124.650225 -393.650987) (xy 124.597895 -393.666352)
			(xy 124.543911 -393.674114) (xy 124.489373 -393.674114) (xy 124.435389 -393.666352) (xy 124.383059 -393.650987)
			(xy 124.333449 -393.62833) (xy 124.287568 -393.598844) (xy 124.246351 -393.563129) (xy 124.210636 -393.521912)
			(xy 124.18115 -393.476031) (xy 124.158493 -393.426421) (xy 124.143128 -393.374091) (xy 124.135366 -393.320107)
			(xy 124.13488 -393.292838) (xy 123.698 -393.292838) (xy 123.697514 -393.320089) (xy 123.689758 -393.374037)
			(xy 123.674403 -393.426332) (xy 123.651761 -393.475909) (xy 123.622295 -393.521759) (xy 123.586604 -393.56295)
			(xy 123.545413 -393.598641) (xy 123.499563 -393.628107) (xy 123.449986 -393.650749) (xy 123.397691 -393.666104)
			(xy 123.343743 -393.67386) (xy 123.289241 -393.67386) (xy 123.235293 -393.666104) (xy 123.182998 -393.650749)
			(xy 123.133421 -393.628107) (xy 123.087571 -393.598641) (xy 123.04638 -393.56295) (xy 123.010689 -393.521759)
			(xy 122.981223 -393.475909) (xy 122.958581 -393.426332) (xy 122.943226 -393.374037) (xy 122.93547 -393.320089)
			(xy 122.934984 -393.292838) (xy 122.498104 -393.292838) (xy 122.497618 -393.320089) (xy 122.489862 -393.374037)
			(xy 122.474507 -393.426332) (xy 122.451865 -393.475909) (xy 122.422399 -393.521759) (xy 122.386708 -393.56295)
			(xy 122.345517 -393.598641) (xy 122.299667 -393.628107) (xy 122.25009 -393.650749) (xy 122.197795 -393.666104)
			(xy 122.143847 -393.67386) (xy 122.089345 -393.67386) (xy 122.035397 -393.666104) (xy 121.983102 -393.650749)
			(xy 121.933525 -393.628107) (xy 121.887675 -393.598641) (xy 121.846484 -393.56295) (xy 121.810793 -393.521759)
			(xy 121.781327 -393.475909) (xy 121.758685 -393.426332) (xy 121.74333 -393.374037) (xy 121.735574 -393.320089)
			(xy 121.735088 -393.292838) (xy 121.298208 -393.292838) (xy 121.297722 -393.320107) (xy 121.28996 -393.374091)
			(xy 121.274595 -393.426421) (xy 121.251938 -393.476031) (xy 121.222452 -393.521912) (xy 121.186737 -393.563129)
			(xy 121.14552 -393.598844) (xy 121.099639 -393.62833) (xy 121.050029 -393.650987) (xy 120.997699 -393.666352)
			(xy 120.943715 -393.674114) (xy 120.889177 -393.674114) (xy 120.835193 -393.666352) (xy 120.782863 -393.650987)
			(xy 120.733253 -393.62833) (xy 120.687372 -393.598844) (xy 120.646155 -393.563129) (xy 120.61044 -393.521912)
			(xy 120.580954 -393.476031) (xy 120.558297 -393.426421) (xy 120.542932 -393.374091) (xy 120.53517 -393.320107)
			(xy 120.534684 -393.292838) (xy 120.098312 -393.292838) (xy 120.097826 -393.320107) (xy 120.090064 -393.374091)
			(xy 120.074699 -393.426421) (xy 120.052042 -393.476031) (xy 120.022556 -393.521912) (xy 119.986841 -393.563129)
			(xy 119.945624 -393.598844) (xy 119.899743 -393.62833) (xy 119.850133 -393.650987) (xy 119.797803 -393.666352)
			(xy 119.743819 -393.674114) (xy 119.689281 -393.674114) (xy 119.635297 -393.666352) (xy 119.582967 -393.650987)
			(xy 119.533357 -393.62833) (xy 119.487476 -393.598844) (xy 119.446259 -393.563129) (xy 119.410544 -393.521912)
			(xy 119.381058 -393.476031) (xy 119.358401 -393.426421) (xy 119.343036 -393.374091) (xy 119.335274 -393.320107)
			(xy 119.334788 -393.292838) (xy 118.897908 -393.292838) (xy 118.897422 -393.320089) (xy 118.889666 -393.374037)
			(xy 118.874311 -393.426332) (xy 118.851669 -393.475909) (xy 118.822203 -393.521759) (xy 118.786512 -393.56295)
			(xy 118.745321 -393.598641) (xy 118.699471 -393.628107) (xy 118.649894 -393.650749) (xy 118.597599 -393.666104)
			(xy 118.543651 -393.67386) (xy 118.489149 -393.67386) (xy 118.435201 -393.666104) (xy 118.382906 -393.650749)
			(xy 118.333329 -393.628107) (xy 118.287479 -393.598641) (xy 118.246288 -393.56295) (xy 118.210597 -393.521759)
			(xy 118.181131 -393.475909) (xy 118.158489 -393.426332) (xy 118.143134 -393.374037) (xy 118.135378 -393.320089)
			(xy 118.134892 -393.292838) (xy 117.698012 -393.292838) (xy 117.697526 -393.320089) (xy 117.68977 -393.374037)
			(xy 117.674415 -393.426332) (xy 117.651773 -393.475909) (xy 117.622307 -393.521759) (xy 117.586616 -393.56295)
			(xy 117.545425 -393.598641) (xy 117.499575 -393.628107) (xy 117.449998 -393.650749) (xy 117.397703 -393.666104)
			(xy 117.343755 -393.67386) (xy 117.289253 -393.67386) (xy 117.235305 -393.666104) (xy 117.18301 -393.650749)
			(xy 117.133433 -393.628107) (xy 117.087583 -393.598641) (xy 117.046392 -393.56295) (xy 117.010701 -393.521759)
			(xy 116.981235 -393.475909) (xy 116.958593 -393.426332) (xy 116.943238 -393.374037) (xy 116.935482 -393.320089)
			(xy 116.934996 -393.292838) (xy 116.498116 -393.292838) (xy 116.49763 -393.320107) (xy 116.489868 -393.374091)
			(xy 116.474503 -393.426421) (xy 116.451846 -393.476031) (xy 116.42236 -393.521912) (xy 116.386645 -393.563129)
			(xy 116.345428 -393.598844) (xy 116.299547 -393.62833) (xy 116.249937 -393.650987) (xy 116.197607 -393.666352)
			(xy 116.143623 -393.674114) (xy 116.089085 -393.674114) (xy 116.035101 -393.666352) (xy 115.982771 -393.650987)
			(xy 115.933161 -393.62833) (xy 115.88728 -393.598844) (xy 115.846063 -393.563129) (xy 115.810348 -393.521912)
			(xy 115.780862 -393.476031) (xy 115.758205 -393.426421) (xy 115.74284 -393.374091) (xy 115.735078 -393.320107)
			(xy 115.734592 -393.292838) (xy 115.29822 -393.292838) (xy 115.297734 -393.320107) (xy 115.289972 -393.374091)
			(xy 115.274607 -393.426421) (xy 115.25195 -393.476031) (xy 115.222464 -393.521912) (xy 115.186749 -393.563129)
			(xy 115.145532 -393.598844) (xy 115.099651 -393.62833) (xy 115.050041 -393.650987) (xy 114.997711 -393.666352)
			(xy 114.943727 -393.674114) (xy 114.889189 -393.674114) (xy 114.835205 -393.666352) (xy 114.782875 -393.650987)
			(xy 114.733265 -393.62833) (xy 114.687384 -393.598844) (xy 114.646167 -393.563129) (xy 114.610452 -393.521912)
			(xy 114.580966 -393.476031) (xy 114.558309 -393.426421) (xy 114.542944 -393.374091) (xy 114.535182 -393.320107)
			(xy 114.534696 -393.292838) (xy 98.725736 -393.292838) (xy 98.72525 -393.320089) (xy 98.717494 -393.374037)
			(xy 98.702139 -393.426332) (xy 98.679497 -393.475909) (xy 98.650031 -393.521759) (xy 98.61434 -393.56295)
			(xy 98.573149 -393.598641) (xy 98.527299 -393.628107) (xy 98.477722 -393.650749) (xy 98.425427 -393.666104)
			(xy 98.371479 -393.67386) (xy 98.316977 -393.67386) (xy 98.263029 -393.666104) (xy 98.210734 -393.650749)
			(xy 98.161157 -393.628107) (xy 98.115307 -393.598641) (xy 98.074116 -393.56295) (xy 98.038425 -393.521759)
			(xy 98.008959 -393.475909) (xy 97.986317 -393.426332) (xy 97.970962 -393.374037) (xy 97.963206 -393.320089)
			(xy 97.96272 -393.292838) (xy 97.52584 -393.292838) (xy 97.525354 -393.320089) (xy 97.517598 -393.374037)
			(xy 97.502243 -393.426332) (xy 97.479601 -393.475909) (xy 97.450135 -393.521759) (xy 97.414444 -393.56295)
			(xy 97.373253 -393.598641) (xy 97.327403 -393.628107) (xy 97.277826 -393.650749) (xy 97.225531 -393.666104)
			(xy 97.171583 -393.67386) (xy 97.117081 -393.67386) (xy 97.063133 -393.666104) (xy 97.010838 -393.650749)
			(xy 96.961261 -393.628107) (xy 96.915411 -393.598641) (xy 96.87422 -393.56295) (xy 96.838529 -393.521759)
			(xy 96.809063 -393.475909) (xy 96.786421 -393.426332) (xy 96.771066 -393.374037) (xy 96.76331 -393.320089)
			(xy 96.762824 -393.292838) (xy 96.325944 -393.292838) (xy 96.325458 -393.320107) (xy 96.317696 -393.374091)
			(xy 96.302331 -393.426421) (xy 96.279674 -393.476031) (xy 96.250188 -393.521912) (xy 96.214473 -393.563129)
			(xy 96.173256 -393.598844) (xy 96.127375 -393.62833) (xy 96.077765 -393.650987) (xy 96.025435 -393.666352)
			(xy 95.971451 -393.674114) (xy 95.916913 -393.674114) (xy 95.862929 -393.666352) (xy 95.810599 -393.650987)
			(xy 95.760989 -393.62833) (xy 95.715108 -393.598844) (xy 95.673891 -393.563129) (xy 95.638176 -393.521912)
			(xy 95.60869 -393.476031) (xy 95.586033 -393.426421) (xy 95.570668 -393.374091) (xy 95.562906 -393.320107)
			(xy 95.56242 -393.292838) (xy 95.126048 -393.292838) (xy 95.125562 -393.320107) (xy 95.1178 -393.374091)
			(xy 95.102435 -393.426421) (xy 95.079778 -393.476031) (xy 95.050292 -393.521912) (xy 95.014577 -393.563129)
			(xy 94.97336 -393.598844) (xy 94.927479 -393.62833) (xy 94.877869 -393.650987) (xy 94.825539 -393.666352)
			(xy 94.771555 -393.674114) (xy 94.717017 -393.674114) (xy 94.663033 -393.666352) (xy 94.610703 -393.650987)
			(xy 94.561093 -393.62833) (xy 94.515212 -393.598844) (xy 94.473995 -393.563129) (xy 94.43828 -393.521912)
			(xy 94.408794 -393.476031) (xy 94.386137 -393.426421) (xy 94.370772 -393.374091) (xy 94.36301 -393.320107)
			(xy 94.362524 -393.292838) (xy 93.926152 -393.292838) (xy 93.925666 -393.320107) (xy 93.917904 -393.374091)
			(xy 93.902539 -393.426421) (xy 93.879882 -393.476031) (xy 93.850396 -393.521912) (xy 93.814681 -393.563129)
			(xy 93.773464 -393.598844) (xy 93.727583 -393.62833) (xy 93.677973 -393.650987) (xy 93.625643 -393.666352)
			(xy 93.571659 -393.674114) (xy 93.517121 -393.674114) (xy 93.463137 -393.666352) (xy 93.410807 -393.650987)
			(xy 93.361197 -393.62833) (xy 93.315316 -393.598844) (xy 93.274099 -393.563129) (xy 93.238384 -393.521912)
			(xy 93.208898 -393.476031) (xy 93.186241 -393.426421) (xy 93.170876 -393.374091) (xy 93.163114 -393.320107)
			(xy 93.162628 -393.292838) (xy 92.726256 -393.292838) (xy 92.72577 -393.320107) (xy 92.718008 -393.374091)
			(xy 92.702643 -393.426421) (xy 92.679986 -393.476031) (xy 92.6505 -393.521912) (xy 92.614785 -393.563129)
			(xy 92.573568 -393.598844) (xy 92.527687 -393.62833) (xy 92.478077 -393.650987) (xy 92.425747 -393.666352)
			(xy 92.371763 -393.674114) (xy 92.317225 -393.674114) (xy 92.263241 -393.666352) (xy 92.210911 -393.650987)
			(xy 92.161301 -393.62833) (xy 92.11542 -393.598844) (xy 92.074203 -393.563129) (xy 92.038488 -393.521912)
			(xy 92.009002 -393.476031) (xy 91.986345 -393.426421) (xy 91.97098 -393.374091) (xy 91.963218 -393.320107)
			(xy 91.962732 -393.292838) (xy 91.525852 -393.292838) (xy 91.525366 -393.320089) (xy 91.51761 -393.374037)
			(xy 91.502255 -393.426332) (xy 91.479613 -393.475909) (xy 91.450147 -393.521759) (xy 91.414456 -393.56295)
			(xy 91.373265 -393.598641) (xy 91.327415 -393.628107) (xy 91.277838 -393.650749) (xy 91.225543 -393.666104)
			(xy 91.171595 -393.67386) (xy 91.117093 -393.67386) (xy 91.063145 -393.666104) (xy 91.01085 -393.650749)
			(xy 90.961273 -393.628107) (xy 90.915423 -393.598641) (xy 90.874232 -393.56295) (xy 90.838541 -393.521759)
			(xy 90.809075 -393.475909) (xy 90.786433 -393.426332) (xy 90.771078 -393.374037) (xy 90.763322 -393.320089)
			(xy 90.762836 -393.292838) (xy 90.325956 -393.292838) (xy 90.32547 -393.320089) (xy 90.317714 -393.374037)
			(xy 90.302359 -393.426332) (xy 90.279717 -393.475909) (xy 90.250251 -393.521759) (xy 90.21456 -393.56295)
			(xy 90.173369 -393.598641) (xy 90.127519 -393.628107) (xy 90.077942 -393.650749) (xy 90.025647 -393.666104)
			(xy 89.971699 -393.67386) (xy 89.917197 -393.67386) (xy 89.863249 -393.666104) (xy 89.810954 -393.650749)
			(xy 89.761377 -393.628107) (xy 89.715527 -393.598641) (xy 89.674336 -393.56295) (xy 89.638645 -393.521759)
			(xy 89.609179 -393.475909) (xy 89.586537 -393.426332) (xy 89.571182 -393.374037) (xy 89.563426 -393.320089)
			(xy 89.56294 -393.292838) (xy 89.12606 -393.292838) (xy 89.125574 -393.320107) (xy 89.117812 -393.374091)
			(xy 89.102447 -393.426421) (xy 89.07979 -393.476031) (xy 89.050304 -393.521912) (xy 89.014589 -393.563129)
			(xy 88.973372 -393.598844) (xy 88.927491 -393.62833) (xy 88.877881 -393.650987) (xy 88.825551 -393.666352)
			(xy 88.771567 -393.674114) (xy 88.717029 -393.674114) (xy 88.663045 -393.666352) (xy 88.610715 -393.650987)
			(xy 88.561105 -393.62833) (xy 88.515224 -393.598844) (xy 88.474007 -393.563129) (xy 88.438292 -393.521912)
			(xy 88.408806 -393.476031) (xy 88.386149 -393.426421) (xy 88.370784 -393.374091) (xy 88.363022 -393.320107)
			(xy 88.362536 -393.292838) (xy 87.926164 -393.292838) (xy 87.925678 -393.320107) (xy 87.917916 -393.374091)
			(xy 87.902551 -393.426421) (xy 87.879894 -393.476031) (xy 87.850408 -393.521912) (xy 87.814693 -393.563129)
			(xy 87.773476 -393.598844) (xy 87.727595 -393.62833) (xy 87.677985 -393.650987) (xy 87.625655 -393.666352)
			(xy 87.571671 -393.674114) (xy 87.517133 -393.674114) (xy 87.463149 -393.666352) (xy 87.410819 -393.650987)
			(xy 87.361209 -393.62833) (xy 87.315328 -393.598844) (xy 87.274111 -393.563129) (xy 87.238396 -393.521912)
			(xy 87.20891 -393.476031) (xy 87.186253 -393.426421) (xy 87.170888 -393.374091) (xy 87.163126 -393.320107)
			(xy 87.16264 -393.292838) (xy 86.72576 -393.292838) (xy 86.725274 -393.320089) (xy 86.717518 -393.374037)
			(xy 86.702163 -393.426332) (xy 86.679521 -393.475909) (xy 86.650055 -393.521759) (xy 86.614364 -393.56295)
			(xy 86.573173 -393.598641) (xy 86.527323 -393.628107) (xy 86.477746 -393.650749) (xy 86.425451 -393.666104)
			(xy 86.371503 -393.67386) (xy 86.317001 -393.67386) (xy 86.263053 -393.666104) (xy 86.210758 -393.650749)
			(xy 86.161181 -393.628107) (xy 86.115331 -393.598641) (xy 86.07414 -393.56295) (xy 86.038449 -393.521759)
			(xy 86.008983 -393.475909) (xy 85.986341 -393.426332) (xy 85.970986 -393.374037) (xy 85.96323 -393.320089)
			(xy 85.962744 -393.292838) (xy 85.525864 -393.292838) (xy 85.525378 -393.320089) (xy 85.517622 -393.374037)
			(xy 85.502267 -393.426332) (xy 85.479625 -393.475909) (xy 85.450159 -393.521759) (xy 85.414468 -393.56295)
			(xy 85.373277 -393.598641) (xy 85.327427 -393.628107) (xy 85.27785 -393.650749) (xy 85.225555 -393.666104)
			(xy 85.171607 -393.67386) (xy 85.117105 -393.67386) (xy 85.063157 -393.666104) (xy 85.010862 -393.650749)
			(xy 84.961285 -393.628107) (xy 84.915435 -393.598641) (xy 84.874244 -393.56295) (xy 84.838553 -393.521759)
			(xy 84.809087 -393.475909) (xy 84.786445 -393.426332) (xy 84.77109 -393.374037) (xy 84.763334 -393.320089)
			(xy 84.762848 -393.292838) (xy 84.325968 -393.292838) (xy 84.325482 -393.320107) (xy 84.31772 -393.374091)
			(xy 84.302355 -393.426421) (xy 84.279698 -393.476031) (xy 84.250212 -393.521912) (xy 84.214497 -393.563129)
			(xy 84.17328 -393.598844) (xy 84.127399 -393.62833) (xy 84.077789 -393.650987) (xy 84.025459 -393.666352)
			(xy 83.971475 -393.674114) (xy 83.916937 -393.674114) (xy 83.862953 -393.666352) (xy 83.810623 -393.650987)
			(xy 83.761013 -393.62833) (xy 83.715132 -393.598844) (xy 83.673915 -393.563129) (xy 83.6382 -393.521912)
			(xy 83.608714 -393.476031) (xy 83.586057 -393.426421) (xy 83.570692 -393.374091) (xy 83.56293 -393.320107)
			(xy 83.562444 -393.292838) (xy 83.126072 -393.292838) (xy 83.125586 -393.320107) (xy 83.117824 -393.374091)
			(xy 83.102459 -393.426421) (xy 83.079802 -393.476031) (xy 83.050316 -393.521912) (xy 83.014601 -393.563129)
			(xy 82.973384 -393.598844) (xy 82.927503 -393.62833) (xy 82.877893 -393.650987) (xy 82.825563 -393.666352)
			(xy 82.771579 -393.674114) (xy 82.717041 -393.674114) (xy 82.663057 -393.666352) (xy 82.610727 -393.650987)
			(xy 82.561117 -393.62833) (xy 82.515236 -393.598844) (xy 82.474019 -393.563129) (xy 82.438304 -393.521912)
			(xy 82.408818 -393.476031) (xy 82.386161 -393.426421) (xy 82.370796 -393.374091) (xy 82.363034 -393.320107)
			(xy 82.362548 -393.292838) (xy 81.925668 -393.292838) (xy 81.925182 -393.320089) (xy 81.917426 -393.374037)
			(xy 81.902071 -393.426332) (xy 81.879429 -393.475909) (xy 81.849963 -393.521759) (xy 81.814272 -393.56295)
			(xy 81.773081 -393.598641) (xy 81.727231 -393.628107) (xy 81.677654 -393.650749) (xy 81.625359 -393.666104)
			(xy 81.571411 -393.67386) (xy 81.516909 -393.67386) (xy 81.462961 -393.666104) (xy 81.410666 -393.650749)
			(xy 81.361089 -393.628107) (xy 81.315239 -393.598641) (xy 81.274048 -393.56295) (xy 81.238357 -393.521759)
			(xy 81.208891 -393.475909) (xy 81.186249 -393.426332) (xy 81.170894 -393.374037) (xy 81.163138 -393.320089)
			(xy 81.162652 -393.292838) (xy 80.725772 -393.292838) (xy 80.725286 -393.320089) (xy 80.71753 -393.374037)
			(xy 80.702175 -393.426332) (xy 80.679533 -393.475909) (xy 80.650067 -393.521759) (xy 80.614376 -393.56295)
			(xy 80.573185 -393.598641) (xy 80.527335 -393.628107) (xy 80.477758 -393.650749) (xy 80.425463 -393.666104)
			(xy 80.371515 -393.67386) (xy 80.317013 -393.67386) (xy 80.263065 -393.666104) (xy 80.21077 -393.650749)
			(xy 80.161193 -393.628107) (xy 80.115343 -393.598641) (xy 80.074152 -393.56295) (xy 80.038461 -393.521759)
			(xy 80.008995 -393.475909) (xy 79.986353 -393.426332) (xy 79.970998 -393.374037) (xy 79.963242 -393.320089)
			(xy 79.962756 -393.292838) (xy 66.197988 -393.292838) (xy 66.197502 -393.320089) (xy 66.189746 -393.374037)
			(xy 66.174391 -393.426332) (xy 66.151749 -393.475909) (xy 66.122283 -393.521759) (xy 66.086592 -393.56295)
			(xy 66.045401 -393.598641) (xy 65.999551 -393.628107) (xy 65.949974 -393.650749) (xy 65.897679 -393.666104)
			(xy 65.843731 -393.67386) (xy 65.789229 -393.67386) (xy 65.735281 -393.666104) (xy 65.682986 -393.650749)
			(xy 65.633409 -393.628107) (xy 65.587559 -393.598641) (xy 65.546368 -393.56295) (xy 65.510677 -393.521759)
			(xy 65.481211 -393.475909) (xy 65.458569 -393.426332) (xy 65.443214 -393.374037) (xy 65.435458 -393.320089)
			(xy 65.434972 -393.292838) (xy 64.998092 -393.292838) (xy 64.997606 -393.320089) (xy 64.98985 -393.374037)
			(xy 64.974495 -393.426332) (xy 64.951853 -393.475909) (xy 64.922387 -393.521759) (xy 64.886696 -393.56295)
			(xy 64.845505 -393.598641) (xy 64.799655 -393.628107) (xy 64.750078 -393.650749) (xy 64.697783 -393.666104)
			(xy 64.643835 -393.67386) (xy 64.589333 -393.67386) (xy 64.535385 -393.666104) (xy 64.48309 -393.650749)
			(xy 64.433513 -393.628107) (xy 64.387663 -393.598641) (xy 64.346472 -393.56295) (xy 64.310781 -393.521759)
			(xy 64.281315 -393.475909) (xy 64.258673 -393.426332) (xy 64.243318 -393.374037) (xy 64.235562 -393.320089)
			(xy 64.235076 -393.292838) (xy 63.798196 -393.292838) (xy 63.79771 -393.320107) (xy 63.789948 -393.374091)
			(xy 63.774583 -393.426421) (xy 63.751926 -393.476031) (xy 63.72244 -393.521912) (xy 63.686725 -393.563129)
			(xy 63.645508 -393.598844) (xy 63.599627 -393.62833) (xy 63.550017 -393.650987) (xy 63.497687 -393.666352)
			(xy 63.443703 -393.674114) (xy 63.389165 -393.674114) (xy 63.335181 -393.666352) (xy 63.282851 -393.650987)
			(xy 63.233241 -393.62833) (xy 63.18736 -393.598844) (xy 63.146143 -393.563129) (xy 63.110428 -393.521912)
			(xy 63.080942 -393.476031) (xy 63.058285 -393.426421) (xy 63.04292 -393.374091) (xy 63.035158 -393.320107)
			(xy 63.034672 -393.292838) (xy 62.5983 -393.292838) (xy 62.597814 -393.320107) (xy 62.590052 -393.374091)
			(xy 62.574687 -393.426421) (xy 62.55203 -393.476031) (xy 62.522544 -393.521912) (xy 62.486829 -393.563129)
			(xy 62.445612 -393.598844) (xy 62.399731 -393.62833) (xy 62.350121 -393.650987) (xy 62.297791 -393.666352)
			(xy 62.243807 -393.674114) (xy 62.189269 -393.674114) (xy 62.135285 -393.666352) (xy 62.082955 -393.650987)
			(xy 62.033345 -393.62833) (xy 61.987464 -393.598844) (xy 61.946247 -393.563129) (xy 61.910532 -393.521912)
			(xy 61.881046 -393.476031) (xy 61.858389 -393.426421) (xy 61.843024 -393.374091) (xy 61.835262 -393.320107)
			(xy 61.834776 -393.292838) (xy 61.398404 -393.292838) (xy 61.397918 -393.320107) (xy 61.390156 -393.374091)
			(xy 61.374791 -393.426421) (xy 61.352134 -393.476031) (xy 61.322648 -393.521912) (xy 61.286933 -393.563129)
			(xy 61.245716 -393.598844) (xy 61.199835 -393.62833) (xy 61.150225 -393.650987) (xy 61.097895 -393.666352)
			(xy 61.043911 -393.674114) (xy 60.989373 -393.674114) (xy 60.935389 -393.666352) (xy 60.883059 -393.650987)
			(xy 60.833449 -393.62833) (xy 60.787568 -393.598844) (xy 60.746351 -393.563129) (xy 60.710636 -393.521912)
			(xy 60.68115 -393.476031) (xy 60.658493 -393.426421) (xy 60.643128 -393.374091) (xy 60.635366 -393.320107)
			(xy 60.63488 -393.292838) (xy 60.198508 -393.292838) (xy 60.198022 -393.320107) (xy 60.19026 -393.374091)
			(xy 60.174895 -393.426421) (xy 60.152238 -393.476031) (xy 60.122752 -393.521912) (xy 60.087037 -393.563129)
			(xy 60.04582 -393.598844) (xy 59.999939 -393.62833) (xy 59.950329 -393.650987) (xy 59.897999 -393.666352)
			(xy 59.844015 -393.674114) (xy 59.789477 -393.674114) (xy 59.735493 -393.666352) (xy 59.683163 -393.650987)
			(xy 59.633553 -393.62833) (xy 59.587672 -393.598844) (xy 59.546455 -393.563129) (xy 59.51074 -393.521912)
			(xy 59.481254 -393.476031) (xy 59.458597 -393.426421) (xy 59.443232 -393.374091) (xy 59.43547 -393.320107)
			(xy 59.434984 -393.292838) (xy 58.998104 -393.292838) (xy 58.997618 -393.320089) (xy 58.989862 -393.374037)
			(xy 58.974507 -393.426332) (xy 58.951865 -393.475909) (xy 58.922399 -393.521759) (xy 58.886708 -393.56295)
			(xy 58.845517 -393.598641) (xy 58.799667 -393.628107) (xy 58.75009 -393.650749) (xy 58.697795 -393.666104)
			(xy 58.643847 -393.67386) (xy 58.589345 -393.67386) (xy 58.535397 -393.666104) (xy 58.483102 -393.650749)
			(xy 58.433525 -393.628107) (xy 58.387675 -393.598641) (xy 58.346484 -393.56295) (xy 58.310793 -393.521759)
			(xy 58.281327 -393.475909) (xy 58.258685 -393.426332) (xy 58.24333 -393.374037) (xy 58.235574 -393.320089)
			(xy 58.235088 -393.292838) (xy 57.798208 -393.292838) (xy 57.797722 -393.320089) (xy 57.789966 -393.374037)
			(xy 57.774611 -393.426332) (xy 57.751969 -393.475909) (xy 57.722503 -393.521759) (xy 57.686812 -393.56295)
			(xy 57.645621 -393.598641) (xy 57.599771 -393.628107) (xy 57.550194 -393.650749) (xy 57.497899 -393.666104)
			(xy 57.443951 -393.67386) (xy 57.389449 -393.67386) (xy 57.335501 -393.666104) (xy 57.283206 -393.650749)
			(xy 57.233629 -393.628107) (xy 57.187779 -393.598641) (xy 57.146588 -393.56295) (xy 57.110897 -393.521759)
			(xy 57.081431 -393.475909) (xy 57.058789 -393.426332) (xy 57.043434 -393.374037) (xy 57.035678 -393.320089)
			(xy 57.035192 -393.292838) (xy 56.598312 -393.292838) (xy 56.597826 -393.320107) (xy 56.590064 -393.374091)
			(xy 56.574699 -393.426421) (xy 56.552042 -393.476031) (xy 56.522556 -393.521912) (xy 56.486841 -393.563129)
			(xy 56.445624 -393.598844) (xy 56.399743 -393.62833) (xy 56.350133 -393.650987) (xy 56.297803 -393.666352)
			(xy 56.243819 -393.674114) (xy 56.189281 -393.674114) (xy 56.135297 -393.666352) (xy 56.082967 -393.650987)
			(xy 56.033357 -393.62833) (xy 55.987476 -393.598844) (xy 55.946259 -393.563129) (xy 55.910544 -393.521912)
			(xy 55.881058 -393.476031) (xy 55.858401 -393.426421) (xy 55.843036 -393.374091) (xy 55.835274 -393.320107)
			(xy 55.834788 -393.292838) (xy 55.398416 -393.292838) (xy 55.39793 -393.320107) (xy 55.390168 -393.374091)
			(xy 55.374803 -393.426421) (xy 55.352146 -393.476031) (xy 55.32266 -393.521912) (xy 55.286945 -393.563129)
			(xy 55.245728 -393.598844) (xy 55.199847 -393.62833) (xy 55.150237 -393.650987) (xy 55.097907 -393.666352)
			(xy 55.043923 -393.674114) (xy 54.989385 -393.674114) (xy 54.935401 -393.666352) (xy 54.883071 -393.650987)
			(xy 54.833461 -393.62833) (xy 54.78758 -393.598844) (xy 54.746363 -393.563129) (xy 54.710648 -393.521912)
			(xy 54.681162 -393.476031) (xy 54.658505 -393.426421) (xy 54.64314 -393.374091) (xy 54.635378 -393.320107)
			(xy 54.634892 -393.292838) (xy 54.198012 -393.292838) (xy 54.197526 -393.320089) (xy 54.18977 -393.374037)
			(xy 54.174415 -393.426332) (xy 54.151773 -393.475909) (xy 54.122307 -393.521759) (xy 54.086616 -393.56295)
			(xy 54.045425 -393.598641) (xy 53.999575 -393.628107) (xy 53.949998 -393.650749) (xy 53.897703 -393.666104)
			(xy 53.843755 -393.67386) (xy 53.789253 -393.67386) (xy 53.735305 -393.666104) (xy 53.68301 -393.650749)
			(xy 53.633433 -393.628107) (xy 53.587583 -393.598641) (xy 53.546392 -393.56295) (xy 53.510701 -393.521759)
			(xy 53.481235 -393.475909) (xy 53.458593 -393.426332) (xy 53.443238 -393.374037) (xy 53.435482 -393.320089)
			(xy 53.434996 -393.292838) (xy 52.998116 -393.292838) (xy 52.99763 -393.320089) (xy 52.989874 -393.374037)
			(xy 52.974519 -393.426332) (xy 52.951877 -393.475909) (xy 52.922411 -393.521759) (xy 52.88672 -393.56295)
			(xy 52.845529 -393.598641) (xy 52.799679 -393.628107) (xy 52.750102 -393.650749) (xy 52.697807 -393.666104)
			(xy 52.643859 -393.67386) (xy 52.589357 -393.67386) (xy 52.535409 -393.666104) (xy 52.483114 -393.650749)
			(xy 52.433537 -393.628107) (xy 52.387687 -393.598641) (xy 52.346496 -393.56295) (xy 52.310805 -393.521759)
			(xy 52.281339 -393.475909) (xy 52.258697 -393.426332) (xy 52.243342 -393.374037) (xy 52.235586 -393.320089)
			(xy 52.2351 -393.292838) (xy 51.79822 -393.292838) (xy 51.797734 -393.320107) (xy 51.789972 -393.374091)
			(xy 51.774607 -393.426421) (xy 51.75195 -393.476031) (xy 51.722464 -393.521912) (xy 51.686749 -393.563129)
			(xy 51.645532 -393.598844) (xy 51.599651 -393.62833) (xy 51.550041 -393.650987) (xy 51.497711 -393.666352)
			(xy 51.443727 -393.674114) (xy 51.389189 -393.674114) (xy 51.335205 -393.666352) (xy 51.282875 -393.650987)
			(xy 51.233265 -393.62833) (xy 51.187384 -393.598844) (xy 51.146167 -393.563129) (xy 51.110452 -393.521912)
			(xy 51.080966 -393.476031) (xy 51.058309 -393.426421) (xy 51.042944 -393.374091) (xy 51.035182 -393.320107)
			(xy 51.034696 -393.292838) (xy 50.598324 -393.292838) (xy 50.597838 -393.320107) (xy 50.590076 -393.374091)
			(xy 50.574711 -393.426421) (xy 50.552054 -393.476031) (xy 50.522568 -393.521912) (xy 50.486853 -393.563129)
			(xy 50.445636 -393.598844) (xy 50.399755 -393.62833) (xy 50.350145 -393.650987) (xy 50.297815 -393.666352)
			(xy 50.243831 -393.674114) (xy 50.189293 -393.674114) (xy 50.135309 -393.666352) (xy 50.082979 -393.650987)
			(xy 50.033369 -393.62833) (xy 49.987488 -393.598844) (xy 49.946271 -393.563129) (xy 49.910556 -393.521912)
			(xy 49.88107 -393.476031) (xy 49.858413 -393.426421) (xy 49.843048 -393.374091) (xy 49.835286 -393.320107)
			(xy 49.8348 -393.292838) (xy 49.39792 -393.292838) (xy 49.397434 -393.320089) (xy 49.389678 -393.374037)
			(xy 49.374323 -393.426332) (xy 49.351681 -393.475909) (xy 49.322215 -393.521759) (xy 49.286524 -393.56295)
			(xy 49.245333 -393.598641) (xy 49.199483 -393.628107) (xy 49.149906 -393.650749) (xy 49.097611 -393.666104)
			(xy 49.043663 -393.67386) (xy 48.989161 -393.67386) (xy 48.935213 -393.666104) (xy 48.882918 -393.650749)
			(xy 48.833341 -393.628107) (xy 48.787491 -393.598641) (xy 48.7463 -393.56295) (xy 48.710609 -393.521759)
			(xy 48.681143 -393.475909) (xy 48.658501 -393.426332) (xy 48.643146 -393.374037) (xy 48.63539 -393.320089)
			(xy 48.634904 -393.292838) (xy 48.198024 -393.292838) (xy 48.197538 -393.320089) (xy 48.189782 -393.374037)
			(xy 48.174427 -393.426332) (xy 48.151785 -393.475909) (xy 48.122319 -393.521759) (xy 48.086628 -393.56295)
			(xy 48.045437 -393.598641) (xy 47.999587 -393.628107) (xy 47.95001 -393.650749) (xy 47.897715 -393.666104)
			(xy 47.843767 -393.67386) (xy 47.789265 -393.67386) (xy 47.735317 -393.666104) (xy 47.683022 -393.650749)
			(xy 47.633445 -393.628107) (xy 47.587595 -393.598641) (xy 47.546404 -393.56295) (xy 47.510713 -393.521759)
			(xy 47.481247 -393.475909) (xy 47.458605 -393.426332) (xy 47.44325 -393.374037) (xy 47.435494 -393.320089)
			(xy 47.435008 -393.292838) (xy 21.426678 -393.292838) (xy 33.019445 -404.885605) (xy 37.250362 -404.885605)
			(xy 37.250362 -404.699771) (xy 37.258357 -404.514108) (xy 37.274332 -404.328962) (xy 37.298258 -404.144674)
			(xy 37.33009 -403.961586) (xy 37.36977 -403.780037) (xy 37.417223 -403.600363) (xy 37.472363 -403.422897)
			(xy 37.535086 -403.247968) (xy 37.605277 -403.075899) (xy 37.682806 -402.90701) (xy 37.767529 -402.741612)
			(xy 37.85929 -402.580012) (xy 37.957918 -402.42251) (xy 38.063231 -402.269396) (xy 38.175033 -402.120956)
			(xy 38.293118 -401.977462) (xy 38.417268 -401.839182) (xy 38.547251 -401.706371) (xy 38.682828 -401.579275)
			(xy 38.823748 -401.45813) (xy 38.969748 -401.343159) (xy 39.12056 -401.234576) (xy 39.275904 -401.132583)
			(xy 39.435492 -401.037366) (xy 39.599029 -400.949104) (xy 39.766211 -400.867959) (xy 39.93673 -400.794082)
			(xy 40.110269 -400.727609) (xy 40.286508 -400.668664) (xy 40.465119 -400.617356) (xy 40.645772 -400.573779)
			(xy 40.828133 -400.538015) (xy 41.011863 -400.510129) (xy 41.196623 -400.490174) (xy 41.38207 -400.478186)
			(xy 41.567862 -400.474188) (xy 41.753654 -400.478186) (xy 41.939101 -400.490174) (xy 42.108501 -400.50847)
			(xy 103.35895 -400.50847) (xy 103.359461 -400.476693) (xy 103.367388 -400.413634) (xy 103.383113 -400.352055)
			(xy 103.406392 -400.292917) (xy 103.436862 -400.237142) (xy 103.474047 -400.1856) (xy 103.495348 -400.162014)
			(xy 103.50159 -400.154785) (xy 103.508577 -400.137022) (xy 103.508569 -400.117934) (xy 103.501566 -400.100177)
			(xy 103.495348 -400.092926) (xy 103.474038 -400.069346) (xy 103.436845 -400.017807) (xy 103.406369 -399.962033)
			(xy 103.383087 -399.902893) (xy 103.367362 -399.841311) (xy 103.359439 -399.778249) (xy 103.35895 -399.74647)
			(xy 103.359451 -399.714541) (xy 103.367455 -399.651186) (xy 103.383336 -399.589334) (xy 103.406844 -399.52996)
			(xy 103.437608 -399.474001) (xy 103.475142 -399.422339) (xy 103.518856 -399.375788) (xy 103.56806 -399.335083)
			(xy 103.621977 -399.300866) (xy 103.679758 -399.273677) (xy 103.740491 -399.253944) (xy 103.803218 -399.241978)
			(xy 103.86695 -399.237968) (xy 103.930682 -399.241978) (xy 103.993409 -399.253944) (xy 104.054142 -399.273677)
			(xy 104.111923 -399.300866) (xy 104.16584 -399.335083) (xy 104.215044 -399.375788) (xy 104.258758 -399.422339)
			(xy 104.296292 -399.474001) (xy 104.327056 -399.52996) (xy 104.350564 -399.589334) (xy 104.366445 -399.651186)
			(xy 104.374449 -399.714541) (xy 104.37495 -399.74647) (xy 104.374464 -399.778248) (xy 104.366532 -399.841308)
			(xy 104.350802 -399.902887) (xy 104.327518 -399.962025) (xy 104.297044 -400.0178) (xy 104.259855 -400.06934)
			(xy 104.238552 -400.092926) (xy 104.232369 -400.1002) (xy 104.225372 -400.117942) (xy 104.225363 -400.137014)
			(xy 104.232345 -400.154763) (xy 104.238552 -400.162014) (xy 104.259833 -400.185619) (xy 104.29703 -400.237152)
			(xy 104.32751 -400.292922) (xy 104.350797 -400.352057) (xy 104.366528 -400.413634) (xy 104.374457 -400.476693)
			(xy 104.37495 -400.50847) (xy 104.374449 -400.540399) (xy 104.366445 -400.603754) (xy 104.350564 -400.665606)
			(xy 104.327056 -400.72498) (xy 104.296292 -400.780939) (xy 104.258758 -400.832601) (xy 104.215044 -400.879152)
			(xy 104.16584 -400.919857) (xy 104.111923 -400.954074) (xy 104.054142 -400.981263) (xy 103.993409 -401.000996)
			(xy 103.930682 -401.012962) (xy 103.86695 -401.016972) (xy 103.803218 -401.012962) (xy 103.740491 -401.000996)
			(xy 103.679758 -400.981263) (xy 103.621977 -400.954074) (xy 103.56806 -400.919857) (xy 103.518856 -400.879152)
			(xy 103.475142 -400.832601) (xy 103.437608 -400.780939) (xy 103.406844 -400.72498) (xy 103.383336 -400.665606)
			(xy 103.367455 -400.603754) (xy 103.359451 -400.540399) (xy 103.35895 -400.50847) (xy 42.108501 -400.50847)
			(xy 42.123861 -400.510129) (xy 42.307591 -400.538015) (xy 42.489952 -400.573779) (xy 42.670605 -400.617356)
			(xy 42.849216 -400.668664) (xy 43.025455 -400.727609) (xy 43.198994 -400.794082) (xy 43.369513 -400.867959)
			(xy 43.536695 -400.949104) (xy 43.700232 -401.037366) (xy 43.85982 -401.132583) (xy 44.015164 -401.234576)
			(xy 44.165976 -401.343159) (xy 44.311976 -401.45813) (xy 44.452896 -401.579275) (xy 44.588473 -401.706371)
			(xy 44.718456 -401.839182) (xy 44.842606 -401.977462) (xy 44.960691 -402.120956) (xy 45.072493 -402.269396)
			(xy 45.177806 -402.42251) (xy 45.276434 -402.580012) (xy 45.368195 -402.741612) (xy 45.452918 -402.90701)
			(xy 45.530447 -403.075899) (xy 45.600638 -403.247968) (xy 45.663361 -403.422897) (xy 45.718501 -403.600363)
			(xy 45.765954 -403.780037) (xy 45.805634 -403.961586) (xy 45.837466 -404.144674) (xy 45.861392 -404.328962)
			(xy 45.875438 -404.491748) (xy 47.413198 -404.491748) (xy 47.413198 -404.437252) (xy 47.420953 -404.38331)
			(xy 47.436306 -404.331021) (xy 47.458943 -404.281449) (xy 47.488404 -404.235603) (xy 47.52409 -404.194416)
			(xy 47.565274 -404.158726) (xy 47.611117 -404.12926) (xy 47.660687 -404.106618) (xy 47.712975 -404.091261)
			(xy 47.766916 -404.083501) (xy 47.794164 -404.083012) (xy 48.657764 -404.083012) (xy 48.68502 -404.083432)
			(xy 48.738978 -404.091186) (xy 48.791283 -404.106539) (xy 48.84087 -404.129181) (xy 48.88673 -404.15865)
			(xy 48.927929 -404.194345) (xy 48.963629 -404.235541) (xy 48.993102 -404.281398) (xy 49.015748 -404.330984)
			(xy 49.031107 -404.383287) (xy 49.038865 -404.437244) (xy 49.038865 -404.491752) (xy 50.476375 -404.491752)
			(xy 50.476375 -404.437248) (xy 50.484132 -404.3833) (xy 50.499487 -404.331005) (xy 50.522129 -404.281427)
			(xy 50.551596 -404.235576) (xy 50.587288 -404.194385) (xy 50.628479 -404.158693) (xy 50.67433 -404.129227)
			(xy 50.723908 -404.106586) (xy 50.776204 -404.091231) (xy 50.830152 -404.083475) (xy 50.857404 -404.083012)
			(xy 51.721004 -404.083012) (xy 51.748256 -404.083458) (xy 51.802207 -404.091215) (xy 51.854504 -404.106572)
			(xy 51.904083 -404.129214) (xy 51.949935 -404.158682) (xy 51.991127 -404.194376) (xy 52.02682 -404.235568)
			(xy 52.056288 -404.281421) (xy 52.07893 -404.331) (xy 52.094285 -404.383297) (xy 52.102042 -404.437248)
			(xy 52.102042 -404.491752) (xy 52.102042 -404.491753) (xy 53.539575 -404.491753) (xy 53.539575 -404.437247)
			(xy 53.547333 -404.383295) (xy 53.562691 -404.330996) (xy 53.585335 -404.281416) (xy 53.614806 -404.235563)
			(xy 53.650502 -404.194371) (xy 53.691698 -404.158679) (xy 53.737554 -404.129214) (xy 53.787137 -404.106575)
			(xy 53.839438 -404.091224) (xy 53.893391 -404.083472) (xy 53.920644 -404.083012) (xy 54.784244 -404.083012)
			(xy 54.811495 -404.083461) (xy 54.86544 -404.091223) (xy 54.917733 -404.106583) (xy 54.967307 -404.129227)
			(xy 55.013154 -404.158696) (xy 55.054341 -404.19439) (xy 55.09003 -404.235581) (xy 55.119494 -404.281432)
			(xy 55.142133 -404.331009) (xy 55.157487 -404.383303) (xy 55.165242 -404.437249) (xy 55.165242 -404.491749)
			(xy 56.602898 -404.491749) (xy 56.602898 -404.437251) (xy 56.610654 -404.383308) (xy 56.626007 -404.331017)
			(xy 56.648646 -404.281443) (xy 56.678109 -404.235596) (xy 56.713797 -404.194409) (xy 56.754983 -404.158719)
			(xy 56.800829 -404.129254) (xy 56.850402 -404.106613) (xy 56.902692 -404.091257) (xy 56.956635 -404.083499)
			(xy 56.983884 -404.083012) (xy 57.847484 -404.083012) (xy 57.874739 -404.083434) (xy 57.928695 -404.091189)
			(xy 57.980997 -404.106545) (xy 58.030582 -404.129188) (xy 58.07644 -404.158657) (xy 58.117636 -404.194352)
			(xy 58.153334 -404.235548) (xy 58.182805 -404.281404) (xy 58.20545 -404.330988) (xy 58.220807 -404.38329)
			(xy 58.228565 -404.437245) (xy 58.228565 -404.491753) (xy 59.666075 -404.491753) (xy 59.666075 -404.437247)
			(xy 59.673833 -404.383297) (xy 59.689189 -404.331) (xy 59.711832 -404.281421) (xy 59.741301 -404.235569)
			(xy 59.776995 -404.194378) (xy 59.818188 -404.158686) (xy 59.864042 -404.129221) (xy 59.913623 -404.106581)
			(xy 59.965921 -404.091227) (xy 60.019871 -404.083474) (xy 60.047124 -404.083012) (xy 60.910724 -404.083012)
			(xy 60.937976 -404.083459) (xy 60.991924 -404.091219) (xy 61.044218 -404.106577) (xy 61.093795 -404.129221)
			(xy 61.139645 -404.158689) (xy 61.180834 -404.194383) (xy 61.216525 -404.235575) (xy 61.245991 -404.281426)
			(xy 61.268631 -404.331004) (xy 61.283986 -404.3833) (xy 61.291742 -404.437248) (xy 61.291742 -404.491748)
			(xy 62.729398 -404.491748) (xy 62.729398 -404.437252) (xy 62.737153 -404.38331) (xy 62.752506 -404.331021)
			(xy 62.775143 -404.281449) (xy 62.804604 -404.235603) (xy 62.84029 -404.194416) (xy 62.881474 -404.158726)
			(xy 62.927317 -404.12926) (xy 62.976887 -404.106618) (xy 63.029175 -404.091261) (xy 63.083116 -404.083501)
			(xy 63.110364 -404.083012) (xy 63.973964 -404.083012) (xy 64.00122 -404.083432) (xy 64.055178 -404.091186)
			(xy 64.107483 -404.106539) (xy 64.15707 -404.129181) (xy 64.20293 -404.15865) (xy 64.244129 -404.194345)
			(xy 64.279829 -404.235541) (xy 64.309302 -404.281398) (xy 64.331948 -404.330984) (xy 64.347307 -404.383287)
			(xy 64.355065 -404.437244) (xy 64.355065 -404.491752) (xy 65.792575 -404.491752) (xy 65.792575 -404.437248)
			(xy 65.800332 -404.3833) (xy 65.815687 -404.331005) (xy 65.838329 -404.281427) (xy 65.867796 -404.235576)
			(xy 65.903488 -404.194385) (xy 65.944679 -404.158693) (xy 65.99053 -404.129227) (xy 66.040108 -404.106586)
			(xy 66.092404 -404.091231) (xy 66.146352 -404.083475) (xy 66.173604 -404.083012) (xy 67.037204 -404.083012)
			(xy 67.064456 -404.083458) (xy 67.118407 -404.091215) (xy 67.170704 -404.106572) (xy 67.220283 -404.129214)
			(xy 67.266135 -404.158682) (xy 67.307327 -404.194376) (xy 67.34302 -404.235568) (xy 67.372488 -404.281421)
			(xy 67.39513 -404.331) (xy 67.410485 -404.383297) (xy 67.418242 -404.437248) (xy 67.418242 -404.491752)
			(xy 67.418242 -404.491753) (xy 68.855775 -404.491753) (xy 68.855775 -404.437247) (xy 68.863533 -404.383295)
			(xy 68.878891 -404.330996) (xy 68.901535 -404.281416) (xy 68.931006 -404.235563) (xy 68.966702 -404.194371)
			(xy 69.007898 -404.158679) (xy 69.053754 -404.129214) (xy 69.103337 -404.106575) (xy 69.155638 -404.091224)
			(xy 69.209591 -404.083472) (xy 69.236844 -404.083012) (xy 70.100444 -404.083012) (xy 70.127695 -404.083461)
			(xy 70.18164 -404.091223) (xy 70.233933 -404.106583) (xy 70.283507 -404.129227) (xy 70.329354 -404.158696)
			(xy 70.370541 -404.19439) (xy 70.40623 -404.235581) (xy 70.435694 -404.281432) (xy 70.458333 -404.331009)
			(xy 70.473687 -404.383303) (xy 70.481442 -404.437249) (xy 70.481442 -404.491749) (xy 71.919098 -404.491749)
			(xy 71.919098 -404.437251) (xy 71.926854 -404.383308) (xy 71.942207 -404.331017) (xy 71.964846 -404.281443)
			(xy 71.994309 -404.235596) (xy 72.029997 -404.194409) (xy 72.071183 -404.158719) (xy 72.117029 -404.129254)
			(xy 72.166602 -404.106613) (xy 72.218892 -404.091257) (xy 72.272835 -404.083499) (xy 72.300084 -404.083012)
			(xy 73.163684 -404.083012) (xy 73.190939 -404.083434) (xy 73.244895 -404.091189) (xy 73.297197 -404.106545)
			(xy 73.346782 -404.129188) (xy 73.39264 -404.158657) (xy 73.433836 -404.194352) (xy 73.469534 -404.235548)
			(xy 73.499005 -404.281404) (xy 73.52165 -404.330988) (xy 73.537007 -404.38329) (xy 73.544765 -404.437245)
			(xy 73.544765 -404.491753) (xy 74.982275 -404.491753) (xy 74.982275 -404.437247) (xy 74.990033 -404.383297)
			(xy 75.005389 -404.331) (xy 75.028032 -404.281421) (xy 75.057501 -404.235569) (xy 75.093195 -404.194378)
			(xy 75.134388 -404.158686) (xy 75.180242 -404.129221) (xy 75.229823 -404.106581) (xy 75.282121 -404.091227)
			(xy 75.336071 -404.083474) (xy 75.363324 -404.083012) (xy 76.226924 -404.083012) (xy 76.254176 -404.083459)
			(xy 76.308124 -404.091219) (xy 76.360418 -404.106577) (xy 76.409995 -404.129221) (xy 76.455845 -404.158689)
			(xy 76.497034 -404.194383) (xy 76.532725 -404.235575) (xy 76.562191 -404.281426) (xy 76.584831 -404.331004)
			(xy 76.600186 -404.3833) (xy 76.607942 -404.437248) (xy 76.607942 -404.491748) (xy 78.045598 -404.491748)
			(xy 78.045598 -404.437252) (xy 78.053353 -404.38331) (xy 78.068706 -404.331021) (xy 78.091343 -404.281449)
			(xy 78.120804 -404.235603) (xy 78.15649 -404.194416) (xy 78.197674 -404.158726) (xy 78.243517 -404.12926)
			(xy 78.293087 -404.106618) (xy 78.345375 -404.091261) (xy 78.399316 -404.083501) (xy 78.426564 -404.083012)
			(xy 79.290164 -404.083012) (xy 79.31742 -404.083432) (xy 79.371378 -404.091186) (xy 79.423683 -404.106539)
			(xy 79.47327 -404.129181) (xy 79.51913 -404.15865) (xy 79.560329 -404.194345) (xy 79.596029 -404.235541)
			(xy 79.625502 -404.281398) (xy 79.648148 -404.330984) (xy 79.663507 -404.383287) (xy 79.671265 -404.437244)
			(xy 79.671265 -404.491752) (xy 81.108775 -404.491752) (xy 81.108775 -404.437248) (xy 81.116532 -404.3833)
			(xy 81.131887 -404.331005) (xy 81.154529 -404.281427) (xy 81.183996 -404.235576) (xy 81.219688 -404.194385)
			(xy 81.260879 -404.158693) (xy 81.30673 -404.129227) (xy 81.356308 -404.106586) (xy 81.408604 -404.091231)
			(xy 81.462552 -404.083475) (xy 81.489804 -404.083012) (xy 82.353404 -404.083012) (xy 82.380656 -404.083458)
			(xy 82.434607 -404.091215) (xy 82.486904 -404.106572) (xy 82.536483 -404.129214) (xy 82.582335 -404.158682)
			(xy 82.623527 -404.194376) (xy 82.65922 -404.235568) (xy 82.688688 -404.281421) (xy 82.71133 -404.331)
			(xy 82.726685 -404.383297) (xy 82.734442 -404.437248) (xy 82.734442 -404.491752) (xy 82.734442 -404.491753)
			(xy 84.171975 -404.491753) (xy 84.171975 -404.437247) (xy 84.179733 -404.383295) (xy 84.195091 -404.330996)
			(xy 84.217735 -404.281416) (xy 84.247206 -404.235563) (xy 84.282902 -404.194371) (xy 84.324098 -404.158679)
			(xy 84.369954 -404.129214) (xy 84.419537 -404.106575) (xy 84.471838 -404.091224) (xy 84.525791 -404.083472)
			(xy 84.553044 -404.083012) (xy 85.416644 -404.083012) (xy 85.443895 -404.083461) (xy 85.49784 -404.091223)
			(xy 85.550133 -404.106583) (xy 85.599707 -404.129227) (xy 85.645554 -404.158696) (xy 85.686741 -404.19439)
			(xy 85.72243 -404.235581) (xy 85.751894 -404.281432) (xy 85.774533 -404.331009) (xy 85.789887 -404.383303)
			(xy 85.797642 -404.437249) (xy 85.797642 -404.491749) (xy 87.235298 -404.491749) (xy 87.235298 -404.437251)
			(xy 87.243054 -404.383308) (xy 87.258407 -404.331017) (xy 87.281046 -404.281443) (xy 87.310509 -404.235596)
			(xy 87.346197 -404.194409) (xy 87.387383 -404.158719) (xy 87.433229 -404.129254) (xy 87.482802 -404.106613)
			(xy 87.535092 -404.091257) (xy 87.589035 -404.083499) (xy 87.616284 -404.083012) (xy 88.479884 -404.083012)
			(xy 88.507139 -404.083434) (xy 88.561095 -404.091189) (xy 88.613397 -404.106545) (xy 88.662982 -404.129188)
			(xy 88.70884 -404.158657) (xy 88.750036 -404.194352) (xy 88.785734 -404.235548) (xy 88.815205 -404.281404)
			(xy 88.83785 -404.330988) (xy 88.853207 -404.38329) (xy 88.860965 -404.437245) (xy 88.860965 -404.491753)
			(xy 90.298475 -404.491753) (xy 90.298475 -404.437247) (xy 90.306233 -404.383297) (xy 90.321589 -404.331)
			(xy 90.344232 -404.281421) (xy 90.373701 -404.235569) (xy 90.409395 -404.194378) (xy 90.450588 -404.158686)
			(xy 90.496442 -404.129221) (xy 90.546023 -404.106581) (xy 90.598321 -404.091227) (xy 90.652271 -404.083474)
			(xy 90.679524 -404.083012) (xy 91.543124 -404.083012) (xy 91.570376 -404.083459) (xy 91.624324 -404.091219)
			(xy 91.676618 -404.106577) (xy 91.726195 -404.129221) (xy 91.772045 -404.158689) (xy 91.813234 -404.194383)
			(xy 91.848925 -404.235575) (xy 91.878391 -404.281426) (xy 91.901031 -404.331004) (xy 91.916386 -404.3833)
			(xy 91.924142 -404.437248) (xy 91.924142 -404.491748) (xy 93.361798 -404.491748) (xy 93.361798 -404.437252)
			(xy 93.369553 -404.38331) (xy 93.384906 -404.331021) (xy 93.407543 -404.281449) (xy 93.437004 -404.235603)
			(xy 93.47269 -404.194416) (xy 93.513874 -404.158726) (xy 93.559717 -404.12926) (xy 93.609287 -404.106618)
			(xy 93.661575 -404.091261) (xy 93.715516 -404.083501) (xy 93.742764 -404.083012) (xy 94.606364 -404.083012)
			(xy 94.63362 -404.083432) (xy 94.687578 -404.091186) (xy 94.739883 -404.106539) (xy 94.78947 -404.129181)
			(xy 94.83533 -404.15865) (xy 94.876529 -404.194345) (xy 94.912229 -404.235541) (xy 94.941702 -404.281398)
			(xy 94.964348 -404.330984) (xy 94.979707 -404.383287) (xy 94.987465 -404.437244) (xy 94.987465 -404.491752)
			(xy 114.513075 -404.491752) (xy 114.513075 -404.437248) (xy 114.520832 -404.3833) (xy 114.536188 -404.331004)
			(xy 114.558829 -404.281426) (xy 114.588296 -404.235575) (xy 114.623989 -404.194384) (xy 114.66518 -404.158693)
			(xy 114.711031 -404.129226) (xy 114.76061 -404.106585) (xy 114.812906 -404.091231) (xy 114.866854 -404.083475)
			(xy 114.894106 -404.083012) (xy 115.757706 -404.083012) (xy 115.784958 -404.083458) (xy 115.838908 -404.091216)
			(xy 115.891205 -404.106572) (xy 115.940784 -404.129215) (xy 115.986636 -404.158683) (xy 116.027828 -404.194376)
			(xy 116.063521 -404.235569) (xy 116.092988 -404.281421) (xy 116.11563 -404.331001) (xy 116.130985 -404.383298)
			(xy 116.138742 -404.437248) (xy 116.138742 -404.491752) (xy 116.138742 -404.491754) (xy 117.576275 -404.491754)
			(xy 117.576275 -404.437246) (xy 117.584033 -404.383294) (xy 117.599391 -404.330996) (xy 117.622035 -404.281415)
			(xy 117.651506 -404.235562) (xy 117.687203 -404.19437) (xy 117.728399 -404.158679) (xy 117.774255 -404.129213)
			(xy 117.823839 -404.106575) (xy 117.876139 -404.091223) (xy 117.930092 -404.083472) (xy 117.957346 -404.083012)
			(xy 118.820946 -404.083012) (xy 118.848197 -404.083461) (xy 118.902142 -404.091223) (xy 118.954434 -404.106583)
			(xy 119.004008 -404.129228) (xy 119.049855 -404.158697) (xy 119.091042 -404.194391) (xy 119.12673 -404.235582)
			(xy 119.156194 -404.281432) (xy 119.178833 -404.331009) (xy 119.194187 -404.383303) (xy 119.201942 -404.437249)
			(xy 119.201942 -404.491749) (xy 120.639598 -404.491749) (xy 120.639598 -404.437251) (xy 120.647354 -404.383307)
			(xy 120.662708 -404.331016) (xy 120.685346 -404.281443) (xy 120.71481 -404.235596) (xy 120.750498 -404.194408)
			(xy 120.791684 -404.158718) (xy 120.83753 -404.129253) (xy 120.887103 -404.106612) (xy 120.939394 -404.091257)
			(xy 120.993337 -404.083499) (xy 121.020586 -404.083012) (xy 121.884186 -404.083012) (xy 121.911441 -404.083434)
			(xy 121.965396 -404.09119) (xy 122.017699 -404.106545) (xy 122.067283 -404.129188) (xy 122.113141 -404.158657)
			(xy 122.154337 -404.194353) (xy 122.190034 -404.235548) (xy 122.219505 -404.281405) (xy 122.24215 -404.330988)
			(xy 122.257507 -404.38329) (xy 122.265265 -404.437245) (xy 122.265265 -404.491753) (xy 123.702775 -404.491753)
			(xy 123.702775 -404.437247) (xy 123.710533 -404.383297) (xy 123.725889 -404.331) (xy 123.748532 -404.281421)
			(xy 123.778001 -404.235569) (xy 123.813696 -404.194377) (xy 123.854889 -404.158686) (xy 123.900743 -404.12922)
			(xy 123.950324 -404.10658) (xy 124.002622 -404.091227) (xy 124.056573 -404.083474) (xy 124.083826 -404.083012)
			(xy 124.947426 -404.083012) (xy 124.974677 -404.08346) (xy 125.028625 -404.09122) (xy 125.08092 -404.106578)
			(xy 125.130496 -404.129222) (xy 125.176346 -404.15869) (xy 125.217535 -404.194383) (xy 125.253226 -404.235575)
			(xy 125.282691 -404.281427) (xy 125.305331 -404.331005) (xy 125.320686 -404.3833) (xy 125.328442 -404.437249)
			(xy 125.328442 -404.491748) (xy 126.766098 -404.491748) (xy 126.766098 -404.437252) (xy 126.773853 -404.38331)
			(xy 126.789206 -404.331021) (xy 126.811843 -404.281448) (xy 126.841305 -404.235602) (xy 126.876991 -404.194415)
			(xy 126.918175 -404.158725) (xy 126.964018 -404.12926) (xy 127.013589 -404.106618) (xy 127.065877 -404.091261)
			(xy 127.119818 -404.083501) (xy 127.147066 -404.083012) (xy 128.010666 -404.083012) (xy 128.037922 -404.083433)
			(xy 128.091879 -404.091186) (xy 128.144184 -404.10654) (xy 128.193771 -404.129182) (xy 128.239631 -404.15865)
			(xy 128.28083 -404.194346) (xy 128.316529 -404.235542) (xy 128.346002 -404.281399) (xy 128.368648 -404.330984)
			(xy 128.384007 -404.383287) (xy 128.391765 -404.437244) (xy 128.391765 -404.491752) (xy 129.829275 -404.491752)
			(xy 129.829275 -404.437248) (xy 129.837032 -404.3833) (xy 129.852388 -404.331004) (xy 129.875029 -404.281426)
			(xy 129.904496 -404.235575) (xy 129.940189 -404.194384) (xy 129.98138 -404.158693) (xy 130.027231 -404.129226)
			(xy 130.07681 -404.106585) (xy 130.129106 -404.091231) (xy 130.183054 -404.083475) (xy 130.210306 -404.083012)
			(xy 131.073906 -404.083012) (xy 131.101158 -404.083458) (xy 131.155108 -404.091216) (xy 131.207405 -404.106572)
			(xy 131.256984 -404.129215) (xy 131.302836 -404.158683) (xy 131.344028 -404.194376) (xy 131.379721 -404.235569)
			(xy 131.409188 -404.281421) (xy 131.43183 -404.331001) (xy 131.447185 -404.383298) (xy 131.454942 -404.437248)
			(xy 131.454942 -404.491752) (xy 131.454942 -404.491754) (xy 132.892475 -404.491754) (xy 132.892475 -404.437246)
			(xy 132.900233 -404.383294) (xy 132.915591 -404.330996) (xy 132.938235 -404.281415) (xy 132.967706 -404.235562)
			(xy 133.003403 -404.19437) (xy 133.044599 -404.158679) (xy 133.090455 -404.129213) (xy 133.140039 -404.106575)
			(xy 133.192339 -404.091223) (xy 133.246292 -404.083472) (xy 133.273546 -404.083012) (xy 134.137146 -404.083012)
			(xy 134.164397 -404.083461) (xy 134.218342 -404.091223) (xy 134.270634 -404.106583) (xy 134.320208 -404.129228)
			(xy 134.366055 -404.158697) (xy 134.407242 -404.194391) (xy 134.44293 -404.235582) (xy 134.472394 -404.281432)
			(xy 134.495033 -404.331009) (xy 134.510387 -404.383303) (xy 134.518142 -404.437249) (xy 134.518142 -404.491749)
			(xy 135.955798 -404.491749) (xy 135.955798 -404.437251) (xy 135.963554 -404.383307) (xy 135.978908 -404.331016)
			(xy 136.001546 -404.281443) (xy 136.03101 -404.235596) (xy 136.066698 -404.194408) (xy 136.107884 -404.158718)
			(xy 136.15373 -404.129253) (xy 136.203303 -404.106612) (xy 136.255594 -404.091257) (xy 136.309537 -404.083499)
			(xy 136.336786 -404.083012) (xy 137.200386 -404.083012) (xy 137.227641 -404.083434) (xy 137.281596 -404.09119)
			(xy 137.333899 -404.106545) (xy 137.383483 -404.129188) (xy 137.429341 -404.158657) (xy 137.470537 -404.194353)
			(xy 137.506234 -404.235548) (xy 137.535705 -404.281405) (xy 137.55835 -404.330988) (xy 137.573707 -404.38329)
			(xy 137.581465 -404.437245) (xy 137.581465 -404.491753) (xy 139.018975 -404.491753) (xy 139.018975 -404.437247)
			(xy 139.026733 -404.383297) (xy 139.042089 -404.331) (xy 139.064732 -404.281421) (xy 139.094201 -404.235569)
			(xy 139.129896 -404.194377) (xy 139.171089 -404.158686) (xy 139.216943 -404.12922) (xy 139.266524 -404.10658)
			(xy 139.318822 -404.091227) (xy 139.372773 -404.083474) (xy 139.400026 -404.083012) (xy 140.263626 -404.083012)
			(xy 140.290877 -404.08346) (xy 140.344825 -404.09122) (xy 140.39712 -404.106578) (xy 140.446696 -404.129222)
			(xy 140.492546 -404.15869) (xy 140.533735 -404.194383) (xy 140.569426 -404.235575) (xy 140.598891 -404.281427)
			(xy 140.621531 -404.331005) (xy 140.636886 -404.3833) (xy 140.644642 -404.437249) (xy 140.644642 -404.491748)
			(xy 142.082298 -404.491748) (xy 142.082298 -404.437252) (xy 142.090053 -404.38331) (xy 142.105406 -404.331021)
			(xy 142.128043 -404.281448) (xy 142.157505 -404.235602) (xy 142.193191 -404.194415) (xy 142.234375 -404.158725)
			(xy 142.280218 -404.12926) (xy 142.329789 -404.106618) (xy 142.382077 -404.091261) (xy 142.436018 -404.083501)
			(xy 142.463266 -404.083012) (xy 143.326866 -404.083012) (xy 143.354122 -404.083433) (xy 143.408079 -404.091186)
			(xy 143.460384 -404.10654) (xy 143.509971 -404.129182) (xy 143.555831 -404.15865) (xy 143.59703 -404.194346)
			(xy 143.632729 -404.235542) (xy 143.662202 -404.281399) (xy 143.684848 -404.330984) (xy 143.700207 -404.383287)
			(xy 143.707965 -404.437244) (xy 143.707965 -404.491752) (xy 145.145475 -404.491752) (xy 145.145475 -404.437248)
			(xy 145.153232 -404.3833) (xy 145.168588 -404.331004) (xy 145.191229 -404.281426) (xy 145.220696 -404.235575)
			(xy 145.256389 -404.194384) (xy 145.29758 -404.158693) (xy 145.343431 -404.129226) (xy 145.39301 -404.106585)
			(xy 145.445306 -404.091231) (xy 145.499254 -404.083475) (xy 145.526506 -404.083012) (xy 146.390106 -404.083012)
			(xy 146.417358 -404.083458) (xy 146.471308 -404.091216) (xy 146.523605 -404.106572) (xy 146.573184 -404.129215)
			(xy 146.619036 -404.158683) (xy 146.660228 -404.194376) (xy 146.695921 -404.235569) (xy 146.725388 -404.281421)
			(xy 146.74803 -404.331001) (xy 146.763385 -404.383298) (xy 146.771142 -404.437248) (xy 146.771142 -404.491752)
			(xy 146.771142 -404.491754) (xy 148.208675 -404.491754) (xy 148.208675 -404.437246) (xy 148.216433 -404.383294)
			(xy 148.231791 -404.330996) (xy 148.254435 -404.281415) (xy 148.283906 -404.235562) (xy 148.319603 -404.19437)
			(xy 148.360799 -404.158679) (xy 148.406655 -404.129213) (xy 148.456239 -404.106575) (xy 148.508539 -404.091223)
			(xy 148.562492 -404.083472) (xy 148.589746 -404.083012) (xy 149.453346 -404.083012) (xy 149.480597 -404.083461)
			(xy 149.534542 -404.091223) (xy 149.586834 -404.106583) (xy 149.636408 -404.129228) (xy 149.682255 -404.158697)
			(xy 149.723442 -404.194391) (xy 149.75913 -404.235582) (xy 149.788594 -404.281432) (xy 149.811233 -404.331009)
			(xy 149.826587 -404.383303) (xy 149.834342 -404.437249) (xy 149.834342 -404.491749) (xy 151.271998 -404.491749)
			(xy 151.271998 -404.437251) (xy 151.279754 -404.383307) (xy 151.295108 -404.331016) (xy 151.317746 -404.281443)
			(xy 151.34721 -404.235596) (xy 151.382898 -404.194408) (xy 151.424084 -404.158718) (xy 151.46993 -404.129253)
			(xy 151.519503 -404.106612) (xy 151.571794 -404.091257) (xy 151.625737 -404.083499) (xy 151.652986 -404.083012)
			(xy 152.516586 -404.083012) (xy 152.543841 -404.083434) (xy 152.597796 -404.09119) (xy 152.650099 -404.106545)
			(xy 152.699683 -404.129188) (xy 152.745541 -404.158657) (xy 152.786737 -404.194353) (xy 152.822434 -404.235548)
			(xy 152.851905 -404.281405) (xy 152.87455 -404.330988) (xy 152.889907 -404.38329) (xy 152.897665 -404.437245)
			(xy 152.897665 -404.491753) (xy 154.335175 -404.491753) (xy 154.335175 -404.437247) (xy 154.342933 -404.383297)
			(xy 154.358289 -404.331) (xy 154.380932 -404.281421) (xy 154.410401 -404.235569) (xy 154.446096 -404.194377)
			(xy 154.487289 -404.158686) (xy 154.533143 -404.12922) (xy 154.582724 -404.10658) (xy 154.635022 -404.091227)
			(xy 154.688973 -404.083474) (xy 154.716226 -404.083012) (xy 155.579826 -404.083012) (xy 155.607077 -404.08346)
			(xy 155.661025 -404.09122) (xy 155.71332 -404.106578) (xy 155.762896 -404.129222) (xy 155.808746 -404.15869)
			(xy 155.849935 -404.194383) (xy 155.885626 -404.235575) (xy 155.915091 -404.281427) (xy 155.937731 -404.331005)
			(xy 155.953086 -404.3833) (xy 155.960842 -404.437249) (xy 155.960842 -404.491748) (xy 157.398498 -404.491748)
			(xy 157.398498 -404.437252) (xy 157.406253 -404.38331) (xy 157.421606 -404.331021) (xy 157.444243 -404.281448)
			(xy 157.473705 -404.235602) (xy 157.509391 -404.194415) (xy 157.550575 -404.158725) (xy 157.596418 -404.12926)
			(xy 157.645989 -404.106618) (xy 157.698277 -404.091261) (xy 157.752218 -404.083501) (xy 157.779466 -404.083012)
			(xy 158.643066 -404.083012) (xy 158.670322 -404.083433) (xy 158.724279 -404.091186) (xy 158.776584 -404.10654)
			(xy 158.826171 -404.129182) (xy 158.872031 -404.15865) (xy 158.91323 -404.194346) (xy 158.948929 -404.235542)
			(xy 158.978402 -404.281399) (xy 159.001048 -404.330984) (xy 159.016407 -404.383287) (xy 159.024165 -404.437244)
			(xy 159.024165 -404.491752) (xy 160.461675 -404.491752) (xy 160.461675 -404.437248) (xy 160.469432 -404.3833)
			(xy 160.484788 -404.331004) (xy 160.507429 -404.281426) (xy 160.536896 -404.235575) (xy 160.572589 -404.194384)
			(xy 160.61378 -404.158693) (xy 160.659631 -404.129226) (xy 160.70921 -404.106585) (xy 160.761506 -404.091231)
			(xy 160.815454 -404.083475) (xy 160.842706 -404.083012) (xy 161.706306 -404.083012) (xy 161.733558 -404.083458)
			(xy 161.787508 -404.091216) (xy 161.839805 -404.106572) (xy 161.889384 -404.129215) (xy 161.935236 -404.158683)
			(xy 161.976428 -404.194376) (xy 162.012121 -404.235569) (xy 162.041588 -404.281421) (xy 162.06423 -404.331001)
			(xy 162.079585 -404.383298) (xy 162.087342 -404.437248) (xy 162.087342 -404.491752) (xy 162.079585 -404.545702)
			(xy 162.06423 -404.597999) (xy 162.041588 -404.647579) (xy 162.012121 -404.693431) (xy 161.976428 -404.734624)
			(xy 161.935236 -404.770317) (xy 161.889384 -404.799785) (xy 161.839805 -404.822428) (xy 161.787508 -404.837784)
			(xy 161.733558 -404.845542) (xy 161.706306 -404.846028) (xy 160.842706 -404.846028) (xy 160.815454 -404.845525)
			(xy 160.761506 -404.837769) (xy 160.70921 -404.822415) (xy 160.659631 -404.799774) (xy 160.61378 -404.770307)
			(xy 160.572589 -404.734616) (xy 160.536896 -404.693425) (xy 160.507429 -404.647574) (xy 160.484788 -404.597996)
			(xy 160.469432 -404.5457) (xy 160.461675 -404.491752) (xy 159.024165 -404.491752) (xy 159.024165 -404.491756)
			(xy 159.016407 -404.545713) (xy 159.001048 -404.598016) (xy 158.978402 -404.647601) (xy 158.948929 -404.693458)
			(xy 158.91323 -404.734654) (xy 158.872031 -404.77035) (xy 158.826171 -404.799818) (xy 158.776584 -404.82246)
			(xy 158.724279 -404.837814) (xy 158.670322 -404.845567) (xy 158.643066 -404.846028) (xy 157.779466 -404.846028)
			(xy 157.752218 -404.845499) (xy 157.698277 -404.837739) (xy 157.645989 -404.822382) (xy 157.596418 -404.79974)
			(xy 157.550575 -404.770275) (xy 157.509391 -404.734585) (xy 157.473705 -404.693398) (xy 157.444243 -404.647552)
			(xy 157.421606 -404.597979) (xy 157.406253 -404.54569) (xy 157.398498 -404.491748) (xy 155.960842 -404.491748)
			(xy 155.960842 -404.491751) (xy 155.953086 -404.5457) (xy 155.937731 -404.597995) (xy 155.915091 -404.647573)
			(xy 155.885626 -404.693425) (xy 155.849935 -404.734617) (xy 155.808746 -404.77031) (xy 155.762896 -404.799778)
			(xy 155.71332 -404.822422) (xy 155.661025 -404.83778) (xy 155.607077 -404.84554) (xy 155.579826 -404.846028)
			(xy 154.716226 -404.846028) (xy 154.688973 -404.845526) (xy 154.635022 -404.837773) (xy 154.582724 -404.82242)
			(xy 154.533143 -404.79978) (xy 154.487289 -404.770314) (xy 154.446096 -404.734623) (xy 154.410401 -404.693431)
			(xy 154.380932 -404.647579) (xy 154.358289 -404.598) (xy 154.342933 -404.545703) (xy 154.335175 -404.491753)
			(xy 152.897665 -404.491753) (xy 152.897665 -404.491755) (xy 152.889907 -404.54571) (xy 152.87455 -404.598012)
			(xy 152.851905 -404.647595) (xy 152.822434 -404.693452) (xy 152.786737 -404.734647) (xy 152.745541 -404.770343)
			(xy 152.699683 -404.799812) (xy 152.650099 -404.822455) (xy 152.597796 -404.83781) (xy 152.543841 -404.845566)
			(xy 152.516586 -404.846028) (xy 151.652986 -404.846028) (xy 151.625737 -404.845501) (xy 151.571794 -404.837743)
			(xy 151.519503 -404.822388) (xy 151.46993 -404.799747) (xy 151.424084 -404.770282) (xy 151.382898 -404.734592)
			(xy 151.34721 -404.693404) (xy 151.317746 -404.647557) (xy 151.295108 -404.597984) (xy 151.279754 -404.545693)
			(xy 151.271998 -404.491749) (xy 149.834342 -404.491749) (xy 149.834342 -404.491751) (xy 149.826587 -404.545697)
			(xy 149.811233 -404.597991) (xy 149.788594 -404.647568) (xy 149.75913 -404.693418) (xy 149.723442 -404.734609)
			(xy 149.682255 -404.770303) (xy 149.636408 -404.799772) (xy 149.586834 -404.822417) (xy 149.534542 -404.837777)
			(xy 149.480597 -404.845539) (xy 149.453346 -404.846028) (xy 148.589746 -404.846028) (xy 148.562492 -404.845528)
			(xy 148.508539 -404.837777) (xy 148.456239 -404.822425) (xy 148.406655 -404.799787) (xy 148.360799 -404.770321)
			(xy 148.319603 -404.73463) (xy 148.283906 -404.693438) (xy 148.254435 -404.647585) (xy 148.231791 -404.598004)
			(xy 148.216433 -404.545706) (xy 148.208675 -404.491754) (xy 146.771142 -404.491754) (xy 146.763385 -404.545702)
			(xy 146.74803 -404.597999) (xy 146.725388 -404.647579) (xy 146.695921 -404.693431) (xy 146.660228 -404.734624)
			(xy 146.619036 -404.770317) (xy 146.573184 -404.799785) (xy 146.523605 -404.822428) (xy 146.471308 -404.837784)
			(xy 146.417358 -404.845542) (xy 146.390106 -404.846028) (xy 145.526506 -404.846028) (xy 145.499254 -404.845525)
			(xy 145.445306 -404.837769) (xy 145.39301 -404.822415) (xy 145.343431 -404.799774) (xy 145.29758 -404.770307)
			(xy 145.256389 -404.734616) (xy 145.220696 -404.693425) (xy 145.191229 -404.647574) (xy 145.168588 -404.597996)
			(xy 145.153232 -404.5457) (xy 145.145475 -404.491752) (xy 143.707965 -404.491752) (xy 143.707965 -404.491756)
			(xy 143.700207 -404.545713) (xy 143.684848 -404.598016) (xy 143.662202 -404.647601) (xy 143.632729 -404.693458)
			(xy 143.59703 -404.734654) (xy 143.555831 -404.77035) (xy 143.509971 -404.799818) (xy 143.460384 -404.82246)
			(xy 143.408079 -404.837814) (xy 143.354122 -404.845567) (xy 143.326866 -404.846028) (xy 142.463266 -404.846028)
			(xy 142.436018 -404.845499) (xy 142.382077 -404.837739) (xy 142.329789 -404.822382) (xy 142.280218 -404.79974)
			(xy 142.234375 -404.770275) (xy 142.193191 -404.734585) (xy 142.157505 -404.693398) (xy 142.128043 -404.647552)
			(xy 142.105406 -404.597979) (xy 142.090053 -404.54569) (xy 142.082298 -404.491748) (xy 140.644642 -404.491748)
			(xy 140.644642 -404.491751) (xy 140.636886 -404.5457) (xy 140.621531 -404.597995) (xy 140.598891 -404.647573)
			(xy 140.569426 -404.693425) (xy 140.533735 -404.734617) (xy 140.492546 -404.77031) (xy 140.446696 -404.799778)
			(xy 140.39712 -404.822422) (xy 140.344825 -404.83778) (xy 140.290877 -404.84554) (xy 140.263626 -404.846028)
			(xy 139.400026 -404.846028) (xy 139.372773 -404.845526) (xy 139.318822 -404.837773) (xy 139.266524 -404.82242)
			(xy 139.216943 -404.79978) (xy 139.171089 -404.770314) (xy 139.129896 -404.734623) (xy 139.094201 -404.693431)
			(xy 139.064732 -404.647579) (xy 139.042089 -404.598) (xy 139.026733 -404.545703) (xy 139.018975 -404.491753)
			(xy 137.581465 -404.491753) (xy 137.581465 -404.491755) (xy 137.573707 -404.54571) (xy 137.55835 -404.598012)
			(xy 137.535705 -404.647595) (xy 137.506234 -404.693452) (xy 137.470537 -404.734647) (xy 137.429341 -404.770343)
			(xy 137.383483 -404.799812) (xy 137.333899 -404.822455) (xy 137.281596 -404.83781) (xy 137.227641 -404.845566)
			(xy 137.200386 -404.846028) (xy 136.336786 -404.846028) (xy 136.309537 -404.845501) (xy 136.255594 -404.837743)
			(xy 136.203303 -404.822388) (xy 136.15373 -404.799747) (xy 136.107884 -404.770282) (xy 136.066698 -404.734592)
			(xy 136.03101 -404.693404) (xy 136.001546 -404.647557) (xy 135.978908 -404.597984) (xy 135.963554 -404.545693)
			(xy 135.955798 -404.491749) (xy 134.518142 -404.491749) (xy 134.518142 -404.491751) (xy 134.510387 -404.545697)
			(xy 134.495033 -404.597991) (xy 134.472394 -404.647568) (xy 134.44293 -404.693418) (xy 134.407242 -404.734609)
			(xy 134.366055 -404.770303) (xy 134.320208 -404.799772) (xy 134.270634 -404.822417) (xy 134.218342 -404.837777)
			(xy 134.164397 -404.845539) (xy 134.137146 -404.846028) (xy 133.273546 -404.846028) (xy 133.246292 -404.845528)
			(xy 133.192339 -404.837777) (xy 133.140039 -404.822425) (xy 133.090455 -404.799787) (xy 133.044599 -404.770321)
			(xy 133.003403 -404.73463) (xy 132.967706 -404.693438) (xy 132.938235 -404.647585) (xy 132.915591 -404.598004)
			(xy 132.900233 -404.545706) (xy 132.892475 -404.491754) (xy 131.454942 -404.491754) (xy 131.447185 -404.545702)
			(xy 131.43183 -404.597999) (xy 131.409188 -404.647579) (xy 131.379721 -404.693431) (xy 131.344028 -404.734624)
			(xy 131.302836 -404.770317) (xy 131.256984 -404.799785) (xy 131.207405 -404.822428) (xy 131.155108 -404.837784)
			(xy 131.101158 -404.845542) (xy 131.073906 -404.846028) (xy 130.210306 -404.846028) (xy 130.183054 -404.845525)
			(xy 130.129106 -404.837769) (xy 130.07681 -404.822415) (xy 130.027231 -404.799774) (xy 129.98138 -404.770307)
			(xy 129.940189 -404.734616) (xy 129.904496 -404.693425) (xy 129.875029 -404.647574) (xy 129.852388 -404.597996)
			(xy 129.837032 -404.5457) (xy 129.829275 -404.491752) (xy 128.391765 -404.491752) (xy 128.391765 -404.491756)
			(xy 128.384007 -404.545713) (xy 128.368648 -404.598016) (xy 128.346002 -404.647601) (xy 128.316529 -404.693458)
			(xy 128.28083 -404.734654) (xy 128.239631 -404.77035) (xy 128.193771 -404.799818) (xy 128.144184 -404.82246)
			(xy 128.091879 -404.837814) (xy 128.037922 -404.845567) (xy 128.010666 -404.846028) (xy 127.147066 -404.846028)
			(xy 127.119818 -404.845499) (xy 127.065877 -404.837739) (xy 127.013589 -404.822382) (xy 126.964018 -404.79974)
			(xy 126.918175 -404.770275) (xy 126.876991 -404.734585) (xy 126.841305 -404.693398) (xy 126.811843 -404.647552)
			(xy 126.789206 -404.597979) (xy 126.773853 -404.54569) (xy 126.766098 -404.491748) (xy 125.328442 -404.491748)
			(xy 125.328442 -404.491751) (xy 125.320686 -404.5457) (xy 125.305331 -404.597995) (xy 125.282691 -404.647573)
			(xy 125.253226 -404.693425) (xy 125.217535 -404.734617) (xy 125.176346 -404.77031) (xy 125.130496 -404.799778)
			(xy 125.08092 -404.822422) (xy 125.028625 -404.83778) (xy 124.974677 -404.84554) (xy 124.947426 -404.846028)
			(xy 124.083826 -404.846028) (xy 124.056573 -404.845526) (xy 124.002622 -404.837773) (xy 123.950324 -404.82242)
			(xy 123.900743 -404.79978) (xy 123.854889 -404.770314) (xy 123.813696 -404.734623) (xy 123.778001 -404.693431)
			(xy 123.748532 -404.647579) (xy 123.725889 -404.598) (xy 123.710533 -404.545703) (xy 123.702775 -404.491753)
			(xy 122.265265 -404.491753) (xy 122.265265 -404.491755) (xy 122.257507 -404.54571) (xy 122.24215 -404.598012)
			(xy 122.219505 -404.647595) (xy 122.190034 -404.693452) (xy 122.154337 -404.734647) (xy 122.113141 -404.770343)
			(xy 122.067283 -404.799812) (xy 122.017699 -404.822455) (xy 121.965396 -404.83781) (xy 121.911441 -404.845566)
			(xy 121.884186 -404.846028) (xy 121.020586 -404.846028) (xy 120.993337 -404.845501) (xy 120.939394 -404.837743)
			(xy 120.887103 -404.822388) (xy 120.83753 -404.799747) (xy 120.791684 -404.770282) (xy 120.750498 -404.734592)
			(xy 120.71481 -404.693404) (xy 120.685346 -404.647557) (xy 120.662708 -404.597984) (xy 120.647354 -404.545693)
			(xy 120.639598 -404.491749) (xy 119.201942 -404.491749) (xy 119.201942 -404.491751) (xy 119.194187 -404.545697)
			(xy 119.178833 -404.597991) (xy 119.156194 -404.647568) (xy 119.12673 -404.693418) (xy 119.091042 -404.734609)
			(xy 119.049855 -404.770303) (xy 119.004008 -404.799772) (xy 118.954434 -404.822417) (xy 118.902142 -404.837777)
			(xy 118.848197 -404.845539) (xy 118.820946 -404.846028) (xy 117.957346 -404.846028) (xy 117.930092 -404.845528)
			(xy 117.876139 -404.837777) (xy 117.823839 -404.822425) (xy 117.774255 -404.799787) (xy 117.728399 -404.770321)
			(xy 117.687203 -404.73463) (xy 117.651506 -404.693438) (xy 117.622035 -404.647585) (xy 117.599391 -404.598004)
			(xy 117.584033 -404.545706) (xy 117.576275 -404.491754) (xy 116.138742 -404.491754) (xy 116.130985 -404.545702)
			(xy 116.11563 -404.597999) (xy 116.092988 -404.647579) (xy 116.063521 -404.693431) (xy 116.027828 -404.734624)
			(xy 115.986636 -404.770317) (xy 115.940784 -404.799785) (xy 115.891205 -404.822428) (xy 115.838908 -404.837784)
			(xy 115.784958 -404.845542) (xy 115.757706 -404.846028) (xy 114.894106 -404.846028) (xy 114.866854 -404.845525)
			(xy 114.812906 -404.837769) (xy 114.76061 -404.822415) (xy 114.711031 -404.799774) (xy 114.66518 -404.770307)
			(xy 114.623989 -404.734616) (xy 114.588296 -404.693425) (xy 114.558829 -404.647574) (xy 114.536188 -404.597996)
			(xy 114.520832 -404.5457) (xy 114.513075 -404.491752) (xy 94.987465 -404.491752) (xy 94.987465 -404.491756)
			(xy 94.979707 -404.545713) (xy 94.964348 -404.598016) (xy 94.941702 -404.647602) (xy 94.912229 -404.693459)
			(xy 94.876529 -404.734655) (xy 94.83533 -404.77035) (xy 94.78947 -404.799819) (xy 94.739883 -404.822461)
			(xy 94.687578 -404.837814) (xy 94.63362 -404.845568) (xy 94.606364 -404.846028) (xy 93.742764 -404.846028)
			(xy 93.715516 -404.845499) (xy 93.661575 -404.837739) (xy 93.609287 -404.822382) (xy 93.559717 -404.79974)
			(xy 93.513874 -404.770274) (xy 93.47269 -404.734584) (xy 93.437004 -404.693397) (xy 93.407543 -404.647551)
			(xy 93.384906 -404.597979) (xy 93.369553 -404.54569) (xy 93.361798 -404.491748) (xy 91.924142 -404.491748)
			(xy 91.924142 -404.491752) (xy 91.916386 -404.5457) (xy 91.901031 -404.597996) (xy 91.878391 -404.647574)
			(xy 91.848925 -404.693425) (xy 91.813234 -404.734617) (xy 91.772045 -404.770311) (xy 91.726195 -404.799779)
			(xy 91.676618 -404.822423) (xy 91.624324 -404.837781) (xy 91.570376 -404.845541) (xy 91.543124 -404.846028)
			(xy 90.679524 -404.846028) (xy 90.652271 -404.845526) (xy 90.598321 -404.837773) (xy 90.546023 -404.822419)
			(xy 90.496442 -404.799779) (xy 90.450588 -404.770314) (xy 90.409395 -404.734622) (xy 90.373701 -404.693431)
			(xy 90.344232 -404.647579) (xy 90.321589 -404.598) (xy 90.306233 -404.545703) (xy 90.298475 -404.491753)
			(xy 88.860965 -404.491753) (xy 88.860965 -404.491755) (xy 88.853207 -404.54571) (xy 88.83785 -404.598012)
			(xy 88.815205 -404.647596) (xy 88.785734 -404.693452) (xy 88.750036 -404.734648) (xy 88.70884 -404.770343)
			(xy 88.662982 -404.799812) (xy 88.613397 -404.822455) (xy 88.561095 -404.837811) (xy 88.507139 -404.845566)
			(xy 88.479884 -404.846028) (xy 87.616284 -404.846028) (xy 87.589035 -404.845501) (xy 87.535092 -404.837743)
			(xy 87.482802 -404.822387) (xy 87.433229 -404.799746) (xy 87.387383 -404.770281) (xy 87.346197 -404.734591)
			(xy 87.310509 -404.693404) (xy 87.281046 -404.647557) (xy 87.258407 -404.597983) (xy 87.243054 -404.545692)
			(xy 87.235298 -404.491749) (xy 85.797642 -404.491749) (xy 85.797642 -404.491751) (xy 85.789887 -404.545697)
			(xy 85.774533 -404.597991) (xy 85.751894 -404.647568) (xy 85.72243 -404.693419) (xy 85.686741 -404.73461)
			(xy 85.645554 -404.770304) (xy 85.599707 -404.799773) (xy 85.550133 -404.822417) (xy 85.49784 -404.837777)
			(xy 85.443895 -404.845539) (xy 85.416644 -404.846028) (xy 84.553044 -404.846028) (xy 84.525791 -404.845528)
			(xy 84.471838 -404.837776) (xy 84.419537 -404.822425) (xy 84.369954 -404.799786) (xy 84.324098 -404.770321)
			(xy 84.282902 -404.734629) (xy 84.247206 -404.693437) (xy 84.217735 -404.647584) (xy 84.195091 -404.598004)
			(xy 84.179733 -404.545705) (xy 84.171975 -404.491753) (xy 82.734442 -404.491753) (xy 82.726685 -404.545703)
			(xy 82.71133 -404.598) (xy 82.688688 -404.647579) (xy 82.65922 -404.693432) (xy 82.623527 -404.734624)
			(xy 82.582335 -404.770318) (xy 82.536483 -404.799786) (xy 82.486904 -404.822428) (xy 82.434607 -404.837785)
			(xy 82.380656 -404.845542) (xy 82.353404 -404.846028) (xy 81.489804 -404.846028) (xy 81.462552 -404.845525)
			(xy 81.408604 -404.837769) (xy 81.356308 -404.822414) (xy 81.30673 -404.799773) (xy 81.260879 -404.770307)
			(xy 81.219688 -404.734615) (xy 81.183996 -404.693424) (xy 81.154529 -404.647573) (xy 81.131887 -404.597995)
			(xy 81.116532 -404.5457) (xy 81.108775 -404.491752) (xy 79.671265 -404.491752) (xy 79.671265 -404.491756)
			(xy 79.663507 -404.545713) (xy 79.648148 -404.598016) (xy 79.625502 -404.647602) (xy 79.596029 -404.693459)
			(xy 79.560329 -404.734655) (xy 79.51913 -404.77035) (xy 79.47327 -404.799819) (xy 79.423683 -404.822461)
			(xy 79.371378 -404.837814) (xy 79.31742 -404.845568) (xy 79.290164 -404.846028) (xy 78.426564 -404.846028)
			(xy 78.399316 -404.845499) (xy 78.345375 -404.837739) (xy 78.293087 -404.822382) (xy 78.243517 -404.79974)
			(xy 78.197674 -404.770274) (xy 78.15649 -404.734584) (xy 78.120804 -404.693397) (xy 78.091343 -404.647551)
			(xy 78.068706 -404.597979) (xy 78.053353 -404.54569) (xy 78.045598 -404.491748) (xy 76.607942 -404.491748)
			(xy 76.607942 -404.491752) (xy 76.600186 -404.5457) (xy 76.584831 -404.597996) (xy 76.562191 -404.647574)
			(xy 76.532725 -404.693425) (xy 76.497034 -404.734617) (xy 76.455845 -404.770311) (xy 76.409995 -404.799779)
			(xy 76.360418 -404.822423) (xy 76.308124 -404.837781) (xy 76.254176 -404.845541) (xy 76.226924 -404.846028)
			(xy 75.363324 -404.846028) (xy 75.336071 -404.845526) (xy 75.282121 -404.837773) (xy 75.229823 -404.822419)
			(xy 75.180242 -404.799779) (xy 75.134388 -404.770314) (xy 75.093195 -404.734622) (xy 75.057501 -404.693431)
			(xy 75.028032 -404.647579) (xy 75.005389 -404.598) (xy 74.990033 -404.545703) (xy 74.982275 -404.491753)
			(xy 73.544765 -404.491753) (xy 73.544765 -404.491755) (xy 73.537007 -404.54571) (xy 73.52165 -404.598012)
			(xy 73.499005 -404.647596) (xy 73.469534 -404.693452) (xy 73.433836 -404.734648) (xy 73.39264 -404.770343)
			(xy 73.346782 -404.799812) (xy 73.297197 -404.822455) (xy 73.244895 -404.837811) (xy 73.190939 -404.845566)
			(xy 73.163684 -404.846028) (xy 72.300084 -404.846028) (xy 72.272835 -404.845501) (xy 72.218892 -404.837743)
			(xy 72.166602 -404.822387) (xy 72.117029 -404.799746) (xy 72.071183 -404.770281) (xy 72.029997 -404.734591)
			(xy 71.994309 -404.693404) (xy 71.964846 -404.647557) (xy 71.942207 -404.597983) (xy 71.926854 -404.545692)
			(xy 71.919098 -404.491749) (xy 70.481442 -404.491749) (xy 70.481442 -404.491751) (xy 70.473687 -404.545697)
			(xy 70.458333 -404.597991) (xy 70.435694 -404.647568) (xy 70.40623 -404.693419) (xy 70.370541 -404.73461)
			(xy 70.329354 -404.770304) (xy 70.283507 -404.799773) (xy 70.233933 -404.822417) (xy 70.18164 -404.837777)
			(xy 70.127695 -404.845539) (xy 70.100444 -404.846028) (xy 69.236844 -404.846028) (xy 69.209591 -404.845528)
			(xy 69.155638 -404.837776) (xy 69.103337 -404.822425) (xy 69.053754 -404.799786) (xy 69.007898 -404.770321)
			(xy 68.966702 -404.734629) (xy 68.931006 -404.693437) (xy 68.901535 -404.647584) (xy 68.878891 -404.598004)
			(xy 68.863533 -404.545705) (xy 68.855775 -404.491753) (xy 67.418242 -404.491753) (xy 67.410485 -404.545703)
			(xy 67.39513 -404.598) (xy 67.372488 -404.647579) (xy 67.34302 -404.693432) (xy 67.307327 -404.734624)
			(xy 67.266135 -404.770318) (xy 67.220283 -404.799786) (xy 67.170704 -404.822428) (xy 67.118407 -404.837785)
			(xy 67.064456 -404.845542) (xy 67.037204 -404.846028) (xy 66.173604 -404.846028) (xy 66.146352 -404.845525)
			(xy 66.092404 -404.837769) (xy 66.040108 -404.822414) (xy 65.99053 -404.799773) (xy 65.944679 -404.770307)
			(xy 65.903488 -404.734615) (xy 65.867796 -404.693424) (xy 65.838329 -404.647573) (xy 65.815687 -404.597995)
			(xy 65.800332 -404.5457) (xy 65.792575 -404.491752) (xy 64.355065 -404.491752) (xy 64.355065 -404.491756)
			(xy 64.347307 -404.545713) (xy 64.331948 -404.598016) (xy 64.309302 -404.647602) (xy 64.279829 -404.693459)
			(xy 64.244129 -404.734655) (xy 64.20293 -404.77035) (xy 64.15707 -404.799819) (xy 64.107483 -404.822461)
			(xy 64.055178 -404.837814) (xy 64.00122 -404.845568) (xy 63.973964 -404.846028) (xy 63.110364 -404.846028)
			(xy 63.083116 -404.845499) (xy 63.029175 -404.837739) (xy 62.976887 -404.822382) (xy 62.927317 -404.79974)
			(xy 62.881474 -404.770274) (xy 62.84029 -404.734584) (xy 62.804604 -404.693397) (xy 62.775143 -404.647551)
			(xy 62.752506 -404.597979) (xy 62.737153 -404.54569) (xy 62.729398 -404.491748) (xy 61.291742 -404.491748)
			(xy 61.291742 -404.491752) (xy 61.283986 -404.5457) (xy 61.268631 -404.597996) (xy 61.245991 -404.647574)
			(xy 61.216525 -404.693425) (xy 61.180834 -404.734617) (xy 61.139645 -404.770311) (xy 61.093795 -404.799779)
			(xy 61.044218 -404.822423) (xy 60.991924 -404.837781) (xy 60.937976 -404.845541) (xy 60.910724 -404.846028)
			(xy 60.047124 -404.846028) (xy 60.019871 -404.845526) (xy 59.965921 -404.837773) (xy 59.913623 -404.822419)
			(xy 59.864042 -404.799779) (xy 59.818188 -404.770314) (xy 59.776995 -404.734622) (xy 59.741301 -404.693431)
			(xy 59.711832 -404.647579) (xy 59.689189 -404.598) (xy 59.673833 -404.545703) (xy 59.666075 -404.491753)
			(xy 58.228565 -404.491753) (xy 58.228565 -404.491755) (xy 58.220807 -404.54571) (xy 58.20545 -404.598012)
			(xy 58.182805 -404.647596) (xy 58.153334 -404.693452) (xy 58.117636 -404.734648) (xy 58.07644 -404.770343)
			(xy 58.030582 -404.799812) (xy 57.980997 -404.822455) (xy 57.928695 -404.837811) (xy 57.874739 -404.845566)
			(xy 57.847484 -404.846028) (xy 56.983884 -404.846028) (xy 56.956635 -404.845501) (xy 56.902692 -404.837743)
			(xy 56.850402 -404.822387) (xy 56.800829 -404.799746) (xy 56.754983 -404.770281) (xy 56.713797 -404.734591)
			(xy 56.678109 -404.693404) (xy 56.648646 -404.647557) (xy 56.626007 -404.597983) (xy 56.610654 -404.545692)
			(xy 56.602898 -404.491749) (xy 55.165242 -404.491749) (xy 55.165242 -404.491751) (xy 55.157487 -404.545697)
			(xy 55.142133 -404.597991) (xy 55.119494 -404.647568) (xy 55.09003 -404.693419) (xy 55.054341 -404.73461)
			(xy 55.013154 -404.770304) (xy 54.967307 -404.799773) (xy 54.917733 -404.822417) (xy 54.86544 -404.837777)
			(xy 54.811495 -404.845539) (xy 54.784244 -404.846028) (xy 53.920644 -404.846028) (xy 53.893391 -404.845528)
			(xy 53.839438 -404.837776) (xy 53.787137 -404.822425) (xy 53.737554 -404.799786) (xy 53.691698 -404.770321)
			(xy 53.650502 -404.734629) (xy 53.614806 -404.693437) (xy 53.585335 -404.647584) (xy 53.562691 -404.598004)
			(xy 53.547333 -404.545705) (xy 53.539575 -404.491753) (xy 52.102042 -404.491753) (xy 52.094285 -404.545703)
			(xy 52.07893 -404.598) (xy 52.056288 -404.647579) (xy 52.02682 -404.693432) (xy 51.991127 -404.734624)
			(xy 51.949935 -404.770318) (xy 51.904083 -404.799786) (xy 51.854504 -404.822428) (xy 51.802207 -404.837785)
			(xy 51.748256 -404.845542) (xy 51.721004 -404.846028) (xy 50.857404 -404.846028) (xy 50.830152 -404.845525)
			(xy 50.776204 -404.837769) (xy 50.723908 -404.822414) (xy 50.67433 -404.799773) (xy 50.628479 -404.770307)
			(xy 50.587288 -404.734615) (xy 50.551596 -404.693424) (xy 50.522129 -404.647573) (xy 50.499487 -404.597995)
			(xy 50.484132 -404.5457) (xy 50.476375 -404.491752) (xy 49.038865 -404.491752) (xy 49.038865 -404.491756)
			(xy 49.031107 -404.545713) (xy 49.015748 -404.598016) (xy 48.993102 -404.647602) (xy 48.963629 -404.693459)
			(xy 48.927929 -404.734655) (xy 48.88673 -404.77035) (xy 48.84087 -404.799819) (xy 48.791283 -404.822461)
			(xy 48.738978 -404.837814) (xy 48.68502 -404.845568) (xy 48.657764 -404.846028) (xy 47.794164 -404.846028)
			(xy 47.766916 -404.845499) (xy 47.712975 -404.837739) (xy 47.660687 -404.822382) (xy 47.611117 -404.79974)
			(xy 47.565274 -404.770274) (xy 47.52409 -404.734584) (xy 47.488404 -404.693397) (xy 47.458943 -404.647551)
			(xy 47.436306 -404.597979) (xy 47.420953 -404.54569) (xy 47.413198 -404.491748) (xy 45.875438 -404.491748)
			(xy 45.877367 -404.514108) (xy 45.885362 -404.699771) (xy 45.885862 -404.792688) (xy 45.885362 -404.885605)
			(xy 45.877367 -405.071268) (xy 45.861392 -405.256414) (xy 45.837466 -405.440702) (xy 45.805634 -405.62379)
			(xy 45.802444 -405.638385) (xy 104.009796 -405.638385) (xy 104.013672 -405.584006) (xy 104.025246 -405.530732)
			(xy 104.044281 -405.479646) (xy 104.070391 -405.431789) (xy 104.103044 -405.388132) (xy 104.121966 -405.368506)
			(xy 104.732582 -404.757636) (xy 104.75423 -404.736857) (xy 104.802784 -404.701606) (xy 104.856253 -404.67438)
			(xy 104.91332 -404.655848) (xy 104.972583 -404.646465) (xy 105.002584 -404.645876) (xy 105.029856 -404.646316)
			(xy 105.083846 -404.654077) (xy 105.136181 -404.669444) (xy 105.185797 -404.692102) (xy 105.231683 -404.721592)
			(xy 105.272904 -404.757312) (xy 105.308622 -404.798535) (xy 105.338108 -404.844422) (xy 105.360764 -404.894039)
			(xy 105.376127 -404.946376) (xy 105.383885 -405.000366) (xy 105.384346 -405.027638) (xy 105.383744 -405.057639)
			(xy 105.374371 -405.116904) (xy 105.355845 -405.173974) (xy 105.328623 -405.227445) (xy 105.29971 -405.267273)
			(xy 106.824184 -405.267273) (xy 106.824184 -405.212727) (xy 106.831947 -405.158735) (xy 106.847315 -405.106398)
			(xy 106.869976 -405.05678) (xy 106.899467 -405.010893) (xy 106.935189 -404.969671) (xy 106.976414 -404.933951)
			(xy 107.022303 -404.904463) (xy 107.071922 -404.881806) (xy 107.12426 -404.866441) (xy 107.178252 -404.858682)
			(xy 107.205526 -404.85822) (xy 108.069126 -404.85822) (xy 108.096393 -404.858744) (xy 108.150371 -404.866508)
			(xy 108.202695 -404.881875) (xy 108.2523 -404.904532) (xy 108.298175 -404.934017) (xy 108.339388 -404.969731)
			(xy 108.375098 -405.010946) (xy 108.404581 -405.056823) (xy 108.427234 -405.106429) (xy 108.442597 -405.158754)
			(xy 108.450358 -405.212733) (xy 108.450358 -405.267267) (xy 108.442597 -405.321246) (xy 108.427234 -405.373571)
			(xy 108.404581 -405.423177) (xy 108.375098 -405.469054) (xy 108.339388 -405.510269) (xy 108.298175 -405.545983)
			(xy 108.2523 -405.575468) (xy 108.202695 -405.598125) (xy 108.150371 -405.613492) (xy 108.096393 -405.621256)
			(xy 108.069126 -405.621744) (xy 107.205526 -405.621744) (xy 107.178252 -405.621318) (xy 107.12426 -405.613559)
			(xy 107.071922 -405.598194) (xy 107.022303 -405.575537) (xy 106.976414 -405.546049) (xy 106.935189 -405.510329)
			(xy 106.899467 -405.469107) (xy 106.869976 -405.42322) (xy 106.847315 -405.373602) (xy 106.831947 -405.321265)
			(xy 106.824184 -405.267273) (xy 105.29971 -405.267273) (xy 105.293374 -405.276001) (xy 105.272586 -405.29764)
			(xy 104.661716 -405.908256) (xy 104.642167 -405.927256) (xy 104.598511 -405.959909) (xy 104.550654 -405.986019)
			(xy 104.499568 -406.005054) (xy 104.446294 -406.016628) (xy 104.391915 -406.020504) (xy 104.337538 -406.016603)
			(xy 104.284269 -406.005006) (xy 104.233192 -405.985949) (xy 104.185346 -405.959818) (xy 104.141704 -405.927145)
			(xy 104.103155 -405.888596) (xy 104.070482 -405.844954) (xy 104.044351 -405.797108) (xy 104.025294 -405.746031)
			(xy 104.013697 -405.692762) (xy 104.009796 -405.638385) (xy 45.802444 -405.638385) (xy 45.765954 -405.805339)
			(xy 45.718501 -405.985013) (xy 45.663361 -406.162479) (xy 45.600638 -406.337408) (xy 45.530447 -406.509477)
			(xy 45.452918 -406.678366) (xy 45.368195 -406.843764) (xy 45.276434 -407.005364) (xy 45.259912 -407.031749)
			(xy 48.944798 -407.031749) (xy 48.944798 -406.977251) (xy 48.952554 -406.923308) (xy 48.967907 -406.871017)
			(xy 48.990546 -406.821443) (xy 49.020009 -406.775596) (xy 49.055697 -406.734409) (xy 49.096883 -406.698719)
			(xy 49.142729 -406.669254) (xy 49.192302 -406.646613) (xy 49.244592 -406.631257) (xy 49.298535 -406.623499)
			(xy 49.325784 -406.623012) (xy 50.189384 -406.623012) (xy 50.216639 -406.623434) (xy 50.270595 -406.631189)
			(xy 50.322897 -406.646545) (xy 50.372482 -406.669188) (xy 50.41834 -406.698657) (xy 50.459536 -406.734352)
			(xy 50.495234 -406.775548) (xy 50.524705 -406.821404) (xy 50.54735 -406.870988) (xy 50.562707 -406.92329)
			(xy 50.570465 -406.977245) (xy 50.570465 -407.031753) (xy 52.007975 -407.031753) (xy 52.007975 -406.977247)
			(xy 52.015733 -406.923297) (xy 52.031089 -406.871) (xy 52.053732 -406.821421) (xy 52.083201 -406.775569)
			(xy 52.118895 -406.734378) (xy 52.160088 -406.698686) (xy 52.205942 -406.669221) (xy 52.255523 -406.646581)
			(xy 52.307821 -406.631227) (xy 52.361771 -406.623474) (xy 52.389024 -406.623012) (xy 53.252624 -406.623012)
			(xy 53.279876 -406.623459) (xy 53.333824 -406.631219) (xy 53.386118 -406.646577) (xy 53.435695 -406.669221)
			(xy 53.481545 -406.698689) (xy 53.522734 -406.734383) (xy 53.558425 -406.775575) (xy 53.587891 -406.821426)
			(xy 53.610531 -406.871004) (xy 53.625886 -406.9233) (xy 53.633642 -406.977248) (xy 53.633642 -407.031748)
			(xy 55.071298 -407.031748) (xy 55.071298 -406.977252) (xy 55.079053 -406.92331) (xy 55.094406 -406.871021)
			(xy 55.117043 -406.821449) (xy 55.146504 -406.775603) (xy 55.18219 -406.734416) (xy 55.223374 -406.698726)
			(xy 55.269217 -406.66926) (xy 55.318787 -406.646618) (xy 55.371075 -406.631261) (xy 55.425016 -406.623501)
			(xy 55.452264 -406.623012) (xy 56.315864 -406.623012) (xy 56.34312 -406.623432) (xy 56.397078 -406.631186)
			(xy 56.449383 -406.646539) (xy 56.49897 -406.669181) (xy 56.54483 -406.69865) (xy 56.586029 -406.734345)
			(xy 56.621729 -406.775541) (xy 56.651202 -406.821398) (xy 56.673848 -406.870984) (xy 56.689207 -406.923287)
			(xy 56.696965 -406.977244) (xy 56.696965 -407.031752) (xy 58.134475 -407.031752) (xy 58.134475 -406.977248)
			(xy 58.142232 -406.9233) (xy 58.157587 -406.871005) (xy 58.180229 -406.821427) (xy 58.209696 -406.775576)
			(xy 58.245388 -406.734385) (xy 58.286579 -406.698693) (xy 58.33243 -406.669227) (xy 58.382008 -406.646586)
			(xy 58.434304 -406.631231) (xy 58.488252 -406.623475) (xy 58.515504 -406.623012) (xy 59.379104 -406.623012)
			(xy 59.406356 -406.623458) (xy 59.460307 -406.631215) (xy 59.512604 -406.646572) (xy 59.562183 -406.669214)
			(xy 59.608035 -406.698682) (xy 59.649227 -406.734376) (xy 59.68492 -406.775568) (xy 59.714388 -406.821421)
			(xy 59.73703 -406.871) (xy 59.752385 -406.923297) (xy 59.760142 -406.977248) (xy 59.760142 -407.031752)
			(xy 59.760142 -407.031753) (xy 61.197675 -407.031753) (xy 61.197675 -406.977247) (xy 61.205433 -406.923295)
			(xy 61.220791 -406.870996) (xy 61.243435 -406.821416) (xy 61.272906 -406.775563) (xy 61.308602 -406.734371)
			(xy 61.349798 -406.698679) (xy 61.395654 -406.669214) (xy 61.445237 -406.646575) (xy 61.497538 -406.631224)
			(xy 61.551491 -406.623472) (xy 61.578744 -406.623012) (xy 62.442344 -406.623012) (xy 62.469595 -406.623461)
			(xy 62.52354 -406.631223) (xy 62.575833 -406.646583) (xy 62.625407 -406.669227) (xy 62.671254 -406.698696)
			(xy 62.712441 -406.73439) (xy 62.74813 -406.775581) (xy 62.777594 -406.821432) (xy 62.800233 -406.871009)
			(xy 62.815587 -406.923303) (xy 62.823342 -406.977249) (xy 62.823342 -407.031749) (xy 64.260998 -407.031749)
			(xy 64.260998 -406.977251) (xy 64.268754 -406.923308) (xy 64.284107 -406.871017) (xy 64.306746 -406.821443)
			(xy 64.336209 -406.775596) (xy 64.371897 -406.734409) (xy 64.413083 -406.698719) (xy 64.458929 -406.669254)
			(xy 64.508502 -406.646613) (xy 64.560792 -406.631257) (xy 64.614735 -406.623499) (xy 64.641984 -406.623012)
			(xy 65.505584 -406.623012) (xy 65.532839 -406.623434) (xy 65.586795 -406.631189) (xy 65.639097 -406.646545)
			(xy 65.688682 -406.669188) (xy 65.73454 -406.698657) (xy 65.775736 -406.734352) (xy 65.811434 -406.775548)
			(xy 65.840905 -406.821404) (xy 65.86355 -406.870988) (xy 65.878907 -406.92329) (xy 65.886665 -406.977245)
			(xy 65.886665 -407.031753) (xy 67.324175 -407.031753) (xy 67.324175 -406.977247) (xy 67.331933 -406.923297)
			(xy 67.347289 -406.871) (xy 67.369932 -406.821421) (xy 67.399401 -406.775569) (xy 67.435095 -406.734378)
			(xy 67.476288 -406.698686) (xy 67.522142 -406.669221) (xy 67.571723 -406.646581) (xy 67.624021 -406.631227)
			(xy 67.677971 -406.623474) (xy 67.705224 -406.623012) (xy 68.568824 -406.623012) (xy 68.596076 -406.623459)
			(xy 68.650024 -406.631219) (xy 68.702318 -406.646577) (xy 68.751895 -406.669221) (xy 68.797745 -406.698689)
			(xy 68.838934 -406.734383) (xy 68.874625 -406.775575) (xy 68.904091 -406.821426) (xy 68.926731 -406.871004)
			(xy 68.942086 -406.9233) (xy 68.949842 -406.977248) (xy 68.949842 -407.031748) (xy 70.387498 -407.031748)
			(xy 70.387498 -406.977252) (xy 70.395253 -406.92331) (xy 70.410606 -406.871021) (xy 70.433243 -406.821449)
			(xy 70.462704 -406.775603) (xy 70.49839 -406.734416) (xy 70.539574 -406.698726) (xy 70.585417 -406.66926)
			(xy 70.634987 -406.646618) (xy 70.687275 -406.631261) (xy 70.741216 -406.623501) (xy 70.768464 -406.623012)
			(xy 71.632064 -406.623012) (xy 71.65932 -406.623432) (xy 71.713278 -406.631186) (xy 71.765583 -406.646539)
			(xy 71.81517 -406.669181) (xy 71.86103 -406.69865) (xy 71.902229 -406.734345) (xy 71.937929 -406.775541)
			(xy 71.967402 -406.821398) (xy 71.990048 -406.870984) (xy 72.005407 -406.923287) (xy 72.013165 -406.977244)
			(xy 72.013165 -407.031752) (xy 73.450675 -407.031752) (xy 73.450675 -406.977248) (xy 73.458432 -406.9233)
			(xy 73.473787 -406.871005) (xy 73.496429 -406.821427) (xy 73.525896 -406.775576) (xy 73.561588 -406.734385)
			(xy 73.602779 -406.698693) (xy 73.64863 -406.669227) (xy 73.698208 -406.646586) (xy 73.750504 -406.631231)
			(xy 73.804452 -406.623475) (xy 73.831704 -406.623012) (xy 74.695304 -406.623012) (xy 74.722556 -406.623458)
			(xy 74.776507 -406.631215) (xy 74.828804 -406.646572) (xy 74.878383 -406.669214) (xy 74.924235 -406.698682)
			(xy 74.965427 -406.734376) (xy 75.00112 -406.775568) (xy 75.030588 -406.821421) (xy 75.05323 -406.871)
			(xy 75.068585 -406.923297) (xy 75.076342 -406.977248) (xy 75.076342 -407.031752) (xy 75.076342 -407.031753)
			(xy 76.513875 -407.031753) (xy 76.513875 -406.977247) (xy 76.521633 -406.923295) (xy 76.536991 -406.870996)
			(xy 76.559635 -406.821416) (xy 76.589106 -406.775563) (xy 76.624802 -406.734371) (xy 76.665998 -406.698679)
			(xy 76.711854 -406.669214) (xy 76.761437 -406.646575) (xy 76.813738 -406.631224) (xy 76.867691 -406.623472)
			(xy 76.894944 -406.623012) (xy 77.758544 -406.623012) (xy 77.785795 -406.623461) (xy 77.83974 -406.631223)
			(xy 77.892033 -406.646583) (xy 77.941607 -406.669227) (xy 77.987454 -406.698696) (xy 78.028641 -406.73439)
			(xy 78.06433 -406.775581) (xy 78.093794 -406.821432) (xy 78.116433 -406.871009) (xy 78.131787 -406.923303)
			(xy 78.139542 -406.977249) (xy 78.139542 -407.031749) (xy 79.577198 -407.031749) (xy 79.577198 -406.977251)
			(xy 79.584954 -406.923308) (xy 79.600307 -406.871017) (xy 79.622946 -406.821443) (xy 79.652409 -406.775596)
			(xy 79.688097 -406.734409) (xy 79.729283 -406.698719) (xy 79.775129 -406.669254) (xy 79.824702 -406.646613)
			(xy 79.876992 -406.631257) (xy 79.930935 -406.623499) (xy 79.958184 -406.623012) (xy 80.821784 -406.623012)
			(xy 80.849039 -406.623434) (xy 80.902995 -406.631189) (xy 80.955297 -406.646545) (xy 81.004882 -406.669188)
			(xy 81.05074 -406.698657) (xy 81.091936 -406.734352) (xy 81.127634 -406.775548) (xy 81.157105 -406.821404)
			(xy 81.17975 -406.870988) (xy 81.195107 -406.92329) (xy 81.202865 -406.977245) (xy 81.202865 -407.031753)
			(xy 82.640375 -407.031753) (xy 82.640375 -406.977247) (xy 82.648133 -406.923297) (xy 82.663489 -406.871)
			(xy 82.686132 -406.821421) (xy 82.715601 -406.775569) (xy 82.751295 -406.734378) (xy 82.792488 -406.698686)
			(xy 82.838342 -406.669221) (xy 82.887923 -406.646581) (xy 82.940221 -406.631227) (xy 82.994171 -406.623474)
			(xy 83.021424 -406.623012) (xy 83.885024 -406.623012) (xy 83.912276 -406.623459) (xy 83.966224 -406.631219)
			(xy 84.018518 -406.646577) (xy 84.068095 -406.669221) (xy 84.113945 -406.698689) (xy 84.155134 -406.734383)
			(xy 84.190825 -406.775575) (xy 84.220291 -406.821426) (xy 84.242931 -406.871004) (xy 84.258286 -406.9233)
			(xy 84.266042 -406.977248) (xy 84.266042 -407.031748) (xy 85.703698 -407.031748) (xy 85.703698 -406.977252)
			(xy 85.711453 -406.92331) (xy 85.726806 -406.871021) (xy 85.749443 -406.821449) (xy 85.778904 -406.775603)
			(xy 85.81459 -406.734416) (xy 85.855774 -406.698726) (xy 85.901617 -406.66926) (xy 85.951187 -406.646618)
			(xy 86.003475 -406.631261) (xy 86.057416 -406.623501) (xy 86.084664 -406.623012) (xy 86.948264 -406.623012)
			(xy 86.97552 -406.623432) (xy 87.029478 -406.631186) (xy 87.081783 -406.646539) (xy 87.13137 -406.669181)
			(xy 87.17723 -406.69865) (xy 87.218429 -406.734345) (xy 87.254129 -406.775541) (xy 87.283602 -406.821398)
			(xy 87.306248 -406.870984) (xy 87.321607 -406.923287) (xy 87.329365 -406.977244) (xy 87.329365 -407.031752)
			(xy 88.766875 -407.031752) (xy 88.766875 -406.977248) (xy 88.774632 -406.9233) (xy 88.789987 -406.871005)
			(xy 88.812629 -406.821427) (xy 88.842096 -406.775576) (xy 88.877788 -406.734385) (xy 88.918979 -406.698693)
			(xy 88.96483 -406.669227) (xy 89.014408 -406.646586) (xy 89.066704 -406.631231) (xy 89.120652 -406.623475)
			(xy 89.147904 -406.623012) (xy 90.011504 -406.623012) (xy 90.038756 -406.623458) (xy 90.092707 -406.631215)
			(xy 90.145004 -406.646572) (xy 90.194583 -406.669214) (xy 90.240435 -406.698682) (xy 90.281627 -406.734376)
			(xy 90.31732 -406.775568) (xy 90.346788 -406.821421) (xy 90.36943 -406.871) (xy 90.384785 -406.923297)
			(xy 90.392542 -406.977248) (xy 90.392542 -407.031752) (xy 90.392542 -407.031753) (xy 91.830075 -407.031753)
			(xy 91.830075 -406.977247) (xy 91.837833 -406.923295) (xy 91.853191 -406.870996) (xy 91.875835 -406.821416)
			(xy 91.905306 -406.775563) (xy 91.941002 -406.734371) (xy 91.982198 -406.698679) (xy 92.028054 -406.669214)
			(xy 92.077637 -406.646575) (xy 92.129938 -406.631224) (xy 92.183891 -406.623472) (xy 92.211144 -406.623012)
			(xy 93.074744 -406.623012) (xy 93.101995 -406.623461) (xy 93.15594 -406.631223) (xy 93.208233 -406.646583)
			(xy 93.257807 -406.669227) (xy 93.303654 -406.698696) (xy 93.344841 -406.73439) (xy 93.38053 -406.775581)
			(xy 93.409994 -406.821432) (xy 93.432633 -406.871009) (xy 93.447987 -406.923303) (xy 93.455742 -406.977249)
			(xy 93.455742 -407.031749) (xy 94.893398 -407.031749) (xy 94.893398 -406.977251) (xy 94.901154 -406.923308)
			(xy 94.916507 -406.871017) (xy 94.939146 -406.821443) (xy 94.968609 -406.775596) (xy 95.004297 -406.734409)
			(xy 95.045483 -406.698719) (xy 95.091329 -406.669254) (xy 95.140902 -406.646613) (xy 95.193192 -406.631257)
			(xy 95.247135 -406.623499) (xy 95.274384 -406.623012) (xy 96.137984 -406.623012) (xy 96.165239 -406.623434)
			(xy 96.219195 -406.631189) (xy 96.271497 -406.646545) (xy 96.321082 -406.669188) (xy 96.36694 -406.698657)
			(xy 96.408136 -406.734352) (xy 96.443834 -406.775548) (xy 96.473305 -406.821404) (xy 96.49595 -406.870988)
			(xy 96.511307 -406.92329) (xy 96.519065 -406.977245) (xy 96.519065 -407.031753) (xy 116.044675 -407.031753)
			(xy 116.044675 -406.977247) (xy 116.052433 -406.923297) (xy 116.067789 -406.871) (xy 116.090432 -406.821421)
			(xy 116.119901 -406.775569) (xy 116.155596 -406.734377) (xy 116.196789 -406.698686) (xy 116.242643 -406.66922)
			(xy 116.292224 -406.64658) (xy 116.344522 -406.631227) (xy 116.398473 -406.623474) (xy 116.425726 -406.623012)
			(xy 117.289326 -406.623012) (xy 117.316577 -406.62346) (xy 117.370525 -406.63122) (xy 117.42282 -406.646578)
			(xy 117.472396 -406.669222) (xy 117.518246 -406.69869) (xy 117.559435 -406.734383) (xy 117.595126 -406.775575)
			(xy 117.624591 -406.821427) (xy 117.647231 -406.871005) (xy 117.662586 -406.9233) (xy 117.670342 -406.977249)
			(xy 117.670342 -407.031748) (xy 119.107998 -407.031748) (xy 119.107998 -406.977252) (xy 119.115753 -406.92331)
			(xy 119.131106 -406.871021) (xy 119.153743 -406.821448) (xy 119.183205 -406.775602) (xy 119.218891 -406.734415)
			(xy 119.260075 -406.698725) (xy 119.305918 -406.66926) (xy 119.355489 -406.646618) (xy 119.407777 -406.631261)
			(xy 119.461718 -406.623501) (xy 119.488966 -406.623012) (xy 120.352566 -406.623012) (xy 120.379822 -406.623433)
			(xy 120.433779 -406.631186) (xy 120.486084 -406.64654) (xy 120.535671 -406.669182) (xy 120.581531 -406.69865)
			(xy 120.62273 -406.734346) (xy 120.658429 -406.775542) (xy 120.687902 -406.821399) (xy 120.710548 -406.870984)
			(xy 120.725907 -406.923287) (xy 120.733665 -406.977244) (xy 120.733665 -407.031752) (xy 122.171175 -407.031752)
			(xy 122.171175 -406.977248) (xy 122.178932 -406.9233) (xy 122.194288 -406.871004) (xy 122.216929 -406.821426)
			(xy 122.246396 -406.775575) (xy 122.282089 -406.734384) (xy 122.32328 -406.698693) (xy 122.369131 -406.669226)
			(xy 122.41871 -406.646585) (xy 122.471006 -406.631231) (xy 122.524954 -406.623475) (xy 122.552206 -406.623012)
			(xy 123.415806 -406.623012) (xy 123.443058 -406.623458) (xy 123.497008 -406.631216) (xy 123.549305 -406.646572)
			(xy 123.598884 -406.669215) (xy 123.644736 -406.698683) (xy 123.685928 -406.734376) (xy 123.721621 -406.775569)
			(xy 123.751088 -406.821421) (xy 123.77373 -406.871001) (xy 123.789085 -406.923298) (xy 123.796842 -406.977248)
			(xy 123.796842 -407.031752) (xy 123.796842 -407.031754) (xy 125.234375 -407.031754) (xy 125.234375 -406.977246)
			(xy 125.242133 -406.923294) (xy 125.257491 -406.870996) (xy 125.280135 -406.821415) (xy 125.309606 -406.775562)
			(xy 125.345303 -406.73437) (xy 125.386499 -406.698679) (xy 125.432355 -406.669213) (xy 125.481939 -406.646575)
			(xy 125.534239 -406.631223) (xy 125.588192 -406.623472) (xy 125.615446 -406.623012) (xy 126.479046 -406.623012)
			(xy 126.506297 -406.623461) (xy 126.560242 -406.631223) (xy 126.612534 -406.646583) (xy 126.662108 -406.669228)
			(xy 126.707955 -406.698697) (xy 126.749142 -406.734391) (xy 126.78483 -406.775582) (xy 126.814294 -406.821432)
			(xy 126.836933 -406.871009) (xy 126.852287 -406.923303) (xy 126.860042 -406.977249) (xy 126.860042 -407.031749)
			(xy 128.297698 -407.031749) (xy 128.297698 -406.977251) (xy 128.305454 -406.923307) (xy 128.320808 -406.871016)
			(xy 128.343446 -406.821443) (xy 128.37291 -406.775596) (xy 128.408598 -406.734408) (xy 128.449784 -406.698718)
			(xy 128.49563 -406.669253) (xy 128.545203 -406.646612) (xy 128.597494 -406.631257) (xy 128.651437 -406.623499)
			(xy 128.678686 -406.623012) (xy 129.542286 -406.623012) (xy 129.569541 -406.623434) (xy 129.623496 -406.63119)
			(xy 129.675799 -406.646545) (xy 129.725383 -406.669188) (xy 129.771241 -406.698657) (xy 129.812437 -406.734353)
			(xy 129.848134 -406.775548) (xy 129.877605 -406.821405) (xy 129.90025 -406.870988) (xy 129.915607 -406.92329)
			(xy 129.923365 -406.977245) (xy 129.923365 -407.031753) (xy 131.360875 -407.031753) (xy 131.360875 -406.977247)
			(xy 131.368633 -406.923297) (xy 131.383989 -406.871) (xy 131.406632 -406.821421) (xy 131.436101 -406.775569)
			(xy 131.471796 -406.734377) (xy 131.512989 -406.698686) (xy 131.558843 -406.66922) (xy 131.608424 -406.64658)
			(xy 131.660722 -406.631227) (xy 131.714673 -406.623474) (xy 131.741926 -406.623012) (xy 132.605526 -406.623012)
			(xy 132.632777 -406.62346) (xy 132.686725 -406.63122) (xy 132.73902 -406.646578) (xy 132.788596 -406.669222)
			(xy 132.834446 -406.69869) (xy 132.875635 -406.734383) (xy 132.911326 -406.775575) (xy 132.940791 -406.821427)
			(xy 132.963431 -406.871005) (xy 132.978786 -406.9233) (xy 132.986542 -406.977249) (xy 132.986542 -407.031748)
			(xy 134.424198 -407.031748) (xy 134.424198 -406.977252) (xy 134.431953 -406.92331) (xy 134.447306 -406.871021)
			(xy 134.469943 -406.821448) (xy 134.499405 -406.775602) (xy 134.535091 -406.734415) (xy 134.576275 -406.698725)
			(xy 134.622118 -406.66926) (xy 134.671689 -406.646618) (xy 134.723977 -406.631261) (xy 134.777918 -406.623501)
			(xy 134.805166 -406.623012) (xy 135.668766 -406.623012) (xy 135.696022 -406.623433) (xy 135.749979 -406.631186)
			(xy 135.802284 -406.64654) (xy 135.851871 -406.669182) (xy 135.897731 -406.69865) (xy 135.93893 -406.734346)
			(xy 135.974629 -406.775542) (xy 136.004102 -406.821399) (xy 136.026748 -406.870984) (xy 136.042107 -406.923287)
			(xy 136.049865 -406.977244) (xy 136.049865 -407.031752) (xy 137.487375 -407.031752) (xy 137.487375 -406.977248)
			(xy 137.495132 -406.9233) (xy 137.510488 -406.871004) (xy 137.533129 -406.821426) (xy 137.562596 -406.775575)
			(xy 137.598289 -406.734384) (xy 137.63948 -406.698693) (xy 137.685331 -406.669226) (xy 137.73491 -406.646585)
			(xy 137.787206 -406.631231) (xy 137.841154 -406.623475) (xy 137.868406 -406.623012) (xy 138.732006 -406.623012)
			(xy 138.759258 -406.623458) (xy 138.813208 -406.631216) (xy 138.865505 -406.646572) (xy 138.915084 -406.669215)
			(xy 138.960936 -406.698683) (xy 139.002128 -406.734376) (xy 139.037821 -406.775569) (xy 139.067288 -406.821421)
			(xy 139.08993 -406.871001) (xy 139.105285 -406.923298) (xy 139.113042 -406.977248) (xy 139.113042 -407.031752)
			(xy 139.113042 -407.031754) (xy 140.550575 -407.031754) (xy 140.550575 -406.977246) (xy 140.558333 -406.923294)
			(xy 140.573691 -406.870996) (xy 140.596335 -406.821415) (xy 140.625806 -406.775562) (xy 140.661503 -406.73437)
			(xy 140.702699 -406.698679) (xy 140.748555 -406.669213) (xy 140.798139 -406.646575) (xy 140.850439 -406.631223)
			(xy 140.904392 -406.623472) (xy 140.931646 -406.623012) (xy 141.795246 -406.623012) (xy 141.822497 -406.623461)
			(xy 141.876442 -406.631223) (xy 141.928734 -406.646583) (xy 141.978308 -406.669228) (xy 142.024155 -406.698697)
			(xy 142.065342 -406.734391) (xy 142.10103 -406.775582) (xy 142.130494 -406.821432) (xy 142.153133 -406.871009)
			(xy 142.168487 -406.923303) (xy 142.176242 -406.977249) (xy 142.176242 -407.031749) (xy 143.613898 -407.031749)
			(xy 143.613898 -406.977251) (xy 143.621654 -406.923307) (xy 143.637008 -406.871016) (xy 143.659646 -406.821443)
			(xy 143.68911 -406.775596) (xy 143.724798 -406.734408) (xy 143.765984 -406.698718) (xy 143.81183 -406.669253)
			(xy 143.861403 -406.646612) (xy 143.913694 -406.631257) (xy 143.967637 -406.623499) (xy 143.994886 -406.623012)
			(xy 144.858486 -406.623012) (xy 144.885741 -406.623434) (xy 144.939696 -406.63119) (xy 144.991999 -406.646545)
			(xy 145.041583 -406.669188) (xy 145.087441 -406.698657) (xy 145.128637 -406.734353) (xy 145.164334 -406.775548)
			(xy 145.193805 -406.821405) (xy 145.21645 -406.870988) (xy 145.231807 -406.92329) (xy 145.239565 -406.977245)
			(xy 145.239565 -407.031753) (xy 146.677075 -407.031753) (xy 146.677075 -406.977247) (xy 146.684833 -406.923297)
			(xy 146.700189 -406.871) (xy 146.722832 -406.821421) (xy 146.752301 -406.775569) (xy 146.787996 -406.734377)
			(xy 146.829189 -406.698686) (xy 146.875043 -406.66922) (xy 146.924624 -406.64658) (xy 146.976922 -406.631227)
			(xy 147.030873 -406.623474) (xy 147.058126 -406.623012) (xy 147.921726 -406.623012) (xy 147.948977 -406.62346)
			(xy 148.002925 -406.63122) (xy 148.05522 -406.646578) (xy 148.104796 -406.669222) (xy 148.150646 -406.69869)
			(xy 148.191835 -406.734383) (xy 148.227526 -406.775575) (xy 148.256991 -406.821427) (xy 148.279631 -406.871005)
			(xy 148.294986 -406.9233) (xy 148.302742 -406.977249) (xy 148.302742 -407.031748) (xy 149.740398 -407.031748)
			(xy 149.740398 -406.977252) (xy 149.748153 -406.92331) (xy 149.763506 -406.871021) (xy 149.786143 -406.821448)
			(xy 149.815605 -406.775602) (xy 149.851291 -406.734415) (xy 149.892475 -406.698725) (xy 149.938318 -406.66926)
			(xy 149.987889 -406.646618) (xy 150.040177 -406.631261) (xy 150.094118 -406.623501) (xy 150.121366 -406.623012)
			(xy 150.984966 -406.623012) (xy 151.012222 -406.623433) (xy 151.066179 -406.631186) (xy 151.118484 -406.64654)
			(xy 151.168071 -406.669182) (xy 151.213931 -406.69865) (xy 151.25513 -406.734346) (xy 151.290829 -406.775542)
			(xy 151.320302 -406.821399) (xy 151.342948 -406.870984) (xy 151.358307 -406.923287) (xy 151.366065 -406.977244)
			(xy 151.366065 -407.031752) (xy 152.803575 -407.031752) (xy 152.803575 -406.977248) (xy 152.811332 -406.9233)
			(xy 152.826688 -406.871004) (xy 152.849329 -406.821426) (xy 152.878796 -406.775575) (xy 152.914489 -406.734384)
			(xy 152.95568 -406.698693) (xy 153.001531 -406.669226) (xy 153.05111 -406.646585) (xy 153.103406 -406.631231)
			(xy 153.157354 -406.623475) (xy 153.184606 -406.623012) (xy 154.048206 -406.623012) (xy 154.075458 -406.623458)
			(xy 154.129408 -406.631216) (xy 154.181705 -406.646572) (xy 154.231284 -406.669215) (xy 154.277136 -406.698683)
			(xy 154.318328 -406.734376) (xy 154.354021 -406.775569) (xy 154.383488 -406.821421) (xy 154.40613 -406.871001)
			(xy 154.421485 -406.923298) (xy 154.429242 -406.977248) (xy 154.429242 -407.031752) (xy 154.429242 -407.031754)
			(xy 155.866775 -407.031754) (xy 155.866775 -406.977246) (xy 155.874533 -406.923294) (xy 155.889891 -406.870996)
			(xy 155.912535 -406.821415) (xy 155.942006 -406.775562) (xy 155.977703 -406.73437) (xy 156.018899 -406.698679)
			(xy 156.064755 -406.669213) (xy 156.114339 -406.646575) (xy 156.166639 -406.631223) (xy 156.220592 -406.623472)
			(xy 156.247846 -406.623012) (xy 157.111446 -406.623012) (xy 157.138697 -406.623461) (xy 157.192642 -406.631223)
			(xy 157.244934 -406.646583) (xy 157.294508 -406.669228) (xy 157.340355 -406.698697) (xy 157.381542 -406.734391)
			(xy 157.41723 -406.775582) (xy 157.446694 -406.821432) (xy 157.469333 -406.871009) (xy 157.484687 -406.923303)
			(xy 157.492442 -406.977249) (xy 157.492442 -407.031749) (xy 158.930098 -407.031749) (xy 158.930098 -406.977251)
			(xy 158.937854 -406.923307) (xy 158.953208 -406.871016) (xy 158.975846 -406.821443) (xy 159.00531 -406.775596)
			(xy 159.040998 -406.734408) (xy 159.082184 -406.698718) (xy 159.12803 -406.669253) (xy 159.177603 -406.646612)
			(xy 159.229894 -406.631257) (xy 159.283837 -406.623499) (xy 159.311086 -406.623012) (xy 160.174686 -406.623012)
			(xy 160.201941 -406.623434) (xy 160.255896 -406.63119) (xy 160.308199 -406.646545) (xy 160.357783 -406.669188)
			(xy 160.403641 -406.698657) (xy 160.444837 -406.734353) (xy 160.480534 -406.775548) (xy 160.510005 -406.821405)
			(xy 160.53265 -406.870988) (xy 160.548007 -406.92329) (xy 160.555765 -406.977245) (xy 160.555765 -407.031753)
			(xy 161.993275 -407.031753) (xy 161.993275 -406.977247) (xy 162.001033 -406.923297) (xy 162.016389 -406.871)
			(xy 162.039032 -406.821421) (xy 162.068501 -406.775569) (xy 162.104196 -406.734377) (xy 162.145389 -406.698686)
			(xy 162.191243 -406.66922) (xy 162.240824 -406.64658) (xy 162.293122 -406.631227) (xy 162.347073 -406.623474)
			(xy 162.374326 -406.623012) (xy 163.237926 -406.623012) (xy 163.265177 -406.62346) (xy 163.319125 -406.63122)
			(xy 163.37142 -406.646578) (xy 163.420996 -406.669222) (xy 163.466846 -406.69869) (xy 163.508035 -406.734383)
			(xy 163.543726 -406.775575) (xy 163.573191 -406.821427) (xy 163.595831 -406.871005) (xy 163.611186 -406.9233)
			(xy 163.618942 -406.977249) (xy 163.618942 -407.031751) (xy 163.611186 -407.0857) (xy 163.595831 -407.137995)
			(xy 163.573191 -407.187573) (xy 163.543726 -407.233425) (xy 163.508035 -407.274617) (xy 163.466846 -407.31031)
			(xy 163.420996 -407.339778) (xy 163.37142 -407.362422) (xy 163.319125 -407.37778) (xy 163.265177 -407.38554)
			(xy 163.237926 -407.386028) (xy 162.374326 -407.386028) (xy 162.347073 -407.385526) (xy 162.293122 -407.377773)
			(xy 162.240824 -407.36242) (xy 162.191243 -407.33978) (xy 162.145389 -407.310314) (xy 162.104196 -407.274623)
			(xy 162.068501 -407.233431) (xy 162.039032 -407.187579) (xy 162.016389 -407.138) (xy 162.001033 -407.085703)
			(xy 161.993275 -407.031753) (xy 160.555765 -407.031753) (xy 160.555765 -407.031755) (xy 160.548007 -407.08571)
			(xy 160.53265 -407.138012) (xy 160.510005 -407.187595) (xy 160.480534 -407.233452) (xy 160.444837 -407.274647)
			(xy 160.403641 -407.310343) (xy 160.357783 -407.339812) (xy 160.308199 -407.362455) (xy 160.255896 -407.37781)
			(xy 160.201941 -407.385566) (xy 160.174686 -407.386028) (xy 159.311086 -407.386028) (xy 159.283837 -407.385501)
			(xy 159.229894 -407.377743) (xy 159.177603 -407.362388) (xy 159.12803 -407.339747) (xy 159.082184 -407.310282)
			(xy 159.040998 -407.274592) (xy 159.00531 -407.233404) (xy 158.975846 -407.187557) (xy 158.953208 -407.137984)
			(xy 158.937854 -407.085693) (xy 158.930098 -407.031749) (xy 157.492442 -407.031749) (xy 157.492442 -407.031751)
			(xy 157.484687 -407.085697) (xy 157.469333 -407.137991) (xy 157.446694 -407.187568) (xy 157.41723 -407.233418)
			(xy 157.381542 -407.274609) (xy 157.340355 -407.310303) (xy 157.294508 -407.339772) (xy 157.244934 -407.362417)
			(xy 157.192642 -407.377777) (xy 157.138697 -407.385539) (xy 157.111446 -407.386028) (xy 156.247846 -407.386028)
			(xy 156.220592 -407.385528) (xy 156.166639 -407.377777) (xy 156.114339 -407.362425) (xy 156.064755 -407.339787)
			(xy 156.018899 -407.310321) (xy 155.977703 -407.27463) (xy 155.942006 -407.233438) (xy 155.912535 -407.187585)
			(xy 155.889891 -407.138004) (xy 155.874533 -407.085706) (xy 155.866775 -407.031754) (xy 154.429242 -407.031754)
			(xy 154.421485 -407.085702) (xy 154.40613 -407.137999) (xy 154.383488 -407.187579) (xy 154.354021 -407.233431)
			(xy 154.318328 -407.274624) (xy 154.277136 -407.310317) (xy 154.231284 -407.339785) (xy 154.181705 -407.362428)
			(xy 154.129408 -407.377784) (xy 154.075458 -407.385542) (xy 154.048206 -407.386028) (xy 153.184606 -407.386028)
			(xy 153.157354 -407.385525) (xy 153.103406 -407.377769) (xy 153.05111 -407.362415) (xy 153.001531 -407.339774)
			(xy 152.95568 -407.310307) (xy 152.914489 -407.274616) (xy 152.878796 -407.233425) (xy 152.849329 -407.187574)
			(xy 152.826688 -407.137996) (xy 152.811332 -407.0857) (xy 152.803575 -407.031752) (xy 151.366065 -407.031752)
			(xy 151.366065 -407.031756) (xy 151.358307 -407.085713) (xy 151.342948 -407.138016) (xy 151.320302 -407.187601)
			(xy 151.290829 -407.233458) (xy 151.25513 -407.274654) (xy 151.213931 -407.31035) (xy 151.168071 -407.339818)
			(xy 151.118484 -407.36246) (xy 151.066179 -407.377814) (xy 151.012222 -407.385567) (xy 150.984966 -407.386028)
			(xy 150.121366 -407.386028) (xy 150.094118 -407.385499) (xy 150.040177 -407.377739) (xy 149.987889 -407.362382)
			(xy 149.938318 -407.33974) (xy 149.892475 -407.310275) (xy 149.851291 -407.274585) (xy 149.815605 -407.233398)
			(xy 149.786143 -407.187552) (xy 149.763506 -407.137979) (xy 149.748153 -407.08569) (xy 149.740398 -407.031748)
			(xy 148.302742 -407.031748) (xy 148.302742 -407.031751) (xy 148.294986 -407.0857) (xy 148.279631 -407.137995)
			(xy 148.256991 -407.187573) (xy 148.227526 -407.233425) (xy 148.191835 -407.274617) (xy 148.150646 -407.31031)
			(xy 148.104796 -407.339778) (xy 148.05522 -407.362422) (xy 148.002925 -407.37778) (xy 147.948977 -407.38554)
			(xy 147.921726 -407.386028) (xy 147.058126 -407.386028) (xy 147.030873 -407.385526) (xy 146.976922 -407.377773)
			(xy 146.924624 -407.36242) (xy 146.875043 -407.33978) (xy 146.829189 -407.310314) (xy 146.787996 -407.274623)
			(xy 146.752301 -407.233431) (xy 146.722832 -407.187579) (xy 146.700189 -407.138) (xy 146.684833 -407.085703)
			(xy 146.677075 -407.031753) (xy 145.239565 -407.031753) (xy 145.239565 -407.031755) (xy 145.231807 -407.08571)
			(xy 145.21645 -407.138012) (xy 145.193805 -407.187595) (xy 145.164334 -407.233452) (xy 145.128637 -407.274647)
			(xy 145.087441 -407.310343) (xy 145.041583 -407.339812) (xy 144.991999 -407.362455) (xy 144.939696 -407.37781)
			(xy 144.885741 -407.385566) (xy 144.858486 -407.386028) (xy 143.994886 -407.386028) (xy 143.967637 -407.385501)
			(xy 143.913694 -407.377743) (xy 143.861403 -407.362388) (xy 143.81183 -407.339747) (xy 143.765984 -407.310282)
			(xy 143.724798 -407.274592) (xy 143.68911 -407.233404) (xy 143.659646 -407.187557) (xy 143.637008 -407.137984)
			(xy 143.621654 -407.085693) (xy 143.613898 -407.031749) (xy 142.176242 -407.031749) (xy 142.176242 -407.031751)
			(xy 142.168487 -407.085697) (xy 142.153133 -407.137991) (xy 142.130494 -407.187568) (xy 142.10103 -407.233418)
			(xy 142.065342 -407.274609) (xy 142.024155 -407.310303) (xy 141.978308 -407.339772) (xy 141.928734 -407.362417)
			(xy 141.876442 -407.377777) (xy 141.822497 -407.385539) (xy 141.795246 -407.386028) (xy 140.931646 -407.386028)
			(xy 140.904392 -407.385528) (xy 140.850439 -407.377777) (xy 140.798139 -407.362425) (xy 140.748555 -407.339787)
			(xy 140.702699 -407.310321) (xy 140.661503 -407.27463) (xy 140.625806 -407.233438) (xy 140.596335 -407.187585)
			(xy 140.573691 -407.138004) (xy 140.558333 -407.085706) (xy 140.550575 -407.031754) (xy 139.113042 -407.031754)
			(xy 139.105285 -407.085702) (xy 139.08993 -407.137999) (xy 139.067288 -407.187579) (xy 139.037821 -407.233431)
			(xy 139.002128 -407.274624) (xy 138.960936 -407.310317) (xy 138.915084 -407.339785) (xy 138.865505 -407.362428)
			(xy 138.813208 -407.377784) (xy 138.759258 -407.385542) (xy 138.732006 -407.386028) (xy 137.868406 -407.386028)
			(xy 137.841154 -407.385525) (xy 137.787206 -407.377769) (xy 137.73491 -407.362415) (xy 137.685331 -407.339774)
			(xy 137.63948 -407.310307) (xy 137.598289 -407.274616) (xy 137.562596 -407.233425) (xy 137.533129 -407.187574)
			(xy 137.510488 -407.137996) (xy 137.495132 -407.0857) (xy 137.487375 -407.031752) (xy 136.049865 -407.031752)
			(xy 136.049865 -407.031756) (xy 136.042107 -407.085713) (xy 136.026748 -407.138016) (xy 136.004102 -407.187601)
			(xy 135.974629 -407.233458) (xy 135.93893 -407.274654) (xy 135.897731 -407.31035) (xy 135.851871 -407.339818)
			(xy 135.802284 -407.36246) (xy 135.749979 -407.377814) (xy 135.696022 -407.385567) (xy 135.668766 -407.386028)
			(xy 134.805166 -407.386028) (xy 134.777918 -407.385499) (xy 134.723977 -407.377739) (xy 134.671689 -407.362382)
			(xy 134.622118 -407.33974) (xy 134.576275 -407.310275) (xy 134.535091 -407.274585) (xy 134.499405 -407.233398)
			(xy 134.469943 -407.187552) (xy 134.447306 -407.137979) (xy 134.431953 -407.08569) (xy 134.424198 -407.031748)
			(xy 132.986542 -407.031748) (xy 132.986542 -407.031751) (xy 132.978786 -407.0857) (xy 132.963431 -407.137995)
			(xy 132.940791 -407.187573) (xy 132.911326 -407.233425) (xy 132.875635 -407.274617) (xy 132.834446 -407.31031)
			(xy 132.788596 -407.339778) (xy 132.73902 -407.362422) (xy 132.686725 -407.37778) (xy 132.632777 -407.38554)
			(xy 132.605526 -407.386028) (xy 131.741926 -407.386028) (xy 131.714673 -407.385526) (xy 131.660722 -407.377773)
			(xy 131.608424 -407.36242) (xy 131.558843 -407.33978) (xy 131.512989 -407.310314) (xy 131.471796 -407.274623)
			(xy 131.436101 -407.233431) (xy 131.406632 -407.187579) (xy 131.383989 -407.138) (xy 131.368633 -407.085703)
			(xy 131.360875 -407.031753) (xy 129.923365 -407.031753) (xy 129.923365 -407.031755) (xy 129.915607 -407.08571)
			(xy 129.90025 -407.138012) (xy 129.877605 -407.187595) (xy 129.848134 -407.233452) (xy 129.812437 -407.274647)
			(xy 129.771241 -407.310343) (xy 129.725383 -407.339812) (xy 129.675799 -407.362455) (xy 129.623496 -407.37781)
			(xy 129.569541 -407.385566) (xy 129.542286 -407.386028) (xy 128.678686 -407.386028) (xy 128.651437 -407.385501)
			(xy 128.597494 -407.377743) (xy 128.545203 -407.362388) (xy 128.49563 -407.339747) (xy 128.449784 -407.310282)
			(xy 128.408598 -407.274592) (xy 128.37291 -407.233404) (xy 128.343446 -407.187557) (xy 128.320808 -407.137984)
			(xy 128.305454 -407.085693) (xy 128.297698 -407.031749) (xy 126.860042 -407.031749) (xy 126.860042 -407.031751)
			(xy 126.852287 -407.085697) (xy 126.836933 -407.137991) (xy 126.814294 -407.187568) (xy 126.78483 -407.233418)
			(xy 126.749142 -407.274609) (xy 126.707955 -407.310303) (xy 126.662108 -407.339772) (xy 126.612534 -407.362417)
			(xy 126.560242 -407.377777) (xy 126.506297 -407.385539) (xy 126.479046 -407.386028) (xy 125.615446 -407.386028)
			(xy 125.588192 -407.385528) (xy 125.534239 -407.377777) (xy 125.481939 -407.362425) (xy 125.432355 -407.339787)
			(xy 125.386499 -407.310321) (xy 125.345303 -407.27463) (xy 125.309606 -407.233438) (xy 125.280135 -407.187585)
			(xy 125.257491 -407.138004) (xy 125.242133 -407.085706) (xy 125.234375 -407.031754) (xy 123.796842 -407.031754)
			(xy 123.789085 -407.085702) (xy 123.77373 -407.137999) (xy 123.751088 -407.187579) (xy 123.721621 -407.233431)
			(xy 123.685928 -407.274624) (xy 123.644736 -407.310317) (xy 123.598884 -407.339785) (xy 123.549305 -407.362428)
			(xy 123.497008 -407.377784) (xy 123.443058 -407.385542) (xy 123.415806 -407.386028) (xy 122.552206 -407.386028)
			(xy 122.524954 -407.385525) (xy 122.471006 -407.377769) (xy 122.41871 -407.362415) (xy 122.369131 -407.339774)
			(xy 122.32328 -407.310307) (xy 122.282089 -407.274616) (xy 122.246396 -407.233425) (xy 122.216929 -407.187574)
			(xy 122.194288 -407.137996) (xy 122.178932 -407.0857) (xy 122.171175 -407.031752) (xy 120.733665 -407.031752)
			(xy 120.733665 -407.031756) (xy 120.725907 -407.085713) (xy 120.710548 -407.138016) (xy 120.687902 -407.187601)
			(xy 120.658429 -407.233458) (xy 120.62273 -407.274654) (xy 120.581531 -407.31035) (xy 120.535671 -407.339818)
			(xy 120.486084 -407.36246) (xy 120.433779 -407.377814) (xy 120.379822 -407.385567) (xy 120.352566 -407.386028)
			(xy 119.488966 -407.386028) (xy 119.461718 -407.385499) (xy 119.407777 -407.377739) (xy 119.355489 -407.362382)
			(xy 119.305918 -407.33974) (xy 119.260075 -407.310275) (xy 119.218891 -407.274585) (xy 119.183205 -407.233398)
			(xy 119.153743 -407.187552) (xy 119.131106 -407.137979) (xy 119.115753 -407.08569) (xy 119.107998 -407.031748)
			(xy 117.670342 -407.031748) (xy 117.670342 -407.031751) (xy 117.662586 -407.0857) (xy 117.647231 -407.137995)
			(xy 117.624591 -407.187573) (xy 117.595126 -407.233425) (xy 117.559435 -407.274617) (xy 117.518246 -407.31031)
			(xy 117.472396 -407.339778) (xy 117.42282 -407.362422) (xy 117.370525 -407.37778) (xy 117.316577 -407.38554)
			(xy 117.289326 -407.386028) (xy 116.425726 -407.386028) (xy 116.398473 -407.385526) (xy 116.344522 -407.377773)
			(xy 116.292224 -407.36242) (xy 116.242643 -407.33978) (xy 116.196789 -407.310314) (xy 116.155596 -407.274623)
			(xy 116.119901 -407.233431) (xy 116.090432 -407.187579) (xy 116.067789 -407.138) (xy 116.052433 -407.085703)
			(xy 116.044675 -407.031753) (xy 96.519065 -407.031753) (xy 96.519065 -407.031755) (xy 96.511307 -407.08571)
			(xy 96.49595 -407.138012) (xy 96.473305 -407.187596) (xy 96.443834 -407.233452) (xy 96.408136 -407.274648)
			(xy 96.36694 -407.310343) (xy 96.321082 -407.339812) (xy 96.271497 -407.362455) (xy 96.219195 -407.377811)
			(xy 96.165239 -407.385566) (xy 96.137984 -407.386028) (xy 95.274384 -407.386028) (xy 95.247135 -407.385501)
			(xy 95.193192 -407.377743) (xy 95.140902 -407.362387) (xy 95.091329 -407.339746) (xy 95.045483 -407.310281)
			(xy 95.004297 -407.274591) (xy 94.968609 -407.233404) (xy 94.939146 -407.187557) (xy 94.916507 -407.137983)
			(xy 94.901154 -407.085692) (xy 94.893398 -407.031749) (xy 93.455742 -407.031749) (xy 93.455742 -407.031751)
			(xy 93.447987 -407.085697) (xy 93.432633 -407.137991) (xy 93.409994 -407.187568) (xy 93.38053 -407.233419)
			(xy 93.344841 -407.27461) (xy 93.303654 -407.310304) (xy 93.257807 -407.339773) (xy 93.208233 -407.362417)
			(xy 93.15594 -407.377777) (xy 93.101995 -407.385539) (xy 93.074744 -407.386028) (xy 92.211144 -407.386028)
			(xy 92.183891 -407.385528) (xy 92.129938 -407.377776) (xy 92.077637 -407.362425) (xy 92.028054 -407.339786)
			(xy 91.982198 -407.310321) (xy 91.941002 -407.274629) (xy 91.905306 -407.233437) (xy 91.875835 -407.187584)
			(xy 91.853191 -407.138004) (xy 91.837833 -407.085705) (xy 91.830075 -407.031753) (xy 90.392542 -407.031753)
			(xy 90.384785 -407.085703) (xy 90.36943 -407.138) (xy 90.346788 -407.187579) (xy 90.31732 -407.233432)
			(xy 90.281627 -407.274624) (xy 90.240435 -407.310318) (xy 90.194583 -407.339786) (xy 90.145004 -407.362428)
			(xy 90.092707 -407.377785) (xy 90.038756 -407.385542) (xy 90.011504 -407.386028) (xy 89.147904 -407.386028)
			(xy 89.120652 -407.385525) (xy 89.066704 -407.377769) (xy 89.014408 -407.362414) (xy 88.96483 -407.339773)
			(xy 88.918979 -407.310307) (xy 88.877788 -407.274615) (xy 88.842096 -407.233424) (xy 88.812629 -407.187573)
			(xy 88.789987 -407.137995) (xy 88.774632 -407.0857) (xy 88.766875 -407.031752) (xy 87.329365 -407.031752)
			(xy 87.329365 -407.031756) (xy 87.321607 -407.085713) (xy 87.306248 -407.138016) (xy 87.283602 -407.187602)
			(xy 87.254129 -407.233459) (xy 87.218429 -407.274655) (xy 87.17723 -407.31035) (xy 87.13137 -407.339819)
			(xy 87.081783 -407.362461) (xy 87.029478 -407.377814) (xy 86.97552 -407.385568) (xy 86.948264 -407.386028)
			(xy 86.084664 -407.386028) (xy 86.057416 -407.385499) (xy 86.003475 -407.377739) (xy 85.951187 -407.362382)
			(xy 85.901617 -407.33974) (xy 85.855774 -407.310274) (xy 85.81459 -407.274584) (xy 85.778904 -407.233397)
			(xy 85.749443 -407.187551) (xy 85.726806 -407.137979) (xy 85.711453 -407.08569) (xy 85.703698 -407.031748)
			(xy 84.266042 -407.031748) (xy 84.266042 -407.031752) (xy 84.258286 -407.0857) (xy 84.242931 -407.137996)
			(xy 84.220291 -407.187574) (xy 84.190825 -407.233425) (xy 84.155134 -407.274617) (xy 84.113945 -407.310311)
			(xy 84.068095 -407.339779) (xy 84.018518 -407.362423) (xy 83.966224 -407.377781) (xy 83.912276 -407.385541)
			(xy 83.885024 -407.386028) (xy 83.021424 -407.386028) (xy 82.994171 -407.385526) (xy 82.940221 -407.377773)
			(xy 82.887923 -407.362419) (xy 82.838342 -407.339779) (xy 82.792488 -407.310314) (xy 82.751295 -407.274622)
			(xy 82.715601 -407.233431) (xy 82.686132 -407.187579) (xy 82.663489 -407.138) (xy 82.648133 -407.085703)
			(xy 82.640375 -407.031753) (xy 81.202865 -407.031753) (xy 81.202865 -407.031755) (xy 81.195107 -407.08571)
			(xy 81.17975 -407.138012) (xy 81.157105 -407.187596) (xy 81.127634 -407.233452) (xy 81.091936 -407.274648)
			(xy 81.05074 -407.310343) (xy 81.004882 -407.339812) (xy 80.955297 -407.362455) (xy 80.902995 -407.377811)
			(xy 80.849039 -407.385566) (xy 80.821784 -407.386028) (xy 79.958184 -407.386028) (xy 79.930935 -407.385501)
			(xy 79.876992 -407.377743) (xy 79.824702 -407.362387) (xy 79.775129 -407.339746) (xy 79.729283 -407.310281)
			(xy 79.688097 -407.274591) (xy 79.652409 -407.233404) (xy 79.622946 -407.187557) (xy 79.600307 -407.137983)
			(xy 79.584954 -407.085692) (xy 79.577198 -407.031749) (xy 78.139542 -407.031749) (xy 78.139542 -407.031751)
			(xy 78.131787 -407.085697) (xy 78.116433 -407.137991) (xy 78.093794 -407.187568) (xy 78.06433 -407.233419)
			(xy 78.028641 -407.27461) (xy 77.987454 -407.310304) (xy 77.941607 -407.339773) (xy 77.892033 -407.362417)
			(xy 77.83974 -407.377777) (xy 77.785795 -407.385539) (xy 77.758544 -407.386028) (xy 76.894944 -407.386028)
			(xy 76.867691 -407.385528) (xy 76.813738 -407.377776) (xy 76.761437 -407.362425) (xy 76.711854 -407.339786)
			(xy 76.665998 -407.310321) (xy 76.624802 -407.274629) (xy 76.589106 -407.233437) (xy 76.559635 -407.187584)
			(xy 76.536991 -407.138004) (xy 76.521633 -407.085705) (xy 76.513875 -407.031753) (xy 75.076342 -407.031753)
			(xy 75.068585 -407.085703) (xy 75.05323 -407.138) (xy 75.030588 -407.187579) (xy 75.00112 -407.233432)
			(xy 74.965427 -407.274624) (xy 74.924235 -407.310318) (xy 74.878383 -407.339786) (xy 74.828804 -407.362428)
			(xy 74.776507 -407.377785) (xy 74.722556 -407.385542) (xy 74.695304 -407.386028) (xy 73.831704 -407.386028)
			(xy 73.804452 -407.385525) (xy 73.750504 -407.377769) (xy 73.698208 -407.362414) (xy 73.64863 -407.339773)
			(xy 73.602779 -407.310307) (xy 73.561588 -407.274615) (xy 73.525896 -407.233424) (xy 73.496429 -407.187573)
			(xy 73.473787 -407.137995) (xy 73.458432 -407.0857) (xy 73.450675 -407.031752) (xy 72.013165 -407.031752)
			(xy 72.013165 -407.031756) (xy 72.005407 -407.085713) (xy 71.990048 -407.138016) (xy 71.967402 -407.187602)
			(xy 71.937929 -407.233459) (xy 71.902229 -407.274655) (xy 71.86103 -407.31035) (xy 71.81517 -407.339819)
			(xy 71.765583 -407.362461) (xy 71.713278 -407.377814) (xy 71.65932 -407.385568) (xy 71.632064 -407.386028)
			(xy 70.768464 -407.386028) (xy 70.741216 -407.385499) (xy 70.687275 -407.377739) (xy 70.634987 -407.362382)
			(xy 70.585417 -407.33974) (xy 70.539574 -407.310274) (xy 70.49839 -407.274584) (xy 70.462704 -407.233397)
			(xy 70.433243 -407.187551) (xy 70.410606 -407.137979) (xy 70.395253 -407.08569) (xy 70.387498 -407.031748)
			(xy 68.949842 -407.031748) (xy 68.949842 -407.031752) (xy 68.942086 -407.0857) (xy 68.926731 -407.137996)
			(xy 68.904091 -407.187574) (xy 68.874625 -407.233425) (xy 68.838934 -407.274617) (xy 68.797745 -407.310311)
			(xy 68.751895 -407.339779) (xy 68.702318 -407.362423) (xy 68.650024 -407.377781) (xy 68.596076 -407.385541)
			(xy 68.568824 -407.386028) (xy 67.705224 -407.386028) (xy 67.677971 -407.385526) (xy 67.624021 -407.377773)
			(xy 67.571723 -407.362419) (xy 67.522142 -407.339779) (xy 67.476288 -407.310314) (xy 67.435095 -407.274622)
			(xy 67.399401 -407.233431) (xy 67.369932 -407.187579) (xy 67.347289 -407.138) (xy 67.331933 -407.085703)
			(xy 67.324175 -407.031753) (xy 65.886665 -407.031753) (xy 65.886665 -407.031755) (xy 65.878907 -407.08571)
			(xy 65.86355 -407.138012) (xy 65.840905 -407.187596) (xy 65.811434 -407.233452) (xy 65.775736 -407.274648)
			(xy 65.73454 -407.310343) (xy 65.688682 -407.339812) (xy 65.639097 -407.362455) (xy 65.586795 -407.377811)
			(xy 65.532839 -407.385566) (xy 65.505584 -407.386028) (xy 64.641984 -407.386028) (xy 64.614735 -407.385501)
			(xy 64.560792 -407.377743) (xy 64.508502 -407.362387) (xy 64.458929 -407.339746) (xy 64.413083 -407.310281)
			(xy 64.371897 -407.274591) (xy 64.336209 -407.233404) (xy 64.306746 -407.187557) (xy 64.284107 -407.137983)
			(xy 64.268754 -407.085692) (xy 64.260998 -407.031749) (xy 62.823342 -407.031749) (xy 62.823342 -407.031751)
			(xy 62.815587 -407.085697) (xy 62.800233 -407.137991) (xy 62.777594 -407.187568) (xy 62.74813 -407.233419)
			(xy 62.712441 -407.27461) (xy 62.671254 -407.310304) (xy 62.625407 -407.339773) (xy 62.575833 -407.362417)
			(xy 62.52354 -407.377777) (xy 62.469595 -407.385539) (xy 62.442344 -407.386028) (xy 61.578744 -407.386028)
			(xy 61.551491 -407.385528) (xy 61.497538 -407.377776) (xy 61.445237 -407.362425) (xy 61.395654 -407.339786)
			(xy 61.349798 -407.310321) (xy 61.308602 -407.274629) (xy 61.272906 -407.233437) (xy 61.243435 -407.187584)
			(xy 61.220791 -407.138004) (xy 61.205433 -407.085705) (xy 61.197675 -407.031753) (xy 59.760142 -407.031753)
			(xy 59.752385 -407.085703) (xy 59.73703 -407.138) (xy 59.714388 -407.187579) (xy 59.68492 -407.233432)
			(xy 59.649227 -407.274624) (xy 59.608035 -407.310318) (xy 59.562183 -407.339786) (xy 59.512604 -407.362428)
			(xy 59.460307 -407.377785) (xy 59.406356 -407.385542) (xy 59.379104 -407.386028) (xy 58.515504 -407.386028)
			(xy 58.488252 -407.385525) (xy 58.434304 -407.377769) (xy 58.382008 -407.362414) (xy 58.33243 -407.339773)
			(xy 58.286579 -407.310307) (xy 58.245388 -407.274615) (xy 58.209696 -407.233424) (xy 58.180229 -407.187573)
			(xy 58.157587 -407.137995) (xy 58.142232 -407.0857) (xy 58.134475 -407.031752) (xy 56.696965 -407.031752)
			(xy 56.696965 -407.031756) (xy 56.689207 -407.085713) (xy 56.673848 -407.138016) (xy 56.651202 -407.187602)
			(xy 56.621729 -407.233459) (xy 56.586029 -407.274655) (xy 56.54483 -407.31035) (xy 56.49897 -407.339819)
			(xy 56.449383 -407.362461) (xy 56.397078 -407.377814) (xy 56.34312 -407.385568) (xy 56.315864 -407.386028)
			(xy 55.452264 -407.386028) (xy 55.425016 -407.385499) (xy 55.371075 -407.377739) (xy 55.318787 -407.362382)
			(xy 55.269217 -407.33974) (xy 55.223374 -407.310274) (xy 55.18219 -407.274584) (xy 55.146504 -407.233397)
			(xy 55.117043 -407.187551) (xy 55.094406 -407.137979) (xy 55.079053 -407.08569) (xy 55.071298 -407.031748)
			(xy 53.633642 -407.031748) (xy 53.633642 -407.031752) (xy 53.625886 -407.0857) (xy 53.610531 -407.137996)
			(xy 53.587891 -407.187574) (xy 53.558425 -407.233425) (xy 53.522734 -407.274617) (xy 53.481545 -407.310311)
			(xy 53.435695 -407.339779) (xy 53.386118 -407.362423) (xy 53.333824 -407.377781) (xy 53.279876 -407.385541)
			(xy 53.252624 -407.386028) (xy 52.389024 -407.386028) (xy 52.361771 -407.385526) (xy 52.307821 -407.377773)
			(xy 52.255523 -407.362419) (xy 52.205942 -407.339779) (xy 52.160088 -407.310314) (xy 52.118895 -407.274622)
			(xy 52.083201 -407.233431) (xy 52.053732 -407.187579) (xy 52.031089 -407.138) (xy 52.015733 -407.085703)
			(xy 52.007975 -407.031753) (xy 50.570465 -407.031753) (xy 50.570465 -407.031755) (xy 50.562707 -407.08571)
			(xy 50.54735 -407.138012) (xy 50.524705 -407.187596) (xy 50.495234 -407.233452) (xy 50.459536 -407.274648)
			(xy 50.41834 -407.310343) (xy 50.372482 -407.339812) (xy 50.322897 -407.362455) (xy 50.270595 -407.377811)
			(xy 50.216639 -407.385566) (xy 50.189384 -407.386028) (xy 49.325784 -407.386028) (xy 49.298535 -407.385501)
			(xy 49.244592 -407.377743) (xy 49.192302 -407.362387) (xy 49.142729 -407.339746) (xy 49.096883 -407.310281)
			(xy 49.055697 -407.274591) (xy 49.020009 -407.233404) (xy 48.990546 -407.187557) (xy 48.967907 -407.137983)
			(xy 48.952554 -407.085692) (xy 48.944798 -407.031749) (xy 45.259912 -407.031749) (xy 45.177806 -407.162866)
			(xy 45.072493 -407.31598) (xy 44.960691 -407.46442) (xy 44.842606 -407.607914) (xy 44.718456 -407.746194)
			(xy 44.588473 -407.879005) (xy 44.452896 -408.006101) (xy 44.311976 -408.127246) (xy 44.165976 -408.242217)
			(xy 44.015164 -408.3508) (xy 43.85982 -408.452793) (xy 43.700232 -408.54801) (xy 43.536695 -408.636272)
			(xy 43.369513 -408.717417) (xy 43.198994 -408.791294) (xy 43.025455 -408.857767) (xy 42.849216 -408.916712)
			(xy 42.670605 -408.96802) (xy 42.489952 -409.011597) (xy 42.307591 -409.047361) (xy 42.123861 -409.075247)
			(xy 41.939101 -409.095202) (xy 41.753654 -409.10719) (xy 41.567862 -409.111188) (xy 41.38207 -409.10719)
			(xy 41.196623 -409.095202) (xy 41.011863 -409.075247) (xy 40.828133 -409.047361) (xy 40.645772 -409.011597)
			(xy 40.465119 -408.96802) (xy 40.286508 -408.916712) (xy 40.110269 -408.857767) (xy 39.93673 -408.791294)
			(xy 39.766211 -408.717417) (xy 39.599029 -408.636272) (xy 39.435492 -408.54801) (xy 39.275904 -408.452793)
			(xy 39.12056 -408.3508) (xy 38.969748 -408.242217) (xy 38.823748 -408.127246) (xy 38.682828 -408.006101)
			(xy 38.547251 -407.879005) (xy 38.417268 -407.746194) (xy 38.293118 -407.607914) (xy 38.175033 -407.46442)
			(xy 38.063231 -407.31598) (xy 37.957918 -407.162866) (xy 37.85929 -407.005364) (xy 37.767529 -406.843764)
			(xy 37.682806 -406.678366) (xy 37.605277 -406.509477) (xy 37.535086 -406.337408) (xy 37.472363 -406.162479)
			(xy 37.417223 -405.985013) (xy 37.36977 -405.805339) (xy 37.33009 -405.62379) (xy 37.298258 -405.440702)
			(xy 37.274332 -405.256414) (xy 37.258357 -405.071268) (xy 37.250362 -404.885605) (xy 33.019445 -404.885605)
			(xy 37.697664 -409.563824) (xy 102.192836 -409.563824) (xy 102.192836 -408.700224) (xy 102.193322 -408.672955)
			(xy 102.201084 -408.618971) (xy 102.216449 -408.566641) (xy 102.239106 -408.517031) (xy 102.268592 -408.47115)
			(xy 102.304307 -408.429933) (xy 102.345524 -408.394218) (xy 102.391405 -408.364732) (xy 102.441015 -408.342075)
			(xy 102.493345 -408.32671) (xy 102.547329 -408.318948) (xy 102.601867 -408.318948) (xy 102.655851 -408.32671)
			(xy 102.708181 -408.342075) (xy 102.757791 -408.364732) (xy 102.803672 -408.394218) (xy 102.844889 -408.429933)
			(xy 102.880604 -408.47115) (xy 102.91009 -408.517031) (xy 102.932747 -408.566641) (xy 102.948112 -408.618971)
			(xy 102.955874 -408.672955) (xy 102.95636 -408.700224) (xy 102.95636 -409.563824) (xy 102.955874 -409.591093)
			(xy 102.948112 -409.645077) (xy 102.932747 -409.697407) (xy 102.91009 -409.747017) (xy 102.880604 -409.792898)
			(xy 102.844889 -409.834115) (xy 102.803672 -409.86983) (xy 102.757791 -409.899316) (xy 102.748244 -409.903676)
			(xy 110.559596 -409.903676) (xy 110.559596 -409.040076) (xy 110.560082 -409.012825) (xy 110.567838 -408.958877)
			(xy 110.583193 -408.906582) (xy 110.605835 -408.857005) (xy 110.635301 -408.811155) (xy 110.670992 -408.769964)
			(xy 110.712183 -408.734273) (xy 110.758033 -408.704807) (xy 110.80761 -408.682165) (xy 110.859905 -408.66681)
			(xy 110.913853 -408.659054) (xy 110.968355 -408.659054) (xy 111.022303 -408.66681) (xy 111.074598 -408.682165)
			(xy 111.124175 -408.704807) (xy 111.170025 -408.734273) (xy 111.211216 -408.769964) (xy 111.246907 -408.811155)
			(xy 111.276373 -408.857005) (xy 111.299015 -408.906582) (xy 111.31437 -408.958877) (xy 111.322126 -409.012825)
			(xy 111.322612 -409.040076) (xy 111.322612 -409.903676) (xy 111.322126 -409.930927) (xy 111.31437 -409.984875)
			(xy 111.299015 -410.03717) (xy 111.28975 -410.057456) (xy 116.044623 -410.057456) (xy 116.044623 -410.002944)
			(xy 116.052381 -409.948986) (xy 116.06774 -409.896681) (xy 116.090386 -409.847095) (xy 116.119859 -409.801237)
			(xy 116.155559 -409.76004) (xy 116.196758 -409.724344) (xy 116.242618 -409.694874) (xy 116.292206 -409.672231)
			(xy 116.344511 -409.656876) (xy 116.39847 -409.649121) (xy 116.425726 -409.64866) (xy 117.289326 -409.64866)
			(xy 117.316574 -409.649212) (xy 117.370514 -409.656971) (xy 117.422801 -409.672327) (xy 117.472371 -409.694968)
			(xy 117.518214 -409.724432) (xy 117.559398 -409.760121) (xy 117.595084 -409.801307) (xy 117.624545 -409.847152)
			(xy 117.647182 -409.896723) (xy 117.662535 -409.949011) (xy 117.67029 -410.002952) (xy 117.67029 -410.057448)
			(xy 117.670289 -410.057452) (xy 119.107946 -410.057452) (xy 119.107946 -410.002948) (xy 119.115702 -409.948999)
			(xy 119.131057 -409.896702) (xy 119.153697 -409.847123) (xy 119.183163 -409.801271) (xy 119.218854 -409.760078)
			(xy 119.260043 -409.724383) (xy 119.305893 -409.694914) (xy 119.35547 -409.672269) (xy 119.407765 -409.656909)
			(xy 119.461714 -409.649148) (xy 119.488966 -409.64866) (xy 120.352566 -409.64866) (xy 120.379818 -409.649185)
			(xy 120.433768 -409.656937) (xy 120.486066 -409.672289) (xy 120.535646 -409.694928) (xy 120.5815 -409.724392)
			(xy 120.622693 -409.760083) (xy 120.658387 -409.801273) (xy 120.687856 -409.847124) (xy 120.710499 -409.896702)
			(xy 120.725855 -409.948999) (xy 120.733613 -410.002948) (xy 120.733613 -410.057452) (xy 120.733613 -410.057455)
			(xy 122.171123 -410.057455) (xy 122.171123 -410.002945) (xy 122.178881 -409.948989) (xy 122.194238 -409.896686)
			(xy 122.216883 -409.847101) (xy 122.246354 -409.801244) (xy 122.282052 -409.760047) (xy 122.323249 -409.724351)
			(xy 122.369106 -409.69488) (xy 122.418691 -409.672236) (xy 122.470994 -409.656879) (xy 122.524951 -409.649123)
			(xy 122.552206 -409.64866) (xy 123.415806 -409.64866) (xy 123.443055 -409.649211) (xy 123.496997 -409.656967)
			(xy 123.549287 -409.672321) (xy 123.598859 -409.694961) (xy 123.644705 -409.724425) (xy 123.685891 -409.760113)
			(xy 123.721579 -409.8013) (xy 123.751042 -409.847146) (xy 123.773681 -409.896719) (xy 123.789034 -409.949009)
			(xy 123.79679 -410.002951) (xy 123.79679 -410.057449) (xy 123.796789 -410.057457) (xy 125.234323 -410.057457)
			(xy 125.234323 -410.002943) (xy 125.242082 -409.948983) (xy 125.257442 -409.896677) (xy 125.280089 -409.84709)
			(xy 125.309564 -409.801231) (xy 125.345266 -409.760033) (xy 125.386467 -409.724337) (xy 125.43233 -409.694867)
			(xy 125.48192 -409.672225) (xy 125.534228 -409.656872) (xy 125.588189 -409.64912) (xy 125.615446 -409.64866)
			(xy 126.479046 -409.64866) (xy 126.506293 -409.649213) (xy 126.560231 -409.656975) (xy 126.612516 -409.672332)
			(xy 126.662083 -409.694974) (xy 126.707924 -409.724439) (xy 126.749105 -409.760128) (xy 126.784788 -409.801313)
			(xy 126.814248 -409.847157) (xy 126.836884 -409.896727) (xy 126.852235 -409.949014) (xy 126.85999 -410.002953)
			(xy 126.85999 -410.057447) (xy 126.859989 -410.057453) (xy 128.297646 -410.057453) (xy 128.297646 -410.002947)
			(xy 128.305403 -409.948996) (xy 128.320758 -409.896698) (xy 128.3434 -409.847118) (xy 128.372868 -409.801264)
			(xy 128.408561 -409.760071) (xy 128.449753 -409.724376) (xy 128.495605 -409.694907) (xy 128.545185 -409.672263)
			(xy 128.597482 -409.656906) (xy 128.651433 -409.649147) (xy 128.678686 -409.64866) (xy 129.542286 -409.64866)
			(xy 129.569537 -409.649186) (xy 129.623485 -409.656941) (xy 129.67578 -409.672295) (xy 129.725358 -409.694934)
			(xy 129.771209 -409.724399) (xy 129.8124 -409.76009) (xy 129.848092 -409.80128) (xy 129.877559 -409.84713)
			(xy 129.900201 -409.896707) (xy 129.915556 -409.949001) (xy 129.923313 -410.002949) (xy 129.923313 -410.057451)
			(xy 129.923312 -410.057456) (xy 131.360823 -410.057456) (xy 131.360823 -410.002944) (xy 131.368581 -409.948986)
			(xy 131.38394 -409.896681) (xy 131.406586 -409.847095) (xy 131.436059 -409.801237) (xy 131.471759 -409.76004)
			(xy 131.512958 -409.724344) (xy 131.558818 -409.694874) (xy 131.608406 -409.672231) (xy 131.660711 -409.656876)
			(xy 131.71467 -409.649121) (xy 131.741926 -409.64866) (xy 132.605526 -409.64866) (xy 132.632774 -409.649212)
			(xy 132.686714 -409.656971) (xy 132.739001 -409.672327) (xy 132.788571 -409.694968) (xy 132.834414 -409.724432)
			(xy 132.875598 -409.760121) (xy 132.911284 -409.801307) (xy 132.940745 -409.847152) (xy 132.963382 -409.896723)
			(xy 132.978735 -409.949011) (xy 132.98649 -410.002952) (xy 132.98649 -410.057448) (xy 132.986489 -410.057452)
			(xy 134.424146 -410.057452) (xy 134.424146 -410.002948) (xy 134.431902 -409.948999) (xy 134.447257 -409.896702)
			(xy 134.469897 -409.847123) (xy 134.499363 -409.801271) (xy 134.535054 -409.760078) (xy 134.576243 -409.724383)
			(xy 134.622093 -409.694914) (xy 134.67167 -409.672269) (xy 134.723965 -409.656909) (xy 134.777914 -409.649148)
			(xy 134.805166 -409.64866) (xy 135.668766 -409.64866) (xy 135.696018 -409.649185) (xy 135.749968 -409.656937)
			(xy 135.802266 -409.672289) (xy 135.851846 -409.694928) (xy 135.8977 -409.724392) (xy 135.938893 -409.760083)
			(xy 135.974587 -409.801273) (xy 136.004056 -409.847124) (xy 136.026699 -409.896702) (xy 136.042055 -409.948999)
			(xy 136.049813 -410.002948) (xy 136.049813 -410.057452) (xy 136.049813 -410.057455) (xy 137.487323 -410.057455)
			(xy 137.487323 -410.002945) (xy 137.495081 -409.948989) (xy 137.510438 -409.896686) (xy 137.533083 -409.847101)
			(xy 137.562554 -409.801244) (xy 137.598252 -409.760047) (xy 137.639449 -409.724351) (xy 137.685306 -409.69488)
			(xy 137.734891 -409.672236) (xy 137.787194 -409.656879) (xy 137.841151 -409.649123) (xy 137.868406 -409.64866)
			(xy 138.732006 -409.64866) (xy 138.759255 -409.649211) (xy 138.813197 -409.656967) (xy 138.865487 -409.672321)
			(xy 138.915059 -409.694961) (xy 138.960905 -409.724425) (xy 139.002091 -409.760113) (xy 139.037779 -409.8013)
			(xy 139.067242 -409.847146) (xy 139.089881 -409.896719) (xy 139.105234 -409.949009) (xy 139.11299 -410.002951)
			(xy 139.11299 -410.057449) (xy 139.112989 -410.057457) (xy 140.550523 -410.057457) (xy 140.550523 -410.002943)
			(xy 140.558282 -409.948983) (xy 140.573642 -409.896677) (xy 140.596289 -409.84709) (xy 140.625764 -409.801231)
			(xy 140.661466 -409.760033) (xy 140.702667 -409.724337) (xy 140.74853 -409.694867) (xy 140.79812 -409.672225)
			(xy 140.850428 -409.656872) (xy 140.904389 -409.64912) (xy 140.931646 -409.64866) (xy 141.795246 -409.64866)
			(xy 141.822493 -409.649213) (xy 141.876431 -409.656975) (xy 141.928716 -409.672332) (xy 141.978283 -409.694974)
			(xy 142.024124 -409.724439) (xy 142.065305 -409.760128) (xy 142.100988 -409.801313) (xy 142.130448 -409.847157)
			(xy 142.153084 -409.896727) (xy 142.168435 -409.949014) (xy 142.17619 -410.002953) (xy 142.17619 -410.057447)
			(xy 142.176189 -410.057453) (xy 143.613846 -410.057453) (xy 143.613846 -410.002947) (xy 143.621603 -409.948996)
			(xy 143.636958 -409.896698) (xy 143.6596 -409.847118) (xy 143.689068 -409.801264) (xy 143.724761 -409.760071)
			(xy 143.765953 -409.724376) (xy 143.811805 -409.694907) (xy 143.861385 -409.672263) (xy 143.913682 -409.656906)
			(xy 143.967633 -409.649147) (xy 143.994886 -409.64866) (xy 144.858486 -409.64866) (xy 144.885737 -409.649186)
			(xy 144.939685 -409.656941) (xy 144.99198 -409.672295) (xy 145.041558 -409.694934) (xy 145.087409 -409.724399)
			(xy 145.1286 -409.76009) (xy 145.164292 -409.80128) (xy 145.193759 -409.84713) (xy 145.216401 -409.896707)
			(xy 145.231756 -409.949001) (xy 145.239513 -410.002949) (xy 145.239513 -410.057451) (xy 145.239512 -410.057456)
			(xy 146.677023 -410.057456) (xy 146.677023 -410.002944) (xy 146.684781 -409.948986) (xy 146.70014 -409.896681)
			(xy 146.722786 -409.847095) (xy 146.752259 -409.801237) (xy 146.787959 -409.76004) (xy 146.829158 -409.724344)
			(xy 146.875018 -409.694874) (xy 146.924606 -409.672231) (xy 146.976911 -409.656876) (xy 147.03087 -409.649121)
			(xy 147.058126 -409.64866) (xy 147.921726 -409.64866) (xy 147.948974 -409.649212) (xy 148.002914 -409.656971)
			(xy 148.055201 -409.672327) (xy 148.104771 -409.694968) (xy 148.150614 -409.724432) (xy 148.191798 -409.760121)
			(xy 148.227484 -409.801307) (xy 148.256945 -409.847152) (xy 148.279582 -409.896723) (xy 148.294935 -409.949011)
			(xy 148.30269 -410.002952) (xy 148.30269 -410.057448) (xy 148.302689 -410.057452) (xy 149.740346 -410.057452)
			(xy 149.740346 -410.002948) (xy 149.748102 -409.948999) (xy 149.763457 -409.896702) (xy 149.786097 -409.847123)
			(xy 149.815563 -409.801271) (xy 149.851254 -409.760078) (xy 149.892443 -409.724383) (xy 149.938293 -409.694914)
			(xy 149.98787 -409.672269) (xy 150.040165 -409.656909) (xy 150.094114 -409.649148) (xy 150.121366 -409.64866)
			(xy 150.984966 -409.64866) (xy 151.012218 -409.649185) (xy 151.066168 -409.656937) (xy 151.118466 -409.672289)
			(xy 151.168046 -409.694928) (xy 151.2139 -409.724392) (xy 151.255093 -409.760083) (xy 151.290787 -409.801273)
			(xy 151.320256 -409.847124) (xy 151.342899 -409.896702) (xy 151.358255 -409.948999) (xy 151.366013 -410.002948)
			(xy 151.366013 -410.057452) (xy 151.366013 -410.057455) (xy 152.803523 -410.057455) (xy 152.803523 -410.002945)
			(xy 152.811281 -409.948989) (xy 152.826638 -409.896686) (xy 152.849283 -409.847101) (xy 152.878754 -409.801244)
			(xy 152.914452 -409.760047) (xy 152.955649 -409.724351) (xy 153.001506 -409.69488) (xy 153.051091 -409.672236)
			(xy 153.103394 -409.656879) (xy 153.157351 -409.649123) (xy 153.184606 -409.64866) (xy 154.048206 -409.64866)
			(xy 154.075455 -409.649211) (xy 154.129397 -409.656967) (xy 154.181687 -409.672321) (xy 154.231259 -409.694961)
			(xy 154.277105 -409.724425) (xy 154.318291 -409.760113) (xy 154.353979 -409.8013) (xy 154.383442 -409.847146)
			(xy 154.406081 -409.896719) (xy 154.421434 -409.949009) (xy 154.42919 -410.002951) (xy 154.42919 -410.057449)
			(xy 154.429189 -410.057457) (xy 155.866723 -410.057457) (xy 155.866723 -410.002943) (xy 155.874482 -409.948983)
			(xy 155.889842 -409.896677) (xy 155.912489 -409.84709) (xy 155.941964 -409.801231) (xy 155.977666 -409.760033)
			(xy 156.018867 -409.724337) (xy 156.06473 -409.694867) (xy 156.11432 -409.672225) (xy 156.166628 -409.656872)
			(xy 156.220589 -409.64912) (xy 156.247846 -409.64866) (xy 157.111446 -409.64866) (xy 157.138693 -409.649213)
			(xy 157.192631 -409.656975) (xy 157.244916 -409.672332) (xy 157.294483 -409.694974) (xy 157.340324 -409.724439)
			(xy 157.381505 -409.760128) (xy 157.417188 -409.801313) (xy 157.446648 -409.847157) (xy 157.469284 -409.896727)
			(xy 157.484635 -409.949014) (xy 157.49239 -410.002953) (xy 157.49239 -410.057447) (xy 157.492389 -410.057453)
			(xy 158.930046 -410.057453) (xy 158.930046 -410.002947) (xy 158.937803 -409.948996) (xy 158.953158 -409.896698)
			(xy 158.9758 -409.847118) (xy 159.005268 -409.801264) (xy 159.040961 -409.760071) (xy 159.082153 -409.724376)
			(xy 159.128005 -409.694907) (xy 159.177585 -409.672263) (xy 159.229882 -409.656906) (xy 159.283833 -409.649147)
			(xy 159.311086 -409.64866) (xy 160.174686 -409.64866) (xy 160.201937 -409.649186) (xy 160.255885 -409.656941)
			(xy 160.30818 -409.672295) (xy 160.357758 -409.694934) (xy 160.403609 -409.724399) (xy 160.4448 -409.76009)
			(xy 160.480492 -409.80128) (xy 160.509959 -409.84713) (xy 160.532601 -409.896707) (xy 160.547956 -409.949001)
			(xy 160.555713 -410.002949) (xy 160.555713 -410.057451) (xy 160.555712 -410.057456) (xy 161.993223 -410.057456)
			(xy 161.993223 -410.002944) (xy 162.000981 -409.948986) (xy 162.01634 -409.896681) (xy 162.038986 -409.847095)
			(xy 162.068459 -409.801237) (xy 162.104159 -409.76004) (xy 162.145358 -409.724344) (xy 162.191218 -409.694874)
			(xy 162.240806 -409.672231) (xy 162.293111 -409.656876) (xy 162.34707 -409.649121) (xy 162.374326 -409.64866)
			(xy 163.237926 -409.64866) (xy 163.265174 -409.649212) (xy 163.319114 -409.656971) (xy 163.371401 -409.672327)
			(xy 163.420971 -409.694968) (xy 163.466814 -409.724432) (xy 163.507998 -409.760121) (xy 163.543684 -409.801307)
			(xy 163.573145 -409.847152) (xy 163.595782 -409.896723) (xy 163.611135 -409.949011) (xy 163.61889 -410.002952)
			(xy 163.61889 -410.057448) (xy 163.611135 -410.111389) (xy 163.595782 -410.163677) (xy 163.573145 -410.213248)
			(xy 163.543684 -410.259093) (xy 163.507998 -410.300279) (xy 163.466814 -410.335968) (xy 163.420971 -410.365432)
			(xy 163.371401 -410.388073) (xy 163.319114 -410.403429) (xy 163.265174 -410.411188) (xy 163.237926 -410.411676)
			(xy 162.374326 -410.411676) (xy 162.34707 -410.411279) (xy 162.293111 -410.403524) (xy 162.240806 -410.388169)
			(xy 162.191218 -410.365526) (xy 162.145358 -410.336056) (xy 162.104159 -410.30036) (xy 162.068459 -410.259163)
			(xy 162.038986 -410.213305) (xy 162.01634 -410.163719) (xy 162.000981 -410.111414) (xy 161.993223 -410.057456)
			(xy 160.555712 -410.057456) (xy 160.547956 -410.111399) (xy 160.532601 -410.163693) (xy 160.509959 -410.21327)
			(xy 160.480492 -410.25912) (xy 160.4448 -410.30031) (xy 160.403609 -410.336001) (xy 160.357758 -410.365466)
			(xy 160.30818 -410.388105) (xy 160.255885 -410.403459) (xy 160.201937 -410.411214) (xy 160.174686 -410.411676)
			(xy 159.311086 -410.411676) (xy 159.283833 -410.411253) (xy 159.229882 -410.403494) (xy 159.177585 -410.388137)
			(xy 159.128005 -410.365493) (xy 159.082153 -410.336024) (xy 159.040961 -410.300329) (xy 159.005268 -410.259136)
			(xy 158.9758 -410.213282) (xy 158.953158 -410.163702) (xy 158.937803 -410.111404) (xy 158.930046 -410.057453)
			(xy 157.492389 -410.057453) (xy 157.484635 -410.111386) (xy 157.469284 -410.163673) (xy 157.446648 -410.213243)
			(xy 157.417188 -410.259087) (xy 157.381505 -410.300272) (xy 157.340324 -410.335961) (xy 157.294483 -410.365426)
			(xy 157.244916 -410.388068) (xy 157.192631 -410.403425) (xy 157.138693 -410.411187) (xy 157.111446 -410.411676)
			(xy 156.247846 -410.411676) (xy 156.220589 -410.41128) (xy 156.166628 -410.403528) (xy 156.11432 -410.388175)
			(xy 156.06473 -410.365533) (xy 156.018867 -410.336063) (xy 155.977666 -410.300367) (xy 155.941964 -410.259169)
			(xy 155.912489 -410.21331) (xy 155.889842 -410.163723) (xy 155.874482 -410.111417) (xy 155.866723 -410.057457)
			(xy 154.429189 -410.057457) (xy 154.421434 -410.111391) (xy 154.406081 -410.163681) (xy 154.383442 -410.213254)
			(xy 154.353979 -410.2591) (xy 154.318291 -410.300287) (xy 154.277105 -410.335975) (xy 154.231259 -410.365439)
			(xy 154.181687 -410.388079) (xy 154.129397 -410.403433) (xy 154.075455 -410.411189) (xy 154.048206 -410.411676)
			(xy 153.184606 -410.411676) (xy 153.157351 -410.411277) (xy 153.103394 -410.403521) (xy 153.051091 -410.388164)
			(xy 153.001506 -410.36552) (xy 152.955649 -410.336049) (xy 152.914452 -410.300353) (xy 152.878754 -410.259156)
			(xy 152.849283 -410.213299) (xy 152.826638 -410.163714) (xy 152.811281 -410.111411) (xy 152.803523 -410.057455)
			(xy 151.366013 -410.057455) (xy 151.358255 -410.111402) (xy 151.342899 -410.163698) (xy 151.320256 -410.213276)
			(xy 151.290787 -410.259127) (xy 151.255093 -410.300317) (xy 151.2139 -410.336008) (xy 151.168046 -410.365472)
			(xy 151.118466 -410.388111) (xy 151.066168 -410.403463) (xy 151.012218 -410.411215) (xy 150.984966 -410.411676)
			(xy 150.121366 -410.411676) (xy 150.094114 -410.411252) (xy 150.040165 -410.403491) (xy 149.98787 -410.388131)
			(xy 149.938293 -410.365486) (xy 149.892443 -410.336017) (xy 149.851254 -410.300322) (xy 149.815563 -410.259129)
			(xy 149.786097 -410.213277) (xy 149.763457 -410.163698) (xy 149.748102 -410.111401) (xy 149.740346 -410.057452)
			(xy 148.302689 -410.057452) (xy 148.294935 -410.111389) (xy 148.279582 -410.163677) (xy 148.256945 -410.213248)
			(xy 148.227484 -410.259093) (xy 148.191798 -410.300279) (xy 148.150614 -410.335968) (xy 148.104771 -410.365432)
			(xy 148.055201 -410.388073) (xy 148.002914 -410.403429) (xy 147.948974 -410.411188) (xy 147.921726 -410.411676)
			(xy 147.058126 -410.411676) (xy 147.03087 -410.411279) (xy 146.976911 -410.403524) (xy 146.924606 -410.388169)
			(xy 146.875018 -410.365526) (xy 146.829158 -410.336056) (xy 146.787959 -410.30036) (xy 146.752259 -410.259163)
			(xy 146.722786 -410.213305) (xy 146.70014 -410.163719) (xy 146.684781 -410.111414) (xy 146.677023 -410.057456)
			(xy 145.239512 -410.057456) (xy 145.231756 -410.111399) (xy 145.216401 -410.163693) (xy 145.193759 -410.21327)
			(xy 145.164292 -410.25912) (xy 145.1286 -410.30031) (xy 145.087409 -410.336001) (xy 145.041558 -410.365466)
			(xy 144.99198 -410.388105) (xy 144.939685 -410.403459) (xy 144.885737 -410.411214) (xy 144.858486 -410.411676)
			(xy 143.994886 -410.411676) (xy 143.967633 -410.411253) (xy 143.913682 -410.403494) (xy 143.861385 -410.388137)
			(xy 143.811805 -410.365493) (xy 143.765953 -410.336024) (xy 143.724761 -410.300329) (xy 143.689068 -410.259136)
			(xy 143.6596 -410.213282) (xy 143.636958 -410.163702) (xy 143.621603 -410.111404) (xy 143.613846 -410.057453)
			(xy 142.176189 -410.057453) (xy 142.168435 -410.111386) (xy 142.153084 -410.163673) (xy 142.130448 -410.213243)
			(xy 142.100988 -410.259087) (xy 142.065305 -410.300272) (xy 142.024124 -410.335961) (xy 141.978283 -410.365426)
			(xy 141.928716 -410.388068) (xy 141.876431 -410.403425) (xy 141.822493 -410.411187) (xy 141.795246 -410.411676)
			(xy 140.931646 -410.411676) (xy 140.904389 -410.41128) (xy 140.850428 -410.403528) (xy 140.79812 -410.388175)
			(xy 140.74853 -410.365533) (xy 140.702667 -410.336063) (xy 140.661466 -410.300367) (xy 140.625764 -410.259169)
			(xy 140.596289 -410.21331) (xy 140.573642 -410.163723) (xy 140.558282 -410.111417) (xy 140.550523 -410.057457)
			(xy 139.112989 -410.057457) (xy 139.105234 -410.111391) (xy 139.089881 -410.163681) (xy 139.067242 -410.213254)
			(xy 139.037779 -410.2591) (xy 139.002091 -410.300287) (xy 138.960905 -410.335975) (xy 138.915059 -410.365439)
			(xy 138.865487 -410.388079) (xy 138.813197 -410.403433) (xy 138.759255 -410.411189) (xy 138.732006 -410.411676)
			(xy 137.868406 -410.411676) (xy 137.841151 -410.411277) (xy 137.787194 -410.403521) (xy 137.734891 -410.388164)
			(xy 137.685306 -410.36552) (xy 137.639449 -410.336049) (xy 137.598252 -410.300353) (xy 137.562554 -410.259156)
			(xy 137.533083 -410.213299) (xy 137.510438 -410.163714) (xy 137.495081 -410.111411) (xy 137.487323 -410.057455)
			(xy 136.049813 -410.057455) (xy 136.042055 -410.111402) (xy 136.026699 -410.163698) (xy 136.004056 -410.213276)
			(xy 135.974587 -410.259127) (xy 135.938893 -410.300317) (xy 135.8977 -410.336008) (xy 135.851846 -410.365472)
			(xy 135.802266 -410.388111) (xy 135.749968 -410.403463) (xy 135.696018 -410.411215) (xy 135.668766 -410.411676)
			(xy 134.805166 -410.411676) (xy 134.777914 -410.411252) (xy 134.723965 -410.403491) (xy 134.67167 -410.388131)
			(xy 134.622093 -410.365486) (xy 134.576243 -410.336017) (xy 134.535054 -410.300322) (xy 134.499363 -410.259129)
			(xy 134.469897 -410.213277) (xy 134.447257 -410.163698) (xy 134.431902 -410.111401) (xy 134.424146 -410.057452)
			(xy 132.986489 -410.057452) (xy 132.978735 -410.111389) (xy 132.963382 -410.163677) (xy 132.940745 -410.213248)
			(xy 132.911284 -410.259093) (xy 132.875598 -410.300279) (xy 132.834414 -410.335968) (xy 132.788571 -410.365432)
			(xy 132.739001 -410.388073) (xy 132.686714 -410.403429) (xy 132.632774 -410.411188) (xy 132.605526 -410.411676)
			(xy 131.741926 -410.411676) (xy 131.71467 -410.411279) (xy 131.660711 -410.403524) (xy 131.608406 -410.388169)
			(xy 131.558818 -410.365526) (xy 131.512958 -410.336056) (xy 131.471759 -410.30036) (xy 131.436059 -410.259163)
			(xy 131.406586 -410.213305) (xy 131.38394 -410.163719) (xy 131.368581 -410.111414) (xy 131.360823 -410.057456)
			(xy 129.923312 -410.057456) (xy 129.915556 -410.111399) (xy 129.900201 -410.163693) (xy 129.877559 -410.21327)
			(xy 129.848092 -410.25912) (xy 129.8124 -410.30031) (xy 129.771209 -410.336001) (xy 129.725358 -410.365466)
			(xy 129.67578 -410.388105) (xy 129.623485 -410.403459) (xy 129.569537 -410.411214) (xy 129.542286 -410.411676)
			(xy 128.678686 -410.411676) (xy 128.651433 -410.411253) (xy 128.597482 -410.403494) (xy 128.545185 -410.388137)
			(xy 128.495605 -410.365493) (xy 128.449753 -410.336024) (xy 128.408561 -410.300329) (xy 128.372868 -410.259136)
			(xy 128.3434 -410.213282) (xy 128.320758 -410.163702) (xy 128.305403 -410.111404) (xy 128.297646 -410.057453)
			(xy 126.859989 -410.057453) (xy 126.852235 -410.111386) (xy 126.836884 -410.163673) (xy 126.814248 -410.213243)
			(xy 126.784788 -410.259087) (xy 126.749105 -410.300272) (xy 126.707924 -410.335961) (xy 126.662083 -410.365426)
			(xy 126.612516 -410.388068) (xy 126.560231 -410.403425) (xy 126.506293 -410.411187) (xy 126.479046 -410.411676)
			(xy 125.615446 -410.411676) (xy 125.588189 -410.41128) (xy 125.534228 -410.403528) (xy 125.48192 -410.388175)
			(xy 125.43233 -410.365533) (xy 125.386467 -410.336063) (xy 125.345266 -410.300367) (xy 125.309564 -410.259169)
			(xy 125.280089 -410.21331) (xy 125.257442 -410.163723) (xy 125.242082 -410.111417) (xy 125.234323 -410.057457)
			(xy 123.796789 -410.057457) (xy 123.789034 -410.111391) (xy 123.773681 -410.163681) (xy 123.751042 -410.213254)
			(xy 123.721579 -410.2591) (xy 123.685891 -410.300287) (xy 123.644705 -410.335975) (xy 123.598859 -410.365439)
			(xy 123.549287 -410.388079) (xy 123.496997 -410.403433) (xy 123.443055 -410.411189) (xy 123.415806 -410.411676)
			(xy 122.552206 -410.411676) (xy 122.524951 -410.411277) (xy 122.470994 -410.403521) (xy 122.418691 -410.388164)
			(xy 122.369106 -410.36552) (xy 122.323249 -410.336049) (xy 122.282052 -410.300353) (xy 122.246354 -410.259156)
			(xy 122.216883 -410.213299) (xy 122.194238 -410.163714) (xy 122.178881 -410.111411) (xy 122.171123 -410.057455)
			(xy 120.733613 -410.057455) (xy 120.725855 -410.111402) (xy 120.710499 -410.163698) (xy 120.687856 -410.213276)
			(xy 120.658387 -410.259127) (xy 120.622693 -410.300317) (xy 120.5815 -410.336008) (xy 120.535646 -410.365472)
			(xy 120.486066 -410.388111) (xy 120.433768 -410.403463) (xy 120.379818 -410.411215) (xy 120.352566 -410.411676)
			(xy 119.488966 -410.411676) (xy 119.461714 -410.411252) (xy 119.407765 -410.403491) (xy 119.35547 -410.388131)
			(xy 119.305893 -410.365486) (xy 119.260043 -410.336017) (xy 119.218854 -410.300322) (xy 119.183163 -410.259129)
			(xy 119.153697 -410.213277) (xy 119.131057 -410.163698) (xy 119.115702 -410.111401) (xy 119.107946 -410.057452)
			(xy 117.670289 -410.057452) (xy 117.662535 -410.111389) (xy 117.647182 -410.163677) (xy 117.624545 -410.213248)
			(xy 117.595084 -410.259093) (xy 117.559398 -410.300279) (xy 117.518214 -410.335968) (xy 117.472371 -410.365432)
			(xy 117.422801 -410.388073) (xy 117.370514 -410.403429) (xy 117.316574 -410.411188) (xy 117.289326 -410.411676)
			(xy 116.425726 -410.411676) (xy 116.39847 -410.411279) (xy 116.344511 -410.403524) (xy 116.292206 -410.388169)
			(xy 116.242618 -410.365526) (xy 116.196758 -410.336056) (xy 116.155559 -410.30036) (xy 116.119859 -410.259163)
			(xy 116.090386 -410.213305) (xy 116.06774 -410.163719) (xy 116.052381 -410.111414) (xy 116.044623 -410.057456)
			(xy 111.28975 -410.057456) (xy 111.276373 -410.086747) (xy 111.246907 -410.132597) (xy 111.211216 -410.173788)
			(xy 111.170025 -410.209479) (xy 111.124175 -410.238945) (xy 111.074598 -410.261587) (xy 111.022303 -410.276942)
			(xy 110.968355 -410.284698) (xy 110.913853 -410.284698) (xy 110.859905 -410.276942) (xy 110.80761 -410.261587)
			(xy 110.758033 -410.238945) (xy 110.712183 -410.209479) (xy 110.670992 -410.173788) (xy 110.635301 -410.132597)
			(xy 110.605835 -410.086747) (xy 110.583193 -410.03717) (xy 110.567838 -409.984875) (xy 110.560082 -409.930927)
			(xy 110.559596 -409.903676) (xy 102.748244 -409.903676) (xy 102.708181 -409.921973) (xy 102.655851 -409.937338)
			(xy 102.601867 -409.9451) (xy 102.547329 -409.9451) (xy 102.493345 -409.937338) (xy 102.441015 -409.921973)
			(xy 102.391405 -409.899316) (xy 102.345524 -409.86983) (xy 102.304307 -409.834115) (xy 102.268592 -409.792898)
			(xy 102.239106 -409.747017) (xy 102.216449 -409.697407) (xy 102.201084 -409.645077) (xy 102.193322 -409.591093)
			(xy 102.192836 -409.563824) (xy 37.697664 -409.563824) (xy 38.191293 -410.057453) (xy 48.944746 -410.057453)
			(xy 48.944746 -410.002947) (xy 48.952503 -409.948996) (xy 48.967858 -409.896698) (xy 48.9905 -409.847118)
			(xy 49.019967 -409.801265) (xy 49.05566 -409.760071) (xy 49.096852 -409.724377) (xy 49.142704 -409.694908)
			(xy 49.192283 -409.672264) (xy 49.244581 -409.656906) (xy 49.298531 -409.649147) (xy 49.325784 -409.64866)
			(xy 50.189384 -409.64866) (xy 50.216635 -409.649186) (xy 50.270583 -409.656941) (xy 50.322879 -409.672294)
			(xy 50.372457 -409.694934) (xy 50.418308 -409.724399) (xy 50.459499 -409.760089) (xy 50.495192 -409.801279)
			(xy 50.524659 -409.847129) (xy 50.5473 -409.896706) (xy 50.562656 -409.949001) (xy 50.570413 -410.002949)
			(xy 50.570413 -410.057451) (xy 50.570412 -410.057456) (xy 52.007923 -410.057456) (xy 52.007923 -410.002944)
			(xy 52.015681 -409.948986) (xy 52.03104 -409.896682) (xy 52.053686 -409.847096) (xy 52.083159 -409.801238)
			(xy 52.118858 -409.760041) (xy 52.160057 -409.724344) (xy 52.205917 -409.694874) (xy 52.255504 -409.672231)
			(xy 52.30781 -409.656876) (xy 52.361768 -409.649121) (xy 52.389024 -409.64866) (xy 53.252624 -409.64866)
			(xy 53.279872 -409.649212) (xy 53.333812 -409.65697) (xy 53.3861 -409.672326) (xy 53.43567 -409.694967)
			(xy 53.481513 -409.724431) (xy 53.522697 -409.76012) (xy 53.558383 -409.801306) (xy 53.587845 -409.847151)
			(xy 53.610482 -409.896723) (xy 53.625835 -409.949011) (xy 53.63359 -410.002952) (xy 53.63359 -410.057448)
			(xy 53.633589 -410.057452) (xy 55.071246 -410.057452) (xy 55.071246 -410.002948) (xy 55.079002 -409.948999)
			(xy 55.094357 -409.896703) (xy 55.116997 -409.847124) (xy 55.146462 -409.801271) (xy 55.182153 -409.760079)
			(xy 55.223342 -409.724384) (xy 55.269192 -409.694914) (xy 55.318769 -409.672269) (xy 55.371064 -409.65691)
			(xy 55.425012 -409.649148) (xy 55.452264 -409.64866) (xy 56.315864 -409.64866) (xy 56.343116 -409.649185)
			(xy 56.397067 -409.656937) (xy 56.449364 -409.672289) (xy 56.498945 -409.694927) (xy 56.544799 -409.724392)
			(xy 56.585992 -409.760082) (xy 56.621687 -409.801273) (xy 56.651156 -409.847124) (xy 56.673799 -409.896702)
			(xy 56.689155 -409.948998) (xy 56.696913 -410.002948) (xy 56.696913 -410.057452) (xy 56.696913 -410.057455)
			(xy 58.134423 -410.057455) (xy 58.134423 -410.002945) (xy 58.142181 -409.948989) (xy 58.157538 -409.896686)
			(xy 58.180183 -409.847102) (xy 58.209654 -409.801244) (xy 58.245351 -409.760048) (xy 58.286548 -409.724351)
			(xy 58.332405 -409.694881) (xy 58.38199 -409.672237) (xy 58.434293 -409.65688) (xy 58.488249 -409.649123)
			(xy 58.515504 -409.64866) (xy 59.379104 -409.64866) (xy 59.406353 -409.64921) (xy 59.460295 -409.656967)
			(xy 59.512585 -409.672321) (xy 59.562158 -409.69496) (xy 59.608004 -409.724424) (xy 59.64919 -409.760113)
			(xy 59.684878 -409.801299) (xy 59.714342 -409.847146) (xy 59.73698 -409.896718) (xy 59.752334 -409.949008)
			(xy 59.76009 -410.002951) (xy 59.76009 -410.057449) (xy 59.760089 -410.057457) (xy 61.197623 -410.057457)
			(xy 61.197623 -410.002943) (xy 61.205382 -409.948983) (xy 61.220741 -409.896678) (xy 61.243389 -409.84709)
			(xy 61.272864 -409.801231) (xy 61.308565 -409.760034) (xy 61.349767 -409.724337) (xy 61.395629 -409.694868)
			(xy 61.445219 -409.672226) (xy 61.497527 -409.656872) (xy 61.551487 -409.64912) (xy 61.578744 -409.64866)
			(xy 62.442344 -409.64866) (xy 62.469591 -409.649213) (xy 62.523529 -409.656974) (xy 62.575814 -409.672332)
			(xy 62.625382 -409.694973) (xy 62.671223 -409.724438) (xy 62.712404 -409.760127) (xy 62.748088 -409.801313)
			(xy 62.777548 -409.847157) (xy 62.800184 -409.896727) (xy 62.815535 -409.949014) (xy 62.82329 -410.002953)
			(xy 62.82329 -410.057447) (xy 62.823289 -410.057453) (xy 64.260946 -410.057453) (xy 64.260946 -410.002947)
			(xy 64.268703 -409.948996) (xy 64.284058 -409.896698) (xy 64.3067 -409.847118) (xy 64.336167 -409.801265)
			(xy 64.37186 -409.760071) (xy 64.413052 -409.724377) (xy 64.458904 -409.694908) (xy 64.508483 -409.672264)
			(xy 64.560781 -409.656906) (xy 64.614731 -409.649147) (xy 64.641984 -409.64866) (xy 65.505584 -409.64866)
			(xy 65.532835 -409.649186) (xy 65.586783 -409.656941) (xy 65.639079 -409.672294) (xy 65.688657 -409.694934)
			(xy 65.734508 -409.724399) (xy 65.775699 -409.760089) (xy 65.811392 -409.801279) (xy 65.840859 -409.847129)
			(xy 65.8635 -409.896706) (xy 65.878856 -409.949001) (xy 65.886613 -410.002949) (xy 65.886613 -410.057451)
			(xy 65.886612 -410.057456) (xy 67.324123 -410.057456) (xy 67.324123 -410.002944) (xy 67.331881 -409.948986)
			(xy 67.34724 -409.896682) (xy 67.369886 -409.847096) (xy 67.399359 -409.801238) (xy 67.435058 -409.760041)
			(xy 67.476257 -409.724344) (xy 67.522117 -409.694874) (xy 67.571704 -409.672231) (xy 67.62401 -409.656876)
			(xy 67.677968 -409.649121) (xy 67.705224 -409.64866) (xy 68.568824 -409.64866) (xy 68.596072 -409.649212)
			(xy 68.650012 -409.65697) (xy 68.7023 -409.672326) (xy 68.75187 -409.694967) (xy 68.797713 -409.724431)
			(xy 68.838897 -409.76012) (xy 68.874583 -409.801306) (xy 68.904045 -409.847151) (xy 68.926682 -409.896723)
			(xy 68.942035 -409.949011) (xy 68.94979 -410.002952) (xy 68.94979 -410.057448) (xy 68.949789 -410.057452)
			(xy 70.387446 -410.057452) (xy 70.387446 -410.002948) (xy 70.395202 -409.948999) (xy 70.410557 -409.896703)
			(xy 70.433197 -409.847124) (xy 70.462662 -409.801271) (xy 70.498353 -409.760079) (xy 70.539542 -409.724384)
			(xy 70.585392 -409.694914) (xy 70.634969 -409.672269) (xy 70.687264 -409.65691) (xy 70.741212 -409.649148)
			(xy 70.768464 -409.64866) (xy 71.632064 -409.64866) (xy 71.659316 -409.649185) (xy 71.713267 -409.656937)
			(xy 71.765564 -409.672289) (xy 71.815145 -409.694927) (xy 71.860999 -409.724392) (xy 71.902192 -409.760082)
			(xy 71.937887 -409.801273) (xy 71.967356 -409.847124) (xy 71.989999 -409.896702) (xy 72.005355 -409.948998)
			(xy 72.013113 -410.002948) (xy 72.013113 -410.057452) (xy 72.013113 -410.057455) (xy 73.450623 -410.057455)
			(xy 73.450623 -410.002945) (xy 73.458381 -409.948989) (xy 73.473738 -409.896686) (xy 73.496383 -409.847102)
			(xy 73.525854 -409.801244) (xy 73.561551 -409.760048) (xy 73.602748 -409.724351) (xy 73.648605 -409.694881)
			(xy 73.69819 -409.672237) (xy 73.750493 -409.65688) (xy 73.804449 -409.649123) (xy 73.831704 -409.64866)
			(xy 74.695304 -409.64866) (xy 74.722553 -409.64921) (xy 74.776495 -409.656967) (xy 74.828785 -409.672321)
			(xy 74.878358 -409.69496) (xy 74.924204 -409.724424) (xy 74.96539 -409.760113) (xy 75.001078 -409.801299)
			(xy 75.030542 -409.847146) (xy 75.05318 -409.896718) (xy 75.068534 -409.949008) (xy 75.07629 -410.002951)
			(xy 75.07629 -410.057449) (xy 75.076289 -410.057457) (xy 76.513823 -410.057457) (xy 76.513823 -410.002943)
			(xy 76.521582 -409.948983) (xy 76.536941 -409.896678) (xy 76.559589 -409.84709) (xy 76.589064 -409.801231)
			(xy 76.624765 -409.760034) (xy 76.665967 -409.724337) (xy 76.711829 -409.694868) (xy 76.761419 -409.672226)
			(xy 76.813727 -409.656872) (xy 76.867687 -409.64912) (xy 76.894944 -409.64866) (xy 77.758544 -409.64866)
			(xy 77.785791 -409.649213) (xy 77.839729 -409.656974) (xy 77.892014 -409.672332) (xy 77.941582 -409.694973)
			(xy 77.987423 -409.724438) (xy 78.028604 -409.760127) (xy 78.064288 -409.801313) (xy 78.093748 -409.847157)
			(xy 78.116384 -409.896727) (xy 78.131735 -409.949014) (xy 78.13949 -410.002953) (xy 78.13949 -410.057447)
			(xy 78.139489 -410.057453) (xy 79.577146 -410.057453) (xy 79.577146 -410.002947) (xy 79.584903 -409.948996)
			(xy 79.600258 -409.896698) (xy 79.6229 -409.847118) (xy 79.652367 -409.801265) (xy 79.68806 -409.760071)
			(xy 79.729252 -409.724377) (xy 79.775104 -409.694908) (xy 79.824683 -409.672264) (xy 79.876981 -409.656906)
			(xy 79.930931 -409.649147) (xy 79.958184 -409.64866) (xy 80.821784 -409.64866) (xy 80.849035 -409.649186)
			(xy 80.902983 -409.656941) (xy 80.955279 -409.672294) (xy 81.004857 -409.694934) (xy 81.050708 -409.724399)
			(xy 81.091899 -409.760089) (xy 81.127592 -409.801279) (xy 81.157059 -409.847129) (xy 81.1797 -409.896706)
			(xy 81.195056 -409.949001) (xy 81.202813 -410.002949) (xy 81.202813 -410.057451) (xy 81.202812 -410.057456)
			(xy 82.640323 -410.057456) (xy 82.640323 -410.002944) (xy 82.648081 -409.948986) (xy 82.66344 -409.896682)
			(xy 82.686086 -409.847096) (xy 82.715559 -409.801238) (xy 82.751258 -409.760041) (xy 82.792457 -409.724344)
			(xy 82.838317 -409.694874) (xy 82.887904 -409.672231) (xy 82.94021 -409.656876) (xy 82.994168 -409.649121)
			(xy 83.021424 -409.64866) (xy 83.885024 -409.64866) (xy 83.912272 -409.649212) (xy 83.966212 -409.65697)
			(xy 84.0185 -409.672326) (xy 84.06807 -409.694967) (xy 84.113913 -409.724431) (xy 84.155097 -409.76012)
			(xy 84.190783 -409.801306) (xy 84.220245 -409.847151) (xy 84.242882 -409.896723) (xy 84.258235 -409.949011)
			(xy 84.26599 -410.002952) (xy 84.26599 -410.057448) (xy 84.265989 -410.057452) (xy 85.703646 -410.057452)
			(xy 85.703646 -410.002948) (xy 85.711402 -409.948999) (xy 85.726757 -409.896703) (xy 85.749397 -409.847124)
			(xy 85.778862 -409.801271) (xy 85.814553 -409.760079) (xy 85.855742 -409.724384) (xy 85.901592 -409.694914)
			(xy 85.951169 -409.672269) (xy 86.003464 -409.65691) (xy 86.057412 -409.649148) (xy 86.084664 -409.64866)
			(xy 86.948264 -409.64866) (xy 86.975516 -409.649185) (xy 87.029467 -409.656937) (xy 87.081764 -409.672289)
			(xy 87.131345 -409.694927) (xy 87.177199 -409.724392) (xy 87.218392 -409.760082) (xy 87.254087 -409.801273)
			(xy 87.283556 -409.847124) (xy 87.306199 -409.896702) (xy 87.321555 -409.948998) (xy 87.329313 -410.002948)
			(xy 87.329313 -410.057452) (xy 87.329313 -410.057455) (xy 88.766823 -410.057455) (xy 88.766823 -410.002945)
			(xy 88.774581 -409.948989) (xy 88.789938 -409.896686) (xy 88.812583 -409.847102) (xy 88.842054 -409.801244)
			(xy 88.877751 -409.760048) (xy 88.918948 -409.724351) (xy 88.964805 -409.694881) (xy 89.01439 -409.672237)
			(xy 89.066693 -409.65688) (xy 89.120649 -409.649123) (xy 89.147904 -409.64866) (xy 90.011504 -409.64866)
			(xy 90.038753 -409.64921) (xy 90.092695 -409.656967) (xy 90.144985 -409.672321) (xy 90.194558 -409.69496)
			(xy 90.240404 -409.724424) (xy 90.28159 -409.760113) (xy 90.317278 -409.801299) (xy 90.346742 -409.847146)
			(xy 90.36938 -409.896718) (xy 90.384734 -409.949008) (xy 90.39249 -410.002951) (xy 90.39249 -410.057449)
			(xy 90.392489 -410.057457) (xy 91.830023 -410.057457) (xy 91.830023 -410.002943) (xy 91.837782 -409.948983)
			(xy 91.853141 -409.896678) (xy 91.875789 -409.84709) (xy 91.905264 -409.801231) (xy 91.940965 -409.760034)
			(xy 91.982167 -409.724337) (xy 92.028029 -409.694868) (xy 92.077619 -409.672226) (xy 92.129927 -409.656872)
			(xy 92.183887 -409.64912) (xy 92.211144 -409.64866) (xy 93.074744 -409.64866) (xy 93.101991 -409.649213)
			(xy 93.155929 -409.656974) (xy 93.208214 -409.672332) (xy 93.257782 -409.694973) (xy 93.303623 -409.724438)
			(xy 93.344804 -409.760127) (xy 93.380488 -409.801313) (xy 93.409948 -409.847157) (xy 93.432584 -409.896727)
			(xy 93.447935 -409.949014) (xy 93.45569 -410.002953) (xy 93.45569 -410.057447) (xy 93.455689 -410.057453)
			(xy 94.893346 -410.057453) (xy 94.893346 -410.002947) (xy 94.901103 -409.948996) (xy 94.916458 -409.896698)
			(xy 94.9391 -409.847118) (xy 94.968567 -409.801265) (xy 95.00426 -409.760071) (xy 95.045452 -409.724377)
			(xy 95.091304 -409.694908) (xy 95.140883 -409.672264) (xy 95.193181 -409.656906) (xy 95.247131 -409.649147)
			(xy 95.274384 -409.64866) (xy 96.137984 -409.64866) (xy 96.165235 -409.649186) (xy 96.219183 -409.656941)
			(xy 96.271479 -409.672294) (xy 96.321057 -409.694934) (xy 96.366908 -409.724399) (xy 96.408099 -409.760089)
			(xy 96.443792 -409.801279) (xy 96.473259 -409.847129) (xy 96.4959 -409.896706) (xy 96.511256 -409.949001)
			(xy 96.519013 -410.002949) (xy 96.519013 -410.057451) (xy 96.511256 -410.111399) (xy 96.4959 -410.163694)
			(xy 96.473259 -410.213271) (xy 96.443792 -410.259121) (xy 96.408099 -410.300311) (xy 96.366908 -410.336001)
			(xy 96.321057 -410.365466) (xy 96.271479 -410.388106) (xy 96.219183 -410.403459) (xy 96.165235 -410.411214)
			(xy 96.137984 -410.411676) (xy 95.274384 -410.411676) (xy 95.247131 -410.411253) (xy 95.193181 -410.403494)
			(xy 95.140883 -410.388136) (xy 95.091304 -410.365492) (xy 95.045452 -410.336023) (xy 95.00426 -410.300329)
			(xy 94.968567 -410.259135) (xy 94.9391 -410.213282) (xy 94.916458 -410.163702) (xy 94.901103 -410.111404)
			(xy 94.893346 -410.057453) (xy 93.455689 -410.057453) (xy 93.447935 -410.111386) (xy 93.432584 -410.163673)
			(xy 93.409948 -410.213243) (xy 93.380488 -410.259087) (xy 93.344804 -410.300273) (xy 93.303623 -410.335962)
			(xy 93.257782 -410.365427) (xy 93.208214 -410.388068) (xy 93.155929 -410.403426) (xy 93.101991 -410.411187)
			(xy 93.074744 -410.411676) (xy 92.211144 -410.411676) (xy 92.183887 -410.41128) (xy 92.129927 -410.403528)
			(xy 92.077619 -410.388174) (xy 92.028029 -410.365532) (xy 91.982167 -410.336063) (xy 91.940965 -410.300366)
			(xy 91.905264 -410.259169) (xy 91.875789 -410.21331) (xy 91.853141 -410.163722) (xy 91.837782 -410.111417)
			(xy 91.830023 -410.057457) (xy 90.392489 -410.057457) (xy 90.384734 -410.111392) (xy 90.36938 -410.163682)
			(xy 90.346742 -410.213254) (xy 90.317278 -410.259101) (xy 90.28159 -410.300287) (xy 90.240404 -410.335976)
			(xy 90.194558 -410.36544) (xy 90.144985 -410.388079) (xy 90.092695 -410.403433) (xy 90.038753 -410.41119)
			(xy 90.011504 -410.411676) (xy 89.147904 -410.411676) (xy 89.120649 -410.411277) (xy 89.066693 -410.40352)
			(xy 89.01439 -410.388163) (xy 88.964805 -410.365519) (xy 88.918948 -410.336049) (xy 88.877751 -410.300352)
			(xy 88.842054 -410.259156) (xy 88.812583 -410.213298) (xy 88.789938 -410.163714) (xy 88.774581 -410.111411)
			(xy 88.766823 -410.057455) (xy 87.329313 -410.057455) (xy 87.321555 -410.111402) (xy 87.306199 -410.163698)
			(xy 87.283556 -410.213276) (xy 87.254087 -410.259127) (xy 87.218392 -410.300318) (xy 87.177199 -410.336008)
			(xy 87.131345 -410.365473) (xy 87.081764 -410.388111) (xy 87.029467 -410.403463) (xy 86.975516 -410.411215)
			(xy 86.948264 -410.411676) (xy 86.084664 -410.411676) (xy 86.057412 -410.411252) (xy 86.003464 -410.40349)
			(xy 85.951169 -410.388131) (xy 85.901592 -410.365486) (xy 85.855742 -410.336016) (xy 85.814553 -410.300321)
			(xy 85.778862 -410.259129) (xy 85.749397 -410.213276) (xy 85.726757 -410.163697) (xy 85.711402 -410.111401)
			(xy 85.703646 -410.057452) (xy 84.265989 -410.057452) (xy 84.258235 -410.111389) (xy 84.242882 -410.163677)
			(xy 84.220245 -410.213249) (xy 84.190783 -410.259094) (xy 84.155097 -410.30028) (xy 84.113913 -410.335969)
			(xy 84.06807 -410.365433) (xy 84.0185 -410.388074) (xy 83.966212 -410.40343) (xy 83.912272 -410.411188)
			(xy 83.885024 -410.411676) (xy 83.021424 -410.411676) (xy 82.994168 -410.411279) (xy 82.94021 -410.403524)
			(xy 82.887904 -410.388169) (xy 82.838317 -410.365526) (xy 82.792457 -410.336056) (xy 82.751258 -410.300359)
			(xy 82.715559 -410.259162) (xy 82.686086 -410.213304) (xy 82.66344 -410.163718) (xy 82.648081 -410.111414)
			(xy 82.640323 -410.057456) (xy 81.202812 -410.057456) (xy 81.195056 -410.111399) (xy 81.1797 -410.163694)
			(xy 81.157059 -410.213271) (xy 81.127592 -410.259121) (xy 81.091899 -410.300311) (xy 81.050708 -410.336001)
			(xy 81.004857 -410.365466) (xy 80.955279 -410.388106) (xy 80.902983 -410.403459) (xy 80.849035 -410.411214)
			(xy 80.821784 -410.411676) (xy 79.958184 -410.411676) (xy 79.930931 -410.411253) (xy 79.876981 -410.403494)
			(xy 79.824683 -410.388136) (xy 79.775104 -410.365492) (xy 79.729252 -410.336023) (xy 79.68806 -410.300329)
			(xy 79.652367 -410.259135) (xy 79.6229 -410.213282) (xy 79.600258 -410.163702) (xy 79.584903 -410.111404)
			(xy 79.577146 -410.057453) (xy 78.139489 -410.057453) (xy 78.131735 -410.111386) (xy 78.116384 -410.163673)
			(xy 78.093748 -410.213243) (xy 78.064288 -410.259087) (xy 78.028604 -410.300273) (xy 77.987423 -410.335962)
			(xy 77.941582 -410.365427) (xy 77.892014 -410.388068) (xy 77.839729 -410.403426) (xy 77.785791 -410.411187)
			(xy 77.758544 -410.411676) (xy 76.894944 -410.411676) (xy 76.867687 -410.41128) (xy 76.813727 -410.403528)
			(xy 76.761419 -410.388174) (xy 76.711829 -410.365532) (xy 76.665967 -410.336063) (xy 76.624765 -410.300366)
			(xy 76.589064 -410.259169) (xy 76.559589 -410.21331) (xy 76.536941 -410.163722) (xy 76.521582 -410.111417)
			(xy 76.513823 -410.057457) (xy 75.076289 -410.057457) (xy 75.068534 -410.111392) (xy 75.05318 -410.163682)
			(xy 75.030542 -410.213254) (xy 75.001078 -410.259101) (xy 74.96539 -410.300287) (xy 74.924204 -410.335976)
			(xy 74.878358 -410.36544) (xy 74.828785 -410.388079) (xy 74.776495 -410.403433) (xy 74.722553 -410.41119)
			(xy 74.695304 -410.411676) (xy 73.831704 -410.411676) (xy 73.804449 -410.411277) (xy 73.750493 -410.40352)
			(xy 73.69819 -410.388163) (xy 73.648605 -410.365519) (xy 73.602748 -410.336049) (xy 73.561551 -410.300352)
			(xy 73.525854 -410.259156) (xy 73.496383 -410.213298) (xy 73.473738 -410.163714) (xy 73.458381 -410.111411)
			(xy 73.450623 -410.057455) (xy 72.013113 -410.057455) (xy 72.005355 -410.111402) (xy 71.989999 -410.163698)
			(xy 71.967356 -410.213276) (xy 71.937887 -410.259127) (xy 71.902192 -410.300318) (xy 71.860999 -410.336008)
			(xy 71.815145 -410.365473) (xy 71.765564 -410.388111) (xy 71.713267 -410.403463) (xy 71.659316 -410.411215)
			(xy 71.632064 -410.411676) (xy 70.768464 -410.411676) (xy 70.741212 -410.411252) (xy 70.687264 -410.40349)
			(xy 70.634969 -410.388131) (xy 70.585392 -410.365486) (xy 70.539542 -410.336016) (xy 70.498353 -410.300321)
			(xy 70.462662 -410.259129) (xy 70.433197 -410.213276) (xy 70.410557 -410.163697) (xy 70.395202 -410.111401)
			(xy 70.387446 -410.057452) (xy 68.949789 -410.057452) (xy 68.942035 -410.111389) (xy 68.926682 -410.163677)
			(xy 68.904045 -410.213249) (xy 68.874583 -410.259094) (xy 68.838897 -410.30028) (xy 68.797713 -410.335969)
			(xy 68.75187 -410.365433) (xy 68.7023 -410.388074) (xy 68.650012 -410.40343) (xy 68.596072 -410.411188)
			(xy 68.568824 -410.411676) (xy 67.705224 -410.411676) (xy 67.677968 -410.411279) (xy 67.62401 -410.403524)
			(xy 67.571704 -410.388169) (xy 67.522117 -410.365526) (xy 67.476257 -410.336056) (xy 67.435058 -410.300359)
			(xy 67.399359 -410.259162) (xy 67.369886 -410.213304) (xy 67.34724 -410.163718) (xy 67.331881 -410.111414)
			(xy 67.324123 -410.057456) (xy 65.886612 -410.057456) (xy 65.878856 -410.111399) (xy 65.8635 -410.163694)
			(xy 65.840859 -410.213271) (xy 65.811392 -410.259121) (xy 65.775699 -410.300311) (xy 65.734508 -410.336001)
			(xy 65.688657 -410.365466) (xy 65.639079 -410.388106) (xy 65.586783 -410.403459) (xy 65.532835 -410.411214)
			(xy 65.505584 -410.411676) (xy 64.641984 -410.411676) (xy 64.614731 -410.411253) (xy 64.560781 -410.403494)
			(xy 64.508483 -410.388136) (xy 64.458904 -410.365492) (xy 64.413052 -410.336023) (xy 64.37186 -410.300329)
			(xy 64.336167 -410.259135) (xy 64.3067 -410.213282) (xy 64.284058 -410.163702) (xy 64.268703 -410.111404)
			(xy 64.260946 -410.057453) (xy 62.823289 -410.057453) (xy 62.815535 -410.111386) (xy 62.800184 -410.163673)
			(xy 62.777548 -410.213243) (xy 62.748088 -410.259087) (xy 62.712404 -410.300273) (xy 62.671223 -410.335962)
			(xy 62.625382 -410.365427) (xy 62.575814 -410.388068) (xy 62.523529 -410.403426) (xy 62.469591 -410.411187)
			(xy 62.442344 -410.411676) (xy 61.578744 -410.411676) (xy 61.551487 -410.41128) (xy 61.497527 -410.403528)
			(xy 61.445219 -410.388174) (xy 61.395629 -410.365532) (xy 61.349767 -410.336063) (xy 61.308565 -410.300366)
			(xy 61.272864 -410.259169) (xy 61.243389 -410.21331) (xy 61.220741 -410.163722) (xy 61.205382 -410.111417)
			(xy 61.197623 -410.057457) (xy 59.760089 -410.057457) (xy 59.752334 -410.111392) (xy 59.73698 -410.163682)
			(xy 59.714342 -410.213254) (xy 59.684878 -410.259101) (xy 59.64919 -410.300287) (xy 59.608004 -410.335976)
			(xy 59.562158 -410.36544) (xy 59.512585 -410.388079) (xy 59.460295 -410.403433) (xy 59.406353 -410.41119)
			(xy 59.379104 -410.411676) (xy 58.515504 -410.411676) (xy 58.488249 -410.411277) (xy 58.434293 -410.40352)
			(xy 58.38199 -410.388163) (xy 58.332405 -410.365519) (xy 58.286548 -410.336049) (xy 58.245351 -410.300352)
			(xy 58.209654 -410.259156) (xy 58.180183 -410.213298) (xy 58.157538 -410.163714) (xy 58.142181 -410.111411)
			(xy 58.134423 -410.057455) (xy 56.696913 -410.057455) (xy 56.689155 -410.111402) (xy 56.673799 -410.163698)
			(xy 56.651156 -410.213276) (xy 56.621687 -410.259127) (xy 56.585992 -410.300318) (xy 56.544799 -410.336008)
			(xy 56.498945 -410.365473) (xy 56.449364 -410.388111) (xy 56.397067 -410.403463) (xy 56.343116 -410.411215)
			(xy 56.315864 -410.411676) (xy 55.452264 -410.411676) (xy 55.425012 -410.411252) (xy 55.371064 -410.40349)
			(xy 55.318769 -410.388131) (xy 55.269192 -410.365486) (xy 55.223342 -410.336016) (xy 55.182153 -410.300321)
			(xy 55.146462 -410.259129) (xy 55.116997 -410.213276) (xy 55.094357 -410.163697) (xy 55.079002 -410.111401)
			(xy 55.071246 -410.057452) (xy 53.633589 -410.057452) (xy 53.625835 -410.111389) (xy 53.610482 -410.163677)
			(xy 53.587845 -410.213249) (xy 53.558383 -410.259094) (xy 53.522697 -410.30028) (xy 53.481513 -410.335969)
			(xy 53.43567 -410.365433) (xy 53.3861 -410.388074) (xy 53.333812 -410.40343) (xy 53.279872 -410.411188)
			(xy 53.252624 -410.411676) (xy 52.389024 -410.411676) (xy 52.361768 -410.411279) (xy 52.30781 -410.403524)
			(xy 52.255504 -410.388169) (xy 52.205917 -410.365526) (xy 52.160057 -410.336056) (xy 52.118858 -410.300359)
			(xy 52.083159 -410.259162) (xy 52.053686 -410.213304) (xy 52.03104 -410.163718) (xy 52.015681 -410.111414)
			(xy 52.007923 -410.057456) (xy 50.570412 -410.057456) (xy 50.562656 -410.111399) (xy 50.5473 -410.163694)
			(xy 50.524659 -410.213271) (xy 50.495192 -410.259121) (xy 50.459499 -410.300311) (xy 50.418308 -410.336001)
			(xy 50.372457 -410.365466) (xy 50.322879 -410.388106) (xy 50.270583 -410.403459) (xy 50.216635 -410.411214)
			(xy 50.189384 -410.411676) (xy 49.325784 -410.411676) (xy 49.298531 -410.411253) (xy 49.244581 -410.403494)
			(xy 49.192283 -410.388136) (xy 49.142704 -410.365492) (xy 49.096852 -410.336023) (xy 49.05566 -410.300329)
			(xy 49.019967 -410.259135) (xy 48.9905 -410.213282) (xy 48.967858 -410.163702) (xy 48.952503 -410.111404)
			(xy 48.944746 -410.057453) (xy 38.191293 -410.057453) (xy 40.731292 -412.597452) (xy 47.413146 -412.597452)
			(xy 47.413146 -412.542948) (xy 47.420902 -412.488999) (xy 47.436257 -412.436703) (xy 47.458897 -412.387124)
			(xy 47.488362 -412.341271) (xy 47.524053 -412.300079) (xy 47.565242 -412.264384) (xy 47.611092 -412.234914)
			(xy 47.660669 -412.212269) (xy 47.712964 -412.19691) (xy 47.766912 -412.189148) (xy 47.794164 -412.18866)
			(xy 48.657764 -412.18866) (xy 48.685016 -412.189185) (xy 48.738967 -412.196937) (xy 48.791264 -412.212289)
			(xy 48.840845 -412.234927) (xy 48.886699 -412.264392) (xy 48.927892 -412.300082) (xy 48.963587 -412.341273)
			(xy 48.993056 -412.387124) (xy 49.015699 -412.436702) (xy 49.031055 -412.488998) (xy 49.038813 -412.542948)
			(xy 49.038813 -412.597452) (xy 49.038813 -412.597455) (xy 50.476323 -412.597455) (xy 50.476323 -412.542945)
			(xy 50.484081 -412.488989) (xy 50.499438 -412.436686) (xy 50.522083 -412.387102) (xy 50.551554 -412.341244)
			(xy 50.587251 -412.300048) (xy 50.628448 -412.264351) (xy 50.674305 -412.234881) (xy 50.72389 -412.212237)
			(xy 50.776193 -412.19688) (xy 50.830149 -412.189123) (xy 50.857404 -412.18866) (xy 51.721004 -412.18866)
			(xy 51.748253 -412.18921) (xy 51.802195 -412.196967) (xy 51.854485 -412.212321) (xy 51.904058 -412.23496)
			(xy 51.949904 -412.264424) (xy 51.99109 -412.300113) (xy 52.026778 -412.341299) (xy 52.056242 -412.387146)
			(xy 52.07888 -412.436718) (xy 52.094234 -412.489008) (xy 52.10199 -412.542951) (xy 52.10199 -412.597449)
			(xy 52.101989 -412.597457) (xy 53.539523 -412.597457) (xy 53.539523 -412.542943) (xy 53.547282 -412.488983)
			(xy 53.562641 -412.436678) (xy 53.585289 -412.38709) (xy 53.614764 -412.341231) (xy 53.650465 -412.300034)
			(xy 53.691667 -412.264337) (xy 53.737529 -412.234868) (xy 53.787119 -412.212226) (xy 53.839427 -412.196872)
			(xy 53.893387 -412.18912) (xy 53.920644 -412.18866) (xy 54.784244 -412.18866) (xy 54.811491 -412.189213)
			(xy 54.865429 -412.196974) (xy 54.917714 -412.212332) (xy 54.967282 -412.234973) (xy 55.013123 -412.264438)
			(xy 55.054304 -412.300127) (xy 55.089988 -412.341313) (xy 55.119448 -412.387157) (xy 55.142084 -412.436727)
			(xy 55.157435 -412.489014) (xy 55.16519 -412.542953) (xy 55.16519 -412.597447) (xy 55.165189 -412.597453)
			(xy 56.602846 -412.597453) (xy 56.602846 -412.542947) (xy 56.610603 -412.488996) (xy 56.625958 -412.436698)
			(xy 56.6486 -412.387118) (xy 56.678067 -412.341265) (xy 56.71376 -412.300071) (xy 56.754952 -412.264377)
			(xy 56.800804 -412.234908) (xy 56.850383 -412.212264) (xy 56.902681 -412.196906) (xy 56.956631 -412.189147)
			(xy 56.983884 -412.18866) (xy 57.847484 -412.18866) (xy 57.874735 -412.189186) (xy 57.928683 -412.196941)
			(xy 57.980979 -412.212294) (xy 58.030557 -412.234934) (xy 58.076408 -412.264399) (xy 58.117599 -412.300089)
			(xy 58.153292 -412.341279) (xy 58.182759 -412.387129) (xy 58.2054 -412.436706) (xy 58.220756 -412.489001)
			(xy 58.228513 -412.542949) (xy 58.228513 -412.597451) (xy 58.228512 -412.597456) (xy 59.666023 -412.597456)
			(xy 59.666023 -412.542944) (xy 59.673781 -412.488986) (xy 59.68914 -412.436682) (xy 59.711786 -412.387096)
			(xy 59.741259 -412.341238) (xy 59.776958 -412.300041) (xy 59.818157 -412.264344) (xy 59.864017 -412.234874)
			(xy 59.913604 -412.212231) (xy 59.96591 -412.196876) (xy 60.019868 -412.189121) (xy 60.047124 -412.18866)
			(xy 60.910724 -412.18866) (xy 60.937972 -412.189212) (xy 60.991912 -412.19697) (xy 61.0442 -412.212326)
			(xy 61.09377 -412.234967) (xy 61.139613 -412.264431) (xy 61.180797 -412.30012) (xy 61.216483 -412.341306)
			(xy 61.245945 -412.387151) (xy 61.268582 -412.436723) (xy 61.283935 -412.489011) (xy 61.29169 -412.542952)
			(xy 61.29169 -412.597448) (xy 61.291689 -412.597452) (xy 62.729346 -412.597452) (xy 62.729346 -412.542948)
			(xy 62.737102 -412.488999) (xy 62.752457 -412.436703) (xy 62.775097 -412.387124) (xy 62.804562 -412.341271)
			(xy 62.840253 -412.300079) (xy 62.881442 -412.264384) (xy 62.927292 -412.234914) (xy 62.976869 -412.212269)
			(xy 63.029164 -412.19691) (xy 63.083112 -412.189148) (xy 63.110364 -412.18866) (xy 63.973964 -412.18866)
			(xy 64.001216 -412.189185) (xy 64.055167 -412.196937) (xy 64.107464 -412.212289) (xy 64.157045 -412.234927)
			(xy 64.202899 -412.264392) (xy 64.244092 -412.300082) (xy 64.279787 -412.341273) (xy 64.309256 -412.387124)
			(xy 64.331899 -412.436702) (xy 64.347255 -412.488998) (xy 64.355013 -412.542948) (xy 64.355013 -412.597452)
			(xy 64.355013 -412.597455) (xy 65.792523 -412.597455) (xy 65.792523 -412.542945) (xy 65.800281 -412.488989)
			(xy 65.815638 -412.436686) (xy 65.838283 -412.387102) (xy 65.867754 -412.341244) (xy 65.903451 -412.300048)
			(xy 65.944648 -412.264351) (xy 65.990505 -412.234881) (xy 66.04009 -412.212237) (xy 66.092393 -412.19688)
			(xy 66.146349 -412.189123) (xy 66.173604 -412.18866) (xy 67.037204 -412.18866) (xy 67.064453 -412.18921)
			(xy 67.118395 -412.196967) (xy 67.170685 -412.212321) (xy 67.220258 -412.23496) (xy 67.266104 -412.264424)
			(xy 67.30729 -412.300113) (xy 67.342978 -412.341299) (xy 67.372442 -412.387146) (xy 67.39508 -412.436718)
			(xy 67.410434 -412.489008) (xy 67.41819 -412.542951) (xy 67.41819 -412.597449) (xy 67.418189 -412.597457)
			(xy 68.855723 -412.597457) (xy 68.855723 -412.542943) (xy 68.863482 -412.488983) (xy 68.878841 -412.436678)
			(xy 68.901489 -412.38709) (xy 68.930964 -412.341231) (xy 68.966665 -412.300034) (xy 69.007867 -412.264337)
			(xy 69.053729 -412.234868) (xy 69.103319 -412.212226) (xy 69.155627 -412.196872) (xy 69.209587 -412.18912)
			(xy 69.236844 -412.18866) (xy 70.100444 -412.18866) (xy 70.127691 -412.189213) (xy 70.181629 -412.196974)
			(xy 70.233914 -412.212332) (xy 70.283482 -412.234973) (xy 70.329323 -412.264438) (xy 70.370504 -412.300127)
			(xy 70.406188 -412.341313) (xy 70.435648 -412.387157) (xy 70.458284 -412.436727) (xy 70.473635 -412.489014)
			(xy 70.48139 -412.542953) (xy 70.48139 -412.597447) (xy 70.481389 -412.597453) (xy 71.919046 -412.597453)
			(xy 71.919046 -412.542947) (xy 71.926803 -412.488996) (xy 71.942158 -412.436698) (xy 71.9648 -412.387118)
			(xy 71.994267 -412.341265) (xy 72.02996 -412.300071) (xy 72.071152 -412.264377) (xy 72.117004 -412.234908)
			(xy 72.166583 -412.212264) (xy 72.218881 -412.196906) (xy 72.272831 -412.189147) (xy 72.300084 -412.18866)
			(xy 73.163684 -412.18866) (xy 73.190935 -412.189186) (xy 73.244883 -412.196941) (xy 73.297179 -412.212294)
			(xy 73.346757 -412.234934) (xy 73.392608 -412.264399) (xy 73.433799 -412.300089) (xy 73.469492 -412.341279)
			(xy 73.498959 -412.387129) (xy 73.5216 -412.436706) (xy 73.536956 -412.489001) (xy 73.544713 -412.542949)
			(xy 73.544713 -412.597451) (xy 73.544712 -412.597456) (xy 74.982223 -412.597456) (xy 74.982223 -412.542944)
			(xy 74.989981 -412.488986) (xy 75.00534 -412.436682) (xy 75.027986 -412.387096) (xy 75.057459 -412.341238)
			(xy 75.093158 -412.300041) (xy 75.134357 -412.264344) (xy 75.180217 -412.234874) (xy 75.229804 -412.212231)
			(xy 75.28211 -412.196876) (xy 75.336068 -412.189121) (xy 75.363324 -412.18866) (xy 76.226924 -412.18866)
			(xy 76.254172 -412.189212) (xy 76.308112 -412.19697) (xy 76.3604 -412.212326) (xy 76.40997 -412.234967)
			(xy 76.455813 -412.264431) (xy 76.496997 -412.30012) (xy 76.532683 -412.341306) (xy 76.562145 -412.387151)
			(xy 76.584782 -412.436723) (xy 76.600135 -412.489011) (xy 76.60789 -412.542952) (xy 76.60789 -412.597448)
			(xy 76.607889 -412.597452) (xy 78.045546 -412.597452) (xy 78.045546 -412.542948) (xy 78.053302 -412.488999)
			(xy 78.068657 -412.436703) (xy 78.091297 -412.387124) (xy 78.120762 -412.341271) (xy 78.156453 -412.300079)
			(xy 78.197642 -412.264384) (xy 78.243492 -412.234914) (xy 78.293069 -412.212269) (xy 78.345364 -412.19691)
			(xy 78.399312 -412.189148) (xy 78.426564 -412.18866) (xy 79.290164 -412.18866) (xy 79.317416 -412.189185)
			(xy 79.371367 -412.196937) (xy 79.423664 -412.212289) (xy 79.473245 -412.234927) (xy 79.519099 -412.264392)
			(xy 79.560292 -412.300082) (xy 79.595987 -412.341273) (xy 79.625456 -412.387124) (xy 79.648099 -412.436702)
			(xy 79.663455 -412.488998) (xy 79.671213 -412.542948) (xy 79.671213 -412.597452) (xy 79.671213 -412.597455)
			(xy 81.108723 -412.597455) (xy 81.108723 -412.542945) (xy 81.116481 -412.488989) (xy 81.131838 -412.436686)
			(xy 81.154483 -412.387102) (xy 81.183954 -412.341244) (xy 81.219651 -412.300048) (xy 81.260848 -412.264351)
			(xy 81.306705 -412.234881) (xy 81.35629 -412.212237) (xy 81.408593 -412.19688) (xy 81.462549 -412.189123)
			(xy 81.489804 -412.18866) (xy 82.353404 -412.18866) (xy 82.380653 -412.18921) (xy 82.434595 -412.196967)
			(xy 82.486885 -412.212321) (xy 82.536458 -412.23496) (xy 82.582304 -412.264424) (xy 82.62349 -412.300113)
			(xy 82.659178 -412.341299) (xy 82.688642 -412.387146) (xy 82.71128 -412.436718) (xy 82.726634 -412.489008)
			(xy 82.73439 -412.542951) (xy 82.73439 -412.597449) (xy 82.734389 -412.597457) (xy 84.171923 -412.597457)
			(xy 84.171923 -412.542943) (xy 84.179682 -412.488983) (xy 84.195041 -412.436678) (xy 84.217689 -412.38709)
			(xy 84.247164 -412.341231) (xy 84.282865 -412.300034) (xy 84.324067 -412.264337) (xy 84.369929 -412.234868)
			(xy 84.419519 -412.212226) (xy 84.471827 -412.196872) (xy 84.525787 -412.18912) (xy 84.553044 -412.18866)
			(xy 85.416644 -412.18866) (xy 85.443891 -412.189213) (xy 85.497829 -412.196974) (xy 85.550114 -412.212332)
			(xy 85.599682 -412.234973) (xy 85.645523 -412.264438) (xy 85.686704 -412.300127) (xy 85.722388 -412.341313)
			(xy 85.751848 -412.387157) (xy 85.774484 -412.436727) (xy 85.789835 -412.489014) (xy 85.79759 -412.542953)
			(xy 85.79759 -412.597447) (xy 85.797589 -412.597453) (xy 87.235246 -412.597453) (xy 87.235246 -412.542947)
			(xy 87.243003 -412.488996) (xy 87.258358 -412.436698) (xy 87.281 -412.387118) (xy 87.310467 -412.341265)
			(xy 87.34616 -412.300071) (xy 87.387352 -412.264377) (xy 87.433204 -412.234908) (xy 87.482783 -412.212264)
			(xy 87.535081 -412.196906) (xy 87.589031 -412.189147) (xy 87.616284 -412.18866) (xy 88.479884 -412.18866)
			(xy 88.507135 -412.189186) (xy 88.561083 -412.196941) (xy 88.613379 -412.212294) (xy 88.662957 -412.234934)
			(xy 88.708808 -412.264399) (xy 88.749999 -412.300089) (xy 88.785692 -412.341279) (xy 88.815159 -412.387129)
			(xy 88.8378 -412.436706) (xy 88.853156 -412.489001) (xy 88.860913 -412.542949) (xy 88.860913 -412.597451)
			(xy 88.860912 -412.597456) (xy 90.298423 -412.597456) (xy 90.298423 -412.542944) (xy 90.306181 -412.488986)
			(xy 90.32154 -412.436682) (xy 90.344186 -412.387096) (xy 90.373659 -412.341238) (xy 90.409358 -412.300041)
			(xy 90.450557 -412.264344) (xy 90.496417 -412.234874) (xy 90.546004 -412.212231) (xy 90.59831 -412.196876)
			(xy 90.652268 -412.189121) (xy 90.679524 -412.18866) (xy 91.543124 -412.18866) (xy 91.570372 -412.189212)
			(xy 91.624312 -412.19697) (xy 91.6766 -412.212326) (xy 91.72617 -412.234967) (xy 91.772013 -412.264431)
			(xy 91.813197 -412.30012) (xy 91.848883 -412.341306) (xy 91.878345 -412.387151) (xy 91.900982 -412.436723)
			(xy 91.916335 -412.489011) (xy 91.92409 -412.542952) (xy 91.92409 -412.597448) (xy 91.924089 -412.597452)
			(xy 93.361746 -412.597452) (xy 93.361746 -412.542948) (xy 93.369502 -412.488999) (xy 93.384857 -412.436703)
			(xy 93.407497 -412.387124) (xy 93.436962 -412.341271) (xy 93.472653 -412.300079) (xy 93.513842 -412.264384)
			(xy 93.559692 -412.234914) (xy 93.609269 -412.212269) (xy 93.661564 -412.19691) (xy 93.715512 -412.189148)
			(xy 93.742764 -412.18866) (xy 94.606364 -412.18866) (xy 94.633616 -412.189185) (xy 94.687567 -412.196937)
			(xy 94.739864 -412.212289) (xy 94.789445 -412.234927) (xy 94.835299 -412.264392) (xy 94.876492 -412.300082)
			(xy 94.912187 -412.341273) (xy 94.941656 -412.387124) (xy 94.964299 -412.436702) (xy 94.979655 -412.488998)
			(xy 94.987413 -412.542948) (xy 94.987413 -412.597452) (xy 94.987413 -412.597455) (xy 114.513023 -412.597455)
			(xy 114.513023 -412.542945) (xy 114.520781 -412.488989) (xy 114.536138 -412.436686) (xy 114.558783 -412.387101)
			(xy 114.588254 -412.341244) (xy 114.623952 -412.300047) (xy 114.665149 -412.264351) (xy 114.711006 -412.23488)
			(xy 114.760591 -412.212236) (xy 114.812894 -412.196879) (xy 114.866851 -412.189123) (xy 114.894106 -412.18866)
			(xy 115.757706 -412.18866) (xy 115.784955 -412.189211) (xy 115.838897 -412.196967) (xy 115.891187 -412.212321)
			(xy 115.940759 -412.234961) (xy 115.986605 -412.264425) (xy 116.027791 -412.300113) (xy 116.063479 -412.3413)
			(xy 116.092942 -412.387146) (xy 116.115581 -412.436719) (xy 116.130934 -412.489009) (xy 116.13869 -412.542951)
			(xy 116.13869 -412.597449) (xy 116.138689 -412.597457) (xy 117.576223 -412.597457) (xy 117.576223 -412.542943)
			(xy 117.583982 -412.488983) (xy 117.599342 -412.436677) (xy 117.621989 -412.38709) (xy 117.651464 -412.341231)
			(xy 117.687166 -412.300033) (xy 117.728367 -412.264337) (xy 117.77423 -412.234867) (xy 117.82382 -412.212225)
			(xy 117.876128 -412.196872) (xy 117.930089 -412.18912) (xy 117.957346 -412.18866) (xy 118.820946 -412.18866)
			(xy 118.848193 -412.189213) (xy 118.902131 -412.196975) (xy 118.954416 -412.212332) (xy 119.003983 -412.234974)
			(xy 119.049824 -412.264439) (xy 119.091005 -412.300128) (xy 119.126688 -412.341313) (xy 119.156148 -412.387157)
			(xy 119.178784 -412.436727) (xy 119.194135 -412.489014) (xy 119.20189 -412.542953) (xy 119.20189 -412.597447)
			(xy 119.201889 -412.597453) (xy 120.639546 -412.597453) (xy 120.639546 -412.542947) (xy 120.647303 -412.488996)
			(xy 120.662658 -412.436698) (xy 120.6853 -412.387118) (xy 120.714768 -412.341264) (xy 120.750461 -412.300071)
			(xy 120.791653 -412.264376) (xy 120.837505 -412.234907) (xy 120.887085 -412.212263) (xy 120.939382 -412.196906)
			(xy 120.993333 -412.189147) (xy 121.020586 -412.18866) (xy 121.884186 -412.18866) (xy 121.911437 -412.189186)
			(xy 121.965385 -412.196941) (xy 122.01768 -412.212295) (xy 122.067258 -412.234934) (xy 122.113109 -412.264399)
			(xy 122.1543 -412.30009) (xy 122.189992 -412.34128) (xy 122.219459 -412.38713) (xy 122.242101 -412.436707)
			(xy 122.257456 -412.489001) (xy 122.265213 -412.542949) (xy 122.265213 -412.597451) (xy 122.265212 -412.597456)
			(xy 123.702723 -412.597456) (xy 123.702723 -412.542944) (xy 123.710481 -412.488986) (xy 123.72584 -412.436681)
			(xy 123.748486 -412.387095) (xy 123.777959 -412.341237) (xy 123.813659 -412.30004) (xy 123.854858 -412.264344)
			(xy 123.900718 -412.234874) (xy 123.950306 -412.212231) (xy 124.002611 -412.196876) (xy 124.05657 -412.189121)
			(xy 124.083826 -412.18866) (xy 124.947426 -412.18866) (xy 124.974674 -412.189212) (xy 125.028614 -412.196971)
			(xy 125.080901 -412.212327) (xy 125.130471 -412.234968) (xy 125.176314 -412.264432) (xy 125.217498 -412.300121)
			(xy 125.253184 -412.341307) (xy 125.282645 -412.387152) (xy 125.305282 -412.436723) (xy 125.320635 -412.489011)
			(xy 125.32839 -412.542952) (xy 125.32839 -412.597448) (xy 125.328389 -412.597452) (xy 126.766046 -412.597452)
			(xy 126.766046 -412.542948) (xy 126.773802 -412.488999) (xy 126.789157 -412.436702) (xy 126.811797 -412.387123)
			(xy 126.841263 -412.341271) (xy 126.876954 -412.300078) (xy 126.918143 -412.264383) (xy 126.963993 -412.234914)
			(xy 127.01357 -412.212269) (xy 127.065865 -412.196909) (xy 127.119814 -412.189148) (xy 127.147066 -412.18866)
			(xy 128.010666 -412.18866) (xy 128.037918 -412.189185) (xy 128.091868 -412.196937) (xy 128.144166 -412.212289)
			(xy 128.193746 -412.234928) (xy 128.2396 -412.264392) (xy 128.280793 -412.300083) (xy 128.316487 -412.341273)
			(xy 128.345956 -412.387124) (xy 128.368599 -412.436702) (xy 128.383955 -412.488999) (xy 128.391713 -412.542948)
			(xy 128.391713 -412.597452) (xy 128.391713 -412.597455) (xy 129.829223 -412.597455) (xy 129.829223 -412.542945)
			(xy 129.836981 -412.488989) (xy 129.852338 -412.436686) (xy 129.874983 -412.387101) (xy 129.904454 -412.341244)
			(xy 129.940152 -412.300047) (xy 129.981349 -412.264351) (xy 130.027206 -412.23488) (xy 130.076791 -412.212236)
			(xy 130.129094 -412.196879) (xy 130.183051 -412.189123) (xy 130.210306 -412.18866) (xy 131.073906 -412.18866)
			(xy 131.101155 -412.189211) (xy 131.155097 -412.196967) (xy 131.207387 -412.212321) (xy 131.256959 -412.234961)
			(xy 131.302805 -412.264425) (xy 131.343991 -412.300113) (xy 131.379679 -412.3413) (xy 131.409142 -412.387146)
			(xy 131.431781 -412.436719) (xy 131.447134 -412.489009) (xy 131.45489 -412.542951) (xy 131.45489 -412.597449)
			(xy 131.454889 -412.597457) (xy 132.892423 -412.597457) (xy 132.892423 -412.542943) (xy 132.900182 -412.488983)
			(xy 132.915542 -412.436677) (xy 132.938189 -412.38709) (xy 132.967664 -412.341231) (xy 133.003366 -412.300033)
			(xy 133.044567 -412.264337) (xy 133.09043 -412.234867) (xy 133.14002 -412.212225) (xy 133.192328 -412.196872)
			(xy 133.246289 -412.18912) (xy 133.273546 -412.18866) (xy 134.137146 -412.18866) (xy 134.164393 -412.189213)
			(xy 134.218331 -412.196975) (xy 134.270616 -412.212332) (xy 134.320183 -412.234974) (xy 134.366024 -412.264439)
			(xy 134.407205 -412.300128) (xy 134.442888 -412.341313) (xy 134.472348 -412.387157) (xy 134.494984 -412.436727)
			(xy 134.510335 -412.489014) (xy 134.51809 -412.542953) (xy 134.51809 -412.597447) (xy 134.518089 -412.597453)
			(xy 135.955746 -412.597453) (xy 135.955746 -412.542947) (xy 135.963503 -412.488996) (xy 135.978858 -412.436698)
			(xy 136.0015 -412.387118) (xy 136.030968 -412.341264) (xy 136.066661 -412.300071) (xy 136.107853 -412.264376)
			(xy 136.153705 -412.234907) (xy 136.203285 -412.212263) (xy 136.255582 -412.196906) (xy 136.309533 -412.189147)
			(xy 136.336786 -412.18866) (xy 137.200386 -412.18866) (xy 137.227637 -412.189186) (xy 137.281585 -412.196941)
			(xy 137.33388 -412.212295) (xy 137.383458 -412.234934) (xy 137.429309 -412.264399) (xy 137.4705 -412.30009)
			(xy 137.506192 -412.34128) (xy 137.535659 -412.38713) (xy 137.558301 -412.436707) (xy 137.573656 -412.489001)
			(xy 137.581413 -412.542949) (xy 137.581413 -412.597451) (xy 137.581412 -412.597456) (xy 139.018923 -412.597456)
			(xy 139.018923 -412.542944) (xy 139.026681 -412.488986) (xy 139.04204 -412.436681) (xy 139.064686 -412.387095)
			(xy 139.094159 -412.341237) (xy 139.129859 -412.30004) (xy 139.171058 -412.264344) (xy 139.216918 -412.234874)
			(xy 139.266506 -412.212231) (xy 139.318811 -412.196876) (xy 139.37277 -412.189121) (xy 139.400026 -412.18866)
			(xy 140.263626 -412.18866) (xy 140.290874 -412.189212) (xy 140.344814 -412.196971) (xy 140.397101 -412.212327)
			(xy 140.446671 -412.234968) (xy 140.492514 -412.264432) (xy 140.533698 -412.300121) (xy 140.569384 -412.341307)
			(xy 140.598845 -412.387152) (xy 140.621482 -412.436723) (xy 140.636835 -412.489011) (xy 140.64459 -412.542952)
			(xy 140.64459 -412.597448) (xy 140.644589 -412.597452) (xy 142.082246 -412.597452) (xy 142.082246 -412.542948)
			(xy 142.090002 -412.488999) (xy 142.105357 -412.436702) (xy 142.127997 -412.387123) (xy 142.157463 -412.341271)
			(xy 142.193154 -412.300078) (xy 142.234343 -412.264383) (xy 142.280193 -412.234914) (xy 142.32977 -412.212269)
			(xy 142.382065 -412.196909) (xy 142.436014 -412.189148) (xy 142.463266 -412.18866) (xy 143.326866 -412.18866)
			(xy 143.354118 -412.189185) (xy 143.408068 -412.196937) (xy 143.460366 -412.212289) (xy 143.509946 -412.234928)
			(xy 143.5558 -412.264392) (xy 143.596993 -412.300083) (xy 143.632687 -412.341273) (xy 143.662156 -412.387124)
			(xy 143.684799 -412.436702) (xy 143.700155 -412.488999) (xy 143.707913 -412.542948) (xy 143.707913 -412.597452)
			(xy 143.707913 -412.597455) (xy 145.145423 -412.597455) (xy 145.145423 -412.542945) (xy 145.153181 -412.488989)
			(xy 145.168538 -412.436686) (xy 145.191183 -412.387101) (xy 145.220654 -412.341244) (xy 145.256352 -412.300047)
			(xy 145.297549 -412.264351) (xy 145.343406 -412.23488) (xy 145.392991 -412.212236) (xy 145.445294 -412.196879)
			(xy 145.499251 -412.189123) (xy 145.526506 -412.18866) (xy 146.390106 -412.18866) (xy 146.417355 -412.189211)
			(xy 146.471297 -412.196967) (xy 146.523587 -412.212321) (xy 146.573159 -412.234961) (xy 146.619005 -412.264425)
			(xy 146.660191 -412.300113) (xy 146.695879 -412.3413) (xy 146.725342 -412.387146) (xy 146.747981 -412.436719)
			(xy 146.763334 -412.489009) (xy 146.77109 -412.542951) (xy 146.77109 -412.597449) (xy 146.771089 -412.597457)
			(xy 148.208623 -412.597457) (xy 148.208623 -412.542943) (xy 148.216382 -412.488983) (xy 148.231742 -412.436677)
			(xy 148.254389 -412.38709) (xy 148.283864 -412.341231) (xy 148.319566 -412.300033) (xy 148.360767 -412.264337)
			(xy 148.40663 -412.234867) (xy 148.45622 -412.212225) (xy 148.508528 -412.196872) (xy 148.562489 -412.18912)
			(xy 148.589746 -412.18866) (xy 149.453346 -412.18866) (xy 149.480593 -412.189213) (xy 149.534531 -412.196975)
			(xy 149.586816 -412.212332) (xy 149.636383 -412.234974) (xy 149.682224 -412.264439) (xy 149.723405 -412.300128)
			(xy 149.759088 -412.341313) (xy 149.788548 -412.387157) (xy 149.811184 -412.436727) (xy 149.826535 -412.489014)
			(xy 149.83429 -412.542953) (xy 149.83429 -412.597447) (xy 149.834289 -412.597453) (xy 151.271946 -412.597453)
			(xy 151.271946 -412.542947) (xy 151.279703 -412.488996) (xy 151.295058 -412.436698) (xy 151.3177 -412.387118)
			(xy 151.347168 -412.341264) (xy 151.382861 -412.300071) (xy 151.424053 -412.264376) (xy 151.469905 -412.234907)
			(xy 151.519485 -412.212263) (xy 151.571782 -412.196906) (xy 151.625733 -412.189147) (xy 151.652986 -412.18866)
			(xy 152.516586 -412.18866) (xy 152.543837 -412.189186) (xy 152.597785 -412.196941) (xy 152.65008 -412.212295)
			(xy 152.699658 -412.234934) (xy 152.745509 -412.264399) (xy 152.7867 -412.30009) (xy 152.822392 -412.34128)
			(xy 152.851859 -412.38713) (xy 152.874501 -412.436707) (xy 152.889856 -412.489001) (xy 152.897613 -412.542949)
			(xy 152.897613 -412.597451) (xy 152.897612 -412.597456) (xy 154.335123 -412.597456) (xy 154.335123 -412.542944)
			(xy 154.342881 -412.488986) (xy 154.35824 -412.436681) (xy 154.380886 -412.387095) (xy 154.410359 -412.341237)
			(xy 154.446059 -412.30004) (xy 154.487258 -412.264344) (xy 154.533118 -412.234874) (xy 154.582706 -412.212231)
			(xy 154.635011 -412.196876) (xy 154.68897 -412.189121) (xy 154.716226 -412.18866) (xy 155.579826 -412.18866)
			(xy 155.607074 -412.189212) (xy 155.661014 -412.196971) (xy 155.713301 -412.212327) (xy 155.762871 -412.234968)
			(xy 155.808714 -412.264432) (xy 155.849898 -412.300121) (xy 155.885584 -412.341307) (xy 155.915045 -412.387152)
			(xy 155.937682 -412.436723) (xy 155.953035 -412.489011) (xy 155.96079 -412.542952) (xy 155.96079 -412.597448)
			(xy 155.960789 -412.597452) (xy 157.398446 -412.597452) (xy 157.398446 -412.542948) (xy 157.406202 -412.488999)
			(xy 157.421557 -412.436702) (xy 157.444197 -412.387123) (xy 157.473663 -412.341271) (xy 157.509354 -412.300078)
			(xy 157.550543 -412.264383) (xy 157.596393 -412.234914) (xy 157.64597 -412.212269) (xy 157.698265 -412.196909)
			(xy 157.752214 -412.189148) (xy 157.779466 -412.18866) (xy 158.643066 -412.18866) (xy 158.670318 -412.189185)
			(xy 158.724268 -412.196937) (xy 158.776566 -412.212289) (xy 158.826146 -412.234928) (xy 158.872 -412.264392)
			(xy 158.913193 -412.300083) (xy 158.948887 -412.341273) (xy 158.978356 -412.387124) (xy 159.000999 -412.436702)
			(xy 159.016355 -412.488999) (xy 159.024113 -412.542948) (xy 159.024113 -412.597452) (xy 159.024113 -412.597455)
			(xy 160.461623 -412.597455) (xy 160.461623 -412.542945) (xy 160.469381 -412.488989) (xy 160.484738 -412.436686)
			(xy 160.507383 -412.387101) (xy 160.536854 -412.341244) (xy 160.572552 -412.300047) (xy 160.613749 -412.264351)
			(xy 160.659606 -412.23488) (xy 160.709191 -412.212236) (xy 160.761494 -412.196879) (xy 160.815451 -412.189123)
			(xy 160.842706 -412.18866) (xy 161.706306 -412.18866) (xy 161.733555 -412.189211) (xy 161.787497 -412.196967)
			(xy 161.839787 -412.212321) (xy 161.889359 -412.234961) (xy 161.935205 -412.264425) (xy 161.976391 -412.300113)
			(xy 162.012079 -412.3413) (xy 162.041542 -412.387146) (xy 162.064181 -412.436719) (xy 162.079534 -412.489009)
			(xy 162.08729 -412.542951) (xy 162.08729 -412.597449) (xy 162.079534 -412.651391) (xy 162.064181 -412.703681)
			(xy 162.041542 -412.753254) (xy 162.012079 -412.7991) (xy 161.976391 -412.840287) (xy 161.935205 -412.875975)
			(xy 161.889359 -412.905439) (xy 161.839787 -412.928079) (xy 161.787497 -412.943433) (xy 161.733555 -412.951189)
			(xy 161.706306 -412.951676) (xy 160.842706 -412.951676) (xy 160.815451 -412.951277) (xy 160.761494 -412.943521)
			(xy 160.709191 -412.928164) (xy 160.659606 -412.90552) (xy 160.613749 -412.876049) (xy 160.572552 -412.840353)
			(xy 160.536854 -412.799156) (xy 160.507383 -412.753299) (xy 160.484738 -412.703714) (xy 160.469381 -412.651411)
			(xy 160.461623 -412.597455) (xy 159.024113 -412.597455) (xy 159.016355 -412.651402) (xy 159.000999 -412.703698)
			(xy 158.978356 -412.753276) (xy 158.948887 -412.799127) (xy 158.913193 -412.840317) (xy 158.872 -412.876008)
			(xy 158.826146 -412.905472) (xy 158.776566 -412.928111) (xy 158.724268 -412.943463) (xy 158.670318 -412.951215)
			(xy 158.643066 -412.951676) (xy 157.779466 -412.951676) (xy 157.752214 -412.951252) (xy 157.698265 -412.943491)
			(xy 157.64597 -412.928131) (xy 157.596393 -412.905486) (xy 157.550543 -412.876017) (xy 157.509354 -412.840322)
			(xy 157.473663 -412.799129) (xy 157.444197 -412.753277) (xy 157.421557 -412.703698) (xy 157.406202 -412.651401)
			(xy 157.398446 -412.597452) (xy 155.960789 -412.597452) (xy 155.953035 -412.651389) (xy 155.937682 -412.703677)
			(xy 155.915045 -412.753248) (xy 155.885584 -412.799093) (xy 155.849898 -412.840279) (xy 155.808714 -412.875968)
			(xy 155.762871 -412.905432) (xy 155.713301 -412.928073) (xy 155.661014 -412.943429) (xy 155.607074 -412.951188)
			(xy 155.579826 -412.951676) (xy 154.716226 -412.951676) (xy 154.68897 -412.951279) (xy 154.635011 -412.943524)
			(xy 154.582706 -412.928169) (xy 154.533118 -412.905526) (xy 154.487258 -412.876056) (xy 154.446059 -412.84036)
			(xy 154.410359 -412.799163) (xy 154.380886 -412.753305) (xy 154.35824 -412.703719) (xy 154.342881 -412.651414)
			(xy 154.335123 -412.597456) (xy 152.897612 -412.597456) (xy 152.889856 -412.651399) (xy 152.874501 -412.703693)
			(xy 152.851859 -412.75327) (xy 152.822392 -412.79912) (xy 152.7867 -412.84031) (xy 152.745509 -412.876001)
			(xy 152.699658 -412.905466) (xy 152.65008 -412.928105) (xy 152.597785 -412.943459) (xy 152.543837 -412.951214)
			(xy 152.516586 -412.951676) (xy 151.652986 -412.951676) (xy 151.625733 -412.951253) (xy 151.571782 -412.943494)
			(xy 151.519485 -412.928137) (xy 151.469905 -412.905493) (xy 151.424053 -412.876024) (xy 151.382861 -412.840329)
			(xy 151.347168 -412.799136) (xy 151.3177 -412.753282) (xy 151.295058 -412.703702) (xy 151.279703 -412.651404)
			(xy 151.271946 -412.597453) (xy 149.834289 -412.597453) (xy 149.826535 -412.651386) (xy 149.811184 -412.703673)
			(xy 149.788548 -412.753243) (xy 149.759088 -412.799087) (xy 149.723405 -412.840272) (xy 149.682224 -412.875961)
			(xy 149.636383 -412.905426) (xy 149.586816 -412.928068) (xy 149.534531 -412.943425) (xy 149.480593 -412.951187)
			(xy 149.453346 -412.951676) (xy 148.589746 -412.951676) (xy 148.562489 -412.95128) (xy 148.508528 -412.943528)
			(xy 148.45622 -412.928175) (xy 148.40663 -412.905533) (xy 148.360767 -412.876063) (xy 148.319566 -412.840367)
			(xy 148.283864 -412.799169) (xy 148.254389 -412.75331) (xy 148.231742 -412.703723) (xy 148.216382 -412.651417)
			(xy 148.208623 -412.597457) (xy 146.771089 -412.597457) (xy 146.763334 -412.651391) (xy 146.747981 -412.703681)
			(xy 146.725342 -412.753254) (xy 146.695879 -412.7991) (xy 146.660191 -412.840287) (xy 146.619005 -412.875975)
			(xy 146.573159 -412.905439) (xy 146.523587 -412.928079) (xy 146.471297 -412.943433) (xy 146.417355 -412.951189)
			(xy 146.390106 -412.951676) (xy 145.526506 -412.951676) (xy 145.499251 -412.951277) (xy 145.445294 -412.943521)
			(xy 145.392991 -412.928164) (xy 145.343406 -412.90552) (xy 145.297549 -412.876049) (xy 145.256352 -412.840353)
			(xy 145.220654 -412.799156) (xy 145.191183 -412.753299) (xy 145.168538 -412.703714) (xy 145.153181 -412.651411)
			(xy 145.145423 -412.597455) (xy 143.707913 -412.597455) (xy 143.700155 -412.651402) (xy 143.684799 -412.703698)
			(xy 143.662156 -412.753276) (xy 143.632687 -412.799127) (xy 143.596993 -412.840317) (xy 143.5558 -412.876008)
			(xy 143.509946 -412.905472) (xy 143.460366 -412.928111) (xy 143.408068 -412.943463) (xy 143.354118 -412.951215)
			(xy 143.326866 -412.951676) (xy 142.463266 -412.951676) (xy 142.436014 -412.951252) (xy 142.382065 -412.943491)
			(xy 142.32977 -412.928131) (xy 142.280193 -412.905486) (xy 142.234343 -412.876017) (xy 142.193154 -412.840322)
			(xy 142.157463 -412.799129) (xy 142.127997 -412.753277) (xy 142.105357 -412.703698) (xy 142.090002 -412.651401)
			(xy 142.082246 -412.597452) (xy 140.644589 -412.597452) (xy 140.636835 -412.651389) (xy 140.621482 -412.703677)
			(xy 140.598845 -412.753248) (xy 140.569384 -412.799093) (xy 140.533698 -412.840279) (xy 140.492514 -412.875968)
			(xy 140.446671 -412.905432) (xy 140.397101 -412.928073) (xy 140.344814 -412.943429) (xy 140.290874 -412.951188)
			(xy 140.263626 -412.951676) (xy 139.400026 -412.951676) (xy 139.37277 -412.951279) (xy 139.318811 -412.943524)
			(xy 139.266506 -412.928169) (xy 139.216918 -412.905526) (xy 139.171058 -412.876056) (xy 139.129859 -412.84036)
			(xy 139.094159 -412.799163) (xy 139.064686 -412.753305) (xy 139.04204 -412.703719) (xy 139.026681 -412.651414)
			(xy 139.018923 -412.597456) (xy 137.581412 -412.597456) (xy 137.573656 -412.651399) (xy 137.558301 -412.703693)
			(xy 137.535659 -412.75327) (xy 137.506192 -412.79912) (xy 137.4705 -412.84031) (xy 137.429309 -412.876001)
			(xy 137.383458 -412.905466) (xy 137.33388 -412.928105) (xy 137.281585 -412.943459) (xy 137.227637 -412.951214)
			(xy 137.200386 -412.951676) (xy 136.336786 -412.951676) (xy 136.309533 -412.951253) (xy 136.255582 -412.943494)
			(xy 136.203285 -412.928137) (xy 136.153705 -412.905493) (xy 136.107853 -412.876024) (xy 136.066661 -412.840329)
			(xy 136.030968 -412.799136) (xy 136.0015 -412.753282) (xy 135.978858 -412.703702) (xy 135.963503 -412.651404)
			(xy 135.955746 -412.597453) (xy 134.518089 -412.597453) (xy 134.510335 -412.651386) (xy 134.494984 -412.703673)
			(xy 134.472348 -412.753243) (xy 134.442888 -412.799087) (xy 134.407205 -412.840272) (xy 134.366024 -412.875961)
			(xy 134.320183 -412.905426) (xy 134.270616 -412.928068) (xy 134.218331 -412.943425) (xy 134.164393 -412.951187)
			(xy 134.137146 -412.951676) (xy 133.273546 -412.951676) (xy 133.246289 -412.95128) (xy 133.192328 -412.943528)
			(xy 133.14002 -412.928175) (xy 133.09043 -412.905533) (xy 133.044567 -412.876063) (xy 133.003366 -412.840367)
			(xy 132.967664 -412.799169) (xy 132.938189 -412.75331) (xy 132.915542 -412.703723) (xy 132.900182 -412.651417)
			(xy 132.892423 -412.597457) (xy 131.454889 -412.597457) (xy 131.447134 -412.651391) (xy 131.431781 -412.703681)
			(xy 131.409142 -412.753254) (xy 131.379679 -412.7991) (xy 131.343991 -412.840287) (xy 131.302805 -412.875975)
			(xy 131.256959 -412.905439) (xy 131.207387 -412.928079) (xy 131.155097 -412.943433) (xy 131.101155 -412.951189)
			(xy 131.073906 -412.951676) (xy 130.210306 -412.951676) (xy 130.183051 -412.951277) (xy 130.129094 -412.943521)
			(xy 130.076791 -412.928164) (xy 130.027206 -412.90552) (xy 129.981349 -412.876049) (xy 129.940152 -412.840353)
			(xy 129.904454 -412.799156) (xy 129.874983 -412.753299) (xy 129.852338 -412.703714) (xy 129.836981 -412.651411)
			(xy 129.829223 -412.597455) (xy 128.391713 -412.597455) (xy 128.383955 -412.651402) (xy 128.368599 -412.703698)
			(xy 128.345956 -412.753276) (xy 128.316487 -412.799127) (xy 128.280793 -412.840317) (xy 128.2396 -412.876008)
			(xy 128.193746 -412.905472) (xy 128.144166 -412.928111) (xy 128.091868 -412.943463) (xy 128.037918 -412.951215)
			(xy 128.010666 -412.951676) (xy 127.147066 -412.951676) (xy 127.119814 -412.951252) (xy 127.065865 -412.943491)
			(xy 127.01357 -412.928131) (xy 126.963993 -412.905486) (xy 126.918143 -412.876017) (xy 126.876954 -412.840322)
			(xy 126.841263 -412.799129) (xy 126.811797 -412.753277) (xy 126.789157 -412.703698) (xy 126.773802 -412.651401)
			(xy 126.766046 -412.597452) (xy 125.328389 -412.597452) (xy 125.320635 -412.651389) (xy 125.305282 -412.703677)
			(xy 125.282645 -412.753248) (xy 125.253184 -412.799093) (xy 125.217498 -412.840279) (xy 125.176314 -412.875968)
			(xy 125.130471 -412.905432) (xy 125.080901 -412.928073) (xy 125.028614 -412.943429) (xy 124.974674 -412.951188)
			(xy 124.947426 -412.951676) (xy 124.083826 -412.951676) (xy 124.05657 -412.951279) (xy 124.002611 -412.943524)
			(xy 123.950306 -412.928169) (xy 123.900718 -412.905526) (xy 123.854858 -412.876056) (xy 123.813659 -412.84036)
			(xy 123.777959 -412.799163) (xy 123.748486 -412.753305) (xy 123.72584 -412.703719) (xy 123.710481 -412.651414)
			(xy 123.702723 -412.597456) (xy 122.265212 -412.597456) (xy 122.257456 -412.651399) (xy 122.242101 -412.703693)
			(xy 122.219459 -412.75327) (xy 122.189992 -412.79912) (xy 122.1543 -412.84031) (xy 122.113109 -412.876001)
			(xy 122.067258 -412.905466) (xy 122.01768 -412.928105) (xy 121.965385 -412.943459) (xy 121.911437 -412.951214)
			(xy 121.884186 -412.951676) (xy 121.020586 -412.951676) (xy 120.993333 -412.951253) (xy 120.939382 -412.943494)
			(xy 120.887085 -412.928137) (xy 120.837505 -412.905493) (xy 120.791653 -412.876024) (xy 120.750461 -412.840329)
			(xy 120.714768 -412.799136) (xy 120.6853 -412.753282) (xy 120.662658 -412.703702) (xy 120.647303 -412.651404)
			(xy 120.639546 -412.597453) (xy 119.201889 -412.597453) (xy 119.194135 -412.651386) (xy 119.178784 -412.703673)
			(xy 119.156148 -412.753243) (xy 119.126688 -412.799087) (xy 119.091005 -412.840272) (xy 119.049824 -412.875961)
			(xy 119.003983 -412.905426) (xy 118.954416 -412.928068) (xy 118.902131 -412.943425) (xy 118.848193 -412.951187)
			(xy 118.820946 -412.951676) (xy 117.957346 -412.951676) (xy 117.930089 -412.95128) (xy 117.876128 -412.943528)
			(xy 117.82382 -412.928175) (xy 117.77423 -412.905533) (xy 117.728367 -412.876063) (xy 117.687166 -412.840367)
			(xy 117.651464 -412.799169) (xy 117.621989 -412.75331) (xy 117.599342 -412.703723) (xy 117.583982 -412.651417)
			(xy 117.576223 -412.597457) (xy 116.138689 -412.597457) (xy 116.130934 -412.651391) (xy 116.115581 -412.703681)
			(xy 116.092942 -412.753254) (xy 116.063479 -412.7991) (xy 116.027791 -412.840287) (xy 115.986605 -412.875975)
			(xy 115.940759 -412.905439) (xy 115.891187 -412.928079) (xy 115.838897 -412.943433) (xy 115.784955 -412.951189)
			(xy 115.757706 -412.951676) (xy 114.894106 -412.951676) (xy 114.866851 -412.951277) (xy 114.812894 -412.943521)
			(xy 114.760591 -412.928164) (xy 114.711006 -412.90552) (xy 114.665149 -412.876049) (xy 114.623952 -412.840353)
			(xy 114.588254 -412.799156) (xy 114.558783 -412.753299) (xy 114.536138 -412.703714) (xy 114.520781 -412.651411)
			(xy 114.513023 -412.597455) (xy 94.987413 -412.597455) (xy 94.979655 -412.651402) (xy 94.964299 -412.703698)
			(xy 94.941656 -412.753276) (xy 94.912187 -412.799127) (xy 94.876492 -412.840318) (xy 94.835299 -412.876008)
			(xy 94.789445 -412.905473) (xy 94.739864 -412.928111) (xy 94.687567 -412.943463) (xy 94.633616 -412.951215)
			(xy 94.606364 -412.951676) (xy 93.742764 -412.951676) (xy 93.715512 -412.951252) (xy 93.661564 -412.94349)
			(xy 93.609269 -412.928131) (xy 93.559692 -412.905486) (xy 93.513842 -412.876016) (xy 93.472653 -412.840321)
			(xy 93.436962 -412.799129) (xy 93.407497 -412.753276) (xy 93.384857 -412.703697) (xy 93.369502 -412.651401)
			(xy 93.361746 -412.597452) (xy 91.924089 -412.597452) (xy 91.916335 -412.651389) (xy 91.900982 -412.703677)
			(xy 91.878345 -412.753249) (xy 91.848883 -412.799094) (xy 91.813197 -412.84028) (xy 91.772013 -412.875969)
			(xy 91.72617 -412.905433) (xy 91.6766 -412.928074) (xy 91.624312 -412.94343) (xy 91.570372 -412.951188)
			(xy 91.543124 -412.951676) (xy 90.679524 -412.951676) (xy 90.652268 -412.951279) (xy 90.59831 -412.943524)
			(xy 90.546004 -412.928169) (xy 90.496417 -412.905526) (xy 90.450557 -412.876056) (xy 90.409358 -412.840359)
			(xy 90.373659 -412.799162) (xy 90.344186 -412.753304) (xy 90.32154 -412.703718) (xy 90.306181 -412.651414)
			(xy 90.298423 -412.597456) (xy 88.860912 -412.597456) (xy 88.853156 -412.651399) (xy 88.8378 -412.703694)
			(xy 88.815159 -412.753271) (xy 88.785692 -412.799121) (xy 88.749999 -412.840311) (xy 88.708808 -412.876001)
			(xy 88.662957 -412.905466) (xy 88.613379 -412.928106) (xy 88.561083 -412.943459) (xy 88.507135 -412.951214)
			(xy 88.479884 -412.951676) (xy 87.616284 -412.951676) (xy 87.589031 -412.951253) (xy 87.535081 -412.943494)
			(xy 87.482783 -412.928136) (xy 87.433204 -412.905492) (xy 87.387352 -412.876023) (xy 87.34616 -412.840329)
			(xy 87.310467 -412.799135) (xy 87.281 -412.753282) (xy 87.258358 -412.703702) (xy 87.243003 -412.651404)
			(xy 87.235246 -412.597453) (xy 85.797589 -412.597453) (xy 85.789835 -412.651386) (xy 85.774484 -412.703673)
			(xy 85.751848 -412.753243) (xy 85.722388 -412.799087) (xy 85.686704 -412.840273) (xy 85.645523 -412.875962)
			(xy 85.599682 -412.905427) (xy 85.550114 -412.928068) (xy 85.497829 -412.943426) (xy 85.443891 -412.951187)
			(xy 85.416644 -412.951676) (xy 84.553044 -412.951676) (xy 84.525787 -412.95128) (xy 84.471827 -412.943528)
			(xy 84.419519 -412.928174) (xy 84.369929 -412.905532) (xy 84.324067 -412.876063) (xy 84.282865 -412.840366)
			(xy 84.247164 -412.799169) (xy 84.217689 -412.75331) (xy 84.195041 -412.703722) (xy 84.179682 -412.651417)
			(xy 84.171923 -412.597457) (xy 82.734389 -412.597457) (xy 82.726634 -412.651392) (xy 82.71128 -412.703682)
			(xy 82.688642 -412.753254) (xy 82.659178 -412.799101) (xy 82.62349 -412.840287) (xy 82.582304 -412.875976)
			(xy 82.536458 -412.90544) (xy 82.486885 -412.928079) (xy 82.434595 -412.943433) (xy 82.380653 -412.95119)
			(xy 82.353404 -412.951676) (xy 81.489804 -412.951676) (xy 81.462549 -412.951277) (xy 81.408593 -412.94352)
			(xy 81.35629 -412.928163) (xy 81.306705 -412.905519) (xy 81.260848 -412.876049) (xy 81.219651 -412.840352)
			(xy 81.183954 -412.799156) (xy 81.154483 -412.753298) (xy 81.131838 -412.703714) (xy 81.116481 -412.651411)
			(xy 81.108723 -412.597455) (xy 79.671213 -412.597455) (xy 79.663455 -412.651402) (xy 79.648099 -412.703698)
			(xy 79.625456 -412.753276) (xy 79.595987 -412.799127) (xy 79.560292 -412.840318) (xy 79.519099 -412.876008)
			(xy 79.473245 -412.905473) (xy 79.423664 -412.928111) (xy 79.371367 -412.943463) (xy 79.317416 -412.951215)
			(xy 79.290164 -412.951676) (xy 78.426564 -412.951676) (xy 78.399312 -412.951252) (xy 78.345364 -412.94349)
			(xy 78.293069 -412.928131) (xy 78.243492 -412.905486) (xy 78.197642 -412.876016) (xy 78.156453 -412.840321)
			(xy 78.120762 -412.799129) (xy 78.091297 -412.753276) (xy 78.068657 -412.703697) (xy 78.053302 -412.651401)
			(xy 78.045546 -412.597452) (xy 76.607889 -412.597452) (xy 76.600135 -412.651389) (xy 76.584782 -412.703677)
			(xy 76.562145 -412.753249) (xy 76.532683 -412.799094) (xy 76.496997 -412.84028) (xy 76.455813 -412.875969)
			(xy 76.40997 -412.905433) (xy 76.3604 -412.928074) (xy 76.308112 -412.94343) (xy 76.254172 -412.951188)
			(xy 76.226924 -412.951676) (xy 75.363324 -412.951676) (xy 75.336068 -412.951279) (xy 75.28211 -412.943524)
			(xy 75.229804 -412.928169) (xy 75.180217 -412.905526) (xy 75.134357 -412.876056) (xy 75.093158 -412.840359)
			(xy 75.057459 -412.799162) (xy 75.027986 -412.753304) (xy 75.00534 -412.703718) (xy 74.989981 -412.651414)
			(xy 74.982223 -412.597456) (xy 73.544712 -412.597456) (xy 73.536956 -412.651399) (xy 73.5216 -412.703694)
			(xy 73.498959 -412.753271) (xy 73.469492 -412.799121) (xy 73.433799 -412.840311) (xy 73.392608 -412.876001)
			(xy 73.346757 -412.905466) (xy 73.297179 -412.928106) (xy 73.244883 -412.943459) (xy 73.190935 -412.951214)
			(xy 73.163684 -412.951676) (xy 72.300084 -412.951676) (xy 72.272831 -412.951253) (xy 72.218881 -412.943494)
			(xy 72.166583 -412.928136) (xy 72.117004 -412.905492) (xy 72.071152 -412.876023) (xy 72.02996 -412.840329)
			(xy 71.994267 -412.799135) (xy 71.9648 -412.753282) (xy 71.942158 -412.703702) (xy 71.926803 -412.651404)
			(xy 71.919046 -412.597453) (xy 70.481389 -412.597453) (xy 70.473635 -412.651386) (xy 70.458284 -412.703673)
			(xy 70.435648 -412.753243) (xy 70.406188 -412.799087) (xy 70.370504 -412.840273) (xy 70.329323 -412.875962)
			(xy 70.283482 -412.905427) (xy 70.233914 -412.928068) (xy 70.181629 -412.943426) (xy 70.127691 -412.951187)
			(xy 70.100444 -412.951676) (xy 69.236844 -412.951676) (xy 69.209587 -412.95128) (xy 69.155627 -412.943528)
			(xy 69.103319 -412.928174) (xy 69.053729 -412.905532) (xy 69.007867 -412.876063) (xy 68.966665 -412.840366)
			(xy 68.930964 -412.799169) (xy 68.901489 -412.75331) (xy 68.878841 -412.703722) (xy 68.863482 -412.651417)
			(xy 68.855723 -412.597457) (xy 67.418189 -412.597457) (xy 67.410434 -412.651392) (xy 67.39508 -412.703682)
			(xy 67.372442 -412.753254) (xy 67.342978 -412.799101) (xy 67.30729 -412.840287) (xy 67.266104 -412.875976)
			(xy 67.220258 -412.90544) (xy 67.170685 -412.928079) (xy 67.118395 -412.943433) (xy 67.064453 -412.95119)
			(xy 67.037204 -412.951676) (xy 66.173604 -412.951676) (xy 66.146349 -412.951277) (xy 66.092393 -412.94352)
			(xy 66.04009 -412.928163) (xy 65.990505 -412.905519) (xy 65.944648 -412.876049) (xy 65.903451 -412.840352)
			(xy 65.867754 -412.799156) (xy 65.838283 -412.753298) (xy 65.815638 -412.703714) (xy 65.800281 -412.651411)
			(xy 65.792523 -412.597455) (xy 64.355013 -412.597455) (xy 64.347255 -412.651402) (xy 64.331899 -412.703698)
			(xy 64.309256 -412.753276) (xy 64.279787 -412.799127) (xy 64.244092 -412.840318) (xy 64.202899 -412.876008)
			(xy 64.157045 -412.905473) (xy 64.107464 -412.928111) (xy 64.055167 -412.943463) (xy 64.001216 -412.951215)
			(xy 63.973964 -412.951676) (xy 63.110364 -412.951676) (xy 63.083112 -412.951252) (xy 63.029164 -412.94349)
			(xy 62.976869 -412.928131) (xy 62.927292 -412.905486) (xy 62.881442 -412.876016) (xy 62.840253 -412.840321)
			(xy 62.804562 -412.799129) (xy 62.775097 -412.753276) (xy 62.752457 -412.703697) (xy 62.737102 -412.651401)
			(xy 62.729346 -412.597452) (xy 61.291689 -412.597452) (xy 61.283935 -412.651389) (xy 61.268582 -412.703677)
			(xy 61.245945 -412.753249) (xy 61.216483 -412.799094) (xy 61.180797 -412.84028) (xy 61.139613 -412.875969)
			(xy 61.09377 -412.905433) (xy 61.0442 -412.928074) (xy 60.991912 -412.94343) (xy 60.937972 -412.951188)
			(xy 60.910724 -412.951676) (xy 60.047124 -412.951676) (xy 60.019868 -412.951279) (xy 59.96591 -412.943524)
			(xy 59.913604 -412.928169) (xy 59.864017 -412.905526) (xy 59.818157 -412.876056) (xy 59.776958 -412.840359)
			(xy 59.741259 -412.799162) (xy 59.711786 -412.753304) (xy 59.68914 -412.703718) (xy 59.673781 -412.651414)
			(xy 59.666023 -412.597456) (xy 58.228512 -412.597456) (xy 58.220756 -412.651399) (xy 58.2054 -412.703694)
			(xy 58.182759 -412.753271) (xy 58.153292 -412.799121) (xy 58.117599 -412.840311) (xy 58.076408 -412.876001)
			(xy 58.030557 -412.905466) (xy 57.980979 -412.928106) (xy 57.928683 -412.943459) (xy 57.874735 -412.951214)
			(xy 57.847484 -412.951676) (xy 56.983884 -412.951676) (xy 56.956631 -412.951253) (xy 56.902681 -412.943494)
			(xy 56.850383 -412.928136) (xy 56.800804 -412.905492) (xy 56.754952 -412.876023) (xy 56.71376 -412.840329)
			(xy 56.678067 -412.799135) (xy 56.6486 -412.753282) (xy 56.625958 -412.703702) (xy 56.610603 -412.651404)
			(xy 56.602846 -412.597453) (xy 55.165189 -412.597453) (xy 55.157435 -412.651386) (xy 55.142084 -412.703673)
			(xy 55.119448 -412.753243) (xy 55.089988 -412.799087) (xy 55.054304 -412.840273) (xy 55.013123 -412.875962)
			(xy 54.967282 -412.905427) (xy 54.917714 -412.928068) (xy 54.865429 -412.943426) (xy 54.811491 -412.951187)
			(xy 54.784244 -412.951676) (xy 53.920644 -412.951676) (xy 53.893387 -412.95128) (xy 53.839427 -412.943528)
			(xy 53.787119 -412.928174) (xy 53.737529 -412.905532) (xy 53.691667 -412.876063) (xy 53.650465 -412.840366)
			(xy 53.614764 -412.799169) (xy 53.585289 -412.75331) (xy 53.562641 -412.703722) (xy 53.547282 -412.651417)
			(xy 53.539523 -412.597457) (xy 52.101989 -412.597457) (xy 52.094234 -412.651392) (xy 52.07888 -412.703682)
			(xy 52.056242 -412.753254) (xy 52.026778 -412.799101) (xy 51.99109 -412.840287) (xy 51.949904 -412.875976)
			(xy 51.904058 -412.90544) (xy 51.854485 -412.928079) (xy 51.802195 -412.943433) (xy 51.748253 -412.95119)
			(xy 51.721004 -412.951676) (xy 50.857404 -412.951676) (xy 50.830149 -412.951277) (xy 50.776193 -412.94352)
			(xy 50.72389 -412.928163) (xy 50.674305 -412.905519) (xy 50.628448 -412.876049) (xy 50.587251 -412.840352)
			(xy 50.551554 -412.799156) (xy 50.522083 -412.753298) (xy 50.499438 -412.703714) (xy 50.484081 -412.651411)
			(xy 50.476323 -412.597455) (xy 49.038813 -412.597455) (xy 49.031055 -412.651402) (xy 49.015699 -412.703698)
			(xy 48.993056 -412.753276) (xy 48.963587 -412.799127) (xy 48.927892 -412.840318) (xy 48.886699 -412.876008)
			(xy 48.840845 -412.905473) (xy 48.791264 -412.928111) (xy 48.738967 -412.943463) (xy 48.685016 -412.951215)
			(xy 48.657764 -412.951676) (xy 47.794164 -412.951676) (xy 47.766912 -412.951252) (xy 47.712964 -412.94349)
			(xy 47.660669 -412.928131) (xy 47.611092 -412.905486) (xy 47.565242 -412.876016) (xy 47.524053 -412.840321)
			(xy 47.488362 -412.799129) (xy 47.458897 -412.753276) (xy 47.436257 -412.703697) (xy 47.420902 -412.651401)
			(xy 47.413146 -412.597452) (xy 40.731292 -412.597452) (xy 41.64457 -413.51073) (xy 41.651969 -413.517573)
			(xy 41.670568 -413.525293) (xy 41.680638 -413.525716) (xy 102.58425 -413.525716)
		)
		(stroke
			(width 0)
			(type solid)
		)
		(fill yes)
		(layer "In9.Cu")
		(net "P0V9_CPU1_RT_2D")
	)
	(gr_poly
		(pts
			(xy 58.120534 -440.465972) (xy 58.129457 -440.465412) (xy 58.146089 -440.458882) (xy 58.159474 -440.447046)
			(xy 58.167991 -440.431338) (xy 58.169556 -440.422538) (xy 58.169556 -440.422284) (xy 58.174454 -440.3911)
			(xy 58.191282 -440.330259) (xy 58.21586 -440.272116) (xy 58.247774 -440.217652) (xy 58.286483 -440.167789)
			(xy 58.331334 -440.123369) (xy 58.381569 -440.085143) (xy 58.436338 -440.053757) (xy 58.494716 -440.029741)
			(xy 58.555716 -440.013501) (xy 58.618308 -440.005312) (xy 58.681432 -440.005312) (xy 58.744024 -440.013501)
			(xy 58.805024 -440.029741) (xy 58.863402 -440.053757) (xy 58.918171 -440.085143) (xy 58.968406 -440.123369)
			(xy 59.013257 -440.167789) (xy 59.051966 -440.217652) (xy 59.08388 -440.272116) (xy 59.108458 -440.330259)
			(xy 59.125286 -440.3911) (xy 59.130184 -440.422284) (xy 59.130184 -440.422538) (xy 59.131813 -440.431328)
			(xy 59.140299 -440.44705) (xy 59.153663 -440.458907) (xy 59.170283 -440.465461) (xy 59.179206 -440.465972)
			(xy 62.119256 -440.465972) (xy 62.120526 -440.465972) (xy 62.129439 -440.465398) (xy 62.146044 -440.458851)
			(xy 62.159403 -440.447013) (xy 62.167901 -440.431316) (xy 62.169548 -440.422538) (xy 62.169548 -440.422284)
			(xy 62.174446 -440.3911) (xy 62.191274 -440.330259) (xy 62.215852 -440.272116) (xy 62.247766 -440.217652)
			(xy 62.286475 -440.167789) (xy 62.331326 -440.123369) (xy 62.381561 -440.085143) (xy 62.43633 -440.053757)
			(xy 62.494708 -440.029741) (xy 62.555708 -440.013501) (xy 62.6183 -440.005312) (xy 62.681424 -440.005312)
			(xy 62.744016 -440.013501) (xy 62.805016 -440.029741) (xy 62.863394 -440.053757) (xy 62.918163 -440.085143)
			(xy 62.968398 -440.123369) (xy 63.013249 -440.167789) (xy 63.051958 -440.217652) (xy 63.083872 -440.272116)
			(xy 63.10845 -440.330259) (xy 63.125278 -440.3911) (xy 63.130176 -440.422284) (xy 63.130176 -440.422538)
			(xy 63.131808 -440.431321) (xy 63.140298 -440.447026) (xy 63.153665 -440.458862) (xy 63.170283 -440.465387)
			(xy 63.179198 -440.465972) (xy 66.119248 -440.465972) (xy 66.120518 -440.465972) (xy 66.129432 -440.465399)
			(xy 66.146039 -440.458854) (xy 66.159401 -440.447016) (xy 66.1679 -440.431318) (xy 66.16954 -440.422538)
			(xy 66.16954 -440.422284) (xy 66.174438 -440.3911) (xy 66.191266 -440.330259) (xy 66.215844 -440.272116)
			(xy 66.247758 -440.217652) (xy 66.286467 -440.167789) (xy 66.331318 -440.123369) (xy 66.381553 -440.085143)
			(xy 66.436322 -440.053757) (xy 66.4947 -440.029741) (xy 66.5557 -440.013501) (xy 66.618292 -440.005312)
			(xy 66.681416 -440.005312) (xy 66.744008 -440.013501) (xy 66.805008 -440.029741) (xy 66.863386 -440.053757)
			(xy 66.918155 -440.085143) (xy 66.96839 -440.123369) (xy 67.013241 -440.167789) (xy 67.05195 -440.217652)
			(xy 67.083864 -440.272116) (xy 67.108442 -440.330259) (xy 67.12527 -440.3911) (xy 67.130168 -440.422284)
			(xy 67.130168 -440.422538) (xy 67.131799 -440.431322) (xy 67.140289 -440.447028) (xy 67.153656 -440.458865)
			(xy 67.170274 -440.465393) (xy 67.17919 -440.465972) (xy 70.11924 -440.465972) (xy 70.12051 -440.465972)
			(xy 70.129425 -440.465401) (xy 70.146034 -440.458856) (xy 70.159398 -440.447019) (xy 70.167899 -440.43132)
			(xy 70.169532 -440.422538) (xy 70.169532 -440.422284) (xy 70.17443 -440.3911) (xy 70.191258 -440.330259)
			(xy 70.215836 -440.272116) (xy 70.24775 -440.217652) (xy 70.286459 -440.167789) (xy 70.33131 -440.123369)
			(xy 70.381545 -440.085143) (xy 70.436314 -440.053757) (xy 70.494692 -440.029741) (xy 70.555692 -440.013501)
			(xy 70.618284 -440.005312) (xy 70.681408 -440.005312) (xy 70.744 -440.013501) (xy 70.805 -440.029741)
			(xy 70.863378 -440.053757) (xy 70.918147 -440.085143) (xy 70.968382 -440.123369) (xy 71.013233 -440.167789)
			(xy 71.051942 -440.217652) (xy 71.083856 -440.272116) (xy 71.108434 -440.330259) (xy 71.125262 -440.3911)
			(xy 71.13016 -440.422284) (xy 71.13016 -440.422538) (xy 71.131791 -440.431322) (xy 71.140281 -440.44703)
			(xy 71.153647 -440.458869) (xy 71.170265 -440.4654) (xy 71.179182 -440.465972) (xy 75.119484 -440.465972)
			(xy 75.120754 -440.465972) (xy 75.129675 -440.465409) (xy 75.146301 -440.458875) (xy 75.159681 -440.447038)
			(xy 75.168193 -440.431333) (xy 75.169776 -440.422538) (xy 75.169776 -440.422284) (xy 75.174674 -440.3911)
			(xy 75.191502 -440.330259) (xy 75.21608 -440.272116) (xy 75.247994 -440.217652) (xy 75.286703 -440.167789)
			(xy 75.331554 -440.123369) (xy 75.381789 -440.085143) (xy 75.436558 -440.053757) (xy 75.494936 -440.029741)
			(xy 75.555936 -440.013501) (xy 75.618528 -440.005312) (xy 75.681652 -440.005312) (xy 75.744244 -440.013501)
			(xy 75.805244 -440.029741) (xy 75.863622 -440.053757) (xy 75.918391 -440.085143) (xy 75.968626 -440.123369)
			(xy 76.013477 -440.167789) (xy 76.052186 -440.217652) (xy 76.0841 -440.272116) (xy 76.108678 -440.330259)
			(xy 76.125506 -440.3911) (xy 76.130404 -440.422284) (xy 76.130404 -440.422538) (xy 76.132034 -440.431326)
			(xy 76.140521 -440.447045) (xy 76.153885 -440.458897) (xy 76.170505 -440.465445) (xy 76.179426 -440.465972)
			(xy 79.119476 -440.465972) (xy 79.120746 -440.465972) (xy 79.129668 -440.465411) (xy 79.146296 -440.458878)
			(xy 79.159678 -440.447041) (xy 79.168193 -440.431335) (xy 79.169768 -440.422538) (xy 79.169768 -440.422284)
			(xy 79.174666 -440.3911) (xy 79.191494 -440.330259) (xy 79.216072 -440.272116) (xy 79.247986 -440.217652)
			(xy 79.286695 -440.167789) (xy 79.331546 -440.123369) (xy 79.381781 -440.085143) (xy 79.43655 -440.053757)
			(xy 79.494928 -440.029741) (xy 79.555928 -440.013501) (xy 79.61852 -440.005312) (xy 79.681644 -440.005312)
			(xy 79.744236 -440.013501) (xy 79.805236 -440.029741) (xy 79.863614 -440.053757) (xy 79.918383 -440.085143)
			(xy 79.968618 -440.123369) (xy 80.013469 -440.167789) (xy 80.052178 -440.217652) (xy 80.084092 -440.272116)
			(xy 80.10867 -440.330259) (xy 80.125498 -440.3911) (xy 80.130396 -440.422284) (xy 80.130396 -440.422538)
			(xy 80.132025 -440.431327) (xy 80.140512 -440.447047) (xy 80.153876 -440.458901) (xy 80.170496 -440.465451)
			(xy 80.179418 -440.465972) (xy 83.119468 -440.465972) (xy 83.120738 -440.465972) (xy 83.129661 -440.465412)
			(xy 83.146291 -440.458881) (xy 83.159676 -440.447044) (xy 83.168192 -440.431337) (xy 83.16976 -440.422538)
			(xy 83.16976 -440.422284) (xy 83.174658 -440.3911) (xy 83.191486 -440.330259) (xy 83.216064 -440.272116)
			(xy 83.247978 -440.217652) (xy 83.286687 -440.167789) (xy 83.331538 -440.123369) (xy 83.381773 -440.085143)
			(xy 83.436542 -440.053757) (xy 83.49492 -440.029741) (xy 83.55592 -440.013501) (xy 83.618512 -440.005312)
			(xy 83.681636 -440.005312) (xy 83.744228 -440.013501) (xy 83.805228 -440.029741) (xy 83.863606 -440.053757)
			(xy 83.918375 -440.085143) (xy 83.96861 -440.123369) (xy 84.013461 -440.167789) (xy 84.05217 -440.217652)
			(xy 84.084084 -440.272116) (xy 84.108662 -440.330259) (xy 84.12549 -440.3911) (xy 84.130388 -440.422284)
			(xy 84.130388 -440.422538) (xy 84.132017 -440.431328) (xy 84.140503 -440.447049) (xy 84.153867 -440.458905)
			(xy 84.170488 -440.465458) (xy 84.17941 -440.465972) (xy 87.11946 -440.465972) (xy 87.12073 -440.465972)
			(xy 87.129654 -440.465413) (xy 87.146287 -440.458883) (xy 87.159673 -440.447047) (xy 87.168191 -440.431339)
			(xy 87.169752 -440.422538) (xy 87.169752 -440.422284) (xy 87.17465 -440.3911) (xy 87.191478 -440.330259)
			(xy 87.216056 -440.272116) (xy 87.24797 -440.217652) (xy 87.286679 -440.167789) (xy 87.33153 -440.123369)
			(xy 87.381765 -440.085143) (xy 87.436534 -440.053757) (xy 87.494912 -440.029741) (xy 87.555912 -440.013501)
			(xy 87.618504 -440.005312) (xy 87.681628 -440.005312) (xy 87.74422 -440.013501) (xy 87.80522 -440.029741)
			(xy 87.863598 -440.053757) (xy 87.918367 -440.085143) (xy 87.968602 -440.123369) (xy 88.013453 -440.167789)
			(xy 88.052162 -440.217652) (xy 88.084076 -440.272116) (xy 88.108654 -440.330259) (xy 88.125482 -440.3911)
			(xy 88.13038 -440.422284) (xy 88.13038 -440.422538) (xy 88.132012 -440.431321) (xy 88.140502 -440.447025)
			(xy 88.153869 -440.45886) (xy 88.170487 -440.465384) (xy 88.179402 -440.465972) (xy 98.017076 -440.465972)
			(xy 98.028369 -440.465371) (xy 98.048772 -440.455686) (xy 98.063042 -440.43818) (xy 98.066352 -440.427364)
			(xy 98.089974 -440.331352) (xy 98.092091 -440.320238) (xy 98.08758 -440.298097) (xy 98.074025 -440.280019)
			(xy 98.06432 -440.274202) (xy 98.064066 -440.274202) (xy 97.973298 -440.226317) (xy 97.795135 -440.124417)
			(xy 97.621073 -440.015658) (xy 97.451376 -439.900207) (xy 97.286302 -439.778237) (xy 97.126101 -439.649935)
			(xy 96.971015 -439.515494) (xy 96.82128 -439.375118) (xy 96.677123 -439.229021) (xy 96.538762 -439.077422)
			(xy 96.406406 -438.920553) (xy 96.280257 -438.758651) (xy 96.160505 -438.591961) (xy 96.047333 -438.420736)
			(xy 95.940911 -438.245236) (xy 95.841402 -438.065726) (xy 95.748955 -437.882479) (xy 95.663711 -437.695772)
			(xy 95.585799 -437.505889) (xy 95.515338 -437.313116) (xy 95.452433 -437.117748) (xy 95.397181 -436.920078)
			(xy 95.349665 -436.720408) (xy 95.309958 -436.51904) (xy 95.278118 -436.316278) (xy 95.254196 -436.112431)
			(xy 95.238226 -435.907807) (xy 95.230233 -435.702717) (xy 95.22968 -435.600094) (xy 95.230176 -435.497873)
			(xy 95.238103 -435.293583) (xy 95.253946 -435.089755) (xy 95.27768 -434.886695) (xy 95.30927 -434.684707)
			(xy 95.348669 -434.484096) (xy 95.395817 -434.285164) (xy 95.450643 -434.08821) (xy 95.513065 -433.893529)
			(xy 95.582988 -433.701416) (xy 95.660309 -433.512158) (xy 95.744909 -433.326041) (xy 95.836663 -433.143344)
			(xy 95.935432 -432.964342) (xy 96.041068 -432.789305) (xy 96.153411 -432.618495) (xy 96.272293 -432.45217)
			(xy 96.397535 -432.29058) (xy 96.528948 -432.133968) (xy 96.666335 -431.982569) (xy 96.80949 -431.836611)
			(xy 96.958196 -431.696314) (xy 97.112231 -431.561888) (xy 97.271362 -431.433536) (xy 97.435351 -431.311451)
			(xy 97.603949 -431.195817) (xy 97.776905 -431.086807) (xy 97.953958 -430.984586) (xy 98.134842 -430.889306)
			(xy 98.319283 -430.801113) (xy 98.507006 -430.720137) (xy 98.697728 -430.646501) (xy 98.891161 -430.580316)
			(xy 99.087015 -430.521681) (xy 99.284996 -430.470685) (xy 99.484805 -430.427403) (xy 99.686142 -430.391902)
			(xy 99.888704 -430.364235) (xy 100.092186 -430.344442) (xy 100.296283 -430.332555) (xy 100.500688 -430.328591)
			(xy 100.705093 -430.332555) (xy 100.90919 -430.344442) (xy 101.112672 -430.364235) (xy 101.315234 -430.391902)
			(xy 101.516571 -430.427403) (xy 101.71638 -430.470685) (xy 101.914361 -430.521681) (xy 102.110215 -430.580316)
			(xy 102.303648 -430.646501) (xy 102.49437 -430.720137) (xy 102.682093 -430.801113) (xy 102.866534 -430.889306)
			(xy 103.047418 -430.984586) (xy 103.224471 -431.086807) (xy 103.397427 -431.195817) (xy 103.566025 -431.311451)
			(xy 103.631334 -431.360072) (xy 108.13796 -431.360072) (xy 108.138464 -431.271581) (xy 108.146519 -431.094782)
			(xy 108.162613 -430.918533) (xy 108.186712 -430.743199) (xy 108.218766 -430.569144) (xy 108.25871 -430.396728)
			(xy 108.306459 -430.226308) (xy 108.361915 -430.058239) (xy 108.424964 -429.892868) (xy 108.495474 -429.730538)
			(xy 108.573299 -429.571585) (xy 108.658278 -429.416339) (xy 108.750235 -429.265122) (xy 108.84898 -429.118247)
			(xy 108.954307 -428.976019) (xy 109.065998 -428.838732) (xy 109.183822 -428.70667) (xy 109.307535 -428.580108)
			(xy 109.43688 -428.459309) (xy 109.571589 -428.344521) (xy 109.711383 -428.235984) (xy 109.855973 -428.133922)
			(xy 110.005057 -428.038546) (xy 110.158328 -427.950055) (xy 110.315468 -427.868632) (xy 110.476152 -427.794445)
			(xy 110.640045 -427.727648) (xy 110.806808 -427.66838) (xy 110.976096 -427.616764) (xy 111.147558 -427.572907)
			(xy 111.320839 -427.536899) (xy 111.495579 -427.508815) (xy 111.671416 -427.488713) (xy 111.847986 -427.476635)
			(xy 112.024922 -427.472607) (xy 112.201858 -427.476635) (xy 112.378428 -427.488713) (xy 112.554265 -427.508815)
			(xy 112.729005 -427.536899) (xy 112.902286 -427.572907) (xy 113.073748 -427.616764) (xy 113.243036 -427.66838)
			(xy 113.409799 -427.727648) (xy 113.573692 -427.794445) (xy 113.734376 -427.868632) (xy 113.891516 -427.950055)
			(xy 113.90967 -427.960536) (xy 125.241304 -427.960536) (xy 125.241304 -425.419012) (xy 125.241723 -425.406929)
			(xy 125.249189 -425.383944) (xy 125.263393 -425.364393) (xy 125.282944 -425.350189) (xy 125.305929 -425.342723)
			(xy 125.318012 -425.342304) (xy 126.257812 -425.342304) (xy 126.269888 -425.342754) (xy 126.292858 -425.350222)
			(xy 126.312396 -425.364421) (xy 126.326589 -425.383964) (xy 126.334049 -425.406935) (xy 126.33452 -425.419012)
			(xy 126.33452 -427.960536) (xy 126.334067 -427.972611) (xy 126.326596 -427.995578) (xy 126.312396 -428.015113)
			(xy 126.292856 -428.029307) (xy 126.269887 -428.036771) (xy 126.257812 -428.037244) (xy 125.318012 -428.037244)
			(xy 125.305942 -428.036726) (xy 125.282981 -428.029271) (xy 125.263447 -428.015087) (xy 125.249251 -427.995562)
			(xy 125.241781 -427.972606) (xy 125.241304 -427.960536) (xy 113.90967 -427.960536) (xy 114.044787 -428.038546)
			(xy 114.193871 -428.133922) (xy 114.338461 -428.235984) (xy 114.478255 -428.344521) (xy 114.612964 -428.459309)
			(xy 114.742309 -428.580108) (xy 114.866022 -428.70667) (xy 114.983846 -428.838732) (xy 115.095537 -428.976019)
			(xy 115.200864 -429.118247) (xy 115.299609 -429.265122) (xy 115.391566 -429.416339) (xy 115.476545 -429.571585)
			(xy 115.55437 -429.730538) (xy 115.62488 -429.892868) (xy 115.687929 -430.058239) (xy 115.743385 -430.226308)
			(xy 115.791134 -430.396728) (xy 115.831078 -430.569144) (xy 115.863132 -430.743199) (xy 115.887231 -430.918533)
			(xy 115.903325 -431.094782) (xy 115.91138 -431.271581) (xy 115.911884 -431.360072) (xy 115.911414 -431.447087)
			(xy 115.906335 -431.560478) (xy 125.241304 -431.560478) (xy 125.241304 -429.018954) (xy 125.241767 -429.006866)
			(xy 125.249232 -428.98387) (xy 125.263421 -428.964293) (xy 125.282953 -428.950043) (xy 125.305925 -428.942506)
			(xy 125.318012 -428.941992) (xy 126.257812 -428.941992) (xy 126.269921 -428.942406) (xy 126.292947 -428.949908)
			(xy 126.307529 -428.960534) (xy 127.2413 -428.960534) (xy 127.2413 -426.41901) (xy 127.241815 -426.406925)
			(xy 127.249264 -426.383931) (xy 127.26344 -426.364355) (xy 127.282961 -426.350103) (xy 127.305925 -426.342563)
			(xy 127.318008 -426.342048) (xy 128.257808 -426.342048) (xy 128.269912 -426.342509) (xy 128.292931 -426.350004)
			(xy 128.312499 -426.364256) (xy 128.326696 -426.383865) (xy 128.334125 -426.406905) (xy 128.334516 -426.41901)
			(xy 128.334516 -427.960536) (xy 129.241296 -427.960536) (xy 129.241296 -425.419012) (xy 129.241723 -425.40693)
			(xy 129.249188 -425.383947) (xy 129.26339 -425.364396) (xy 129.282939 -425.350191) (xy 129.305922 -425.342724)
			(xy 129.318004 -425.342304) (xy 130.257804 -425.342304) (xy 130.269888 -425.342709) (xy 130.292873 -425.350179)
			(xy 130.312424 -425.364387) (xy 130.326628 -425.383941) (xy 130.334093 -425.406928) (xy 130.334512 -425.419012)
			(xy 130.334512 -427.960536) (xy 130.334067 -427.972612) (xy 130.326595 -427.99558) (xy 130.312393 -428.015116)
			(xy 130.292851 -428.029309) (xy 130.26988 -428.036772) (xy 130.257804 -428.037244) (xy 129.318004 -428.037244)
			(xy 129.305933 -428.036733) (xy 129.282972 -428.029276) (xy 129.263438 -428.01509) (xy 129.249242 -427.995564)
			(xy 129.241773 -427.972607) (xy 129.241296 -427.960536) (xy 128.334516 -427.960536) (xy 128.334516 -428.960534)
			(xy 128.334121 -428.97263) (xy 128.326649 -428.995639) (xy 128.312446 -429.015222) (xy 128.292895 -429.02947)
			(xy 128.269903 -429.036993) (xy 128.257808 -429.037496) (xy 127.318008 -429.037496) (xy 127.305899 -429.037077)
			(xy 127.282871 -429.029579) (xy 127.263298 -429.015319) (xy 127.249103 -428.995697) (xy 127.241683 -428.972644)
			(xy 127.2413 -428.960534) (xy 126.307529 -428.960534) (xy 126.312519 -428.96417) (xy 126.326714 -428.983792)
			(xy 126.334136 -429.006844) (xy 126.33452 -429.018954) (xy 126.33452 -431.560478) (xy 126.334073 -431.57257)
			(xy 126.326618 -431.595577) (xy 126.312427 -431.615161) (xy 126.292887 -431.629411) (xy 126.269903 -431.636936)
			(xy 126.257812 -431.63744) (xy 125.318012 -431.63744) (xy 125.305908 -431.636974) (xy 125.282888 -431.629483)
			(xy 125.263318 -431.615232) (xy 125.249122 -431.595624) (xy 125.241693 -431.572583) (xy 125.241304 -431.560478)
			(xy 115.906335 -431.560478) (xy 115.903626 -431.620942) (xy 115.888064 -431.794275) (xy 115.86476 -431.966737)
			(xy 115.83376 -432.137984) (xy 115.795126 -432.307671) (xy 115.748935 -432.475459) (xy 115.695281 -432.641011)
			(xy 115.634271 -432.803996) (xy 115.566027 -432.964087) (xy 115.490686 -433.120963) (xy 115.408398 -433.27431)
			(xy 115.31933 -433.423819) (xy 115.223659 -433.569193) (xy 115.121577 -433.710138) (xy 115.013289 -433.846373)
			(xy 114.899011 -433.977625) (xy 114.778974 -434.10363) (xy 114.653417 -434.224137) (xy 114.522592 -434.338902)
			(xy 114.386761 -434.447698) (xy 114.246197 -434.550304) (xy 114.101181 -434.646516) (xy 113.952004 -434.736141)
			(xy 113.798966 -434.818999) (xy 113.72088 -434.857398) (xy 113.710212 -434.862478) (xy 113.695734 -434.881274)
			(xy 113.674906 -434.984398) (xy 113.681256 -435.007258) (xy 113.68913 -435.016148) (xy 113.733262 -435.066761)
			(xy 113.806634 -435.16042) (xy 125.241304 -435.16042) (xy 125.241304 -432.618896) (xy 125.241709 -432.606812)
			(xy 125.249179 -432.583827) (xy 125.263387 -432.564276) (xy 125.282941 -432.550072) (xy 125.305928 -432.542607)
			(xy 125.318012 -432.542188) (xy 126.257812 -432.542188) (xy 126.269887 -432.542654) (xy 126.292854 -432.550119)
			(xy 126.307106 -432.560476) (xy 127.2413 -432.560476) (xy 127.2413 -430.018952) (xy 127.241723 -430.006874)
			(xy 127.2492 -429.983904) (xy 127.263407 -429.964367) (xy 127.282954 -429.950174) (xy 127.30593 -429.942714)
			(xy 127.318008 -429.942244) (xy 128.257808 -429.942244) (xy 128.269878 -429.942757) (xy 128.292837 -429.950216)
			(xy 128.31237 -429.964401) (xy 128.326566 -429.983927) (xy 128.334037 -430.006882) (xy 128.334516 -430.018952)
			(xy 128.334516 -431.560478) (xy 129.241296 -431.560478) (xy 129.241296 -429.018954) (xy 129.241767 -429.006866)
			(xy 129.249231 -428.983872) (xy 129.263418 -428.964296) (xy 129.282948 -428.950046) (xy 129.305918 -428.942507)
			(xy 129.318004 -428.941992) (xy 130.257804 -428.941992) (xy 130.269912 -428.942413) (xy 130.292938 -428.949912)
			(xy 130.307517 -428.960534) (xy 131.241292 -428.960534) (xy 131.241292 -426.41901) (xy 131.241815 -426.406926)
			(xy 131.249263 -426.383934) (xy 131.263437 -426.364358) (xy 131.282956 -426.350105) (xy 131.305918 -426.342564)
			(xy 131.318 -426.342048) (xy 132.2578 -426.342048) (xy 132.269904 -426.342515) (xy 132.292922 -426.350009)
			(xy 132.312491 -426.364259) (xy 132.326687 -426.383866) (xy 132.334117 -426.406905) (xy 132.334508 -426.41901)
			(xy 132.334508 -427.960536) (xy 133.241288 -427.960536) (xy 133.241288 -425.419012) (xy 133.241723 -425.40693)
			(xy 133.249187 -425.383949) (xy 133.263387 -425.364399) (xy 133.282934 -425.350194) (xy 133.305914 -425.342726)
			(xy 133.317996 -425.342304) (xy 134.257796 -425.342304) (xy 134.26988 -425.342716) (xy 134.292864 -425.350184)
			(xy 134.312416 -425.36439) (xy 134.32662 -425.383943) (xy 134.334085 -425.406928) (xy 134.334504 -425.419012)
			(xy 134.334504 -427.960536) (xy 134.334067 -427.972613) (xy 134.326594 -427.995582) (xy 134.31239 -428.015119)
			(xy 134.292846 -428.029312) (xy 134.269873 -428.036773) (xy 134.257796 -428.037244) (xy 133.317996 -428.037244)
			(xy 133.305925 -428.03674) (xy 133.282964 -428.02928) (xy 133.26343 -428.015093) (xy 133.249234 -427.995565)
			(xy 133.241765 -427.972607) (xy 133.241288 -427.960536) (xy 132.334508 -427.960536) (xy 132.334508 -428.960534)
			(xy 132.334023 -428.972621) (xy 132.326562 -428.995614) (xy 132.312379 -429.01519) (xy 132.292853 -429.029441)
			(xy 132.269885 -429.03698) (xy 132.2578 -429.037496) (xy 131.318 -429.037496) (xy 131.305891 -429.037084)
			(xy 131.282863 -429.029584) (xy 131.263289 -429.015321) (xy 131.249095 -428.995699) (xy 131.241675 -428.972645)
			(xy 131.241292 -428.960534) (xy 130.307517 -428.960534) (xy 130.312511 -428.964173) (xy 130.326706 -428.983793)
			(xy 130.334128 -429.006844) (xy 130.334512 -429.018954) (xy 130.334512 -431.560478) (xy 130.334073 -431.572571)
			(xy 130.326616 -431.595579) (xy 130.312424 -431.615164) (xy 130.292882 -431.629413) (xy 130.269896 -431.636937)
			(xy 130.257804 -431.63744) (xy 129.318004 -431.63744) (xy 129.305899 -431.636981) (xy 129.282879 -431.629488)
			(xy 129.263309 -431.615236) (xy 129.249113 -431.595625) (xy 129.241685 -431.572584) (xy 129.241296 -431.560478)
			(xy 128.334516 -431.560478) (xy 128.334516 -432.560476) (xy 128.334067 -432.572557) (xy 128.326607 -432.595537)
			(xy 128.31241 -432.615087) (xy 128.292866 -432.629292) (xy 128.269888 -432.636762) (xy 128.257808 -432.637184)
			(xy 127.318008 -432.637184) (xy 127.305923 -432.63678) (xy 127.282937 -432.629312) (xy 127.263384 -432.615105)
			(xy 127.249181 -432.595549) (xy 127.241717 -432.572561) (xy 127.2413 -432.560476) (xy 126.307106 -432.560476)
			(xy 126.31239 -432.564316) (xy 126.326584 -432.583854) (xy 126.334047 -432.606821) (xy 126.33452 -432.618896)
			(xy 126.33452 -435.16042) (xy 126.334053 -435.172494) (xy 126.326586 -435.19546) (xy 126.31239 -435.214996)
			(xy 126.292853 -435.22919) (xy 126.269886 -435.236654) (xy 126.257812 -435.237128) (xy 125.318012 -435.237128)
			(xy 125.30594 -435.236626) (xy 125.282977 -435.229169) (xy 125.263441 -435.214982) (xy 125.249246 -435.195452)
			(xy 125.241779 -435.172492) (xy 125.241304 -435.16042) (xy 113.806634 -435.16042) (xy 113.816083 -435.172481)
			(xy 113.892372 -435.283007) (xy 113.96185 -435.397937) (xy 114.024263 -435.516852) (xy 114.079384 -435.639317)
			(xy 114.127013 -435.764886) (xy 114.166974 -435.893101) (xy 114.199124 -436.023494) (xy 114.223343 -436.155591)
			(xy 114.239544 -436.288908) (xy 114.247669 -436.422961) (xy 114.248184 -436.49011) (xy 114.247677 -436.557275)
			(xy 114.239566 -436.691359) (xy 114.223375 -436.824708) (xy 114.199161 -436.956837) (xy 114.167014 -437.087263)
			(xy 114.127051 -437.21551) (xy 114.079417 -437.34111) (xy 114.024287 -437.463604) (xy 113.961861 -437.582547)
			(xy 113.892367 -437.697503) (xy 113.81606 -437.808054) (xy 113.733216 -437.913796) (xy 113.64414 -438.014343)
			(xy 113.549155 -438.109328) (xy 113.448608 -438.198404) (xy 113.342866 -438.281248) (xy 113.232315 -438.357555)
			(xy 113.117359 -438.427049) (xy 112.998416 -438.489475) (xy 112.875922 -438.544605) (xy 112.750322 -438.592239)
			(xy 112.622075 -438.632202) (xy 112.491649 -438.664349) (xy 112.35952 -438.688563) (xy 112.226171 -438.704754)
			(xy 112.092087 -438.712865) (xy 111.957757 -438.712865) (xy 111.823673 -438.704754) (xy 111.690324 -438.688563)
			(xy 111.558195 -438.664349) (xy 111.427769 -438.632202) (xy 111.299522 -438.592239) (xy 111.173922 -438.544605)
			(xy 111.051428 -438.489475) (xy 110.932485 -438.427049) (xy 110.817529 -438.357555) (xy 110.706978 -438.281248)
			(xy 110.601236 -438.198404) (xy 110.500689 -438.109328) (xy 110.405704 -438.014343) (xy 110.316628 -437.913796)
			(xy 110.233784 -437.808054) (xy 110.157477 -437.697503) (xy 110.087983 -437.582547) (xy 110.025557 -437.463604)
			(xy 109.970427 -437.34111) (xy 109.922793 -437.21551) (xy 109.88283 -437.087263) (xy 109.850683 -436.956837)
			(xy 109.826469 -436.824708) (xy 109.810278 -436.691359) (xy 109.802167 -436.557275) (xy 109.80166 -436.49011)
			(xy 109.802144 -436.42296) (xy 109.810269 -436.288906) (xy 109.826471 -436.155587) (xy 109.850691 -436.023489)
			(xy 109.882841 -435.893094) (xy 109.922804 -435.764877) (xy 109.970434 -435.639307) (xy 110.025557 -435.516841)
			(xy 110.087972 -435.397926) (xy 110.157452 -435.282995) (xy 110.233742 -435.172468) (xy 110.316566 -435.066748)
			(xy 110.360714 -435.016148) (xy 110.368588 -435.007258) (xy 110.374938 -434.984398) (xy 110.35411 -434.881274)
			(xy 110.339632 -434.862478) (xy 110.328964 -434.857398) (xy 110.250887 -434.818983) (xy 110.097852 -434.736122)
			(xy 109.948678 -434.646495) (xy 109.803665 -434.550281) (xy 109.663104 -434.447673) (xy 109.527276 -434.338877)
			(xy 109.396454 -434.22411) (xy 109.270899 -434.103604) (xy 109.150864 -433.977598) (xy 109.036588 -433.846347)
			(xy 108.928302 -433.710112) (xy 108.826221 -433.569168) (xy 108.730551 -433.423796) (xy 108.641483 -433.274288)
			(xy 108.559196 -433.120943) (xy 108.483855 -432.964069) (xy 108.41561 -432.80398) (xy 108.354599 -432.640997)
			(xy 108.300943 -432.475446) (xy 108.254751 -432.30766) (xy 108.216115 -432.137975) (xy 108.185111 -431.966731)
			(xy 108.161804 -431.79427) (xy 108.146238 -431.62094) (xy 108.138446 -431.447086) (xy 108.13796 -431.360072)
			(xy 103.631334 -431.360072) (xy 103.730014 -431.433536) (xy 103.889145 -431.561888) (xy 104.04318 -431.696314)
			(xy 104.191886 -431.836611) (xy 104.335041 -431.982569) (xy 104.472428 -432.133968) (xy 104.603841 -432.29058)
			(xy 104.729083 -432.45217) (xy 104.847965 -432.618495) (xy 104.960308 -432.789305) (xy 105.065944 -432.964342)
			(xy 105.164713 -433.143344) (xy 105.256467 -433.326041) (xy 105.341067 -433.512158) (xy 105.418388 -433.701416)
			(xy 105.488311 -433.893529) (xy 105.550733 -434.08821) (xy 105.605559 -434.285164) (xy 105.652707 -434.484096)
			(xy 105.692106 -434.684707) (xy 105.723696 -434.886695) (xy 105.74743 -435.089755) (xy 105.763273 -435.293583)
			(xy 105.7712 -435.497873) (xy 105.771696 -435.600094) (xy 105.7712 -435.702718) (xy 105.763212 -435.907811)
			(xy 105.747246 -436.112437) (xy 105.723327 -436.316287) (xy 105.69149 -436.519051) (xy 105.651785 -436.720423)
			(xy 105.604271 -436.920096) (xy 105.54902 -437.117768) (xy 105.486116 -437.313139) (xy 105.415654 -437.505914)
			(xy 105.337742 -437.695799) (xy 105.252497 -437.882508) (xy 105.160048 -438.065757) (xy 105.060536 -438.245268)
			(xy 104.954112 -438.420769) (xy 104.840936 -438.591994) (xy 104.721181 -438.758684) (xy 104.719676 -438.760616)
			(xy 125.241304 -438.760616) (xy 125.241304 -436.219092) (xy 125.241706 -436.207008) (xy 125.249177 -436.184023)
			(xy 125.263386 -436.164471) (xy 125.282941 -436.150268) (xy 125.305928 -436.142803) (xy 125.318012 -436.142384)
			(xy 126.257812 -436.142384) (xy 126.269886 -436.142854) (xy 126.292853 -436.150319) (xy 126.306752 -436.160418)
			(xy 127.2413 -436.160418) (xy 127.2413 -433.618894) (xy 127.241802 -433.606808) (xy 127.249255 -433.583814)
			(xy 127.263434 -433.564238) (xy 127.282958 -433.549986) (xy 127.305924 -433.542447) (xy 127.318008 -433.541932)
			(xy 128.257808 -433.541932) (xy 128.269921 -433.54231) (xy 128.292954 -433.549815) (xy 128.312529 -433.564086)
			(xy 128.326723 -433.583717) (xy 128.334137 -433.60678) (xy 128.334516 -433.618894) (xy 128.334516 -435.16042)
			(xy 129.241296 -435.16042) (xy 129.241296 -432.618896) (xy 129.241761 -432.606821) (xy 129.249225 -432.583853)
			(xy 129.263421 -432.564316) (xy 129.28296 -432.550121) (xy 129.305929 -432.54266) (xy 129.318004 -432.542188)
			(xy 130.257804 -432.542188) (xy 130.269878 -432.542661) (xy 130.292845 -432.550124) (xy 130.307094 -432.560476)
			(xy 131.241292 -432.560476) (xy 131.241292 -430.018952) (xy 131.241723 -430.006875) (xy 131.249199 -429.983906)
			(xy 131.263404 -429.96437) (xy 131.282949 -429.950177) (xy 131.305923 -429.942716) (xy 131.318 -429.942244)
			(xy 132.2578 -429.942244) (xy 132.26987 -429.942764) (xy 132.292829 -429.95022) (xy 132.312362 -429.964404)
			(xy 132.326558 -429.983928) (xy 132.334029 -430.006883) (xy 132.334508 -430.018952) (xy 132.334508 -431.560478)
			(xy 133.241288 -431.560478) (xy 133.241288 -429.018954) (xy 133.241669 -429.006857) (xy 133.249144 -428.983847)
			(xy 133.263351 -428.964264) (xy 133.282905 -428.950016) (xy 133.3059 -428.942494) (xy 133.317996 -428.941992)
			(xy 134.257796 -428.941992) (xy 134.269904 -428.942419) (xy 134.29293 -428.949917) (xy 134.307503 -428.960534)
			(xy 135.241284 -428.960534) (xy 135.241284 -426.41901) (xy 135.241717 -426.406917) (xy 135.249176 -426.383909)
			(xy 135.26337 -426.364325) (xy 135.282914 -426.350076) (xy 135.3059 -426.342551) (xy 135.317992 -426.342048)
			(xy 136.257792 -426.342048) (xy 136.269895 -426.342522) (xy 136.292914 -426.350013) (xy 136.312482 -426.364262)
			(xy 136.326679 -426.383868) (xy 136.334109 -426.406906) (xy 136.3345 -426.41901) (xy 136.3345 -427.960536)
			(xy 137.24128 -427.960536) (xy 137.24128 -425.419012) (xy 137.241774 -425.406939) (xy 137.249232 -425.383974)
			(xy 137.263421 -425.364438) (xy 137.282953 -425.350243) (xy 137.305915 -425.342778) (xy 137.317988 -425.342304)
			(xy 138.257788 -425.342304) (xy 138.269871 -425.342723) (xy 138.292856 -425.350189) (xy 138.312407 -425.364393)
			(xy 138.326611 -425.383944) (xy 138.334077 -425.406929) (xy 138.334496 -425.419012) (xy 138.334496 -427.960536)
			(xy 138.334066 -427.972614) (xy 138.326593 -427.995584) (xy 138.312387 -428.015122) (xy 138.292841 -428.029315)
			(xy 138.269866 -428.036774) (xy 138.257788 -428.037244) (xy 137.317988 -428.037244) (xy 137.305916 -428.036746)
			(xy 137.282955 -428.029285) (xy 137.263421 -428.015096) (xy 137.249226 -427.995567) (xy 137.241757 -427.972607)
			(xy 137.24128 -427.960536) (xy 136.3345 -427.960536) (xy 136.3345 -428.960534) (xy 136.334022 -428.972621)
			(xy 136.326561 -428.995616) (xy 136.312376 -429.015192) (xy 136.292848 -429.029443) (xy 136.269878 -429.036981)
			(xy 136.257792 -429.037496) (xy 135.317992 -429.037496) (xy 135.305882 -429.037091) (xy 135.282854 -429.029588)
			(xy 135.263281 -429.015324) (xy 135.249086 -428.9957) (xy 135.241667 -428.972645) (xy 135.241284 -428.960534)
			(xy 134.307503 -428.960534) (xy 134.312502 -428.964176) (xy 134.326697 -428.983795) (xy 134.33412 -429.006845)
			(xy 134.334504 -429.018954) (xy 134.334504 -431.560478) (xy 134.333975 -431.572562) (xy 134.326529 -431.595555)
			(xy 134.312357 -431.615131) (xy 134.29284 -431.629384) (xy 134.269878 -431.636924) (xy 134.257796 -431.63744)
			(xy 133.317996 -431.63744) (xy 133.305891 -431.636988) (xy 133.28287 -431.629492) (xy 133.263301 -431.615238)
			(xy 133.249105 -431.595627) (xy 133.241677 -431.572584) (xy 133.241288 -431.560478) (xy 132.334508 -431.560478)
			(xy 132.334508 -432.560476) (xy 132.334067 -432.572557) (xy 132.326606 -432.595539) (xy 132.312407 -432.61509)
			(xy 132.292861 -432.629295) (xy 132.269881 -432.636763) (xy 132.2578 -432.637184) (xy 131.318 -432.637184)
			(xy 131.305915 -432.636787) (xy 131.282928 -432.629317) (xy 131.263376 -432.615107) (xy 131.249172 -432.59555)
			(xy 131.241709 -432.572561) (xy 131.241292 -432.560476) (xy 130.307094 -432.560476) (xy 130.312382 -432.564318)
			(xy 130.326576 -432.583855) (xy 130.334039 -432.606822) (xy 130.334512 -432.618896) (xy 130.334512 -435.16042)
			(xy 130.334053 -435.172495) (xy 130.326585 -435.195462) (xy 130.312387 -435.214999) (xy 130.292848 -435.229193)
			(xy 130.269879 -435.236655) (xy 130.257804 -435.237128) (xy 129.318004 -435.237128) (xy 129.305932 -435.236633)
			(xy 129.282968 -435.229174) (xy 129.263433 -435.214984) (xy 129.249237 -435.195454) (xy 129.241771 -435.172492)
			(xy 129.241296 -435.16042) (xy 128.334516 -435.16042) (xy 128.334516 -436.160418) (xy 128.334107 -436.172513)
			(xy 128.32664 -436.195522) (xy 128.31244 -436.215105) (xy 128.292892 -436.229353) (xy 128.269902 -436.236877)
			(xy 128.257808 -436.23738) (xy 127.318008 -436.23738) (xy 127.305898 -436.236977) (xy 127.282867 -436.229477)
			(xy 127.263292 -436.215213) (xy 127.249098 -436.195587) (xy 127.24168 -436.17253) (xy 127.2413 -436.160418)
			(xy 126.306752 -436.160418) (xy 126.312389 -436.164514) (xy 126.326583 -436.184051) (xy 126.334047 -436.207018)
			(xy 126.33452 -436.219092) (xy 126.33452 -438.760616) (xy 126.334049 -438.77269) (xy 126.326584 -438.795656)
			(xy 126.312389 -438.815191) (xy 126.292852 -438.829386) (xy 126.269886 -438.83685) (xy 126.257812 -438.837324)
			(xy 125.318012 -438.837324) (xy 125.30594 -438.836826) (xy 125.282976 -438.829369) (xy 125.26344 -438.81518)
			(xy 125.249244 -438.79565) (xy 125.241779 -438.772688) (xy 125.241304 -438.760616) (xy 104.719676 -438.760616)
			(xy 104.595027 -438.920586) (xy 104.462667 -439.077455) (xy 104.324301 -439.229052) (xy 104.180138 -439.375147)
			(xy 104.030397 -439.515521) (xy 103.875306 -439.649958) (xy 103.73713 -439.760614) (xy 127.2413 -439.760614)
			(xy 127.2413 -437.21909) (xy 127.241798 -437.207004) (xy 127.249253 -437.18401) (xy 127.263433 -437.164434)
			(xy 127.282957 -437.150182) (xy 127.305924 -437.142643) (xy 127.318008 -437.142128) (xy 128.257808 -437.142128)
			(xy 128.26992 -437.14251) (xy 128.292952 -437.150015) (xy 128.312528 -437.164284) (xy 128.326721 -437.183915)
			(xy 128.334137 -437.206976) (xy 128.334516 -437.21909) (xy 128.334516 -438.760616) (xy 129.241296 -438.760616)
			(xy 129.241296 -436.219092) (xy 129.241758 -436.207017) (xy 129.249223 -436.184049) (xy 129.26342 -436.164511)
			(xy 129.282959 -436.150317) (xy 129.305929 -436.142856) (xy 129.318004 -436.142384) (xy 130.257804 -436.142384)
			(xy 130.269878 -436.142861) (xy 130.292844 -436.150323) (xy 130.306738 -436.160418) (xy 131.241292 -436.160418)
			(xy 131.241292 -433.618894) (xy 131.241802 -433.606809) (xy 131.249254 -433.583816) (xy 131.263431 -433.564241)
			(xy 131.282953 -433.549989) (xy 131.305917 -433.542448) (xy 131.318 -433.541932) (xy 132.2578 -433.541932)
			(xy 132.269912 -433.542317) (xy 132.292945 -433.54982) (xy 132.312521 -433.564088) (xy 132.326714 -433.583719)
			(xy 132.334129 -433.60678) (xy 132.334508 -433.618894) (xy 132.334508 -435.16042) (xy 133.241288 -435.16042)
			(xy 133.241288 -432.618896) (xy 133.241761 -432.606822) (xy 133.249224 -432.583855) (xy 133.263418 -432.564318)
			(xy 133.282955 -432.550124) (xy 133.305922 -432.542661) (xy 133.317996 -432.542188) (xy 134.257796 -432.542188)
			(xy 134.26987 -432.542668) (xy 134.292836 -432.550129) (xy 134.30708 -432.560476) (xy 135.241284 -432.560476)
			(xy 135.241284 -430.018952) (xy 135.241723 -430.006876) (xy 135.249198 -429.983908) (xy 135.263401 -429.964373)
			(xy 135.282944 -429.95018) (xy 135.305915 -429.942717) (xy 135.317992 -429.942244) (xy 136.257792 -429.942244)
			(xy 136.269861 -429.94277) (xy 136.29282 -429.950225) (xy 136.312353 -429.964407) (xy 136.32655 -429.98393)
			(xy 136.334021 -430.006883) (xy 136.3345 -430.018952) (xy 136.3345 -431.560478) (xy 137.24128 -431.560478)
			(xy 137.24128 -429.018954) (xy 137.241669 -429.006858) (xy 137.249143 -428.983849) (xy 137.263348 -428.964267)
			(xy 137.2829 -428.950019) (xy 137.305893 -428.942495) (xy 137.317988 -428.941992) (xy 138.257788 -428.941992)
			(xy 138.269895 -428.942427) (xy 138.292921 -428.949922) (xy 138.307489 -428.960534) (xy 139.241276 -428.960534)
			(xy 139.241276 -426.41901) (xy 139.241717 -426.406917) (xy 139.249175 -426.383911) (xy 139.263367 -426.364328)
			(xy 139.282909 -426.350078) (xy 139.305893 -426.342553) (xy 139.317984 -426.342048) (xy 140.257784 -426.342048)
			(xy 140.269887 -426.342529) (xy 140.292905 -426.350018) (xy 140.312473 -426.364265) (xy 140.32667 -426.383869)
			(xy 140.334101 -426.406906) (xy 140.334492 -426.41901) (xy 140.334492 -427.960536) (xy 142.241016 -427.960536)
			(xy 142.241016 -425.419012) (xy 142.24147 -425.406961) (xy 142.248902 -425.384033) (xy 142.263043 -425.364516)
			(xy 142.282516 -425.350313) (xy 142.30542 -425.342809) (xy 142.31747 -425.342304) (xy 143.257778 -425.342304)
			(xy 143.269863 -425.342825) (xy 143.292857 -425.350272) (xy 143.312434 -425.364446) (xy 143.326686 -425.383966)
			(xy 143.334225 -425.406929) (xy 143.33474 -425.419012) (xy 143.33474 -427.960536) (xy 143.334272 -427.972584)
			(xy 143.326834 -427.995504) (xy 143.312694 -428.015016) (xy 143.293228 -428.029219) (xy 143.270333 -428.036732)
			(xy 143.258286 -428.037244) (xy 142.317978 -428.037244) (xy 142.305886 -428.036811) (xy 142.282882 -428.029347)
			(xy 142.263301 -428.015152) (xy 142.249051 -427.99561) (xy 142.241523 -427.972627) (xy 142.241016 -427.960536)
			(xy 140.334492 -427.960536) (xy 140.334492 -428.960534) (xy 140.334022 -428.972622) (xy 140.32656 -428.995619)
			(xy 140.312373 -429.015195) (xy 140.292843 -429.029446) (xy 140.269871 -429.036983) (xy 140.257784 -429.037496)
			(xy 139.317984 -429.037496) (xy 139.305874 -429.037097) (xy 139.282845 -429.029593) (xy 139.263272 -429.015327)
			(xy 139.249078 -428.995702) (xy 139.241659 -428.972646) (xy 139.241276 -428.960534) (xy 138.307489 -428.960534)
			(xy 138.312493 -428.964179) (xy 138.326689 -428.983796) (xy 138.334111 -429.006845) (xy 138.334496 -429.018954)
			(xy 138.334496 -431.560478) (xy 138.333975 -431.572563) (xy 138.326528 -431.595557) (xy 138.312354 -431.615134)
			(xy 138.292834 -431.629386) (xy 138.269871 -431.636925) (xy 138.257788 -431.63744) (xy 137.317988 -431.63744)
			(xy 137.305882 -431.636995) (xy 137.282862 -431.629497) (xy 137.263292 -431.615241) (xy 137.249096 -431.595628)
			(xy 137.241669 -431.572585) (xy 137.24128 -431.560478) (xy 136.3345 -431.560478) (xy 136.3345 -432.560476)
			(xy 136.334067 -432.572558) (xy 136.326605 -432.595542) (xy 136.312404 -432.615093) (xy 136.292856 -432.629297)
			(xy 136.269874 -432.636764) (xy 136.257792 -432.637184) (xy 135.317992 -432.637184) (xy 135.305906 -432.636794)
			(xy 135.282919 -432.629321) (xy 135.263367 -432.61511) (xy 135.249164 -432.595552) (xy 135.241701 -432.572562)
			(xy 135.241284 -432.560476) (xy 134.30708 -432.560476) (xy 134.312373 -432.564321) (xy 134.326568 -432.583857)
			(xy 134.334031 -432.606822) (xy 134.334504 -432.618896) (xy 134.334504 -435.16042) (xy 134.334053 -435.172496)
			(xy 134.326584 -435.195464) (xy 134.312384 -435.215001) (xy 134.292843 -435.229195) (xy 134.269872 -435.236656)
			(xy 134.257796 -435.237128) (xy 133.317996 -435.237128) (xy 133.305923 -435.236639) (xy 133.282959 -435.229178)
			(xy 133.263424 -435.214987) (xy 133.249229 -435.195455) (xy 133.241763 -435.172493) (xy 133.241288 -435.16042)
			(xy 132.334508 -435.16042) (xy 132.334508 -436.160418) (xy 132.334009 -436.172504) (xy 132.326553 -436.195497)
			(xy 132.312373 -436.215072) (xy 132.29285 -436.229324) (xy 132.269884 -436.236864) (xy 132.2578 -436.23738)
			(xy 131.318 -436.23738) (xy 131.305889 -436.236984) (xy 131.282858 -436.229482) (xy 131.263283 -436.215216)
			(xy 131.24909 -436.195589) (xy 131.241672 -436.17253) (xy 131.241292 -436.160418) (xy 130.306738 -436.160418)
			(xy 130.31238 -436.164517) (xy 130.326575 -436.184053) (xy 130.334039 -436.207018) (xy 130.334512 -436.219092)
			(xy 130.334512 -438.760616) (xy 130.334049 -438.772691) (xy 130.326583 -438.795658) (xy 130.312386 -438.815194)
			(xy 130.292847 -438.829388) (xy 130.269879 -438.836851) (xy 130.257804 -438.837324) (xy 129.318004 -438.837324)
			(xy 129.305931 -438.836833) (xy 129.282967 -438.829373) (xy 129.263431 -438.815183) (xy 129.249236 -438.795651)
			(xy 129.241771 -438.772689) (xy 129.241296 -438.760616) (xy 128.334516 -438.760616) (xy 128.334516 -439.760614)
			(xy 131.241292 -439.760614) (xy 131.241292 -437.21909) (xy 131.241798 -437.207005) (xy 131.249252 -437.184012)
			(xy 131.26343 -437.164436) (xy 131.282952 -437.150184) (xy 131.305917 -437.142644) (xy 131.318 -437.142128)
			(xy 132.2578 -437.142128) (xy 132.269912 -437.142516) (xy 132.292944 -437.150019) (xy 132.312519 -437.164287)
			(xy 132.326713 -437.183916) (xy 132.334129 -437.206977) (xy 132.334508 -437.21909) (xy 132.334508 -438.760616)
			(xy 133.241288 -438.760616) (xy 133.241288 -436.219092) (xy 133.241757 -436.207017) (xy 133.249222 -436.184051)
			(xy 133.263417 -436.164514) (xy 133.282954 -436.15032) (xy 133.305921 -436.142857) (xy 133.317996 -436.142384)
			(xy 134.257796 -436.142384) (xy 134.26987 -436.142868) (xy 134.292835 -436.150328) (xy 134.306725 -436.160418)
			(xy 135.241284 -436.160418) (xy 135.241284 -433.618894) (xy 135.241703 -433.6068) (xy 135.249167 -433.583792)
			(xy 135.263364 -433.564208) (xy 135.282911 -433.549959) (xy 135.305899 -433.542435) (xy 135.317992 -433.541932)
			(xy 136.257792 -433.541932) (xy 136.269904 -433.542323) (xy 136.292936 -433.549824) (xy 136.312512 -433.564091)
			(xy 136.326706 -433.58372) (xy 136.334121 -433.606781) (xy 136.3345 -433.618894) (xy 136.3345 -435.16042)
			(xy 137.24128 -435.16042) (xy 137.24128 -432.618896) (xy 137.241761 -432.606822) (xy 137.249223 -432.583857)
			(xy 137.263416 -432.564321) (xy 137.28295 -432.550126) (xy 137.305914 -432.542662) (xy 137.317988 -432.542188)
			(xy 138.257788 -432.542188) (xy 138.26987 -432.542623) (xy 138.292851 -432.550087) (xy 138.307154 -432.560476)
			(xy 139.241276 -432.560476) (xy 139.241276 -430.018952) (xy 139.241723 -430.006877) (xy 139.249197 -429.98391)
			(xy 139.263398 -429.964376) (xy 139.282939 -429.950182) (xy 139.305908 -429.942718) (xy 139.317984 -429.942244)
			(xy 140.257784 -429.942244) (xy 140.269853 -429.942777) (xy 140.292812 -429.950229) (xy 140.312345 -429.96441)
			(xy 140.326541 -429.983931) (xy 140.334013 -430.006883) (xy 140.334492 -430.018952) (xy 140.334492 -431.560478)
			(xy 142.241016 -431.560478) (xy 142.241016 -429.018954) (xy 142.241472 -429.006839) (xy 142.248969 -428.983798)
			(xy 142.263216 -428.964199) (xy 142.28282 -428.949958) (xy 142.305863 -428.942468) (xy 142.317978 -428.941992)
			(xy 143.257778 -428.941992) (xy 143.269887 -428.94253) (xy 143.292922 -428.950005) (xy 143.307426 -428.960534)
			(xy 144.241012 -428.960534) (xy 144.241012 -426.41901) (xy 144.24152 -426.406899) (xy 144.249001 -426.38386)
			(xy 144.263235 -426.36426) (xy 144.282828 -426.350018) (xy 144.305863 -426.342526) (xy 144.317974 -426.342048)
			(xy 145.257774 -426.342048) (xy 145.269896 -426.342482) (xy 145.292956 -426.349969) (xy 145.312572 -426.364216)
			(xy 145.326824 -426.38383) (xy 145.334315 -426.406888) (xy 145.334736 -426.41901) (xy 145.334736 -427.960536)
			(xy 146.241008 -427.960536) (xy 146.241008 -425.419012) (xy 146.24147 -425.406962) (xy 146.248901 -425.384035)
			(xy 146.263041 -425.364518) (xy 146.282511 -425.350315) (xy 146.305413 -425.34281) (xy 146.317462 -425.342304)
			(xy 147.25777 -425.342304) (xy 147.269854 -425.342832) (xy 147.292848 -425.350276) (xy 147.312425 -425.364448)
			(xy 147.326678 -425.383967) (xy 147.334217 -425.40693) (xy 147.334732 -425.419012) (xy 147.334732 -427.960536)
			(xy 147.334272 -427.972585) (xy 147.326833 -427.995506) (xy 147.312691 -428.015019) (xy 147.293223 -428.029222)
			(xy 147.270325 -428.036733) (xy 147.258278 -428.037244) (xy 146.31797 -428.037244) (xy 146.305877 -428.036818)
			(xy 146.282873 -428.029351) (xy 146.263292 -428.015154) (xy 146.249043 -427.995612) (xy 146.241515 -427.972627)
			(xy 146.241008 -427.960536) (xy 145.334736 -427.960536) (xy 145.334736 -428.960534) (xy 145.334317 -428.972653)
			(xy 145.326817 -428.995702) (xy 145.312562 -429.015305) (xy 145.292948 -429.029545) (xy 145.269893 -429.037026)
			(xy 145.257774 -429.037496) (xy 144.317974 -429.037496) (xy 144.305861 -429.037011) (xy 144.282823 -429.029521)
			(xy 144.263225 -429.015281) (xy 144.248983 -428.995684) (xy 144.24149 -428.972646) (xy 144.241012 -428.960534)
			(xy 143.307426 -428.960534) (xy 143.31252 -428.964232) (xy 143.326764 -428.983817) (xy 143.334259 -429.006846)
			(xy 143.33474 -429.018954) (xy 143.33474 -431.560478) (xy 143.334321 -431.572602) (xy 143.326832 -431.595664)
			(xy 143.312581 -431.615281) (xy 143.292964 -431.629532) (xy 143.269902 -431.637021) (xy 143.257778 -431.63744)
			(xy 142.317978 -431.63744) (xy 142.30586 -431.637007) (xy 142.282812 -431.629511) (xy 142.263209 -431.61526)
			(xy 142.248969 -431.595648) (xy 142.241486 -431.572596) (xy 142.241016 -431.560478) (xy 140.334492 -431.560478)
			(xy 140.334492 -432.560476) (xy 140.334067 -432.572559) (xy 140.326604 -432.595544) (xy 140.312401 -432.615096)
			(xy 140.292851 -432.6293) (xy 140.269867 -432.636765) (xy 140.257784 -432.637184) (xy 139.317984 -432.637184)
			(xy 139.305898 -432.636801) (xy 139.282911 -432.629326) (xy 139.263359 -432.615113) (xy 139.249156 -432.595553)
			(xy 139.241693 -432.572562) (xy 139.241276 -432.560476) (xy 138.307154 -432.560476) (xy 138.312401 -432.564287)
			(xy 138.326606 -432.583834) (xy 138.334074 -432.606814) (xy 138.334496 -432.618896) (xy 138.334496 -435.16042)
			(xy 138.334052 -435.172497) (xy 138.326583 -435.195467) (xy 138.312381 -435.215004) (xy 138.292838 -435.229198)
			(xy 138.269865 -435.236657) (xy 138.257788 -435.237128) (xy 137.317988 -435.237128) (xy 137.305915 -435.236646)
			(xy 137.282951 -435.229183) (xy 137.263416 -435.21499) (xy 137.249221 -435.195456) (xy 137.241755 -435.172493)
			(xy 137.24128 -435.16042) (xy 136.3345 -435.16042) (xy 136.3345 -436.160418) (xy 136.334009 -436.172505)
			(xy 136.326552 -436.195499) (xy 136.31237 -436.215075) (xy 136.292845 -436.229327) (xy 136.269877 -436.236865)
			(xy 136.257792 -436.23738) (xy 135.317992 -436.23738) (xy 135.305881 -436.23699) (xy 135.28285 -436.229486)
			(xy 135.263275 -436.215219) (xy 135.249081 -436.19559) (xy 135.241664 -436.172531) (xy 135.241284 -436.160418)
			(xy 134.306725 -436.160418) (xy 134.312372 -436.16452) (xy 134.326567 -436.184054) (xy 134.334031 -436.207019)
			(xy 134.334504 -436.219092) (xy 134.334504 -438.760616) (xy 134.334049 -438.772692) (xy 134.326582 -438.79566)
			(xy 134.312383 -438.815197) (xy 134.292842 -438.829391) (xy 134.269872 -438.836852) (xy 134.257796 -438.837324)
			(xy 133.317996 -438.837324) (xy 133.305923 -438.836839) (xy 133.282958 -438.829378) (xy 133.263423 -438.815186)
			(xy 133.249228 -438.795652) (xy 133.241763 -438.772689) (xy 133.241288 -438.760616) (xy 132.334508 -438.760616)
			(xy 132.334508 -439.760614) (xy 135.241284 -439.760614) (xy 135.241284 -437.21909) (xy 135.2417 -437.206996)
			(xy 135.249165 -437.183987) (xy 135.263363 -437.164404) (xy 135.28291 -437.150155) (xy 135.305899 -437.142631)
			(xy 135.317992 -437.142128) (xy 136.257792 -437.142128) (xy 136.269903 -437.142523) (xy 136.292935 -437.150024)
			(xy 136.312511 -437.16429) (xy 136.326705 -437.183918) (xy 136.334121 -437.206977) (xy 136.3345 -437.21909)
			(xy 136.3345 -438.760616) (xy 137.24128 -438.760616) (xy 137.24128 -436.219092) (xy 137.241757 -436.207018)
			(xy 137.249221 -436.184053) (xy 137.263414 -436.164517) (xy 137.282949 -436.150322) (xy 137.305914 -436.142858)
			(xy 137.317988 -436.142384) (xy 138.257788 -436.142384) (xy 138.269869 -436.142823) (xy 138.29285 -436.150286)
			(xy 138.306799 -436.160418) (xy 139.241276 -436.160418) (xy 139.241276 -433.618894) (xy 139.241703 -433.606801)
			(xy 139.249166 -433.583794) (xy 139.263361 -433.564211) (xy 139.282906 -433.549962) (xy 139.305892 -433.542436)
			(xy 139.317984 -433.541932) (xy 140.257784 -433.541932) (xy 140.269895 -433.542331) (xy 140.292927 -433.549829)
			(xy 140.312503 -433.564094) (xy 140.326697 -433.583722) (xy 140.334113 -433.606781) (xy 140.334492 -433.618894)
			(xy 140.334492 -435.16042) (xy 142.241016 -435.16042) (xy 142.241016 -432.618896) (xy 142.241457 -432.606844)
			(xy 142.248893 -432.583916) (xy 142.263038 -432.564399) (xy 142.282513 -432.550196) (xy 142.305419 -432.542693)
			(xy 142.31747 -432.542188) (xy 143.257778 -432.542188) (xy 143.269871 -432.542627) (xy 143.292879 -432.550084)
			(xy 143.30722 -432.560476) (xy 144.241012 -432.560476) (xy 144.241012 -430.018952) (xy 144.241419 -430.006898)
			(xy 144.248867 -429.983969) (xy 144.263021 -429.964453) (xy 144.282502 -429.950252) (xy 144.305413 -429.942749)
			(xy 144.317466 -429.942244) (xy 145.257774 -429.942244) (xy 145.269863 -429.94273) (xy 145.292863 -429.95018)
			(xy 145.312444 -429.964361) (xy 145.326695 -429.983891) (xy 145.334227 -430.006865) (xy 145.334736 -430.018952)
			(xy 145.334736 -431.560478) (xy 146.241008 -431.560478) (xy 146.241008 -429.018954) (xy 146.241472 -429.00684)
			(xy 146.248968 -428.9838) (xy 146.263213 -428.964202) (xy 146.282815 -428.949961) (xy 146.305856 -428.94247)
			(xy 146.31797 -428.941992) (xy 147.25777 -428.941992) (xy 147.269878 -428.942537) (xy 147.292913 -428.95001)
			(xy 147.307412 -428.960534) (xy 148.241004 -428.960534) (xy 148.241004 -426.41901) (xy 148.24152 -426.406899)
			(xy 148.249 -426.383862) (xy 148.263232 -426.364263) (xy 148.282823 -426.35002) (xy 148.305856 -426.342527)
			(xy 148.317966 -426.342048) (xy 149.257766 -426.342048) (xy 149.269888 -426.342489) (xy 149.292947 -426.349973)
			(xy 149.312564 -426.364219) (xy 149.326816 -426.383831) (xy 149.334307 -426.406888) (xy 149.334728 -426.41901)
			(xy 149.334728 -427.960536) (xy 150.241 -427.960536) (xy 150.241 -425.419012) (xy 150.24147 -425.406962)
			(xy 150.2489 -425.384037) (xy 150.263038 -425.364521) (xy 150.282506 -425.350318) (xy 150.305406 -425.342811)
			(xy 150.317454 -425.342304) (xy 151.257762 -425.342304) (xy 151.269846 -425.342839) (xy 151.292839 -425.350281)
			(xy 151.312417 -425.364451) (xy 151.32667 -425.383968) (xy 151.334209 -425.40693) (xy 151.334724 -425.419012)
			(xy 151.334724 -427.960536) (xy 151.334271 -427.972586) (xy 151.326832 -427.995508) (xy 151.312688 -428.015022)
			(xy 151.293218 -428.029225) (xy 151.270318 -428.036734) (xy 151.25827 -428.037244) (xy 150.317962 -428.037244)
			(xy 150.305869 -428.036825) (xy 150.282864 -428.029356) (xy 150.263284 -428.015157) (xy 150.249035 -427.995613)
			(xy 150.241507 -427.972628) (xy 150.241 -427.960536) (xy 149.334728 -427.960536) (xy 149.334728 -428.960534)
			(xy 149.334317 -428.972654) (xy 149.326816 -428.995704) (xy 149.31256 -429.015308) (xy 149.292943 -429.029547)
			(xy 149.269886 -429.037027) (xy 149.257766 -429.037496) (xy 148.317966 -429.037496) (xy 148.305853 -429.037018)
			(xy 148.282814 -429.029525) (xy 148.263216 -429.015284) (xy 148.248975 -428.995686) (xy 148.241482 -428.972647)
			(xy 148.241004 -428.960534) (xy 147.307412 -428.960534) (xy 147.312511 -428.964235) (xy 147.326755 -428.983819)
			(xy 147.334251 -429.006846) (xy 147.334732 -429.018954) (xy 147.334732 -431.560478) (xy 147.334321 -431.572603)
			(xy 147.326831 -431.595666) (xy 147.312578 -431.615284) (xy 147.292959 -431.629535) (xy 147.269895 -431.637022)
			(xy 147.25777 -431.63744) (xy 146.31797 -431.63744) (xy 146.305852 -431.637014) (xy 146.282804 -431.629515)
			(xy 146.263201 -431.615262) (xy 146.248961 -431.59565) (xy 146.241478 -431.572597) (xy 146.241008 -431.560478)
			(xy 145.334736 -431.560478) (xy 145.334736 -432.560476) (xy 145.33422 -432.572521) (xy 145.326799 -432.59544)
			(xy 145.312671 -432.614953) (xy 145.293214 -432.629159) (xy 145.270325 -432.636672) (xy 145.258282 -432.637184)
			(xy 144.317974 -432.637184) (xy 144.305885 -432.636715) (xy 144.282888 -432.629254) (xy 144.263311 -432.615067)
			(xy 144.24906 -432.595536) (xy 144.241524 -432.572563) (xy 144.241012 -432.560476) (xy 143.30722 -432.560476)
			(xy 143.312464 -432.564276) (xy 143.326713 -432.583818) (xy 143.334237 -432.606804) (xy 143.33474 -432.618896)
			(xy 143.33474 -435.16042) (xy 143.334258 -435.172467) (xy 143.326824 -435.195387) (xy 143.312688 -435.214899)
			(xy 143.293225 -435.229103) (xy 143.270332 -435.236615) (xy 143.258286 -435.237128) (xy 142.317978 -435.237128)
			(xy 142.305884 -435.236711) (xy 142.282877 -435.229244) (xy 142.263295 -435.215046) (xy 142.249046 -435.1955)
			(xy 142.24152 -435.172513) (xy 142.241016 -435.16042) (xy 140.334492 -435.16042) (xy 140.334492 -436.160418)
			(xy 140.334009 -436.172505) (xy 140.326551 -436.195501) (xy 140.312367 -436.215078) (xy 140.29284 -436.229329)
			(xy 140.26987 -436.236866) (xy 140.257784 -436.23738) (xy 139.317984 -436.23738) (xy 139.305872 -436.236997)
			(xy 139.282841 -436.229491) (xy 139.263266 -436.215221) (xy 139.249073 -436.195592) (xy 139.241656 -436.172531)
			(xy 139.241276 -436.160418) (xy 138.306799 -436.160418) (xy 138.3124 -436.164486) (xy 138.326605 -436.184032)
			(xy 138.334074 -436.207011) (xy 138.334496 -436.219092) (xy 138.334496 -438.760616) (xy 138.334049 -438.772693)
			(xy 138.326581 -438.795662) (xy 138.31238 -438.8152) (xy 138.292837 -438.829394) (xy 138.269865 -438.836853)
			(xy 138.257788 -438.837324) (xy 137.317988 -438.837324) (xy 137.305914 -438.836846) (xy 137.28295 -438.829382)
			(xy 137.263414 -438.815189) (xy 137.24922 -438.795654) (xy 137.241755 -438.77269) (xy 137.24128 -438.760616)
			(xy 136.3345 -438.760616) (xy 136.3345 -439.760614) (xy 139.241276 -439.760614) (xy 139.241276 -437.21909)
			(xy 139.2417 -437.206996) (xy 139.249164 -437.183989) (xy 139.26336 -437.164407) (xy 139.282905 -437.150158)
			(xy 139.305892 -437.142632) (xy 139.317984 -437.142128) (xy 140.257784 -437.142128) (xy 140.269895 -437.14253)
			(xy 140.292926 -437.150029) (xy 140.312502 -437.164293) (xy 140.326696 -437.18392) (xy 140.334112 -437.206978)
			(xy 140.334492 -437.21909) (xy 140.334492 -438.760616) (xy 142.241016 -438.760616) (xy 142.241016 -436.219092)
			(xy 142.241454 -436.20704) (xy 142.24889 -436.184111) (xy 142.263036 -436.164594) (xy 142.282512 -436.150392)
			(xy 142.305419 -436.142889) (xy 142.31747 -436.142384) (xy 143.257778 -436.142384) (xy 143.269871 -436.142827)
			(xy 143.292878 -436.150283) (xy 143.306865 -436.160418) (xy 144.241012 -436.160418) (xy 144.241012 -433.618894)
			(xy 144.241506 -433.606782) (xy 144.248992 -433.583743) (xy 144.263229 -433.564143) (xy 144.282825 -433.549901)
			(xy 144.305862 -433.54241) (xy 144.317974 -433.541932) (xy 145.257774 -433.541932) (xy 145.269895 -433.542382)
			(xy 145.292952 -433.549866) (xy 145.312567 -433.56411) (xy 145.326819 -433.58372) (xy 145.334313 -433.606773)
			(xy 145.334736 -433.618894) (xy 145.334736 -435.16042) (xy 146.241008 -435.16042) (xy 146.241008 -432.618896)
			(xy 146.241457 -432.606845) (xy 146.248892 -432.583918) (xy 146.263035 -432.564401) (xy 146.282508 -432.550199)
			(xy 146.305412 -432.542694) (xy 146.317462 -432.542188) (xy 147.25777 -432.542188) (xy 147.269863 -432.542634)
			(xy 147.29287 -432.550088) (xy 147.307207 -432.560476) (xy 148.241004 -432.560476) (xy 148.241004 -430.018952)
			(xy 148.241419 -430.006899) (xy 148.248865 -429.983971) (xy 148.263018 -429.964456) (xy 148.282497 -429.950254)
			(xy 148.305406 -429.94275) (xy 148.317458 -429.942244) (xy 149.257766 -429.942244) (xy 149.269854 -429.942736)
			(xy 149.292854 -429.950184) (xy 149.312435 -429.964364) (xy 149.326687 -429.983893) (xy 149.334219 -430.006866)
			(xy 149.334728 -430.018952) (xy 149.334728 -431.560478) (xy 150.241 -431.560478) (xy 150.241 -429.018954)
			(xy 150.241472 -429.006841) (xy 150.248967 -428.983803) (xy 150.263211 -428.964205) (xy 150.28281 -428.949964)
			(xy 150.305849 -428.942471) (xy 150.317962 -428.941992) (xy 151.257762 -428.941992) (xy 151.26987 -428.942543)
			(xy 151.292904 -428.950015) (xy 151.307399 -428.960534) (xy 152.240996 -428.960534) (xy 152.240996 -426.41901)
			(xy 152.24152 -426.4069) (xy 152.248999 -426.383864) (xy 152.263229 -426.364266) (xy 152.282818 -426.350023)
			(xy 152.305848 -426.342528) (xy 152.317958 -426.342048) (xy 153.257758 -426.342048) (xy 153.26988 -426.342496)
			(xy 153.292939 -426.349978) (xy 153.312555 -426.364222) (xy 153.326808 -426.383833) (xy 153.334299 -426.406889)
			(xy 153.33472 -426.41901) (xy 153.33472 -427.960536) (xy 154.240992 -427.960536) (xy 154.240992 -425.419012)
			(xy 154.24147 -425.406963) (xy 154.248898 -425.384039) (xy 154.263035 -425.364524) (xy 154.282501 -425.35032)
			(xy 154.305399 -425.342812) (xy 154.317446 -425.342304) (xy 155.257754 -425.342304) (xy 155.269838 -425.342846)
			(xy 155.292831 -425.350286) (xy 155.312408 -425.364454) (xy 155.326662 -425.38397) (xy 155.334201 -425.40693)
			(xy 155.334716 -425.419012) (xy 155.334716 -427.960536) (xy 155.334271 -427.972587) (xy 155.326831 -427.995511)
			(xy 155.312685 -428.015024) (xy 155.293213 -428.029227) (xy 155.270311 -428.036735) (xy 155.258262 -428.037244)
			(xy 154.317954 -428.037244) (xy 154.30586 -428.036832) (xy 154.282856 -428.02936) (xy 154.263275 -428.01516)
			(xy 154.249027 -427.995615) (xy 154.241499 -427.972628) (xy 154.240992 -427.960536) (xy 153.33472 -427.960536)
			(xy 153.33472 -428.960534) (xy 153.334369 -428.972663) (xy 153.326862 -428.99573) (xy 153.312594 -429.015348)
			(xy 153.292962 -429.029597) (xy 153.269887 -429.03708) (xy 153.257758 -429.037496) (xy 152.317958 -429.037496)
			(xy 152.305845 -429.037025) (xy 152.282806 -429.02953) (xy 152.263208 -429.015287) (xy 152.248966 -428.995687)
			(xy 152.241474 -428.972647) (xy 152.240996 -428.960534) (xy 151.307399 -428.960534) (xy 151.312503 -428.964238)
			(xy 151.326747 -428.98382) (xy 151.334243 -429.006847) (xy 151.334724 -429.018954) (xy 151.334724 -431.560478)
			(xy 151.334321 -431.572603) (xy 151.32683 -431.595668) (xy 151.312575 -431.615287) (xy 151.292954 -431.629537)
			(xy 151.269887 -431.637023) (xy 151.257762 -431.63744) (xy 150.317962 -431.63744) (xy 150.305843 -431.63702)
			(xy 150.282795 -431.62952) (xy 150.263192 -431.615265) (xy 150.248953 -431.595651) (xy 150.24147 -431.572597)
			(xy 150.241 -431.560478) (xy 149.334728 -431.560478) (xy 149.334728 -432.560476) (xy 149.33422 -432.572522)
			(xy 149.326797 -432.595442) (xy 149.312668 -432.614956) (xy 149.293209 -432.629161) (xy 149.270318 -432.636673)
			(xy 149.258274 -432.637184) (xy 148.317966 -432.637184) (xy 148.305877 -432.636722) (xy 148.282879 -432.629259)
			(xy 148.263302 -432.61507) (xy 148.249052 -432.595538) (xy 148.241516 -432.572563) (xy 148.241004 -432.560476)
			(xy 147.307207 -432.560476) (xy 147.312455 -432.564278) (xy 147.326705 -432.58382) (xy 147.334229 -432.606805)
			(xy 147.334732 -432.618896) (xy 147.334732 -435.16042) (xy 147.334258 -435.172468) (xy 147.326823 -435.195389)
			(xy 147.312685 -435.214901) (xy 147.29322 -435.229105) (xy 147.270324 -435.236616) (xy 147.258278 -435.237128)
			(xy 146.31797 -435.237128) (xy 146.305876 -435.236718) (xy 146.282869 -435.229249) (xy 146.263286 -435.215049)
			(xy 146.249038 -435.195502) (xy 146.241512 -435.172513) (xy 146.241008 -435.16042) (xy 145.334736 -435.16042)
			(xy 145.334736 -436.160418) (xy 145.334355 -436.172544) (xy 145.326854 -436.195608) (xy 145.312594 -436.215225)
			(xy 145.292969 -436.229474) (xy 145.2699 -436.236962) (xy 145.257774 -436.23738) (xy 144.317974 -436.23738)
			(xy 144.30586 -436.236911) (xy 144.282819 -436.229419) (xy 144.263219 -436.215175) (xy 144.248978 -436.195574)
			(xy 144.241488 -436.172532) (xy 144.241012 -436.160418) (xy 143.306865 -436.160418) (xy 143.312462 -436.164474)
			(xy 143.326712 -436.184016) (xy 143.334237 -436.207001) (xy 143.33474 -436.219092) (xy 143.33474 -438.760616)
			(xy 143.334254 -438.772663) (xy 143.326822 -438.795582) (xy 143.312686 -438.815094) (xy 143.293224 -438.829298)
			(xy 143.270331 -438.836811) (xy 143.258286 -438.837324) (xy 142.317978 -438.837324) (xy 142.305884 -438.836911)
			(xy 142.282876 -438.829444) (xy 142.263294 -438.815245) (xy 142.249045 -438.795698) (xy 142.24152 -438.772709)
			(xy 142.241016 -438.760616) (xy 140.334492 -438.760616) (xy 140.334492 -439.760614) (xy 144.241012 -439.760614)
			(xy 144.241012 -437.21909) (xy 144.241503 -437.206978) (xy 144.24899 -437.183938) (xy 144.263228 -437.164339)
			(xy 144.282824 -437.150097) (xy 144.305862 -437.142606) (xy 144.317974 -437.142128) (xy 145.257774 -437.142128)
			(xy 145.269894 -437.142582) (xy 145.292951 -437.150066) (xy 145.312565 -437.164309) (xy 145.326818 -437.183917)
			(xy 145.334312 -437.20697) (xy 145.334736 -437.21909) (xy 145.334736 -438.760616) (xy 146.241008 -438.760616)
			(xy 146.241008 -436.219092) (xy 146.241453 -436.207041) (xy 146.248889 -436.184113) (xy 146.263034 -436.164597)
			(xy 146.282507 -436.150394) (xy 146.305412 -436.14289) (xy 146.317462 -436.142384) (xy 147.25777 -436.142384)
			(xy 147.269862 -436.142834) (xy 147.292869 -436.150288) (xy 147.306851 -436.160418) (xy 148.241004 -436.160418)
			(xy 148.241004 -433.618894) (xy 148.241506 -433.606783) (xy 148.248991 -433.583745) (xy 148.263226 -433.564146)
			(xy 148.28282 -433.549904) (xy 148.305855 -433.542411) (xy 148.317966 -433.541932) (xy 149.257766 -433.541932)
			(xy 149.269886 -433.542389) (xy 149.292943 -433.549871) (xy 149.312558 -433.564113) (xy 149.326811 -433.583721)
			(xy 149.334305 -433.606774) (xy 149.334728 -433.618894) (xy 149.334728 -435.16042) (xy 150.241 -435.16042)
			(xy 150.241 -432.618896) (xy 150.241457 -432.606846) (xy 150.24889 -432.58392) (xy 150.263032 -432.564404)
			(xy 150.282503 -432.550201) (xy 150.305405 -432.542695) (xy 150.317454 -432.542188) (xy 151.257762 -432.542188)
			(xy 151.269854 -432.542641) (xy 151.292862 -432.550093) (xy 151.307195 -432.560476) (xy 152.240996 -432.560476)
			(xy 152.240996 -430.018952) (xy 152.241419 -430.0069) (xy 152.248864 -429.983973) (xy 152.263015 -429.964459)
			(xy 152.282492 -429.950257) (xy 152.305399 -429.942751) (xy 152.31745 -429.942244) (xy 153.257758 -429.942244)
			(xy 153.269846 -429.942743) (xy 153.292846 -429.950189) (xy 153.312427 -429.964367) (xy 153.326679 -429.983894)
			(xy 153.334211 -430.006866) (xy 153.33472 -430.018952) (xy 153.33472 -431.560478) (xy 154.240992 -431.560478)
			(xy 154.240992 -429.018954) (xy 154.241472 -429.006842) (xy 154.248966 -428.983805) (xy 154.263208 -428.964208)
			(xy 154.282805 -428.949966) (xy 154.305842 -428.942472) (xy 154.317954 -428.941992) (xy 155.257754 -428.941992)
			(xy 155.269862 -428.94255) (xy 155.292896 -428.950019) (xy 155.307387 -428.960534) (xy 156.240988 -428.960534)
			(xy 156.240988 -426.41901) (xy 156.24152 -426.406901) (xy 156.248998 -426.383867) (xy 156.263226 -426.364269)
			(xy 156.282813 -426.350025) (xy 156.305841 -426.342529) (xy 156.31795 -426.342048) (xy 157.25775 -426.342048)
			(xy 157.269868 -426.342469) (xy 157.292915 -426.349972) (xy 157.312516 -426.364226) (xy 157.326756 -426.383839)
			(xy 157.33424 -426.406891) (xy 157.334712 -426.41901) (xy 157.334712 -428.960534) (xy 157.334218 -428.972645)
			(xy 157.326728 -428.995681) (xy 157.31249 -429.015278) (xy 157.292896 -429.02952) (xy 157.269861 -429.037016)
			(xy 157.25775 -429.037496) (xy 156.31795 -429.037496) (xy 156.305836 -429.037031) (xy 156.282797 -429.029535)
			(xy 156.263199 -429.015289) (xy 156.248958 -428.995689) (xy 156.241466 -428.972648) (xy 156.240988 -428.960534)
			(xy 155.307387 -428.960534) (xy 155.312494 -428.96424) (xy 155.326739 -428.983822) (xy 155.334235 -429.006847)
			(xy 155.334716 -429.018954) (xy 155.334716 -431.560478) (xy 155.334321 -431.572604) (xy 155.326829 -431.59567)
			(xy 155.312572 -431.61529) (xy 155.292949 -431.62954) (xy 155.26988 -431.637024) (xy 155.257754 -431.63744)
			(xy 154.317954 -431.63744) (xy 154.305835 -431.637027) (xy 154.282786 -431.629525) (xy 154.263184 -431.615268)
			(xy 154.248944 -431.595653) (xy 154.241462 -431.572598) (xy 154.240992 -431.560478) (xy 153.33472 -431.560478)
			(xy 153.33472 -432.560476) (xy 153.33422 -432.572523) (xy 153.326796 -432.595444) (xy 153.312665 -432.614959)
			(xy 153.293204 -432.629164) (xy 153.270311 -432.636674) (xy 153.258266 -432.637184) (xy 152.317958 -432.637184)
			(xy 152.305869 -432.636729) (xy 152.282871 -432.629264) (xy 152.263293 -432.615073) (xy 152.249043 -432.595539)
			(xy 152.241508 -432.572564) (xy 152.240996 -432.560476) (xy 151.307195 -432.560476) (xy 151.312447 -432.564281)
			(xy 151.326697 -432.583821) (xy 151.334221 -432.606805) (xy 151.334724 -432.618896) (xy 151.334724 -435.16042)
			(xy 151.334257 -435.172469) (xy 151.326822 -435.195391) (xy 151.312682 -435.214904) (xy 151.293215 -435.229108)
			(xy 151.270317 -435.236618) (xy 151.25827 -435.237128) (xy 150.317962 -435.237128) (xy 150.305867 -435.236724)
			(xy 150.28286 -435.229253) (xy 150.263278 -435.215052) (xy 150.24903 -435.195503) (xy 150.241504 -435.172514)
			(xy 150.241 -435.16042) (xy 149.334728 -435.16042) (xy 149.334728 -436.160418) (xy 149.334355 -436.172545)
			(xy 149.326853 -436.19561) (xy 149.312591 -436.215228) (xy 149.292964 -436.229477) (xy 149.269893 -436.236963)
			(xy 149.257766 -436.23738) (xy 148.317966 -436.23738) (xy 148.305851 -436.236918) (xy 148.28281 -436.229423)
			(xy 148.26321 -436.215178) (xy 148.248969 -436.195576) (xy 148.24148 -436.172533) (xy 148.241004 -436.160418)
			(xy 147.306851 -436.160418) (xy 147.312454 -436.164477) (xy 147.326704 -436.184017) (xy 147.334229 -436.207001)
			(xy 147.334732 -436.219092) (xy 147.334732 -438.760616) (xy 147.334254 -438.772664) (xy 147.326821 -438.795584)
			(xy 147.312684 -438.815097) (xy 147.293219 -438.829301) (xy 147.270324 -438.836812) (xy 147.258278 -438.837324)
			(xy 146.31797 -438.837324) (xy 146.305875 -438.836918) (xy 146.282868 -438.829448) (xy 146.263285 -438.815247)
			(xy 146.249037 -438.795699) (xy 146.241512 -438.77271) (xy 146.241008 -438.760616) (xy 145.334736 -438.760616)
			(xy 145.334736 -439.760614) (xy 148.241004 -439.760614) (xy 148.241004 -437.21909) (xy 148.241503 -437.206978)
			(xy 148.248989 -437.183941) (xy 148.263225 -437.164342) (xy 148.282819 -437.1501) (xy 148.305854 -437.142607)
			(xy 148.317966 -437.142128) (xy 149.257766 -437.142128) (xy 149.269886 -437.142589) (xy 149.292942 -437.15007)
			(xy 149.312557 -437.164312) (xy 149.32681 -437.183918) (xy 149.334304 -437.20697) (xy 149.334728 -437.21909)
			(xy 149.334728 -438.760616) (xy 150.241 -438.760616) (xy 150.241 -436.219092) (xy 150.241453 -436.207041)
			(xy 150.248888 -436.184116) (xy 150.263031 -436.1646) (xy 150.282502 -436.150397) (xy 150.305405 -436.142891)
			(xy 150.317454 -436.142384) (xy 151.257762 -436.142384) (xy 151.269854 -436.142841) (xy 151.292861 -436.150292)
			(xy 151.306838 -436.160418) (xy 152.240996 -436.160418) (xy 152.240996 -433.618894) (xy 152.241506 -433.606783)
			(xy 152.24899 -433.583747) (xy 152.263224 -433.564149) (xy 152.282815 -433.549906) (xy 152.305848 -433.542412)
			(xy 152.317958 -433.541932) (xy 153.257758 -433.541932) (xy 153.269878 -433.542396) (xy 153.292934 -433.549876)
			(xy 153.31255 -433.564116) (xy 153.326803 -433.583722) (xy 153.334297 -433.606774) (xy 153.33472 -433.618894)
			(xy 153.33472 -435.16042) (xy 154.240992 -435.16042) (xy 154.240992 -432.618896) (xy 154.241456 -432.606846)
			(xy 154.248889 -432.583922) (xy 154.263029 -432.564407) (xy 154.282498 -432.550204) (xy 154.305398 -432.542696)
			(xy 154.317446 -432.542188) (xy 155.257754 -432.542188) (xy 155.269846 -432.542647) (xy 155.292853 -432.550097)
			(xy 155.307181 -432.560476) (xy 156.240988 -432.560476) (xy 156.240988 -430.018952) (xy 156.241419 -430.0069)
			(xy 156.248863 -429.983975) (xy 156.263012 -429.964461) (xy 156.282487 -429.950259) (xy 156.305392 -429.942752)
			(xy 156.317442 -429.942244) (xy 157.25775 -429.942244) (xy 157.269837 -429.94275) (xy 157.292837 -429.950193)
			(xy 157.312418 -429.96437) (xy 157.32667 -429.983896) (xy 157.334203 -430.006866) (xy 157.334712 -430.018952)
			(xy 157.334712 -432.560476) (xy 157.33422 -432.572524) (xy 157.326795 -432.595447) (xy 157.312662 -432.614962)
			(xy 157.293199 -432.629166) (xy 157.270304 -432.636675) (xy 157.258258 -432.637184) (xy 156.31795 -432.637184)
			(xy 156.305865 -432.636651) (xy 156.28287 -432.62921) (xy 156.263292 -432.61504) (xy 156.249039 -432.595522)
			(xy 156.241501 -432.572559) (xy 156.240988 -432.560476) (xy 155.307181 -432.560476) (xy 155.312438 -432.564284)
			(xy 155.326688 -432.583823) (xy 155.334213 -432.606806) (xy 155.334716 -432.618896) (xy 155.334716 -435.16042)
			(xy 155.334257 -435.17247) (xy 155.326821 -435.195393) (xy 155.312679 -435.214907) (xy 155.29321 -435.22911)
			(xy 155.27031 -435.236619) (xy 155.258262 -435.237128) (xy 154.317954 -435.237128) (xy 154.305859 -435.236731)
			(xy 154.282851 -435.229258) (xy 154.263269 -435.215054) (xy 154.249022 -435.195505) (xy 154.241496 -435.172514)
			(xy 154.240992 -435.16042) (xy 153.33472 -435.16042) (xy 153.33472 -436.160418) (xy 153.334354 -436.172546)
			(xy 153.326852 -436.195612) (xy 153.312588 -436.215231) (xy 153.292958 -436.22948) (xy 153.269886 -436.236964)
			(xy 153.257758 -436.23738) (xy 152.317958 -436.23738) (xy 152.305843 -436.236924) (xy 152.282801 -436.229428)
			(xy 152.263202 -436.215181) (xy 152.248961 -436.195577) (xy 152.241472 -436.172533) (xy 152.240996 -436.160418)
			(xy 151.306838 -436.160418) (xy 151.312445 -436.16448) (xy 151.326695 -436.184019) (xy 151.334221 -436.207002)
			(xy 151.334724 -436.219092) (xy 151.334724 -438.760616) (xy 151.334254 -438.772665) (xy 151.32682 -438.795587)
			(xy 151.312681 -438.8151) (xy 151.293214 -438.829304) (xy 151.270317 -438.836814) (xy 151.25827 -438.837324)
			(xy 150.317962 -438.837324) (xy 150.305867 -438.836924) (xy 150.282859 -438.829453) (xy 150.263277 -438.81525)
			(xy 150.249029 -438.795701) (xy 150.241504 -438.77271) (xy 150.241 -438.760616) (xy 149.334728 -438.760616)
			(xy 149.334728 -439.760614) (xy 152.240996 -439.760614) (xy 152.240996 -437.21909) (xy 152.241503 -437.206979)
			(xy 152.248988 -437.183943) (xy 152.263222 -437.164345) (xy 152.282814 -437.150102) (xy 152.305847 -437.142608)
			(xy 152.317958 -437.142128) (xy 153.257758 -437.142128) (xy 153.269878 -437.142595) (xy 153.292933 -437.150075)
			(xy 153.312548 -437.164315) (xy 153.326801 -437.18392) (xy 153.334296 -437.206971) (xy 153.33472 -437.21909)
			(xy 153.33472 -438.760616) (xy 154.240992 -438.760616) (xy 154.240992 -436.219092) (xy 154.241453 -436.207042)
			(xy 154.248887 -436.184118) (xy 154.263028 -436.164603) (xy 154.282497 -436.1504) (xy 154.305398 -436.142892)
			(xy 154.317446 -436.142384) (xy 155.257754 -436.142384) (xy 155.269846 -436.142847) (xy 155.292852 -436.150297)
			(xy 155.306825 -436.160418) (xy 156.240988 -436.160418) (xy 156.240988 -433.618894) (xy 156.241506 -433.606784)
			(xy 156.248989 -433.583749) (xy 156.263221 -433.564152) (xy 156.28281 -433.549909) (xy 156.30584 -433.542413)
			(xy 156.31795 -433.541932) (xy 157.25775 -433.541932) (xy 157.269867 -433.542369) (xy 157.29291 -433.549869)
			(xy 157.312511 -433.564121) (xy 157.326751 -433.583729) (xy 157.334238 -433.606777) (xy 157.334712 -433.618894)
			(xy 157.334712 -436.160418) (xy 157.334205 -436.172529) (xy 157.326718 -436.195564) (xy 157.312484 -436.215161)
			(xy 157.292893 -436.229404) (xy 157.26986 -436.2369) (xy 157.25775 -436.23738) (xy 156.31795 -436.23738)
			(xy 156.305835 -436.236931) (xy 156.282793 -436.229432) (xy 156.263193 -436.215184) (xy 156.248953 -436.195578)
			(xy 156.241464 -436.172534) (xy 156.240988 -436.160418) (xy 155.306825 -436.160418) (xy 155.312437 -436.164483)
			(xy 155.326687 -436.18402) (xy 155.334212 -436.207002) (xy 155.334716 -436.219092) (xy 155.334716 -438.760616)
			(xy 155.334254 -438.772665) (xy 155.326819 -438.795589) (xy 155.312678 -438.815103) (xy 155.293209 -438.829306)
			(xy 155.27031 -438.836815) (xy 155.258262 -438.837324) (xy 154.317954 -438.837324) (xy 154.305858 -438.836931)
			(xy 154.28285 -438.829457) (xy 154.263268 -438.815253) (xy 154.24902 -438.795702) (xy 154.241496 -438.77271)
			(xy 154.240992 -438.760616) (xy 153.33472 -438.760616) (xy 153.33472 -439.760614) (xy 156.240988 -439.760614)
			(xy 156.240988 -437.21909) (xy 156.241503 -437.20698) (xy 156.248987 -437.183945) (xy 156.263219 -437.164348)
			(xy 156.282809 -437.150105) (xy 156.30584 -437.142609) (xy 156.31795 -437.142128) (xy 157.25775 -437.142128)
			(xy 157.269866 -437.142569) (xy 157.292909 -437.150069) (xy 157.312509 -437.164319) (xy 157.32675 -437.183927)
			(xy 157.334237 -437.206974) (xy 157.334712 -437.21909) (xy 157.334712 -439.760614) (xy 157.334201 -439.772724)
			(xy 157.326716 -439.79576) (xy 157.312482 -439.815357) (xy 157.292892 -439.8296) (xy 157.26986 -439.837096)
			(xy 157.25775 -439.837576) (xy 156.31795 -439.837576) (xy 156.305834 -439.837131) (xy 156.282792 -439.829632)
			(xy 156.263192 -439.815382) (xy 156.248952 -439.795776) (xy 156.241463 -439.77273) (xy 156.240988 -439.760614)
			(xy 153.33472 -439.760614) (xy 153.334351 -439.772742) (xy 153.32685 -439.795808) (xy 153.312586 -439.815426)
			(xy 153.292958 -439.829675) (xy 153.269886 -439.83716) (xy 153.257758 -439.837576) (xy 152.317958 -439.837576)
			(xy 152.305843 -439.837124) (xy 152.2828 -439.829627) (xy 152.263201 -439.815379) (xy 152.24896 -439.795774)
			(xy 152.241471 -439.77273) (xy 152.240996 -439.760614) (xy 149.334728 -439.760614) (xy 149.334351 -439.772741)
			(xy 149.326851 -439.795806) (xy 149.312589 -439.815424) (xy 149.292963 -439.829673) (xy 149.269893 -439.837159)
			(xy 149.257766 -439.837576) (xy 148.317966 -439.837576) (xy 148.305851 -439.837118) (xy 148.282809 -439.829623)
			(xy 148.263209 -439.815377) (xy 148.248968 -439.795773) (xy 148.241479 -439.772729) (xy 148.241004 -439.760614)
			(xy 145.334736 -439.760614) (xy 145.334351 -439.77274) (xy 145.326852 -439.795804) (xy 145.312592 -439.815421)
			(xy 145.292968 -439.82967) (xy 145.2699 -439.837158) (xy 145.257774 -439.837576) (xy 144.317974 -439.837576)
			(xy 144.305859 -439.837111) (xy 144.282818 -439.829618) (xy 144.263218 -439.815374) (xy 144.248976 -439.795772)
			(xy 144.241487 -439.772729) (xy 144.241012 -439.760614) (xy 140.334492 -439.760614) (xy 140.334005 -439.772701)
			(xy 140.326549 -439.795697) (xy 140.312366 -439.815274) (xy 140.292839 -439.829525) (xy 140.269869 -439.837062)
			(xy 140.257784 -439.837576) (xy 139.317984 -439.837576) (xy 139.305872 -439.837197) (xy 139.28284 -439.82969)
			(xy 139.263265 -439.81542) (xy 139.249072 -439.795789) (xy 139.241656 -439.772728) (xy 139.241276 -439.760614)
			(xy 136.3345 -439.760614) (xy 136.334006 -439.7727) (xy 136.32655 -439.795695) (xy 136.312369 -439.815271)
			(xy 136.292844 -439.829523) (xy 136.269877 -439.837061) (xy 136.257792 -439.837576) (xy 135.317992 -439.837576)
			(xy 135.30588 -439.83719) (xy 135.282849 -439.829686) (xy 135.263274 -439.815417) (xy 135.24908 -439.795788)
			(xy 135.241664 -439.772727) (xy 135.241284 -439.760614) (xy 132.334508 -439.760614) (xy 132.334006 -439.7727)
			(xy 132.326551 -439.795693) (xy 132.312372 -439.815268) (xy 132.292849 -439.82952) (xy 132.269884 -439.83706)
			(xy 132.2578 -439.837576) (xy 131.318 -439.837576) (xy 131.305889 -439.837184) (xy 131.282857 -439.829681)
			(xy 131.263282 -439.815414) (xy 131.249088 -439.795786) (xy 131.241672 -439.772727) (xy 131.241292 -439.760614)
			(xy 128.334516 -439.760614) (xy 128.334104 -439.772709) (xy 128.326638 -439.795717) (xy 128.312439 -439.815301)
			(xy 128.292891 -439.829549) (xy 128.269901 -439.837073) (xy 128.257808 -439.837576) (xy 127.318008 -439.837576)
			(xy 127.305897 -439.837177) (xy 127.282866 -439.829677) (xy 127.263291 -439.815412) (xy 127.249096 -439.795785)
			(xy 127.24168 -439.772726) (xy 127.2413 -439.760614) (xy 103.73713 -439.760614) (xy 103.715099 -439.778257)
			(xy 103.550019 -439.900222) (xy 103.380316 -440.015668) (xy 103.206247 -440.124421) (xy 103.028078 -440.226315)
			(xy 102.93731 -440.274202) (xy 102.937056 -440.274202) (xy 102.927326 -440.279991) (xy 102.913754 -440.298074)
			(xy 102.909264 -440.320234) (xy 102.911402 -440.331352) (xy 102.935024 -440.427364) (xy 102.938326 -440.438177)
			(xy 102.952617 -440.455661) (xy 102.973011 -440.465356) (xy 102.9843 -440.465972) (xy 125.219206 -440.465972)
			(xy 125.220476 -440.465972) (xy 125.229394 -440.465406) (xy 125.246014 -440.458868) (xy 125.259388 -440.447031)
			(xy 125.267896 -440.431328) (xy 125.269498 -440.422538) (xy 125.269498 -440.422284) (xy 125.274396 -440.3911)
			(xy 125.291224 -440.330259) (xy 125.315802 -440.272116) (xy 125.347716 -440.217652) (xy 125.386425 -440.167789)
			(xy 125.431276 -440.123369) (xy 125.481511 -440.085143) (xy 125.53628 -440.053757) (xy 125.594658 -440.029741)
			(xy 125.655658 -440.013501) (xy 125.71825 -440.005312) (xy 125.781374 -440.005312) (xy 125.843966 -440.013501)
			(xy 125.904966 -440.029741) (xy 125.963344 -440.053757) (xy 126.018113 -440.085143) (xy 126.068348 -440.123369)
			(xy 126.113199 -440.167789) (xy 126.151908 -440.217652) (xy 126.183822 -440.272116) (xy 126.2084 -440.330259)
			(xy 126.225228 -440.3911) (xy 126.230126 -440.422284) (xy 126.230126 -440.422538) (xy 126.231756 -440.431325)
			(xy 126.240244 -440.447039) (xy 126.253609 -440.458886) (xy 126.270229 -440.465427) (xy 126.279148 -440.465972)
			(xy 129.219198 -440.465972) (xy 129.220468 -440.465972) (xy 129.229387 -440.465407) (xy 129.246009 -440.45887)
			(xy 129.259385 -440.447034) (xy 129.267895 -440.43133) (xy 129.26949 -440.422538) (xy 129.26949 -440.422284)
			(xy 129.274388 -440.3911) (xy 129.291216 -440.330259) (xy 129.315794 -440.272116) (xy 129.347708 -440.217652)
			(xy 129.386417 -440.167789) (xy 129.431268 -440.123369) (xy 129.481503 -440.085143) (xy 129.536272 -440.053757)
			(xy 129.59465 -440.029741) (xy 129.65565 -440.013501) (xy 129.718242 -440.005312) (xy 129.781366 -440.005312)
			(xy 129.843958 -440.013501) (xy 129.904958 -440.029741) (xy 129.963336 -440.053757) (xy 130.018105 -440.085143)
			(xy 130.06834 -440.123369) (xy 130.113191 -440.167789) (xy 130.1519 -440.217652) (xy 130.183814 -440.272116)
			(xy 130.208392 -440.330259) (xy 130.22522 -440.3911) (xy 130.230118 -440.422284) (xy 130.230118 -440.422538)
			(xy 130.231748 -440.431325) (xy 130.240236 -440.447041) (xy 130.253601 -440.45889) (xy 130.27022 -440.465433)
			(xy 130.27914 -440.465972) (xy 133.21919 -440.465972) (xy 133.22046 -440.465972) (xy 133.22938 -440.465408)
			(xy 133.246005 -440.458873) (xy 133.259383 -440.447036) (xy 133.267894 -440.431332) (xy 133.269482 -440.422538)
			(xy 133.269482 -440.422284) (xy 133.27438 -440.3911) (xy 133.291208 -440.330259) (xy 133.315786 -440.272116)
			(xy 133.3477 -440.217652) (xy 133.386409 -440.167789) (xy 133.43126 -440.123369) (xy 133.481495 -440.085143)
			(xy 133.536264 -440.053757) (xy 133.594642 -440.029741) (xy 133.655642 -440.013501) (xy 133.718234 -440.005312)
			(xy 133.781358 -440.005312) (xy 133.84395 -440.013501) (xy 133.90495 -440.029741) (xy 133.963328 -440.053757)
			(xy 134.018097 -440.085143) (xy 134.068332 -440.123369) (xy 134.113183 -440.167789) (xy 134.151892 -440.217652)
			(xy 134.183806 -440.272116) (xy 134.208384 -440.330259) (xy 134.225212 -440.3911) (xy 134.23011 -440.422284)
			(xy 134.23011 -440.422538) (xy 134.23174 -440.431326) (xy 134.240227 -440.447043) (xy 134.253592 -440.458894)
			(xy 134.270211 -440.46544) (xy 134.279132 -440.465972) (xy 137.219182 -440.465972) (xy 137.220452 -440.465972)
			(xy 137.229373 -440.46541) (xy 137.246 -440.458876) (xy 137.25938 -440.447039) (xy 137.267893 -440.431334)
			(xy 137.269474 -440.422538) (xy 137.269474 -440.422284) (xy 137.274372 -440.3911) (xy 137.2912 -440.330259)
			(xy 137.315778 -440.272116) (xy 137.347692 -440.217652) (xy 137.386401 -440.167789) (xy 137.431252 -440.123369)
			(xy 137.481487 -440.085143) (xy 137.536256 -440.053757) (xy 137.594634 -440.029741) (xy 137.655634 -440.013501)
			(xy 137.718226 -440.005312) (xy 137.78135 -440.005312) (xy 137.843942 -440.013501) (xy 137.904942 -440.029741)
			(xy 137.96332 -440.053757) (xy 138.018089 -440.085143) (xy 138.068324 -440.123369) (xy 138.113175 -440.167789)
			(xy 138.151884 -440.217652) (xy 138.183798 -440.272116) (xy 138.208376 -440.330259) (xy 138.225204 -440.3911)
			(xy 138.230102 -440.422284) (xy 138.230102 -440.422538) (xy 138.231732 -440.431326) (xy 138.240218 -440.447045)
			(xy 138.253583 -440.458898) (xy 138.270203 -440.465446) (xy 138.279124 -440.465972) (xy 142.219426 -440.465972)
			(xy 142.220696 -440.465972) (xy 142.229612 -440.465403) (xy 142.246226 -440.458861) (xy 142.259594 -440.447024)
			(xy 142.268098 -440.431323) (xy 142.269718 -440.422538) (xy 142.269718 -440.422284) (xy 142.274616 -440.3911)
			(xy 142.291444 -440.330259) (xy 142.316022 -440.272116) (xy 142.347936 -440.217652) (xy 142.386645 -440.167789)
			(xy 142.431496 -440.123369) (xy 142.481731 -440.085143) (xy 142.5365 -440.053757) (xy 142.594878 -440.029741)
			(xy 142.655878 -440.013501) (xy 142.71847 -440.005312) (xy 142.781594 -440.005312) (xy 142.844186 -440.013501)
			(xy 142.905186 -440.029741) (xy 142.963564 -440.053757) (xy 143.018333 -440.085143) (xy 143.068568 -440.123369)
			(xy 143.113419 -440.167789) (xy 143.152128 -440.217652) (xy 143.184042 -440.272116) (xy 143.20862 -440.330259)
			(xy 143.225448 -440.3911) (xy 143.230346 -440.422284) (xy 143.230346 -440.422538) (xy 143.231977 -440.431323)
			(xy 143.240465 -440.447034) (xy 143.253831 -440.458877) (xy 143.27045 -440.465411) (xy 143.279368 -440.465972)
			(xy 146.219418 -440.465972) (xy 146.220688 -440.465972) (xy 146.229605 -440.465404) (xy 146.246221 -440.458864)
			(xy 146.259591 -440.447026) (xy 146.268097 -440.431325) (xy 146.26971 -440.422538) (xy 146.26971 -440.422284)
			(xy 146.274608 -440.3911) (xy 146.291436 -440.330259) (xy 146.316014 -440.272116) (xy 146.347928 -440.217652)
			(xy 146.386637 -440.167789) (xy 146.431488 -440.123369) (xy 146.481723 -440.085143) (xy 146.536492 -440.053757)
			(xy 146.59487 -440.029741) (xy 146.65587 -440.013501) (xy 146.718462 -440.005312) (xy 146.781586 -440.005312)
			(xy 146.844178 -440.013501) (xy 146.905178 -440.029741) (xy 146.963556 -440.053757) (xy 147.018325 -440.085143)
			(xy 147.06856 -440.123369) (xy 147.113411 -440.167789) (xy 147.15212 -440.217652) (xy 147.184034 -440.272116)
			(xy 147.208612 -440.330259) (xy 147.22544 -440.3911) (xy 147.230338 -440.422284) (xy 147.230338 -440.422538)
			(xy 147.231968 -440.431324) (xy 147.240457 -440.447036) (xy 147.253823 -440.45888) (xy 147.270442 -440.465418)
			(xy 147.27936 -440.465972) (xy 150.21941 -440.465972) (xy 150.22068 -440.465972) (xy 150.229598 -440.465405)
			(xy 150.246217 -440.458866) (xy 150.259589 -440.447029) (xy 150.268096 -440.431327) (xy 150.269702 -440.422538)
			(xy 150.269702 -440.422284) (xy 150.2746 -440.3911) (xy 150.291428 -440.330259) (xy 150.316006 -440.272116)
			(xy 150.34792 -440.217652) (xy 150.386629 -440.167789) (xy 150.43148 -440.123369) (xy 150.481715 -440.085143)
			(xy 150.536484 -440.053757) (xy 150.594862 -440.029741) (xy 150.655862 -440.013501) (xy 150.718454 -440.005312)
			(xy 150.781578 -440.005312) (xy 150.84417 -440.013501) (xy 150.90517 -440.029741) (xy 150.963548 -440.053757)
			(xy 151.018317 -440.085143) (xy 151.068552 -440.123369) (xy 151.113403 -440.167789) (xy 151.152112 -440.217652)
			(xy 151.184026 -440.272116) (xy 151.208604 -440.330259) (xy 151.225432 -440.3911) (xy 151.23033 -440.422284)
			(xy 151.23033 -440.422538) (xy 151.23196 -440.431324) (xy 151.240448 -440.447038) (xy 151.253814 -440.458884)
			(xy 151.270433 -440.465424) (xy 151.279352 -440.465972) (xy 154.219402 -440.465972) (xy 154.220672 -440.465972)
			(xy 154.229591 -440.465407) (xy 154.246212 -440.458869) (xy 154.259586 -440.447032) (xy 154.268095 -440.431329)
			(xy 154.269694 -440.422538) (xy 154.269694 -440.422284) (xy 154.274592 -440.3911) (xy 154.29142 -440.330259)
			(xy 154.315998 -440.272116) (xy 154.347912 -440.217652) (xy 154.386621 -440.167789) (xy 154.431472 -440.123369)
			(xy 154.481707 -440.085143) (xy 154.536476 -440.053757) (xy 154.594854 -440.029741) (xy 154.655854 -440.013501)
			(xy 154.718446 -440.005312) (xy 154.78157 -440.005312) (xy 154.844162 -440.013501) (xy 154.905162 -440.029741)
			(xy 154.96354 -440.053757) (xy 155.018309 -440.085143) (xy 155.068544 -440.123369) (xy 155.113395 -440.167789)
			(xy 155.152104 -440.217652) (xy 155.184018 -440.272116) (xy 155.208596 -440.330259) (xy 155.225424 -440.3911)
			(xy 155.230322 -440.422284) (xy 155.230322 -440.422538) (xy 155.231952 -440.431325) (xy 155.24044 -440.44704)
			(xy 155.253805 -440.458888) (xy 155.270424 -440.46543) (xy 155.279344 -440.465972) (xy 177.2666 -440.465972)
			(xy 177.27789 -440.465366) (xy 177.298284 -440.455676) (xy 177.312546 -440.438172) (xy 177.315876 -440.427364)
			(xy 177.339498 -440.331352) (xy 177.341616 -440.320241) (xy 177.337101 -440.298105) (xy 177.323536 -440.280041)
			(xy 177.313844 -440.274202) (xy 177.31359 -440.274202) (xy 177.222822 -440.226317) (xy 177.044658 -440.124417)
			(xy 176.870595 -440.015659) (xy 176.700898 -439.900208) (xy 176.535823 -439.77824) (xy 176.375621 -439.649938)
			(xy 176.220535 -439.515497) (xy 176.070799 -439.375121) (xy 175.926641 -439.229024) (xy 175.788279 -439.077426)
			(xy 175.655923 -438.920556) (xy 175.529773 -438.758654) (xy 175.410021 -438.591964) (xy 175.296848 -438.420739)
			(xy 175.190426 -438.245239) (xy 175.090916 -438.065729) (xy 174.998469 -437.882482) (xy 174.913224 -437.695775)
			(xy 174.835312 -437.505891) (xy 174.76485 -437.313119) (xy 174.701946 -437.11775) (xy 174.646693 -436.92008)
			(xy 174.599177 -436.72041) (xy 174.559469 -436.519041) (xy 174.52763 -436.316279) (xy 174.503707 -436.112432)
			(xy 174.487737 -435.907808) (xy 174.479744 -435.702717) (xy 174.479204 -435.600094) (xy 174.4797 -435.497873)
			(xy 174.487627 -435.293583) (xy 174.50347 -435.089755) (xy 174.527204 -434.886695) (xy 174.558794 -434.684707)
			(xy 174.598193 -434.484096) (xy 174.645341 -434.285164) (xy 174.700167 -434.08821) (xy 174.762589 -433.893529)
			(xy 174.832512 -433.701416) (xy 174.909833 -433.512158) (xy 174.994433 -433.326041) (xy 175.086187 -433.143344)
			(xy 175.184956 -432.964342) (xy 175.290592 -432.789305) (xy 175.402935 -432.618495) (xy 175.521817 -432.45217)
			(xy 175.647059 -432.29058) (xy 175.778472 -432.133968) (xy 175.915859 -431.982569) (xy 176.059014 -431.836611)
			(xy 176.20772 -431.696314) (xy 176.361755 -431.561888) (xy 176.520886 -431.433536) (xy 176.684875 -431.311451)
			(xy 176.853473 -431.195817) (xy 177.026429 -431.086807) (xy 177.203482 -430.984586) (xy 177.384366 -430.889306)
			(xy 177.568807 -430.801113) (xy 177.75653 -430.720137) (xy 177.947252 -430.646501) (xy 178.140685 -430.580316)
			(xy 178.336539 -430.521681) (xy 178.53452 -430.470685) (xy 178.734329 -430.427403) (xy 178.935666 -430.391902)
			(xy 179.138228 -430.364235) (xy 179.34171 -430.344442) (xy 179.545807 -430.332555) (xy 179.750212 -430.328591)
			(xy 179.954617 -430.332555) (xy 180.158714 -430.344442) (xy 180.362196 -430.364235) (xy 180.564758 -430.391902)
			(xy 180.766095 -430.427403) (xy 180.965904 -430.470685) (xy 181.163885 -430.521681) (xy 181.359739 -430.580316)
			(xy 181.553172 -430.646501) (xy 181.743894 -430.720137) (xy 181.931617 -430.801113) (xy 182.116058 -430.889306)
			(xy 182.296942 -430.984586) (xy 182.473995 -431.086807) (xy 182.646951 -431.195817) (xy 182.815549 -431.311451)
			(xy 182.979538 -431.433536) (xy 183.138669 -431.561888) (xy 183.292704 -431.696314) (xy 183.44141 -431.836611)
			(xy 183.584565 -431.982569) (xy 183.721952 -432.133968) (xy 183.853365 -432.29058) (xy 183.978607 -432.45217)
			(xy 184.097489 -432.618495) (xy 184.209832 -432.789305) (xy 184.315468 -432.964342) (xy 184.409109 -433.134051)
			(xy 196.769222 -433.134051) (xy 196.769222 -432.950069) (xy 196.777247 -432.766261) (xy 196.793282 -432.582979)
			(xy 196.817296 -432.400571) (xy 196.849245 -432.219383) (xy 196.889066 -432.039762) (xy 196.936684 -431.862048)
			(xy 196.992008 -431.686581) (xy 197.054934 -431.513694) (xy 197.125341 -431.343717) (xy 197.203096 -431.176972)
			(xy 197.288049 -431.013777) (xy 197.38004 -430.854444) (xy 197.478894 -430.699275) (xy 197.584422 -430.548565)
			(xy 197.696424 -430.402602) (xy 197.814685 -430.261663) (xy 197.938982 -430.126017) (xy 198.069077 -429.995922)
			(xy 198.204723 -429.871625) (xy 198.345662 -429.753364) (xy 198.491625 -429.641362) (xy 198.642335 -429.535834)
			(xy 198.797504 -429.43698) (xy 198.956837 -429.344989) (xy 199.120032 -429.260036) (xy 199.286777 -429.182281)
			(xy 199.456754 -429.111874) (xy 199.629641 -429.048948) (xy 199.805108 -428.993624) (xy 199.982822 -428.946006)
			(xy 200.162443 -428.906185) (xy 200.343631 -428.874236) (xy 200.526039 -428.850222) (xy 200.709321 -428.834187)
			(xy 200.893129 -428.826162) (xy 201.077111 -428.826162) (xy 201.260919 -428.834187) (xy 201.444201 -428.850222)
			(xy 201.626609 -428.874236) (xy 201.807797 -428.906185) (xy 201.987418 -428.946006) (xy 202.165132 -428.993624)
			(xy 202.340599 -429.048948) (xy 202.513486 -429.111874) (xy 202.683463 -429.182281) (xy 202.850208 -429.260036)
			(xy 203.013403 -429.344989) (xy 203.172736 -429.43698) (xy 203.327905 -429.535834) (xy 203.478615 -429.641362)
			(xy 203.624578 -429.753364) (xy 203.765517 -429.871625) (xy 203.901163 -429.995922) (xy 204.031258 -430.126017)
			(xy 204.155555 -430.261663) (xy 204.273816 -430.402602) (xy 204.385818 -430.548565) (xy 204.491346 -430.699275)
			(xy 204.5902 -430.854444) (xy 204.682191 -431.013777) (xy 204.767144 -431.176972) (xy 204.844899 -431.343717)
			(xy 204.915306 -431.513694) (xy 204.978232 -431.686581) (xy 205.033556 -431.862048) (xy 205.081174 -432.039762)
			(xy 205.120995 -432.219383) (xy 205.152944 -432.400571) (xy 205.176958 -432.582979) (xy 205.192993 -432.766261)
			(xy 205.201018 -432.950069) (xy 205.20152 -433.04206) (xy 205.201018 -433.134051) (xy 205.192993 -433.317859)
			(xy 205.176958 -433.501141) (xy 205.152944 -433.683549) (xy 205.120995 -433.864737) (xy 205.081174 -434.044358)
			(xy 205.033556 -434.222072) (xy 204.978232 -434.397539) (xy 204.915306 -434.570426) (xy 204.844899 -434.740403)
			(xy 204.767144 -434.907148) (xy 204.682191 -435.070343) (xy 204.5902 -435.229676) (xy 204.491346 -435.384845)
			(xy 204.385818 -435.535555) (xy 204.273816 -435.681518) (xy 204.155555 -435.822457) (xy 204.031258 -435.958103)
			(xy 203.901163 -436.088198) (xy 203.765517 -436.212495) (xy 203.624578 -436.330756) (xy 203.478615 -436.442758)
			(xy 203.327905 -436.548286) (xy 203.172736 -436.64714) (xy 203.013403 -436.739131) (xy 202.850208 -436.824084)
			(xy 202.683463 -436.901839) (xy 202.513486 -436.972246) (xy 202.340599 -437.035172) (xy 202.165132 -437.090496)
			(xy 201.987418 -437.138114) (xy 201.807797 -437.177935) (xy 201.626609 -437.209884) (xy 201.444201 -437.233898)
			(xy 201.260919 -437.249933) (xy 201.077111 -437.257958) (xy 200.893129 -437.257958) (xy 200.709321 -437.249933)
			(xy 200.526039 -437.233898) (xy 200.343631 -437.209884) (xy 200.162443 -437.177935) (xy 199.982822 -437.138114)
			(xy 199.805108 -437.090496) (xy 199.629641 -437.035172) (xy 199.456754 -436.972246) (xy 199.286777 -436.901839)
			(xy 199.120032 -436.824084) (xy 198.956837 -436.739131) (xy 198.797504 -436.64714) (xy 198.642335 -436.548286)
			(xy 198.491625 -436.442758) (xy 198.345662 -436.330756) (xy 198.204723 -436.212495) (xy 198.069077 -436.088198)
			(xy 197.938982 -435.958103) (xy 197.814685 -435.822457) (xy 197.696424 -435.681518) (xy 197.584422 -435.535555)
			(xy 197.478894 -435.384845) (xy 197.38004 -435.229676) (xy 197.288049 -435.070343) (xy 197.203096 -434.907148)
			(xy 197.125341 -434.740403) (xy 197.054934 -434.570426) (xy 196.992008 -434.397539) (xy 196.936684 -434.222072)
			(xy 196.889066 -434.044358) (xy 196.849245 -433.864737) (xy 196.817296 -433.683549) (xy 196.793282 -433.501141)
			(xy 196.777247 -433.317859) (xy 196.769222 -433.134051) (xy 184.409109 -433.134051) (xy 184.414237 -433.143344)
			(xy 184.505991 -433.326041) (xy 184.590591 -433.512158) (xy 184.667912 -433.701416) (xy 184.737835 -433.893529)
			(xy 184.800257 -434.08821) (xy 184.855083 -434.285164) (xy 184.902231 -434.484096) (xy 184.94163 -434.684707)
			(xy 184.97322 -434.886695) (xy 184.996954 -435.089755) (xy 185.012797 -435.293583) (xy 185.020724 -435.497873)
			(xy 185.02122 -435.600094) (xy 185.020723 -435.702718) (xy 185.012734 -435.90781) (xy 184.996767 -436.112436)
			(xy 184.972846 -436.316285) (xy 184.941009 -436.519049) (xy 184.901302 -436.720419) (xy 184.853787 -436.920092)
			(xy 184.798535 -437.117763) (xy 184.73563 -437.313134) (xy 184.665168 -437.505908) (xy 184.587255 -437.695792)
			(xy 184.50201 -437.8825) (xy 184.409561 -438.065749) (xy 184.310049 -438.245259) (xy 184.203624 -438.42076)
			(xy 184.090448 -438.591985) (xy 183.970693 -438.758674) (xy 183.84454 -438.920576) (xy 183.71218 -439.077444)
			(xy 183.573814 -439.22904) (xy 183.429652 -439.375136) (xy 183.279912 -439.515509) (xy 183.124821 -439.649947)
			(xy 182.964614 -439.778245) (xy 182.799535 -439.90021) (xy 182.629832 -440.015657) (xy 182.455765 -440.124409)
			(xy 182.277596 -440.226304) (xy 182.186834 -440.274202) (xy 182.18658 -440.274202) (xy 182.176862 -440.279998)
			(xy 182.163311 -440.298082) (xy 182.158828 -440.320231) (xy 182.160926 -440.331352) (xy 182.184548 -440.427364)
			(xy 182.187851 -440.438175) (xy 182.202143 -440.455652) (xy 182.222537 -440.465338) (xy 182.233824 -440.465972)
			(xy 193.556636 -440.465972) (xy 193.564279 -440.465708) (xy 193.578878 -440.461176) (xy 193.585338 -440.457082)
			(xy 193.606674 -440.442604) (xy 193.612731 -440.438123) (xy 193.622153 -440.426374) (xy 193.625216 -440.41949)
			(xy 193.649199 -440.360754) (xy 193.703536 -440.246093) (xy 193.764949 -440.135061) (xy 193.833197 -440.028094)
			(xy 193.908011 -439.925612) (xy 193.989097 -439.828018) (xy 194.076138 -439.735696) (xy 194.168791 -439.649006)
			(xy 194.266693 -439.568291) (xy 194.369458 -439.493867) (xy 194.476684 -439.426027) (xy 194.587948 -439.365037)
			(xy 194.702815 -439.311136) (xy 194.820832 -439.264537) (xy 194.941537 -439.225422) (xy 195.064455 -439.193944)
			(xy 195.189103 -439.170229) (xy 195.314992 -439.154368) (xy 195.441628 -439.146424) (xy 195.50507 -439.145934)
			(xy 276.314916 -439.145934) (xy 276.378357 -439.146429) (xy 276.504991 -439.154378) (xy 276.630878 -439.170243)
			(xy 276.755524 -439.193962) (xy 276.878439 -439.225442) (xy 276.999141 -439.26456) (xy 277.117156 -439.311161)
			(xy 277.232021 -439.365063) (xy 277.343283 -439.426053) (xy 277.450507 -439.493894) (xy 277.553271 -439.568317)
			(xy 277.651171 -439.649031) (xy 277.743823 -439.735719) (xy 277.830863 -439.82804) (xy 277.91195 -439.925632)
			(xy 277.986765 -440.028111) (xy 278.055013 -440.135075) (xy 278.116428 -440.246104) (xy 278.170767 -440.360762)
			(xy 278.19477 -440.41949) (xy 278.197778 -440.426407) (xy 278.207212 -440.438168) (xy 278.213312 -440.442604)
			(xy 278.234648 -440.457082) (xy 278.241101 -440.46119) (xy 278.255705 -440.465719) (xy 278.26335 -440.465972)
			(xy 291.06622 -440.465972) (xy 291.077521 -440.465382) (xy 291.097944 -440.455707) (xy 291.112232 -440.438198)
			(xy 291.115496 -440.427364) (xy 291.139118 -440.331606) (xy 291.141295 -440.320453) (xy 291.136826 -440.298202)
			(xy 291.123214 -440.280044) (xy 291.113464 -440.274202) (xy 291.11321 -440.274202) (xy 291.022455 -440.226313)
			(xy 290.844317 -440.124405) (xy 290.67028 -440.015642) (xy 290.500608 -439.900186) (xy 290.335558 -439.778215)
			(xy 290.175381 -439.649912) (xy 290.020319 -439.515472) (xy 289.870607 -439.375099) (xy 289.726472 -439.229005)
			(xy 289.588132 -439.077411) (xy 289.455797 -438.920549) (xy 289.329668 -438.758654) (xy 289.209935 -438.591973)
			(xy 289.096781 -438.420759) (xy 288.990376 -438.245269) (xy 288.890882 -438.065772) (xy 288.79845 -437.882538)
			(xy 288.71322 -437.695845) (xy 288.63532 -437.505977) (xy 288.564869 -437.31322) (xy 288.501974 -437.117868)
			(xy 288.44673 -436.920215) (xy 288.399221 -436.720562) (xy 288.359519 -436.519212) (xy 288.327683 -436.316468)
			(xy 288.303763 -436.112639) (xy 288.287794 -435.908034) (xy 288.2798 -435.702962) (xy 288.279332 -435.600348)
			(xy 288.279828 -435.498127) (xy 288.287755 -435.293837) (xy 288.303598 -435.090009) (xy 288.327332 -434.886949)
			(xy 288.358922 -434.684961) (xy 288.398321 -434.48435) (xy 288.445469 -434.285418) (xy 288.500295 -434.088464)
			(xy 288.562717 -433.893783) (xy 288.63264 -433.70167) (xy 288.709961 -433.512412) (xy 288.794561 -433.326295)
			(xy 288.886315 -433.143598) (xy 288.985084 -432.964596) (xy 289.09072 -432.789559) (xy 289.203063 -432.618749)
			(xy 289.321945 -432.452424) (xy 289.447187 -432.290834) (xy 289.5786 -432.134222) (xy 289.715987 -431.982823)
			(xy 289.859142 -431.836865) (xy 290.007848 -431.696568) (xy 290.161883 -431.562142) (xy 290.321014 -431.43379)
			(xy 290.485003 -431.311705) (xy 290.653601 -431.196071) (xy 290.826557 -431.087061) (xy 291.00361 -430.98484)
			(xy 291.184494 -430.88956) (xy 291.368935 -430.801367) (xy 291.556658 -430.720391) (xy 291.74738 -430.646755)
			(xy 291.940813 -430.58057) (xy 292.136667 -430.521935) (xy 292.334648 -430.470939) (xy 292.534457 -430.427657)
			(xy 292.735794 -430.392156) (xy 292.938356 -430.364489) (xy 293.141838 -430.344696) (xy 293.345935 -430.332809)
			(xy 293.55034 -430.328845) (xy 293.754745 -430.332809) (xy 293.958842 -430.344696) (xy 294.162324 -430.364489)
			(xy 294.364886 -430.392156) (xy 294.566223 -430.427657) (xy 294.766032 -430.470939) (xy 294.964013 -430.521935)
			(xy 295.159867 -430.58057) (xy 295.3533 -430.646755) (xy 295.544022 -430.720391) (xy 295.731745 -430.801367)
			(xy 295.916186 -430.88956) (xy 296.09707 -430.98484) (xy 296.274123 -431.087061) (xy 296.447079 -431.196071)
			(xy 296.615677 -431.311705) (xy 296.779666 -431.43379) (xy 296.936734 -431.560478) (xy 314.141104 -431.560478)
			(xy 314.141104 -429.018954) (xy 314.141572 -429.00684) (xy 314.149068 -428.983801) (xy 314.163312 -428.964203)
			(xy 314.182912 -428.949962) (xy 314.205952 -428.94247) (xy 314.218066 -428.941992) (xy 315.157866 -428.941992)
			(xy 315.169974 -428.94254) (xy 315.193009 -428.950012) (xy 315.207506 -428.960534) (xy 316.1411 -428.960534)
			(xy 316.1411 -426.41901) (xy 316.14162 -426.4069) (xy 316.1491 -426.383863) (xy 316.163331 -426.364265)
			(xy 316.18292 -426.350022) (xy 316.205952 -426.342527) (xy 316.218062 -426.342048) (xy 317.157862 -426.342048)
			(xy 317.169984 -426.342492) (xy 317.193043 -426.349975) (xy 317.21266 -426.36422) (xy 317.226912 -426.383832)
			(xy 317.234403 -426.406888) (xy 317.234824 -426.41901) (xy 317.234824 -427.960536) (xy 318.141096 -427.960536)
			(xy 318.141096 -425.419012) (xy 318.14157 -425.406963) (xy 318.148999 -425.384038) (xy 318.163136 -425.364523)
			(xy 318.182604 -425.350319) (xy 318.205503 -425.342812) (xy 318.21755 -425.342304) (xy 319.157858 -425.342304)
			(xy 319.169942 -425.342842) (xy 319.192935 -425.350283) (xy 319.212513 -425.364453) (xy 319.226766 -425.383969)
			(xy 319.234305 -425.40693) (xy 319.23482 -425.419012) (xy 319.23482 -427.960536) (xy 319.234371 -427.972586)
			(xy 319.226931 -427.99551) (xy 319.212787 -428.015023) (xy 319.193316 -428.029226) (xy 319.170415 -428.036735)
			(xy 319.158366 -428.037244) (xy 318.218058 -428.037244) (xy 318.205965 -428.036828) (xy 318.18296 -428.029358)
			(xy 318.163379 -428.015159) (xy 318.149131 -427.995614) (xy 318.141603 -427.972628) (xy 318.141096 -427.960536)
			(xy 317.234824 -427.960536) (xy 317.234824 -428.960534) (xy 317.234469 -428.972662) (xy 317.226962 -428.995729)
			(xy 317.212695 -429.015347) (xy 317.193064 -429.029595) (xy 317.169991 -429.03708) (xy 317.157862 -429.037496)
			(xy 316.218062 -429.037496) (xy 316.205949 -429.037021) (xy 316.18291 -429.029528) (xy 316.163312 -429.015285)
			(xy 316.14907 -428.995686) (xy 316.141578 -428.972647) (xy 316.1411 -428.960534) (xy 315.207506 -428.960534)
			(xy 315.212607 -428.964236) (xy 315.226851 -428.98382) (xy 315.234347 -429.006846) (xy 315.234828 -429.018954)
			(xy 315.234828 -431.560478) (xy 315.234421 -431.572603) (xy 315.22693 -431.595667) (xy 315.212677 -431.615285)
			(xy 315.193056 -431.629536) (xy 315.169991 -431.637023) (xy 315.157866 -431.63744) (xy 314.218066 -431.63744)
			(xy 314.205947 -431.637017) (xy 314.182899 -431.629518) (xy 314.163296 -431.615264) (xy 314.149057 -431.59565)
			(xy 314.141574 -431.572597) (xy 314.141104 -431.560478) (xy 296.936734 -431.560478) (xy 296.938797 -431.562142)
			(xy 297.092832 -431.696568) (xy 297.241538 -431.836865) (xy 297.384693 -431.982823) (xy 297.52208 -432.134222)
			(xy 297.653493 -432.290834) (xy 297.778735 -432.452424) (xy 297.897617 -432.618749) (xy 298.00996 -432.789559)
			(xy 298.115596 -432.964596) (xy 298.214365 -433.143598) (xy 298.306119 -433.326295) (xy 298.390719 -433.512412)
			(xy 298.46804 -433.70167) (xy 298.537963 -433.893783) (xy 298.600385 -434.088464) (xy 298.655211 -434.285418)
			(xy 298.702359 -434.48435) (xy 298.741758 -434.684961) (xy 298.773348 -434.886949) (xy 298.797082 -435.090009)
			(xy 298.802555 -435.16042) (xy 314.141104 -435.16042) (xy 314.141104 -432.618896) (xy 314.141557 -432.606845)
			(xy 314.148991 -432.583919) (xy 314.163134 -432.564403) (xy 314.182606 -432.5502) (xy 314.205509 -432.542694)
			(xy 314.217558 -432.542188) (xy 315.157866 -432.542188) (xy 315.169959 -432.542637) (xy 315.192966 -432.55009)
			(xy 315.207301 -432.560476) (xy 316.1411 -432.560476) (xy 316.1411 -430.018952) (xy 316.141519 -430.006899)
			(xy 316.148965 -429.983972) (xy 316.163116 -429.964457) (xy 316.182595 -429.950255) (xy 316.205503 -429.94275)
			(xy 316.217554 -429.942244) (xy 317.157862 -429.942244) (xy 317.16995 -429.94274) (xy 317.19295 -429.950187)
			(xy 317.212531 -429.964366) (xy 317.226783 -429.983894) (xy 317.234315 -430.006866) (xy 317.234824 -430.018952)
			(xy 317.234824 -431.560478) (xy 318.141096 -431.560478) (xy 318.141096 -429.018954) (xy 318.141572 -429.006841)
			(xy 318.149067 -428.983804) (xy 318.163309 -428.964206) (xy 318.182907 -428.949965) (xy 318.205945 -428.942471)
			(xy 318.218058 -428.941992) (xy 319.157858 -428.941992) (xy 319.169966 -428.942547) (xy 319.193 -428.950017)
			(xy 319.207492 -428.960534) (xy 320.141092 -428.960534) (xy 320.141092 -426.41901) (xy 320.14162 -426.406901)
			(xy 320.149099 -426.383865) (xy 320.163328 -426.364268) (xy 320.182915 -426.350024) (xy 320.205945 -426.342528)
			(xy 320.218054 -426.342048) (xy 321.157854 -426.342048) (xy 321.169975 -426.342499) (xy 321.193034 -426.34998)
			(xy 321.212651 -426.364223) (xy 321.226904 -426.383833) (xy 321.234395 -426.406889) (xy 321.234816 -426.41901)
			(xy 321.234816 -427.960536) (xy 322.141088 -427.960536) (xy 322.141088 -425.419012) (xy 322.14157 -425.406964)
			(xy 322.148998 -425.38404) (xy 322.163133 -425.364526) (xy 322.182598 -425.350321) (xy 322.205495 -425.342813)
			(xy 322.217542 -425.342304) (xy 323.15785 -425.342304) (xy 323.169933 -425.342849) (xy 323.192926 -425.350288)
			(xy 323.212504 -425.364455) (xy 323.226758 -425.383971) (xy 323.234297 -425.406931) (xy 323.234812 -425.419012)
			(xy 323.234812 -427.960536) (xy 323.234371 -427.972587) (xy 323.22693 -427.995512) (xy 323.212784 -428.015026)
			(xy 323.193311 -428.029228) (xy 323.170407 -428.036736) (xy 323.158358 -428.037244) (xy 322.21805 -428.037244)
			(xy 322.205961 -428.03675) (xy 322.18296 -428.029305) (xy 322.163378 -428.015126) (xy 322.149126 -427.995597)
			(xy 322.141595 -427.972623) (xy 322.141088 -427.960536) (xy 321.234816 -427.960536) (xy 321.234816 -428.960534)
			(xy 321.234468 -428.972663) (xy 321.226961 -428.995731) (xy 321.212692 -429.015349) (xy 321.193059 -429.029598)
			(xy 321.169984 -429.037081) (xy 321.157854 -429.037496) (xy 320.218054 -429.037496) (xy 320.20594 -429.037028)
			(xy 320.182901 -429.029532) (xy 320.163303 -429.015288) (xy 320.149062 -428.995688) (xy 320.14157 -428.972648)
			(xy 320.141092 -428.960534) (xy 319.207492 -428.960534) (xy 319.212598 -428.964239) (xy 319.226843 -428.983821)
			(xy 319.234339 -429.006847) (xy 319.23482 -429.018954) (xy 319.23482 -431.560478) (xy 319.234421 -431.572604)
			(xy 319.226929 -431.595669) (xy 319.212674 -431.615288) (xy 319.193051 -431.629538) (xy 319.169984 -431.637024)
			(xy 319.157858 -431.63744) (xy 318.218058 -431.63744) (xy 318.205939 -431.637024) (xy 318.182891 -431.629522)
			(xy 318.163288 -431.615267) (xy 318.149048 -431.595652) (xy 318.141566 -431.572597) (xy 318.141096 -431.560478)
			(xy 317.234824 -431.560478) (xy 317.234824 -432.560476) (xy 317.23432 -432.572523) (xy 317.226897 -432.595443)
			(xy 317.212767 -432.614957) (xy 317.193307 -432.629162) (xy 317.170415 -432.636673) (xy 317.15837 -432.637184)
			(xy 316.218062 -432.637184) (xy 316.205973 -432.636726) (xy 316.182975 -432.629261) (xy 316.163398 -432.615072)
			(xy 316.149148 -432.595538) (xy 316.141612 -432.572564) (xy 316.1411 -432.560476) (xy 315.207301 -432.560476)
			(xy 315.212551 -432.56428) (xy 315.226801 -432.583821) (xy 315.234325 -432.606805) (xy 315.234828 -432.618896)
			(xy 315.234828 -435.16042) (xy 315.234357 -435.172468) (xy 315.226923 -435.19539) (xy 315.212784 -435.214903)
			(xy 315.193317 -435.229106) (xy 315.170421 -435.236617) (xy 315.158374 -435.237128) (xy 314.218066 -435.237128)
			(xy 314.205971 -435.236721) (xy 314.182964 -435.229251) (xy 314.163382 -435.21505) (xy 314.149134 -435.195502)
			(xy 314.141608 -435.172513) (xy 314.141104 -435.16042) (xy 298.802555 -435.16042) (xy 298.812925 -435.293837)
			(xy 298.820852 -435.498127) (xy 298.821348 -435.600348) (xy 298.820852 -435.702962) (xy 298.812866 -435.908036)
			(xy 298.796904 -436.112643) (xy 298.77299 -436.316473) (xy 298.74116 -436.519219) (xy 298.701463 -436.720571)
			(xy 298.653959 -436.920227) (xy 298.598719 -437.117881) (xy 298.535828 -437.313236) (xy 298.465381 -437.505995)
			(xy 298.387484 -437.695866) (xy 298.302256 -437.882561) (xy 298.209826 -438.065797) (xy 298.110333 -438.245297)
			(xy 298.00393 -438.420787) (xy 297.890776 -438.592004) (xy 297.771044 -438.758686) (xy 297.76954 -438.760616)
			(xy 314.141104 -438.760616) (xy 314.141104 -436.219092) (xy 314.141553 -436.207041) (xy 314.148989 -436.184115)
			(xy 314.163132 -436.164599) (xy 314.182605 -436.150396) (xy 314.205509 -436.14289) (xy 314.217558 -436.142384)
			(xy 315.157866 -436.142384) (xy 315.169958 -436.142837) (xy 315.192965 -436.15029) (xy 315.206945 -436.160418)
			(xy 316.1411 -436.160418) (xy 316.1411 -433.618894) (xy 316.141606 -433.606783) (xy 316.14909 -433.583746)
			(xy 316.163325 -433.564148) (xy 316.182917 -433.549905) (xy 316.205951 -433.542411) (xy 316.218062 -433.541932)
			(xy 317.157862 -433.541932) (xy 317.169982 -433.542392) (xy 317.193039 -433.549873) (xy 317.212654 -433.564115)
			(xy 317.226907 -433.583722) (xy 317.234401 -433.606774) (xy 317.234824 -433.618894) (xy 317.234824 -435.16042)
			(xy 318.141096 -435.16042) (xy 318.141096 -432.618896) (xy 318.141557 -432.606846) (xy 318.14899 -432.583921)
			(xy 318.163131 -432.564406) (xy 318.182601 -432.550202) (xy 318.205502 -432.542696) (xy 318.21755 -432.542188)
			(xy 319.157858 -432.542188) (xy 319.16995 -432.542644) (xy 319.192958 -432.550095) (xy 319.207287 -432.560476)
			(xy 320.141092 -432.560476) (xy 320.141092 -430.018952) (xy 320.141519 -430.0069) (xy 320.148964 -429.983974)
			(xy 320.163113 -429.96446) (xy 320.18259 -429.950258) (xy 320.205495 -429.942752) (xy 320.217546 -429.942244)
			(xy 321.157854 -429.942244) (xy 321.169942 -429.942747) (xy 321.192941 -429.950191) (xy 321.212522 -429.964368)
			(xy 321.226774 -429.983895) (xy 321.234307 -430.006866) (xy 321.234816 -430.018952) (xy 321.234816 -431.560478)
			(xy 322.141088 -431.560478) (xy 322.141088 -429.018954) (xy 322.141572 -429.006842) (xy 322.149066 -428.983806)
			(xy 322.163306 -428.964209) (xy 322.182902 -428.949967) (xy 322.205938 -428.942472) (xy 322.21805 -428.941992)
			(xy 323.15785 -428.941992) (xy 323.169963 -428.942468) (xy 323.193 -428.949964) (xy 323.207544 -428.960534)
			(xy 324.141084 -428.960534) (xy 324.141084 -426.41901) (xy 324.141469 -426.406883) (xy 324.148964 -426.383817)
			(xy 324.163223 -426.364198) (xy 324.182849 -426.349948) (xy 324.205919 -426.342464) (xy 324.218046 -426.342048)
			(xy 325.157846 -426.342048) (xy 325.169964 -426.342473) (xy 325.19301 -426.349974) (xy 325.212612 -426.364228)
			(xy 325.226852 -426.38384) (xy 325.234336 -426.406892) (xy 325.234808 -426.41901) (xy 325.234808 -427.960536)
			(xy 326.14108 -427.960536) (xy 326.14108 -425.419012) (xy 326.14157 -425.406964) (xy 326.148997 -425.384043)
			(xy 326.163131 -425.364528) (xy 326.182593 -425.350324) (xy 326.205488 -425.342814) (xy 326.217534 -425.342304)
			(xy 327.157842 -425.342304) (xy 327.16993 -425.342771) (xy 327.192926 -425.350235) (xy 327.212502 -425.364423)
			(xy 327.226753 -425.383953) (xy 327.23429 -425.406925) (xy 327.234804 -425.419012) (xy 327.234804 -427.960536)
			(xy 327.234371 -427.972588) (xy 327.226929 -427.995514) (xy 327.212781 -428.015029) (xy 327.193306 -428.029231)
			(xy 327.1704 -428.036737) (xy 327.15835 -428.037244) (xy 326.218042 -428.037244) (xy 326.205953 -428.036757)
			(xy 326.182951 -428.029309) (xy 326.163369 -428.015129) (xy 326.149118 -427.995598) (xy 326.141587 -427.972623)
			(xy 326.14108 -427.960536) (xy 325.234808 -427.960536) (xy 325.234808 -428.960534) (xy 325.234318 -428.972646)
			(xy 325.226827 -428.995682) (xy 325.212588 -429.01528) (xy 325.192993 -429.029522) (xy 325.169958 -429.037016)
			(xy 325.157846 -429.037496) (xy 324.218046 -429.037496) (xy 324.205929 -429.037002) (xy 324.182877 -429.029526)
			(xy 324.163264 -429.015292) (xy 324.149011 -428.995694) (xy 324.141511 -428.972651) (xy 324.141084 -428.960534)
			(xy 323.207544 -428.960534) (xy 323.212597 -428.964206) (xy 323.226838 -428.983804) (xy 323.234332 -429.006841)
			(xy 323.234812 -429.018954) (xy 323.234812 -431.560478) (xy 323.23427 -431.572586) (xy 323.226795 -431.59562)
			(xy 323.212569 -431.615218) (xy 323.192985 -431.629462) (xy 323.169958 -431.636959) (xy 323.15785 -431.63744)
			(xy 322.21805 -431.63744) (xy 322.205931 -431.63703) (xy 322.182882 -431.629527) (xy 322.163279 -431.615269)
			(xy 322.14904 -431.595653) (xy 322.141558 -431.572598) (xy 322.141088 -431.560478) (xy 321.234816 -431.560478)
			(xy 321.234816 -432.560476) (xy 321.23432 -432.572523) (xy 321.226896 -432.595445) (xy 321.212764 -432.61496)
			(xy 321.193302 -432.629165) (xy 321.170408 -432.636675) (xy 321.158362 -432.637184) (xy 320.218054 -432.637184)
			(xy 320.205964 -432.636732) (xy 320.182966 -432.629266) (xy 320.163389 -432.615074) (xy 320.149139 -432.59554)
			(xy 320.141604 -432.572564) (xy 320.141092 -432.560476) (xy 319.207287 -432.560476) (xy 319.212542 -432.564283)
			(xy 319.226793 -432.583822) (xy 319.234317 -432.606805) (xy 319.23482 -432.618896) (xy 319.23482 -435.16042)
			(xy 319.234357 -435.172469) (xy 319.226921 -435.195392) (xy 319.212781 -435.214906) (xy 319.193312 -435.229109)
			(xy 319.170414 -435.236618) (xy 319.158366 -435.237128) (xy 318.218058 -435.237128) (xy 318.205963 -435.236728)
			(xy 318.182956 -435.229256) (xy 318.163374 -435.215053) (xy 318.149126 -435.195504) (xy 318.1416 -435.172514)
			(xy 318.141096 -435.16042) (xy 317.234824 -435.16042) (xy 317.234824 -436.160418) (xy 317.234455 -436.172545)
			(xy 317.226953 -436.195611) (xy 317.212689 -436.215229) (xy 317.193061 -436.229478) (xy 317.16999 -436.236963)
			(xy 317.157862 -436.23738) (xy 316.218062 -436.23738) (xy 316.205947 -436.236921) (xy 316.182906 -436.229425)
			(xy 316.163306 -436.21518) (xy 316.149065 -436.195576) (xy 316.141576 -436.172533) (xy 316.1411 -436.160418)
			(xy 315.206945 -436.160418) (xy 315.212549 -436.164478) (xy 315.2268 -436.184018) (xy 315.234325 -436.207001)
			(xy 315.234828 -436.219092) (xy 315.234828 -438.760616) (xy 315.234354 -438.772664) (xy 315.22692 -438.795586)
			(xy 315.212782 -438.815099) (xy 315.193317 -438.829302) (xy 315.170421 -438.836813) (xy 315.158374 -438.837324)
			(xy 314.218066 -438.837324) (xy 314.205971 -438.836921) (xy 314.182963 -438.829451) (xy 314.163381 -438.815249)
			(xy 314.149133 -438.7957) (xy 314.141608 -438.77271) (xy 314.141104 -438.760616) (xy 297.76954 -438.760616)
			(xy 297.644914 -438.920582) (xy 297.512579 -439.077445) (xy 297.374238 -439.229039) (xy 297.230102 -439.375134)
			(xy 297.080389 -439.515507) (xy 296.925325 -439.649947) (xy 296.787162 -439.760614) (xy 316.1411 -439.760614)
			(xy 316.1411 -437.21909) (xy 316.141603 -437.206979) (xy 316.149088 -437.183942) (xy 316.163324 -437.164343)
			(xy 316.182917 -437.150101) (xy 316.205951 -437.142607) (xy 316.218062 -437.142128) (xy 317.157862 -437.142128)
			(xy 317.169982 -437.142592) (xy 317.193038 -437.150073) (xy 317.212653 -437.164313) (xy 317.226905 -437.183919)
			(xy 317.2344 -437.20697) (xy 317.234824 -437.21909) (xy 317.234824 -438.760616) (xy 318.141096 -438.760616)
			(xy 318.141096 -436.219092) (xy 318.141553 -436.207042) (xy 318.148988 -436.184117) (xy 318.163129 -436.164601)
			(xy 318.1826 -436.150398) (xy 318.205501 -436.142892) (xy 318.21755 -436.142384) (xy 319.157858 -436.142384)
			(xy 319.16995 -436.142844) (xy 319.192956 -436.150294) (xy 319.206932 -436.160418) (xy 320.141092 -436.160418)
			(xy 320.141092 -433.618894) (xy 320.141606 -433.606784) (xy 320.149089 -433.583748) (xy 320.163322 -433.564151)
			(xy 320.182912 -433.549908) (xy 320.205944 -433.542412) (xy 320.218054 -433.541932) (xy 321.157854 -433.541932)
			(xy 321.169974 -433.542399) (xy 321.19303 -433.549878) (xy 321.212646 -433.564117) (xy 321.226898 -433.583723)
			(xy 321.234393 -433.606775) (xy 321.234816 -433.618894) (xy 321.234816 -435.16042) (xy 322.141088 -435.16042)
			(xy 322.141088 -432.618896) (xy 322.141556 -432.606847) (xy 322.148989 -432.583923) (xy 322.163128 -432.564409)
			(xy 322.182596 -432.550205) (xy 322.205494 -432.542697) (xy 322.217542 -432.542188) (xy 323.15785 -432.542188)
			(xy 323.169942 -432.542651) (xy 323.192949 -432.5501) (xy 323.207275 -432.560476) (xy 324.141084 -432.560476)
			(xy 324.141084 -430.018952) (xy 324.141519 -430.006901) (xy 324.148963 -429.983976) (xy 324.163111 -429.964463)
			(xy 324.182585 -429.950261) (xy 324.205488 -429.942753) (xy 324.217538 -429.942244) (xy 325.157846 -429.942244)
			(xy 325.169938 -429.942668) (xy 325.192941 -429.950138) (xy 325.212521 -429.964336) (xy 325.22677 -429.983878)
			(xy 325.2343 -430.006861) (xy 325.234808 -430.018952) (xy 325.234808 -431.560478) (xy 326.14108 -431.560478)
			(xy 326.14108 -429.018954) (xy 326.141473 -429.006833) (xy 326.148978 -428.983781) (xy 326.163239 -428.964176)
			(xy 326.18286 -428.949938) (xy 326.20592 -428.942459) (xy 326.218042 -428.941992) (xy 327.157842 -428.941992)
			(xy 327.169954 -428.942475) (xy 327.192991 -428.949968) (xy 327.207531 -428.960534) (xy 328.141076 -428.960534)
			(xy 328.141076 -426.41901) (xy 328.141469 -426.406884) (xy 328.148963 -426.383819) (xy 328.16322 -426.364201)
			(xy 328.182844 -426.34995) (xy 328.205912 -426.342465) (xy 328.218038 -426.342048) (xy 329.157838 -426.342048)
			(xy 329.169956 -426.342479) (xy 329.193002 -426.349978) (xy 329.212604 -426.36423) (xy 329.226844 -426.383841)
			(xy 329.234328 -426.406892) (xy 329.2348 -426.41901) (xy 329.2348 -427.960536) (xy 331.141324 -427.960536)
			(xy 331.141324 -425.419012) (xy 331.141724 -425.406927) (xy 331.149192 -425.383939) (xy 331.1634 -425.364386)
			(xy 331.182957 -425.350183) (xy 331.205947 -425.34272) (xy 331.218032 -425.342304) (xy 332.157832 -425.342304)
			(xy 332.169909 -425.342737) (xy 332.19288 -425.35021) (xy 332.212417 -425.364414) (xy 332.22661 -425.38396)
			(xy 332.23407 -425.406934) (xy 332.23454 -425.419012) (xy 332.23454 -427.960536) (xy 332.234067 -427.972609)
			(xy 332.226599 -427.995572) (xy 332.212403 -428.015106) (xy 332.192869 -428.0293) (xy 332.169905 -428.036768)
			(xy 332.157832 -428.037244) (xy 331.218032 -428.037244) (xy 331.205963 -428.036709) (xy 331.183003 -428.02926)
			(xy 331.163468 -428.01508) (xy 331.149271 -427.995558) (xy 331.141801 -427.972605) (xy 331.141324 -427.960536)
			(xy 329.2348 -427.960536) (xy 329.2348 -428.960534) (xy 329.234318 -428.972647) (xy 329.226826 -428.995684)
			(xy 329.212585 -429.015282) (xy 329.192988 -429.029524) (xy 329.169951 -429.037017) (xy 329.157838 -429.037496)
			(xy 328.218038 -429.037496) (xy 328.205921 -429.037008) (xy 328.182869 -429.029531) (xy 328.163256 -429.015295)
			(xy 328.149002 -428.995696) (xy 328.141503 -428.972651) (xy 328.141076 -428.960534) (xy 327.207531 -428.960534)
			(xy 327.212588 -428.964209) (xy 327.22683 -428.983805) (xy 327.234324 -429.006842) (xy 327.234804 -429.018954)
			(xy 327.234804 -431.560478) (xy 327.23427 -431.572587) (xy 327.226794 -431.595623) (xy 327.212567 -431.615221)
			(xy 327.19298 -431.629465) (xy 327.169951 -431.63696) (xy 327.157842 -431.63744) (xy 326.218042 -431.63744)
			(xy 326.205919 -431.637004) (xy 326.182858 -431.629521) (xy 326.16324 -431.615274) (xy 326.148988 -431.59566)
			(xy 326.141499 -431.572601) (xy 326.14108 -431.560478) (xy 325.234808 -431.560478) (xy 325.234808 -432.560476)
			(xy 325.23432 -432.572524) (xy 325.226895 -432.595448) (xy 325.212761 -432.614963) (xy 325.193297 -432.629168)
			(xy 325.1704 -432.636676) (xy 325.158354 -432.637184) (xy 324.218046 -432.637184) (xy 324.205961 -432.636654)
			(xy 324.182966 -432.629213) (xy 324.163387 -432.615042) (xy 324.149134 -432.595522) (xy 324.141597 -432.572559)
			(xy 324.141084 -432.560476) (xy 323.207275 -432.560476) (xy 323.212534 -432.564285) (xy 323.226784 -432.583823)
			(xy 323.234309 -432.606806) (xy 323.234812 -432.618896) (xy 323.234812 -435.16042) (xy 323.234357 -435.17247)
			(xy 323.22692 -435.195394) (xy 323.212778 -435.214908) (xy 323.193307 -435.229111) (xy 323.170406 -435.236619)
			(xy 323.158358 -435.237128) (xy 322.21805 -435.237128) (xy 322.20596 -435.23665) (xy 322.182955 -435.229203)
			(xy 322.163372 -435.21502) (xy 322.149121 -435.195487) (xy 322.141593 -435.172508) (xy 322.141088 -435.16042)
			(xy 321.234816 -435.16042) (xy 321.234816 -436.160418) (xy 321.234454 -436.172546) (xy 321.226952 -436.195613)
			(xy 321.212686 -436.215232) (xy 321.193056 -436.229481) (xy 321.169983 -436.236965) (xy 321.157854 -436.23738)
			(xy 320.218054 -436.23738) (xy 320.205939 -436.236928) (xy 320.182897 -436.22943) (xy 320.163298 -436.215182)
			(xy 320.149057 -436.195578) (xy 320.141568 -436.172533) (xy 320.141092 -436.160418) (xy 319.206932 -436.160418)
			(xy 319.212541 -436.164481) (xy 319.226791 -436.184019) (xy 319.234316 -436.207002) (xy 319.23482 -436.219092)
			(xy 319.23482 -438.760616) (xy 319.234354 -438.772665) (xy 319.226919 -438.795588) (xy 319.212779 -438.815101)
			(xy 319.193312 -438.829305) (xy 319.170413 -438.836814) (xy 319.158366 -438.837324) (xy 318.218058 -438.837324)
			(xy 318.205963 -438.836928) (xy 318.182955 -438.829455) (xy 318.163372 -438.815252) (xy 318.149124 -438.795701)
			(xy 318.1416 -438.77271) (xy 318.141096 -438.760616) (xy 317.234824 -438.760616) (xy 317.234824 -439.760614)
			(xy 320.141092 -439.760614) (xy 320.141092 -437.21909) (xy 320.141603 -437.20698) (xy 320.149087 -437.183944)
			(xy 320.163321 -437.164346) (xy 320.182912 -437.150104) (xy 320.205944 -437.142608) (xy 320.218054 -437.142128)
			(xy 321.157854 -437.142128) (xy 321.169973 -437.142599) (xy 321.193029 -437.150077) (xy 321.212644 -437.164316)
			(xy 321.226897 -437.183921) (xy 321.234392 -437.206971) (xy 321.234816 -437.21909) (xy 321.234816 -438.760616)
			(xy 322.141088 -438.760616) (xy 322.141088 -436.219092) (xy 322.141553 -436.207043) (xy 322.148986 -436.184119)
			(xy 322.163126 -436.164604) (xy 322.182595 -436.150401) (xy 322.205494 -436.142893) (xy 322.217542 -436.142384)
			(xy 323.15785 -436.142384) (xy 323.169941 -436.142851) (xy 323.192948 -436.150299) (xy 323.206918 -436.160418)
			(xy 324.141084 -436.160418) (xy 324.141084 -433.618894) (xy 324.141456 -433.606766) (xy 324.148955 -433.5837)
			(xy 324.163218 -433.564081) (xy 324.182846 -433.549831) (xy 324.205918 -433.542348) (xy 324.218046 -433.541932)
			(xy 325.157846 -433.541932) (xy 325.169962 -433.542372) (xy 325.193006 -433.549872) (xy 325.212607 -433.564122)
			(xy 325.226847 -433.58373) (xy 325.234334 -433.606777) (xy 325.234808 -433.618894) (xy 325.234808 -435.16042)
			(xy 326.14108 -435.16042) (xy 326.14108 -432.618896) (xy 326.141556 -432.606848) (xy 326.148988 -432.583925)
			(xy 326.163125 -432.564411) (xy 326.182591 -432.550208) (xy 326.205487 -432.542698) (xy 326.217534 -432.542188)
			(xy 327.157842 -432.542188) (xy 327.169939 -432.542572) (xy 327.192949 -432.550047) (xy 327.207325 -432.560476)
			(xy 328.141076 -432.560476) (xy 328.141076 -430.018952) (xy 328.141518 -430.006902) (xy 328.148961 -429.983979)
			(xy 328.163108 -429.964466) (xy 328.18258 -429.950263) (xy 328.205481 -429.942754) (xy 328.21753 -429.942244)
			(xy 329.157838 -429.942244) (xy 329.16993 -429.942675) (xy 329.192933 -429.950143) (xy 329.212512 -429.964338)
			(xy 329.226761 -429.983879) (xy 329.234292 -430.006861) (xy 329.2348 -430.018952) (xy 329.2348 -431.560478)
			(xy 331.141324 -431.560478) (xy 331.141324 -429.018954) (xy 331.141768 -429.006864) (xy 331.149235 -428.983864)
			(xy 331.163428 -428.964286) (xy 331.182965 -428.950037) (xy 331.205943 -428.942503) (xy 331.218032 -428.941992)
			(xy 332.157832 -428.941992) (xy 332.169942 -428.942389) (xy 332.192969 -428.949896) (xy 332.207563 -428.960534)
			(xy 333.14132 -428.960534) (xy 333.14132 -426.41901) (xy 333.141816 -426.406923) (xy 333.149267 -426.383926)
			(xy 333.163447 -426.364348) (xy 333.182973 -426.350096) (xy 333.205943 -426.34256) (xy 333.218028 -426.342048)
			(xy 334.157828 -426.342048) (xy 334.169933 -426.342492) (xy 334.192952 -426.349993) (xy 334.212521 -426.364249)
			(xy 334.226716 -426.383861) (xy 334.234145 -426.406904) (xy 334.234536 -426.41901) (xy 334.234536 -427.960536)
			(xy 335.141316 -427.960536) (xy 335.141316 -425.419012) (xy 335.141723 -425.406928) (xy 335.149191 -425.383941)
			(xy 335.163397 -425.364389) (xy 335.182952 -425.350185) (xy 335.205939 -425.342722) (xy 335.218024 -425.342304)
			(xy 336.157824 -425.342304) (xy 336.169901 -425.342744) (xy 336.192871 -425.350215) (xy 336.212409 -425.364417)
			(xy 336.226602 -425.383961) (xy 336.234061 -425.406935) (xy 336.234532 -425.419012) (xy 336.234532 -427.960536)
			(xy 336.234067 -427.97261) (xy 336.226598 -427.995574) (xy 336.2124 -428.015109) (xy 336.192864 -428.029303)
			(xy 336.169898 -428.036769) (xy 336.157824 -428.037244) (xy 335.218024 -428.037244) (xy 335.205954 -428.036716)
			(xy 335.182994 -428.029264) (xy 335.16346 -428.015083) (xy 335.149263 -427.99556) (xy 335.141793 -427.972605)
			(xy 335.141316 -427.960536) (xy 334.234536 -427.960536) (xy 334.234536 -428.960534) (xy 334.234121 -428.972628)
			(xy 334.226652 -428.995634) (xy 334.212453 -429.015215) (xy 334.192907 -429.029464) (xy 334.16992 -429.03699)
			(xy 334.157828 -429.037496) (xy 333.218028 -429.037496) (xy 333.20592 -429.03706) (xy 333.182893 -429.029567)
			(xy 333.163319 -429.015311) (xy 333.149124 -428.995693) (xy 333.141703 -428.972643) (xy 333.14132 -428.960534)
			(xy 332.207563 -428.960534) (xy 332.212541 -428.964163) (xy 332.226734 -428.983788) (xy 332.234156 -429.006843)
			(xy 332.23454 -429.018954) (xy 332.23454 -431.560478) (xy 332.234073 -431.572568) (xy 332.22662 -431.595572)
			(xy 332.212434 -431.615154) (xy 332.192899 -431.629404) (xy 332.169921 -431.636933) (xy 332.157832 -431.63744)
			(xy 331.218032 -431.63744) (xy 331.205929 -431.636957) (xy 331.182909 -431.629471) (xy 331.163339 -431.615225)
			(xy 331.149142 -431.59562) (xy 331.141713 -431.572582) (xy 331.141324 -431.560478) (xy 329.2348 -431.560478)
			(xy 329.2348 -432.560476) (xy 329.23432 -432.572525) (xy 329.226894 -432.59545) (xy 329.212758 -432.614966)
			(xy 329.193292 -432.62917) (xy 329.170393 -432.636677) (xy 329.158346 -432.637184) (xy 328.218038 -432.637184)
			(xy 328.205953 -432.636661) (xy 328.182957 -432.629217) (xy 328.163379 -432.615044) (xy 328.149126 -432.595524)
			(xy 328.141589 -432.572559) (xy 328.141076 -432.560476) (xy 327.207325 -432.560476) (xy 327.212532 -432.564253)
			(xy 327.226779 -432.583806) (xy 327.234302 -432.606801) (xy 327.234804 -432.618896) (xy 327.234804 -435.16042)
			(xy 327.234357 -435.172471) (xy 327.226919 -435.195396) (xy 327.212775 -435.214911) (xy 327.193302 -435.229114)
			(xy 327.170399 -435.23662) (xy 327.15835 -435.237128) (xy 326.218042 -435.237128) (xy 326.205951 -435.236656)
			(xy 326.182947 -435.229207) (xy 326.163363 -435.215023) (xy 326.149113 -435.195488) (xy 326.141585 -435.172509)
			(xy 326.14108 -435.16042) (xy 325.234808 -435.16042) (xy 325.234808 -436.160418) (xy 325.234305 -436.172529)
			(xy 325.226818 -436.195565) (xy 325.212582 -436.215163) (xy 325.19299 -436.229405) (xy 325.169957 -436.2369)
			(xy 325.157846 -436.23738) (xy 324.218046 -436.23738) (xy 324.205927 -436.236901) (xy 324.182873 -436.229424)
			(xy 324.163259 -436.215187) (xy 324.149005 -436.195584) (xy 324.141509 -436.172536) (xy 324.141084 -436.160418)
			(xy 323.206918 -436.160418) (xy 323.212532 -436.164484) (xy 323.226783 -436.184021) (xy 323.234308 -436.207002)
			(xy 323.234812 -436.219092) (xy 323.234812 -438.760616) (xy 323.234354 -438.772666) (xy 323.226918 -438.79559)
			(xy 323.212776 -438.815104) (xy 323.193307 -438.829307) (xy 323.170406 -438.836815) (xy 323.158358 -438.837324)
			(xy 322.21805 -438.837324) (xy 322.205959 -438.836849) (xy 322.182954 -438.829402) (xy 322.16337 -438.815219)
			(xy 322.149119 -438.795684) (xy 322.141593 -438.772705) (xy 322.141088 -438.760616) (xy 321.234816 -438.760616)
			(xy 321.234816 -439.760614) (xy 324.141084 -439.760614) (xy 324.141084 -437.21909) (xy 324.141452 -437.206962)
			(xy 324.148953 -437.183895) (xy 324.163216 -437.164276) (xy 324.182845 -437.150027) (xy 324.205918 -437.142544)
			(xy 324.218046 -437.142128) (xy 325.157846 -437.142128) (xy 325.169962 -437.142572) (xy 325.193005 -437.150071)
			(xy 325.212605 -437.164321) (xy 325.226845 -437.183927) (xy 325.234333 -437.206974) (xy 325.234808 -437.21909)
			(xy 325.234808 -438.760616) (xy 326.14108 -438.760616) (xy 326.14108 -436.219092) (xy 326.141553 -436.207043)
			(xy 326.148985 -436.184121) (xy 326.163124 -436.164607) (xy 326.18259 -436.150403) (xy 326.205487 -436.142894)
			(xy 326.217534 -436.142384) (xy 327.157842 -436.142384) (xy 327.169938 -436.142772) (xy 327.192948 -436.150246)
			(xy 327.206971 -436.160418) (xy 328.141076 -436.160418) (xy 328.141076 -433.618894) (xy 328.141456 -433.606767)
			(xy 328.148954 -433.583702) (xy 328.163215 -433.564084) (xy 328.182841 -433.549834) (xy 328.205911 -433.542349)
			(xy 328.218038 -433.541932) (xy 329.157838 -433.541932) (xy 329.169954 -433.542379) (xy 329.192997 -433.549876)
			(xy 329.212598 -433.564125) (xy 329.226838 -433.583731) (xy 329.234326 -433.606778) (xy 329.2348 -433.618894)
			(xy 329.2348 -435.16042) (xy 331.141324 -435.16042) (xy 331.141324 -432.618896) (xy 331.14171 -432.60681)
			(xy 331.149182 -432.583822) (xy 331.163394 -432.564268) (xy 331.182954 -432.550066) (xy 331.205946 -432.542604)
			(xy 331.218032 -432.542188) (xy 332.157832 -432.542188) (xy 332.169908 -432.542637) (xy 332.192875 -432.550108)
			(xy 332.20714 -432.560476) (xy 333.14132 -432.560476) (xy 333.14132 -430.018952) (xy 333.141724 -430.006872)
			(xy 333.149203 -429.983899) (xy 333.163414 -429.96436) (xy 333.182967 -429.950168) (xy 333.205948 -429.942712)
			(xy 333.218028 -429.942244) (xy 334.157828 -429.942244) (xy 334.169899 -429.942739) (xy 334.192859 -429.950204)
			(xy 334.212392 -429.964394) (xy 334.226587 -429.983923) (xy 334.234058 -430.006881) (xy 334.234536 -430.018952)
			(xy 334.234536 -431.560478) (xy 335.141316 -431.560478) (xy 335.141316 -429.018954) (xy 335.141768 -429.006864)
			(xy 335.149234 -428.983866) (xy 335.163426 -428.964289) (xy 335.18296 -428.950039) (xy 335.205936 -428.942504)
			(xy 335.218024 -428.941992) (xy 336.157824 -428.941992) (xy 336.169933 -428.942396) (xy 336.19296 -428.949901)
			(xy 336.207549 -428.960534) (xy 337.141312 -428.960534) (xy 337.141312 -426.41901) (xy 337.141815 -426.406924)
			(xy 337.149266 -426.383928) (xy 337.163444 -426.364351) (xy 337.182968 -426.350099) (xy 337.205936 -426.342562)
			(xy 337.21802 -426.342048) (xy 338.15782 -426.342048) (xy 338.169925 -426.342499) (xy 338.192944 -426.349997)
			(xy 338.212512 -426.364252) (xy 338.226708 -426.383863) (xy 338.234137 -426.406904) (xy 338.234528 -426.41901)
			(xy 338.234528 -427.960536) (xy 339.141308 -427.960536) (xy 339.141308 -425.419012) (xy 339.141723 -425.406928)
			(xy 339.149189 -425.383943) (xy 339.163394 -425.364392) (xy 339.182947 -425.350188) (xy 339.205932 -425.342723)
			(xy 339.218016 -425.342304) (xy 340.157816 -425.342304) (xy 340.169893 -425.342751) (xy 340.192862 -425.350219)
			(xy 340.2124 -425.36442) (xy 340.226594 -425.383963) (xy 340.234053 -425.406935) (xy 340.234524 -425.419012)
			(xy 340.234524 -427.960536) (xy 340.234067 -427.972611) (xy 340.226596 -427.995577) (xy 340.212397 -428.015112)
			(xy 340.192859 -428.029306) (xy 340.169891 -428.03677) (xy 340.157816 -428.037244) (xy 339.218016 -428.037244)
			(xy 339.205946 -428.036723) (xy 339.182985 -428.029269) (xy 339.163451 -428.015086) (xy 339.149255 -427.995561)
			(xy 339.141785 -427.972606) (xy 339.141308 -427.960536) (xy 338.234528 -427.960536) (xy 338.234528 -428.960534)
			(xy 338.234121 -428.972629) (xy 338.226651 -428.995636) (xy 338.21245 -429.015218) (xy 338.192902 -429.029466)
			(xy 338.169913 -429.036992) (xy 338.15782 -429.037496) (xy 337.21802 -429.037496) (xy 337.205912 -429.037066)
			(xy 337.182885 -429.029572) (xy 337.163311 -429.015314) (xy 337.149116 -428.995695) (xy 337.141695 -428.972643)
			(xy 337.141312 -428.960534) (xy 336.207549 -428.960534) (xy 336.212532 -428.964166) (xy 336.226726 -428.983789)
			(xy 336.234148 -429.006843) (xy 336.234532 -429.018954) (xy 336.234532 -431.560478) (xy 336.234073 -431.572569)
			(xy 336.226619 -431.595574) (xy 336.212432 -431.615156) (xy 336.192894 -431.629407) (xy 336.169914 -431.636934)
			(xy 336.157824 -431.63744) (xy 335.218024 -431.63744) (xy 335.20592 -431.636964) (xy 335.182901 -431.629476)
			(xy 335.163331 -431.615228) (xy 335.149134 -431.595622) (xy 335.141705 -431.572583) (xy 335.141316 -431.560478)
			(xy 334.234536 -431.560478) (xy 334.234536 -432.560476) (xy 334.234016 -432.572547) (xy 334.226563 -432.595508)
			(xy 334.21238 -432.615043) (xy 334.192855 -432.62924) (xy 334.169898 -432.636708) (xy 334.157828 -432.637184)
			(xy 333.218028 -432.637184) (xy 333.205944 -432.636763) (xy 333.182959 -432.6293) (xy 333.163406 -432.615097)
			(xy 333.149202 -432.595545) (xy 333.141738 -432.57256) (xy 333.14132 -432.560476) (xy 332.20714 -432.560476)
			(xy 332.212412 -432.564308) (xy 332.226605 -432.58385) (xy 332.234068 -432.60682) (xy 332.23454 -432.618896)
			(xy 332.23454 -435.16042) (xy 332.234053 -435.172492) (xy 332.226589 -435.195455) (xy 332.212397 -435.214989)
			(xy 332.192865 -435.229184) (xy 332.169904 -435.236651) (xy 332.157832 -435.237128) (xy 331.218032 -435.237128)
			(xy 331.205953 -435.23666) (xy 331.182975 -435.229204) (xy 331.163426 -435.215011) (xy 331.14922 -435.195472)
			(xy 331.141748 -435.172499) (xy 331.141324 -435.16042) (xy 329.2348 -435.16042) (xy 329.2348 -436.160418)
			(xy 329.234304 -436.17253) (xy 329.226817 -436.195567) (xy 329.21258 -436.215165) (xy 329.192985 -436.229408)
			(xy 329.16995 -436.236901) (xy 329.157838 -436.23738) (xy 328.218038 -436.23738) (xy 328.205919 -436.236908)
			(xy 328.182864 -436.229428) (xy 328.16325 -436.21519) (xy 328.148997 -436.195586) (xy 328.141501 -436.172537)
			(xy 328.141076 -436.160418) (xy 327.206971 -436.160418) (xy 327.212531 -436.164451) (xy 327.226778 -436.184004)
			(xy 327.234301 -436.206997) (xy 327.234804 -436.219092) (xy 327.234804 -438.760616) (xy 327.234354 -438.772667)
			(xy 327.226917 -438.795592) (xy 327.212774 -438.815107) (xy 327.193302 -438.82931) (xy 327.170399 -438.836816)
			(xy 327.15835 -438.837324) (xy 326.218042 -438.837324) (xy 326.205951 -438.836856) (xy 326.182946 -438.829407)
			(xy 326.163362 -438.815222) (xy 326.149111 -438.795686) (xy 326.141585 -438.772705) (xy 326.14108 -438.760616)
			(xy 325.234808 -438.760616) (xy 325.234808 -439.760614) (xy 328.141076 -439.760614) (xy 328.141076 -437.21909)
			(xy 328.141452 -437.206963) (xy 328.148952 -437.183897) (xy 328.163213 -437.164279) (xy 328.18284 -437.15003)
			(xy 328.205911 -437.142545) (xy 328.218038 -437.142128) (xy 329.157838 -437.142128) (xy 329.169954 -437.142579)
			(xy 329.192996 -437.150076) (xy 329.212597 -437.164323) (xy 329.226837 -437.183929) (xy 329.234325 -437.206974)
			(xy 329.2348 -437.21909) (xy 329.2348 -438.760616) (xy 331.141324 -438.760616) (xy 331.141324 -436.219092)
			(xy 331.141706 -436.207006) (xy 331.14918 -436.184017) (xy 331.163393 -436.164464) (xy 331.182953 -436.150262)
			(xy 331.205945 -436.1428) (xy 331.218032 -436.142384) (xy 332.157832 -436.142384) (xy 332.169907 -436.142837)
			(xy 332.192874 -436.150307) (xy 332.206784 -436.160418) (xy 333.14132 -436.160418) (xy 333.14132 -433.618894)
			(xy 333.141802 -433.606806) (xy 333.149258 -433.583809) (xy 333.163441 -433.564231) (xy 333.18297 -433.54998)
			(xy 333.205942 -433.542444) (xy 333.218028 -433.541932) (xy 334.157828 -433.541932) (xy 334.169942 -433.542293)
			(xy 334.192975 -433.549804) (xy 334.212551 -433.564079) (xy 334.226743 -433.583714) (xy 334.234157 -433.606779)
			(xy 334.234536 -433.618894) (xy 334.234536 -435.16042) (xy 335.141316 -435.16042) (xy 335.141316 -432.618896)
			(xy 335.141709 -432.606811) (xy 335.149181 -432.583824) (xy 335.163391 -432.564271) (xy 335.182949 -432.550068)
			(xy 335.205938 -432.542605) (xy 335.218024 -432.542188) (xy 336.157824 -432.542188) (xy 336.169899 -432.542644)
			(xy 336.192867 -432.550113) (xy 336.207126 -432.560476) (xy 337.141312 -432.560476) (xy 337.141312 -430.018952)
			(xy 337.141724 -430.006873) (xy 337.149202 -429.983901) (xy 337.163411 -429.964363) (xy 337.182962 -429.950171)
			(xy 337.205941 -429.942713) (xy 337.21802 -429.942244) (xy 338.15782 -429.942244) (xy 338.169891 -429.942747)
			(xy 338.19285 -429.950209) (xy 338.212383 -429.964397) (xy 338.226578 -429.983924) (xy 338.234049 -430.006881)
			(xy 338.234528 -430.018952) (xy 338.234528 -431.560478) (xy 339.141308 -431.560478) (xy 339.141308 -429.018954)
			(xy 339.141768 -429.006865) (xy 339.149233 -428.983868) (xy 339.163423 -428.964292) (xy 339.182955 -428.950042)
			(xy 339.205929 -428.942505) (xy 339.218016 -428.941992) (xy 340.157816 -428.941992) (xy 340.169925 -428.942402)
			(xy 340.192951 -428.949905) (xy 340.207536 -428.960534) (xy 341.141304 -428.960534) (xy 341.141304 -426.41901)
			(xy 341.141815 -426.406925) (xy 341.149265 -426.38393) (xy 341.163441 -426.364353) (xy 341.182963 -426.350101)
			(xy 341.205928 -426.342563) (xy 341.218012 -426.342048) (xy 342.157812 -426.342048) (xy 342.169916 -426.342505)
			(xy 342.192935 -426.350002) (xy 342.212504 -426.364255) (xy 342.2267 -426.383864) (xy 342.234129 -426.406905)
			(xy 342.23452 -426.41901) (xy 342.23452 -427.960536) (xy 343.1413 -427.960536) (xy 343.1413 -425.419012)
			(xy 343.141723 -425.406929) (xy 343.149188 -425.383946) (xy 343.163392 -425.364394) (xy 343.182942 -425.35019)
			(xy 343.205925 -425.342724) (xy 343.218008 -425.342304) (xy 344.157808 -425.342304) (xy 344.169892 -425.342706)
			(xy 344.192877 -425.350177) (xy 344.212429 -425.364386) (xy 344.226632 -425.383941) (xy 344.234097 -425.406928)
			(xy 344.234516 -425.419012) (xy 344.234516 -427.960536) (xy 344.234067 -427.972612) (xy 344.226595 -427.995579)
			(xy 344.212395 -428.015115) (xy 344.192854 -428.029308) (xy 344.169884 -428.036771) (xy 344.157808 -428.037244)
			(xy 343.218008 -428.037244) (xy 343.205937 -428.03673) (xy 343.182977 -428.029274) (xy 343.163443 -428.015089)
			(xy 343.149247 -427.995563) (xy 343.141777 -427.972606) (xy 343.1413 -427.960536) (xy 342.23452 -427.960536)
			(xy 342.23452 -428.960534) (xy 342.234121 -428.972629) (xy 342.22665 -428.995638) (xy 342.212447 -429.015221)
			(xy 342.192897 -429.029469) (xy 342.169906 -429.036993) (xy 342.157812 -429.037496) (xy 341.218012 -429.037496)
			(xy 341.205903 -429.037073) (xy 341.182876 -429.029577) (xy 341.163302 -429.015317) (xy 341.149107 -428.995696)
			(xy 341.141687 -428.972644) (xy 341.141304 -428.960534) (xy 340.207536 -428.960534) (xy 340.212524 -428.964169)
			(xy 340.226718 -428.983791) (xy 340.23414 -429.006844) (xy 340.234524 -429.018954) (xy 340.234524 -431.560478)
			(xy 340.234073 -431.57257) (xy 340.226618 -431.595576) (xy 340.212429 -431.615159) (xy 340.192889 -431.629409)
			(xy 340.169906 -431.636935) (xy 340.157816 -431.63744) (xy 339.218016 -431.63744) (xy 339.205912 -431.63697)
			(xy 339.182892 -431.62948) (xy 339.163322 -431.615231) (xy 339.149126 -431.595623) (xy 339.141697 -431.572583)
			(xy 339.141308 -431.560478) (xy 338.234528 -431.560478) (xy 338.234528 -432.560476) (xy 338.234067 -432.572555)
			(xy 338.226609 -432.595534) (xy 338.212414 -432.615083) (xy 338.192873 -432.629288) (xy 338.169899 -432.63676)
			(xy 338.15782 -432.637184) (xy 337.21802 -432.637184) (xy 337.205936 -432.63677) (xy 337.18295 -432.629305)
			(xy 337.163397 -432.6151) (xy 337.149193 -432.595547) (xy 337.14173 -432.57256) (xy 337.141312 -432.560476)
			(xy 336.207126 -432.560476) (xy 336.212403 -432.564311) (xy 336.226597 -432.583851) (xy 336.234059 -432.606821)
			(xy 336.234532 -432.618896) (xy 336.234532 -435.16042) (xy 336.234053 -435.172493) (xy 336.226588 -435.195457)
			(xy 336.212394 -435.214991) (xy 336.19286 -435.229186) (xy 336.169897 -435.236652) (xy 336.157824 -435.237128)
			(xy 335.218024 -435.237128) (xy 335.205945 -435.236667) (xy 335.182966 -435.229209) (xy 335.163417 -435.215014)
			(xy 335.149212 -435.195473) (xy 335.14174 -435.172499) (xy 335.141316 -435.16042) (xy 334.234536 -435.16042)
			(xy 334.234536 -436.160418) (xy 334.234108 -436.172511) (xy 334.226643 -436.195516) (xy 334.212447 -436.215098)
			(xy 334.192904 -436.229347) (xy 334.16992 -436.236874) (xy 334.157828 -436.23738) (xy 333.218028 -436.23738)
			(xy 333.205919 -436.236959) (xy 333.182889 -436.229465) (xy 333.163314 -436.215206) (xy 333.149119 -436.195583)
			(xy 333.141701 -436.172529) (xy 333.14132 -436.160418) (xy 332.206784 -436.160418) (xy 332.21241 -436.164507)
			(xy 332.226604 -436.184047) (xy 332.234067 -436.207016) (xy 332.23454 -436.219092) (xy 332.23454 -438.760616)
			(xy 332.23405 -438.772688) (xy 332.226587 -438.79565) (xy 332.212396 -438.815184) (xy 332.192865 -438.829379)
			(xy 332.169904 -438.836847) (xy 332.157832 -438.837324) (xy 331.218032 -438.837324) (xy 331.205953 -438.83686)
			(xy 331.182974 -438.829403) (xy 331.163424 -438.81521) (xy 331.149218 -438.795669) (xy 331.141747 -438.772695)
			(xy 331.141324 -438.760616) (xy 329.2348 -438.760616) (xy 329.2348 -439.760614) (xy 333.14132 -439.760614)
			(xy 333.14132 -437.21909) (xy 333.141799 -437.207002) (xy 333.149256 -437.184004) (xy 333.16344 -437.164426)
			(xy 333.18297 -437.150176) (xy 333.205942 -437.14264) (xy 333.218028 -437.142128) (xy 334.157828 -437.142128)
			(xy 334.169941 -437.142493) (xy 334.192974 -437.150003) (xy 334.212549 -437.164277) (xy 334.226742 -437.183911)
			(xy 334.234157 -437.206975) (xy 334.234536 -437.21909) (xy 334.234536 -438.760616) (xy 335.141316 -438.760616)
			(xy 335.141316 -436.219092) (xy 335.141706 -436.207006) (xy 335.149179 -436.184019) (xy 335.16339 -436.164467)
			(xy 335.182948 -436.150264) (xy 335.205938 -436.142801) (xy 335.218024 -436.142384) (xy 336.157824 -436.142384)
			(xy 336.169899 -436.142844) (xy 336.192866 -436.150312) (xy 336.206771 -436.160418) (xy 337.141312 -436.160418)
			(xy 337.141312 -433.618894) (xy 337.141802 -433.606807) (xy 337.149257 -433.583811) (xy 337.163439 -433.564234)
			(xy 337.182965 -433.549982) (xy 337.205935 -433.542445) (xy 337.21802 -433.541932) (xy 338.15782 -433.541932)
			(xy 338.169933 -433.5423) (xy 338.192967 -433.549808) (xy 338.212542 -433.564081) (xy 338.226735 -433.583715)
			(xy 338.234149 -433.606779) (xy 338.234528 -433.618894) (xy 338.234528 -435.16042) (xy 339.141308 -435.16042)
			(xy 339.141308 -432.618896) (xy 339.141709 -432.606811) (xy 339.14918 -432.583826) (xy 339.163388 -432.564274)
			(xy 339.182944 -432.550071) (xy 339.205931 -432.542606) (xy 339.218016 -432.542188) (xy 340.157816 -432.542188)
			(xy 340.169891 -432.542651) (xy 340.192858 -432.550117) (xy 340.207113 -432.560476) (xy 341.141304 -432.560476)
			(xy 341.141304 -430.018952) (xy 341.141723 -430.006874) (xy 341.149201 -429.983903) (xy 341.163408 -429.964366)
			(xy 341.182957 -429.950173) (xy 341.205933 -429.942714) (xy 341.218012 -429.942244) (xy 342.157812 -429.942244)
			(xy 342.169882 -429.942753) (xy 342.192842 -429.950213) (xy 342.212374 -429.9644) (xy 342.22657 -429.983926)
			(xy 342.234041 -430.006882) (xy 342.23452 -430.018952) (xy 342.23452 -431.560478) (xy 343.1413 -431.560478)
			(xy 343.1413 -429.018954) (xy 343.141767 -429.006866) (xy 343.149232 -428.983871) (xy 343.16342 -428.964295)
			(xy 343.18295 -428.950044) (xy 343.205922 -428.942507) (xy 343.218008 -428.941992) (xy 344.157808 -428.941992)
			(xy 344.169917 -428.942409) (xy 344.192943 -428.94991) (xy 344.207523 -428.960534) (xy 345.141296 -428.960534)
			(xy 345.141296 -426.41901) (xy 345.141815 -426.406925) (xy 345.149264 -426.383932) (xy 345.163439 -426.364356)
			(xy 345.182958 -426.350104) (xy 345.205921 -426.342564) (xy 345.218004 -426.342048) (xy 346.157804 -426.342048)
			(xy 346.169908 -426.342512) (xy 346.192927 -426.350006) (xy 346.212495 -426.364257) (xy 346.226691 -426.383866)
			(xy 346.234121 -426.406905) (xy 346.234512 -426.41901) (xy 346.234512 -428.960534) (xy 346.234121 -428.97263)
			(xy 346.226649 -428.99564) (xy 346.212444 -429.015223) (xy 346.192892 -429.029471) (xy 346.169899 -429.036994)
			(xy 346.157804 -429.037496) (xy 345.218004 -429.037496) (xy 345.205895 -429.03708) (xy 345.182867 -429.029582)
			(xy 345.163293 -429.01532) (xy 345.149099 -428.995698) (xy 345.141679 -428.972644) (xy 345.141296 -428.960534)
			(xy 344.207523 -428.960534) (xy 344.212515 -428.964172) (xy 344.22671 -428.983792) (xy 344.234132 -429.006844)
			(xy 344.234516 -429.018954) (xy 344.234516 -431.560478) (xy 344.234073 -431.572571) (xy 344.226617 -431.595578)
			(xy 344.212426 -431.615162) (xy 344.192884 -431.629412) (xy 344.169899 -431.636937) (xy 344.157808 -431.63744)
			(xy 343.218008 -431.63744) (xy 343.205904 -431.636978) (xy 343.182883 -431.629485) (xy 343.163313 -431.615234)
			(xy 343.149117 -431.595625) (xy 343.141689 -431.572584) (xy 343.1413 -431.560478) (xy 342.23452 -431.560478)
			(xy 342.23452 -432.560476) (xy 342.234067 -432.572556) (xy 342.226607 -432.595536) (xy 342.212411 -432.615086)
			(xy 342.192868 -432.629291) (xy 342.169892 -432.636761) (xy 342.157812 -432.637184) (xy 341.218012 -432.637184)
			(xy 341.205928 -432.636777) (xy 341.182941 -432.629309) (xy 341.163389 -432.615103) (xy 341.149185 -432.595548)
			(xy 341.141722 -432.572561) (xy 341.141304 -432.560476) (xy 340.207113 -432.560476) (xy 340.212394 -432.564314)
			(xy 340.226588 -432.583853) (xy 340.234051 -432.606821) (xy 340.234524 -432.618896) (xy 340.234524 -435.16042)
			(xy 340.234053 -435.172494) (xy 340.226587 -435.195459) (xy 340.212391 -435.214994) (xy 340.192855 -435.229189)
			(xy 340.16989 -435.236654) (xy 340.157816 -435.237128) (xy 339.218016 -435.237128) (xy 339.205944 -435.236622)
			(xy 339.182981 -435.229167) (xy 339.163445 -435.21498) (xy 339.14925 -435.195451) (xy 339.141783 -435.172492)
			(xy 339.141308 -435.16042) (xy 338.234528 -435.16042) (xy 338.234528 -436.160418) (xy 338.234108 -436.172512)
			(xy 338.226642 -436.195518) (xy 338.212445 -436.215101) (xy 338.192899 -436.22935) (xy 338.169912 -436.236876)
			(xy 338.15782 -436.23738) (xy 337.21802 -436.23738) (xy 337.20591 -436.236966) (xy 337.18288 -436.22947)
			(xy 337.163305 -436.215208) (xy 337.149111 -436.195585) (xy 337.141693 -436.172529) (xy 337.141312 -436.160418)
			(xy 336.206771 -436.160418) (xy 336.212401 -436.16451) (xy 336.226595 -436.184049) (xy 336.234059 -436.207017)
			(xy 336.234532 -436.219092) (xy 336.234532 -438.760616) (xy 336.23405 -438.772689) (xy 336.226586 -438.795653)
			(xy 336.212393 -438.815187) (xy 336.19286 -438.829382) (xy 336.169897 -438.836848) (xy 336.157824 -438.837324)
			(xy 335.218024 -438.837324) (xy 335.205944 -438.836867) (xy 335.182965 -438.829408) (xy 335.163416 -438.815213)
			(xy 335.14921 -438.795671) (xy 335.141739 -438.772696) (xy 335.141316 -438.760616) (xy 334.234536 -438.760616)
			(xy 334.234536 -439.760614) (xy 337.141312 -439.760614) (xy 337.141312 -437.21909) (xy 337.141799 -437.207003)
			(xy 337.149255 -437.184007) (xy 337.163437 -437.164429) (xy 337.182965 -437.150178) (xy 337.205934 -437.142641)
			(xy 337.21802 -437.142128) (xy 338.15782 -437.142128) (xy 338.169933 -437.1425) (xy 338.192965 -437.150008)
			(xy 338.212541 -437.16428) (xy 338.226734 -437.183913) (xy 338.234149 -437.206976) (xy 338.234528 -437.21909)
			(xy 338.234528 -438.760616) (xy 339.141308 -438.760616) (xy 339.141308 -436.219092) (xy 339.141706 -436.207007)
			(xy 339.149178 -436.184021) (xy 339.163387 -436.16447) (xy 339.182943 -436.150267) (xy 339.205931 -436.142802)
			(xy 339.218016 -436.142384) (xy 340.157816 -436.142384) (xy 340.169891 -436.142851) (xy 340.192857 -436.150317)
			(xy 340.206758 -436.160418) (xy 341.141304 -436.160418) (xy 341.141304 -433.618894) (xy 341.141802 -433.606808)
			(xy 341.149256 -433.583813) (xy 341.163436 -433.564236) (xy 341.18296 -433.549985) (xy 341.205928 -433.542447)
			(xy 341.218012 -433.541932) (xy 342.157812 -433.541932) (xy 342.169925 -433.542306) (xy 342.192958 -433.549813)
			(xy 342.212534 -433.564084) (xy 342.226727 -433.583717) (xy 342.234141 -433.60678) (xy 342.23452 -433.618894)
			(xy 342.23452 -435.16042) (xy 343.1413 -435.16042) (xy 343.1413 -432.618896) (xy 343.141709 -432.606812)
			(xy 343.149179 -432.583828) (xy 343.163386 -432.564277) (xy 343.182939 -432.550073) (xy 343.205924 -432.542607)
			(xy 343.218008 -432.542188) (xy 344.157808 -432.542188) (xy 344.169883 -432.542657) (xy 344.192849 -432.550122)
			(xy 344.2071 -432.560476) (xy 345.141296 -432.560476) (xy 345.141296 -430.018952) (xy 345.141723 -430.006875)
			(xy 345.149199 -429.983905) (xy 345.163405 -429.964368) (xy 345.182952 -429.950176) (xy 345.205926 -429.942715)
			(xy 345.218004 -429.942244) (xy 346.157804 -429.942244) (xy 346.169874 -429.94276) (xy 346.192833 -429.950218)
			(xy 346.212366 -429.964403) (xy 346.226562 -429.983927) (xy 346.234033 -430.006882) (xy 346.234512 -430.018952)
			(xy 346.234512 -431.360072) (xy 355.888036 -431.360072) (xy 355.88854 -431.271581) (xy 355.896595 -431.094782)
			(xy 355.912689 -430.918533) (xy 355.936788 -430.743199) (xy 355.968842 -430.569144) (xy 356.008786 -430.396728)
			(xy 356.056535 -430.226308) (xy 356.111991 -430.058239) (xy 356.17504 -429.892868) (xy 356.24555 -429.730538)
			(xy 356.323375 -429.571585) (xy 356.408354 -429.416339) (xy 356.500311 -429.265122) (xy 356.599056 -429.118247)
			(xy 356.704383 -428.976019) (xy 356.816074 -428.838732) (xy 356.933898 -428.70667) (xy 357.057611 -428.580108)
			(xy 357.186956 -428.459309) (xy 357.321665 -428.344521) (xy 357.461459 -428.235984) (xy 357.606049 -428.133922)
			(xy 357.755133 -428.038546) (xy 357.908404 -427.950055) (xy 358.065544 -427.868632) (xy 358.226228 -427.794445)
			(xy 358.390121 -427.727648) (xy 358.556884 -427.66838) (xy 358.726172 -427.616764) (xy 358.897634 -427.572907)
			(xy 359.070915 -427.536899) (xy 359.245655 -427.508815) (xy 359.421492 -427.488713) (xy 359.598062 -427.476635)
			(xy 359.774998 -427.472607) (xy 359.951934 -427.476635) (xy 360.128504 -427.488713) (xy 360.304341 -427.508815)
			(xy 360.479081 -427.536899) (xy 360.652362 -427.572907) (xy 360.823824 -427.616764) (xy 360.993112 -427.66838)
			(xy 361.159875 -427.727648) (xy 361.323768 -427.794445) (xy 361.484452 -427.868632) (xy 361.641592 -427.950055)
			(xy 361.659746 -427.960536) (xy 381.2413 -427.960536) (xy 381.2413 -425.419012) (xy 381.241723 -425.406929)
			(xy 381.249188 -425.383946) (xy 381.263392 -425.364394) (xy 381.282942 -425.35019) (xy 381.305925 -425.342724)
			(xy 381.318008 -425.342304) (xy 382.257808 -425.342304) (xy 382.269892 -425.342706) (xy 382.292877 -425.350177)
			(xy 382.312429 -425.364386) (xy 382.326632 -425.383941) (xy 382.334097 -425.406928) (xy 382.334516 -425.419012)
			(xy 382.334516 -427.960536) (xy 382.334067 -427.972612) (xy 382.326595 -427.995579) (xy 382.312395 -428.015115)
			(xy 382.292854 -428.029308) (xy 382.269884 -428.036771) (xy 382.257808 -428.037244) (xy 381.318008 -428.037244)
			(xy 381.305937 -428.03673) (xy 381.282977 -428.029274) (xy 381.263443 -428.015089) (xy 381.249247 -427.995563)
			(xy 381.241777 -427.972606) (xy 381.2413 -427.960536) (xy 361.659746 -427.960536) (xy 361.794863 -428.038546)
			(xy 361.943947 -428.133922) (xy 362.088537 -428.235984) (xy 362.228331 -428.344521) (xy 362.36304 -428.459309)
			(xy 362.492385 -428.580108) (xy 362.616098 -428.70667) (xy 362.733922 -428.838732) (xy 362.845613 -428.976019)
			(xy 362.95094 -429.118247) (xy 363.049685 -429.265122) (xy 363.141642 -429.416339) (xy 363.226621 -429.571585)
			(xy 363.304446 -429.730538) (xy 363.374956 -429.892868) (xy 363.438005 -430.058239) (xy 363.493461 -430.226308)
			(xy 363.54121 -430.396728) (xy 363.581154 -430.569144) (xy 363.613208 -430.743199) (xy 363.637307 -430.918533)
			(xy 363.653401 -431.094782) (xy 363.661456 -431.271581) (xy 363.66196 -431.360072) (xy 363.661504 -431.447087)
			(xy 363.653716 -431.620943) (xy 363.638154 -431.794276) (xy 363.614849 -431.966739) (xy 363.583849 -432.137985)
			(xy 363.545214 -432.307673) (xy 363.499024 -432.475461) (xy 363.445369 -432.641014) (xy 363.384358 -432.803999)
			(xy 363.316114 -432.96409) (xy 363.240772 -433.120966) (xy 363.158484 -433.274313) (xy 363.069415 -433.423823)
			(xy 362.973744 -433.569196) (xy 362.871661 -433.710142) (xy 362.763372 -433.846377) (xy 362.649094 -433.977629)
			(xy 362.529056 -434.103634) (xy 362.403498 -434.22414) (xy 362.272672 -434.338905) (xy 362.136841 -434.4477)
			(xy 361.996276 -434.550306) (xy 361.851259 -434.646518) (xy 361.702082 -434.736142) (xy 361.549042 -434.819)
			(xy 361.470956 -434.857398) (xy 361.460288 -434.862478) (xy 361.44581 -434.881274) (xy 361.424982 -434.984398)
			(xy 361.431332 -435.007258) (xy 361.439206 -435.016148) (xy 361.483334 -435.066765) (xy 361.566156 -435.172484)
			(xy 361.642445 -435.28301) (xy 361.711923 -435.397939) (xy 361.774337 -435.516853) (xy 361.829459 -435.639318)
			(xy 361.877088 -435.764887) (xy 361.91705 -435.893102) (xy 361.949199 -436.023495) (xy 361.973419 -436.155591)
			(xy 361.98962 -436.288909) (xy 361.997745 -436.422961) (xy 361.99826 -436.49011) (xy 361.997753 -436.557275)
			(xy 361.989642 -436.691359) (xy 361.973451 -436.824708) (xy 361.949237 -436.956837) (xy 361.91709 -437.087263)
			(xy 361.877127 -437.21551) (xy 361.829493 -437.34111) (xy 361.774363 -437.463604) (xy 361.711937 -437.582547)
			(xy 361.642443 -437.697503) (xy 361.566136 -437.808054) (xy 361.483292 -437.913796) (xy 361.394216 -438.014343)
			(xy 361.299231 -438.109328) (xy 361.198684 -438.198404) (xy 361.092942 -438.281248) (xy 360.982391 -438.357555)
			(xy 360.867435 -438.427049) (xy 360.748492 -438.489475) (xy 360.625998 -438.544605) (xy 360.500398 -438.592239)
			(xy 360.372151 -438.632202) (xy 360.241725 -438.664349) (xy 360.109596 -438.688563) (xy 359.976247 -438.704754)
			(xy 359.842163 -438.712865) (xy 359.707833 -438.712865) (xy 359.573749 -438.704754) (xy 359.4404 -438.688563)
			(xy 359.308271 -438.664349) (xy 359.177845 -438.632202) (xy 359.049598 -438.592239) (xy 358.923998 -438.544605)
			(xy 358.801504 -438.489475) (xy 358.682561 -438.427049) (xy 358.567605 -438.357555) (xy 358.457054 -438.281248)
			(xy 358.351312 -438.198404) (xy 358.250765 -438.109328) (xy 358.15578 -438.014343) (xy 358.066704 -437.913796)
			(xy 357.98386 -437.808054) (xy 357.907553 -437.697503) (xy 357.838059 -437.582547) (xy 357.775633 -437.463604)
			(xy 357.720503 -437.34111) (xy 357.672869 -437.21551) (xy 357.632906 -437.087263) (xy 357.600759 -436.956837)
			(xy 357.576545 -436.824708) (xy 357.560354 -436.691359) (xy 357.552243 -436.557275) (xy 357.551736 -436.49011)
			(xy 357.552226 -436.42296) (xy 357.560351 -436.288906) (xy 357.576553 -436.155587) (xy 357.600772 -436.02349)
			(xy 357.632922 -435.893095) (xy 357.672885 -435.764878) (xy 357.720514 -435.639308) (xy 357.775636 -435.516842)
			(xy 357.838051 -435.397927) (xy 357.90753 -435.282996) (xy 357.98382 -435.172468) (xy 358.066642 -435.066748)
			(xy 358.11079 -435.016148) (xy 358.118664 -435.007258) (xy 358.125014 -434.984398) (xy 358.104186 -434.881274)
			(xy 358.089708 -434.862478) (xy 358.07904 -434.857398) (xy 358.000981 -434.818946) (xy 357.847945 -434.736088)
			(xy 357.698771 -434.646463) (xy 357.553757 -434.550252) (xy 357.413195 -434.447647) (xy 357.277366 -434.338853)
			(xy 357.146543 -434.224088) (xy 357.020987 -434.103584) (xy 356.90095 -433.977581) (xy 356.786674 -433.846331)
			(xy 356.678386 -433.710098) (xy 356.576305 -433.569155) (xy 356.480633 -433.423784) (xy 356.391565 -433.274278)
			(xy 356.309277 -433.120934) (xy 356.233934 -432.964061) (xy 356.165689 -432.803973) (xy 356.104677 -432.640991)
			(xy 356.051021 -432.475441) (xy 356.004828 -432.307656) (xy 355.966191 -432.137972) (xy 355.935188 -431.966728)
			(xy 355.91188 -431.794269) (xy 355.896314 -431.620939) (xy 355.888522 -431.447086) (xy 355.888036 -431.360072)
			(xy 346.234512 -431.360072) (xy 346.234512 -432.560476) (xy 346.234067 -432.572557) (xy 346.226606 -432.595538)
			(xy 346.212409 -432.615089) (xy 346.192863 -432.629294) (xy 346.169885 -432.636762) (xy 346.157804 -432.637184)
			(xy 345.218004 -432.637184) (xy 345.205919 -432.636784) (xy 345.182932 -432.629314) (xy 345.16338 -432.615106)
			(xy 345.149176 -432.59555) (xy 345.141713 -432.572561) (xy 345.141296 -432.560476) (xy 344.2071 -432.560476)
			(xy 344.212386 -432.564317) (xy 344.22658 -432.583854) (xy 344.234043 -432.606821) (xy 344.234516 -432.618896)
			(xy 344.234516 -435.16042) (xy 344.234053 -435.172495) (xy 344.226586 -435.195461) (xy 344.212389 -435.214997)
			(xy 344.19285 -435.229191) (xy 344.169883 -435.236655) (xy 344.157808 -435.237128) (xy 343.218008 -435.237128)
			(xy 343.205936 -435.236629) (xy 343.182972 -435.229171) (xy 343.163437 -435.214983) (xy 343.149241 -435.195453)
			(xy 343.141775 -435.172492) (xy 343.1413 -435.16042) (xy 342.23452 -435.16042) (xy 342.23452 -436.160418)
			(xy 342.234107 -436.172513) (xy 342.226641 -436.195521) (xy 342.212442 -436.215104) (xy 342.192894 -436.229352)
			(xy 342.169905 -436.236877) (xy 342.157812 -436.23738) (xy 341.218012 -436.23738) (xy 341.205902 -436.236973)
			(xy 341.182872 -436.229474) (xy 341.163297 -436.215211) (xy 341.149102 -436.195586) (xy 341.141685 -436.17253)
			(xy 341.141304 -436.160418) (xy 340.206758 -436.160418) (xy 340.212393 -436.164513) (xy 340.226587 -436.18405)
			(xy 340.234051 -436.207017) (xy 340.234524 -436.219092) (xy 340.234524 -438.760616) (xy 340.23405 -438.77269)
			(xy 340.226585 -438.795655) (xy 340.21239 -438.81519) (xy 340.192855 -438.829385) (xy 340.16989 -438.83685)
			(xy 340.157816 -438.837324) (xy 339.218016 -438.837324) (xy 339.205944 -438.836822) (xy 339.18298 -438.829366)
			(xy 339.163444 -438.815179) (xy 339.149248 -438.795649) (xy 339.141783 -438.772688) (xy 339.141308 -438.760616)
			(xy 338.234528 -438.760616) (xy 338.234528 -439.760614) (xy 341.141304 -439.760614) (xy 341.141304 -437.21909)
			(xy 341.141798 -437.207004) (xy 341.149253 -437.184009) (xy 341.163434 -437.164432) (xy 341.18296 -437.150181)
			(xy 341.205927 -437.142643) (xy 341.218012 -437.142128) (xy 342.157812 -437.142128) (xy 342.169924 -437.142506)
			(xy 342.192957 -437.150012) (xy 342.212532 -437.164283) (xy 342.226725 -437.183914) (xy 342.234141 -437.206976)
			(xy 342.23452 -437.21909) (xy 342.23452 -438.760616) (xy 343.1413 -438.760616) (xy 343.1413 -436.219092)
			(xy 343.141758 -436.207016) (xy 343.149223 -436.184047) (xy 343.163421 -436.16451) (xy 343.182962 -436.150316)
			(xy 343.205932 -436.142855) (xy 343.218008 -436.142384) (xy 344.157808 -436.142384) (xy 344.169882 -436.142857)
			(xy 344.192848 -436.150321) (xy 344.206744 -436.160418) (xy 345.141296 -436.160418) (xy 345.141296 -433.618894)
			(xy 345.141802 -433.606809) (xy 345.149255 -433.583815) (xy 345.163433 -433.564239) (xy 345.182955 -433.549987)
			(xy 345.20592 -433.542448) (xy 345.218004 -433.541932) (xy 346.157804 -433.541932) (xy 346.169916 -433.542313)
			(xy 346.192949 -433.549818) (xy 346.212525 -433.564087) (xy 346.226718 -433.583718) (xy 346.234133 -433.60678)
			(xy 346.234512 -433.618894) (xy 346.234512 -436.160418) (xy 346.234107 -436.172513) (xy 346.22664 -436.195523)
			(xy 346.212439 -436.215106) (xy 346.192889 -436.229355) (xy 346.169898 -436.236878) (xy 346.157804 -436.23738)
			(xy 345.218004 -436.23738) (xy 345.205893 -436.23698) (xy 345.182863 -436.229479) (xy 345.163288 -436.215214)
			(xy 345.149094 -436.195588) (xy 345.141676 -436.17253) (xy 345.141296 -436.160418) (xy 344.206744 -436.160418)
			(xy 344.212384 -436.164516) (xy 344.226579 -436.184052) (xy 344.234043 -436.207018) (xy 344.234516 -436.219092)
			(xy 344.234516 -438.760616) (xy 344.234049 -438.772691) (xy 344.226583 -438.795657) (xy 344.212387 -438.815193)
			(xy 344.19285 -438.829387) (xy 344.169883 -438.836851) (xy 344.157808 -438.837324) (xy 343.218008 -438.837324)
			(xy 343.205935 -438.836829) (xy 343.182971 -438.829371) (xy 343.163435 -438.815182) (xy 343.14924 -438.79565)
			(xy 343.141775 -438.772688) (xy 343.1413 -438.760616) (xy 342.23452 -438.760616) (xy 342.23452 -439.760614)
			(xy 345.141296 -439.760614) (xy 345.141296 -437.21909) (xy 345.141798 -437.207004) (xy 345.149252 -437.184011)
			(xy 345.163431 -437.164435) (xy 345.182955 -437.150183) (xy 345.20592 -437.142644) (xy 345.218004 -437.142128)
			(xy 346.157804 -437.142128) (xy 346.169916 -437.142513) (xy 346.192948 -437.150017) (xy 346.212524 -437.164286)
			(xy 346.226717 -437.183916) (xy 346.234133 -437.206977) (xy 346.234512 -437.21909) (xy 346.234512 -439.760614)
			(xy 346.234104 -439.772709) (xy 346.226638 -439.795718) (xy 346.212437 -439.815302) (xy 346.192889 -439.829551)
			(xy 346.169898 -439.837074) (xy 346.157804 -439.837576) (xy 345.218004 -439.837576) (xy 345.205893 -439.83718)
			(xy 345.182862 -439.829679) (xy 345.163286 -439.815413) (xy 345.149092 -439.795785) (xy 345.141676 -439.772727)
			(xy 345.141296 -439.760614) (xy 342.23452 -439.760614) (xy 342.234104 -439.772708) (xy 342.226639 -439.795716)
			(xy 342.21244 -439.815299) (xy 342.192894 -439.829548) (xy 342.169905 -439.837073) (xy 342.157812 -439.837576)
			(xy 341.218012 -439.837576) (xy 341.205901 -439.837173) (xy 341.18287 -439.829674) (xy 341.163295 -439.81541)
			(xy 341.149101 -439.795784) (xy 341.141684 -439.772726) (xy 341.141304 -439.760614) (xy 338.234528 -439.760614)
			(xy 338.234104 -439.772708) (xy 338.22664 -439.795714) (xy 338.212443 -439.815297) (xy 338.192899 -439.829546)
			(xy 338.169912 -439.837072) (xy 338.15782 -439.837576) (xy 337.21802 -439.837576) (xy 337.20591 -439.837166)
			(xy 337.182879 -439.829669) (xy 337.163304 -439.815407) (xy 337.149109 -439.795782) (xy 337.141692 -439.772726)
			(xy 337.141312 -439.760614) (xy 334.234536 -439.760614) (xy 334.234104 -439.772707) (xy 334.226641 -439.795712)
			(xy 334.212446 -439.815294) (xy 334.192904 -439.829543) (xy 334.169919 -439.83707) (xy 334.157828 -439.837576)
			(xy 333.218028 -439.837576) (xy 333.205918 -439.837159) (xy 333.182888 -439.829665) (xy 333.163312 -439.815404)
			(xy 333.149117 -439.795781) (xy 333.1417 -439.772725) (xy 333.14132 -439.760614) (xy 329.2348 -439.760614)
			(xy 329.234301 -439.772726) (xy 329.226815 -439.795763) (xy 329.212578 -439.815361) (xy 329.192984 -439.829604)
			(xy 329.169949 -439.837097) (xy 329.157838 -439.837576) (xy 328.218038 -439.837576) (xy 328.205919 -439.837108)
			(xy 328.182863 -439.829628) (xy 328.163249 -439.815388) (xy 328.148996 -439.795783) (xy 328.1415 -439.772733)
			(xy 328.141076 -439.760614) (xy 325.234808 -439.760614) (xy 325.234301 -439.772725) (xy 325.226816 -439.795761)
			(xy 325.212581 -439.815358) (xy 325.192989 -439.829601) (xy 325.169957 -439.837096) (xy 325.157846 -439.837576)
			(xy 324.218046 -439.837576) (xy 324.205927 -439.837101) (xy 324.182872 -439.829623) (xy 324.163257 -439.815385)
			(xy 324.149004 -439.795782) (xy 324.141508 -439.772733) (xy 324.141084 -439.760614) (xy 321.234816 -439.760614)
			(xy 321.234451 -439.772742) (xy 321.226949 -439.795809) (xy 321.212685 -439.815428) (xy 321.193055 -439.829677)
			(xy 321.169982 -439.83716) (xy 321.157854 -439.837576) (xy 320.218054 -439.837576) (xy 320.205938 -439.837128)
			(xy 320.182896 -439.82963) (xy 320.163296 -439.815381) (xy 320.149056 -439.795775) (xy 320.141567 -439.77273)
			(xy 320.141092 -439.760614) (xy 317.234824 -439.760614) (xy 317.234451 -439.772741) (xy 317.22695 -439.795807)
			(xy 317.212688 -439.815425) (xy 317.19306 -439.829674) (xy 317.16999 -439.837159) (xy 317.157862 -439.837576)
			(xy 316.218062 -439.837576) (xy 316.205947 -439.837121) (xy 316.182905 -439.829625) (xy 316.163305 -439.815378)
			(xy 316.149064 -439.795774) (xy 316.141575 -439.772729) (xy 316.1411 -439.760614) (xy 296.787162 -439.760614)
			(xy 296.765145 -439.778249) (xy 296.600094 -439.900219) (xy 296.43042 -440.015672) (xy 296.25638 -440.124434)
			(xy 296.078239 -440.226339) (xy 295.98747 -440.274202) (xy 295.987216 -440.274202) (xy 295.977461 -440.280027)
			(xy 295.963872 -440.298199) (xy 295.959411 -440.320448) (xy 295.961562 -440.331606) (xy 295.985184 -440.427364)
			(xy 295.988489 -440.438171) (xy 296.002783 -440.455638) (xy 296.023175 -440.46531) (xy 296.03446 -440.465972)
			(xy 314.119006 -440.465972) (xy 314.120276 -440.465972) (xy 314.129194 -440.465406) (xy 314.145814 -440.458868)
			(xy 314.159188 -440.447031) (xy 314.167696 -440.431328) (xy 314.169298 -440.422538) (xy 314.169298 -440.422284)
			(xy 314.174196 -440.3911) (xy 314.191024 -440.330259) (xy 314.215602 -440.272116) (xy 314.247516 -440.217652)
			(xy 314.286225 -440.167789) (xy 314.331076 -440.123369) (xy 314.381311 -440.085143) (xy 314.43608 -440.053757)
			(xy 314.494458 -440.029741) (xy 314.555458 -440.013501) (xy 314.61805 -440.005312) (xy 314.681174 -440.005312)
			(xy 314.743766 -440.013501) (xy 314.804766 -440.029741) (xy 314.863144 -440.053757) (xy 314.917913 -440.085143)
			(xy 314.968148 -440.123369) (xy 315.012999 -440.167789) (xy 315.051708 -440.217652) (xy 315.083622 -440.272116)
			(xy 315.1082 -440.330259) (xy 315.125028 -440.3911) (xy 315.129926 -440.422284) (xy 315.129926 -440.422538)
			(xy 315.131556 -440.431325) (xy 315.140044 -440.447039) (xy 315.153409 -440.458886) (xy 315.170029 -440.465427)
			(xy 315.178948 -440.465972) (xy 318.118998 -440.465972) (xy 318.120268 -440.465972) (xy 318.129187 -440.465407)
			(xy 318.145809 -440.45887) (xy 318.159185 -440.447034) (xy 318.167695 -440.43133) (xy 318.16929 -440.422538)
			(xy 318.16929 -440.422284) (xy 318.174188 -440.3911) (xy 318.191016 -440.330259) (xy 318.215594 -440.272116)
			(xy 318.247508 -440.217652) (xy 318.286217 -440.167789) (xy 318.331068 -440.123369) (xy 318.381303 -440.085143)
			(xy 318.436072 -440.053757) (xy 318.49445 -440.029741) (xy 318.55545 -440.013501) (xy 318.618042 -440.005312)
			(xy 318.681166 -440.005312) (xy 318.743758 -440.013501) (xy 318.804758 -440.029741) (xy 318.863136 -440.053757)
			(xy 318.917905 -440.085143) (xy 318.96814 -440.123369) (xy 319.012991 -440.167789) (xy 319.0517 -440.217652)
			(xy 319.083614 -440.272116) (xy 319.108192 -440.330259) (xy 319.12502 -440.3911) (xy 319.129918 -440.422284)
			(xy 319.129918 -440.422538) (xy 319.131548 -440.431325) (xy 319.140036 -440.447041) (xy 319.153401 -440.45889)
			(xy 319.17002 -440.465433) (xy 319.17894 -440.465972) (xy 322.11899 -440.465972) (xy 322.12026 -440.465972)
			(xy 322.12918 -440.465408) (xy 322.145805 -440.458873) (xy 322.159183 -440.447036) (xy 322.167694 -440.431332)
			(xy 322.169282 -440.422538) (xy 322.169282 -440.422284) (xy 322.17418 -440.3911) (xy 322.191008 -440.330259)
			(xy 322.215586 -440.272116) (xy 322.2475 -440.217652) (xy 322.286209 -440.167789) (xy 322.33106 -440.123369)
			(xy 322.381295 -440.085143) (xy 322.436064 -440.053757) (xy 322.494442 -440.029741) (xy 322.555442 -440.013501)
			(xy 322.618034 -440.005312) (xy 322.681158 -440.005312) (xy 322.74375 -440.013501) (xy 322.80475 -440.029741)
			(xy 322.863128 -440.053757) (xy 322.917897 -440.085143) (xy 322.968132 -440.123369) (xy 323.012983 -440.167789)
			(xy 323.051692 -440.217652) (xy 323.083606 -440.272116) (xy 323.108184 -440.330259) (xy 323.125012 -440.3911)
			(xy 323.12991 -440.422284) (xy 323.12991 -440.422538) (xy 323.13154 -440.431326) (xy 323.140027 -440.447043)
			(xy 323.153392 -440.458894) (xy 323.170011 -440.46544) (xy 323.178932 -440.465972) (xy 326.118982 -440.465972)
			(xy 326.120252 -440.465972) (xy 326.129173 -440.46541) (xy 326.1458 -440.458876) (xy 326.15918 -440.447039)
			(xy 326.167693 -440.431334) (xy 326.169274 -440.422538) (xy 326.169274 -440.422284) (xy 326.174172 -440.3911)
			(xy 326.191 -440.330259) (xy 326.215578 -440.272116) (xy 326.247492 -440.217652) (xy 326.286201 -440.167789)
			(xy 326.331052 -440.123369) (xy 326.381287 -440.085143) (xy 326.436056 -440.053757) (xy 326.494434 -440.029741)
			(xy 326.555434 -440.013501) (xy 326.618026 -440.005312) (xy 326.68115 -440.005312) (xy 326.743742 -440.013501)
			(xy 326.804742 -440.029741) (xy 326.86312 -440.053757) (xy 326.917889 -440.085143) (xy 326.968124 -440.123369)
			(xy 327.012975 -440.167789) (xy 327.051684 -440.217652) (xy 327.083598 -440.272116) (xy 327.108176 -440.330259)
			(xy 327.125004 -440.3911) (xy 327.129902 -440.422284) (xy 327.129902 -440.422538) (xy 327.131532 -440.431326)
			(xy 327.140018 -440.447045) (xy 327.153383 -440.458898) (xy 327.170003 -440.465446) (xy 327.178924 -440.465972)
			(xy 331.119226 -440.465972) (xy 331.120496 -440.465972) (xy 331.129412 -440.465403) (xy 331.146026 -440.458861)
			(xy 331.159394 -440.447024) (xy 331.167898 -440.431323) (xy 331.169518 -440.422538) (xy 331.169518 -440.422284)
			(xy 331.174416 -440.3911) (xy 331.191244 -440.330259) (xy 331.215822 -440.272116) (xy 331.247736 -440.217652)
			(xy 331.286445 -440.167789) (xy 331.331296 -440.123369) (xy 331.381531 -440.085143) (xy 331.4363 -440.053757)
			(xy 331.494678 -440.029741) (xy 331.555678 -440.013501) (xy 331.61827 -440.005312) (xy 331.681394 -440.005312)
			(xy 331.743986 -440.013501) (xy 331.804986 -440.029741) (xy 331.863364 -440.053757) (xy 331.918133 -440.085143)
			(xy 331.968368 -440.123369) (xy 332.013219 -440.167789) (xy 332.051928 -440.217652) (xy 332.083842 -440.272116)
			(xy 332.10842 -440.330259) (xy 332.125248 -440.3911) (xy 332.130146 -440.422284) (xy 332.130146 -440.422538)
			(xy 332.131777 -440.431323) (xy 332.140265 -440.447034) (xy 332.153631 -440.458877) (xy 332.17025 -440.465411)
			(xy 332.179168 -440.465972) (xy 335.119218 -440.465972) (xy 335.120488 -440.465972) (xy 335.129405 -440.465404)
			(xy 335.146021 -440.458864) (xy 335.159391 -440.447026) (xy 335.167897 -440.431325) (xy 335.16951 -440.422538)
			(xy 335.16951 -440.422284) (xy 335.174408 -440.3911) (xy 335.191236 -440.330259) (xy 335.215814 -440.272116)
			(xy 335.247728 -440.217652) (xy 335.286437 -440.167789) (xy 335.331288 -440.123369) (xy 335.381523 -440.085143)
			(xy 335.436292 -440.053757) (xy 335.49467 -440.029741) (xy 335.55567 -440.013501) (xy 335.618262 -440.005312)
			(xy 335.681386 -440.005312) (xy 335.743978 -440.013501) (xy 335.804978 -440.029741) (xy 335.863356 -440.053757)
			(xy 335.918125 -440.085143) (xy 335.96836 -440.123369) (xy 336.013211 -440.167789) (xy 336.05192 -440.217652)
			(xy 336.083834 -440.272116) (xy 336.108412 -440.330259) (xy 336.12524 -440.3911) (xy 336.130138 -440.422284)
			(xy 336.130138 -440.422538) (xy 336.131768 -440.431324) (xy 336.140257 -440.447036) (xy 336.153623 -440.45888)
			(xy 336.170242 -440.465418) (xy 336.17916 -440.465972) (xy 339.11921 -440.465972) (xy 339.12048 -440.465972)
			(xy 339.129398 -440.465405) (xy 339.146017 -440.458866) (xy 339.159389 -440.447029) (xy 339.167896 -440.431327)
			(xy 339.169502 -440.422538) (xy 339.169502 -440.422284) (xy 339.1744 -440.3911) (xy 339.191228 -440.330259)
			(xy 339.215806 -440.272116) (xy 339.24772 -440.217652) (xy 339.286429 -440.167789) (xy 339.33128 -440.123369)
			(xy 339.381515 -440.085143) (xy 339.436284 -440.053757) (xy 339.494662 -440.029741) (xy 339.555662 -440.013501)
			(xy 339.618254 -440.005312) (xy 339.681378 -440.005312) (xy 339.74397 -440.013501) (xy 339.80497 -440.029741)
			(xy 339.863348 -440.053757) (xy 339.918117 -440.085143) (xy 339.968352 -440.123369) (xy 340.013203 -440.167789)
			(xy 340.051912 -440.217652) (xy 340.083826 -440.272116) (xy 340.108404 -440.330259) (xy 340.125232 -440.3911)
			(xy 340.13013 -440.422284) (xy 340.13013 -440.422538) (xy 340.13176 -440.431324) (xy 340.140248 -440.447038)
			(xy 340.153614 -440.458884) (xy 340.170233 -440.465424) (xy 340.179152 -440.465972) (xy 343.119202 -440.465972)
			(xy 343.120472 -440.465972) (xy 343.129391 -440.465407) (xy 343.146012 -440.458869) (xy 343.159386 -440.447032)
			(xy 343.167895 -440.431329) (xy 343.169494 -440.422538) (xy 343.169494 -440.422284) (xy 343.174392 -440.3911)
			(xy 343.19122 -440.330259) (xy 343.215798 -440.272116) (xy 343.247712 -440.217652) (xy 343.286421 -440.167789)
			(xy 343.331272 -440.123369) (xy 343.381507 -440.085143) (xy 343.436276 -440.053757) (xy 343.494654 -440.029741)
			(xy 343.555654 -440.013501) (xy 343.618246 -440.005312) (xy 343.68137 -440.005312) (xy 343.743962 -440.013501)
			(xy 343.804962 -440.029741) (xy 343.86334 -440.053757) (xy 343.918109 -440.085143) (xy 343.968344 -440.123369)
			(xy 344.013195 -440.167789) (xy 344.051904 -440.217652) (xy 344.083818 -440.272116) (xy 344.108396 -440.330259)
			(xy 344.125224 -440.3911) (xy 344.130122 -440.422284) (xy 344.130122 -440.422538) (xy 344.131752 -440.431325)
			(xy 344.14024 -440.44704) (xy 344.153605 -440.458888) (xy 344.170224 -440.46543) (xy 344.179144 -440.465972)
			(xy 368.814858 -440.465972) (xy 368.826153 -440.465375) (xy 368.846563 -440.455693) (xy 368.860839 -440.438185)
			(xy 368.864134 -440.427364) (xy 368.887756 -440.331606) (xy 368.889934 -440.320455) (xy 368.885463 -440.298209)
			(xy 368.871841 -440.280062) (xy 368.862102 -440.274202) (xy 368.861848 -440.274202) (xy 368.771086 -440.226319)
			(xy 368.592935 -440.124422) (xy 368.418885 -440.015668) (xy 368.2492 -439.900222) (xy 368.084138 -439.778258)
			(xy 367.923948 -439.649962) (xy 367.768873 -439.515527) (xy 367.619149 -439.375158) (xy 367.475002 -439.229068)
			(xy 367.336651 -439.077477) (xy 367.204305 -438.920616) (xy 367.078166 -438.758722) (xy 366.958423 -438.592041)
			(xy 366.84526 -438.420826) (xy 366.738846 -438.245335) (xy 366.639345 -438.065835) (xy 366.546905 -437.882598)
			(xy 366.461669 -437.695902) (xy 366.383764 -437.506029) (xy 366.313308 -437.313268) (xy 366.25041 -437.117911)
			(xy 366.195163 -436.920253) (xy 366.147652 -436.720595) (xy 366.107948 -436.519238) (xy 366.076113 -436.316489)
			(xy 366.052193 -436.112654) (xy 366.036226 -435.908043) (xy 366.028236 -435.702965) (xy 366.027716 -435.600348)
			(xy 366.028212 -435.498122) (xy 366.036139 -435.293823) (xy 366.051983 -435.089985) (xy 366.075719 -434.886914)
			(xy 366.10731 -434.684917) (xy 366.146711 -434.484297) (xy 366.193861 -434.285355) (xy 366.24869 -434.088391)
			(xy 366.311114 -433.893701) (xy 366.381041 -433.701578) (xy 366.458365 -433.512312) (xy 366.54297 -433.326185)
			(xy 366.634728 -433.14348) (xy 366.733502 -432.964469) (xy 366.839143 -432.789424) (xy 366.951491 -432.618606)
			(xy 367.070379 -432.452273) (xy 367.195627 -432.290675) (xy 367.327047 -432.134055) (xy 367.464441 -431.982648)
			(xy 367.607602 -431.836684) (xy 367.756316 -431.69638) (xy 367.910358 -431.561947) (xy 368.069496 -431.43359)
			(xy 368.233493 -431.311499) (xy 368.4021 -431.195859) (xy 368.575064 -431.086844) (xy 368.752126 -430.984617)
			(xy 368.933018 -430.889333) (xy 369.117468 -430.801135) (xy 369.3052 -430.720156) (xy 369.495931 -430.646516)
			(xy 369.689373 -430.580328) (xy 369.885237 -430.52169) (xy 370.083227 -430.470691) (xy 370.283046 -430.427408)
			(xy 370.484392 -430.391905) (xy 370.686964 -430.364236) (xy 370.890457 -430.344443) (xy 371.094564 -430.332555)
			(xy 371.298978 -430.328591) (xy 371.503392 -430.332555) (xy 371.707499 -430.344443) (xy 371.910992 -430.364236)
			(xy 372.113564 -430.391905) (xy 372.31491 -430.427408) (xy 372.514729 -430.470691) (xy 372.712719 -430.52169)
			(xy 372.908583 -430.580328) (xy 373.102025 -430.646516) (xy 373.292756 -430.720156) (xy 373.480488 -430.801135)
			(xy 373.664938 -430.889333) (xy 373.84583 -430.984617) (xy 374.022892 -431.086844) (xy 374.195856 -431.195859)
			(xy 374.364463 -431.311499) (xy 374.52846 -431.43359) (xy 374.685777 -431.560478) (xy 381.2413 -431.560478)
			(xy 381.2413 -429.018954) (xy 381.241767 -429.006866) (xy 381.249232 -428.983871) (xy 381.26342 -428.964295)
			(xy 381.28295 -428.950044) (xy 381.305922 -428.942507) (xy 381.318008 -428.941992) (xy 382.257808 -428.941992)
			(xy 382.269917 -428.942409) (xy 382.292943 -428.94991) (xy 382.307523 -428.960534) (xy 383.241296 -428.960534)
			(xy 383.241296 -426.41901) (xy 383.241815 -426.406925) (xy 383.249264 -426.383932) (xy 383.263439 -426.364356)
			(xy 383.282958 -426.350104) (xy 383.305921 -426.342564) (xy 383.318004 -426.342048) (xy 384.257804 -426.342048)
			(xy 384.269908 -426.342512) (xy 384.292927 -426.350006) (xy 384.312495 -426.364257) (xy 384.326691 -426.383866)
			(xy 384.334121 -426.406905) (xy 384.334512 -426.41901) (xy 384.334512 -427.960536) (xy 385.241292 -427.960536)
			(xy 385.241292 -425.419012) (xy 385.241723 -425.40693) (xy 385.249187 -425.383948) (xy 385.263389 -425.364397)
			(xy 385.282937 -425.350193) (xy 385.305918 -425.342725) (xy 385.318 -425.342304) (xy 386.2578 -425.342304)
			(xy 386.269884 -425.342713) (xy 386.292869 -425.350182) (xy 386.31242 -425.364388) (xy 386.326624 -425.383942)
			(xy 386.334089 -425.406928) (xy 386.334508 -425.419012) (xy 386.334508 -427.960536) (xy 386.334067 -427.972612)
			(xy 386.326594 -427.995581) (xy 386.312392 -428.015117) (xy 386.292849 -428.029311) (xy 386.269877 -428.036772)
			(xy 386.2578 -428.037244) (xy 385.318 -428.037244) (xy 385.305929 -428.036736) (xy 385.282968 -428.029278)
			(xy 385.263434 -428.015092) (xy 385.249238 -427.995564) (xy 385.241769 -427.972607) (xy 385.241292 -427.960536)
			(xy 384.334512 -427.960536) (xy 384.334512 -428.960534) (xy 384.334121 -428.97263) (xy 384.326649 -428.99564)
			(xy 384.312444 -429.015223) (xy 384.292892 -429.029471) (xy 384.269899 -429.036994) (xy 384.257804 -429.037496)
			(xy 383.318004 -429.037496) (xy 383.305895 -429.03708) (xy 383.282867 -429.029582) (xy 383.263293 -429.01532)
			(xy 383.249099 -428.995698) (xy 383.241679 -428.972644) (xy 383.241296 -428.960534) (xy 382.307523 -428.960534)
			(xy 382.312515 -428.964172) (xy 382.32671 -428.983792) (xy 382.334132 -429.006844) (xy 382.334516 -429.018954)
			(xy 382.334516 -431.560478) (xy 382.334073 -431.572571) (xy 382.326617 -431.595578) (xy 382.312426 -431.615162)
			(xy 382.292884 -431.629412) (xy 382.269899 -431.636937) (xy 382.257808 -431.63744) (xy 381.318008 -431.63744)
			(xy 381.305904 -431.636978) (xy 381.282883 -431.629485) (xy 381.263313 -431.615234) (xy 381.249117 -431.595625)
			(xy 381.241689 -431.572584) (xy 381.2413 -431.560478) (xy 374.685777 -431.560478) (xy 374.687598 -431.561947)
			(xy 374.84164 -431.69638) (xy 374.990354 -431.836684) (xy 375.133515 -431.982648) (xy 375.270909 -432.134055)
			(xy 375.402329 -432.290675) (xy 375.527577 -432.452273) (xy 375.646465 -432.618606) (xy 375.758813 -432.789424)
			(xy 375.864454 -432.964469) (xy 375.963228 -433.14348) (xy 376.054986 -433.326185) (xy 376.139591 -433.512312)
			(xy 376.216915 -433.701578) (xy 376.286842 -433.893701) (xy 376.349266 -434.088391) (xy 376.404095 -434.285355)
			(xy 376.451245 -434.484297) (xy 376.490646 -434.684917) (xy 376.522237 -434.886914) (xy 376.545973 -435.089985)
			(xy 376.551448 -435.16042) (xy 381.2413 -435.16042) (xy 381.2413 -432.618896) (xy 381.241709 -432.606812)
			(xy 381.249179 -432.583828) (xy 381.263386 -432.564277) (xy 381.282939 -432.550073) (xy 381.305924 -432.542607)
			(xy 381.318008 -432.542188) (xy 382.257808 -432.542188) (xy 382.269883 -432.542657) (xy 382.292849 -432.550122)
			(xy 382.3071 -432.560476) (xy 383.241296 -432.560476) (xy 383.241296 -430.018952) (xy 383.241723 -430.006875)
			(xy 383.249199 -429.983905) (xy 383.263405 -429.964368) (xy 383.282952 -429.950176) (xy 383.305926 -429.942715)
			(xy 383.318004 -429.942244) (xy 384.257804 -429.942244) (xy 384.269874 -429.94276) (xy 384.292833 -429.950218)
			(xy 384.312366 -429.964403) (xy 384.326562 -429.983927) (xy 384.334033 -430.006882) (xy 384.334512 -430.018952)
			(xy 384.334512 -431.560478) (xy 385.241292 -431.560478) (xy 385.241292 -429.018954) (xy 385.241767 -429.006867)
			(xy 385.249231 -428.983873) (xy 385.263417 -428.964298) (xy 385.282945 -428.950047) (xy 385.305914 -428.942508)
			(xy 385.318 -428.941992) (xy 386.2578 -428.941992) (xy 386.269908 -428.942416) (xy 386.292934 -428.949914)
			(xy 386.307511 -428.960534) (xy 387.241288 -428.960534) (xy 387.241288 -426.41901) (xy 387.241717 -426.406916)
			(xy 387.249177 -426.383908) (xy 387.263371 -426.364324) (xy 387.282916 -426.350075) (xy 387.305904 -426.342551)
			(xy 387.317996 -426.342048) (xy 388.257796 -426.342048) (xy 388.269899 -426.342519) (xy 388.292918 -426.350011)
			(xy 388.312487 -426.36426) (xy 388.326683 -426.383867) (xy 388.334113 -426.406905) (xy 388.334504 -426.41901)
			(xy 388.334504 -427.960536) (xy 389.241284 -427.960536) (xy 389.241284 -425.419012) (xy 389.241723 -425.406931)
			(xy 389.249186 -425.38395) (xy 389.263386 -425.3644) (xy 389.282932 -425.350195) (xy 389.305911 -425.342726)
			(xy 389.317992 -425.342304) (xy 390.257792 -425.342304) (xy 390.269876 -425.342719) (xy 390.29286 -425.350186)
			(xy 390.312412 -425.364391) (xy 390.326616 -425.383943) (xy 390.334081 -425.406928) (xy 390.3345 -425.419012)
			(xy 390.3345 -427.960536) (xy 390.334067 -427.972613) (xy 390.326593 -427.995583) (xy 390.312389 -428.01512)
			(xy 390.292844 -428.029313) (xy 390.26987 -428.036773) (xy 390.257792 -428.037244) (xy 389.317992 -428.037244)
			(xy 389.305921 -428.036743) (xy 389.282959 -428.029283) (xy 389.263426 -428.015094) (xy 389.24923 -427.995566)
			(xy 389.241761 -427.972607) (xy 389.241284 -427.960536) (xy 388.334504 -427.960536) (xy 388.334504 -428.960534)
			(xy 388.334023 -428.972621) (xy 388.326562 -428.995615) (xy 388.312377 -429.015191) (xy 388.29285 -429.029442)
			(xy 388.269881 -429.036981) (xy 388.257796 -429.037496) (xy 387.317996 -429.037496) (xy 387.305887 -429.037087)
			(xy 387.282858 -429.029586) (xy 387.263285 -429.015323) (xy 387.249091 -428.995699) (xy 387.241671 -428.972645)
			(xy 387.241288 -428.960534) (xy 386.307511 -428.960534) (xy 386.312507 -428.964174) (xy 386.326701 -428.983794)
			(xy 386.334124 -429.006845) (xy 386.334508 -429.018954) (xy 386.334508 -431.560478) (xy 386.333975 -431.572562)
			(xy 386.32653 -431.595553) (xy 386.312359 -431.61513) (xy 386.292842 -431.629383) (xy 386.269882 -431.636924)
			(xy 386.2578 -431.63744) (xy 385.318 -431.63744) (xy 385.305895 -431.636984) (xy 385.282875 -431.62949)
			(xy 385.263305 -431.615237) (xy 385.249109 -431.595626) (xy 385.241681 -431.572584) (xy 385.241292 -431.560478)
			(xy 384.334512 -431.560478) (xy 384.334512 -432.560476) (xy 384.334067 -432.572557) (xy 384.326606 -432.595538)
			(xy 384.312409 -432.615089) (xy 384.292863 -432.629294) (xy 384.269885 -432.636762) (xy 384.257804 -432.637184)
			(xy 383.318004 -432.637184) (xy 383.305919 -432.636784) (xy 383.282932 -432.629314) (xy 383.26338 -432.615106)
			(xy 383.249176 -432.59555) (xy 383.241713 -432.572561) (xy 383.241296 -432.560476) (xy 382.3071 -432.560476)
			(xy 382.312386 -432.564317) (xy 382.32658 -432.583854) (xy 382.334043 -432.606821) (xy 382.334516 -432.618896)
			(xy 382.334516 -435.16042) (xy 382.334053 -435.172495) (xy 382.326586 -435.195461) (xy 382.312389 -435.214997)
			(xy 382.29285 -435.229191) (xy 382.269883 -435.236655) (xy 382.257808 -435.237128) (xy 381.318008 -435.237128)
			(xy 381.305936 -435.236629) (xy 381.282972 -435.229171) (xy 381.263437 -435.214983) (xy 381.249241 -435.195453)
			(xy 381.241775 -435.172492) (xy 381.2413 -435.16042) (xy 376.551448 -435.16042) (xy 376.561817 -435.293823)
			(xy 376.569744 -435.498122) (xy 376.57024 -435.600348) (xy 376.569744 -435.702966) (xy 376.561757 -435.908045)
			(xy 376.545793 -436.112659) (xy 376.521877 -436.316496) (xy 376.490044 -436.519247) (xy 376.450343 -436.720606)
			(xy 376.402833 -436.920267) (xy 376.347588 -437.117927) (xy 376.284691 -437.313286) (xy 376.214236 -437.50605)
			(xy 376.136332 -437.695924) (xy 376.051096 -437.882622) (xy 375.958656 -438.065861) (xy 375.859154 -438.245363)
			(xy 375.75274 -438.420855) (xy 375.639576 -438.592073) (xy 375.519833 -438.758755) (xy 375.518383 -438.760616)
			(xy 381.2413 -438.760616) (xy 381.2413 -436.219092) (xy 381.241758 -436.207016) (xy 381.249223 -436.184047)
			(xy 381.263421 -436.16451) (xy 381.282962 -436.150316) (xy 381.305932 -436.142855) (xy 381.318008 -436.142384)
			(xy 382.257808 -436.142384) (xy 382.269882 -436.142857) (xy 382.292848 -436.150321) (xy 382.306744 -436.160418)
			(xy 383.241296 -436.160418) (xy 383.241296 -433.618894) (xy 383.241802 -433.606809) (xy 383.249255 -433.583815)
			(xy 383.263433 -433.564239) (xy 383.282955 -433.549987) (xy 383.30592 -433.542448) (xy 383.318004 -433.541932)
			(xy 384.257804 -433.541932) (xy 384.269916 -433.542313) (xy 384.292949 -433.549818) (xy 384.312525 -433.564087)
			(xy 384.326718 -433.583718) (xy 384.334133 -433.60678) (xy 384.334512 -433.618894) (xy 384.334512 -435.16042)
			(xy 385.241292 -435.16042) (xy 385.241292 -432.618896) (xy 385.241761 -432.606821) (xy 385.249224 -432.583854)
			(xy 385.26342 -432.564317) (xy 385.282958 -432.550123) (xy 385.305925 -432.54266) (xy 385.318 -432.542188)
			(xy 386.2578 -432.542188) (xy 386.269874 -432.542664) (xy 386.292841 -432.550126) (xy 386.307086 -432.560476)
			(xy 387.241288 -432.560476) (xy 387.241288 -430.018952) (xy 387.241723 -430.006875) (xy 387.249198 -429.983907)
			(xy 387.263403 -429.964371) (xy 387.282947 -429.950178) (xy 387.305919 -429.942716) (xy 387.317996 -429.942244)
			(xy 388.257796 -429.942244) (xy 388.269866 -429.942767) (xy 388.292824 -429.950222) (xy 388.312357 -429.964406)
			(xy 388.326554 -429.983929) (xy 388.334025 -430.006883) (xy 388.334504 -430.018952) (xy 388.334504 -431.560478)
			(xy 389.241284 -431.560478) (xy 389.241284 -429.018954) (xy 389.241669 -429.006858) (xy 389.249144 -428.983848)
			(xy 389.26335 -428.964265) (xy 389.282903 -428.950018) (xy 389.305897 -428.942495) (xy 389.317992 -428.941992)
			(xy 390.257792 -428.941992) (xy 390.2699 -428.942423) (xy 390.292925 -428.949919) (xy 390.307497 -428.960534)
			(xy 391.24128 -428.960534) (xy 391.24128 -426.41901) (xy 391.241717 -426.406917) (xy 391.249176 -426.38391)
			(xy 391.263369 -426.364326) (xy 391.282911 -426.350077) (xy 391.305896 -426.342552) (xy 391.317988 -426.342048)
			(xy 392.257788 -426.342048) (xy 392.269891 -426.342526) (xy 392.292909 -426.350016) (xy 392.312478 -426.364263)
			(xy 392.326675 -426.383869) (xy 392.334105 -426.406906) (xy 392.334496 -426.41901) (xy 392.334496 -427.960536)
			(xy 393.241276 -427.960536) (xy 393.241276 -425.419012) (xy 393.241774 -425.40694) (xy 393.249231 -425.383976)
			(xy 393.26342 -425.36444) (xy 393.28295 -425.350244) (xy 393.305912 -425.342779) (xy 393.317984 -425.342304)
			(xy 394.257784 -425.342304) (xy 394.269867 -425.342727) (xy 394.292851 -425.350191) (xy 394.312403 -425.364394)
			(xy 394.326607 -425.383945) (xy 394.334073 -425.406929) (xy 394.334492 -425.419012) (xy 394.334492 -427.960536)
			(xy 394.334066 -427.972614) (xy 394.326592 -427.995585) (xy 394.312386 -428.015123) (xy 394.292839 -428.029316)
			(xy 394.269862 -428.036775) (xy 394.257784 -428.037244) (xy 393.317984 -428.037244) (xy 393.305912 -428.03675)
			(xy 393.282951 -428.029287) (xy 393.263417 -428.015097) (xy 393.249222 -427.995567) (xy 393.241753 -427.972608)
			(xy 393.241276 -427.960536) (xy 392.334496 -427.960536) (xy 392.334496 -428.960534) (xy 392.334022 -428.972622)
			(xy 392.326561 -428.995617) (xy 392.312374 -429.015194) (xy 392.292845 -429.029444) (xy 392.269874 -429.036982)
			(xy 392.257788 -429.037496) (xy 391.317988 -429.037496) (xy 391.305878 -429.037094) (xy 391.28285 -429.029591)
			(xy 391.263276 -429.015326) (xy 391.249082 -428.995701) (xy 391.241663 -428.972645) (xy 391.24128 -428.960534)
			(xy 390.307497 -428.960534) (xy 390.312498 -428.964177) (xy 390.326693 -428.983795) (xy 390.334116 -429.006845)
			(xy 390.3345 -429.018954) (xy 390.3345 -431.560478) (xy 390.333975 -431.572562) (xy 390.326529 -431.595556)
			(xy 390.312356 -431.615132) (xy 390.292837 -431.629385) (xy 390.269874 -431.636925) (xy 390.257792 -431.63744)
			(xy 389.317992 -431.63744) (xy 389.305887 -431.636991) (xy 389.282866 -431.629494) (xy 389.263296 -431.61524)
			(xy 389.249101 -431.595628) (xy 389.241673 -431.572585) (xy 389.241284 -431.560478) (xy 388.334504 -431.560478)
			(xy 388.334504 -432.560476) (xy 388.334067 -432.572558) (xy 388.326605 -432.59554) (xy 388.312406 -432.615091)
			(xy 388.292858 -432.629296) (xy 388.269878 -432.636764) (xy 388.257796 -432.637184) (xy 387.317996 -432.637184)
			(xy 387.305911 -432.636791) (xy 387.282924 -432.629319) (xy 387.263371 -432.615109) (xy 387.249168 -432.595551)
			(xy 387.241705 -432.572562) (xy 387.241288 -432.560476) (xy 386.307086 -432.560476) (xy 386.312377 -432.56432)
			(xy 386.326572 -432.583856) (xy 386.334035 -432.606822) (xy 386.334508 -432.618896) (xy 386.334508 -435.16042)
			(xy 386.334053 -435.172496) (xy 386.326585 -435.195463) (xy 386.312386 -435.215) (xy 386.292845 -435.229194)
			(xy 386.269876 -435.236656) (xy 386.2578 -435.237128) (xy 385.318 -435.237128) (xy 385.305927 -435.236636)
			(xy 385.282964 -435.229176) (xy 385.263428 -435.214986) (xy 385.249233 -435.195454) (xy 385.241767 -435.172492)
			(xy 385.241292 -435.16042) (xy 384.334512 -435.16042) (xy 384.334512 -436.160418) (xy 384.334107 -436.172513)
			(xy 384.32664 -436.195523) (xy 384.312439 -436.215106) (xy 384.292889 -436.229355) (xy 384.269898 -436.236878)
			(xy 384.257804 -436.23738) (xy 383.318004 -436.23738) (xy 383.305893 -436.23698) (xy 383.282863 -436.229479)
			(xy 383.263288 -436.215214) (xy 383.249094 -436.195588) (xy 383.241676 -436.17253) (xy 383.241296 -436.160418)
			(xy 382.306744 -436.160418) (xy 382.312384 -436.164516) (xy 382.326579 -436.184052) (xy 382.334043 -436.207018)
			(xy 382.334516 -436.219092) (xy 382.334516 -438.760616) (xy 382.334049 -438.772691) (xy 382.326583 -438.795657)
			(xy 382.312387 -438.815193) (xy 382.29285 -438.829387) (xy 382.269883 -438.836851) (xy 382.257808 -438.837324)
			(xy 381.318008 -438.837324) (xy 381.305935 -438.836829) (xy 381.282971 -438.829371) (xy 381.263435 -438.815182)
			(xy 381.24924 -438.79565) (xy 381.241775 -438.772688) (xy 381.2413 -438.760616) (xy 375.518383 -438.760616)
			(xy 375.393692 -438.92065) (xy 375.261344 -439.077512) (xy 375.122991 -439.229103) (xy 374.978842 -439.375194)
			(xy 374.829116 -439.515563) (xy 374.674039 -439.649997) (xy 374.53592 -439.760614) (xy 383.241296 -439.760614)
			(xy 383.241296 -437.21909) (xy 383.241798 -437.207004) (xy 383.249252 -437.184011) (xy 383.263431 -437.164435)
			(xy 383.282955 -437.150183) (xy 383.30592 -437.142644) (xy 383.318004 -437.142128) (xy 384.257804 -437.142128)
			(xy 384.269916 -437.142513) (xy 384.292948 -437.150017) (xy 384.312524 -437.164286) (xy 384.326717 -437.183916)
			(xy 384.334133 -437.206977) (xy 384.334512 -437.21909) (xy 384.334512 -438.760616) (xy 385.241292 -438.760616)
			(xy 385.241292 -436.219092) (xy 385.241758 -436.207017) (xy 385.249222 -436.18405) (xy 385.263418 -436.164513)
			(xy 385.282957 -436.150319) (xy 385.305925 -436.142856) (xy 385.318 -436.142384) (xy 386.2578 -436.142384)
			(xy 386.269874 -436.142864) (xy 386.29284 -436.150326) (xy 386.306732 -436.160418) (xy 387.241288 -436.160418)
			(xy 387.241288 -433.618894) (xy 387.241703 -433.606799) (xy 387.249168 -433.583791) (xy 387.263366 -433.564207)
			(xy 387.282913 -433.549958) (xy 387.305903 -433.542435) (xy 387.317996 -433.541932) (xy 388.257796 -433.541932)
			(xy 388.269908 -433.54232) (xy 388.292941 -433.549822) (xy 388.312517 -433.56409) (xy 388.32671 -433.58372)
			(xy 388.334125 -433.606781) (xy 388.334504 -433.618894) (xy 388.334504 -435.16042) (xy 389.241284 -435.16042)
			(xy 389.241284 -432.618896) (xy 389.241761 -432.606822) (xy 389.249223 -432.583856) (xy 389.263417 -432.56432)
			(xy 389.282953 -432.550125) (xy 389.305918 -432.542661) (xy 389.317992 -432.542188) (xy 390.257792 -432.542188)
			(xy 390.269874 -432.542619) (xy 390.292856 -432.550084) (xy 390.307161 -432.560476) (xy 391.24128 -432.560476)
			(xy 391.24128 -430.018952) (xy 391.241723 -430.006876) (xy 391.249197 -429.983909) (xy 391.2634 -429.964374)
			(xy 391.282942 -429.950181) (xy 391.305912 -429.942717) (xy 391.317988 -429.942244) (xy 392.257788 -429.942244)
			(xy 392.269857 -429.942774) (xy 392.292816 -429.950227) (xy 392.312349 -429.964408) (xy 392.326546 -429.98393)
			(xy 392.334017 -430.006883) (xy 392.334496 -430.018952) (xy 392.334496 -431.560478) (xy 393.241276 -431.560478)
			(xy 393.241276 -429.018954) (xy 393.241669 -429.006858) (xy 393.249143 -428.98385) (xy 393.263347 -428.964268)
			(xy 393.282898 -428.95002) (xy 393.30589 -428.942496) (xy 393.317984 -428.941992) (xy 394.257784 -428.941992)
			(xy 394.269891 -428.94243) (xy 394.292917 -428.949924) (xy 394.307483 -428.960534) (xy 395.241272 -428.960534)
			(xy 395.241272 -426.41901) (xy 395.241717 -426.406918) (xy 395.249174 -426.383912) (xy 395.263366 -426.364329)
			(xy 395.282906 -426.35008) (xy 395.305889 -426.342553) (xy 395.31798 -426.342048) (xy 396.25778 -426.342048)
			(xy 396.269883 -426.342533) (xy 396.2929 -426.35002) (xy 396.312469 -426.364266) (xy 396.326666 -426.38387)
			(xy 396.334097 -426.406906) (xy 396.334488 -426.41901) (xy 396.334488 -427.960536) (xy 398.241012 -427.960536)
			(xy 398.241012 -425.419012) (xy 398.24147 -425.406961) (xy 398.248901 -425.384034) (xy 398.263042 -425.364517)
			(xy 398.282514 -425.350314) (xy 398.305417 -425.342809) (xy 398.317466 -425.342304) (xy 399.257774 -425.342304)
			(xy 399.269859 -425.342829) (xy 399.292852 -425.350274) (xy 399.31243 -425.364447) (xy 399.326682 -425.383966)
			(xy 399.334221 -425.406929) (xy 399.334736 -425.419012) (xy 399.334736 -427.960536) (xy 399.334272 -427.972585)
			(xy 399.326833 -427.995505) (xy 399.312692 -428.015017) (xy 399.293226 -428.029221) (xy 399.270329 -428.036732)
			(xy 399.258282 -428.037244) (xy 398.317974 -428.037244) (xy 398.305881 -428.036815) (xy 398.282877 -428.029349)
			(xy 398.263296 -428.015153) (xy 398.249047 -427.995611) (xy 398.241519 -427.972627) (xy 398.241012 -427.960536)
			(xy 396.334488 -427.960536) (xy 396.334488 -428.960534) (xy 396.334022 -428.972623) (xy 396.32656 -428.99562)
			(xy 396.312372 -429.015197) (xy 396.29284 -429.029447) (xy 396.269867 -429.036983) (xy 396.25778 -429.037496)
			(xy 395.31798 -429.037496) (xy 395.30587 -429.037101) (xy 395.282841 -429.029595) (xy 395.263268 -429.015328)
			(xy 395.249074 -428.995702) (xy 395.241655 -428.972646) (xy 395.241272 -428.960534) (xy 394.307483 -428.960534)
			(xy 394.312489 -428.96418) (xy 394.326685 -428.983797) (xy 394.334107 -429.006846) (xy 394.334492 -429.018954)
			(xy 394.334492 -431.560478) (xy 394.333974 -431.572563) (xy 394.326528 -431.595558) (xy 394.312353 -431.615135)
			(xy 394.292832 -431.629388) (xy 394.269867 -431.636926) (xy 394.257784 -431.63744) (xy 393.317984 -431.63744)
			(xy 393.305878 -431.636998) (xy 393.282857 -431.629499) (xy 393.263288 -431.615243) (xy 393.249092 -431.595629)
			(xy 393.241665 -431.572585) (xy 393.241276 -431.560478) (xy 392.334496 -431.560478) (xy 392.334496 -432.560476)
			(xy 392.334067 -432.572559) (xy 392.326604 -432.595543) (xy 392.312403 -432.615094) (xy 392.292853 -432.629299)
			(xy 392.269871 -432.636765) (xy 392.257788 -432.637184) (xy 391.317988 -432.637184) (xy 391.305902 -432.636797)
			(xy 391.282915 -432.629324) (xy 391.263363 -432.615112) (xy 391.24916 -432.595553) (xy 391.241697 -432.572562)
			(xy 391.24128 -432.560476) (xy 390.307161 -432.560476) (xy 390.312406 -432.564286) (xy 390.326611 -432.583833)
			(xy 390.334079 -432.606814) (xy 390.3345 -432.618896) (xy 390.3345 -435.16042) (xy 390.334053 -435.172496)
			(xy 390.326584 -435.195465) (xy 390.312383 -435.215003) (xy 390.29284 -435.229196) (xy 390.269869 -435.236657)
			(xy 390.257792 -435.237128) (xy 389.317992 -435.237128) (xy 389.305919 -435.236643) (xy 389.282955 -435.229181)
			(xy 389.26342 -435.214989) (xy 389.249225 -435.195456) (xy 389.241759 -435.172493) (xy 389.241284 -435.16042)
			(xy 388.334504 -435.16042) (xy 388.334504 -436.160418) (xy 388.334009 -436.172504) (xy 388.326553 -436.195498)
			(xy 388.312372 -436.215074) (xy 388.292847 -436.229325) (xy 388.26988 -436.236865) (xy 388.257796 -436.23738)
			(xy 387.317996 -436.23738) (xy 387.305885 -436.236987) (xy 387.282854 -436.229484) (xy 387.263279 -436.215217)
			(xy 387.249085 -436.195589) (xy 387.241668 -436.172531) (xy 387.241288 -436.160418) (xy 386.306732 -436.160418)
			(xy 386.312376 -436.164518) (xy 386.326571 -436.184053) (xy 386.334035 -436.207018) (xy 386.334508 -436.219092)
			(xy 386.334508 -438.760616) (xy 386.334049 -438.772691) (xy 386.326582 -438.795659) (xy 386.312384 -438.815196)
			(xy 386.292845 -438.82939) (xy 386.269875 -438.836852) (xy 386.2578 -438.837324) (xy 385.318 -438.837324)
			(xy 385.305927 -438.836836) (xy 385.282963 -438.829375) (xy 385.263427 -438.815184) (xy 385.249232 -438.795652)
			(xy 385.241767 -438.772689) (xy 385.241292 -438.760616) (xy 384.334512 -438.760616) (xy 384.334512 -439.760614)
			(xy 387.241288 -439.760614) (xy 387.241288 -437.21909) (xy 387.2417 -437.206995) (xy 387.249165 -437.183986)
			(xy 387.263364 -437.164402) (xy 387.282912 -437.150154) (xy 387.305902 -437.142631) (xy 387.317996 -437.142128)
			(xy 388.257796 -437.142128) (xy 388.269907 -437.14252) (xy 388.292939 -437.150022) (xy 388.312515 -437.164288)
			(xy 388.326709 -437.183917) (xy 388.334125 -437.206977) (xy 388.334504 -437.21909) (xy 388.334504 -438.760616)
			(xy 389.241284 -438.760616) (xy 389.241284 -436.219092) (xy 389.241757 -436.207018) (xy 389.249221 -436.184052)
			(xy 389.263416 -436.164516) (xy 389.282952 -436.150321) (xy 389.305918 -436.142857) (xy 389.317992 -436.142384)
			(xy 390.257792 -436.142384) (xy 390.269865 -436.142871) (xy 390.292831 -436.15033) (xy 390.306719 -436.160418)
			(xy 391.24128 -436.160418) (xy 391.24128 -433.618894) (xy 391.241703 -433.6068) (xy 391.249166 -433.583793)
			(xy 391.263363 -433.564209) (xy 391.282908 -433.549961) (xy 391.305896 -433.542436) (xy 391.317988 -433.541932)
			(xy 392.257788 -433.541932) (xy 392.269899 -433.542327) (xy 392.292932 -433.549827) (xy 392.312508 -433.564093)
			(xy 392.326702 -433.583721) (xy 392.334117 -433.606781) (xy 392.334496 -433.618894) (xy 392.334496 -435.16042)
			(xy 393.241276 -435.16042) (xy 393.241276 -432.618896) (xy 393.241761 -432.606823) (xy 393.249222 -432.583858)
			(xy 393.263414 -432.564323) (xy 393.282948 -432.550128) (xy 393.305911 -432.542663) (xy 393.317984 -432.542188)
			(xy 394.257784 -432.542188) (xy 394.269865 -432.542626) (xy 394.292847 -432.550089) (xy 394.307147 -432.560476)
			(xy 395.241272 -432.560476) (xy 395.241272 -430.018952) (xy 395.241723 -430.006877) (xy 395.249196 -429.983912)
			(xy 395.263397 -429.964377) (xy 395.282937 -429.950183) (xy 395.305905 -429.942718) (xy 395.31798 -429.942244)
			(xy 396.25778 -429.942244) (xy 396.269849 -429.94278) (xy 396.292807 -429.950232) (xy 396.31234 -429.964411)
			(xy 396.326537 -429.983932) (xy 396.334009 -430.006884) (xy 396.334488 -430.018952) (xy 396.334488 -431.560478)
			(xy 398.241012 -431.560478) (xy 398.241012 -429.018954) (xy 398.241472 -429.00684) (xy 398.248969 -428.983799)
			(xy 398.263215 -428.964201) (xy 398.282817 -428.94996) (xy 398.30586 -428.942469) (xy 398.317974 -428.941992)
			(xy 399.257774 -428.941992) (xy 399.269883 -428.942533) (xy 399.292917 -428.950008) (xy 399.307419 -428.960534)
			(xy 400.241008 -428.960534) (xy 400.241008 -426.41901) (xy 400.24152 -426.406899) (xy 400.249001 -426.383861)
			(xy 400.263233 -426.364262) (xy 400.282825 -426.350019) (xy 400.305859 -426.342526) (xy 400.31797 -426.342048)
			(xy 401.25777 -426.342048) (xy 401.269892 -426.342486) (xy 401.292952 -426.349971) (xy 401.312568 -426.364218)
			(xy 401.32682 -426.38383) (xy 401.334311 -426.406888) (xy 401.334732 -426.41901) (xy 401.334732 -427.960536)
			(xy 402.241004 -427.960536) (xy 402.241004 -425.419012) (xy 402.24147 -425.406962) (xy 402.2489 -425.384036)
			(xy 402.263039 -425.36452) (xy 402.282509 -425.350316) (xy 402.30541 -425.342811) (xy 402.317458 -425.342304)
			(xy 403.257766 -425.342304) (xy 403.26985 -425.342836) (xy 403.292844 -425.350279) (xy 403.312421 -425.36445)
			(xy 403.326674 -425.383968) (xy 403.334213 -425.40693) (xy 403.334728 -425.419012) (xy 403.334728 -427.960536)
			(xy 403.334271 -427.972585) (xy 403.326832 -427.995507) (xy 403.31269 -428.01502) (xy 403.293221 -428.029223)
			(xy 403.270322 -428.036734) (xy 403.258274 -428.037244) (xy 402.317966 -428.037244) (xy 402.305873 -428.036821)
			(xy 402.282869 -428.029353) (xy 402.263288 -428.015156) (xy 402.249039 -427.995612) (xy 402.241511 -427.972628)
			(xy 402.241004 -427.960536) (xy 401.334732 -427.960536) (xy 401.334732 -428.960534) (xy 401.334317 -428.972653)
			(xy 401.326817 -428.995703) (xy 401.312561 -429.015307) (xy 401.292945 -429.029546) (xy 401.26989 -429.037027)
			(xy 401.25777 -429.037496) (xy 400.31797 -429.037496) (xy 400.305857 -429.037014) (xy 400.282819 -429.029523)
			(xy 400.26322 -429.015282) (xy 400.248979 -428.995685) (xy 400.241486 -428.972647) (xy 400.241008 -428.960534)
			(xy 399.307419 -428.960534) (xy 399.312515 -428.964233) (xy 399.326759 -428.983818) (xy 399.334255 -429.006846)
			(xy 399.334736 -429.018954) (xy 399.334736 -431.560478) (xy 399.334321 -431.572602) (xy 399.326832 -431.595665)
			(xy 399.31258 -431.615282) (xy 399.292961 -431.629533) (xy 399.269898 -431.637022) (xy 399.257774 -431.63744)
			(xy 398.317974 -431.63744) (xy 398.305856 -431.63701) (xy 398.282808 -431.629513) (xy 398.263205 -431.615261)
			(xy 398.248965 -431.595649) (xy 398.241482 -431.572596) (xy 398.241012 -431.560478) (xy 396.334488 -431.560478)
			(xy 396.334488 -432.560476) (xy 396.334066 -432.572559) (xy 396.326603 -432.595545) (xy 396.3124 -432.615097)
			(xy 396.292848 -432.629301) (xy 396.269863 -432.636766) (xy 396.25778 -432.637184) (xy 395.31798 -432.637184)
			(xy 395.305894 -432.636804) (xy 395.282906 -432.629328) (xy 395.263354 -432.615114) (xy 395.249152 -432.595554)
			(xy 395.241689 -432.572562) (xy 395.241272 -432.560476) (xy 394.307147 -432.560476) (xy 394.312397 -432.564289)
			(xy 394.326602 -432.583835) (xy 394.33407 -432.606815) (xy 394.334492 -432.618896) (xy 394.334492 -435.16042)
			(xy 394.334052 -435.172497) (xy 394.326582 -435.195468) (xy 394.31238 -435.215006) (xy 394.292835 -435.229199)
			(xy 394.269861 -435.236658) (xy 394.257784 -435.237128) (xy 393.317984 -435.237128) (xy 393.305911 -435.23665)
			(xy 393.282946 -435.229185) (xy 393.263411 -435.214991) (xy 393.249217 -435.195457) (xy 393.241751 -435.172493)
			(xy 393.241276 -435.16042) (xy 392.334496 -435.16042) (xy 392.334496 -436.160418) (xy 392.334009 -436.172505)
			(xy 392.326552 -436.1955) (xy 392.312369 -436.215077) (xy 392.292842 -436.229328) (xy 392.269873 -436.236866)
			(xy 392.257788 -436.23738) (xy 391.317988 -436.23738) (xy 391.305876 -436.236994) (xy 391.282845 -436.229489)
			(xy 391.263271 -436.21522) (xy 391.249077 -436.195591) (xy 391.24166 -436.172531) (xy 391.24128 -436.160418)
			(xy 390.306719 -436.160418) (xy 390.312367 -436.164521) (xy 390.326562 -436.184055) (xy 390.334027 -436.207019)
			(xy 390.3345 -436.219092) (xy 390.3345 -438.760616) (xy 390.334049 -438.772692) (xy 390.326581 -438.795661)
			(xy 390.312382 -438.815199) (xy 390.29284 -438.829392) (xy 390.269868 -438.836853) (xy 390.257792 -438.837324)
			(xy 389.317992 -438.837324) (xy 389.305919 -438.836843) (xy 389.282954 -438.82938) (xy 389.263418 -438.815187)
			(xy 389.249224 -438.795653) (xy 389.241759 -438.772689) (xy 389.241284 -438.760616) (xy 388.334504 -438.760616)
			(xy 388.334504 -439.760614) (xy 391.24128 -439.760614) (xy 391.24128 -437.21909) (xy 391.2417 -437.206996)
			(xy 391.249164 -437.183988) (xy 391.263361 -437.164405) (xy 391.282907 -437.150156) (xy 391.305895 -437.142632)
			(xy 391.317988 -437.142128) (xy 392.257788 -437.142128) (xy 392.269899 -437.142527) (xy 392.292931 -437.150027)
			(xy 392.312506 -437.164292) (xy 392.3267 -437.183919) (xy 392.334116 -437.206978) (xy 392.334496 -437.21909)
			(xy 392.334496 -438.760616) (xy 393.241276 -438.760616) (xy 393.241276 -436.219092) (xy 393.241757 -436.207019)
			(xy 393.24922 -436.184054) (xy 393.263413 -436.164518) (xy 393.282947 -436.150324) (xy 393.305911 -436.142859)
			(xy 393.317984 -436.142384) (xy 394.257784 -436.142384) (xy 394.269865 -436.142826) (xy 394.292846 -436.150288)
			(xy 394.306794 -436.160418) (xy 395.241272 -436.160418) (xy 395.241272 -433.618894) (xy 395.241703 -433.606801)
			(xy 395.249165 -433.583795) (xy 395.26336 -433.564212) (xy 395.282903 -433.549963) (xy 395.305888 -433.542437)
			(xy 395.31798 -433.541932) (xy 396.25778 -433.541932) (xy 396.269891 -433.542334) (xy 396.292923 -433.549832)
			(xy 396.312499 -433.564096) (xy 396.326693 -433.583723) (xy 396.334109 -433.606782) (xy 396.334488 -433.618894)
			(xy 396.334488 -435.16042) (xy 398.241012 -435.16042) (xy 398.241012 -432.618896) (xy 398.241457 -432.606844)
			(xy 398.248892 -432.583917) (xy 398.263036 -432.5644) (xy 398.282511 -432.550197) (xy 398.305416 -432.542693)
			(xy 398.317466 -432.542188) (xy 399.257774 -432.542188) (xy 399.269867 -432.54263) (xy 399.292875 -432.550086)
			(xy 399.307214 -432.560476) (xy 400.241008 -432.560476) (xy 400.241008 -430.018952) (xy 400.241419 -430.006898)
			(xy 400.248866 -429.98397) (xy 400.263019 -429.964454) (xy 400.2825 -429.950253) (xy 400.30541 -429.942749)
			(xy 400.317462 -429.942244) (xy 401.25777 -429.942244) (xy 401.269858 -429.942733) (xy 401.292859 -429.950182)
			(xy 401.312439 -429.964363) (xy 401.326691 -429.983892) (xy 401.334223 -430.006865) (xy 401.334732 -430.018952)
			(xy 401.334732 -431.560478) (xy 402.241004 -431.560478) (xy 402.241004 -429.018954) (xy 402.241472 -429.00684)
			(xy 402.248968 -428.983801) (xy 402.263212 -428.964203) (xy 402.282812 -428.949962) (xy 402.305852 -428.94247)
			(xy 402.317966 -428.941992) (xy 403.257766 -428.941992) (xy 403.269874 -428.94254) (xy 403.292909 -428.950012)
			(xy 403.307406 -428.960534) (xy 404.241 -428.960534) (xy 404.241 -426.41901) (xy 404.24152 -426.4069)
			(xy 404.249 -426.383863) (xy 404.263231 -426.364265) (xy 404.28282 -426.350022) (xy 404.305852 -426.342527)
			(xy 404.317962 -426.342048) (xy 405.257762 -426.342048) (xy 405.269884 -426.342492) (xy 405.292943 -426.349975)
			(xy 405.31256 -426.36422) (xy 405.326812 -426.383832) (xy 405.334303 -426.406888) (xy 405.334724 -426.41901)
			(xy 405.334724 -427.960536) (xy 406.240996 -427.960536) (xy 406.240996 -425.419012) (xy 406.24147 -425.406963)
			(xy 406.248899 -425.384038) (xy 406.263036 -425.364523) (xy 406.282504 -425.350319) (xy 406.305403 -425.342812)
			(xy 406.31745 -425.342304) (xy 407.257758 -425.342304) (xy 407.269842 -425.342842) (xy 407.292835 -425.350283)
			(xy 407.312413 -425.364453) (xy 407.326666 -425.383969) (xy 407.334205 -425.40693) (xy 407.33472 -425.419012)
			(xy 407.33472 -427.960536) (xy 407.334271 -427.972586) (xy 407.326831 -427.99551) (xy 407.312687 -428.015023)
			(xy 407.293216 -428.029226) (xy 407.270315 -428.036735) (xy 407.258266 -428.037244) (xy 406.317958 -428.037244)
			(xy 406.305865 -428.036828) (xy 406.28286 -428.029358) (xy 406.263279 -428.015159) (xy 406.249031 -427.995614)
			(xy 406.241503 -427.972628) (xy 406.240996 -427.960536) (xy 405.334724 -427.960536) (xy 405.334724 -428.960534)
			(xy 405.334369 -428.972662) (xy 405.326862 -428.995729) (xy 405.312595 -429.015347) (xy 405.292964 -429.029595)
			(xy 405.269891 -429.03708) (xy 405.257762 -429.037496) (xy 404.317962 -429.037496) (xy 404.305849 -429.037021)
			(xy 404.28281 -429.029528) (xy 404.263212 -429.015285) (xy 404.24897 -428.995686) (xy 404.241478 -428.972647)
			(xy 404.241 -428.960534) (xy 403.307406 -428.960534) (xy 403.312507 -428.964236) (xy 403.326751 -428.98382)
			(xy 403.334247 -429.006846) (xy 403.334728 -429.018954) (xy 403.334728 -431.560478) (xy 403.334321 -431.572603)
			(xy 403.32683 -431.595667) (xy 403.312577 -431.615285) (xy 403.292956 -431.629536) (xy 403.269891 -431.637023)
			(xy 403.257766 -431.63744) (xy 402.317966 -431.63744) (xy 402.305847 -431.637017) (xy 402.282799 -431.629518)
			(xy 402.263196 -431.615264) (xy 402.248957 -431.59565) (xy 402.241474 -431.572597) (xy 402.241004 -431.560478)
			(xy 401.334732 -431.560478) (xy 401.334732 -432.560476) (xy 401.33422 -432.572522) (xy 401.326798 -432.595441)
			(xy 401.312669 -432.614955) (xy 401.293212 -432.62916) (xy 401.270322 -432.636672) (xy 401.258278 -432.637184)
			(xy 400.31797 -432.637184) (xy 400.305881 -432.636719) (xy 400.282884 -432.629257) (xy 400.263306 -432.615069)
			(xy 400.249056 -432.595537) (xy 400.24152 -432.572563) (xy 400.241008 -432.560476) (xy 399.307214 -432.560476)
			(xy 399.312459 -432.564277) (xy 399.326709 -432.583819) (xy 399.334233 -432.606804) (xy 399.334736 -432.618896)
			(xy 399.334736 -435.16042) (xy 399.334258 -435.172468) (xy 399.326824 -435.195388) (xy 399.312686 -435.2149)
			(xy 399.293223 -435.229104) (xy 399.270328 -435.236616) (xy 399.258282 -435.237128) (xy 398.317974 -435.237128)
			(xy 398.30588 -435.236714) (xy 398.282873 -435.229247) (xy 398.263291 -435.215047) (xy 398.249042 -435.195501)
			(xy 398.241516 -435.172513) (xy 398.241012 -435.16042) (xy 396.334488 -435.16042) (xy 396.334488 -436.160418)
			(xy 396.334009 -436.172506) (xy 396.32655 -436.195502) (xy 396.312366 -436.21508) (xy 396.292837 -436.229331)
			(xy 396.269866 -436.236867) (xy 396.25778 -436.23738) (xy 395.31798 -436.23738) (xy 395.305868 -436.237001)
			(xy 395.282837 -436.229493) (xy 395.263262 -436.215223) (xy 395.249069 -436.195592) (xy 395.241652 -436.172532)
			(xy 395.241272 -436.160418) (xy 394.306794 -436.160418) (xy 394.312396 -436.164487) (xy 394.326601 -436.184033)
			(xy 394.33407 -436.207011) (xy 394.334492 -436.219092) (xy 394.334492 -438.760616) (xy 394.334049 -438.772693)
			(xy 394.32658 -438.795663) (xy 394.312379 -438.815201) (xy 394.292835 -438.829395) (xy 394.269861 -438.836854)
			(xy 394.257784 -438.837324) (xy 393.317984 -438.837324) (xy 393.30591 -438.83685) (xy 393.282945 -438.829385)
			(xy 393.26341 -438.81519) (xy 393.249215 -438.795655) (xy 393.24175 -438.77269) (xy 393.241276 -438.760616)
			(xy 392.334496 -438.760616) (xy 392.334496 -439.760614) (xy 395.241272 -439.760614) (xy 395.241272 -437.21909)
			(xy 395.2417 -437.206997) (xy 395.249163 -437.183991) (xy 395.263359 -437.164408) (xy 395.282902 -437.150159)
			(xy 395.305888 -437.142633) (xy 395.31798 -437.142128) (xy 396.25778 -437.142128) (xy 396.269891 -437.142534)
			(xy 396.292922 -437.150031) (xy 396.312498 -437.164294) (xy 396.326692 -437.18392) (xy 396.334108 -437.206978)
			(xy 396.334488 -437.21909) (xy 396.334488 -438.760616) (xy 398.241012 -438.760616) (xy 398.241012 -436.219092)
			(xy 398.241453 -436.20704) (xy 398.24889 -436.184112) (xy 398.263035 -436.164596) (xy 398.28251 -436.150393)
			(xy 398.305416 -436.142889) (xy 398.317466 -436.142384) (xy 399.257774 -436.142384) (xy 399.269867 -436.14283)
			(xy 399.292874 -436.150285) (xy 399.306858 -436.160418) (xy 400.241008 -436.160418) (xy 400.241008 -433.618894)
			(xy 400.241506 -433.606782) (xy 400.248992 -433.583744) (xy 400.263228 -433.564145) (xy 400.282822 -433.549903)
			(xy 400.305858 -433.54241) (xy 400.31797 -433.541932) (xy 401.25777 -433.541932) (xy 401.269891 -433.542385)
			(xy 401.292947 -433.549869) (xy 401.312563 -433.564112) (xy 401.326815 -433.58372) (xy 401.334309 -433.606774)
			(xy 401.334732 -433.618894) (xy 401.334732 -435.16042) (xy 402.241004 -435.16042) (xy 402.241004 -432.618896)
			(xy 402.241457 -432.606845) (xy 402.248891 -432.583919) (xy 402.263034 -432.564403) (xy 402.282506 -432.5502)
			(xy 402.305409 -432.542694) (xy 402.317458 -432.542188) (xy 403.257766 -432.542188) (xy 403.269859 -432.542637)
			(xy 403.292866 -432.55009) (xy 403.307201 -432.560476) (xy 404.241 -432.560476) (xy 404.241 -430.018952)
			(xy 404.241419 -430.006899) (xy 404.248865 -429.983972) (xy 404.263016 -429.964457) (xy 404.282495 -429.950255)
			(xy 404.305403 -429.94275) (xy 404.317454 -429.942244) (xy 405.257762 -429.942244) (xy 405.26985 -429.94274)
			(xy 405.29285 -429.950187) (xy 405.312431 -429.964366) (xy 405.326683 -429.983894) (xy 405.334215 -430.006866)
			(xy 405.334724 -430.018952) (xy 405.334724 -431.560478) (xy 406.240996 -431.560478) (xy 406.240996 -429.018954)
			(xy 406.241472 -429.006841) (xy 406.248967 -428.983804) (xy 406.263209 -428.964206) (xy 406.282807 -428.949965)
			(xy 406.305845 -428.942471) (xy 406.317958 -428.941992) (xy 407.257758 -428.941992) (xy 407.269866 -428.942547)
			(xy 407.2929 -428.950017) (xy 407.307392 -428.960534) (xy 408.240992 -428.960534) (xy 408.240992 -426.41901)
			(xy 408.24152 -426.406901) (xy 408.248999 -426.383865) (xy 408.263228 -426.364268) (xy 408.282815 -426.350024)
			(xy 408.305845 -426.342528) (xy 408.317954 -426.342048) (xy 409.257754 -426.342048) (xy 409.269875 -426.342499)
			(xy 409.292934 -426.34998) (xy 409.312551 -426.364223) (xy 409.326804 -426.383833) (xy 409.334295 -426.406889)
			(xy 409.334716 -426.41901) (xy 409.334716 -427.960536) (xy 410.240988 -427.960536) (xy 410.240988 -425.419012)
			(xy 410.24147 -425.406964) (xy 410.248898 -425.38404) (xy 410.263033 -425.364526) (xy 410.282498 -425.350321)
			(xy 410.305395 -425.342813) (xy 410.317442 -425.342304) (xy 411.25775 -425.342304) (xy 411.269833 -425.342849)
			(xy 411.292826 -425.350288) (xy 411.312404 -425.364455) (xy 411.326658 -425.383971) (xy 411.334197 -425.406931)
			(xy 411.334712 -425.419012) (xy 411.334712 -427.960536) (xy 411.334271 -427.972587) (xy 411.32683 -427.995512)
			(xy 411.312684 -428.015026) (xy 411.293211 -428.029228) (xy 411.270307 -428.036736) (xy 411.258258 -428.037244)
			(xy 410.31795 -428.037244) (xy 410.305861 -428.03675) (xy 410.28286 -428.029305) (xy 410.263278 -428.015126)
			(xy 410.249026 -427.995597) (xy 410.241495 -427.972623) (xy 410.240988 -427.960536) (xy 409.334716 -427.960536)
			(xy 409.334716 -428.960534) (xy 409.334368 -428.972663) (xy 409.326861 -428.995731) (xy 409.312592 -429.015349)
			(xy 409.292959 -429.029598) (xy 409.269884 -429.037081) (xy 409.257754 -429.037496) (xy 408.317954 -429.037496)
			(xy 408.30584 -429.037028) (xy 408.282801 -429.029532) (xy 408.263203 -429.015288) (xy 408.248962 -428.995688)
			(xy 408.24147 -428.972648) (xy 408.240992 -428.960534) (xy 407.307392 -428.960534) (xy 407.312498 -428.964239)
			(xy 407.326743 -428.983821) (xy 407.334239 -429.006847) (xy 407.33472 -429.018954) (xy 407.33472 -431.560478)
			(xy 407.334321 -431.572604) (xy 407.326829 -431.595669) (xy 407.312574 -431.615288) (xy 407.292951 -431.629538)
			(xy 407.269884 -431.637024) (xy 407.257758 -431.63744) (xy 406.317958 -431.63744) (xy 406.305839 -431.637024)
			(xy 406.282791 -431.629522) (xy 406.263188 -431.615267) (xy 406.248948 -431.595652) (xy 406.241466 -431.572597)
			(xy 406.240996 -431.560478) (xy 405.334724 -431.560478) (xy 405.334724 -432.560476) (xy 405.33422 -432.572523)
			(xy 405.326797 -432.595443) (xy 405.312667 -432.614957) (xy 405.293207 -432.629162) (xy 405.270315 -432.636673)
			(xy 405.25827 -432.637184) (xy 404.317962 -432.637184) (xy 404.305873 -432.636726) (xy 404.282875 -432.629261)
			(xy 404.263298 -432.615072) (xy 404.249048 -432.595538) (xy 404.241512 -432.572564) (xy 404.241 -432.560476)
			(xy 403.307201 -432.560476) (xy 403.312451 -432.56428) (xy 403.326701 -432.583821) (xy 403.334225 -432.606805)
			(xy 403.334728 -432.618896) (xy 403.334728 -435.16042) (xy 403.334257 -435.172468) (xy 403.326823 -435.19539)
			(xy 403.312684 -435.214903) (xy 403.293217 -435.229106) (xy 403.270321 -435.236617) (xy 403.258274 -435.237128)
			(xy 402.317966 -435.237128) (xy 402.305871 -435.236721) (xy 402.282864 -435.229251) (xy 402.263282 -435.21505)
			(xy 402.249034 -435.195502) (xy 402.241508 -435.172513) (xy 402.241004 -435.16042) (xy 401.334732 -435.16042)
			(xy 401.334732 -436.160418) (xy 401.334355 -436.172545) (xy 401.326854 -436.195609) (xy 401.312592 -436.215226)
			(xy 401.292966 -436.229476) (xy 401.269897 -436.236962) (xy 401.25777 -436.23738) (xy 400.31797 -436.23738)
			(xy 400.305856 -436.236914) (xy 400.282814 -436.229421) (xy 400.263215 -436.215177) (xy 400.248974 -436.195575)
			(xy 400.241484 -436.172532) (xy 400.241008 -436.160418) (xy 399.306858 -436.160418) (xy 399.312458 -436.164476)
			(xy 399.326708 -436.184017) (xy 399.334233 -436.207001) (xy 399.334736 -436.219092) (xy 399.334736 -438.760616)
			(xy 399.334254 -438.772663) (xy 399.326821 -438.795583) (xy 399.312685 -438.815096) (xy 399.293222 -438.8293)
			(xy 399.270328 -438.836812) (xy 399.258282 -438.837324) (xy 398.317974 -438.837324) (xy 398.305879 -438.836914)
			(xy 398.282872 -438.829446) (xy 398.263289 -438.815246) (xy 398.249041 -438.795698) (xy 398.241516 -438.772709)
			(xy 398.241012 -438.760616) (xy 396.334488 -438.760616) (xy 396.334488 -439.760614) (xy 400.241008 -439.760614)
			(xy 400.241008 -437.21909) (xy 400.241503 -437.206978) (xy 400.248989 -437.18394) (xy 400.263226 -437.164341)
			(xy 400.282822 -437.150098) (xy 400.305858 -437.142606) (xy 400.31797 -437.142128) (xy 401.25777 -437.142128)
			(xy 401.26989 -437.142585) (xy 401.292946 -437.150068) (xy 401.312561 -437.16431) (xy 401.326814 -437.183918)
			(xy 401.334308 -437.20697) (xy 401.334732 -437.21909) (xy 401.334732 -438.760616) (xy 402.241004 -438.760616)
			(xy 402.241004 -436.219092) (xy 402.241453 -436.207041) (xy 402.248889 -436.184115) (xy 402.263032 -436.164599)
			(xy 402.282505 -436.150396) (xy 402.305409 -436.14289) (xy 402.317458 -436.142384) (xy 403.257766 -436.142384)
			(xy 403.269858 -436.142837) (xy 403.292865 -436.15029) (xy 403.306845 -436.160418) (xy 404.241 -436.160418)
			(xy 404.241 -433.618894) (xy 404.241506 -433.606783) (xy 404.24899 -433.583746) (xy 404.263225 -433.564148)
			(xy 404.282817 -433.549905) (xy 404.305851 -433.542411) (xy 404.317962 -433.541932) (xy 405.257762 -433.541932)
			(xy 405.269882 -433.542392) (xy 405.292939 -433.549873) (xy 405.312554 -433.564115) (xy 405.326807 -433.583722)
			(xy 405.334301 -433.606774) (xy 405.334724 -433.618894) (xy 405.334724 -435.16042) (xy 406.240996 -435.16042)
			(xy 406.240996 -432.618896) (xy 406.241457 -432.606846) (xy 406.24889 -432.583921) (xy 406.263031 -432.564406)
			(xy 406.282501 -432.550202) (xy 406.305402 -432.542696) (xy 406.31745 -432.542188) (xy 407.257758 -432.542188)
			(xy 407.26985 -432.542644) (xy 407.292858 -432.550095) (xy 407.307187 -432.560476) (xy 408.240992 -432.560476)
			(xy 408.240992 -430.018952) (xy 408.241419 -430.0069) (xy 408.248864 -429.983974) (xy 408.263013 -429.96446)
			(xy 408.28249 -429.950258) (xy 408.305395 -429.942752) (xy 408.317446 -429.942244) (xy 409.257754 -429.942244)
			(xy 409.269842 -429.942747) (xy 409.292841 -429.950191) (xy 409.312422 -429.964368) (xy 409.326674 -429.983895)
			(xy 409.334207 -430.006866) (xy 409.334716 -430.018952) (xy 409.334716 -431.560478) (xy 410.240988 -431.560478)
			(xy 410.240988 -429.018954) (xy 410.241472 -429.006842) (xy 410.248966 -428.983806) (xy 410.263206 -428.964209)
			(xy 410.282802 -428.949967) (xy 410.305838 -428.942472) (xy 410.31795 -428.941992) (xy 411.25775 -428.941992)
			(xy 411.269863 -428.942468) (xy 411.2929 -428.949964) (xy 411.307444 -428.960534) (xy 412.240984 -428.960534)
			(xy 412.240984 -426.41901) (xy 412.241369 -426.406883) (xy 412.248864 -426.383817) (xy 412.263123 -426.364198)
			(xy 412.282749 -426.349948) (xy 412.305819 -426.342464) (xy 412.317946 -426.342048) (xy 413.257746 -426.342048)
			(xy 413.269864 -426.342473) (xy 413.29291 -426.349974) (xy 413.312512 -426.364228) (xy 413.326752 -426.38384)
			(xy 413.334236 -426.406892) (xy 413.334708 -426.41901) (xy 413.334708 -428.960534) (xy 413.334218 -428.972646)
			(xy 413.326727 -428.995682) (xy 413.312488 -429.01528) (xy 413.292893 -429.029522) (xy 413.269858 -429.037016)
			(xy 413.257746 -429.037496) (xy 412.317946 -429.037496) (xy 412.305829 -429.037002) (xy 412.282777 -429.029526)
			(xy 412.263164 -429.015292) (xy 412.248911 -428.995694) (xy 412.241411 -428.972651) (xy 412.240984 -428.960534)
			(xy 411.307444 -428.960534) (xy 411.312497 -428.964206) (xy 411.326738 -428.983804) (xy 411.334232 -429.006841)
			(xy 411.334712 -429.018954) (xy 411.334712 -431.560478) (xy 411.33417 -431.572586) (xy 411.326695 -431.59562)
			(xy 411.312469 -431.615218) (xy 411.292885 -431.629462) (xy 411.269858 -431.636959) (xy 411.25775 -431.63744)
			(xy 410.31795 -431.63744) (xy 410.305831 -431.63703) (xy 410.282782 -431.629527) (xy 410.263179 -431.615269)
			(xy 410.24894 -431.595653) (xy 410.241458 -431.572598) (xy 410.240988 -431.560478) (xy 409.334716 -431.560478)
			(xy 409.334716 -432.560476) (xy 409.33422 -432.572523) (xy 409.326796 -432.595445) (xy 409.312664 -432.61496)
			(xy 409.293202 -432.629165) (xy 409.270308 -432.636675) (xy 409.258262 -432.637184) (xy 408.317954 -432.637184)
			(xy 408.305864 -432.636732) (xy 408.282866 -432.629266) (xy 408.263289 -432.615074) (xy 408.249039 -432.59554)
			(xy 408.241504 -432.572564) (xy 408.240992 -432.560476) (xy 407.307187 -432.560476) (xy 407.312442 -432.564283)
			(xy 407.326693 -432.583822) (xy 407.334217 -432.606805) (xy 407.33472 -432.618896) (xy 407.33472 -435.16042)
			(xy 407.334257 -435.172469) (xy 407.326821 -435.195392) (xy 407.312681 -435.214906) (xy 407.293212 -435.229109)
			(xy 407.270314 -435.236618) (xy 407.258266 -435.237128) (xy 406.317958 -435.237128) (xy 406.305863 -435.236728)
			(xy 406.282856 -435.229256) (xy 406.263274 -435.215053) (xy 406.249026 -435.195504) (xy 406.2415 -435.172514)
			(xy 406.240996 -435.16042) (xy 405.334724 -435.16042) (xy 405.334724 -436.160418) (xy 405.334355 -436.172545)
			(xy 405.326853 -436.195611) (xy 405.312589 -436.215229) (xy 405.292961 -436.229478) (xy 405.26989 -436.236963)
			(xy 405.257762 -436.23738) (xy 404.317962 -436.23738) (xy 404.305847 -436.236921) (xy 404.282806 -436.229425)
			(xy 404.263206 -436.21518) (xy 404.248965 -436.195576) (xy 404.241476 -436.172533) (xy 404.241 -436.160418)
			(xy 403.306845 -436.160418) (xy 403.312449 -436.164478) (xy 403.3267 -436.184018) (xy 403.334225 -436.207001)
			(xy 403.334728 -436.219092) (xy 403.334728 -438.760616) (xy 403.334254 -438.772664) (xy 403.32682 -438.795586)
			(xy 403.312682 -438.815099) (xy 403.293217 -438.829302) (xy 403.270321 -438.836813) (xy 403.258274 -438.837324)
			(xy 402.317966 -438.837324) (xy 402.305871 -438.836921) (xy 402.282863 -438.829451) (xy 402.263281 -438.815249)
			(xy 402.249033 -438.7957) (xy 402.241508 -438.77271) (xy 402.241004 -438.760616) (xy 401.334732 -438.760616)
			(xy 401.334732 -439.760614) (xy 404.241 -439.760614) (xy 404.241 -437.21909) (xy 404.241503 -437.206979)
			(xy 404.248988 -437.183942) (xy 404.263224 -437.164343) (xy 404.282817 -437.150101) (xy 404.305851 -437.142607)
			(xy 404.317962 -437.142128) (xy 405.257762 -437.142128) (xy 405.269882 -437.142592) (xy 405.292938 -437.150073)
			(xy 405.312553 -437.164313) (xy 405.326805 -437.183919) (xy 405.3343 -437.20697) (xy 405.334724 -437.21909)
			(xy 405.334724 -438.760616) (xy 406.240996 -438.760616) (xy 406.240996 -436.219092) (xy 406.241453 -436.207042)
			(xy 406.248888 -436.184117) (xy 406.263029 -436.164601) (xy 406.2825 -436.150398) (xy 406.305401 -436.142892)
			(xy 406.31745 -436.142384) (xy 407.257758 -436.142384) (xy 407.26985 -436.142844) (xy 407.292856 -436.150294)
			(xy 407.306832 -436.160418) (xy 408.240992 -436.160418) (xy 408.240992 -433.618894) (xy 408.241506 -433.606784)
			(xy 408.248989 -433.583748) (xy 408.263222 -433.564151) (xy 408.282812 -433.549908) (xy 408.305844 -433.542412)
			(xy 408.317954 -433.541932) (xy 409.257754 -433.541932) (xy 409.269874 -433.542399) (xy 409.29293 -433.549878)
			(xy 409.312546 -433.564117) (xy 409.326798 -433.583723) (xy 409.334293 -433.606775) (xy 409.334716 -433.618894)
			(xy 409.334716 -435.16042) (xy 410.240988 -435.16042) (xy 410.240988 -432.618896) (xy 410.241456 -432.606847)
			(xy 410.248889 -432.583923) (xy 410.263028 -432.564409) (xy 410.282496 -432.550205) (xy 410.305394 -432.542697)
			(xy 410.317442 -432.542188) (xy 411.25775 -432.542188) (xy 411.269842 -432.542651) (xy 411.292849 -432.5501)
			(xy 411.307175 -432.560476) (xy 412.240984 -432.560476) (xy 412.240984 -430.018952) (xy 412.241419 -430.006901)
			(xy 412.248863 -429.983976) (xy 412.263011 -429.964463) (xy 412.282485 -429.950261) (xy 412.305388 -429.942753)
			(xy 412.317438 -429.942244) (xy 413.257746 -429.942244) (xy 413.269838 -429.942668) (xy 413.292841 -429.950138)
			(xy 413.312421 -429.964336) (xy 413.32667 -429.983878) (xy 413.3342 -430.006861) (xy 413.334708 -430.018952)
			(xy 413.334708 -432.560476) (xy 413.33422 -432.572524) (xy 413.326795 -432.595448) (xy 413.312661 -432.614963)
			(xy 413.293197 -432.629168) (xy 413.2703 -432.636676) (xy 413.258254 -432.637184) (xy 412.317946 -432.637184)
			(xy 412.305861 -432.636654) (xy 412.282866 -432.629213) (xy 412.263287 -432.615042) (xy 412.249034 -432.595522)
			(xy 412.241497 -432.572559) (xy 412.240984 -432.560476) (xy 411.307175 -432.560476) (xy 411.312434 -432.564285)
			(xy 411.326684 -432.583823) (xy 411.334209 -432.606806) (xy 411.334712 -432.618896) (xy 411.334712 -435.16042)
			(xy 411.334257 -435.17247) (xy 411.32682 -435.195394) (xy 411.312678 -435.214908) (xy 411.293207 -435.229111)
			(xy 411.270306 -435.236619) (xy 411.258258 -435.237128) (xy 410.31795 -435.237128) (xy 410.30586 -435.23665)
			(xy 410.282855 -435.229203) (xy 410.263272 -435.21502) (xy 410.249021 -435.195487) (xy 410.241493 -435.172508)
			(xy 410.240988 -435.16042) (xy 409.334716 -435.16042) (xy 409.334716 -436.160418) (xy 409.334354 -436.172546)
			(xy 409.326852 -436.195613) (xy 409.312586 -436.215232) (xy 409.292956 -436.229481) (xy 409.269883 -436.236965)
			(xy 409.257754 -436.23738) (xy 408.317954 -436.23738) (xy 408.305839 -436.236928) (xy 408.282797 -436.22943)
			(xy 408.263198 -436.215182) (xy 408.248957 -436.195578) (xy 408.241468 -436.172533) (xy 408.240992 -436.160418)
			(xy 407.306832 -436.160418) (xy 407.312441 -436.164481) (xy 407.326691 -436.184019) (xy 407.334216 -436.207002)
			(xy 407.33472 -436.219092) (xy 407.33472 -438.760616) (xy 407.334254 -438.772665) (xy 407.326819 -438.795588)
			(xy 407.312679 -438.815101) (xy 407.293212 -438.829305) (xy 407.270313 -438.836814) (xy 407.258266 -438.837324)
			(xy 406.317958 -438.837324) (xy 406.305863 -438.836928) (xy 406.282855 -438.829455) (xy 406.263272 -438.815252)
			(xy 406.249024 -438.795701) (xy 406.2415 -438.77271) (xy 406.240996 -438.760616) (xy 405.334724 -438.760616)
			(xy 405.334724 -439.760614) (xy 408.240992 -439.760614) (xy 408.240992 -437.21909) (xy 408.241503 -437.20698)
			(xy 408.248987 -437.183944) (xy 408.263221 -437.164346) (xy 408.282812 -437.150104) (xy 408.305844 -437.142608)
			(xy 408.317954 -437.142128) (xy 409.257754 -437.142128) (xy 409.269873 -437.142599) (xy 409.292929 -437.150077)
			(xy 409.312544 -437.164316) (xy 409.326797 -437.183921) (xy 409.334292 -437.206971) (xy 409.334716 -437.21909)
			(xy 409.334716 -438.760616) (xy 410.240988 -438.760616) (xy 410.240988 -436.219092) (xy 410.241453 -436.207043)
			(xy 410.248886 -436.184119) (xy 410.263026 -436.164604) (xy 410.282495 -436.150401) (xy 410.305394 -436.142893)
			(xy 410.317442 -436.142384) (xy 411.25775 -436.142384) (xy 411.269841 -436.142851) (xy 411.292848 -436.150299)
			(xy 411.306818 -436.160418) (xy 412.240984 -436.160418) (xy 412.240984 -433.618894) (xy 412.241356 -433.606766)
			(xy 412.248855 -433.5837) (xy 412.263118 -433.564081) (xy 412.282746 -433.549831) (xy 412.305818 -433.542348)
			(xy 412.317946 -433.541932) (xy 413.257746 -433.541932) (xy 413.269862 -433.542372) (xy 413.292906 -433.549872)
			(xy 413.312507 -433.564122) (xy 413.326747 -433.58373) (xy 413.334234 -433.606777) (xy 413.334708 -433.618894)
			(xy 413.334708 -435.679338) (xy 445.662808 -435.679338) (xy 445.662808 -435.520342) (xy 445.670861 -435.361549)
			(xy 445.686946 -435.203369) (xy 445.711023 -435.046206) (xy 445.743028 -434.890464) (xy 445.782881 -434.736543)
			(xy 445.830479 -434.584838) (xy 445.885699 -434.435739) (xy 445.9484 -434.289628) (xy 446.018422 -434.14688)
			(xy 446.095583 -434.007862) (xy 446.179686 -433.87293) (xy 446.270516 -433.742432) (xy 446.367839 -433.616701)
			(xy 446.471405 -433.496061) (xy 446.580948 -433.380822) (xy 446.696187 -433.271279) (xy 446.816827 -433.167713)
			(xy 446.942558 -433.07039) (xy 447.073056 -432.97956) (xy 447.207988 -432.895457) (xy 447.347006 -432.818296)
			(xy 447.489754 -432.748274) (xy 447.635865 -432.685573) (xy 447.784964 -432.630353) (xy 447.936669 -432.582755)
			(xy 448.09059 -432.542902) (xy 448.246332 -432.510897) (xy 448.403495 -432.48682) (xy 448.561675 -432.470735)
			(xy 448.720468 -432.462682) (xy 448.879464 -432.462682) (xy 449.038257 -432.470735) (xy 449.196437 -432.48682)
			(xy 449.3536 -432.510897) (xy 449.509342 -432.542902) (xy 449.663263 -432.582755) (xy 449.814968 -432.630353)
			(xy 449.964067 -432.685573) (xy 450.110178 -432.748274) (xy 450.252926 -432.818296) (xy 450.391944 -432.895457)
			(xy 450.526876 -432.97956) (xy 450.657374 -433.07039) (xy 450.783105 -433.167713) (xy 450.903745 -433.271279)
			(xy 451.018984 -433.380822) (xy 451.128527 -433.496061) (xy 451.232093 -433.616701) (xy 451.329416 -433.742432)
			(xy 451.420246 -433.87293) (xy 451.504349 -434.007862) (xy 451.58151 -434.14688) (xy 451.651532 -434.289628)
			(xy 451.714233 -434.435739) (xy 451.769453 -434.584838) (xy 451.817051 -434.736543) (xy 451.856904 -434.890464)
			(xy 451.888909 -435.046206) (xy 451.912986 -435.203369) (xy 451.929071 -435.361549) (xy 451.937124 -435.520342)
			(xy 451.937628 -435.59984) (xy 451.937124 -435.679338) (xy 451.929071 -435.838131) (xy 451.912986 -435.996311)
			(xy 451.888909 -436.153474) (xy 451.856904 -436.309216) (xy 451.817051 -436.463137) (xy 451.769453 -436.614842)
			(xy 451.714233 -436.763941) (xy 451.651532 -436.910052) (xy 451.58151 -437.0528) (xy 451.504349 -437.191818)
			(xy 451.420246 -437.32675) (xy 451.329416 -437.457248) (xy 451.232093 -437.582979) (xy 451.128527 -437.703619)
			(xy 451.018984 -437.818858) (xy 450.903745 -437.928401) (xy 450.783105 -438.031967) (xy 450.657374 -438.12929)
			(xy 450.526876 -438.22012) (xy 450.391944 -438.304223) (xy 450.252926 -438.381384) (xy 450.110178 -438.451406)
			(xy 449.964067 -438.514107) (xy 449.814968 -438.569327) (xy 449.663263 -438.616925) (xy 449.509342 -438.656778)
			(xy 449.3536 -438.688783) (xy 449.196437 -438.71286) (xy 449.038257 -438.728945) (xy 448.879464 -438.736998)
			(xy 448.720468 -438.736998) (xy 448.561675 -438.728945) (xy 448.403495 -438.71286) (xy 448.246332 -438.688783)
			(xy 448.09059 -438.656778) (xy 447.936669 -438.616925) (xy 447.784964 -438.569327) (xy 447.635865 -438.514107)
			(xy 447.489754 -438.451406) (xy 447.347006 -438.381384) (xy 447.207988 -438.304223) (xy 447.073056 -438.22012)
			(xy 446.942558 -438.12929) (xy 446.816827 -438.031967) (xy 446.696187 -437.928401) (xy 446.580948 -437.818858)
			(xy 446.471405 -437.703619) (xy 446.367839 -437.582979) (xy 446.270516 -437.457248) (xy 446.179686 -437.32675)
			(xy 446.095583 -437.191818) (xy 446.018422 -437.0528) (xy 445.9484 -436.910052) (xy 445.885699 -436.763941)
			(xy 445.830479 -436.614842) (xy 445.782881 -436.463137) (xy 445.743028 -436.309216) (xy 445.711023 -436.153474)
			(xy 445.686946 -435.996311) (xy 445.670861 -435.838131) (xy 445.662808 -435.679338) (xy 413.334708 -435.679338)
			(xy 413.334708 -436.160418) (xy 413.334205 -436.172529) (xy 413.326718 -436.195565) (xy 413.312482 -436.215163)
			(xy 413.29289 -436.229405) (xy 413.269857 -436.2369) (xy 413.257746 -436.23738) (xy 412.317946 -436.23738)
			(xy 412.305827 -436.236901) (xy 412.282773 -436.229424) (xy 412.263159 -436.215187) (xy 412.248905 -436.195584)
			(xy 412.241409 -436.172536) (xy 412.240984 -436.160418) (xy 411.306818 -436.160418) (xy 411.312432 -436.164484)
			(xy 411.326683 -436.184021) (xy 411.334208 -436.207002) (xy 411.334712 -436.219092) (xy 411.334712 -438.760616)
			(xy 411.334254 -438.772666) (xy 411.326818 -438.79559) (xy 411.312676 -438.815104) (xy 411.293207 -438.829307)
			(xy 411.270306 -438.836815) (xy 411.258258 -438.837324) (xy 410.31795 -438.837324) (xy 410.305859 -438.836849)
			(xy 410.282854 -438.829402) (xy 410.26327 -438.815219) (xy 410.249019 -438.795684) (xy 410.241493 -438.772705)
			(xy 410.240988 -438.760616) (xy 409.334716 -438.760616) (xy 409.334716 -439.760614) (xy 412.240984 -439.760614)
			(xy 412.240984 -437.21909) (xy 412.241352 -437.206962) (xy 412.248853 -437.183895) (xy 412.263116 -437.164276)
			(xy 412.282745 -437.150027) (xy 412.305818 -437.142544) (xy 412.317946 -437.142128) (xy 413.257746 -437.142128)
			(xy 413.269862 -437.142572) (xy 413.292905 -437.150071) (xy 413.312505 -437.164321) (xy 413.326745 -437.183927)
			(xy 413.334233 -437.206974) (xy 413.334708 -437.21909) (xy 413.334708 -439.760614) (xy 413.334201 -439.772725)
			(xy 413.326716 -439.795761) (xy 413.312481 -439.815358) (xy 413.292889 -439.829601) (xy 413.269857 -439.837096)
			(xy 413.257746 -439.837576) (xy 412.317946 -439.837576) (xy 412.305827 -439.837101) (xy 412.282772 -439.829623)
			(xy 412.263157 -439.815385) (xy 412.248904 -439.795782) (xy 412.241408 -439.772733) (xy 412.240984 -439.760614)
			(xy 409.334716 -439.760614) (xy 409.334351 -439.772742) (xy 409.326849 -439.795809) (xy 409.312585 -439.815428)
			(xy 409.292955 -439.829677) (xy 409.269882 -439.83716) (xy 409.257754 -439.837576) (xy 408.317954 -439.837576)
			(xy 408.305838 -439.837128) (xy 408.282796 -439.82963) (xy 408.263196 -439.815381) (xy 408.248956 -439.795775)
			(xy 408.241467 -439.77273) (xy 408.240992 -439.760614) (xy 405.334724 -439.760614) (xy 405.334351 -439.772741)
			(xy 405.32685 -439.795807) (xy 405.312588 -439.815425) (xy 405.29296 -439.829674) (xy 405.26989 -439.837159)
			(xy 405.257762 -439.837576) (xy 404.317962 -439.837576) (xy 404.305847 -439.837121) (xy 404.282805 -439.829625)
			(xy 404.263205 -439.815378) (xy 404.248964 -439.795774) (xy 404.241475 -439.772729) (xy 404.241 -439.760614)
			(xy 401.334732 -439.760614) (xy 401.334351 -439.77274) (xy 401.326852 -439.795805) (xy 401.312591 -439.815422)
			(xy 401.292965 -439.829672) (xy 401.269897 -439.837158) (xy 401.25777 -439.837576) (xy 400.31797 -439.837576)
			(xy 400.305855 -439.837114) (xy 400.282813 -439.82962) (xy 400.263213 -439.815375) (xy 400.248972 -439.795772)
			(xy 400.241483 -439.772729) (xy 400.241008 -439.760614) (xy 396.334488 -439.760614) (xy 396.334005 -439.772702)
			(xy 396.326548 -439.795698) (xy 396.312365 -439.815275) (xy 396.292836 -439.829526) (xy 396.269866 -439.837063)
			(xy 396.25778 -439.837576) (xy 395.31798 -439.837576) (xy 395.305868 -439.8372) (xy 395.282836 -439.829693)
			(xy 395.263261 -439.815421) (xy 395.249068 -439.79579) (xy 395.241652 -439.772728) (xy 395.241272 -439.760614)
			(xy 392.334496 -439.760614) (xy 392.334005 -439.772701) (xy 392.326549 -439.795696) (xy 392.312367 -439.815272)
			(xy 392.292841 -439.829524) (xy 392.269873 -439.837062) (xy 392.257788 -439.837576) (xy 391.317988 -439.837576)
			(xy 391.305876 -439.837194) (xy 391.282844 -439.829688) (xy 391.263269 -439.815419) (xy 391.249076 -439.795788)
			(xy 391.24166 -439.772727) (xy 391.24128 -439.760614) (xy 388.334504 -439.760614) (xy 388.334006 -439.7727)
			(xy 388.32655 -439.795694) (xy 388.31237 -439.81527) (xy 388.292846 -439.829521) (xy 388.26988 -439.837061)
			(xy 388.257796 -439.837576) (xy 387.317996 -439.837576) (xy 387.305885 -439.837187) (xy 387.282853 -439.829683)
			(xy 387.263278 -439.815416) (xy 387.249084 -439.795787) (xy 387.241668 -439.772727) (xy 387.241288 -439.760614)
			(xy 384.334512 -439.760614) (xy 384.334104 -439.772709) (xy 384.326638 -439.795718) (xy 384.312437 -439.815302)
			(xy 384.292889 -439.829551) (xy 384.269898 -439.837074) (xy 384.257804 -439.837576) (xy 383.318004 -439.837576)
			(xy 383.305893 -439.83718) (xy 383.282862 -439.829679) (xy 383.263286 -439.815413) (xy 383.249092 -439.795785)
			(xy 383.241676 -439.772727) (xy 383.241296 -439.760614) (xy 374.53592 -439.760614) (xy 374.513846 -439.778293)
			(xy 374.348781 -439.900257) (xy 374.179093 -440.015702) (xy 374.005041 -440.124454) (xy 373.826886 -440.226349)
			(xy 373.736108 -440.274202) (xy 373.735854 -440.274202) (xy 373.726093 -440.280024) (xy 373.712493 -440.298196)
			(xy 373.708029 -440.32045) (xy 373.7102 -440.331606) (xy 373.733822 -440.427364) (xy 373.737124 -440.438178)
			(xy 373.751415 -440.455662) (xy 373.771809 -440.465357) (xy 373.783098 -440.465972) (xy 381.219202 -440.465972)
			(xy 381.220472 -440.465972) (xy 381.229391 -440.465407) (xy 381.246012 -440.458869) (xy 381.259386 -440.447032)
			(xy 381.267895 -440.431329) (xy 381.269494 -440.422538) (xy 381.269494 -440.422284) (xy 381.274392 -440.3911)
			(xy 381.29122 -440.330259) (xy 381.315798 -440.272116) (xy 381.347712 -440.217652) (xy 381.386421 -440.167789)
			(xy 381.431272 -440.123369) (xy 381.481507 -440.085143) (xy 381.536276 -440.053757) (xy 381.594654 -440.029741)
			(xy 381.655654 -440.013501) (xy 381.718246 -440.005312) (xy 381.78137 -440.005312) (xy 381.843962 -440.013501)
			(xy 381.904962 -440.029741) (xy 381.96334 -440.053757) (xy 382.018109 -440.085143) (xy 382.068344 -440.123369)
			(xy 382.113195 -440.167789) (xy 382.151904 -440.217652) (xy 382.183818 -440.272116) (xy 382.208396 -440.330259)
			(xy 382.225224 -440.3911) (xy 382.230122 -440.422284) (xy 382.230122 -440.422538) (xy 382.231752 -440.431325)
			(xy 382.24024 -440.44704) (xy 382.253605 -440.458888) (xy 382.270224 -440.46543) (xy 382.279144 -440.465972)
			(xy 385.219194 -440.465972) (xy 385.220464 -440.465972) (xy 385.229384 -440.465408) (xy 385.246007 -440.458872)
			(xy 385.259384 -440.447035) (xy 385.267894 -440.431331) (xy 385.269486 -440.422538) (xy 385.269486 -440.422284)
			(xy 385.274384 -440.3911) (xy 385.291212 -440.330259) (xy 385.31579 -440.272116) (xy 385.347704 -440.217652)
			(xy 385.386413 -440.167789) (xy 385.431264 -440.123369) (xy 385.481499 -440.085143) (xy 385.536268 -440.053757)
			(xy 385.594646 -440.029741) (xy 385.655646 -440.013501) (xy 385.718238 -440.005312) (xy 385.781362 -440.005312)
			(xy 385.843954 -440.013501) (xy 385.904954 -440.029741) (xy 385.963332 -440.053757) (xy 386.018101 -440.085143)
			(xy 386.068336 -440.123369) (xy 386.113187 -440.167789) (xy 386.151896 -440.217652) (xy 386.18381 -440.272116)
			(xy 386.208388 -440.330259) (xy 386.225216 -440.3911) (xy 386.230114 -440.422284) (xy 386.230114 -440.422538)
			(xy 386.231744 -440.431326) (xy 386.240231 -440.447042) (xy 386.253596 -440.458892) (xy 386.270216 -440.465437)
			(xy 386.279136 -440.465972) (xy 389.219186 -440.465972) (xy 389.220456 -440.465972) (xy 389.229377 -440.465409)
			(xy 389.246002 -440.458874) (xy 389.259381 -440.447038) (xy 389.267894 -440.431333) (xy 389.269478 -440.422538)
			(xy 389.269478 -440.422284) (xy 389.274376 -440.3911) (xy 389.291204 -440.330259) (xy 389.315782 -440.272116)
			(xy 389.347696 -440.217652) (xy 389.386405 -440.167789) (xy 389.431256 -440.123369) (xy 389.481491 -440.085143)
			(xy 389.53626 -440.053757) (xy 389.594638 -440.029741) (xy 389.655638 -440.013501) (xy 389.71823 -440.005312)
			(xy 389.781354 -440.005312) (xy 389.843946 -440.013501) (xy 389.904946 -440.029741) (xy 389.963324 -440.053757)
			(xy 390.018093 -440.085143) (xy 390.068328 -440.123369) (xy 390.113179 -440.167789) (xy 390.151888 -440.217652)
			(xy 390.183802 -440.272116) (xy 390.20838 -440.330259) (xy 390.225208 -440.3911) (xy 390.230106 -440.422284)
			(xy 390.230106 -440.422538) (xy 390.231736 -440.431326) (xy 390.240223 -440.447044) (xy 390.253587 -440.458896)
			(xy 390.270207 -440.465443) (xy 390.279128 -440.465972) (xy 393.219178 -440.465972) (xy 393.220448 -440.465972)
			(xy 393.22937 -440.46541) (xy 393.245997 -440.458877) (xy 393.259379 -440.447041) (xy 393.267893 -440.431335)
			(xy 393.26947 -440.422538) (xy 393.26947 -440.422284) (xy 393.274368 -440.3911) (xy 393.291196 -440.330259)
			(xy 393.315774 -440.272116) (xy 393.347688 -440.217652) (xy 393.386397 -440.167789) (xy 393.431248 -440.123369)
			(xy 393.481483 -440.085143) (xy 393.536252 -440.053757) (xy 393.59463 -440.029741) (xy 393.65563 -440.013501)
			(xy 393.718222 -440.005312) (xy 393.781346 -440.005312) (xy 393.843938 -440.013501) (xy 393.904938 -440.029741)
			(xy 393.963316 -440.053757) (xy 394.018085 -440.085143) (xy 394.06832 -440.123369) (xy 394.113171 -440.167789)
			(xy 394.15188 -440.217652) (xy 394.183794 -440.272116) (xy 394.208372 -440.330259) (xy 394.2252 -440.3911)
			(xy 394.230098 -440.422284) (xy 394.230098 -440.422538) (xy 394.231727 -440.431327) (xy 394.240214 -440.447046)
			(xy 394.253578 -440.4589) (xy 394.270198 -440.46545) (xy 394.27912 -440.465972) (xy 398.219422 -440.465972)
			(xy 398.220692 -440.465972) (xy 398.229609 -440.465403) (xy 398.246224 -440.458862) (xy 398.259593 -440.447025)
			(xy 398.268097 -440.431324) (xy 398.269714 -440.422538) (xy 398.269714 -440.422284) (xy 398.274612 -440.3911)
			(xy 398.29144 -440.330259) (xy 398.316018 -440.272116) (xy 398.347932 -440.217652) (xy 398.386641 -440.167789)
			(xy 398.431492 -440.123369) (xy 398.481727 -440.085143) (xy 398.536496 -440.053757) (xy 398.594874 -440.029741)
			(xy 398.655874 -440.013501) (xy 398.718466 -440.005312) (xy 398.78159 -440.005312) (xy 398.844182 -440.013501)
			(xy 398.905182 -440.029741) (xy 398.96356 -440.053757) (xy 399.018329 -440.085143) (xy 399.068564 -440.123369)
			(xy 399.113415 -440.167789) (xy 399.152124 -440.217652) (xy 399.184038 -440.272116) (xy 399.208616 -440.330259)
			(xy 399.225444 -440.3911) (xy 399.230342 -440.422284) (xy 399.230342 -440.422538) (xy 399.231973 -440.431324)
			(xy 399.240461 -440.447035) (xy 399.253827 -440.458878) (xy 399.270446 -440.465415) (xy 399.279364 -440.465972)
			(xy 402.219414 -440.465972) (xy 402.220684 -440.465972) (xy 402.229602 -440.465405) (xy 402.246219 -440.458865)
			(xy 402.25959 -440.447028) (xy 402.268097 -440.431326) (xy 402.269706 -440.422538) (xy 402.269706 -440.422284)
			(xy 402.274604 -440.3911) (xy 402.291432 -440.330259) (xy 402.31601 -440.272116) (xy 402.347924 -440.217652)
			(xy 402.386633 -440.167789) (xy 402.431484 -440.123369) (xy 402.481719 -440.085143) (xy 402.536488 -440.053757)
			(xy 402.594866 -440.029741) (xy 402.655866 -440.013501) (xy 402.718458 -440.005312) (xy 402.781582 -440.005312)
			(xy 402.844174 -440.013501) (xy 402.905174 -440.029741) (xy 402.963552 -440.053757) (xy 403.018321 -440.085143)
			(xy 403.068556 -440.123369) (xy 403.113407 -440.167789) (xy 403.152116 -440.217652) (xy 403.18403 -440.272116)
			(xy 403.208608 -440.330259) (xy 403.225436 -440.3911) (xy 403.230334 -440.422284) (xy 403.230334 -440.422538)
			(xy 403.231964 -440.431324) (xy 403.240453 -440.447037) (xy 403.253818 -440.458882) (xy 403.270437 -440.465421)
			(xy 403.279356 -440.465972) (xy 406.219406 -440.465972) (xy 406.220676 -440.465972) (xy 406.229594 -440.465406)
			(xy 406.246214 -440.458868) (xy 406.259588 -440.447031) (xy 406.268096 -440.431328) (xy 406.269698 -440.422538)
			(xy 406.269698 -440.422284) (xy 406.274596 -440.3911) (xy 406.291424 -440.330259) (xy 406.316002 -440.272116)
			(xy 406.347916 -440.217652) (xy 406.386625 -440.167789) (xy 406.431476 -440.123369) (xy 406.481711 -440.085143)
			(xy 406.53648 -440.053757) (xy 406.594858 -440.029741) (xy 406.655858 -440.013501) (xy 406.71845 -440.005312)
			(xy 406.781574 -440.005312) (xy 406.844166 -440.013501) (xy 406.905166 -440.029741) (xy 406.963544 -440.053757)
			(xy 407.018313 -440.085143) (xy 407.068548 -440.123369) (xy 407.113399 -440.167789) (xy 407.152108 -440.217652)
			(xy 407.184022 -440.272116) (xy 407.2086 -440.330259) (xy 407.225428 -440.3911) (xy 407.230326 -440.422284)
			(xy 407.230326 -440.422538) (xy 407.231956 -440.431325) (xy 407.240444 -440.447039) (xy 407.253809 -440.458886)
			(xy 407.270429 -440.465427) (xy 407.279348 -440.465972) (xy 410.219398 -440.465972) (xy 410.220668 -440.465972)
			(xy 410.229587 -440.465407) (xy 410.246209 -440.45887) (xy 410.259585 -440.447034) (xy 410.268095 -440.43133)
			(xy 410.26969 -440.422538) (xy 410.26969 -440.422284) (xy 410.274588 -440.3911) (xy 410.291416 -440.330259)
			(xy 410.315994 -440.272116) (xy 410.347908 -440.217652) (xy 410.386617 -440.167789) (xy 410.431468 -440.123369)
			(xy 410.481703 -440.085143) (xy 410.536472 -440.053757) (xy 410.59485 -440.029741) (xy 410.65585 -440.013501)
			(xy 410.718442 -440.005312) (xy 410.781566 -440.005312) (xy 410.844158 -440.013501) (xy 410.905158 -440.029741)
			(xy 410.963536 -440.053757) (xy 411.018305 -440.085143) (xy 411.06854 -440.123369) (xy 411.113391 -440.167789)
			(xy 411.1521 -440.217652) (xy 411.184014 -440.272116) (xy 411.208592 -440.330259) (xy 411.22542 -440.3911)
			(xy 411.230318 -440.422284) (xy 411.230318 -440.422538) (xy 411.231948 -440.431325) (xy 411.240436 -440.447041)
			(xy 411.253801 -440.45889) (xy 411.27042 -440.465433) (xy 411.27934 -440.465972) (xy 456.315064 -440.465972)
			(xy 456.326359 -440.465373) (xy 456.346766 -440.45569) (xy 456.36104 -440.438184) (xy 456.36434 -440.427364)
			(xy 456.388216 -440.331606) (xy 456.389486 -440.323732) (xy 456.389839 -440.313715) (xy 456.383795 -440.294627)
			(xy 456.370959 -440.279259) (xy 456.362308 -440.274202) (xy 456.271116 -440.226075) (xy 456.092138 -440.123629)
			(xy 455.917305 -440.014262) (xy 455.746883 -439.89814) (xy 455.581133 -439.775442) (xy 455.420308 -439.646354)
			(xy 455.264656 -439.511075) (xy 455.114414 -439.369812) (xy 454.969812 -439.22278) (xy 454.831071 -439.070206)
			(xy 454.698404 -438.912321) (xy 454.572014 -438.749369) (xy 454.452094 -438.581598) (xy 454.338827 -438.409265)
			(xy 454.232388 -438.232633) (xy 454.132938 -438.051974) (xy 454.040631 -437.867563) (xy 453.955607 -437.679683)
			(xy 453.877996 -437.488622) (xy 453.807917 -437.294671) (xy 453.745478 -437.098127) (xy 453.690774 -436.899292)
			(xy 453.643889 -436.698469) (xy 453.604894 -436.495966) (xy 453.57385 -436.292093) (xy 453.550803 -436.087162)
			(xy 453.535789 -435.881486) (xy 453.52883 -435.67538) (xy 453.529939 -435.46916) (xy 453.539112 -435.263141)
			(xy 453.556336 -435.057638) (xy 453.581585 -434.852967) (xy 453.61482 -434.649439) (xy 453.655989 -434.447367)
			(xy 453.70503 -434.24706) (xy 453.761869 -434.048824) (xy 453.826417 -433.852963) (xy 453.898577 -433.659777)
			(xy 453.978237 -433.46956) (xy 454.065276 -433.282605) (xy 454.15956 -433.099198) (xy 454.260946 -432.919618)
			(xy 454.369278 -432.744141) (xy 454.484391 -432.573035) (xy 454.606108 -432.406563) (xy 454.734242 -432.244979)
			(xy 454.868599 -432.08853) (xy 455.008972 -431.937455) (xy 455.155146 -431.791987) (xy 455.306898 -431.652347)
			(xy 455.463996 -431.518749) (xy 455.626198 -431.391398) (xy 455.793258 -431.270488) (xy 455.964918 -431.156205)
			(xy 456.140918 -431.048724) (xy 456.320986 -430.948208) (xy 456.504848 -430.854812) (xy 456.692222 -430.768679)
			(xy 456.882822 -430.68994) (xy 457.076355 -430.618717) (xy 457.272526 -430.555117) (xy 457.471035 -430.499239)
			(xy 457.671577 -430.451168) (xy 457.873846 -430.410977) (xy 458.077532 -430.378728) (xy 458.282323 -430.35447)
			(xy 458.487907 -430.338241) (xy 458.693968 -430.330064) (xy 458.900191 -430.329954) (xy 459.106261 -430.33791)
			(xy 459.311862 -430.353919) (xy 459.516679 -430.377958) (xy 459.720399 -430.409989) (xy 459.922711 -430.449963)
			(xy 460.123305 -430.49782) (xy 460.321873 -430.553485) (xy 460.518112 -430.616875) (xy 460.711721 -430.687891)
			(xy 460.902405 -430.766426) (xy 461.089872 -430.852359) (xy 461.273833 -430.945558) (xy 461.454009 -431.04588)
			(xy 461.630123 -431.153174) (xy 461.801906 -431.267273) (xy 461.969095 -431.388003) (xy 462.131434 -431.515181)
			(xy 462.288674 -431.648611) (xy 462.440576 -431.788088) (xy 462.586905 -431.9334) (xy 462.72744 -432.084324)
			(xy 462.861964 -432.240629) (xy 462.990271 -432.402076) (xy 463.112166 -432.568418) (xy 463.227462 -432.739401)
			(xy 463.335982 -432.914761) (xy 463.43756 -433.094233) (xy 463.532041 -433.277539) (xy 463.576162 -433.370736)
			(xy 463.579401 -433.377091) (xy 463.58881 -433.387802) (xy 463.594704 -433.391818) (xy 463.628232 -433.413408)
			(xy 463.639408 -433.412138) (xy 463.736182 -433.390802) (xy 463.746444 -433.387959) (xy 463.763562 -433.375335)
			(xy 463.774117 -433.356869) (xy 463.775806 -433.346352) (xy 463.77606 -433.341272) (xy 463.77606 -409.528264)
			(xy 463.776591 -409.442432) (xy 463.784964 -409.270971) (xy 463.801675 -409.100122) (xy 463.826683 -408.930289)
			(xy 463.859929 -408.761874) (xy 463.901335 -408.595278) (xy 463.950802 -408.430895) (xy 464.008213 -408.269115)
			(xy 464.073432 -408.110322) (xy 464.146304 -407.954892) (xy 464.226656 -407.803194) (xy 464.314298 -407.655588)
			(xy 464.409022 -407.512423) (xy 464.510603 -407.37404) (xy 464.618801 -407.240766) (xy 464.733358 -407.112917)
			(xy 464.79333 -407.05151) (xy 464.808062 -407.036778) (xy 464.808062 -407.036524) (xy 466.636608 -405.207978)
			(xy 466.658299 -405.185621) (xy 466.696247 -405.13622) (xy 466.72742 -405.082289) (xy 466.751285 -405.024748)
			(xy 466.767434 -404.964585) (xy 466.77559 -404.902828) (xy 466.776054 -404.871682) (xy 466.776054 -82.82813)
			(xy 466.776586 -82.742298) (xy 466.784961 -82.570838) (xy 466.801673 -82.39999) (xy 466.826682 -82.230157)
			(xy 466.85993 -82.061744) (xy 466.901337 -81.895148) (xy 466.950805 -81.730766) (xy 467.008217 -81.568988)
			(xy 467.073437 -81.410196) (xy 467.14631 -81.254767) (xy 467.226663 -81.10307) (xy 467.314306 -80.955465)
			(xy 467.40903 -80.812301) (xy 467.510612 -80.673919) (xy 467.61881 -80.540646) (xy 467.733368 -80.412798)
			(xy 467.793324 -80.351376) (xy 467.808056 -80.336644) (xy 467.808056 -80.33639) (xy 470.136474 -78.007972)
			(xy 470.158166 -77.985616) (xy 470.196116 -77.936216) (xy 470.22729 -77.882284) (xy 470.251157 -77.824744)
			(xy 470.267306 -77.76458) (xy 470.275462 -77.702823) (xy 470.27592 -77.671676) (xy 470.27592 -13.780008)
			(xy 470.275411 -13.748842) (xy 470.267276 -13.687043) (xy 470.251145 -13.626835) (xy 470.227293 -13.569247)
			(xy 470.196128 -13.515265) (xy 470.158185 -13.465813) (xy 470.114111 -13.421736) (xy 470.064661 -13.383789)
			(xy 470.010681 -13.352621) (xy 469.953095 -13.328766) (xy 469.892888 -13.31263) (xy 469.83109 -13.304491)
			(xy 469.799924 -13.304012) (xy 458.20203 -13.304012) (xy 458.118154 -13.303522) (xy 457.950593 -13.295541)
			(xy 457.783601 -13.279597) (xy 457.617557 -13.255724) (xy 457.452837 -13.223979) (xy 457.289814 -13.184431)
			(xy 457.128858 -13.137171) (xy 456.970332 -13.082306) (xy 456.814597 -13.019961) (xy 456.662004 -12.950276)
			(xy 456.5129 -12.873409) (xy 456.367623 -12.789534) (xy 456.226501 -12.698842) (xy 456.089854 -12.601537)
			(xy 455.957992 -12.497841) (xy 455.831213 -12.387988) (xy 455.709805 -12.272228) (xy 455.594043 -12.150821)
			(xy 455.484188 -12.024044) (xy 455.38049 -11.892183) (xy 455.283184 -11.755537) (xy 455.19249 -11.614417)
			(xy 455.108614 -11.46914) (xy 455.031745 -11.320037) (xy 454.962057 -11.167446) (xy 454.89971 -11.011711)
			(xy 454.844843 -10.853186) (xy 454.797581 -10.69223) (xy 454.758031 -10.529208) (xy 454.726283 -10.364488)
			(xy 454.702409 -10.198445) (xy 454.686462 -10.031453) (xy 454.67848 -9.863892) (xy 454.678034 -9.780016)
			(xy 454.678034 -7.29234) (xy 454.677691 -7.283605) (xy 454.671823 -7.267153) (xy 454.66073 -7.253659)
			(xy 454.653396 -7.248906) (xy 454.578974 -7.203694) (xy 454.5711 -7.199884) (xy 454.560642 -7.196362)
			(xy 454.538638 -7.197667) (xy 454.528682 -7.202424) (xy 454.486547 -7.224219) (xy 454.399396 -7.261709)
			(xy 454.309493 -7.292011) (xy 454.21743 -7.314927) (xy 454.123812 -7.330305) (xy 454.029256 -7.338045)
			(xy 453.98182 -7.338568) (xy 453.933503 -7.338083) (xy 453.837199 -7.330105) (xy 453.741883 -7.314201)
			(xy 453.648206 -7.29048) (xy 453.556808 -7.259104) (xy 453.468312 -7.220288) (xy 453.383325 -7.174296)
			(xy 453.302426 -7.121443) (xy 453.226168 -7.062091) (xy 453.155071 -6.996643) (xy 453.089622 -6.925548)
			(xy 453.030268 -6.84929) (xy 452.977414 -6.768392) (xy 452.931421 -6.683406) (xy 452.892603 -6.594911)
			(xy 452.861226 -6.503513) (xy 452.837503 -6.409836) (xy 452.821598 -6.314521) (xy 452.813618 -6.218217)
			(xy 452.813618 -6.121583) (xy 452.821598 -6.025279) (xy 452.837503 -5.929964) (xy 452.861226 -5.836287)
			(xy 452.892603 -5.744889) (xy 452.931421 -5.656394) (xy 452.977414 -5.571408) (xy 453.030268 -5.49051)
			(xy 453.089622 -5.414252) (xy 453.155071 -5.343157) (xy 453.226168 -5.277709) (xy 453.302426 -5.218357)
			(xy 453.383325 -5.165504) (xy 453.468312 -5.119512) (xy 453.556808 -5.080696) (xy 453.648206 -5.04932)
			(xy 453.741883 -5.025599) (xy 453.837199 -5.009695) (xy 453.933503 -5.001717) (xy 453.98182 -5.00126)
			(xy 454.029257 -5.001754) (xy 454.123817 -5.009483) (xy 454.217439 -5.024857) (xy 454.309505 -5.047774)
			(xy 454.399409 -5.078083) (xy 454.486558 -5.115585) (xy 454.528682 -5.137404) (xy 454.538657 -5.142095)
			(xy 454.560639 -5.143416) (xy 454.5711 -5.139944) (xy 454.578974 -5.136134) (xy 454.653396 -5.090922)
			(xy 454.660683 -5.086113) (xy 454.671749 -5.072622) (xy 454.677671 -5.05621) (xy 454.678034 -5.047488)
			(xy 454.678034 -1.5748) (xy 454.677547 -1.56479) (xy 454.669888 -1.546292) (xy 454.655736 -1.532131)
			(xy 454.637244 -1.52446) (xy 454.627234 -1.524) (xy 389.176768 -1.524) (xy 389.166765 -1.524494)
			(xy 389.148284 -1.532159) (xy 389.134141 -1.546311) (xy 389.126487 -1.564796) (xy 389.125968 -1.5748)
			(xy 389.125968 -4.044442) (xy 389.126324 -4.053169) (xy 389.13221 -4.069601) (xy 389.143309 -4.083072)
			(xy 389.150606 -4.087876) (xy 389.224774 -4.133088) (xy 389.237982 -4.138676) (xy 389.247276 -4.140771)
			(xy 389.266199 -4.138684) (xy 389.274812 -4.134612) (xy 389.316649 -4.113242) (xy 389.403115 -4.076491)
			(xy 389.492252 -4.046798) (xy 389.583485 -4.024353) (xy 389.676224 -4.009303) (xy 389.769872 -4.001743)
			(xy 389.816848 -4.001262) (xy 389.865161 -4.001763) (xy 389.961458 -4.009746) (xy 390.056766 -4.025654)
			(xy 390.150435 -4.049378) (xy 390.241825 -4.080755) (xy 390.330312 -4.119572) (xy 390.415291 -4.165564)
			(xy 390.496182 -4.218416) (xy 390.572433 -4.277767) (xy 390.643522 -4.343212) (xy 390.708964 -4.414304)
			(xy 390.768312 -4.490557) (xy 390.821161 -4.57145) (xy 390.867149 -4.656431) (xy 390.905962 -4.74492)
			(xy 390.937336 -4.836311) (xy 390.961056 -4.929981) (xy 390.97696 -5.02529) (xy 390.984939 -5.121587)
			(xy 390.984939 -5.218213) (xy 390.97696 -5.31451) (xy 390.961056 -5.409819) (xy 390.937336 -5.503489)
			(xy 390.905962 -5.59488) (xy 390.867149 -5.683369) (xy 390.821161 -5.76835) (xy 390.768312 -5.849243)
			(xy 390.708964 -5.925496) (xy 390.643522 -5.996588) (xy 390.572433 -6.062033) (xy 390.496182 -6.121384)
			(xy 390.415291 -6.174236) (xy 390.330312 -6.220228) (xy 390.241825 -6.259045) (xy 390.150435 -6.290422)
			(xy 390.056766 -6.314146) (xy 389.961458 -6.330054) (xy 389.865161 -6.338037) (xy 389.816848 -6.33857)
			(xy 389.769871 -6.338101) (xy 389.67622 -6.330556) (xy 389.583478 -6.315512) (xy 389.492245 -6.293064)
			(xy 389.40311 -6.263359) (xy 389.316651 -6.226589) (xy 389.274812 -6.20522) (xy 389.266201 -6.201137)
			(xy 389.247274 -6.199041) (xy 389.237982 -6.201156) (xy 389.234516 -6.202127) (xy 389.227887 -6.204935)
			(xy 389.224774 -6.206744) (xy 389.150606 -6.251956) (xy 389.143316 -6.256764) (xy 389.132244 -6.270253)
			(xy 389.126315 -6.286666) (xy 389.125968 -6.29539) (xy 389.125968 -6.598158) (xy 392.428222 -6.598158)
			(xy 392.428685 -6.570888) (xy 392.436452 -6.516905) (xy 392.451822 -6.464576) (xy 392.474482 -6.414966)
			(xy 392.503971 -6.369087) (xy 392.539688 -6.32787) (xy 392.580907 -6.292155) (xy 392.626789 -6.26267)
			(xy 392.6764 -6.240013) (xy 392.72873 -6.224647) (xy 392.782714 -6.216883) (xy 392.809984 -6.216396)
			(xy 392.810238 -6.216396) (xy 392.829796 -6.216904) (xy 392.840718 -6.217412) (xy 392.860784 -6.210046)
			(xy 392.929618 -6.140958) (xy 392.937238 -6.121146) (xy 392.93673 -6.110224) (xy 392.936222 -6.091174)
			(xy 392.9367 -6.063905) (xy 392.944465 -6.009922) (xy 392.959833 -5.957593) (xy 392.982491 -5.907984)
			(xy 393.011978 -5.862104) (xy 393.047694 -5.820887) (xy 393.088912 -5.785172) (xy 393.134793 -5.755686)
			(xy 393.184402 -5.733029) (xy 393.236731 -5.717663) (xy 393.290715 -5.7099) (xy 393.317984 -5.709412)
			(xy 393.3468 -5.709883) (xy 393.403776 -5.718565) (xy 393.458802 -5.735704) (xy 393.51063 -5.760911)
			(xy 393.558086 -5.793615) (xy 393.600092 -5.833075) (xy 393.635697 -5.878394) (xy 393.664093 -5.928547)
			(xy 393.674854 -5.955284) (xy 393.679841 -5.966338) (xy 393.69787 -5.982508) (xy 393.709398 -5.986272)
			(xy 393.746493 -5.9965) (xy 393.818584 -6.023419) (xy 393.887599 -6.057458) (xy 393.920472 -6.077458)
			(xy 393.928728 -6.082172) (xy 393.947396 -6.085699) (xy 393.966064 -6.082172) (xy 393.97432 -6.077458)
			(xy 394.007202 -6.057473) (xy 394.076218 -6.023441) (xy 394.148303 -5.996511) (xy 394.185394 -5.986272)
			(xy 394.196957 -5.982569) (xy 394.215001 -5.966377) (xy 394.219938 -5.955284) (xy 394.230707 -5.92855)
			(xy 394.259091 -5.878393) (xy 394.29469 -5.833071) (xy 394.336696 -5.793612) (xy 394.384153 -5.760914)
			(xy 394.435985 -5.735717) (xy 394.491015 -5.718595) (xy 394.547992 -5.709937) (xy 394.576808 -5.709412)
			(xy 394.587564 -5.709519) (xy 394.60904 -5.710789) (xy 394.619734 -5.711952) (xy 394.630656 -5.713222)
			(xy 394.651484 -5.706364) (xy 394.716254 -5.646674) (xy 394.723884 -5.639) (xy 394.732428 -5.619137)
			(xy 394.732764 -5.60832) (xy 394.732764 -5.608066) (xy 394.73251 -5.597652) (xy 394.73251 -5.597398)
			(xy 394.732898 -5.572667) (xy 394.73927 -5.523618) (xy 394.74521 -5.499608) (xy 394.74785 -5.487606)
			(xy 394.742524 -5.463643) (xy 394.73505 -5.453888) (xy 394.718213 -5.433581) (xy 394.68707 -5.390997)
			(xy 394.67282 -5.368798) (xy 394.667808 -5.361478) (xy 394.653834 -5.350566) (xy 394.636988 -5.345039)
			(xy 394.628116 -5.344922) (xy 394.614654 -5.345176) (xy 394.587388 -5.344658) (xy 394.533411 -5.336892)
			(xy 394.481089 -5.321523) (xy 394.431486 -5.298865) (xy 394.385613 -5.269379) (xy 394.344402 -5.233665)
			(xy 394.308693 -5.19245) (xy 394.279213 -5.146573) (xy 394.256561 -5.096968) (xy 394.241198 -5.044644)
			(xy 394.233438 -4.990666) (xy 394.233438 -4.936134) (xy 394.241198 -4.882156) (xy 394.256561 -4.829832)
			(xy 394.279213 -4.780227) (xy 394.308693 -4.73435) (xy 394.344402 -4.693135) (xy 394.385613 -4.657421)
			(xy 394.431486 -4.627935) (xy 394.481089 -4.605277) (xy 394.533411 -4.589908) (xy 394.587388 -4.582142)
			(xy 394.614654 -4.581652) (xy 394.628116 -4.581906) (xy 394.637001 -4.581876) (xy 394.653878 -4.576356)
			(xy 394.667846 -4.565393) (xy 394.67282 -4.55803) (xy 394.687084 -4.53584) (xy 394.718225 -4.493256)
			(xy 394.73505 -4.47294) (xy 394.742339 -4.463099) (xy 394.747638 -4.439224) (xy 394.74521 -4.42722)
			(xy 394.73929 -4.4034) (xy 394.73292 -4.354733) (xy 394.73251 -4.330192) (xy 394.73251 -4.32943)
			(xy 394.733029 -4.302161) (xy 394.740787 -4.248178) (xy 394.756148 -4.195848) (xy 394.7788 -4.146236)
			(xy 394.808282 -4.100354) (xy 394.843993 -4.059134) (xy 394.885208 -4.023416) (xy 394.931086 -3.993928)
			(xy 394.980693 -3.971268) (xy 395.033021 -3.955899) (xy 395.087003 -3.948133) (xy 395.114272 -3.947668)
			(xy 395.14295 -3.948235) (xy 395.199659 -3.956818) (xy 395.254449 -3.973782) (xy 395.306088 -3.998744)
			(xy 395.353415 -4.031145) (xy 395.395368 -4.070255) (xy 395.431003 -4.115197) (xy 395.459521 -4.164961)
			(xy 395.47038 -4.191508) (xy 395.475438 -4.20265) (xy 395.493758 -4.218823) (xy 395.505432 -4.222496)
			(xy 395.544079 -4.232699) (xy 395.619167 -4.26011) (xy 395.690985 -4.295208) (xy 395.725142 -4.315968)
			(xy 395.733403 -4.320664) (xy 395.752066 -4.324172) (xy 395.770729 -4.320664) (xy 395.77899 -4.315968)
			(xy 395.811487 -4.296173) (xy 395.879674 -4.262388) (xy 395.950883 -4.235555) (xy 395.987524 -4.22529)
			(xy 395.999071 -4.221547) (xy 396.017123 -4.205384) (xy 396.022068 -4.194302) (xy 396.032844 -4.16752)
			(xy 396.06118 -4.11723) (xy 396.096761 -4.071776) (xy 396.138777 -4.032194) (xy 396.186271 -3.999386)
			(xy 396.238161 -3.974098) (xy 396.293266 -3.956907) (xy 396.35033 -3.948205) (xy 396.379192 -3.947668)
			(xy 396.406464 -3.948109) (xy 396.460453 -3.955871) (xy 396.512788 -3.971238) (xy 396.562403 -3.993896)
			(xy 396.608289 -4.023386) (xy 396.64951 -4.059106) (xy 396.685227 -4.100329) (xy 396.714714 -4.146216)
			(xy 396.73737 -4.195832) (xy 396.752734 -4.248168) (xy 396.760493 -4.302158) (xy 396.760954 -4.32943)
			(xy 396.760954 -4.329684) (xy 396.760599 -4.352127) (xy 396.755245 -4.396693) (xy 396.750286 -4.418584)
			(xy 396.748149 -4.430576) (xy 396.753977 -4.454187) (xy 396.761462 -4.463796) (xy 396.78049 -4.486154)
			(xy 396.815456 -4.533322) (xy 396.831312 -4.55803) (xy 396.836324 -4.565351) (xy 396.850295 -4.576269)
			(xy 396.867143 -4.581793) (xy 396.876016 -4.581906) (xy 396.889478 -4.581652) (xy 396.916751 -4.582086)
			(xy 396.970742 -4.589846) (xy 397.023079 -4.605211) (xy 397.072697 -4.627868) (xy 397.118585 -4.657356)
			(xy 397.15981 -4.693075) (xy 397.195531 -4.734297) (xy 397.225021 -4.780183) (xy 397.247681 -4.8298)
			(xy 397.263049 -4.882136) (xy 397.270812 -4.936127) (xy 397.270812 -4.990673) (xy 397.263049 -5.044664)
			(xy 397.247681 -5.097) (xy 397.225021 -5.146617) (xy 397.195531 -5.192503) (xy 397.15981 -5.233725)
			(xy 397.118585 -5.269444) (xy 397.072697 -5.298932) (xy 397.023079 -5.321589) (xy 396.970742 -5.336954)
			(xy 396.916751 -5.344714) (xy 396.889478 -5.345176) (xy 396.876016 -5.344922) (xy 396.867132 -5.344961)
			(xy 396.850253 -5.350474) (xy 396.836285 -5.361436) (xy 396.831312 -5.368798) (xy 396.815464 -5.393512)
			(xy 396.780498 -5.44068) (xy 396.761462 -5.463032) (xy 396.754023 -5.472666) (xy 396.748179 -5.496257)
			(xy 396.750286 -5.508244) (xy 396.75524 -5.5302) (xy 396.760593 -5.574893) (xy 396.760954 -5.597398)
			(xy 396.760954 -5.597652) (xy 396.7607 -5.60832) (xy 396.760977 -5.619209) (xy 396.769518 -5.639218)
			(xy 396.77721 -5.646928) (xy 396.833852 -5.698998) (xy 396.842244 -5.705905) (xy 396.862885 -5.712634)
			(xy 396.87373 -5.711952) (xy 396.874238 -5.711952) (xy 396.885121 -5.710769) (xy 396.906979 -5.709497)
			(xy 396.917926 -5.709412) (xy 396.946741 -5.709933) (xy 397.003714 -5.718607) (xy 397.058739 -5.735737)
			(xy 397.110567 -5.760937) (xy 397.158023 -5.793635) (xy 397.20003 -5.833088) (xy 397.235636 -5.878402)
			(xy 397.264034 -5.928549) (xy 397.274796 -5.955284) (xy 397.279763 -5.96635) (xy 397.297806 -5.982515)
			(xy 397.30934 -5.986272) (xy 397.346438 -5.99649) (xy 397.418528 -6.023413) (xy 397.487541 -6.057456)
			(xy 397.520414 -6.077458) (xy 397.52867 -6.082172) (xy 397.547338 -6.085699) (xy 397.566006 -6.082172)
			(xy 397.574262 -6.077458) (xy 397.607139 -6.057465) (xy 397.676157 -6.023436) (xy 397.748244 -5.996509)
			(xy 397.785336 -5.986272) (xy 397.796889 -5.982543) (xy 397.814938 -5.966371) (xy 397.81988 -5.955284)
			(xy 397.830614 -5.928535) (xy 397.859003 -5.878377) (xy 397.894606 -5.833054) (xy 397.936616 -5.793596)
			(xy 397.984079 -5.760898) (xy 398.035916 -5.735705) (xy 398.090951 -5.718587) (xy 398.147932 -5.709933)
			(xy 398.17675 -5.709412) (xy 398.18757 -5.709513) (xy 398.209173 -5.710782) (xy 398.21993 -5.711952)
			(xy 398.230852 -5.713222) (xy 398.25168 -5.706364) (xy 398.31645 -5.646674) (xy 398.32408 -5.639)
			(xy 398.332624 -5.619137) (xy 398.33296 -5.60832) (xy 398.33296 -5.608066) (xy 398.332706 -5.597398)
			(xy 398.332706 -5.59689) (xy 398.33305 -5.572356) (xy 398.339297 -5.523689) (xy 398.345152 -5.499862)
			(xy 398.347579 -5.487921) (xy 398.342264 -5.464175) (xy 398.334992 -5.454396) (xy 398.318153 -5.433958)
			(xy 398.287008 -5.391121) (xy 398.272762 -5.368798) (xy 398.267724 -5.361498) (xy 398.253762 -5.350582)
			(xy 398.236926 -5.345046) (xy 398.228058 -5.344922) (xy 398.214596 -5.345176) (xy 398.187328 -5.344661)
			(xy 398.133347 -5.336899) (xy 398.081019 -5.321534) (xy 398.031412 -5.298879) (xy 397.985533 -5.269394)
			(xy 397.944317 -5.23368) (xy 397.908604 -5.192464) (xy 397.879119 -5.146585) (xy 397.856464 -5.096977)
			(xy 397.8411 -5.044649) (xy 397.833338 -4.990668) (xy 397.833338 -4.936132) (xy 397.8411 -4.882151)
			(xy 397.856464 -4.829823) (xy 397.879119 -4.780215) (xy 397.908604 -4.734336) (xy 397.944317 -4.69312)
			(xy 397.985533 -4.657406) (xy 398.031412 -4.627921) (xy 398.081019 -4.605266) (xy 398.133347 -4.589901)
			(xy 398.187328 -4.582139) (xy 398.214596 -4.581652) (xy 398.228058 -4.581906) (xy 398.236944 -4.581907)
			(xy 398.253824 -4.576373) (xy 398.26779 -4.565398) (xy 398.272762 -4.55803) (xy 398.287003 -4.535703)
			(xy 398.318145 -4.492864) (xy 398.334992 -4.472432) (xy 398.342268 -4.462654) (xy 398.347582 -4.438908)
			(xy 398.345152 -4.426966) (xy 398.339328 -4.403133) (xy 398.333086 -4.354469) (xy 398.332706 -4.329938)
			(xy 398.332706 -4.32943) (xy 398.333252 -4.302163) (xy 398.341009 -4.248183) (xy 398.356369 -4.195857)
			(xy 398.379019 -4.146249) (xy 398.408499 -4.100369) (xy 398.444208 -4.059152) (xy 398.485419 -4.023436)
			(xy 398.531294 -3.993949) (xy 398.580898 -3.971291) (xy 398.633222 -3.955922) (xy 398.687201 -3.948157)
			(xy 398.714468 -3.947668) (xy 398.743146 -3.948238) (xy 398.799855 -3.956821) (xy 398.854645 -3.973784)
			(xy 398.906283 -3.998746) (xy 398.953611 -4.031146) (xy 398.995563 -4.070256) (xy 399.031199 -4.115198)
			(xy 399.059717 -4.164961) (xy 399.070576 -4.191508) (xy 399.075636 -4.202649) (xy 399.093954 -4.218823)
			(xy 399.105628 -4.222496) (xy 399.144223 -4.232676) (xy 399.21922 -4.260007) (xy 399.29096 -4.295008)
			(xy 399.325084 -4.315714) (xy 399.33334 -4.320428) (xy 399.352008 -4.323955) (xy 399.370676 -4.320428)
			(xy 399.378932 -4.315714) (xy 399.411502 -4.295886) (xy 399.479858 -4.262087) (xy 399.551242 -4.235267)
			(xy 399.587974 -4.225036) (xy 399.599454 -4.221266) (xy 399.617356 -4.205089) (xy 399.622264 -4.194048)
			(xy 399.633001 -4.167262) (xy 399.661371 -4.117012) (xy 399.696977 -4.071601) (xy 399.739007 -4.032061)
			(xy 399.786505 -3.999292) (xy 399.838392 -3.974039) (xy 399.893486 -3.956877) (xy 399.950535 -3.948196)
			(xy 399.979388 -3.947668) (xy 400.00666 -3.948113) (xy 400.060649 -3.955874) (xy 400.112984 -3.97124)
			(xy 400.162599 -3.993899) (xy 400.208484 -4.023388) (xy 400.249705 -4.059107) (xy 400.285423 -4.10033)
			(xy 400.31491 -4.146217) (xy 400.337566 -4.195833) (xy 400.35293 -4.248168) (xy 400.360689 -4.302158)
			(xy 400.36115 -4.32943) (xy 400.36115 -4.330192) (xy 400.360773 -4.352571) (xy 400.355427 -4.397009)
			(xy 400.350482 -4.418838) (xy 400.34831 -4.430826) (xy 400.354162 -4.454443) (xy 400.361658 -4.46405)
			(xy 400.380613 -4.486353) (xy 400.41545 -4.533394) (xy 400.431254 -4.55803) (xy 400.436302 -4.565323)
			(xy 400.450256 -4.576246) (xy 400.46709 -4.581784) (xy 400.475958 -4.581906) (xy 400.48942 -4.581652)
			(xy 400.516689 -4.582112) (xy 400.570673 -4.589876) (xy 400.623002 -4.605244) (xy 400.672611 -4.627902)
			(xy 400.718491 -4.657389) (xy 400.759708 -4.693106) (xy 400.795423 -4.734325) (xy 400.824908 -4.780206)
			(xy 400.847563 -4.829817) (xy 400.862928 -4.882147) (xy 400.87069 -4.936131) (xy 400.87069 -4.990669)
			(xy 400.862928 -5.044653) (xy 400.847563 -5.096983) (xy 400.824908 -5.146594) (xy 400.795423 -5.192475)
			(xy 400.759708 -5.233694) (xy 400.718491 -5.269411) (xy 400.672611 -5.298898) (xy 400.623002 -5.321556)
			(xy 400.570673 -5.336924) (xy 400.516689 -5.344688) (xy 400.48942 -5.345176) (xy 400.475958 -5.344922)
			(xy 400.467071 -5.34492) (xy 400.450191 -5.350452) (xy 400.436224 -5.361429) (xy 400.431254 -5.368798)
			(xy 400.415459 -5.39344) (xy 400.380621 -5.440482) (xy 400.361658 -5.462778) (xy 400.354192 -5.472395)
			(xy 400.348364 -5.496) (xy 400.350482 -5.50799) (xy 400.355421 -5.52982) (xy 400.360769 -5.574258)
			(xy 400.36115 -5.596636) (xy 400.36115 -5.597398) (xy 400.360896 -5.608066) (xy 400.360896 -5.60832)
			(xy 400.361155 -5.61915) (xy 400.369731 -5.639025) (xy 400.377406 -5.646674) (xy 400.434048 -5.698998)
			(xy 400.442441 -5.705903) (xy 400.463081 -5.712633) (xy 400.473926 -5.711952) (xy 400.474434 -5.711952)
			(xy 400.48519 -5.710777) (xy 400.506794 -5.709508) (xy 400.517614 -5.709412) (xy 400.517868 -5.709412)
			(xy 400.546684 -5.709897) (xy 400.603659 -5.718576) (xy 400.658684 -5.735713) (xy 400.710513 -5.760918)
			(xy 400.757968 -5.79362) (xy 400.799975 -5.833078) (xy 400.835581 -5.878396) (xy 400.863977 -5.928547)
			(xy 400.874738 -5.955284) (xy 400.879733 -5.966334) (xy 400.897756 -5.982506) (xy 400.909282 -5.986272)
			(xy 400.946376 -5.996503) (xy 401.018467 -6.023421) (xy 401.087482 -6.057459) (xy 401.120356 -6.077458)
			(xy 401.128612 -6.082172) (xy 401.14728 -6.085699) (xy 401.165948 -6.082172) (xy 401.174204 -6.077458)
			(xy 401.207088 -6.057476) (xy 401.276103 -6.023443) (xy 401.348187 -5.996512) (xy 401.385278 -5.986272)
			(xy 401.396838 -5.982562) (xy 401.414883 -5.966375) (xy 401.419822 -5.955284) (xy 401.430521 -5.92852)
			(xy 401.458914 -5.87836) (xy 401.494522 -5.833036) (xy 401.536537 -5.793579) (xy 401.584005 -5.760883)
			(xy 401.635847 -5.735692) (xy 401.690887 -5.718579) (xy 401.747873 -5.70993) (xy 401.776692 -5.709412)
			(xy 401.787512 -5.70951) (xy 401.809115 -5.710781) (xy 401.819872 -5.711952) (xy 401.830794 -5.713222)
			(xy 401.851622 -5.706364) (xy 401.916392 -5.646674) (xy 401.924014 -5.638992) (xy 401.932565 -5.619135)
			(xy 401.932902 -5.60832) (xy 401.932902 -5.608066) (xy 401.932648 -5.597398) (xy 401.932648 -5.59689)
			(xy 401.932994 -5.572356) (xy 401.939239 -5.523689) (xy 401.945094 -5.499862) (xy 401.947512 -5.48792)
			(xy 401.942201 -5.464177) (xy 401.934934 -5.454396) (xy 401.918092 -5.43396) (xy 401.886949 -5.391122)
			(xy 401.872704 -5.368798) (xy 401.867701 -5.361471) (xy 401.853724 -5.350559) (xy 401.836873 -5.345037)
			(xy 401.828 -5.344922) (xy 401.814538 -5.345176) (xy 401.787266 -5.344687) (xy 401.733277 -5.33693)
			(xy 401.680942 -5.321567) (xy 401.631326 -5.298913) (xy 401.585439 -5.269427) (xy 401.544216 -5.233711)
			(xy 401.508496 -5.192491) (xy 401.479006 -5.146608) (xy 401.456346 -5.096994) (xy 401.440978 -5.04466)
			(xy 401.433216 -4.990672) (xy 401.433216 -4.936128) (xy 401.440978 -4.88214) (xy 401.456346 -4.829806)
			(xy 401.479006 -4.780192) (xy 401.508496 -4.734309) (xy 401.544216 -4.693089) (xy 401.585439 -4.657373)
			(xy 401.631326 -4.627887) (xy 401.680942 -4.605233) (xy 401.733277 -4.58987) (xy 401.787266 -4.582113)
			(xy 401.814538 -4.581652) (xy 401.828 -4.581906) (xy 401.836884 -4.581865) (xy 401.853761 -4.57635)
			(xy 401.86773 -4.565391) (xy 401.872704 -4.55803) (xy 401.886948 -4.535705) (xy 401.918088 -4.492865)
			(xy 401.934934 -4.472432) (xy 401.942213 -4.462656) (xy 401.947523 -4.438909) (xy 401.945094 -4.426966)
			(xy 401.939271 -4.403133) (xy 401.933028 -4.354469) (xy 401.932648 -4.329938) (xy 401.932648 -4.32943)
			(xy 401.933129 -4.302159) (xy 401.940888 -4.248173) (xy 401.956251 -4.19584) (xy 401.978906 -4.146226)
			(xy 402.008391 -4.100342) (xy 402.044107 -4.059121) (xy 402.085326 -4.023403) (xy 402.131208 -3.993915)
			(xy 402.180821 -3.971258) (xy 402.233153 -3.955892) (xy 402.287139 -3.948131) (xy 402.31441 -3.947668)
			(xy 402.343089 -3.948202) (xy 402.3998 -3.956791) (xy 402.45459 -3.97376) (xy 402.506229 -3.998727)
			(xy 402.553556 -4.031132) (xy 402.595508 -4.070247) (xy 402.631143 -4.115192) (xy 402.65966 -4.164959)
			(xy 402.670518 -4.191508) (xy 402.675606 -4.202633) (xy 402.693905 -4.218813) (xy 402.70557 -4.222496)
			(xy 402.744161 -4.23269) (xy 402.81916 -4.260015) (xy 402.890901 -4.295011) (xy 402.925026 -4.315714)
			(xy 402.933282 -4.320428) (xy 402.95195 -4.323955) (xy 402.970618 -4.320428) (xy 402.978874 -4.315714)
			(xy 403.011439 -4.295878) (xy 403.079797 -4.262081) (xy 403.151183 -4.235265) (xy 403.187916 -4.225036)
			(xy 403.199403 -4.221284) (xy 403.217301 -4.205094) (xy 403.222206 -4.194048) (xy 403.232908 -4.167247)
			(xy 403.261283 -4.116996) (xy 403.296892 -4.071584) (xy 403.338927 -4.032044) (xy 403.386431 -3.999276)
			(xy 403.438323 -3.974026) (xy 403.493422 -3.956869) (xy 403.550475 -3.948193) (xy 403.57933 -3.947668)
			(xy 403.606601 -3.948097) (xy 403.660589 -3.955863) (xy 403.712921 -3.971234) (xy 403.762533 -3.993896)
			(xy 403.808416 -4.023387) (xy 403.849634 -4.059109) (xy 403.885349 -4.100332) (xy 403.914833 -4.146219)
			(xy 403.937487 -4.195835) (xy 403.95285 -4.24817) (xy 403.960608 -4.302158) (xy 403.961092 -4.32943)
			(xy 403.961092 -4.330192) (xy 403.960716 -4.352571) (xy 403.955369 -4.397009) (xy 403.950424 -4.418838)
			(xy 403.948242 -4.430826) (xy 403.954099 -4.454445) (xy 403.9616 -4.46405) (xy 403.980557 -4.486351)
			(xy 404.015393 -4.533393) (xy 404.031196 -4.55803) (xy 404.036218 -4.565343) (xy 404.050184 -4.576263)
			(xy 404.067029 -4.58179) (xy 404.0759 -4.581906) (xy 404.089362 -4.581652) (xy 404.116636 -4.582085)
			(xy 404.170629 -4.589843) (xy 404.222968 -4.605206) (xy 404.272588 -4.627863) (xy 404.318478 -4.65735)
			(xy 404.359704 -4.693069) (xy 404.395427 -4.734292) (xy 404.424919 -4.780179) (xy 404.44758 -4.829796)
			(xy 404.462949 -4.882134) (xy 404.470712 -4.936126) (xy 404.470712 -4.990674) (xy 404.462949 -5.044666)
			(xy 404.44758 -5.097004) (xy 404.424919 -5.146621) (xy 404.395427 -5.192508) (xy 404.359704 -5.233731)
			(xy 404.318478 -5.26945) (xy 404.272588 -5.298937) (xy 404.222968 -5.321594) (xy 404.170629 -5.336957)
			(xy 404.116636 -5.344715) (xy 404.089362 -5.345176) (xy 404.0759 -5.344922) (xy 404.067015 -5.34495)
			(xy 404.050136 -5.350468) (xy 404.036168 -5.361434) (xy 404.031196 -5.368798) (xy 404.015399 -5.393439)
			(xy 403.980562 -5.440481) (xy 403.9616 -5.462778) (xy 403.954137 -5.472397) (xy 403.948306 -5.496)
			(xy 403.950424 -5.50799) (xy 403.955385 -5.529945) (xy 403.960734 -5.574638) (xy 403.961092 -5.597144)
			(xy 403.961092 -5.597652) (xy 403.960838 -5.60832) (xy 403.961104 -5.61921) (xy 403.969651 -5.639221)
			(xy 403.977348 -5.646928) (xy 404.03399 -5.698998) (xy 404.042368 -5.705925) (xy 404.06302 -5.712641)
			(xy 404.073868 -5.711952) (xy 404.074376 -5.711952) (xy 404.085259 -5.710766) (xy 404.107117 -5.709496)
			(xy 404.118064 -5.709412) (xy 404.14688 -5.7099) (xy 404.203855 -5.718579) (xy 404.25888 -5.735715)
			(xy 404.310708 -5.76092) (xy 404.358164 -5.793622) (xy 404.400171 -5.833079) (xy 404.435776 -5.878397)
			(xy 404.464173 -5.928548) (xy 404.474934 -5.955284) (xy 404.479931 -5.966333) (xy 404.497953 -5.982505)
			(xy 404.509478 -5.986272) (xy 404.546572 -5.996504) (xy 404.618663 -6.023421) (xy 404.687678 -6.057459)
			(xy 404.720552 -6.077458) (xy 404.728808 -6.082172) (xy 404.747476 -6.085699) (xy 404.766144 -6.082172)
			(xy 404.7744 -6.077458) (xy 404.807284 -6.057477) (xy 404.876299 -6.023444) (xy 404.948383 -5.996512)
			(xy 404.985474 -5.986272) (xy 404.997034 -5.98256) (xy 405.015079 -5.966375) (xy 405.020018 -5.955284)
			(xy 405.03072 -5.928522) (xy 405.059113 -5.878362) (xy 405.094721 -5.833038) (xy 405.136735 -5.79358)
			(xy 405.184203 -5.760885) (xy 405.236044 -5.735694) (xy 405.291083 -5.718579) (xy 405.348069 -5.709931)
			(xy 405.376888 -5.709412) (xy 405.377142 -5.709412) (xy 405.388025 -5.709509) (xy 405.409756 -5.710777)
			(xy 405.420576 -5.711952) (xy 405.42083 -5.711952) (xy 405.431681 -5.712648) (xy 405.452342 -5.705943)
			(xy 405.460708 -5.698998) (xy 405.51735 -5.646674) (xy 405.52498 -5.639) (xy 405.533524 -5.619137)
			(xy 405.53386 -5.60832) (xy 405.53386 -5.608066) (xy 405.533606 -5.597398) (xy 405.533606 -5.59689)
			(xy 405.534015 -5.572549) (xy 405.540253 -5.524268) (xy 405.546052 -5.500624) (xy 405.548352 -5.488651)
			(xy 405.542937 -5.46492) (xy 405.535638 -5.455158) (xy 405.518639 -5.434553) (xy 405.487241 -5.391333)
			(xy 405.4729 -5.368798) (xy 405.4679 -5.361469) (xy 405.453921 -5.350558) (xy 405.43707 -5.345036)
			(xy 405.428196 -5.344922) (xy 405.414734 -5.345176) (xy 405.387462 -5.344687) (xy 405.333474 -5.336929)
			(xy 405.281139 -5.321566) (xy 405.231523 -5.298911) (xy 405.185637 -5.269426) (xy 405.144414 -5.23371)
			(xy 405.108695 -5.19249) (xy 405.079205 -5.146607) (xy 405.056546 -5.096993) (xy 405.041178 -5.044659)
			(xy 405.033416 -4.990672) (xy 405.033416 -4.936128) (xy 405.041178 -4.882141) (xy 405.056546 -4.829807)
			(xy 405.079205 -4.780193) (xy 405.108695 -4.73431) (xy 405.144414 -4.69309) (xy 405.185637 -4.657374)
			(xy 405.231523 -4.627889) (xy 405.281139 -4.605234) (xy 405.333474 -4.589871) (xy 405.387462 -4.582113)
			(xy 405.414734 -4.581652) (xy 405.428196 -4.581906) (xy 405.43708 -4.581862) (xy 405.453956 -4.576349)
			(xy 405.467925 -4.56539) (xy 405.4729 -4.55803) (xy 405.48725 -4.535501) (xy 405.51865 -4.492283)
			(xy 405.535638 -4.47167) (xy 405.542984 -4.461926) (xy 405.548421 -4.438175) (xy 405.546052 -4.426204)
			(xy 405.540273 -4.402556) (xy 405.534025 -4.354278) (xy 405.533606 -4.329938) (xy 405.533606 -4.32943)
			(xy 405.534152 -4.302163) (xy 405.541909 -4.248183) (xy 405.557269 -4.195857) (xy 405.579919 -4.146249)
			(xy 405.609399 -4.100369) (xy 405.645108 -4.059152) (xy 405.686319 -4.023436) (xy 405.732194 -3.993949)
			(xy 405.781798 -3.971291) (xy 405.834122 -3.955922) (xy 405.888101 -3.948157) (xy 405.915368 -3.947668)
			(xy 405.944046 -3.948238) (xy 406.000755 -3.956821) (xy 406.055545 -3.973784) (xy 406.107183 -3.998746)
			(xy 406.154511 -4.031146) (xy 406.196463 -4.070256) (xy 406.232099 -4.115198) (xy 406.260617 -4.164961)
			(xy 406.271476 -4.191508) (xy 406.276381 -4.202761) (xy 406.294761 -4.218996) (xy 406.306528 -4.222496)
			(xy 406.344988 -4.232722) (xy 406.419725 -4.260074) (xy 406.491216 -4.295044) (xy 406.525222 -4.315714)
			(xy 406.533443 -4.320485) (xy 406.5521 -4.324063) (xy 406.570785 -4.32063) (xy 406.57907 -4.315968)
			(xy 406.611712 -4.296075) (xy 406.680232 -4.262176) (xy 406.751794 -4.235289) (xy 406.78862 -4.225036)
			(xy 406.800178 -4.221317) (xy 406.818226 -4.205138) (xy 406.823164 -4.194048) (xy 406.833901 -4.167262)
			(xy 406.862271 -4.117012) (xy 406.897877 -4.071601) (xy 406.939907 -4.032061) (xy 406.987405 -3.999292)
			(xy 407.039292 -3.974039) (xy 407.094386 -3.956877) (xy 407.151435 -3.948196) (xy 407.180288 -3.947668)
			(xy 407.20756 -3.948113) (xy 407.261549 -3.955874) (xy 407.313884 -3.97124) (xy 407.363499 -3.993899)
			(xy 407.409384 -4.023388) (xy 407.450605 -4.059107) (xy 407.486323 -4.10033) (xy 407.51581 -4.146217)
			(xy 407.538466 -4.195833) (xy 407.55383 -4.248168) (xy 407.561589 -4.302158) (xy 407.56205 -4.32943)
			(xy 407.56205 -4.329684) (xy 407.561736 -4.352318) (xy 407.556386 -4.397269) (xy 407.551382 -4.419346)
			(xy 407.549139 -4.431308) (xy 407.554858 -4.454929) (xy 407.562304 -4.464558) (xy 407.58112 -4.486745)
			(xy 407.615701 -4.533533) (xy 407.631392 -4.55803) (xy 407.636417 -4.565341) (xy 407.650382 -4.576261)
			(xy 407.667225 -4.58179) (xy 407.676096 -4.581906) (xy 407.689558 -4.581652) (xy 407.716832 -4.582085)
			(xy 407.770825 -4.589842) (xy 407.823165 -4.605205) (xy 407.872785 -4.627861) (xy 407.918676 -4.657349)
			(xy 407.959903 -4.693068) (xy 407.995626 -4.73429) (xy 408.025118 -4.780178) (xy 408.04778 -4.829796)
			(xy 408.063149 -4.882134) (xy 408.070912 -4.936126) (xy 408.070912 -4.990674) (xy 408.063149 -5.044666)
			(xy 408.04778 -5.097004) (xy 408.025118 -5.146622) (xy 407.995626 -5.19251) (xy 407.959903 -5.233732)
			(xy 407.918676 -5.269451) (xy 407.872785 -5.298939) (xy 407.823165 -5.321595) (xy 407.770825 -5.336958)
			(xy 407.716832 -5.344715) (xy 407.689558 -5.345176) (xy 407.676096 -5.344922) (xy 407.667211 -5.344947)
			(xy 407.650332 -5.350467) (xy 407.636364 -5.361433) (xy 407.631392 -5.368798) (xy 407.6157 -5.393294)
			(xy 407.581118 -5.440081) (xy 407.562304 -5.46227) (xy 407.554878 -5.471902) (xy 407.549192 -5.495517)
			(xy 407.551382 -5.507482) (xy 407.556365 -5.529562) (xy 407.561714 -5.574511) (xy 407.56205 -5.597144)
			(xy 407.56205 -5.597398) (xy 407.561597 -5.62467) (xy 407.553834 -5.678657) (xy 407.538468 -5.730991)
			(xy 407.51581 -5.780605) (xy 407.486321 -5.826489) (xy 407.450603 -5.86771) (xy 407.409381 -5.903427)
			(xy 407.363496 -5.932914) (xy 407.313882 -5.955571) (xy 407.261548 -5.970937) (xy 407.20756 -5.978697)
			(xy 407.180288 -5.97916) (xy 407.151436 -5.978613) (xy 407.094389 -5.969933) (xy 407.039296 -5.952772)
			(xy 406.987411 -5.927522) (xy 406.939912 -5.894755) (xy 406.897882 -5.855218) (xy 406.862276 -5.80981)
			(xy 406.833904 -5.759564) (xy 406.823164 -5.73278) (xy 406.818145 -5.721743) (xy 406.80014 -5.705563)
			(xy 406.78862 -5.701792) (xy 406.751795 -5.691538) (xy 406.68023 -5.664657) (xy 406.611711 -5.630755)
			(xy 406.57907 -5.61086) (xy 406.570773 -5.606223) (xy 406.5521 -5.60277) (xy 406.533455 -5.606369)
			(xy 406.525222 -5.611114) (xy 406.491219 -5.631792) (xy 406.419732 -5.666773) (xy 406.344993 -5.694122)
			(xy 406.306528 -5.704332) (xy 406.294865 -5.708023) (xy 406.27656 -5.724194) (xy 406.271476 -5.73532)
			(xy 406.260603 -5.761865) (xy 406.232105 -5.811647) (xy 406.196481 -5.856607) (xy 406.154534 -5.895732)
			(xy 406.107206 -5.928143) (xy 406.055563 -5.95311) (xy 406.000766 -5.970072) (xy 405.944049 -5.978647)
			(xy 405.915368 -5.97916) (xy 405.915114 -5.97916) (xy 405.90423 -5.979067) (xy 405.8825 -5.977796)
			(xy 405.87168 -5.97662) (xy 405.871426 -5.97662) (xy 405.860574 -5.97588) (xy 405.839909 -5.982613)
			(xy 405.831548 -5.989574) (xy 405.774906 -6.041898) (xy 405.767297 -6.04959) (xy 405.758738 -6.069439)
			(xy 405.758396 -6.080252) (xy 405.758396 -6.080506) (xy 405.75865 -6.09092) (xy 405.75865 -6.091428)
			(xy 405.758142 -6.110224) (xy 405.757634 -6.121146) (xy 405.765254 -6.140958) (xy 405.834088 -6.210046)
			(xy 405.854154 -6.217412) (xy 405.865076 -6.216904) (xy 405.884634 -6.216396) (xy 405.884888 -6.216396)
			(xy 405.912155 -6.216935) (xy 405.966135 -6.224694) (xy 406.018461 -6.240056) (xy 406.068068 -6.262708)
			(xy 406.113947 -6.292189) (xy 406.155164 -6.327898) (xy 406.190879 -6.36911) (xy 406.220366 -6.414985)
			(xy 406.243025 -6.464589) (xy 406.258394 -6.516912) (xy 406.266161 -6.570891) (xy 406.26665 -6.598158)
			(xy 412.338266 -6.598158) (xy 412.338685 -6.570886) (xy 412.346454 -6.516899) (xy 412.361826 -6.464566)
			(xy 412.384489 -6.414954) (xy 412.413982 -6.369072) (xy 412.449704 -6.327854) (xy 412.490928 -6.29214)
			(xy 412.536816 -6.262655) (xy 412.586432 -6.240001) (xy 412.638767 -6.224639) (xy 412.692756 -6.21688)
			(xy 412.720028 -6.216396) (xy 412.720282 -6.216396) (xy 412.73984 -6.216904) (xy 412.750762 -6.217412)
			(xy 412.770828 -6.210046) (xy 412.839662 -6.140958) (xy 412.847282 -6.121146) (xy 412.846774 -6.110224)
			(xy 412.846266 -6.091174) (xy 412.846677 -6.063901) (xy 412.854444 -6.009911) (xy 412.869815 -5.957576)
			(xy 412.892477 -5.90796) (xy 412.92197 -5.862076) (xy 412.957693 -5.820855) (xy 412.998919 -5.785138)
			(xy 413.044808 -5.755652) (xy 413.094426 -5.732996) (xy 413.146764 -5.717632) (xy 413.200755 -5.709874)
			(xy 413.228028 -5.709412) (xy 413.256843 -5.709932) (xy 413.313816 -5.718605) (xy 413.368841 -5.735736)
			(xy 413.420669 -5.760936) (xy 413.468125 -5.793634) (xy 413.510132 -5.833087) (xy 413.545738 -5.878402)
			(xy 413.574136 -5.928549) (xy 413.584898 -5.955284) (xy 413.589864 -5.96635) (xy 413.607907 -5.982515)
			(xy 413.619442 -5.986272) (xy 413.65654 -5.99649) (xy 413.72863 -6.023413) (xy 413.797643 -6.057456)
			(xy 413.830516 -6.077458) (xy 413.838772 -6.082172) (xy 413.85744 -6.085699) (xy 413.876108 -6.082172)
			(xy 413.884364 -6.077458) (xy 413.91724 -6.057464) (xy 413.986259 -6.023436) (xy 414.058346 -5.996509)
			(xy 414.095438 -5.986272) (xy 414.106991 -5.982544) (xy 414.125041 -5.966371) (xy 414.129982 -5.955284)
			(xy 414.140714 -5.928535) (xy 414.169103 -5.878376) (xy 414.204707 -5.833053) (xy 414.246717 -5.793595)
			(xy 414.29418 -5.760898) (xy 414.346018 -5.735704) (xy 414.401052 -5.718587) (xy 414.458034 -5.709933)
			(xy 414.486852 -5.709412) (xy 414.497608 -5.709515) (xy 414.519084 -5.710788) (xy 414.529778 -5.711952)
			(xy 414.5407 -5.713222) (xy 414.561528 -5.706364) (xy 414.626298 -5.646674) (xy 414.63392 -5.638993)
			(xy 414.642471 -5.619136) (xy 414.642808 -5.60832) (xy 414.642808 -5.608066) (xy 414.642554 -5.597652)
			(xy 414.642554 -5.597398) (xy 414.642944 -5.572667) (xy 414.649315 -5.523618) (xy 414.655254 -5.499608)
			(xy 414.657884 -5.487605) (xy 414.652563 -5.463644) (xy 414.645094 -5.453888) (xy 414.628255 -5.433583)
			(xy 414.597113 -5.390998) (xy 414.582864 -5.368798) (xy 414.577825 -5.361499) (xy 414.563864 -5.350583)
			(xy 414.547028 -5.345046) (xy 414.53816 -5.344922) (xy 414.524698 -5.345176) (xy 414.49743 -5.344661)
			(xy 414.443448 -5.3369) (xy 414.391121 -5.321535) (xy 414.341513 -5.298879) (xy 414.295634 -5.269395)
			(xy 414.254418 -5.233681) (xy 414.218704 -5.192465) (xy 414.18922 -5.146585) (xy 414.166564 -5.096977)
			(xy 414.1512 -5.04465) (xy 414.143438 -4.990668) (xy 414.143438 -4.936132) (xy 414.1512 -4.88215)
			(xy 414.166564 -4.829823) (xy 414.18922 -4.780215) (xy 414.218704 -4.734335) (xy 414.254418 -4.693119)
			(xy 414.295634 -4.657405) (xy 414.341513 -4.627921) (xy 414.391121 -4.605265) (xy 414.443448 -4.5899)
			(xy 414.49743 -4.582139) (xy 414.524698 -4.581652) (xy 414.53816 -4.581906) (xy 414.547042 -4.581836)
			(xy 414.563917 -4.576334) (xy 414.577888 -4.565386) (xy 414.582864 -4.55803) (xy 414.597126 -4.535839)
			(xy 414.628268 -4.493256) (xy 414.645094 -4.47294) (xy 414.652379 -4.463096) (xy 414.657683 -4.439224)
			(xy 414.655254 -4.42722) (xy 414.649333 -4.403401) (xy 414.642964 -4.354733) (xy 414.642554 -4.330192)
			(xy 414.642554 -4.32943) (xy 414.643029 -4.302159) (xy 414.650788 -4.248172) (xy 414.666151 -4.195838)
			(xy 414.688806 -4.146224) (xy 414.718292 -4.10034) (xy 414.754009 -4.059119) (xy 414.795228 -4.023401)
			(xy 414.841112 -3.993913) (xy 414.890725 -3.971256) (xy 414.943058 -3.955891) (xy 414.997045 -3.94813)
			(xy 415.024316 -3.947668) (xy 415.052995 -3.948196) (xy 415.109706 -3.956787) (xy 415.164497 -3.973756)
			(xy 415.216136 -3.998724) (xy 415.263463 -4.03113) (xy 415.305415 -4.070245) (xy 415.341049 -4.115191)
			(xy 415.369566 -4.164959) (xy 415.380424 -4.191508) (xy 415.385509 -4.202634) (xy 415.40381 -4.218814)
			(xy 415.415476 -4.222496) (xy 415.454119 -4.232712) (xy 415.529209 -4.260117) (xy 415.601028 -4.295211)
			(xy 415.635186 -4.315968) (xy 415.643447 -4.320664) (xy 415.66211 -4.324172) (xy 415.680773 -4.320664)
			(xy 415.689034 -4.315968) (xy 415.721526 -4.296164) (xy 415.789715 -4.262382) (xy 415.860926 -4.235553)
			(xy 415.897568 -4.22529) (xy 415.909123 -4.221567) (xy 415.92717 -4.205389) (xy 415.932112 -4.194302)
			(xy 415.942851 -4.167505) (xy 415.971191 -4.117212) (xy 416.006777 -4.071758) (xy 416.048799 -4.032177)
			(xy 416.096298 -3.99937) (xy 416.148194 -3.974085) (xy 416.203304 -3.956899) (xy 416.260372 -3.948201)
			(xy 416.289236 -3.947668) (xy 416.316508 -3.948091) (xy 416.370495 -3.955858) (xy 416.422828 -3.97123)
			(xy 416.47244 -3.993892) (xy 416.518322 -4.023385) (xy 416.55954 -4.059107) (xy 416.595255 -4.100331)
			(xy 416.624739 -4.146218) (xy 416.647393 -4.195834) (xy 416.662756 -4.24817) (xy 416.670514 -4.302158)
			(xy 416.670998 -4.32943) (xy 416.670998 -4.329684) (xy 416.670642 -4.352127) (xy 416.665289 -4.396693)
			(xy 416.66033 -4.418584) (xy 416.658182 -4.430575) (xy 416.664016 -4.454189) (xy 416.671506 -4.463796)
			(xy 416.690536 -4.486152) (xy 416.7255 -4.533321) (xy 416.741356 -4.55803) (xy 416.746403 -4.565324)
			(xy 416.760358 -4.576247) (xy 416.777192 -4.581784) (xy 416.78606 -4.581906) (xy 416.799522 -4.581652)
			(xy 416.826791 -4.582112) (xy 416.880775 -4.589876) (xy 416.933103 -4.605244) (xy 416.982713 -4.627903)
			(xy 417.028592 -4.65739) (xy 417.069809 -4.693107) (xy 417.105523 -4.734325) (xy 417.135008 -4.780207)
			(xy 417.157663 -4.829817) (xy 417.173028 -4.882147) (xy 417.18079 -4.936131) (xy 417.18079 -4.990669)
			(xy 417.173028 -5.044653) (xy 417.157663 -5.096983) (xy 417.135008 -5.146593) (xy 417.105523 -5.192475)
			(xy 417.069809 -5.233693) (xy 417.028592 -5.26941) (xy 416.982713 -5.298897) (xy 416.933103 -5.321556)
			(xy 416.880775 -5.336924) (xy 416.826791 -5.344688) (xy 416.799522 -5.345176) (xy 416.78606 -5.344922)
			(xy 416.777173 -5.344922) (xy 416.760293 -5.350453) (xy 416.746326 -5.361429) (xy 416.741356 -5.368798)
			(xy 416.725506 -5.393511) (xy 416.690541 -5.44068) (xy 416.671506 -5.463032) (xy 416.66407 -5.472669)
			(xy 416.658222 -5.496258) (xy 416.66033 -5.508244) (xy 416.665284 -5.530201) (xy 416.670637 -5.574893)
			(xy 416.670998 -5.597398) (xy 416.670998 -5.597652) (xy 416.670744 -5.60832) (xy 416.671008 -5.61921)
			(xy 416.679556 -5.639221) (xy 416.687254 -5.646928) (xy 416.743896 -5.698998) (xy 416.752272 -5.705928)
			(xy 416.772926 -5.712643) (xy 416.783774 -5.711952) (xy 416.784282 -5.711952) (xy 416.795165 -5.710765)
			(xy 416.817023 -5.709496) (xy 416.82797 -5.709412) (xy 416.856786 -5.709895) (xy 416.913761 -5.718575)
			(xy 416.968787 -5.735712) (xy 417.020615 -5.760917) (xy 417.068071 -5.79362) (xy 417.110077 -5.833078)
			(xy 417.145683 -5.878396) (xy 417.174079 -5.928547) (xy 417.18484 -5.955284) (xy 417.189834 -5.966334)
			(xy 417.207858 -5.982506) (xy 417.219384 -5.986272) (xy 417.256478 -5.996503) (xy 417.328569 -6.02342)
			(xy 417.397585 -6.057458) (xy 417.430458 -6.077458) (xy 417.438714 -6.082172) (xy 417.457382 -6.085699)
			(xy 417.47605 -6.082172) (xy 417.484306 -6.077458) (xy 417.517189 -6.057476) (xy 417.586205 -6.023443)
			(xy 417.658289 -5.996511) (xy 417.69538 -5.986272) (xy 417.706941 -5.982563) (xy 417.724986 -5.966375)
			(xy 417.729924 -5.955284) (xy 417.740621 -5.92852) (xy 417.769014 -5.878359) (xy 417.804623 -5.833036)
			(xy 417.846638 -5.793578) (xy 417.894106 -5.760882) (xy 417.945949 -5.735692) (xy 418.000988 -5.718578)
			(xy 418.057975 -5.70993) (xy 418.086794 -5.709412) (xy 418.097614 -5.70951) (xy 418.119217 -5.710781)
			(xy 418.129974 -5.711952) (xy 418.140896 -5.713222) (xy 418.161724 -5.706364) (xy 418.226494 -5.646674)
			(xy 418.234116 -5.638993) (xy 418.242667 -5.619135) (xy 418.243004 -5.60832) (xy 418.243004 -5.608066)
			(xy 418.24275 -5.597398) (xy 418.24275 -5.59689) (xy 418.243096 -5.572356) (xy 418.249341 -5.523689)
			(xy 418.255196 -5.499862) (xy 418.257614 -5.48792) (xy 418.252303 -5.464177) (xy 418.245036 -5.454396)
			(xy 418.228194 -5.43396) (xy 418.197051 -5.391122) (xy 418.182806 -5.368798) (xy 418.177802 -5.361472)
			(xy 418.163825 -5.35056) (xy 418.146975 -5.345037) (xy 418.138102 -5.344922) (xy 418.12464 -5.345176)
			(xy 418.097368 -5.344687) (xy 418.043379 -5.33693) (xy 417.991043 -5.321568) (xy 417.941427 -5.298913)
			(xy 417.89554 -5.269428) (xy 417.854317 -5.233712) (xy 417.818596 -5.192492) (xy 417.789106 -5.146608)
			(xy 417.766446 -5.096994) (xy 417.751078 -5.04466) (xy 417.743316 -4.990672) (xy 417.743316 -4.936128)
			(xy 417.751078 -4.88214) (xy 417.766446 -4.829806) (xy 417.789106 -4.780192) (xy 417.818596 -4.734308)
			(xy 417.854317 -4.693088) (xy 417.89554 -4.657372) (xy 417.941427 -4.627887) (xy 417.991043 -4.605232)
			(xy 418.043379 -4.58987) (xy 418.097368 -4.582113) (xy 418.12464 -4.581652) (xy 418.138102 -4.581906)
			(xy 418.146986 -4.581866) (xy 418.163863 -4.576351) (xy 418.177832 -4.565391) (xy 418.182806 -4.55803)
			(xy 418.19705 -4.535705) (xy 418.22819 -4.492865) (xy 418.245036 -4.472432) (xy 418.252315 -4.462657)
			(xy 418.257625 -4.438909) (xy 418.255196 -4.426966) (xy 418.249373 -4.403133) (xy 418.24313 -4.354469)
			(xy 418.24275 -4.329938) (xy 418.24275 -4.32943) (xy 418.243229 -4.302159) (xy 418.250988 -4.248172)
			(xy 418.266351 -4.195839) (xy 418.289006 -4.146225) (xy 418.318491 -4.100341) (xy 418.354207 -4.05912)
			(xy 418.395426 -4.023402) (xy 418.441309 -3.993914) (xy 418.490922 -3.971257) (xy 418.543255 -3.955892)
			(xy 418.597241 -3.948131) (xy 418.624512 -3.947668) (xy 418.653191 -3.9482) (xy 418.709902 -3.956789)
			(xy 418.764693 -3.973759) (xy 418.816331 -3.998726) (xy 418.863659 -4.031131) (xy 418.905611 -4.070246)
			(xy 418.941245 -4.115192) (xy 418.969762 -4.164959) (xy 418.98062 -4.191508) (xy 418.985707 -4.202633)
			(xy 419.004007 -4.218813) (xy 419.015672 -4.222496) (xy 419.054263 -4.232689) (xy 419.129262 -4.260015)
			(xy 419.201003 -4.295011) (xy 419.235128 -4.315714) (xy 419.243384 -4.320428) (xy 419.262052 -4.323955)
			(xy 419.28072 -4.320428) (xy 419.288976 -4.315714) (xy 419.321553 -4.295897) (xy 419.389905 -4.262094)
			(xy 419.461287 -4.23527) (xy 419.498018 -4.225036) (xy 419.509488 -4.221241) (xy 419.527395 -4.205083)
			(xy 419.532308 -4.194048) (xy 419.543009 -4.167247) (xy 419.571383 -4.116995) (xy 419.606993 -4.071583)
			(xy 419.649028 -4.032043) (xy 419.696532 -3.999276) (xy 419.748425 -3.974026) (xy 419.803524 -3.956868)
			(xy 419.860577 -3.948193) (xy 419.889432 -3.947668) (xy 419.916704 -3.948095) (xy 419.970691 -3.955862)
			(xy 420.023023 -3.971232) (xy 420.072636 -3.993895) (xy 420.118518 -4.023387) (xy 420.159736 -4.059108)
			(xy 420.195451 -4.100332) (xy 420.224935 -4.146219) (xy 420.247589 -4.195835) (xy 420.262952 -4.24817)
			(xy 420.27071 -4.302158) (xy 420.271194 -4.32943) (xy 420.271194 -4.330192) (xy 420.270818 -4.352571)
			(xy 420.265471 -4.397009) (xy 420.260526 -4.418838) (xy 420.258343 -4.430826) (xy 420.264201 -4.454445)
			(xy 420.271702 -4.46405) (xy 420.290659 -4.486351) (xy 420.325495 -4.533393) (xy 420.341298 -4.55803)
			(xy 420.346319 -4.565344) (xy 420.360286 -4.576263) (xy 420.377131 -4.581791) (xy 420.386002 -4.581906)
			(xy 420.399464 -4.581652) (xy 420.426738 -4.582085) (xy 420.48073 -4.589843) (xy 420.533069 -4.605207)
			(xy 420.582689 -4.627863) (xy 420.628579 -4.657351) (xy 420.669805 -4.69307) (xy 420.705527 -4.734292)
			(xy 420.735019 -4.78018) (xy 420.75768 -4.829797) (xy 420.773049 -4.882134) (xy 420.780812 -4.936126)
			(xy 420.780812 -4.990674) (xy 420.773049 -5.044666) (xy 420.75768 -5.097003) (xy 420.735019 -5.14662)
			(xy 420.705527 -5.192508) (xy 420.669805 -5.23373) (xy 420.628579 -5.269449) (xy 420.582689 -5.298937)
			(xy 420.533069 -5.321593) (xy 420.48073 -5.336957) (xy 420.426738 -5.344715) (xy 420.399464 -5.345176)
			(xy 420.386002 -5.344922) (xy 420.377117 -5.344951) (xy 420.360238 -5.350469) (xy 420.34627 -5.361434)
			(xy 420.341298 -5.368798) (xy 420.325501 -5.393439) (xy 420.290664 -5.440481) (xy 420.271702 -5.462778)
			(xy 420.264239 -5.472398) (xy 420.258408 -5.496) (xy 420.260526 -5.50799) (xy 420.265464 -5.52982)
			(xy 420.270813 -5.574258) (xy 420.271194 -5.596636) (xy 420.271194 -5.597398) (xy 420.270674 -5.624666)
			(xy 420.262913 -5.678647) (xy 420.24755 -5.730974) (xy 420.224896 -5.780582) (xy 420.195413 -5.826461)
			(xy 420.159702 -5.867678) (xy 420.118488 -5.903393) (xy 420.072611 -5.93288) (xy 420.023005 -5.955538)
			(xy 419.97068 -5.970906) (xy 419.9167 -5.978671) (xy 419.889432 -5.97916) (xy 419.860581 -5.978575)
			(xy 419.803536 -5.969901) (xy 419.748444 -5.952747) (xy 419.696559 -5.927502) (xy 419.64906 -5.894741)
			(xy 419.607029 -5.855209) (xy 419.571422 -5.809805) (xy 419.543048 -5.759562) (xy 419.532308 -5.73278)
			(xy 419.527382 -5.721752) (xy 419.509486 -5.705582) (xy 419.498018 -5.701792) (xy 419.461287 -5.691555)
			(xy 419.389904 -5.664736) (xy 419.321546 -5.630941) (xy 419.288976 -5.611114) (xy 419.28072 -5.6064)
			(xy 419.262052 -5.602873) (xy 419.243384 -5.6064) (xy 419.235128 -5.611114) (xy 419.201005 -5.631822)
			(xy 419.129267 -5.666826) (xy 419.054267 -5.694152) (xy 419.015672 -5.704332) (xy 419.003985 -5.707983)
			(xy 418.985667 -5.724166) (xy 418.98062 -5.73532) (xy 418.96971 -5.761849) (xy 418.941216 -5.81163)
			(xy 418.905598 -5.856589) (xy 418.863656 -5.895714) (xy 418.816333 -5.928127) (xy 418.764696 -5.953097)
			(xy 418.709904 -5.970064) (xy 418.653191 -5.978644) (xy 418.624512 -5.97916) (xy 418.613692 -5.979062)
			(xy 418.592089 -5.977791) (xy 418.581332 -5.97662) (xy 418.57041 -5.97535) (xy 418.549582 -5.982208)
			(xy 418.484812 -6.041898) (xy 418.477204 -6.049591) (xy 418.468644 -6.069439) (xy 418.468302 -6.080252)
			(xy 418.468302 -6.080506) (xy 418.468556 -6.09092) (xy 418.468556 -6.091428) (xy 418.468048 -6.110224)
			(xy 418.46754 -6.121146) (xy 418.47516 -6.140958) (xy 418.543994 -6.210046) (xy 418.56406 -6.217412)
			(xy 418.574982 -6.216904) (xy 418.59454 -6.216396) (xy 418.594794 -6.216396) (xy 418.622061 -6.21693)
			(xy 418.676041 -6.22469) (xy 418.728367 -6.240052) (xy 418.777974 -6.262705) (xy 418.823853 -6.292186)
			(xy 418.86507 -6.327896) (xy 418.900785 -6.369108) (xy 418.930272 -6.414983) (xy 418.952931 -6.464588)
			(xy 418.9683 -6.516912) (xy 418.976067 -6.570891) (xy 418.976556 -6.598158) (xy 423.548302 -6.598158)
			(xy 423.548785 -6.570889) (xy 423.556552 -6.516907) (xy 423.571921 -6.46458) (xy 423.594579 -6.414972)
			(xy 423.624066 -6.369093) (xy 423.659781 -6.327877) (xy 423.700998 -6.292162) (xy 423.746877 -6.262676)
			(xy 423.796486 -6.240018) (xy 423.848813 -6.22465) (xy 423.902795 -6.216885) (xy 423.930064 -6.216396)
			(xy 423.930318 -6.216396) (xy 423.949876 -6.216904) (xy 423.960798 -6.217412) (xy 423.980864 -6.210046)
			(xy 424.049698 -6.140958) (xy 424.057318 -6.121146) (xy 424.05681 -6.110224) (xy 424.056302 -6.091174)
			(xy 424.0568 -6.063906) (xy 424.064564 -6.009924) (xy 424.079931 -5.957597) (xy 424.102588 -5.907989)
			(xy 424.132073 -5.86211) (xy 424.167787 -5.820894) (xy 424.209002 -5.785179) (xy 424.254881 -5.755693)
			(xy 424.304488 -5.733035) (xy 424.356815 -5.717667) (xy 424.410796 -5.709901) (xy 424.438064 -5.709412)
			(xy 424.46688 -5.7099) (xy 424.523855 -5.718579) (xy 424.57888 -5.735715) (xy 424.630708 -5.76092)
			(xy 424.678164 -5.793622) (xy 424.720171 -5.833079) (xy 424.755776 -5.878397) (xy 424.784173 -5.928548)
			(xy 424.794934 -5.955284) (xy 424.799931 -5.966333) (xy 424.817953 -5.982505) (xy 424.829478 -5.986272)
			(xy 424.866572 -5.996504) (xy 424.938663 -6.023421) (xy 425.007678 -6.057459) (xy 425.040552 -6.077458)
			(xy 425.048808 -6.082172) (xy 425.067476 -6.085699) (xy 425.086144 -6.082172) (xy 425.0944 -6.077458)
			(xy 425.127284 -6.057477) (xy 425.196299 -6.023444) (xy 425.268383 -5.996512) (xy 425.305474 -5.986272)
			(xy 425.317034 -5.98256) (xy 425.335079 -5.966375) (xy 425.340018 -5.955284) (xy 425.35072 -5.928522)
			(xy 425.379113 -5.878362) (xy 425.414721 -5.833038) (xy 425.456735 -5.79358) (xy 425.504203 -5.760885)
			(xy 425.556044 -5.735694) (xy 425.611083 -5.718579) (xy 425.668069 -5.709931) (xy 425.696888 -5.709412)
			(xy 425.707644 -5.709521) (xy 425.72912 -5.71079) (xy 425.739814 -5.711952) (xy 425.750736 -5.713222)
			(xy 425.771564 -5.706364) (xy 425.836334 -5.646674) (xy 425.843962 -5.638998) (xy 425.852508 -5.619137)
			(xy 425.852844 -5.60832) (xy 425.852844 -5.608066) (xy 425.85259 -5.597652) (xy 425.85259 -5.597398)
			(xy 425.852979 -5.572667) (xy 425.859351 -5.523618) (xy 425.86529 -5.499608) (xy 425.867934 -5.487606)
			(xy 425.862606 -5.463642) (xy 425.85513 -5.453888) (xy 425.838292 -5.433581) (xy 425.80715 -5.390997)
			(xy 425.7929 -5.368798) (xy 425.7879 -5.361469) (xy 425.773921 -5.350558) (xy 425.75707 -5.345036)
			(xy 425.748196 -5.344922) (xy 425.734734 -5.345176) (xy 425.707462 -5.344687) (xy 425.653474 -5.336929)
			(xy 425.601139 -5.321566) (xy 425.551523 -5.298911) (xy 425.505637 -5.269426) (xy 425.464414 -5.23371)
			(xy 425.428695 -5.19249) (xy 425.399205 -5.146607) (xy 425.376546 -5.096993) (xy 425.361178 -5.044659)
			(xy 425.353416 -4.990672) (xy 425.353416 -4.936128) (xy 425.361178 -4.882141) (xy 425.376546 -4.829807)
			(xy 425.399205 -4.780193) (xy 425.428695 -4.73431) (xy 425.464414 -4.69309) (xy 425.505637 -4.657374)
			(xy 425.551523 -4.627889) (xy 425.601139 -4.605234) (xy 425.653474 -4.589871) (xy 425.707462 -4.582113)
			(xy 425.734734 -4.581652) (xy 425.748196 -4.581906) (xy 425.75708 -4.581862) (xy 425.773956 -4.576349)
			(xy 425.787925 -4.56539) (xy 425.7929 -4.55803) (xy 425.80716 -4.535838) (xy 425.838303 -4.493255)
			(xy 425.85513 -4.47294) (xy 425.862418 -4.463098) (xy 425.867718 -4.439224) (xy 425.86529 -4.42722)
			(xy 425.85937 -4.4034) (xy 425.853 -4.354733) (xy 425.85259 -4.330192) (xy 425.85259 -4.32943) (xy 425.853152 -4.302164)
			(xy 425.860909 -4.248185) (xy 425.876268 -4.19586) (xy 425.898917 -4.146253) (xy 425.928395 -4.100374)
			(xy 425.964102 -4.059158) (xy 426.005312 -4.023442) (xy 426.051185 -3.993954) (xy 426.100787 -3.971295)
			(xy 426.153109 -3.955925) (xy 426.207086 -3.948158) (xy 426.234352 -3.947668) (xy 426.263029 -3.948252)
			(xy 426.319738 -3.956833) (xy 426.374527 -3.973793) (xy 426.426166 -3.998753) (xy 426.473493 -4.031151)
			(xy 426.515446 -4.07026) (xy 426.551082 -4.1152) (xy 426.579601 -4.164961) (xy 426.59046 -4.191508)
			(xy 426.595528 -4.202644) (xy 426.613841 -4.21882) (xy 426.625512 -4.222496) (xy 426.664157 -4.232703)
			(xy 426.739246 -4.260113) (xy 426.811064 -4.295209) (xy 426.845222 -4.315968) (xy 426.853483 -4.320664)
			(xy 426.872146 -4.324172) (xy 426.890809 -4.320664) (xy 426.89907 -4.315968) (xy 426.93157 -4.296177)
			(xy 426.999755 -4.26239) (xy 427.070963 -4.235556) (xy 427.107604 -4.22529) (xy 427.119165 -4.221583)
			(xy 427.137209 -4.205393) (xy 427.142148 -4.194302) (xy 427.152857 -4.167492) (xy 427.181201 -4.117198)
			(xy 427.216791 -4.071743) (xy 427.258816 -4.032162) (xy 427.30632 -3.999357) (xy 427.358221 -3.974075)
			(xy 427.413334 -3.956892) (xy 427.470407 -3.948199) (xy 427.499272 -3.947668) (xy 427.526544 -3.948128)
			(xy 427.580532 -3.955887) (xy 427.632867 -3.971251) (xy 427.682482 -3.993907) (xy 427.728367 -4.023395)
			(xy 427.769588 -4.059113) (xy 427.805306 -4.100334) (xy 427.834794 -4.14622) (xy 427.85745 -4.195835)
			(xy 427.872814 -4.24817) (xy 427.880573 -4.302158) (xy 427.881034 -4.32943) (xy 427.881034 -4.329684)
			(xy 427.880677 -4.352127) (xy 427.875325 -4.396693) (xy 427.870366 -4.418584) (xy 427.868233 -4.430576)
			(xy 427.874059 -4.454187) (xy 427.881542 -4.463796) (xy 427.900569 -4.486155) (xy 427.935535 -4.533322)
			(xy 427.951392 -4.55803) (xy 427.956417 -4.565341) (xy 427.970382 -4.576261) (xy 427.987225 -4.58179)
			(xy 427.996096 -4.581906) (xy 428.009558 -4.581652) (xy 428.036832 -4.582085) (xy 428.090825 -4.589842)
			(xy 428.143165 -4.605205) (xy 428.192785 -4.627861) (xy 428.238676 -4.657349) (xy 428.279903 -4.693068)
			(xy 428.315626 -4.73429) (xy 428.345118 -4.780178) (xy 428.36778 -4.829796) (xy 428.383149 -4.882134)
			(xy 428.390912 -4.936126) (xy 428.390912 -4.990674) (xy 428.383149 -5.044666) (xy 428.36778 -5.097004)
			(xy 428.345118 -5.146622) (xy 428.315626 -5.19251) (xy 428.279903 -5.233732) (xy 428.238676 -5.269451)
			(xy 428.192785 -5.298939) (xy 428.143165 -5.321595) (xy 428.090825 -5.336958) (xy 428.036832 -5.344715)
			(xy 428.009558 -5.345176) (xy 427.996096 -5.344922) (xy 427.987211 -5.344947) (xy 427.970332 -5.350467)
			(xy 427.956364 -5.361433) (xy 427.951392 -5.368798) (xy 427.93554 -5.393509) (xy 427.900576 -5.440679)
			(xy 427.881542 -5.463032) (xy 427.874109 -5.472671) (xy 427.868258 -5.496258) (xy 427.870366 -5.508244)
			(xy 427.87532 -5.5302) (xy 427.880673 -5.574893) (xy 427.881034 -5.597398) (xy 427.881034 -5.597652)
			(xy 427.88078 -5.60832) (xy 427.881033 -5.619212) (xy 427.889588 -5.639223) (xy 427.89729 -5.646928)
			(xy 427.953932 -5.698998) (xy 427.962295 -5.705946) (xy 427.982959 -5.71265) (xy 427.99381 -5.711952)
			(xy 427.994318 -5.711952) (xy 428.005202 -5.710771) (xy 428.027059 -5.709498) (xy 428.038006 -5.709412)
			(xy 428.06682 -5.70995) (xy 428.123793 -5.718621) (xy 428.178817 -5.735749) (xy 428.230645 -5.760946)
			(xy 428.278101 -5.793641) (xy 428.320109 -5.833092) (xy 428.355715 -5.878404) (xy 428.384113 -5.92855)
			(xy 428.394876 -5.955284) (xy 428.399852 -5.966344) (xy 428.417889 -5.982512) (xy 428.42942 -5.986272)
			(xy 428.466517 -5.996495) (xy 428.538607 -6.023416) (xy 428.607621 -6.057457) (xy 428.640494 -6.077458)
			(xy 428.64875 -6.082172) (xy 428.667418 -6.085699) (xy 428.686086 -6.082172) (xy 428.694342 -6.077458)
			(xy 428.727221 -6.057469) (xy 428.796239 -6.023438) (xy 428.868324 -5.99651) (xy 428.905416 -5.986272)
			(xy 428.916983 -5.982579) (xy 428.935024 -5.966379) (xy 428.93996 -5.955284) (xy 428.95071 -5.928543)
			(xy 428.979097 -5.878385) (xy 429.014699 -5.833062) (xy 429.056707 -5.793604) (xy 429.104167 -5.760906)
			(xy 429.156001 -5.735711) (xy 429.211033 -5.718591) (xy 429.268013 -5.709935) (xy 429.29683 -5.709412)
			(xy 429.30765 -5.709507) (xy 429.329253 -5.71078) (xy 429.34001 -5.711952) (xy 429.350932 -5.713222)
			(xy 429.37176 -5.706364) (xy 429.43653 -5.646674) (xy 429.444157 -5.638997) (xy 429.452704 -5.619136)
			(xy 429.45304 -5.60832) (xy 429.45304 -5.608066) (xy 429.452786 -5.597398) (xy 429.452786 -5.59689)
			(xy 429.453131 -5.572356) (xy 429.459377 -5.523689) (xy 429.465232 -5.499862) (xy 429.467664 -5.487921)
			(xy 429.462346 -5.464174) (xy 429.455072 -5.454396) (xy 429.438232 -5.433959) (xy 429.407088 -5.391121)
			(xy 429.392842 -5.368798) (xy 429.387816 -5.361489) (xy 429.373849 -5.350574) (xy 429.357008 -5.345043)
			(xy 429.348138 -5.344922) (xy 429.334676 -5.345176) (xy 429.307409 -5.34466) (xy 429.25343 -5.336896)
			(xy 429.201105 -5.321529) (xy 429.1515 -5.298872) (xy 429.105623 -5.269387) (xy 429.06441 -5.233673)
			(xy 429.028699 -5.192457) (xy 428.999216 -5.146579) (xy 428.976563 -5.096972) (xy 428.961199 -5.044647)
			(xy 428.953438 -4.990667) (xy 428.953438 -4.936133) (xy 428.961199 -4.882153) (xy 428.976563 -4.829828)
			(xy 428.999216 -4.780221) (xy 429.028699 -4.734343) (xy 429.06441 -4.693127) (xy 429.105623 -4.657413)
			(xy 429.1515 -4.627928) (xy 429.201105 -4.605271) (xy 429.25343 -4.589904) (xy 429.307409 -4.58214)
			(xy 429.334676 -4.581652) (xy 429.348138 -4.581906) (xy 429.357023 -4.581893) (xy 429.373902 -4.576365)
			(xy 429.38787 -4.565395) (xy 429.392842 -4.55803) (xy 429.407084 -4.535703) (xy 429.438225 -4.492865)
			(xy 429.455072 -4.472432) (xy 429.462347 -4.462653) (xy 429.467662 -4.438908) (xy 429.465232 -4.426966)
			(xy 429.459408 -4.403133) (xy 429.453166 -4.354469) (xy 429.452786 -4.329938) (xy 429.452786 -4.32943)
			(xy 429.45323 -4.302158) (xy 429.460989 -4.248167) (xy 429.476354 -4.195831) (xy 429.499011 -4.146215)
			(xy 429.5285 -4.100329) (xy 429.56422 -4.059107) (xy 429.605444 -4.023389) (xy 429.651331 -3.993903)
			(xy 429.700948 -3.971247) (xy 429.753285 -3.955885) (xy 429.807276 -3.948128) (xy 429.834548 -3.947668)
			(xy 429.863225 -3.948255) (xy 429.919934 -3.956835) (xy 429.974723 -3.973796) (xy 430.026361 -3.998755)
			(xy 430.073689 -4.031153) (xy 430.115642 -4.070261) (xy 430.151278 -4.1152) (xy 430.179797 -4.164962)
			(xy 430.190656 -4.191508) (xy 430.195726 -4.202643) (xy 430.214037 -4.218819) (xy 430.225708 -4.222496)
			(xy 430.264301 -4.232681) (xy 430.339299 -4.26001) (xy 430.411039 -4.295009) (xy 430.445164 -4.315714)
			(xy 430.45342 -4.320428) (xy 430.472088 -4.323955) (xy 430.490756 -4.320428) (xy 430.499012 -4.315714)
			(xy 430.531584 -4.29589) (xy 430.599939 -4.262089) (xy 430.671322 -4.235268) (xy 430.708054 -4.225036)
			(xy 430.71953 -4.221257) (xy 430.737434 -4.205087) (xy 430.742344 -4.194048) (xy 430.753098 -4.167269)
			(xy 430.781466 -4.11702) (xy 430.817069 -4.071609) (xy 430.859097 -4.032069) (xy 430.906593 -3.999299)
			(xy 430.958477 -3.974045) (xy 431.013569 -3.956881) (xy 431.070616 -3.948198) (xy 431.099468 -3.947668)
			(xy 431.12674 -3.948131) (xy 431.180728 -3.95589) (xy 431.233063 -3.971254) (xy 431.282678 -3.99391)
			(xy 431.328563 -4.023397) (xy 431.369784 -4.059114) (xy 431.405502 -4.100336) (xy 431.434989 -4.146221)
			(xy 431.457646 -4.195836) (xy 431.47301 -4.24817) (xy 431.480769 -4.302158) (xy 431.48123 -4.32943)
			(xy 431.48123 -4.330192) (xy 431.480854 -4.352571) (xy 431.475507 -4.397009) (xy 431.470562 -4.418838)
			(xy 431.468394 -4.430827) (xy 431.474244 -4.454442) (xy 431.481738 -4.46405) (xy 431.500698 -4.486349)
			(xy 431.535535 -4.53339) (xy 431.551334 -4.55803) (xy 431.556394 -4.565314) (xy 431.570343 -4.576239)
			(xy 431.587172 -4.58178) (xy 431.596038 -4.581906) (xy 431.6095 -4.581652) (xy 431.63677 -4.58211)
			(xy 431.690756 -4.589872) (xy 431.743087 -4.605238) (xy 431.792699 -4.627895) (xy 431.838582 -4.657382)
			(xy 431.879801 -4.693099) (xy 431.915518 -4.734318) (xy 431.945005 -4.780201) (xy 431.967662 -4.829813)
			(xy 431.983028 -4.882144) (xy 431.99079 -4.93613) (xy 431.99079 -4.99067) (xy 431.983028 -5.044656)
			(xy 431.967662 -5.096987) (xy 431.945005 -5.146599) (xy 431.915518 -5.192482) (xy 431.879801 -5.233701)
			(xy 431.838582 -5.269418) (xy 431.792699 -5.298905) (xy 431.743087 -5.321562) (xy 431.690756 -5.336928)
			(xy 431.63677 -5.34469) (xy 431.6095 -5.345176) (xy 431.596038 -5.344922) (xy 431.587155 -5.344978)
			(xy 431.570277 -5.350483) (xy 431.556308 -5.361438) (xy 431.551334 -5.368798) (xy 431.53554 -5.393441)
			(xy 431.500701 -5.440482) (xy 431.481738 -5.462778) (xy 431.474278 -5.4724) (xy 431.468443 -5.496001)
			(xy 431.470562 -5.50799) (xy 431.475501 -5.52982) (xy 431.480849 -5.574258) (xy 431.48123 -5.596636)
			(xy 431.48123 -5.597398) (xy 431.480797 -5.62467) (xy 431.473034 -5.67866) (xy 431.457666 -5.730995)
			(xy 431.435007 -5.780611) (xy 431.405516 -5.826496) (xy 431.369795 -5.867717) (xy 431.328572 -5.903434)
			(xy 431.282684 -5.932921) (xy 431.233067 -5.955577) (xy 431.180731 -5.97094) (xy 431.12674 -5.978699)
			(xy 431.099468 -5.97916) (xy 431.070616 -5.97863) (xy 431.013568 -5.969947) (xy 430.958474 -5.952784)
			(xy 430.906589 -5.927531) (xy 430.859091 -5.894762) (xy 430.817061 -5.855223) (xy 430.781455 -5.809813)
			(xy 430.753083 -5.759564) (xy 430.742344 -5.73278) (xy 430.737449 -5.721735) (xy 430.719531 -5.705571)
			(xy 430.708054 -5.701792) (xy 430.671326 -5.691547) (xy 430.599941 -5.664732) (xy 430.531583 -5.63094)
			(xy 430.499012 -5.611114) (xy 430.490756 -5.6064) (xy 430.472088 -5.602873) (xy 430.45342 -5.6064)
			(xy 430.445164 -5.611114) (xy 430.411037 -5.631815) (xy 430.3393 -5.666821) (xy 430.264302 -5.694151)
			(xy 430.225708 -5.704332) (xy 430.21401 -5.707954) (xy 430.195698 -5.724159) (xy 430.190656 -5.73532)
			(xy 430.179799 -5.761873) (xy 430.151299 -5.811655) (xy 430.115673 -5.856615) (xy 430.073724 -5.89574)
			(xy 430.026393 -5.92815) (xy 429.974748 -5.953116) (xy 429.919949 -5.970076) (xy 429.86323 -5.978649)
			(xy 429.834548 -5.97916) (xy 429.823728 -5.979059) (xy 429.802125 -5.97779) (xy 429.791368 -5.97662)
			(xy 429.780446 -5.97535) (xy 429.759618 -5.982208) (xy 429.694848 -6.041898) (xy 429.687231 -6.049582)
			(xy 429.678679 -6.069438) (xy 429.678338 -6.080252) (xy 429.678338 -6.080506) (xy 429.678592 -6.09092)
			(xy 429.678592 -6.091428) (xy 429.678084 -6.110224) (xy 429.677576 -6.121146) (xy 429.685196 -6.140958)
			(xy 429.75403 -6.210046) (xy 429.774096 -6.217412) (xy 429.785018 -6.216904) (xy 429.804576 -6.216396)
			(xy 429.80483 -6.216396) (xy 429.832098 -6.216896) (xy 429.886079 -6.224661) (xy 429.938406 -6.240028)
			(xy 429.988013 -6.262685) (xy 430.033892 -6.29217) (xy 430.075108 -6.327883) (xy 430.110823 -6.369098)
			(xy 430.14031 -6.414976) (xy 430.162968 -6.464583) (xy 430.178336 -6.516909) (xy 430.186103 -6.57089)
			(xy 430.186592 -6.598158) (xy 430.186103 -6.624997) (xy 430.17857 -6.678145) (xy 430.163673 -6.729715)
			(xy 430.141707 -6.778693) (xy 430.113103 -6.824116) (xy 430.078425 -6.865089) (xy 430.038354 -6.900806)
			(xy 429.993679 -6.930565) (xy 429.969676 -6.942582) (xy 429.96104 -6.946646) (xy 429.947832 -6.96087)
			(xy 429.915828 -7.043928) (xy 429.916082 -7.063232) (xy 429.919638 -7.072122) (xy 429.928377 -7.094807)
			(xy 429.940676 -7.141841) (xy 429.94691 -7.190055) (xy 429.947324 -7.214362) (xy 429.947324 -7.215124)
			(xy 430.983898 -7.215124) (xy 430.984421 -7.185969) (xy 430.993298 -7.12834) (xy 431.010833 -7.07273)
			(xy 431.03662 -7.020433) (xy 431.070058 -6.972664) (xy 431.089816 -6.951218) (xy 431.098063 -6.941611)
			(xy 431.104711 -6.917208) (xy 431.102516 -6.904736) (xy 431.093268 -6.86222) (xy 431.083334 -6.775776)
			(xy 431.082704 -6.73227) (xy 431.083217 -6.69227) (xy 431.091582 -6.612707) (xy 431.108218 -6.534455)
			(xy 431.132941 -6.45837) (xy 431.165482 -6.385287) (xy 431.205484 -6.316005) (xy 431.252508 -6.251283)
			(xy 431.30604 -6.191831) (xy 431.365492 -6.138301) (xy 431.430215 -6.091277) (xy 431.499497 -6.051277)
			(xy 431.572582 -6.018737) (xy 431.648667 -5.994015) (xy 431.726919 -5.97738) (xy 431.806482 -5.969016)
			(xy 431.846482 -5.968492) (xy 431.889171 -5.969113) (xy 431.974013 -5.978673) (xy 432.057261 -5.997631)
			(xy 432.137876 -6.025751) (xy 432.214854 -6.062683) (xy 432.251358 -6.084824) (xy 432.259619 -6.08952)
			(xy 432.278282 -6.093028) (xy 432.296945 -6.08952) (xy 432.305206 -6.084824) (xy 432.341711 -6.062682)
			(xy 432.418683 -6.025734) (xy 432.499297 -5.997606) (xy 432.582547 -5.978647) (xy 432.667392 -5.969096)
			(xy 432.710082 -5.968492) (xy 432.750081 -5.969062) (xy 432.829641 -5.977423) (xy 432.907892 -5.994053)
			(xy 432.983975 -6.018772) (xy 433.057058 -6.051308) (xy 433.12634 -6.091305) (xy 433.191061 -6.138325)
			(xy 433.250513 -6.191853) (xy 433.304045 -6.251301) (xy 433.351069 -6.31602) (xy 433.39107 -6.385299)
			(xy 433.423611 -6.45838) (xy 433.448334 -6.534462) (xy 433.46497 -6.612711) (xy 433.473335 -6.692271)
			(xy 433.47386 -6.73227) (xy 433.473516 -6.764888) (xy 433.467959 -6.829886) (xy 433.456889 -6.894175)
			(xy 433.448968 -6.925818) (xy 433.446529 -6.937735) (xy 433.451692 -6.961468) (xy 433.458874 -6.971284)
			(xy 433.475474 -6.991915) (xy 433.503432 -7.036885) (xy 433.524892 -7.085295) (xy 433.539441 -7.136209)
			(xy 433.546799 -7.188648) (xy 433.547266 -7.215124) (xy 444.97879 -7.215124) (xy 444.979306 -7.186968)
			(xy 444.987629 -7.131275) (xy 445.004041 -7.077407) (xy 445.028184 -7.026533) (xy 445.059535 -6.979755)
			(xy 445.078104 -6.958584) (xy 445.0861 -6.948778) (xy 445.092231 -6.924262) (xy 445.089788 -6.911848)
			(xy 445.078982 -6.866062) (xy 445.067386 -6.772704) (xy 445.066674 -6.725666) (xy 445.066674 -6.725158)
			(xy 445.067206 -6.685158) (xy 445.075572 -6.605598) (xy 445.092207 -6.527347) (xy 445.116931 -6.451264)
			(xy 445.149471 -6.378182) (xy 445.189472 -6.308901) (xy 445.236495 -6.24418) (xy 445.290025 -6.184729)
			(xy 445.349476 -6.131199) (xy 445.414196 -6.084175) (xy 445.483476 -6.044174) (xy 445.556558 -6.011633)
			(xy 445.632641 -5.986909) (xy 445.710892 -5.970272) (xy 445.790452 -5.961906) (xy 445.830452 -5.96138)
			(xy 445.873141 -5.962017) (xy 445.957982 -5.971573) (xy 446.04123 -5.990528) (xy 446.121845 -6.018645)
			(xy 446.198824 -6.055573) (xy 446.235328 -6.077712) (xy 446.243589 -6.082408) (xy 446.262252 -6.085916)
			(xy 446.280915 -6.082408) (xy 446.289176 -6.077712) (xy 446.325687 -6.055581) (xy 446.402658 -6.018632)
			(xy 446.48327 -5.990501) (xy 446.566518 -5.97154) (xy 446.651362 -5.961986) (xy 446.694052 -5.96138)
			(xy 446.734051 -5.961973) (xy 446.813612 -5.97033) (xy 446.891863 -5.986958) (xy 446.967947 -6.011674)
			(xy 447.041031 -6.044208) (xy 447.110314 -6.084203) (xy 447.175037 -6.131221) (xy 447.23449 -6.184746)
			(xy 447.288023 -6.244193) (xy 447.335048 -6.308911) (xy 447.375051 -6.378189) (xy 447.407594 -6.451269)
			(xy 447.432319 -6.52735) (xy 447.448956 -6.605599) (xy 447.457322 -6.685159) (xy 447.45783 -6.725158)
			(xy 447.457078 -6.772981) (xy 447.445102 -6.867876) (xy 447.433954 -6.914388) (xy 447.431466 -6.926715)
			(xy 447.437463 -6.951103) (xy 447.445384 -6.96087) (xy 447.463545 -6.981976) (xy 447.494216 -7.028442)
			(xy 447.517808 -7.078874) (xy 447.533819 -7.132199) (xy 447.541908 -7.187285) (xy 447.542412 -7.215124)
			(xy 447.541898 -7.242392) (xy 447.534134 -7.296372) (xy 447.518769 -7.348698) (xy 447.496113 -7.398305)
			(xy 447.466629 -7.444183) (xy 447.430917 -7.485399) (xy 447.389704 -7.521114) (xy 447.343827 -7.550601)
			(xy 447.294222 -7.573259) (xy 447.241897 -7.588629) (xy 447.187918 -7.596396) (xy 447.16065 -7.596886)
			(xy 447.130937 -7.596292) (xy 447.072229 -7.587088) (xy 447.015652 -7.56891) (xy 446.96257 -7.542196)
			(xy 446.914261 -7.507589) (xy 446.89268 -7.487158) (xy 446.883343 -7.4788) (xy 446.85936 -7.471623)
			(xy 446.84696 -7.473442) (xy 446.809148 -7.480681) (xy 446.732548 -7.488443) (xy 446.694052 -7.488936)
			(xy 446.651363 -7.48831) (xy 446.566521 -7.478753) (xy 446.483273 -7.459796) (xy 446.402657 -7.431677)
			(xy 446.32568 -7.394745) (xy 446.289176 -7.372604) (xy 446.280915 -7.367908) (xy 446.262252 -7.3644)
			(xy 446.243589 -7.367908) (xy 446.235328 -7.372604) (xy 446.198817 -7.394735) (xy 446.121846 -7.431684)
			(xy 446.041234 -7.459815) (xy 445.957986 -7.478776) (xy 445.873142 -7.48833) (xy 445.830452 -7.488936)
			(xy 445.829944 -7.488936) (xy 445.790991 -7.488395) (xy 445.713496 -7.480383) (xy 445.675258 -7.472934)
			(xy 445.662798 -7.471038) (xy 445.638678 -7.478246) (xy 445.629284 -7.48665) (xy 445.607683 -7.507165)
			(xy 445.559313 -7.541934) (xy 445.506135 -7.56878) (xy 445.449437 -7.587052) (xy 445.390591 -7.596308)
			(xy 445.360806 -7.596886) (xy 445.360552 -7.596886) (xy 445.333283 -7.59642) (xy 445.279299 -7.588653)
			(xy 445.226971 -7.573282) (xy 445.177362 -7.550622) (xy 445.131483 -7.521134) (xy 445.090266 -7.485417)
			(xy 445.054552 -7.444198) (xy 445.025066 -7.398317) (xy 445.002409 -7.348706) (xy 444.987042 -7.296377)
			(xy 444.979278 -7.242393) (xy 444.97879 -7.215124) (xy 433.547266 -7.215124) (xy 433.546798 -7.242394)
			(xy 433.539033 -7.296378) (xy 433.523665 -7.348707) (xy 433.501006 -7.398317) (xy 433.471518 -7.444198)
			(xy 433.435801 -7.485415) (xy 433.394582 -7.52113) (xy 433.3487 -7.550616) (xy 433.299089 -7.573272)
			(xy 433.246758 -7.588637) (xy 433.192774 -7.596399) (xy 433.165504 -7.596886) (xy 433.1368 -7.596378)
			(xy 433.08004 -7.587777) (xy 433.025209 -7.570768) (xy 432.973546 -7.545736) (xy 432.926217 -7.513245)
			(xy 432.9049 -7.494016) (xy 432.895558 -7.486253) (xy 432.872225 -7.479626) (xy 432.860196 -7.481316)
			(xy 432.823182 -7.488229) (xy 432.748242 -7.495608) (xy 432.71059 -7.496048) (xy 432.710082 -7.496048)
			(xy 432.667392 -7.495453) (xy 432.582549 -7.485889) (xy 432.499301 -7.466925) (xy 432.418686 -7.438798)
			(xy 432.341709 -7.40186) (xy 432.305206 -7.379716) (xy 432.296945 -7.37502) (xy 432.278282 -7.371512)
			(xy 432.259619 -7.37502) (xy 432.251358 -7.379716) (xy 432.214865 -7.401877) (xy 432.137889 -7.438821)
			(xy 432.057272 -7.466945) (xy 431.97402 -7.485899) (xy 431.889173 -7.495446) (xy 431.846482 -7.496048)
			(xy 431.803761 -7.495445) (xy 431.718853 -7.485896) (xy 431.677064 -7.476998) (xy 431.664567 -7.474811)
			(xy 431.640162 -7.481631) (xy 431.630582 -7.489952) (xy 431.609121 -7.509904) (xy 431.561218 -7.54365)
			(xy 431.508722 -7.569681) (xy 431.452864 -7.587386) (xy 431.394958 -7.596348) (xy 431.36566 -7.596886)
			(xy 431.338391 -7.596413) (xy 431.284408 -7.588646) (xy 431.23208 -7.573277) (xy 431.182471 -7.550618)
			(xy 431.136591 -7.52113) (xy 431.095375 -7.485414) (xy 431.05966 -7.444196) (xy 431.030174 -7.398315)
			(xy 431.007517 -7.348705) (xy 430.99215 -7.296376) (xy 430.984386 -7.242393) (xy 430.983898 -7.215124)
			(xy 429.947324 -7.215124) (xy 429.946921 -7.242397) (xy 429.939154 -7.296388) (xy 429.923783 -7.348724)
			(xy 429.90112 -7.39834) (xy 429.871626 -7.444226) (xy 429.835902 -7.485446) (xy 429.794676 -7.521163)
			(xy 429.748786 -7.55065) (xy 429.699166 -7.573305) (xy 429.646828 -7.588668) (xy 429.592835 -7.596425)
			(xy 429.565562 -7.596886) (xy 429.535871 -7.596306) (xy 429.477208 -7.587102) (xy 429.420678 -7.56892)
			(xy 429.367647 -7.542201) (xy 429.319396 -7.50759) (xy 429.297846 -7.487158) (xy 429.288482 -7.478838)
			(xy 429.264521 -7.471639) (xy 429.252126 -7.473442) (xy 429.214315 -7.480686) (xy 429.137714 -7.488444)
			(xy 429.099218 -7.488936) (xy 429.056528 -7.488326) (xy 428.971686 -7.478765) (xy 428.888438 -7.459805)
			(xy 428.807822 -7.431682) (xy 428.730845 -7.394747) (xy 428.694342 -7.372604) (xy 428.686081 -7.367908)
			(xy 428.667418 -7.3644) (xy 428.648755 -7.367908) (xy 428.640494 -7.372604) (xy 428.603991 -7.394749)
			(xy 428.527018 -7.431696) (xy 428.446403 -7.459823) (xy 428.363154 -7.478781) (xy 428.278308 -7.488332)
			(xy 428.235618 -7.488936) (xy 428.23511 -7.488936) (xy 428.196157 -7.4884) (xy 428.118662 -7.480384)
			(xy 428.080424 -7.472934) (xy 428.067962 -7.471082) (xy 428.043847 -7.47826) (xy 428.03445 -7.48665)
			(xy 428.012864 -7.507181) (xy 427.96449 -7.541948) (xy 427.911308 -7.568791) (xy 427.854607 -7.587059)
			(xy 427.795758 -7.596311) (xy 427.765972 -7.596886) (xy 427.765718 -7.596886) (xy 427.73845 -7.596359)
			(xy 427.684469 -7.5886) (xy 427.632142 -7.573238) (xy 427.582533 -7.550586) (xy 427.536654 -7.521104)
			(xy 427.495436 -7.485393) (xy 427.459721 -7.44418) (xy 427.430234 -7.398303) (xy 427.407576 -7.348697)
			(xy 427.392209 -7.296372) (xy 427.384444 -7.242392) (xy 427.383956 -7.215124) (xy 427.384345 -7.190503)
			(xy 427.390666 -7.141668) (xy 427.403219 -7.094053) (xy 427.41215 -7.071106) (xy 427.415706 -7.062216)
			(xy 427.41596 -7.042912) (xy 427.387766 -6.968744) (xy 427.384009 -6.959993) (xy 427.371218 -6.945902)
			(xy 427.362874 -6.941312) (xy 427.36262 -6.941312) (xy 427.338881 -6.929167) (xy 427.294679 -6.899343)
			(xy 427.255057 -6.863659) (xy 427.220785 -6.822809) (xy 427.192529 -6.777589) (xy 427.17084 -6.728877)
			(xy 427.15614 -6.677621) (xy 427.148713 -6.624819) (xy 427.148244 -6.598158) (xy 427.148685 -6.570887)
			(xy 427.156453 -6.516902) (xy 427.171824 -6.464571) (xy 427.194485 -6.41496) (xy 427.223976 -6.369079)
			(xy 427.259696 -6.327862) (xy 427.300918 -6.292147) (xy 427.346803 -6.262662) (xy 427.396416 -6.240007)
			(xy 427.448749 -6.224643) (xy 427.502735 -6.216882) (xy 427.530006 -6.216396) (xy 427.53026 -6.216396)
			(xy 427.549818 -6.216904) (xy 427.56074 -6.217412) (xy 427.580806 -6.210046) (xy 427.64964 -6.140958)
			(xy 427.65726 -6.121146) (xy 427.656752 -6.110224) (xy 427.656244 -6.091174) (xy 427.656244 -6.09092)
			(xy 427.656498 -6.080252) (xy 427.656237 -6.069362) (xy 427.647685 -6.049352) (xy 427.639988 -6.041644)
			(xy 427.583346 -5.989574) (xy 427.574958 -5.982662) (xy 427.554314 -5.975938) (xy 427.543468 -5.97662)
			(xy 427.54296 -5.97662) (xy 427.532077 -5.977803) (xy 427.510219 -5.979074) (xy 427.499272 -5.97916)
			(xy 427.470405 -5.97862) (xy 427.413326 -5.969949) (xy 427.358204 -5.95278) (xy 427.306297 -5.927504)
			(xy 427.25879 -5.894698) (xy 427.216766 -5.855111) (xy 427.181185 -5.809645) (xy 427.152857 -5.759338)
			(xy 427.142148 -5.732526) (xy 427.137156 -5.721475) (xy 427.119131 -5.705303) (xy 427.107604 -5.701538)
			(xy 427.07096 -5.691283) (xy 426.999752 -5.664445) (xy 426.931565 -5.630659) (xy 426.89907 -5.61086)
			(xy 426.890809 -5.606164) (xy 426.872146 -5.602656) (xy 426.853483 -5.606164) (xy 426.845222 -5.61086)
			(xy 426.811077 -5.631642) (xy 426.739258 -5.666742) (xy 426.664163 -5.694142) (xy 426.625512 -5.704332)
			(xy 426.613815 -5.707956) (xy 426.595502 -5.724159) (xy 426.59046 -5.73532) (xy 426.5796 -5.761871)
			(xy 426.5511 -5.811654) (xy 426.515475 -5.856613) (xy 426.473526 -5.895738) (xy 426.426196 -5.928149)
			(xy 426.374551 -5.953115) (xy 426.319752 -5.970075) (xy 426.263034 -5.978649) (xy 426.234352 -5.97916)
			(xy 426.223596 -5.979056) (xy 426.20212 -5.977784) (xy 426.191426 -5.97662) (xy 426.180504 -5.97535)
			(xy 426.159676 -5.982208) (xy 426.094906 -6.041898) (xy 426.087297 -6.04959) (xy 426.078738 -6.069439)
			(xy 426.078396 -6.080252) (xy 426.078396 -6.080506) (xy 426.07865 -6.090666) (xy 426.07865 -6.091174)
			(xy 426.078142 -6.110224) (xy 426.077634 -6.121146) (xy 426.085254 -6.140958) (xy 426.154088 -6.210046)
			(xy 426.174154 -6.217412) (xy 426.185076 -6.216904) (xy 426.204634 -6.216396) (xy 426.204888 -6.216396)
			(xy 426.232155 -6.216935) (xy 426.286135 -6.224694) (xy 426.338461 -6.240056) (xy 426.388068 -6.262708)
			(xy 426.433947 -6.292189) (xy 426.475164 -6.327898) (xy 426.510879 -6.36911) (xy 426.540366 -6.414985)
			(xy 426.563025 -6.464589) (xy 426.578394 -6.516912) (xy 426.586161 -6.570891) (xy 426.58665 -6.598158)
			(xy 426.586185 -6.624998) (xy 426.57865 -6.678148) (xy 426.563752 -6.72972) (xy 426.541783 -6.778699)
			(xy 426.513176 -6.824122) (xy 426.478493 -6.865095) (xy 426.438418 -6.900811) (xy 426.393739 -6.930567)
			(xy 426.369734 -6.942582) (xy 426.361098 -6.946646) (xy 426.34789 -6.96087) (xy 426.315886 -7.043928)
			(xy 426.31614 -7.063232) (xy 426.319696 -7.072122) (xy 426.328438 -7.094806) (xy 426.340735 -7.141841)
			(xy 426.346968 -7.190055) (xy 426.347382 -7.214362) (xy 426.347382 -7.215124) (xy 426.346898 -7.242393)
			(xy 426.339134 -7.296376) (xy 426.323766 -7.348704) (xy 426.301109 -7.398313) (xy 426.271622 -7.444193)
			(xy 426.235907 -7.48541) (xy 426.19469 -7.521125) (xy 426.148809 -7.550611) (xy 426.0992 -7.573268)
			(xy 426.046872 -7.588634) (xy 425.992889 -7.596398) (xy 425.96562 -7.596886) (xy 425.935928 -7.596332)
			(xy 425.877263 -7.587121) (xy 425.820734 -7.568934) (xy 425.767703 -7.542209) (xy 425.719453 -7.507592)
			(xy 425.697904 -7.487158) (xy 425.688557 -7.478814) (xy 425.664582 -7.471629) (xy 425.652184 -7.473442)
			(xy 425.614371 -7.480677) (xy 425.537772 -7.488441) (xy 425.499276 -7.488936) (xy 425.456586 -7.488346)
			(xy 425.371742 -7.47878) (xy 425.288494 -7.459816) (xy 425.207879 -7.431688) (xy 425.130903 -7.394749)
			(xy 425.0944 -7.372604) (xy 425.086139 -7.367908) (xy 425.067476 -7.3644) (xy 425.048813 -7.367908)
			(xy 425.040552 -7.372604) (xy 425.004059 -7.394766) (xy 424.927083 -7.43171) (xy 424.846466 -7.459834)
			(xy 424.763214 -7.478788) (xy 424.678367 -7.488334) (xy 424.635676 -7.488936) (xy 424.596468 -7.488447)
			(xy 424.518463 -7.480426) (xy 424.479974 -7.472934) (xy 424.467483 -7.470968) (xy 424.443236 -7.478038)
			(xy 424.433746 -7.486396) (xy 424.412201 -7.506954) (xy 424.363902 -7.541786) (xy 424.310777 -7.568688)
			(xy 424.254116 -7.587007) (xy 424.195296 -7.596296) (xy 424.165522 -7.596886) (xy 424.138254 -7.596355)
			(xy 424.084273 -7.588597) (xy 424.031946 -7.573236) (xy 423.982338 -7.550584) (xy 423.936458 -7.521103)
			(xy 423.895241 -7.485392) (xy 423.859525 -7.444179) (xy 423.830038 -7.398303) (xy 423.80738 -7.348697)
			(xy 423.792013 -7.296372) (xy 423.784248 -7.242392) (xy 423.78376 -7.215124) (xy 423.784181 -7.190454)
			(xy 423.790586 -7.141529) (xy 423.803229 -7.093834) (xy 423.812208 -7.070852) (xy 423.812208 -7.070598)
			(xy 423.815298 -7.061658) (xy 423.815413 -7.042757) (xy 423.812462 -7.033768) (xy 423.784268 -6.959346)
			(xy 423.771568 -6.945376) (xy 423.762678 -6.941058) (xy 423.738902 -6.929006) (xy 423.694698 -6.899215)
			(xy 423.655072 -6.86356) (xy 423.620798 -6.822734) (xy 423.592542 -6.777533) (xy 423.570855 -6.728838)
			(xy 423.55616 -6.677598) (xy 423.548743 -6.624811) (xy 423.548302 -6.598158) (xy 418.976556 -6.598158)
			(xy 418.976087 -6.624998) (xy 418.968553 -6.678147) (xy 418.953655 -6.729719) (xy 418.931687 -6.778699)
			(xy 418.90308 -6.824122) (xy 418.868398 -6.865094) (xy 418.828323 -6.90081) (xy 418.783645 -6.930567)
			(xy 418.75964 -6.942582) (xy 418.751004 -6.946646) (xy 418.737796 -6.96087) (xy 418.705792 -7.043928)
			(xy 418.706046 -7.063232) (xy 418.709602 -7.072122) (xy 418.718344 -7.094806) (xy 418.730641 -7.141841)
			(xy 418.736874 -7.190055) (xy 418.737288 -7.214362) (xy 418.737288 -7.215124) (xy 418.736798 -7.242393)
			(xy 418.729034 -7.296375) (xy 418.713667 -7.348703) (xy 418.69101 -7.398311) (xy 418.661524 -7.444191)
			(xy 418.625809 -7.485407) (xy 418.584592 -7.521122) (xy 418.538713 -7.550609) (xy 418.489105 -7.573266)
			(xy 418.436777 -7.588633) (xy 418.382795 -7.596398) (xy 418.355526 -7.596886) (xy 418.325834 -7.596329)
			(xy 418.26717 -7.587118) (xy 418.21064 -7.568932) (xy 418.15761 -7.542208) (xy 418.109359 -7.507592)
			(xy 418.08781 -7.487158) (xy 418.078461 -7.478818) (xy 418.054488 -7.47163) (xy 418.04209 -7.473442)
			(xy 418.004277 -7.480676) (xy 417.927678 -7.488441) (xy 417.889182 -7.488936) (xy 417.846492 -7.488343)
			(xy 417.761648 -7.478778) (xy 417.6784 -7.459814) (xy 417.597785 -7.431687) (xy 417.520809 -7.394748)
			(xy 417.484306 -7.372604) (xy 417.476045 -7.367908) (xy 417.457382 -7.3644) (xy 417.438719 -7.367908)
			(xy 417.430458 -7.372604) (xy 417.393964 -7.394764) (xy 417.316988 -7.431708) (xy 417.236371 -7.459833)
			(xy 417.15312 -7.478787) (xy 417.068273 -7.488334) (xy 417.025582 -7.488936) (xy 417.025074 -7.488936)
			(xy 416.98612 -7.488405) (xy 416.908626 -7.480386) (xy 416.870388 -7.472934) (xy 416.857927 -7.471058)
			(xy 416.833809 -7.478252) (xy 416.824414 -7.48665) (xy 416.8028 -7.507151) (xy 416.754433 -7.541922)
			(xy 416.701259 -7.56877) (xy 416.644564 -7.587046) (xy 416.58572 -7.596306) (xy 416.555936 -7.596886)
			(xy 416.555682 -7.596886) (xy 416.528413 -7.596392) (xy 416.474431 -7.588629) (xy 416.422103 -7.573262)
			(xy 416.372495 -7.550606) (xy 416.326615 -7.52112) (xy 416.285398 -7.485406) (xy 416.249683 -7.44419)
			(xy 416.220197 -7.398311) (xy 416.19754 -7.348702) (xy 416.182172 -7.296375) (xy 416.174408 -7.242393)
			(xy 416.17392 -7.215124) (xy 416.174311 -7.190503) (xy 416.180631 -7.141668) (xy 416.193183 -7.094053)
			(xy 416.202114 -7.071106) (xy 416.20567 -7.062216) (xy 416.205924 -7.042912) (xy 416.17773 -6.968744)
			(xy 416.173986 -6.959987) (xy 416.161186 -6.945898) (xy 416.152838 -6.941312) (xy 416.152584 -6.941312)
			(xy 416.128836 -6.929183) (xy 416.084636 -6.899355) (xy 416.045015 -6.863668) (xy 416.010745 -6.822816)
			(xy 415.982491 -6.777593) (xy 415.960803 -6.72888) (xy 415.946103 -6.677623) (xy 415.938676 -6.62482)
			(xy 415.938208 -6.598158) (xy 415.938685 -6.570889) (xy 415.946452 -6.516907) (xy 415.961821 -6.464579)
			(xy 415.98448 -6.41497) (xy 416.013967 -6.369091) (xy 416.049683 -6.327875) (xy 416.090901 -6.29216)
			(xy 416.136781 -6.262674) (xy 416.18639 -6.240017) (xy 416.238718 -6.224649) (xy 416.292701 -6.216884)
			(xy 416.31997 -6.216396) (xy 416.320224 -6.216396) (xy 416.339782 -6.216904) (xy 416.350704 -6.217412)
			(xy 416.37077 -6.210046) (xy 416.439604 -6.140958) (xy 416.447224 -6.121146) (xy 416.446716 -6.110224)
			(xy 416.446208 -6.091174) (xy 416.446208 -6.09092) (xy 416.446462 -6.080252) (xy 416.446212 -6.06936)
			(xy 416.437654 -6.04935) (xy 416.429952 -6.041644) (xy 416.37331 -5.989574) (xy 416.364934 -5.982644)
			(xy 416.34428 -5.97593) (xy 416.333432 -5.97662) (xy 416.332924 -5.97662) (xy 416.322041 -5.977806)
			(xy 416.300183 -5.979075) (xy 416.289236 -5.97916) (xy 416.260368 -5.978651) (xy 416.203287 -5.969975)
			(xy 416.148165 -5.952801) (xy 416.096258 -5.92752) (xy 416.048751 -5.89471) (xy 416.006728 -5.855118)
			(xy 415.971147 -5.809649) (xy 415.942821 -5.75934) (xy 415.932112 -5.732526) (xy 415.927138 -5.721464)
			(xy 415.9091 -5.705297) (xy 415.897568 -5.701538) (xy 415.860928 -5.69127) (xy 415.789719 -5.664437)
			(xy 415.72153 -5.630657) (xy 415.689034 -5.61086) (xy 415.680773 -5.606164) (xy 415.66211 -5.602656)
			(xy 415.643447 -5.606164) (xy 415.635186 -5.61086) (xy 415.601046 -5.63165) (xy 415.529224 -5.666746)
			(xy 415.454128 -5.694143) (xy 415.415476 -5.704332) (xy 415.40379 -5.707985) (xy 415.385471 -5.724167)
			(xy 415.380424 -5.73532) (xy 415.369594 -5.761884) (xy 415.341091 -5.811668) (xy 415.305461 -5.856628)
			(xy 415.263508 -5.895753) (xy 415.216173 -5.928162) (xy 415.164524 -5.953126) (xy 415.109722 -5.970083)
			(xy 415.052999 -5.978651) (xy 415.024316 -5.97916) (xy 415.01356 -5.979051) (xy 414.992084 -5.977782)
			(xy 414.98139 -5.97662) (xy 414.970468 -5.97535) (xy 414.94964 -5.982208) (xy 414.88487 -6.041898)
			(xy 414.877256 -6.049585) (xy 414.868701 -6.069438) (xy 414.86836 -6.080252) (xy 414.86836 -6.080506)
			(xy 414.868614 -6.090666) (xy 414.868614 -6.091174) (xy 414.868106 -6.110224) (xy 414.867598 -6.121146)
			(xy 414.875218 -6.140958) (xy 414.944052 -6.210046) (xy 414.964118 -6.217412) (xy 414.97504 -6.216904)
			(xy 414.994598 -6.216396) (xy 414.994852 -6.216396) (xy 415.02212 -6.216946) (xy 415.076102 -6.2247)
			(xy 415.12843 -6.240059) (xy 415.17804 -6.262707) (xy 415.223922 -6.292186) (xy 415.265142 -6.327895)
			(xy 415.30086 -6.369106) (xy 415.330349 -6.414981) (xy 415.35301 -6.464586) (xy 415.36838 -6.51691)
			(xy 415.376148 -6.57089) (xy 415.376614 -6.598158) (xy 415.376169 -6.624999) (xy 415.368634 -6.67815)
			(xy 415.353734 -6.729724) (xy 415.331763 -6.778705) (xy 415.303153 -6.824128) (xy 415.268467 -6.8651)
			(xy 415.228388 -6.900815) (xy 415.183705 -6.930568) (xy 415.159698 -6.942582) (xy 415.151062 -6.946646)
			(xy 415.137854 -6.96087) (xy 415.10585 -7.043928) (xy 415.106104 -7.063232) (xy 415.10966 -7.072122)
			(xy 415.1184 -7.094807) (xy 415.130699 -7.141841) (xy 415.136932 -7.190055) (xy 415.137346 -7.214362)
			(xy 415.137346 -7.215124) (xy 415.136898 -7.242395) (xy 415.129132 -7.29638) (xy 415.113763 -7.348712)
			(xy 415.091103 -7.398323) (xy 415.061613 -7.444205) (xy 415.025894 -7.485422) (xy 414.984673 -7.521137)
			(xy 414.938788 -7.550622) (xy 414.889174 -7.573277) (xy 414.836841 -7.588641) (xy 414.782855 -7.596401)
			(xy 414.755584 -7.596886) (xy 414.725894 -7.596293) (xy 414.667231 -7.587091) (xy 414.610701 -7.568913)
			(xy 414.557671 -7.542197) (xy 414.509419 -7.507588) (xy 414.487868 -7.487158) (xy 414.478494 -7.478851)
			(xy 414.454541 -7.471644) (xy 414.442148 -7.473442) (xy 414.404336 -7.480683) (xy 414.327736 -7.488443)
			(xy 414.28924 -7.488936) (xy 414.246551 -7.488316) (xy 414.161708 -7.478757) (xy 414.07846 -7.459799)
			(xy 413.997845 -7.431679) (xy 413.920867 -7.394746) (xy 413.884364 -7.372604) (xy 413.876103 -7.367908)
			(xy 413.85744 -7.3644) (xy 413.838777 -7.367908) (xy 413.830516 -7.372604) (xy 413.794008 -7.39474)
			(xy 413.717036 -7.431688) (xy 413.636423 -7.459818) (xy 413.553174 -7.478778) (xy 413.46833 -7.488331)
			(xy 413.42564 -7.488936) (xy 413.386432 -7.488437) (xy 413.308427 -7.480423) (xy 413.269938 -7.472934)
			(xy 413.257449 -7.470944) (xy 413.233198 -7.478031) (xy 413.22371 -7.486396) (xy 413.20218 -7.506971)
			(xy 413.153877 -7.541801) (xy 413.100748 -7.5687) (xy 413.044084 -7.587014) (xy 412.985261 -7.596299)
			(xy 412.955486 -7.596886) (xy 412.928217 -7.596389) (xy 412.874235 -7.588626) (xy 412.821908 -7.57326)
			(xy 412.772299 -7.550604) (xy 412.726419 -7.521119) (xy 412.685202 -7.485405) (xy 412.649487 -7.444189)
			(xy 412.620001 -7.39831) (xy 412.597344 -7.348702) (xy 412.581976 -7.296374) (xy 412.574212 -7.242393)
			(xy 412.573724 -7.215124) (xy 412.574147 -7.190454) (xy 412.580552 -7.141529) (xy 412.593194 -7.093834)
			(xy 412.602172 -7.070852) (xy 412.602172 -7.070598) (xy 412.60526 -7.061657) (xy 412.605374 -7.042757)
			(xy 412.602426 -7.033768) (xy 412.574232 -6.959346) (xy 412.561532 -6.945376) (xy 412.552642 -6.941058)
			(xy 412.528881 -6.928977) (xy 412.484674 -6.899193) (xy 412.445046 -6.863544) (xy 412.410768 -6.822722)
			(xy 412.38251 -6.777525) (xy 412.360821 -6.728833) (xy 412.346125 -6.677595) (xy 412.338707 -6.62481)
			(xy 412.338266 -6.598158) (xy 406.26665 -6.598158) (xy 406.266185 -6.624998) (xy 406.25865 -6.678148)
			(xy 406.243752 -6.72972) (xy 406.221783 -6.778699) (xy 406.193176 -6.824122) (xy 406.158493 -6.865095)
			(xy 406.118418 -6.900811) (xy 406.073739 -6.930567) (xy 406.049734 -6.942582) (xy 406.041098 -6.946646)
			(xy 406.02789 -6.96087) (xy 405.995886 -7.043928) (xy 405.99614 -7.063232) (xy 405.999696 -7.072122)
			(xy 406.008438 -7.094806) (xy 406.020735 -7.141841) (xy 406.026968 -7.190055) (xy 406.027382 -7.214362)
			(xy 406.027382 -7.215124) (xy 406.026898 -7.242393) (xy 406.019134 -7.296376) (xy 406.003766 -7.348704)
			(xy 405.981109 -7.398313) (xy 405.951622 -7.444193) (xy 405.915907 -7.48541) (xy 405.87469 -7.521125)
			(xy 405.828809 -7.550611) (xy 405.7792 -7.573268) (xy 405.726872 -7.588634) (xy 405.672889 -7.596398)
			(xy 405.64562 -7.596886) (xy 405.615928 -7.596332) (xy 405.557263 -7.587121) (xy 405.500734 -7.568934)
			(xy 405.447703 -7.542209) (xy 405.399453 -7.507592) (xy 405.377904 -7.487158) (xy 405.368557 -7.478814)
			(xy 405.344582 -7.471629) (xy 405.332184 -7.473442) (xy 405.294371 -7.480677) (xy 405.217772 -7.488441)
			(xy 405.179276 -7.488936) (xy 405.136586 -7.488346) (xy 405.051742 -7.47878) (xy 404.968494 -7.459816)
			(xy 404.887879 -7.431688) (xy 404.810903 -7.394749) (xy 404.7744 -7.372604) (xy 404.766139 -7.367908)
			(xy 404.747476 -7.3644) (xy 404.728813 -7.367908) (xy 404.720552 -7.372604) (xy 404.684059 -7.394766)
			(xy 404.607083 -7.43171) (xy 404.526466 -7.459834) (xy 404.443214 -7.478788) (xy 404.358367 -7.488334)
			(xy 404.315676 -7.488936) (xy 404.276468 -7.488447) (xy 404.198463 -7.480426) (xy 404.159974 -7.472934)
			(xy 404.147483 -7.470968) (xy 404.123236 -7.478038) (xy 404.113746 -7.486396) (xy 404.092201 -7.506954)
			(xy 404.043902 -7.541786) (xy 403.990777 -7.568688) (xy 403.934116 -7.587007) (xy 403.875296 -7.596296)
			(xy 403.845522 -7.596886) (xy 403.818254 -7.596355) (xy 403.764273 -7.588597) (xy 403.711946 -7.573236)
			(xy 403.662338 -7.550584) (xy 403.616458 -7.521103) (xy 403.575241 -7.485392) (xy 403.539525 -7.444179)
			(xy 403.510038 -7.398303) (xy 403.48738 -7.348697) (xy 403.472013 -7.296372) (xy 403.464248 -7.242392)
			(xy 403.46376 -7.215124) (xy 403.464181 -7.190454) (xy 403.470586 -7.141529) (xy 403.483229 -7.093834)
			(xy 403.492208 -7.070852) (xy 403.492208 -7.070598) (xy 403.495298 -7.061658) (xy 403.495413 -7.042757)
			(xy 403.492462 -7.033768) (xy 403.464268 -6.959346) (xy 403.451568 -6.945376) (xy 403.442678 -6.941058)
			(xy 403.418902 -6.929006) (xy 403.374698 -6.899215) (xy 403.335072 -6.86356) (xy 403.300798 -6.822734)
			(xy 403.272542 -6.777533) (xy 403.250855 -6.728838) (xy 403.23616 -6.677598) (xy 403.228743 -6.624811)
			(xy 403.228302 -6.598158) (xy 403.228785 -6.570889) (xy 403.236552 -6.516907) (xy 403.251921 -6.46458)
			(xy 403.274579 -6.414972) (xy 403.304066 -6.369093) (xy 403.339781 -6.327877) (xy 403.380998 -6.292162)
			(xy 403.426877 -6.262676) (xy 403.476486 -6.240018) (xy 403.528813 -6.22465) (xy 403.582795 -6.216885)
			(xy 403.610064 -6.216396) (xy 403.610318 -6.216396) (xy 403.629876 -6.216904) (xy 403.640798 -6.217412)
			(xy 403.660864 -6.210046) (xy 403.729698 -6.140958) (xy 403.737318 -6.121146) (xy 403.73681 -6.110224)
			(xy 403.736302 -6.091174) (xy 403.736302 -6.09092) (xy 403.736556 -6.080252) (xy 403.736308 -6.06936)
			(xy 403.727748 -6.049349) (xy 403.720046 -6.041644) (xy 403.663404 -5.989574) (xy 403.65503 -5.982641)
			(xy 403.634375 -5.975929) (xy 403.623526 -5.97662) (xy 403.623018 -5.97662) (xy 403.612135 -5.977806)
			(xy 403.590277 -5.979075) (xy 403.57933 -5.97916) (xy 403.550479 -5.978576) (xy 403.493434 -5.969903)
			(xy 403.438342 -5.952748) (xy 403.386456 -5.927503) (xy 403.338958 -5.894742) (xy 403.296927 -5.855209)
			(xy 403.26132 -5.809805) (xy 403.232946 -5.759562) (xy 403.222206 -5.73278) (xy 403.217281 -5.721752)
			(xy 403.199384 -5.705581) (xy 403.187916 -5.701792) (xy 403.151185 -5.691556) (xy 403.079802 -5.664737)
			(xy 403.011444 -5.630942) (xy 402.978874 -5.611114) (xy 402.970618 -5.6064) (xy 402.95195 -5.602873)
			(xy 402.933282 -5.6064) (xy 402.925026 -5.611114) (xy 402.890904 -5.631823) (xy 402.819165 -5.666826)
			(xy 402.744165 -5.694153) (xy 402.70557 -5.704332) (xy 402.693883 -5.707982) (xy 402.675565 -5.724166)
			(xy 402.670518 -5.73532) (xy 402.65961 -5.76185) (xy 402.631116 -5.811631) (xy 402.595497 -5.856589)
			(xy 402.553555 -5.895715) (xy 402.506232 -5.928128) (xy 402.454594 -5.953098) (xy 402.399802 -5.970064)
			(xy 402.343089 -5.978644) (xy 402.31441 -5.97916) (xy 402.30359 -5.979062) (xy 402.281987 -5.977791)
			(xy 402.27123 -5.97662) (xy 402.260308 -5.97535) (xy 402.23948 -5.982208) (xy 402.17471 -6.041898)
			(xy 402.167101 -6.049591) (xy 402.158542 -6.069439) (xy 402.1582 -6.080252) (xy 402.1582 -6.080506)
			(xy 402.158454 -6.09092) (xy 402.158454 -6.091428) (xy 402.157946 -6.110224) (xy 402.157438 -6.121146)
			(xy 402.165058 -6.140958) (xy 402.233892 -6.210046) (xy 402.253958 -6.217412) (xy 402.26488 -6.216904)
			(xy 402.284438 -6.216396) (xy 402.284692 -6.216396) (xy 402.311959 -6.216932) (xy 402.365939 -6.224691)
			(xy 402.418265 -6.240053) (xy 402.467872 -6.262706) (xy 402.513751 -6.292187) (xy 402.554968 -6.327897)
			(xy 402.590683 -6.369109) (xy 402.62017 -6.414984) (xy 402.642829 -6.464588) (xy 402.658198 -6.516912)
			(xy 402.665965 -6.570891) (xy 402.666454 -6.598158) (xy 402.665955 -6.624974) (xy 402.658442 -6.678076)
			(xy 402.643571 -6.729605) (xy 402.621636 -6.778546) (xy 402.593068 -6.823935) (xy 402.558429 -6.86488)
			(xy 402.518401 -6.900575) (xy 402.473772 -6.930317) (xy 402.449792 -6.942328) (xy 402.441156 -6.946392)
			(xy 402.427948 -6.960616) (xy 402.39569 -7.043928) (xy 402.395944 -7.062724) (xy 402.3995 -7.071614)
			(xy 402.3995 -7.072122) (xy 402.408304 -7.094883) (xy 402.42073 -7.142076) (xy 402.427022 -7.19047)
			(xy 402.42744 -7.21487) (xy 402.42744 -7.215124) (xy 402.426998 -7.242395) (xy 402.419232 -7.296381)
			(xy 402.403863 -7.348713) (xy 402.381202 -7.398325) (xy 402.351712 -7.444207) (xy 402.315992 -7.485424)
			(xy 402.27477 -7.521139) (xy 402.228884 -7.550624) (xy 402.17927 -7.573279) (xy 402.126936 -7.588642)
			(xy 402.072949 -7.596401) (xy 402.045678 -7.596886) (xy 402.015964 -7.596337) (xy 401.957253 -7.587122)
			(xy 401.900676 -7.568934) (xy 401.847594 -7.542209) (xy 401.799288 -7.507593) (xy 401.777708 -7.487158)
			(xy 401.768359 -7.478816) (xy 401.744386 -7.47163) (xy 401.731988 -7.473442) (xy 401.694175 -7.480677)
			(xy 401.617576 -7.488441) (xy 401.57908 -7.488936) (xy 401.53639 -7.488344) (xy 401.451546 -7.478779)
			(xy 401.368298 -7.459815) (xy 401.287683 -7.431688) (xy 401.210707 -7.394749) (xy 401.174204 -7.372604)
			(xy 401.165943 -7.367908) (xy 401.14728 -7.3644) (xy 401.128617 -7.367908) (xy 401.120356 -7.372604)
			(xy 401.083862 -7.394765) (xy 401.006887 -7.431709) (xy 400.92627 -7.459833) (xy 400.843018 -7.478787)
			(xy 400.758171 -7.488334) (xy 400.71548 -7.488936) (xy 400.714972 -7.488936) (xy 400.676018 -7.488406)
			(xy 400.598524 -7.480386) (xy 400.560286 -7.472934) (xy 400.547825 -7.471057) (xy 400.523707 -7.478252)
			(xy 400.514312 -7.48665) (xy 400.492699 -7.507152) (xy 400.444332 -7.541923) (xy 400.391157 -7.568771)
			(xy 400.334462 -7.587046) (xy 400.275618 -7.596306) (xy 400.245834 -7.596886) (xy 400.24558 -7.596886)
			(xy 400.218311 -7.596394) (xy 400.164329 -7.58863) (xy 400.112001 -7.573264) (xy 400.062392 -7.550607)
			(xy 400.016513 -7.521121) (xy 399.975296 -7.485407) (xy 399.939581 -7.44419) (xy 399.910095 -7.398311)
			(xy 399.887438 -7.348703) (xy 399.87207 -7.296375) (xy 399.864306 -7.242393) (xy 399.863818 -7.215124)
			(xy 399.864209 -7.190503) (xy 399.870529 -7.141668) (xy 399.883081 -7.094053) (xy 399.892012 -7.071106)
			(xy 399.895568 -7.062216) (xy 399.895822 -7.042912) (xy 399.867628 -6.968744) (xy 399.863885 -6.959986)
			(xy 399.851084 -6.945898) (xy 399.842736 -6.941312) (xy 399.842482 -6.941312) (xy 399.818734 -6.929184)
			(xy 399.774533 -6.899356) (xy 399.734913 -6.863669) (xy 399.700642 -6.822816) (xy 399.672388 -6.777594)
			(xy 399.650701 -6.72888) (xy 399.636001 -6.677623) (xy 399.628574 -6.62482) (xy 399.628106 -6.598158)
			(xy 399.628585 -6.570889) (xy 399.636352 -6.516907) (xy 399.651721 -6.464579) (xy 399.67438 -6.414971)
			(xy 399.703867 -6.369092) (xy 399.739583 -6.327876) (xy 399.7808 -6.292161) (xy 399.82668 -6.262675)
			(xy 399.876289 -6.240017) (xy 399.928617 -6.22465) (xy 399.982599 -6.216885) (xy 400.009868 -6.216396)
			(xy 400.010122 -6.216396) (xy 400.02968 -6.216904) (xy 400.040602 -6.217412) (xy 400.060668 -6.210046)
			(xy 400.129502 -6.140958) (xy 400.137122 -6.121146) (xy 400.136614 -6.110224) (xy 400.136106 -6.091428)
			(xy 400.136106 -6.09092) (xy 400.13636 -6.080506) (xy 400.13636 -6.080252) (xy 400.136044 -6.069428)
			(xy 400.127505 -6.049554) (xy 400.11985 -6.041898) (xy 400.063208 -5.989574) (xy 400.054833 -5.982643)
			(xy 400.034179 -5.97593) (xy 400.02333 -5.97662) (xy 400.022822 -5.97662) (xy 400.012065 -5.977791)
			(xy 399.990462 -5.979063) (xy 399.979642 -5.97916) (xy 399.979388 -5.97916) (xy 399.950536 -5.978613)
			(xy 399.893489 -5.969933) (xy 399.838396 -5.952772) (xy 399.786511 -5.927522) (xy 399.739012 -5.894755)
			(xy 399.696982 -5.855218) (xy 399.661376 -5.80981) (xy 399.633004 -5.759564) (xy 399.622264 -5.73278)
			(xy 399.617359 -5.72174) (xy 399.599448 -5.705575) (xy 399.587974 -5.701792) (xy 399.55124 -5.691565)
			(xy 399.479858 -5.664742) (xy 399.411501 -5.630943) (xy 399.378932 -5.611114) (xy 399.370676 -5.6064)
			(xy 399.352008 -5.602873) (xy 399.33334 -5.6064) (xy 399.325084 -5.611114) (xy 399.290967 -5.631832)
			(xy 399.219226 -5.666832) (xy 399.144224 -5.694155) (xy 399.105628 -5.704332) (xy 399.093934 -5.707964)
			(xy 399.07562 -5.724161) (xy 399.070576 -5.73532) (xy 399.059703 -5.761865) (xy 399.031205 -5.811647)
			(xy 398.995581 -5.856607) (xy 398.953634 -5.895732) (xy 398.906306 -5.928143) (xy 398.854663 -5.95311)
			(xy 398.799866 -5.970072) (xy 398.743149 -5.978647) (xy 398.714468 -5.97916) (xy 398.703648 -5.979066)
			(xy 398.682045 -5.977793) (xy 398.671288 -5.97662) (xy 398.660366 -5.97535) (xy 398.639538 -5.982208)
			(xy 398.574768 -6.041898) (xy 398.567153 -6.049585) (xy 398.558599 -6.069438) (xy 398.558258 -6.080252)
			(xy 398.558258 -6.080506) (xy 398.558512 -6.09092) (xy 398.558512 -6.091428) (xy 398.558004 -6.110224)
			(xy 398.557496 -6.121146) (xy 398.565116 -6.140958) (xy 398.63395 -6.210046) (xy 398.654016 -6.217412)
			(xy 398.664938 -6.216904) (xy 398.684496 -6.216396) (xy 398.68475 -6.216396) (xy 398.712019 -6.216878)
			(xy 398.766 -6.224645) (xy 398.818327 -6.240015) (xy 398.867935 -6.262674) (xy 398.913813 -6.292161)
			(xy 398.955029 -6.327876) (xy 398.990744 -6.369093) (xy 399.02023 -6.414972) (xy 399.042888 -6.46458)
			(xy 399.058256 -6.516908) (xy 399.066023 -6.570889) (xy 399.066512 -6.598158) (xy 399.066012 -6.624997)
			(xy 399.058479 -6.678143) (xy 399.043583 -6.729713) (xy 399.021618 -6.77869) (xy 398.993016 -6.824113)
			(xy 398.95834 -6.865086) (xy 398.918271 -6.900804) (xy 398.873598 -6.930564) (xy 398.849596 -6.942582)
			(xy 398.84096 -6.946646) (xy 398.827752 -6.96087) (xy 398.795748 -7.043928) (xy 398.796002 -7.063232)
			(xy 398.799558 -7.072122) (xy 398.808298 -7.094807) (xy 398.820596 -7.141841) (xy 398.82683 -7.190055)
			(xy 398.827244 -7.214362) (xy 398.827244 -7.215124) (xy 398.826798 -7.242395) (xy 398.819032 -7.296381)
			(xy 398.803663 -7.348712) (xy 398.781003 -7.398324) (xy 398.751513 -7.444205) (xy 398.715793 -7.485423)
			(xy 398.674572 -7.521138) (xy 398.628687 -7.550623) (xy 398.579073 -7.573278) (xy 398.52674 -7.588641)
			(xy 398.472753 -7.596401) (xy 398.445482 -7.596886) (xy 398.415792 -7.596294) (xy 398.357129 -7.587092)
			(xy 398.300599 -7.568914) (xy 398.247568 -7.542197) (xy 398.199316 -7.507588) (xy 398.177766 -7.487158)
			(xy 398.168393 -7.47885) (xy 398.144439 -7.471643) (xy 398.132046 -7.473442) (xy 398.094234 -7.480683)
			(xy 398.017634 -7.488443) (xy 397.979138 -7.488936) (xy 397.936449 -7.488317) (xy 397.851606 -7.478758)
			(xy 397.768358 -7.4598) (xy 397.687743 -7.431679) (xy 397.610765 -7.394746) (xy 397.574262 -7.372604)
			(xy 397.566001 -7.367908) (xy 397.547338 -7.3644) (xy 397.528675 -7.367908) (xy 397.520414 -7.372604)
			(xy 397.483906 -7.39474) (xy 397.406935 -7.431689) (xy 397.326321 -7.459818) (xy 397.243072 -7.478778)
			(xy 397.158228 -7.488331) (xy 397.115538 -7.488936) (xy 397.11503 -7.488936) (xy 397.076077 -7.488397)
			(xy 396.998582 -7.480383) (xy 396.960344 -7.472934) (xy 396.947881 -7.471096) (xy 396.923768 -7.478264)
			(xy 396.91437 -7.48665) (xy 396.892775 -7.507172) (xy 396.844403 -7.54194) (xy 396.791224 -7.568784)
			(xy 396.734525 -7.587055) (xy 396.675677 -7.59631) (xy 396.645892 -7.596886) (xy 396.645638 -7.596886)
			(xy 396.618369 -7.596363) (xy 396.564386 -7.588607) (xy 396.512055 -7.573247) (xy 396.462444 -7.550595)
			(xy 396.416561 -7.521114) (xy 396.375341 -7.485403) (xy 396.339623 -7.444188) (xy 396.310134 -7.398311)
			(xy 396.287475 -7.348703) (xy 396.272106 -7.296375) (xy 396.264341 -7.242393) (xy 396.263876 -7.215124)
			(xy 396.264263 -7.190503) (xy 396.270585 -7.141668) (xy 396.283139 -7.094053) (xy 396.29207 -7.071106)
			(xy 396.295626 -7.062216) (xy 396.29588 -7.042912) (xy 396.267686 -6.968744) (xy 396.263957 -6.959979)
			(xy 396.251147 -6.945894) (xy 396.242794 -6.941312) (xy 396.24254 -6.941312) (xy 396.218782 -6.929203)
			(xy 396.174583 -6.89937) (xy 396.134965 -6.863679) (xy 396.100696 -6.822824) (xy 396.072444 -6.777599)
			(xy 396.050757 -6.728883) (xy 396.036058 -6.677625) (xy 396.028632 -6.62482) (xy 396.028164 -6.598158)
			(xy 396.028585 -6.570886) (xy 396.036354 -6.516899) (xy 396.051726 -6.464567) (xy 396.074388 -6.414955)
			(xy 396.103881 -6.369073) (xy 396.139603 -6.327855) (xy 396.180827 -6.29214) (xy 396.226715 -6.262656)
			(xy 396.276331 -6.240002) (xy 396.328666 -6.224639) (xy 396.382654 -6.216881) (xy 396.409926 -6.216396)
			(xy 396.41018 -6.216396) (xy 396.429738 -6.216904) (xy 396.44066 -6.217412) (xy 396.460726 -6.210046)
			(xy 396.52956 -6.140958) (xy 396.53718 -6.121146) (xy 396.536672 -6.110224) (xy 396.536164 -6.091174)
			(xy 396.536164 -6.09092) (xy 396.536418 -6.080252) (xy 396.536181 -6.069359) (xy 396.527615 -6.049347)
			(xy 396.519908 -6.041644) (xy 396.463266 -5.989574) (xy 396.454906 -5.982622) (xy 396.43424 -5.975921)
			(xy 396.423388 -5.97662) (xy 396.42288 -5.97662) (xy 396.411996 -5.977801) (xy 396.390139 -5.979074)
			(xy 396.379192 -5.97916) (xy 396.350325 -5.978602) (xy 396.293247 -5.969935) (xy 396.238126 -5.952769)
			(xy 396.186219 -5.927495) (xy 396.138712 -5.894692) (xy 396.096687 -5.855106) (xy 396.061105 -5.809642)
			(xy 396.032778 -5.759337) (xy 396.022068 -5.732526) (xy 396.017066 -5.72148) (xy 395.999048 -5.705306)
			(xy 395.987524 -5.701538) (xy 395.950881 -5.691279) (xy 395.879673 -5.664442) (xy 395.811486 -5.630658)
			(xy 395.77899 -5.61086) (xy 395.770729 -5.606164) (xy 395.752066 -5.602656) (xy 395.733403 -5.606164)
			(xy 395.725142 -5.61086) (xy 395.690986 -5.631622) (xy 395.61917 -5.666722) (xy 395.544078 -5.694124)
			(xy 395.505432 -5.704332) (xy 395.493738 -5.707965) (xy 395.475424 -5.724162) (xy 395.47038 -5.73532)
			(xy 395.459503 -5.761864) (xy 395.431006 -5.811646) (xy 395.395383 -5.856605) (xy 395.353436 -5.89573)
			(xy 395.306108 -5.928142) (xy 395.254466 -5.953109) (xy 395.19967 -5.970072) (xy 395.142953 -5.978647)
			(xy 395.114272 -5.97916) (xy 395.103516 -5.979054) (xy 395.08204 -5.977783) (xy 395.071346 -5.97662)
			(xy 395.060424 -5.97535) (xy 395.039596 -5.982208) (xy 394.974826 -6.041898) (xy 394.967205 -6.049579)
			(xy 394.958656 -6.069437) (xy 394.958316 -6.080252) (xy 394.958316 -6.080506) (xy 394.95857 -6.090666)
			(xy 394.95857 -6.091174) (xy 394.958062 -6.110224) (xy 394.957554 -6.121146) (xy 394.965174 -6.140958)
			(xy 395.034008 -6.210046) (xy 395.054074 -6.217412) (xy 395.064996 -6.216904) (xy 395.084554 -6.216396)
			(xy 395.084808 -6.216396) (xy 395.112076 -6.216917) (xy 395.166056 -6.224679) (xy 395.218382 -6.240043)
			(xy 395.26799 -6.262697) (xy 395.313868 -6.29218) (xy 395.355085 -6.327891) (xy 395.3908 -6.369104)
			(xy 395.420287 -6.414981) (xy 395.442945 -6.464586) (xy 395.458314 -6.516911) (xy 395.466081 -6.57089)
			(xy 395.46657 -6.598158) (xy 395.466094 -6.624998) (xy 395.45856 -6.678146) (xy 395.443662 -6.729717)
			(xy 395.421695 -6.778696) (xy 395.393089 -6.824119) (xy 395.358408 -6.865092) (xy 395.318335 -6.900809)
			(xy 395.273658 -6.930566) (xy 395.249654 -6.942582) (xy 395.241018 -6.946646) (xy 395.22781 -6.96087)
			(xy 395.195806 -7.043928) (xy 395.19606 -7.063232) (xy 395.199616 -7.072122) (xy 395.208359 -7.094806)
			(xy 395.220655 -7.141841) (xy 395.226888 -7.190055) (xy 395.227302 -7.214362) (xy 395.227302 -7.215124)
			(xy 395.226798 -7.242392) (xy 395.219034 -7.296373) (xy 395.203668 -7.3487) (xy 395.181012 -7.398307)
			(xy 395.151527 -7.444186) (xy 395.115814 -7.485403) (xy 395.074599 -7.521117) (xy 395.028721 -7.550604)
			(xy 394.979115 -7.573262) (xy 394.926789 -7.588631) (xy 394.872808 -7.596397) (xy 394.84554 -7.596886)
			(xy 394.815849 -7.59632) (xy 394.757185 -7.587112) (xy 394.700655 -7.568927) (xy 394.647624 -7.542205)
			(xy 394.599374 -7.507591) (xy 394.577824 -7.487158) (xy 394.568469 -7.478826) (xy 394.544501 -7.471633)
			(xy 394.532104 -7.473442) (xy 394.494291 -7.480674) (xy 394.417692 -7.48844) (xy 394.379196 -7.488936)
			(xy 394.336506 -7.488337) (xy 394.251663 -7.478773) (xy 394.168415 -7.459811) (xy 394.0878 -7.431685)
			(xy 394.010823 -7.394748) (xy 393.97432 -7.372604) (xy 393.966059 -7.367908) (xy 393.947396 -7.3644)
			(xy 393.928733 -7.367908) (xy 393.920472 -7.372604) (xy 393.883975 -7.394758) (xy 393.807 -7.431703)
			(xy 393.726384 -7.459829) (xy 393.643133 -7.478785) (xy 393.558287 -7.488333) (xy 393.515596 -7.488936)
			(xy 393.515088 -7.488936) (xy 393.476135 -7.488403) (xy 393.39864 -7.480385) (xy 393.360402 -7.472934)
			(xy 393.34794 -7.471067) (xy 393.323824 -7.478255) (xy 393.314428 -7.48665) (xy 393.292808 -7.507144)
			(xy 393.244443 -7.541916) (xy 393.19127 -7.568766) (xy 393.134576 -7.587043) (xy 393.075733 -7.596305)
			(xy 393.04595 -7.596886) (xy 393.045696 -7.596886) (xy 393.018428 -7.596379) (xy 392.964446 -7.588618)
			(xy 392.912118 -7.573253) (xy 392.86251 -7.550598) (xy 392.81663 -7.521114) (xy 392.775413 -7.485401)
			(xy 392.739698 -7.444186) (xy 392.710211 -7.398308) (xy 392.687554 -7.3487) (xy 392.672186 -7.296374)
			(xy 392.664422 -7.242392) (xy 392.663934 -7.215124) (xy 392.664324 -7.190503) (xy 392.670645 -7.141668)
			(xy 392.683197 -7.094053) (xy 392.692128 -7.071106) (xy 392.695684 -7.062216) (xy 392.695938 -7.042912)
			(xy 392.667744 -6.968744) (xy 392.663995 -6.959989) (xy 392.651199 -6.9459) (xy 392.642852 -6.941312)
			(xy 392.642598 -6.941312) (xy 392.618853 -6.929177) (xy 392.574653 -6.89935) (xy 392.535031 -6.863665)
			(xy 392.50076 -6.822813) (xy 392.472506 -6.777592) (xy 392.450817 -6.728879) (xy 392.436117 -6.677622)
			(xy 392.42869 -6.624819) (xy 392.428222 -6.598158) (xy 389.125968 -6.598158) (xy 389.125968 -9.780016)
			(xy 389.125476 -9.863891) (xy 389.117494 -10.03145) (xy 389.101547 -10.198439) (xy 389.077674 -10.364481)
			(xy 389.045926 -10.529198) (xy 389.006377 -10.692219) (xy 388.959116 -10.853173) (xy 388.904249 -11.011695)
			(xy 388.841902 -11.167428) (xy 388.772216 -11.320018) (xy 388.695348 -11.469118) (xy 388.611473 -11.614393)
			(xy 388.52078 -11.755512) (xy 388.423475 -11.892156) (xy 388.319779 -12.024015) (xy 388.209926 -12.150791)
			(xy 388.094165 -12.272196) (xy 387.986471 -12.37488) (xy 430.986438 -12.37488) (xy 430.986906 -12.34761)
			(xy 430.99467 -12.293626) (xy 431.010038 -12.241296) (xy 431.032697 -12.191686) (xy 431.062185 -12.145805)
			(xy 431.097902 -12.104588) (xy 431.139121 -12.068873) (xy 431.185003 -12.039387) (xy 431.234615 -12.016731)
			(xy 431.286945 -12.001366) (xy 431.34093 -11.993604) (xy 431.3682 -11.993118) (xy 431.397892 -11.993658)
			(xy 431.456558 -12.002872) (xy 431.513088 -12.021063) (xy 431.566118 -12.047791) (xy 431.614367 -12.082411)
			(xy 431.635916 -12.102846) (xy 431.645254 -12.111202) (xy 431.669236 -12.11838) (xy 431.681636 -12.116562)
			(xy 431.719448 -12.109324) (xy 431.796048 -12.101562) (xy 431.834544 -12.101068) (xy 431.877233 -12.10171)
			(xy 431.962074 -12.111266) (xy 432.045321 -12.130219) (xy 432.125937 -12.158335) (xy 432.202915 -12.195262)
			(xy 432.23942 -12.2174) (xy 432.247681 -12.222096) (xy 432.266344 -12.225604) (xy 432.285007 -12.222096)
			(xy 432.293268 -12.2174) (xy 432.32978 -12.195272) (xy 432.406751 -12.158322) (xy 432.487363 -12.13019)
			(xy 432.570611 -12.111229) (xy 432.655454 -12.101674) (xy 432.698144 -12.101068) (xy 432.698652 -12.101068)
			(xy 432.737606 -12.101595) (xy 432.8151 -12.109616) (xy 432.853338 -12.11707) (xy 432.865797 -12.11899)
			(xy 432.889923 -12.11177) (xy 432.899312 -12.103354) (xy 432.920915 -12.082842) (xy 432.969285 -12.048072)
			(xy 433.022462 -12.021226) (xy 433.07916 -12.002953) (xy 433.138005 -11.993696) (xy 433.16779 -11.993118)
			(xy 433.168044 -11.993118) (xy 433.195314 -11.993583) (xy 433.249297 -12.001351) (xy 433.301626 -12.016721)
			(xy 433.351235 -12.03938) (xy 433.397114 -12.068869) (xy 433.438331 -12.104586) (xy 433.474045 -12.145805)
			(xy 433.503531 -12.191687) (xy 433.526188 -12.241297) (xy 433.541554 -12.293627) (xy 433.549318 -12.34761)
			(xy 433.549806 -12.37488) (xy 433.549335 -12.400788) (xy 436.813452 -12.400788) (xy 436.813941 -12.359678)
			(xy 436.821529 -12.27781) (xy 436.83664 -12.196991) (xy 436.859145 -12.117912) (xy 436.888851 -12.041247)
			(xy 436.925505 -11.96765) (xy 436.968795 -11.89775) (xy 437.01835 -11.832142) (xy 437.073748 -11.771388)
			(xy 437.134516 -11.716006) (xy 437.200136 -11.666467) (xy 437.270047 -11.623195) (xy 437.343653 -11.58656)
			(xy 437.420326 -11.556873) (xy 437.499411 -11.534389) (xy 437.580234 -11.519298) (xy 437.662104 -11.511731)
			(xy 437.703214 -11.51128) (xy 437.747029 -11.511772) (xy 437.83424 -11.520318) (xy 437.920187 -11.537406)
			(xy 438.004035 -11.562868) (xy 438.084971 -11.596458) (xy 438.123838 -11.61669) (xy 438.135191 -11.622017)
			(xy 438.160237 -11.622017) (xy 438.17159 -11.61669) (xy 438.210465 -11.596477) (xy 438.291405 -11.562905)
			(xy 438.375252 -11.537448) (xy 438.461195 -11.520353) (xy 438.548401 -11.511784) (xy 438.592214 -11.51128)
			(xy 438.636029 -11.511772) (xy 438.72324 -11.520318) (xy 438.809187 -11.537406) (xy 438.893035 -11.562868)
			(xy 438.973971 -11.596458) (xy 439.012838 -11.61669) (xy 439.024191 -11.622017) (xy 439.049237 -11.622017)
			(xy 439.06059 -11.61669) (xy 439.099465 -11.596477) (xy 439.180405 -11.562905) (xy 439.264252 -11.537448)
			(xy 439.350195 -11.520353) (xy 439.437401 -11.511784) (xy 439.481214 -11.51128) (xy 439.521951 -11.511719)
			(xy 439.603086 -11.519152) (xy 439.683202 -11.533973) (xy 439.761626 -11.556057) (xy 439.837703 -11.585219)
			(xy 439.910794 -11.621216) (xy 439.94578 -11.64209) (xy 439.954798 -11.647053) (xy 439.975154 -11.650004)
			(xy 439.995036 -11.644737) (xy 440.003438 -11.638788) (xy 440.091322 -11.570462) (xy 440.10072 -11.54049)
			(xy 440.095894 -11.52525) (xy 440.083229 -11.482506) (xy 440.065483 -11.395136) (xy 440.056563 -11.306429)
			(xy 440.056016 -11.261852) (xy 440.056016 -11.26109) (xy 440.056438 -11.22287) (xy 440.062998 -11.146712)
			(xy 440.076079 -11.071399) (xy 440.095582 -10.997489) (xy 440.108086 -10.96137) (xy 440.110695 -10.953059)
			(xy 440.110679 -10.935651) (xy 440.108086 -10.927334) (xy 440.095582 -10.891215) (xy 440.076095 -10.817302)
			(xy 440.063015 -10.74199) (xy 440.056437 -10.665834) (xy 440.056016 -10.627614) (xy 440.056016 -10.626852)
			(xy 440.05652 -10.584504) (xy 440.064571 -10.50019) (xy 440.0806 -10.417024) (xy 440.104461 -10.335757)
			(xy 440.13594 -10.257127) (xy 440.174751 -10.181846) (xy 440.220541 -10.110594) (xy 440.272897 -10.044018)
			(xy 440.331345 -9.98272) (xy 440.395355 -9.927255) (xy 440.464347 -9.878126) (xy 440.537697 -9.835777)
			(xy 440.61474 -9.800593) (xy 440.694779 -9.772891) (xy 440.777088 -9.752923) (xy 440.860923 -9.74087)
			(xy 440.945524 -9.73684) (xy 441.030125 -9.74087) (xy 441.11396 -9.752923) (xy 441.196269 -9.772891)
			(xy 441.276308 -9.800593) (xy 441.353351 -9.835777) (xy 441.426701 -9.878126) (xy 441.495693 -9.927255)
			(xy 441.559703 -9.98272) (xy 441.618151 -10.044018) (xy 441.670507 -10.110594) (xy 441.716297 -10.181846)
			(xy 441.755108 -10.257127) (xy 441.786587 -10.335757) (xy 441.810448 -10.417024) (xy 441.826477 -10.50019)
			(xy 441.834528 -10.584504) (xy 441.835032 -10.626852) (xy 441.835032 -10.627614) (xy 441.834614 -10.665834)
			(xy 441.828053 -10.741992) (xy 441.814972 -10.817305) (xy 441.795467 -10.891215) (xy 441.782962 -10.927334)
			(xy 441.780399 -10.935656) (xy 441.780383 -10.953054) (xy 441.782962 -10.96137) (xy 441.795465 -10.997489)
			(xy 441.814952 -11.071403) (xy 441.828033 -11.146715) (xy 441.834611 -11.22287) (xy 441.835032 -11.26109)
			(xy 441.835032 -11.261852) (xy 441.834502 -11.302954) (xy 441.826922 -11.384807) (xy 441.811821 -11.465611)
			(xy 441.789329 -11.544677) (xy 441.759637 -11.621331) (xy 441.722999 -11.694918) (xy 441.679728 -11.764811)
			(xy 441.630192 -11.830413) (xy 441.574815 -11.891164) (xy 441.514068 -11.946546) (xy 441.44847 -11.996087)
			(xy 441.378581 -12.039364) (xy 441.304997 -12.076008) (xy 441.228346 -12.105706) (xy 441.149281 -12.128204)
			(xy 441.068478 -12.143312) (xy 440.986626 -12.150899) (xy 440.945524 -12.15136) (xy 440.945016 -12.15136)
			(xy 440.904322 -12.150875) (xy 440.823276 -12.143416) (xy 440.74325 -12.128584) (xy 440.664913 -12.106505)
			(xy 440.58892 -12.077363) (xy 440.515907 -12.041401) (xy 440.480958 -12.02055) (xy 440.471926 -12.015614)
			(xy 440.451579 -12.012649) (xy 440.431701 -12.017907) (xy 440.4233 -12.023852) (xy 440.335416 -12.092178)
			(xy 440.326018 -12.12215) (xy 440.330844 -12.13739) (xy 440.343568 -12.180123) (xy 440.361398 -12.267491)
			(xy 440.370394 -12.356204) (xy 440.370638 -12.37488) (xy 444.98133 -12.37488) (xy 444.981806 -12.347611)
			(xy 444.98957 -12.293627) (xy 445.004937 -12.241298) (xy 445.027595 -12.191688) (xy 445.057083 -12.145808)
			(xy 445.092799 -12.10459) (xy 445.134017 -12.068875) (xy 445.179899 -12.03939) (xy 445.229509 -12.016733)
			(xy 445.281839 -12.001367) (xy 445.335822 -11.993605) (xy 445.363092 -11.993118) (xy 445.392806 -11.993684)
			(xy 445.451515 -12.002895) (xy 445.508093 -12.021079) (xy 445.561174 -12.0478) (xy 445.609482 -12.082412)
			(xy 445.631062 -12.102846) (xy 445.640423 -12.111171) (xy 445.664386 -12.118367) (xy 445.676782 -12.116562)
			(xy 445.714593 -12.109317) (xy 445.791194 -12.101559) (xy 445.82969 -12.101068) (xy 445.872379 -12.101688)
			(xy 445.957221 -12.111249) (xy 446.040469 -12.130208) (xy 446.121084 -12.158328) (xy 446.198062 -12.195259)
			(xy 446.234566 -12.2174) (xy 446.242827 -12.222096) (xy 446.26149 -12.225604) (xy 446.280153 -12.222096)
			(xy 446.288414 -12.2174) (xy 446.324915 -12.195252) (xy 446.401889 -12.158306) (xy 446.482504 -12.130179)
			(xy 446.565754 -12.111222) (xy 446.6506 -12.101672) (xy 446.69329 -12.101068) (xy 446.693798 -12.101068)
			(xy 446.732751 -12.101603) (xy 446.810246 -12.109619) (xy 446.848484 -12.11707) (xy 446.860946 -12.118954)
			(xy 446.885066 -12.111758) (xy 446.894458 -12.103354) (xy 446.916042 -12.08282) (xy 446.964416 -12.048053)
			(xy 447.017598 -12.021211) (xy 447.074301 -12.002943) (xy 447.13315 -11.993692) (xy 447.162936 -11.993118)
			(xy 447.16319 -11.993118) (xy 447.190458 -11.993634) (xy 447.24444 -12.001393) (xy 447.296768 -12.016757)
			(xy 447.346376 -12.03941) (xy 447.392256 -12.068893) (xy 447.433474 -12.104605) (xy 447.469189 -12.14582)
			(xy 447.498676 -12.191697) (xy 447.521333 -12.241304) (xy 447.5367 -12.293631) (xy 447.544464 -12.347612)
			(xy 447.544952 -12.37488) (xy 447.544428 -12.403035) (xy 447.536105 -12.458728) (xy 447.519695 -12.512595)
			(xy 447.495554 -12.563469) (xy 447.464205 -12.610248) (xy 447.445638 -12.63142) (xy 447.437635 -12.641221)
			(xy 447.431511 -12.66574) (xy 447.433954 -12.678156) (xy 447.444761 -12.723941) (xy 447.456357 -12.8173)
			(xy 447.457068 -12.864338) (xy 447.457068 -12.864846) (xy 447.456598 -12.904848) (xy 447.448231 -12.984412)
			(xy 447.431593 -13.062666) (xy 447.406867 -13.138753) (xy 447.374323 -13.211838) (xy 447.334318 -13.281121)
			(xy 447.287291 -13.345843) (xy 447.233756 -13.405295) (xy 447.1743 -13.458826) (xy 447.109574 -13.505849)
			(xy 447.040288 -13.545849) (xy 446.967201 -13.578387) (xy 446.891112 -13.603108) (xy 446.812857 -13.61974)
			(xy 446.733292 -13.628101) (xy 446.69329 -13.628624) (xy 446.650601 -13.628014) (xy 446.565758 -13.618451)
			(xy 446.482511 -13.59949) (xy 446.401895 -13.571368) (xy 446.324918 -13.534434) (xy 446.288414 -13.512292)
			(xy 446.280153 -13.507596) (xy 446.26149 -13.504088) (xy 446.242827 -13.507596) (xy 446.234566 -13.512292)
			(xy 446.198069 -13.534447) (xy 446.121095 -13.571392) (xy 446.040478 -13.599518) (xy 445.957227 -13.618473)
			(xy 445.872381 -13.628021) (xy 445.82969 -13.628624) (xy 445.789691 -13.628064) (xy 445.710131 -13.619701)
			(xy 445.631881 -13.603069) (xy 445.555798 -13.578348) (xy 445.482716 -13.54581) (xy 445.413435 -13.505812)
			(xy 445.348714 -13.458791) (xy 445.289263 -13.405263) (xy 445.235732 -13.345814) (xy 445.188708 -13.281096)
			(xy 445.148706 -13.211816) (xy 445.116165 -13.138736) (xy 445.091441 -13.062654) (xy 445.074804 -12.984405)
			(xy 445.066438 -12.904845) (xy 445.065912 -12.864846) (xy 445.066666 -12.817023) (xy 445.078641 -12.722128)
			(xy 445.089788 -12.675616) (xy 445.092263 -12.663288) (xy 445.086273 -12.638902) (xy 445.078358 -12.629134)
			(xy 445.06019 -12.608035) (xy 445.029521 -12.561565) (xy 445.005932 -12.511132) (xy 444.989923 -12.457806)
			(xy 444.981834 -12.402719) (xy 444.98133 -12.37488) (xy 440.370638 -12.37488) (xy 440.370976 -12.400788)
			(xy 440.370415 -12.444238) (xy 440.361895 -12.530719) (xy 440.344992 -12.615959) (xy 440.319868 -12.699148)
			(xy 440.286761 -12.779495) (xy 440.266836 -12.81811) (xy 440.262961 -12.82623) (xy 440.260628 -12.84406)
			(xy 440.262264 -12.852908) (xy 440.272023 -12.900055) (xy 440.282457 -12.995773) (xy 440.283092 -13.043916)
			(xy 440.282667 -13.085188) (xy 440.275027 -13.167377) (xy 440.259804 -13.248505) (xy 440.23713 -13.327874)
			(xy 440.2072 -13.4048) (xy 440.170271 -13.478622) (xy 440.126661 -13.548705) (xy 440.076745 -13.614446)
			(xy 440.020952 -13.675279) (xy 439.959763 -13.730681) (xy 439.893704 -13.780175) (xy 439.823344 -13.823336)
			(xy 439.786522 -13.841984) (xy 439.778885 -13.846179) (xy 439.766763 -13.858679) (xy 439.759479 -13.874495)
			(xy 439.758328 -13.883132) (xy 439.755251 -13.911241) (xy 439.741951 -13.966197) (xy 439.720685 -14.018587)
			(xy 439.69192 -14.067266) (xy 439.656285 -14.111165) (xy 439.643167 -14.123162) (xy 440.58586 -14.123162)
			(xy 440.586283 -14.084873) (xy 440.592885 -14.008579) (xy 440.60603 -13.933136) (xy 440.625619 -13.859105)
			(xy 440.638184 -13.822934) (xy 440.640853 -13.814502) (xy 440.64084 -13.796827) (xy 440.638184 -13.78839)
			(xy 440.625655 -13.752208) (xy 440.606078 -13.678176) (xy 440.592927 -13.602738) (xy 440.586298 -13.52645)
			(xy 440.58586 -13.488162) (xy 440.586364 -13.445801) (xy 440.594417 -13.361464) (xy 440.610451 -13.278274)
			(xy 440.634319 -13.196984) (xy 440.665807 -13.118332) (xy 440.704629 -13.043029) (xy 440.750432 -12.971757)
			(xy 440.802803 -12.905161) (xy 440.861268 -12.843846) (xy 440.925296 -12.788365) (xy 440.994308 -12.739222)
			(xy 441.067678 -12.696862) (xy 441.144743 -12.661667) (xy 441.224805 -12.633958) (xy 441.307138 -12.613984)
			(xy 441.390997 -12.601927) (xy 441.475622 -12.597896) (xy 441.560247 -12.601927) (xy 441.644106 -12.613984)
			(xy 441.726439 -12.633958) (xy 441.806501 -12.661667) (xy 441.883566 -12.696862) (xy 441.956936 -12.739222)
			(xy 442.025948 -12.788365) (xy 442.089976 -12.843846) (xy 442.148441 -12.905161) (xy 442.200812 -12.971757)
			(xy 442.246615 -13.043029) (xy 442.285437 -13.118332) (xy 442.316925 -13.196984) (xy 442.340793 -13.278274)
			(xy 442.356827 -13.361464) (xy 442.36488 -13.445801) (xy 442.365384 -13.488162) (xy 442.364966 -13.526452)
			(xy 442.358362 -13.602745) (xy 442.345216 -13.678188) (xy 442.325626 -13.752219) (xy 442.31306 -13.78839)
			(xy 442.310428 -13.796831) (xy 442.310415 -13.814498) (xy 442.31306 -13.822934) (xy 442.325598 -13.859113)
			(xy 442.345172 -13.933146) (xy 442.358321 -14.008585) (xy 442.364947 -14.084874) (xy 442.365384 -14.123162)
			(xy 442.36488 -14.165523) (xy 442.356827 -14.24986) (xy 442.340793 -14.33305) (xy 442.316925 -14.41434)
			(xy 442.285437 -14.492992) (xy 442.268155 -14.526514) (xy 449.780152 -14.526514) (xy 449.780656 -14.484153)
			(xy 449.788709 -14.399816) (xy 449.804743 -14.316626) (xy 449.828611 -14.235336) (xy 449.860099 -14.156684)
			(xy 449.898921 -14.081381) (xy 449.944724 -14.010109) (xy 449.997095 -13.943513) (xy 450.05556 -13.882198)
			(xy 450.119588 -13.826717) (xy 450.1886 -13.777574) (xy 450.26197 -13.735214) (xy 450.339035 -13.700019)
			(xy 450.419097 -13.67231) (xy 450.50143 -13.652336) (xy 450.585289 -13.640279) (xy 450.669914 -13.636248)
			(xy 450.754539 -13.640279) (xy 450.838398 -13.652336) (xy 450.920731 -13.67231) (xy 451.000793 -13.700019)
			(xy 451.077858 -13.735214) (xy 451.151228 -13.777574) (xy 451.22024 -13.826717) (xy 451.284268 -13.882198)
			(xy 451.342733 -13.943513) (xy 451.395104 -14.010109) (xy 451.440907 -14.081381) (xy 451.479729 -14.156684)
			(xy 451.511217 -14.235336) (xy 451.535085 -14.316626) (xy 451.551119 -14.399816) (xy 451.559172 -14.484153)
			(xy 451.559676 -14.526514) (xy 451.559114 -14.571839) (xy 451.549887 -14.662018) (xy 451.531531 -14.750791)
			(xy 451.504235 -14.837234) (xy 451.486778 -14.879066) (xy 451.483143 -14.888844) (xy 451.483128 -14.909681)
			(xy 451.486778 -14.919452) (xy 451.504363 -14.961485) (xy 451.531877 -15.048351) (xy 451.550364 -15.137575)
			(xy 451.559632 -15.228222) (xy 451.560184 -15.273782) (xy 451.559623 -15.318552) (xy 451.550621 -15.407639)
			(xy 451.532717 -15.495371) (xy 451.506092 -15.580861) (xy 451.489064 -15.62227) (xy 451.485509 -15.631864)
			(xy 451.485503 -15.652304) (xy 451.489064 -15.661894) (xy 451.50607 -15.703278) (xy 451.532693 -15.788702)
			(xy 451.550602 -15.876368) (xy 451.559616 -15.96539) (xy 451.560184 -16.010128) (xy 451.560184 -16.010382)
			(xy 451.55968 -16.05273) (xy 451.551629 -16.137044) (xy 451.5356 -16.22021) (xy 451.511739 -16.301477)
			(xy 451.48026 -16.380107) (xy 451.441449 -16.455388) (xy 451.395659 -16.52664) (xy 451.343303 -16.593216)
			(xy 451.284855 -16.654514) (xy 451.220845 -16.709979) (xy 451.151853 -16.759108) (xy 451.078503 -16.801457)
			(xy 451.00146 -16.836641) (xy 450.921421 -16.864343) (xy 450.839112 -16.884311) (xy 450.755277 -16.896364)
			(xy 450.670676 -16.900395) (xy 450.586075 -16.896364) (xy 450.50224 -16.884311) (xy 450.419931 -16.864343)
			(xy 450.339892 -16.836641) (xy 450.262849 -16.801457) (xy 450.189499 -16.759108) (xy 450.120507 -16.709979)
			(xy 450.056497 -16.654514) (xy 449.998049 -16.593216) (xy 449.945693 -16.52664) (xy 449.899903 -16.455388)
			(xy 449.861092 -16.380107) (xy 449.829613 -16.301477) (xy 449.805752 -16.22021) (xy 449.789723 -16.137044)
			(xy 449.781672 -16.05273) (xy 449.781168 -16.010382) (xy 449.781168 -16.010128) (xy 449.781731 -15.96539)
			(xy 449.790749 -15.876368) (xy 449.808655 -15.788701) (xy 449.83527 -15.703273) (xy 449.852288 -15.661894)
			(xy 449.855865 -15.652307) (xy 449.855859 -15.63186) (xy 449.852288 -15.62227) (xy 449.835263 -15.580859)
			(xy 449.808628 -15.495372) (xy 449.790721 -15.40764) (xy 449.781723 -15.318552) (xy 449.781168 -15.273782)
			(xy 449.781749 -15.228458) (xy 449.79099 -15.138283) (xy 449.809345 -15.049513) (xy 449.836623 -14.963067)
			(xy 449.854066 -14.92123) (xy 449.857691 -14.911438) (xy 449.857571 -14.890584) (xy 449.853812 -14.880844)
			(xy 449.836183 -14.838823) (xy 449.808624 -14.751958) (xy 449.790079 -14.662732) (xy 449.780742 -14.57208)
			(xy 449.780152 -14.526514) (xy 442.268155 -14.526514) (xy 442.246615 -14.568295) (xy 442.200812 -14.639567)
			(xy 442.148441 -14.706163) (xy 442.089976 -14.767478) (xy 442.025948 -14.822959) (xy 441.956936 -14.872102)
			(xy 441.883566 -14.914462) (xy 441.806501 -14.949657) (xy 441.726439 -14.977366) (xy 441.644106 -14.99734)
			(xy 441.560247 -15.009397) (xy 441.475622 -15.013429) (xy 441.390997 -15.009397) (xy 441.307138 -14.99734)
			(xy 441.224805 -14.977366) (xy 441.144743 -14.949657) (xy 441.067678 -14.914462) (xy 440.994308 -14.872102)
			(xy 440.925296 -14.822959) (xy 440.861268 -14.767478) (xy 440.802803 -14.706163) (xy 440.750432 -14.639567)
			(xy 440.704629 -14.568295) (xy 440.665807 -14.492992) (xy 440.634319 -14.41434) (xy 440.610451 -14.33305)
			(xy 440.594417 -14.24986) (xy 440.586364 -14.165523) (xy 440.58586 -14.123162) (xy 439.643167 -14.123162)
			(xy 439.614561 -14.149324) (xy 439.567661 -14.180907) (xy 439.516614 -14.205222) (xy 439.462537 -14.221736)
			(xy 439.406615 -14.230088) (xy 439.378344 -14.230604) (xy 439.350975 -14.230111) (xy 439.296797 -14.2223)
			(xy 439.244294 -14.206817) (xy 439.194547 -14.183981) (xy 439.148579 -14.154262) (xy 439.127646 -14.136624)
			(xy 439.127392 -14.13637) (xy 439.120314 -14.130771) (xy 439.103391 -14.124533) (xy 439.094372 -14.124178)
			(xy 439.027316 -14.124178) (xy 439.018301 -14.124547) (xy 439.001384 -14.130787) (xy 438.994296 -14.13637)
			(xy 438.994296 -14.136624) (xy 438.994042 -14.136624) (xy 438.973108 -14.154261) (xy 438.927135 -14.183972)
			(xy 438.877388 -14.206808) (xy 438.824888 -14.2223) (xy 438.770713 -14.230129) (xy 438.743344 -14.230604)
			(xy 438.713998 -14.230028) (xy 438.656001 -14.221024) (xy 438.600065 -14.203253) (xy 438.547506 -14.177132)
			(xy 438.499563 -14.143277) (xy 438.457364 -14.102486) (xy 438.421903 -14.055718) (xy 438.394015 -14.004075)
			(xy 438.38368 -13.976604) (xy 438.380221 -13.968026) (xy 438.368225 -13.953963) (xy 438.360312 -13.949172)
			(xy 438.333388 -13.93444) (xy 438.324705 -13.93016) (xy 438.305508 -13.927807) (xy 438.29605 -13.929868)
			(xy 438.259095 -13.939128) (xy 438.184005 -13.952036) (xy 438.108086 -13.958466) (xy 438.06999 -13.958824)
			(xy 438.028658 -13.958363) (xy 437.94635 -13.95071) (xy 437.865107 -13.935453) (xy 437.78563 -13.912724)
			(xy 437.708605 -13.882718) (xy 437.634696 -13.845694) (xy 437.564542 -13.801972) (xy 437.498747 -13.751929)
			(xy 437.43788 -13.695998) (xy 437.382465 -13.634659) (xy 437.332981 -13.568444) (xy 437.289854 -13.497922)
			(xy 437.253456 -13.423703) (xy 437.224103 -13.346427) (xy 437.202046 -13.266761) (xy 437.187477 -13.185391)
			(xy 437.18353 -13.144246) (xy 437.182106 -13.133691) (xy 437.171856 -13.11505) (xy 437.163718 -13.108178)
			(xy 437.131484 -13.082996) (xy 437.071245 -13.027653) (xy 437.016344 -12.967011) (xy 436.967245 -12.901582)
			(xy 436.924364 -12.831919) (xy 436.888063 -12.758612) (xy 436.858649 -12.682281) (xy 436.83637 -12.603571)
			(xy 436.821416 -12.523147) (xy 436.813913 -12.441689) (xy 436.813452 -12.400788) (xy 433.549335 -12.400788)
			(xy 433.549294 -12.403036) (xy 433.540969 -12.45873) (xy 433.524557 -12.512597) (xy 433.500414 -12.563471)
			(xy 433.469061 -12.610249) (xy 433.450492 -12.63142) (xy 433.442494 -12.641224) (xy 433.436365 -12.665741)
			(xy 433.438808 -12.678156) (xy 433.449615 -12.723941) (xy 433.461211 -12.8173) (xy 433.461922 -12.864338)
			(xy 433.461922 -12.864846) (xy 433.461398 -12.904846) (xy 433.453032 -12.984407) (xy 433.436395 -13.062658)
			(xy 433.411671 -13.138741) (xy 433.37913 -13.211824) (xy 433.339129 -13.281105) (xy 433.292106 -13.345825)
			(xy 433.238575 -13.405276) (xy 433.179124 -13.458807) (xy 433.114403 -13.50583) (xy 433.045122 -13.545831)
			(xy 432.972039 -13.578372) (xy 432.895956 -13.603096) (xy 432.817705 -13.619732) (xy 432.738144 -13.628098)
			(xy 432.698144 -13.628624) (xy 432.655455 -13.627989) (xy 432.570614 -13.618432) (xy 432.487366 -13.599476)
			(xy 432.406751 -13.571359) (xy 432.329772 -13.534431) (xy 432.293268 -13.512292) (xy 432.285007 -13.507596)
			(xy 432.266344 -13.504088) (xy 432.247681 -13.507596) (xy 432.23942 -13.512292) (xy 432.20291 -13.534425)
			(xy 432.125939 -13.571374) (xy 432.045326 -13.599504) (xy 431.962078 -13.618465) (xy 431.877234 -13.628018)
			(xy 431.834544 -13.628624) (xy 431.794546 -13.628013) (xy 431.714987 -13.619656) (xy 431.636738 -13.603028)
			(xy 431.560656 -13.578312) (xy 431.487574 -13.545779) (xy 431.418293 -13.505785) (xy 431.353572 -13.458768)
			(xy 431.29412 -13.405244) (xy 431.240588 -13.345798) (xy 431.193564 -13.281083) (xy 431.153562 -13.211806)
			(xy 431.12102 -13.138728) (xy 431.096295 -13.062649) (xy 431.079658 -12.984402) (xy 431.071292 -12.904844)
			(xy 431.070766 -12.864846) (xy 431.070766 -12.864338) (xy 431.071539 -12.816579) (xy 431.083509 -12.721812)
			(xy 431.094642 -12.675362) (xy 431.097165 -12.663039) (xy 431.091145 -12.638645) (xy 431.083212 -12.62888)
			(xy 431.065086 -12.607791) (xy 431.034497 -12.561353) (xy 431.010971 -12.510968) (xy 430.995005 -12.457702)
			(xy 430.986939 -12.402684) (xy 430.986438 -12.37488) (xy 387.986471 -12.37488) (xy 387.972758 -12.387955)
			(xy 387.845981 -12.497807) (xy 387.714121 -12.601501) (xy 387.577476 -12.698805) (xy 387.436355 -12.789496)
			(xy 387.29108 -12.873369) (xy 387.141978 -12.950235) (xy 386.989387 -13.01992) (xy 386.833654 -13.082265)
			(xy 386.675131 -13.137129) (xy 386.514176 -13.184388) (xy 386.351155 -13.223935) (xy 386.186437 -13.255681)
			(xy 386.020395 -13.279553) (xy 385.853406 -13.295497) (xy 385.685847 -13.303478) (xy 385.601972 -13.304012)
			(xy 260.800088 -13.304012) (xy 260.768924 -13.304522) (xy 260.707128 -13.31266) (xy 260.646924 -13.328793)
			(xy 260.58934 -13.352646) (xy 260.535363 -13.383812) (xy 260.485915 -13.421756) (xy 260.441843 -13.46583)
			(xy 260.403901 -13.51528) (xy 260.372737 -13.569258) (xy 260.348886 -13.626843) (xy 260.332756 -13.687048)
			(xy 260.324621 -13.748844) (xy 260.324092 -13.780008) (xy 260.324092 -17.137634) (xy 310.13197 -17.137634)
			(xy 310.136013 -17.041183) (xy 310.148112 -16.945408) (xy 310.168183 -16.850982) (xy 310.196085 -16.758566)
			(xy 310.231622 -16.668809) (xy 310.274545 -16.582341) (xy 310.324553 -16.499767) (xy 310.381296 -16.421668)
			(xy 310.444374 -16.348591) (xy 310.513347 -16.281048) (xy 310.587729 -16.219514) (xy 310.666999 -16.164419)
			(xy 310.750602 -16.116151) (xy 310.83795 -16.075048) (xy 310.928432 -16.041399) (xy 311.021411 -16.015438)
			(xy 311.116237 -15.997349) (xy 311.212245 -15.987258) (xy 311.308759 -15.985237) (xy 311.405105 -15.991298)
			(xy 311.500605 -16.005401) (xy 311.59459 -16.027445) (xy 311.686402 -16.057276) (xy 311.775395 -16.094685)
			(xy 311.860945 -16.13941) (xy 311.942453 -16.191136) (xy 312.019347 -16.249502) (xy 312.091087 -16.314097)
			(xy 312.15717 -16.384469) (xy 312.217133 -16.460123) (xy 312.270556 -16.54053) (xy 312.317062 -16.625125)
			(xy 312.356327 -16.713315) (xy 312.388074 -16.804481) (xy 312.412082 -16.897985) (xy 312.428181 -16.993169)
			(xy 312.436259 -17.089366) (xy 312.436764 -17.137634) (xy 312.436259 -17.185902) (xy 312.428181 -17.282099)
			(xy 312.412082 -17.377283) (xy 312.388074 -17.470787) (xy 312.356327 -17.561953) (xy 312.321724 -17.639671)
			(xy 388.966684 -17.639671) (xy 388.966684 -17.585129) (xy 388.974446 -17.531143) (xy 388.989811 -17.478811)
			(xy 389.012467 -17.429198) (xy 389.041953 -17.383314) (xy 389.077668 -17.342093) (xy 389.118885 -17.306374)
			(xy 389.164767 -17.276884) (xy 389.214377 -17.254224) (xy 389.266708 -17.238854) (xy 389.320693 -17.231087)
			(xy 389.347964 -17.230598) (xy 389.37184 -17.23136) (xy 389.389578 -17.201218) (xy 389.429774 -17.143978)
			(xy 389.452104 -17.11706) (xy 389.459422 -17.107371) (xy 389.465005 -17.083781) (xy 389.462772 -17.071848)
			(xy 389.457447 -17.04917) (xy 389.451718 -17.002938) (xy 389.451342 -16.979646) (xy 389.451342 -16.979138)
			(xy 389.451837 -16.951868) (xy 389.459594 -16.897882) (xy 389.474956 -16.845549) (xy 389.497609 -16.795936)
			(xy 389.527093 -16.750052) (xy 389.562807 -16.708831) (xy 389.604025 -16.673113) (xy 389.649906 -16.643625)
			(xy 389.699518 -16.620967) (xy 389.751849 -16.605601) (xy 389.805834 -16.597839) (xy 389.833104 -16.597376)
			(xy 389.861805 -16.597968) (xy 389.918558 -16.606576) (xy 389.973383 -16.623581) (xy 390.025046 -16.648601)
			(xy 390.072381 -16.681071) (xy 390.114323 -16.720262) (xy 390.149927 -16.765288) (xy 390.17839 -16.815137)
			(xy 390.189212 -16.841724) (xy 390.19422 -16.852833) (xy 390.212399 -16.869011) (xy 390.22401 -16.872712)
			(xy 390.261734 -16.88292) (xy 390.335057 -16.909977) (xy 390.405232 -16.944382) (xy 390.43864 -16.96466)
			(xy 390.446896 -16.969374) (xy 390.465564 -16.972901) (xy 390.484232 -16.969374) (xy 390.492488 -16.96466)
			(xy 390.525896 -16.94438) (xy 390.59607 -16.909973) (xy 390.66939 -16.882908) (xy 390.707118 -16.872712)
			(xy 390.718728 -16.86901) (xy 390.736902 -16.85283) (xy 390.741916 -16.841724) (xy 390.75273 -16.815127)
			(xy 390.781173 -16.765256) (xy 390.816766 -16.720208) (xy 390.858705 -16.681) (xy 390.906045 -16.648517)
			(xy 390.957716 -16.623492) (xy 391.012553 -16.606489) (xy 391.069318 -16.597892) (xy 391.098024 -16.597376)
			(xy 391.125297 -16.597779) (xy 391.179288 -16.605546) (xy 391.231624 -16.620917) (xy 391.28124 -16.64358)
			(xy 391.327126 -16.673074) (xy 391.368346 -16.708798) (xy 391.404063 -16.750024) (xy 391.43355 -16.795914)
			(xy 391.456205 -16.845534) (xy 391.471568 -16.897872) (xy 391.479325 -16.951865) (xy 391.479786 -16.979138)
			(xy 391.479786 -16.979646) (xy 391.479408 -17.002938) (xy 391.473673 -17.049168) (xy 391.468356 -17.071848)
			(xy 391.46608 -17.083783) (xy 391.471658 -17.107396) (xy 391.479024 -17.11706) (xy 391.501353 -17.143979)
			(xy 391.54155 -17.201218) (xy 391.559288 -17.23136) (xy 391.583164 -17.230598) (xy 391.610434 -17.231139)
			(xy 391.664419 -17.238896) (xy 391.71675 -17.254258) (xy 391.766363 -17.276911) (xy 391.812246 -17.306394)
			(xy 391.853466 -17.342108) (xy 391.889184 -17.383325) (xy 391.918672 -17.429205) (xy 391.94133 -17.478816)
			(xy 391.956696 -17.531146) (xy 391.964459 -17.58513) (xy 391.964458 -17.63967) (xy 391.964458 -17.639671)
			(xy 394.554684 -17.639671) (xy 394.554684 -17.585129) (xy 394.562446 -17.531143) (xy 394.577811 -17.478811)
			(xy 394.600467 -17.429198) (xy 394.629953 -17.383314) (xy 394.665668 -17.342093) (xy 394.706885 -17.306374)
			(xy 394.752767 -17.276884) (xy 394.802377 -17.254224) (xy 394.854708 -17.238854) (xy 394.908693 -17.231087)
			(xy 394.935964 -17.230598) (xy 394.95984 -17.23136) (xy 394.977578 -17.201218) (xy 395.017774 -17.143978)
			(xy 395.040104 -17.11706) (xy 395.047422 -17.107371) (xy 395.053005 -17.083781) (xy 395.050772 -17.071848)
			(xy 395.045447 -17.04917) (xy 395.039718 -17.002938) (xy 395.039342 -16.979646) (xy 395.039342 -16.979138)
			(xy 395.039837 -16.951868) (xy 395.047594 -16.897882) (xy 395.062956 -16.845549) (xy 395.085609 -16.795936)
			(xy 395.115093 -16.750052) (xy 395.150807 -16.708831) (xy 395.192025 -16.673113) (xy 395.237906 -16.643625)
			(xy 395.287518 -16.620967) (xy 395.339849 -16.605601) (xy 395.393834 -16.597839) (xy 395.421104 -16.597376)
			(xy 395.449805 -16.597968) (xy 395.506558 -16.606576) (xy 395.561383 -16.623581) (xy 395.613046 -16.648601)
			(xy 395.660381 -16.681071) (xy 395.702323 -16.720262) (xy 395.737927 -16.765288) (xy 395.76639 -16.815137)
			(xy 395.777212 -16.841724) (xy 395.78222 -16.852833) (xy 395.800399 -16.869011) (xy 395.81201 -16.872712)
			(xy 395.849734 -16.88292) (xy 395.923057 -16.909977) (xy 395.993232 -16.944382) (xy 396.02664 -16.96466)
			(xy 396.034896 -16.969374) (xy 396.053564 -16.972901) (xy 396.072232 -16.969374) (xy 396.080488 -16.96466)
			(xy 396.113896 -16.94438) (xy 396.18407 -16.909973) (xy 396.25739 -16.882908) (xy 396.295118 -16.872712)
			(xy 396.306728 -16.86901) (xy 396.324902 -16.85283) (xy 396.329916 -16.841724) (xy 396.34073 -16.815127)
			(xy 396.369173 -16.765256) (xy 396.404766 -16.720208) (xy 396.446705 -16.681) (xy 396.494045 -16.648517)
			(xy 396.545716 -16.623492) (xy 396.600553 -16.606489) (xy 396.657318 -16.597892) (xy 396.686024 -16.597376)
			(xy 396.713297 -16.597779) (xy 396.767288 -16.605546) (xy 396.819624 -16.620917) (xy 396.86924 -16.64358)
			(xy 396.915126 -16.673074) (xy 396.956346 -16.708798) (xy 396.992063 -16.750024) (xy 397.02155 -16.795914)
			(xy 397.044205 -16.845534) (xy 397.059568 -16.897872) (xy 397.067325 -16.951865) (xy 397.067786 -16.979138)
			(xy 397.067786 -16.979646) (xy 397.067408 -17.002938) (xy 397.061673 -17.049168) (xy 397.056356 -17.071848)
			(xy 397.05408 -17.083783) (xy 397.059658 -17.107396) (xy 397.067024 -17.11706) (xy 397.089353 -17.143979)
			(xy 397.12955 -17.201218) (xy 397.147288 -17.23136) (xy 397.171164 -17.230598) (xy 397.198434 -17.231139)
			(xy 397.252419 -17.238896) (xy 397.30475 -17.254258) (xy 397.354363 -17.276911) (xy 397.400246 -17.306394)
			(xy 397.441466 -17.342108) (xy 397.477184 -17.383325) (xy 397.506672 -17.429205) (xy 397.52933 -17.478816)
			(xy 397.544696 -17.531146) (xy 397.552459 -17.58513) (xy 397.552458 -17.63967) (xy 397.552458 -17.639671)
			(xy 400.142684 -17.639671) (xy 400.142684 -17.585129) (xy 400.150446 -17.531143) (xy 400.165811 -17.478811)
			(xy 400.188467 -17.429198) (xy 400.217953 -17.383314) (xy 400.253668 -17.342093) (xy 400.294885 -17.306374)
			(xy 400.340767 -17.276884) (xy 400.390377 -17.254224) (xy 400.442708 -17.238854) (xy 400.496693 -17.231087)
			(xy 400.523964 -17.230598) (xy 400.54784 -17.23136) (xy 400.565578 -17.201218) (xy 400.605774 -17.143978)
			(xy 400.628104 -17.11706) (xy 400.635422 -17.107371) (xy 400.641005 -17.083781) (xy 400.638772 -17.071848)
			(xy 400.633447 -17.04917) (xy 400.627718 -17.002938) (xy 400.627342 -16.979646) (xy 400.627342 -16.979138)
			(xy 400.627837 -16.951868) (xy 400.635594 -16.897882) (xy 400.650956 -16.845549) (xy 400.673609 -16.795936)
			(xy 400.703093 -16.750052) (xy 400.738807 -16.708831) (xy 400.780025 -16.673113) (xy 400.825906 -16.643625)
			(xy 400.875518 -16.620967) (xy 400.927849 -16.605601) (xy 400.981834 -16.597839) (xy 401.009104 -16.597376)
			(xy 401.037805 -16.597968) (xy 401.094558 -16.606576) (xy 401.149383 -16.623581) (xy 401.201046 -16.648601)
			(xy 401.248381 -16.681071) (xy 401.290323 -16.720262) (xy 401.325927 -16.765288) (xy 401.35439 -16.815137)
			(xy 401.365212 -16.841724) (xy 401.37022 -16.852833) (xy 401.388399 -16.869011) (xy 401.40001 -16.872712)
			(xy 401.437734 -16.88292) (xy 401.511057 -16.909977) (xy 401.581232 -16.944382) (xy 401.61464 -16.96466)
			(xy 401.622896 -16.969374) (xy 401.641564 -16.972901) (xy 401.660232 -16.969374) (xy 401.668488 -16.96466)
			(xy 401.701896 -16.94438) (xy 401.77207 -16.909973) (xy 401.84539 -16.882908) (xy 401.883118 -16.872712)
			(xy 401.894728 -16.86901) (xy 401.912902 -16.85283) (xy 401.917916 -16.841724) (xy 401.92873 -16.815127)
			(xy 401.957173 -16.765256) (xy 401.992766 -16.720208) (xy 402.034705 -16.681) (xy 402.082045 -16.648517)
			(xy 402.133716 -16.623492) (xy 402.188553 -16.606489) (xy 402.245318 -16.597892) (xy 402.274024 -16.597376)
			(xy 402.301297 -16.597779) (xy 402.355288 -16.605546) (xy 402.407624 -16.620917) (xy 402.45724 -16.64358)
			(xy 402.503126 -16.673074) (xy 402.544346 -16.708798) (xy 402.580063 -16.750024) (xy 402.60955 -16.795914)
			(xy 402.632205 -16.845534) (xy 402.647568 -16.897872) (xy 402.655325 -16.951865) (xy 402.655786 -16.979138)
			(xy 402.655786 -16.979646) (xy 402.655408 -17.002938) (xy 402.649673 -17.049168) (xy 402.644356 -17.071848)
			(xy 402.64208 -17.083783) (xy 402.647658 -17.107396) (xy 402.655024 -17.11706) (xy 402.677353 -17.143979)
			(xy 402.71755 -17.201218) (xy 402.735288 -17.23136) (xy 402.759164 -17.230598) (xy 402.786434 -17.231139)
			(xy 402.840419 -17.238896) (xy 402.89275 -17.254258) (xy 402.942363 -17.276911) (xy 402.988246 -17.306394)
			(xy 403.029466 -17.342108) (xy 403.065184 -17.383325) (xy 403.094672 -17.429205) (xy 403.11733 -17.478816)
			(xy 403.132696 -17.531146) (xy 403.140459 -17.58513) (xy 403.140458 -17.63967) (xy 403.140358 -17.640366)
			(xy 405.730746 -17.640366) (xy 405.730746 -17.585834) (xy 405.738507 -17.531857) (xy 405.753869 -17.479533)
			(xy 405.776521 -17.429928) (xy 405.806002 -17.384051) (xy 405.841712 -17.342837) (xy 405.882923 -17.307124)
			(xy 405.928796 -17.277639) (xy 405.978399 -17.254982) (xy 406.030721 -17.239614) (xy 406.084698 -17.231849)
			(xy 406.111964 -17.23136) (xy 406.134824 -17.232122) (xy 406.152721 -17.201764) (xy 406.193299 -17.14414)
			(xy 406.21585 -17.11706) (xy 406.223163 -17.107368) (xy 406.228751 -17.08378) (xy 406.226518 -17.071848)
			(xy 406.221292 -17.04935) (xy 406.215691 -17.003502) (xy 406.215342 -16.980408) (xy 406.215342 -16.9799)
			(xy 406.215801 -16.952629) (xy 406.223564 -16.898642) (xy 406.23893 -16.846309) (xy 406.261588 -16.796695)
			(xy 406.291076 -16.750811) (xy 406.326794 -16.709591) (xy 406.368015 -16.673874) (xy 406.413899 -16.644386)
			(xy 406.463512 -16.621729) (xy 406.515846 -16.606363) (xy 406.569833 -16.598601) (xy 406.597104 -16.598138)
			(xy 406.625832 -16.598652) (xy 406.682636 -16.607283) (xy 406.737508 -16.62432) (xy 406.789212 -16.649379)
			(xy 406.836581 -16.681896) (xy 406.87855 -16.721137) (xy 406.914171 -16.766218) (xy 406.942643 -16.816123)
			(xy 406.953466 -16.84274) (xy 406.958491 -16.85384) (xy 406.976658 -16.87002) (xy 406.988264 -16.873728)
			(xy 407.02577 -16.883926) (xy 407.098656 -16.910938) (xy 407.168414 -16.945227) (xy 407.201624 -16.965422)
			(xy 407.20988 -16.970136) (xy 407.228548 -16.973663) (xy 407.247216 -16.970136) (xy 407.255472 -16.965422)
			(xy 407.289022 -16.945008) (xy 407.359518 -16.910385) (xy 407.4332 -16.883193) (xy 407.471118 -16.872966)
			(xy 407.482685 -16.869299) (xy 407.500848 -16.853258) (xy 407.505916 -16.842232) (xy 407.516699 -16.815636)
			(xy 407.545184 -16.765813) (xy 407.580805 -16.720814) (xy 407.622758 -16.681652) (xy 407.670099 -16.64921)
			(xy 407.721762 -16.624217) (xy 407.776583 -16.607237) (xy 407.833329 -16.598652) (xy 407.862024 -16.598138)
			(xy 407.889294 -16.598602) (xy 407.943278 -16.606367) (xy 407.995608 -16.621735) (xy 408.045219 -16.644394)
			(xy 408.091099 -16.673883) (xy 408.132317 -16.7096) (xy 408.168032 -16.75082) (xy 408.197517 -16.796703)
			(xy 408.220173 -16.846314) (xy 408.235538 -16.898645) (xy 408.2433 -16.95263) (xy 408.243786 -16.9799)
			(xy 408.243425 -17.003518) (xy 408.237561 -17.05039) (xy 408.232102 -17.073372) (xy 408.229792 -17.085344)
			(xy 408.235211 -17.109077) (xy 408.242516 -17.118838) (xy 408.264678 -17.145528) (xy 408.304615 -17.20226)
			(xy 408.322272 -17.232122) (xy 408.347164 -17.23136) (xy 408.374438 -17.231777) (xy 408.428432 -17.239536)
			(xy 408.480772 -17.2549) (xy 408.530393 -17.277556) (xy 408.576284 -17.307045) (xy 408.61751 -17.342764)
			(xy 408.653234 -17.383988) (xy 408.682726 -17.429876) (xy 408.705388 -17.479494) (xy 408.720757 -17.531833)
			(xy 408.72852 -17.585826) (xy 408.72852 -17.640372) (xy 411.317624 -17.640372) (xy 411.317624 -17.585828)
			(xy 411.325387 -17.53184) (xy 411.340754 -17.479507) (xy 411.363414 -17.429893) (xy 411.392904 -17.38401)
			(xy 411.428625 -17.342791) (xy 411.469849 -17.307076) (xy 411.515736 -17.277591) (xy 411.565352 -17.254938)
			(xy 411.617687 -17.239576) (xy 411.671676 -17.23182) (xy 411.698948 -17.23136) (xy 411.722824 -17.232122)
			(xy 411.740721 -17.201764) (xy 411.781299 -17.14414) (xy 411.80385 -17.11706) (xy 411.811163 -17.107368)
			(xy 411.816751 -17.08378) (xy 411.814518 -17.071848) (xy 411.809292 -17.04935) (xy 411.803691 -17.003502)
			(xy 411.803342 -16.980408) (xy 411.803342 -16.9799) (xy 411.803801 -16.952629) (xy 411.811564 -16.898642)
			(xy 411.82693 -16.846309) (xy 411.849588 -16.796695) (xy 411.879076 -16.750811) (xy 411.914794 -16.709591)
			(xy 411.956015 -16.673874) (xy 412.001899 -16.644386) (xy 412.051512 -16.621729) (xy 412.103846 -16.606363)
			(xy 412.157833 -16.598601) (xy 412.185104 -16.598138) (xy 412.213832 -16.598652) (xy 412.270636 -16.607283)
			(xy 412.325508 -16.62432) (xy 412.377212 -16.649379) (xy 412.424581 -16.681896) (xy 412.46655 -16.721137)
			(xy 412.502171 -16.766218) (xy 412.530643 -16.816123) (xy 412.541466 -16.84274) (xy 412.546491 -16.85384)
			(xy 412.564658 -16.87002) (xy 412.576264 -16.873728) (xy 412.61377 -16.883926) (xy 412.686656 -16.910938)
			(xy 412.756414 -16.945227) (xy 412.789624 -16.965422) (xy 412.79788 -16.970136) (xy 412.816548 -16.973663)
			(xy 412.835216 -16.970136) (xy 412.843472 -16.965422) (xy 412.877022 -16.945008) (xy 412.947518 -16.910385)
			(xy 413.0212 -16.883193) (xy 413.059118 -16.872966) (xy 413.070685 -16.869299) (xy 413.088848 -16.853258)
			(xy 413.093916 -16.842232) (xy 413.104699 -16.815636) (xy 413.133184 -16.765813) (xy 413.168805 -16.720814)
			(xy 413.210758 -16.681652) (xy 413.258099 -16.64921) (xy 413.309762 -16.624217) (xy 413.364583 -16.607237)
			(xy 413.421329 -16.598652) (xy 413.450024 -16.598138) (xy 413.477294 -16.598602) (xy 413.531278 -16.606367)
			(xy 413.583608 -16.621735) (xy 413.633219 -16.644394) (xy 413.679099 -16.673883) (xy 413.720317 -16.7096)
			(xy 413.756032 -16.75082) (xy 413.785517 -16.796703) (xy 413.808173 -16.846314) (xy 413.823538 -16.898645)
			(xy 413.8313 -16.95263) (xy 413.831786 -16.9799) (xy 413.831425 -17.003518) (xy 413.825561 -17.05039)
			(xy 413.820102 -17.073372) (xy 413.817792 -17.085344) (xy 413.823211 -17.109077) (xy 413.830516 -17.118838)
			(xy 413.852678 -17.145528) (xy 413.892615 -17.20226) (xy 413.910272 -17.232122) (xy 413.934148 -17.23136)
			(xy 413.961417 -17.231806) (xy 414.015398 -17.239573) (xy 414.067725 -17.254944) (xy 414.117332 -17.277604)
			(xy 414.16321 -17.307093) (xy 414.204424 -17.34281) (xy 414.240136 -17.384029) (xy 414.269619 -17.42991)
			(xy 414.292273 -17.47952) (xy 414.307637 -17.531849) (xy 414.315398 -17.585831) (xy 414.315398 -17.639671)
			(xy 417.212484 -17.639671) (xy 417.212484 -17.585129) (xy 417.220246 -17.531141) (xy 417.235612 -17.478808)
			(xy 417.258269 -17.429194) (xy 417.287757 -17.383309) (xy 417.323473 -17.342088) (xy 417.364693 -17.306369)
			(xy 417.410576 -17.276879) (xy 417.460189 -17.254219) (xy 417.512522 -17.238851) (xy 417.566509 -17.231086)
			(xy 417.59378 -17.230598) (xy 417.617656 -17.23136) (xy 417.635393 -17.201217) (xy 417.67559 -17.143978)
			(xy 417.69792 -17.11706) (xy 417.705239 -17.107372) (xy 417.71082 -17.083781) (xy 417.708588 -17.071848)
			(xy 417.703263 -17.04917) (xy 417.697534 -17.002938) (xy 417.697158 -16.979646) (xy 417.697158 -16.979138)
			(xy 417.697637 -16.951867) (xy 417.705394 -16.89788) (xy 417.720757 -16.845546) (xy 417.743411 -16.795932)
			(xy 417.772897 -16.750047) (xy 417.808613 -16.708826) (xy 417.849832 -16.673108) (xy 417.895716 -16.64362)
			(xy 417.945329 -16.620963) (xy 417.997662 -16.605598) (xy 418.051649 -16.597838) (xy 418.07892 -16.597376)
			(xy 418.107621 -16.597954) (xy 418.164375 -16.606564) (xy 418.219201 -16.623572) (xy 418.270863 -16.648594)
			(xy 418.318199 -16.681066) (xy 418.36014 -16.720258) (xy 418.395743 -16.765286) (xy 418.424206 -16.815136)
			(xy 418.435028 -16.841724) (xy 418.440078 -16.852809) (xy 418.458227 -16.868996) (xy 418.469826 -16.872712)
			(xy 418.507551 -16.882916) (xy 418.580874 -16.909975) (xy 418.651048 -16.944381) (xy 418.684456 -16.96466)
			(xy 418.692712 -16.969374) (xy 418.71138 -16.972901) (xy 418.730048 -16.969374) (xy 418.738304 -16.96466)
			(xy 418.77171 -16.944377) (xy 418.841885 -16.909971) (xy 418.915206 -16.882907) (xy 418.952934 -16.872712)
			(xy 418.964547 -16.869017) (xy 418.982719 -16.852832) (xy 418.987732 -16.841724) (xy 418.998533 -16.815122)
			(xy 419.026977 -16.76525) (xy 419.062572 -16.720202) (xy 419.104513 -16.680994) (xy 419.151855 -16.648511)
			(xy 419.203528 -16.623487) (xy 419.258367 -16.606486) (xy 419.315133 -16.597891) (xy 419.34384 -16.597376)
			(xy 419.371112 -16.597787) (xy 419.4251 -16.605555) (xy 419.477434 -16.620928) (xy 419.527046 -16.643591)
			(xy 419.572929 -16.673085) (xy 419.614147 -16.708808) (xy 419.649862 -16.750034) (xy 419.679346 -16.795922)
			(xy 419.701999 -16.84554) (xy 419.717361 -16.897876) (xy 419.725118 -16.951866) (xy 419.725602 -16.979138)
			(xy 419.725602 -16.979646) (xy 419.725223 -17.002938) (xy 419.719489 -17.049168) (xy 419.714172 -17.071848)
			(xy 419.711892 -17.083783) (xy 419.717472 -17.107396) (xy 419.72484 -17.11706) (xy 419.74717 -17.143978)
			(xy 419.787367 -17.201217) (xy 419.805104 -17.23136) (xy 419.82898 -17.230598) (xy 419.856249 -17.23114)
			(xy 419.910232 -17.238899) (xy 419.962562 -17.254262) (xy 420.012173 -17.276916) (xy 420.058054 -17.3064)
			(xy 420.099272 -17.342114) (xy 420.134988 -17.38333) (xy 420.164474 -17.42921) (xy 420.187131 -17.478819)
			(xy 420.202497 -17.531148) (xy 420.210259 -17.585131) (xy 420.210259 -17.639669) (xy 420.210259 -17.639671)
			(xy 422.800484 -17.639671) (xy 422.800484 -17.585129) (xy 422.808246 -17.531141) (xy 422.823612 -17.478808)
			(xy 422.846269 -17.429194) (xy 422.875757 -17.383309) (xy 422.911473 -17.342088) (xy 422.952693 -17.306369)
			(xy 422.998576 -17.276879) (xy 423.048189 -17.254219) (xy 423.100522 -17.238851) (xy 423.154509 -17.231086)
			(xy 423.18178 -17.230598) (xy 423.205656 -17.23136) (xy 423.223393 -17.201217) (xy 423.26359 -17.143978)
			(xy 423.28592 -17.11706) (xy 423.293239 -17.107372) (xy 423.29882 -17.083781) (xy 423.296588 -17.071848)
			(xy 423.291263 -17.04917) (xy 423.285534 -17.002938) (xy 423.285158 -16.979646) (xy 423.285158 -16.979138)
			(xy 423.285637 -16.951867) (xy 423.293394 -16.89788) (xy 423.308757 -16.845546) (xy 423.331411 -16.795932)
			(xy 423.360897 -16.750047) (xy 423.396613 -16.708826) (xy 423.437832 -16.673108) (xy 423.483716 -16.64362)
			(xy 423.533329 -16.620963) (xy 423.585662 -16.605598) (xy 423.639649 -16.597838) (xy 423.66692 -16.597376)
			(xy 423.695621 -16.597954) (xy 423.752375 -16.606564) (xy 423.807201 -16.623572) (xy 423.858863 -16.648594)
			(xy 423.906199 -16.681066) (xy 423.94814 -16.720258) (xy 423.983743 -16.765286) (xy 424.012206 -16.815136)
			(xy 424.023028 -16.841724) (xy 424.028078 -16.852809) (xy 424.046227 -16.868996) (xy 424.057826 -16.872712)
			(xy 424.095551 -16.882916) (xy 424.168874 -16.909975) (xy 424.239048 -16.944381) (xy 424.272456 -16.96466)
			(xy 424.280712 -16.969374) (xy 424.29938 -16.972901) (xy 424.318048 -16.969374) (xy 424.326304 -16.96466)
			(xy 424.35971 -16.944377) (xy 424.429885 -16.909971) (xy 424.503206 -16.882907) (xy 424.540934 -16.872712)
			(xy 424.552547 -16.869017) (xy 424.570719 -16.852832) (xy 424.575732 -16.841724) (xy 424.586533 -16.815122)
			(xy 424.614977 -16.76525) (xy 424.650572 -16.720202) (xy 424.692513 -16.680994) (xy 424.739855 -16.648511)
			(xy 424.791528 -16.623487) (xy 424.846367 -16.606486) (xy 424.903133 -16.597891) (xy 424.93184 -16.597376)
			(xy 424.959112 -16.597787) (xy 425.0131 -16.605555) (xy 425.065434 -16.620928) (xy 425.115046 -16.643591)
			(xy 425.160929 -16.673085) (xy 425.202147 -16.708808) (xy 425.237862 -16.750034) (xy 425.267346 -16.795922)
			(xy 425.289999 -16.84554) (xy 425.305361 -16.897876) (xy 425.313118 -16.951866) (xy 425.313602 -16.979138)
			(xy 425.313602 -16.979646) (xy 425.313223 -17.002938) (xy 425.307489 -17.049168) (xy 425.302172 -17.071848)
			(xy 425.299892 -17.083783) (xy 425.305472 -17.107396) (xy 425.31284 -17.11706) (xy 425.33517 -17.143978)
			(xy 425.375367 -17.201217) (xy 425.393104 -17.23136) (xy 425.41698 -17.230598) (xy 425.444249 -17.23114)
			(xy 425.498232 -17.238899) (xy 425.550562 -17.254262) (xy 425.600173 -17.276916) (xy 425.646054 -17.3064)
			(xy 425.687272 -17.342114) (xy 425.722988 -17.38333) (xy 425.752474 -17.42921) (xy 425.775131 -17.478819)
			(xy 425.790497 -17.531148) (xy 425.798259 -17.585131) (xy 425.798259 -17.639669) (xy 425.798158 -17.640368)
			(xy 428.421546 -17.640368) (xy 428.421546 -17.585832) (xy 428.429308 -17.531852) (xy 428.444672 -17.479525)
			(xy 428.467327 -17.429918) (xy 428.496811 -17.38404) (xy 428.532524 -17.342824) (xy 428.57374 -17.307111)
			(xy 428.619618 -17.277627) (xy 428.669225 -17.254972) (xy 428.721552 -17.239608) (xy 428.775532 -17.231846)
			(xy 428.8028 -17.23136) (xy 428.826676 -17.232122) (xy 428.844559 -17.201755) (xy 428.88514 -17.144132)
			(xy 428.907702 -17.11706) (xy 428.91502 -17.107371) (xy 428.920603 -17.083781) (xy 428.91837 -17.071848)
			(xy 428.913145 -17.04935) (xy 428.907543 -17.003502) (xy 428.907194 -16.980408) (xy 428.907194 -16.9799)
			(xy 428.907724 -16.952633) (xy 428.915485 -16.898653) (xy 428.930848 -16.846327) (xy 428.953501 -16.79672)
			(xy 428.982983 -16.750841) (xy 429.018693 -16.709624) (xy 429.059906 -16.673909) (xy 429.105781 -16.644422)
			(xy 429.155386 -16.621763) (xy 429.20771 -16.606394) (xy 429.261689 -16.598627) (xy 429.288956 -16.598138)
			(xy 429.317682 -16.598693) (xy 429.374485 -16.607317) (xy 429.429356 -16.624348) (xy 429.481059 -16.649401)
			(xy 429.528429 -16.681911) (xy 429.570399 -16.721147) (xy 429.606021 -16.766224) (xy 429.634495 -16.816125)
			(xy 429.645318 -16.84274) (xy 429.650317 -16.853854) (xy 429.668503 -16.870029) (xy 429.680116 -16.873728)
			(xy 429.717626 -16.883914) (xy 429.79051 -16.910931) (xy 429.860267 -16.945225) (xy 429.893476 -16.965422)
			(xy 429.901732 -16.970136) (xy 429.9204 -16.973663) (xy 429.939068 -16.970136) (xy 429.947324 -16.965422)
			(xy 429.98088 -16.945017) (xy 430.051374 -16.910391) (xy 430.125053 -16.883195) (xy 430.16297 -16.872966)
			(xy 430.174529 -16.869277) (xy 430.192696 -16.853252) (xy 430.197768 -16.842232) (xy 430.208591 -16.815653)
			(xy 430.237072 -16.765832) (xy 430.272686 -16.720834) (xy 430.314634 -16.681672) (xy 430.361969 -16.649227)
			(xy 430.413626 -16.624231) (xy 430.468442 -16.607247) (xy 430.525183 -16.598656) (xy 430.553876 -16.598138)
			(xy 430.581146 -16.598624) (xy 430.635132 -16.606383) (xy 430.687465 -16.621746) (xy 430.737078 -16.644401)
			(xy 430.782962 -16.673886) (xy 430.824182 -16.709601) (xy 430.8599 -16.750819) (xy 430.889388 -16.796701)
			(xy 430.912046 -16.846313) (xy 430.927412 -16.898644) (xy 430.935174 -16.95263) (xy 430.935638 -16.9799)
			(xy 430.935278 -17.003518) (xy 430.929413 -17.05039) (xy 430.923954 -17.073372) (xy 430.921655 -17.085345)
			(xy 430.927069 -17.109076) (xy 430.934368 -17.118838) (xy 430.956527 -17.14553) (xy 430.996466 -17.202261)
			(xy 431.014124 -17.232122) (xy 431.038 -17.23136) (xy 431.065271 -17.231802) (xy 431.119258 -17.239565)
			(xy 431.17159 -17.254931) (xy 431.221203 -17.277588) (xy 431.267087 -17.307076) (xy 431.308307 -17.342793)
			(xy 431.344024 -17.384013) (xy 431.373512 -17.429897) (xy 431.396169 -17.47951) (xy 431.411535 -17.531842)
			(xy 431.419298 -17.585829) (xy 431.419298 -17.640371) (xy 431.411535 -17.694358) (xy 431.396169 -17.74669)
			(xy 431.373512 -17.796303) (xy 431.344024 -17.842187) (xy 431.308307 -17.883407) (xy 431.267087 -17.919124)
			(xy 431.221203 -17.948612) (xy 431.17159 -17.971269) (xy 431.119258 -17.986635) (xy 431.065271 -17.994398)
			(xy 431.038 -17.994884) (xy 431.014124 -17.994122) (xy 430.996418 -18.024119) (xy 430.956352 -18.081104)
			(xy 430.934114 -18.107914) (xy 430.926781 -18.117667) (xy 430.921333 -18.141411) (xy 430.9237 -18.15338)
			(xy 430.929273 -18.176604) (xy 430.935255 -18.223988) (xy 430.935638 -18.247868) (xy 430.935169 -18.275139)
			(xy 430.92741 -18.329127) (xy 430.912047 -18.381461) (xy 430.889391 -18.431076) (xy 430.859905 -18.476961)
			(xy 430.824188 -18.518182) (xy 430.782967 -18.5539) (xy 430.737083 -18.583387) (xy 430.687469 -18.606044)
			(xy 430.635135 -18.621409) (xy 430.581147 -18.629168) (xy 430.553876 -18.62963) (xy 430.525085 -18.629127)
			(xy 430.468158 -18.620463) (xy 430.413177 -18.60335) (xy 430.361389 -18.578175) (xy 430.313967 -18.54551)
			(xy 430.271988 -18.506095) (xy 430.236403 -18.460824) (xy 430.208019 -18.410723) (xy 430.19726 -18.384012)
			(xy 430.19225 -18.37279) (xy 430.173928 -18.356469) (xy 430.162208 -18.35277) (xy 430.124427 -18.342555)
			(xy 430.051011 -18.315421) (xy 429.980761 -18.280909) (xy 429.947324 -18.260568) (xy 429.939063 -18.255872)
			(xy 429.9204 -18.252364) (xy 429.901737 -18.255872) (xy 429.893476 -18.260568) (xy 429.86034 -18.280732)
			(xy 429.790747 -18.314996) (xy 429.71804 -18.342034) (xy 429.680624 -18.352262) (xy 429.669056 -18.356076)
			(xy 429.651007 -18.372368) (xy 429.64608 -18.383504) (xy 429.635294 -18.410257) (xy 429.606905 -18.460468)
			(xy 429.571291 -18.505841) (xy 429.529261 -18.545344) (xy 429.48177 -18.578079) (xy 429.429897 -18.603303)
			(xy 429.374822 -18.620442) (xy 429.317796 -18.629107) (xy 429.288956 -18.62963) (xy 429.261684 -18.629216)
			(xy 429.207696 -18.621448) (xy 429.155363 -18.606075) (xy 429.105751 -18.583412) (xy 429.059869 -18.553918)
			(xy 429.018651 -18.518195) (xy 428.982936 -18.47697) (xy 428.953452 -18.431082) (xy 428.930798 -18.381465)
			(xy 428.915436 -18.329129) (xy 428.907678 -18.27514) (xy 428.907194 -18.247868) (xy 428.907194 -18.24736)
			(xy 428.907548 -18.223941) (xy 428.913281 -18.177454) (xy 428.918624 -18.15465) (xy 428.920895 -18.14265)
			(xy 428.915341 -18.118909) (xy 428.907956 -18.109184) (xy 428.885351 -18.082101) (xy 428.844643 -18.024481)
			(xy 428.826676 -17.994122) (xy 428.8028 -17.994884) (xy 428.775532 -17.994354) (xy 428.721552 -17.986592)
			(xy 428.669225 -17.971228) (xy 428.619618 -17.948573) (xy 428.57374 -17.919089) (xy 428.532524 -17.883376)
			(xy 428.496811 -17.84216) (xy 428.467327 -17.796282) (xy 428.444672 -17.746675) (xy 428.429308 -17.694348)
			(xy 428.421546 -17.640368) (xy 425.798158 -17.640368) (xy 425.790497 -17.693652) (xy 425.775131 -17.745981)
			(xy 425.752474 -17.79559) (xy 425.722988 -17.84147) (xy 425.687272 -17.882686) (xy 425.646054 -17.9184)
			(xy 425.600173 -17.947884) (xy 425.550562 -17.970538) (xy 425.498232 -17.985901) (xy 425.444249 -17.99366)
			(xy 425.41698 -17.994122) (xy 425.393104 -17.99336) (xy 425.375243 -18.023515) (xy 425.334794 -18.080757)
			(xy 425.312332 -18.10766) (xy 425.304973 -18.117397) (xy 425.29954 -18.141154) (xy 425.301918 -18.153126)
			(xy 425.307366 -18.17611) (xy 425.31323 -18.22298) (xy 425.313602 -18.246598) (xy 425.313602 -18.247106)
			(xy 425.313081 -18.274374) (xy 425.30532 -18.328354) (xy 425.289956 -18.38068) (xy 425.267302 -18.430288)
			(xy 425.237819 -18.476167) (xy 425.202107 -18.517383) (xy 425.160894 -18.553099) (xy 425.115018 -18.582585)
			(xy 425.065412 -18.605244) (xy 425.013087 -18.620613) (xy 424.959108 -18.628379) (xy 424.93184 -18.628868)
			(xy 424.903027 -18.628325) (xy 424.846057 -18.619649) (xy 424.791035 -18.602518) (xy 424.73921 -18.577319)
			(xy 424.691755 -18.544626) (xy 424.649747 -18.505177) (xy 424.614138 -18.459869) (xy 424.585735 -18.409728)
			(xy 424.57497 -18.382996) (xy 424.569987 -18.37182) (xy 424.551822 -18.355489) (xy 424.540172 -18.351754)
			(xy 424.502575 -18.341525) (xy 424.429512 -18.314446) (xy 424.35959 -18.280059) (xy 424.326304 -18.259806)
			(xy 424.318043 -18.25511) (xy 424.29938 -18.251602) (xy 424.280717 -18.25511) (xy 424.272456 -18.259806)
			(xy 424.239163 -18.280046) (xy 424.16924 -18.314429) (xy 424.096183 -18.341523) (xy 424.058588 -18.351754)
			(xy 424.046946 -18.355502) (xy 424.028781 -18.371829) (xy 424.02379 -18.382996) (xy 424.013071 -18.409751)
			(xy 423.984681 -18.459911) (xy 423.949076 -18.505236) (xy 423.907064 -18.544694) (xy 423.859599 -18.577391)
			(xy 423.80776 -18.602583) (xy 423.752723 -18.619699) (xy 423.695739 -18.628349) (xy 423.66692 -18.628868)
			(xy 423.63965 -18.62838) (xy 423.585664 -18.620621) (xy 423.533332 -18.605257) (xy 423.48372 -18.582602)
			(xy 423.437836 -18.553117) (xy 423.396616 -18.517403) (xy 423.360898 -18.476185) (xy 423.33141 -18.430303)
			(xy 423.308752 -18.380692) (xy 423.293385 -18.328361) (xy 423.285622 -18.274376) (xy 423.285158 -18.247106)
			(xy 423.285158 -18.246598) (xy 423.285517 -18.22298) (xy 423.291383 -18.176108) (xy 423.296842 -18.153126)
			(xy 423.299143 -18.141153) (xy 423.293728 -18.117422) (xy 423.286428 -18.10766) (xy 423.263971 -18.080752)
			(xy 423.223519 -18.023513) (xy 423.205656 -17.99336) (xy 423.18178 -17.994122) (xy 423.154509 -17.993714)
			(xy 423.100522 -17.985949) (xy 423.048189 -17.970581) (xy 422.998576 -17.947921) (xy 422.952693 -17.918431)
			(xy 422.911473 -17.882712) (xy 422.875757 -17.841491) (xy 422.846269 -17.795606) (xy 422.823612 -17.745992)
			(xy 422.808246 -17.693659) (xy 422.800484 -17.639671) (xy 420.210259 -17.639671) (xy 420.202497 -17.693652)
			(xy 420.187131 -17.745981) (xy 420.164474 -17.79559) (xy 420.134988 -17.84147) (xy 420.099272 -17.882686)
			(xy 420.058054 -17.9184) (xy 420.012173 -17.947884) (xy 419.962562 -17.970538) (xy 419.910232 -17.985901)
			(xy 419.856249 -17.99366) (xy 419.82898 -17.994122) (xy 419.805104 -17.99336) (xy 419.787243 -18.023515)
			(xy 419.746794 -18.080757) (xy 419.724332 -18.10766) (xy 419.716973 -18.117397) (xy 419.71154 -18.141154)
			(xy 419.713918 -18.153126) (xy 419.719366 -18.17611) (xy 419.72523 -18.22298) (xy 419.725602 -18.246598)
			(xy 419.725602 -18.247106) (xy 419.725081 -18.274374) (xy 419.71732 -18.328354) (xy 419.701956 -18.38068)
			(xy 419.679302 -18.430288) (xy 419.649819 -18.476167) (xy 419.614107 -18.517383) (xy 419.572894 -18.553099)
			(xy 419.527018 -18.582585) (xy 419.477412 -18.605244) (xy 419.425087 -18.620613) (xy 419.371108 -18.628379)
			(xy 419.34384 -18.628868) (xy 419.315027 -18.628325) (xy 419.258057 -18.619649) (xy 419.203035 -18.602518)
			(xy 419.15121 -18.577319) (xy 419.103755 -18.544626) (xy 419.061747 -18.505177) (xy 419.026138 -18.459869)
			(xy 418.997735 -18.409728) (xy 418.98697 -18.382996) (xy 418.981987 -18.37182) (xy 418.963822 -18.355489)
			(xy 418.952172 -18.351754) (xy 418.914575 -18.341525) (xy 418.841512 -18.314446) (xy 418.77159 -18.280059)
			(xy 418.738304 -18.259806) (xy 418.730043 -18.25511) (xy 418.71138 -18.251602) (xy 418.692717 -18.25511)
			(xy 418.684456 -18.259806) (xy 418.651163 -18.280046) (xy 418.58124 -18.314429) (xy 418.508183 -18.341523)
			(xy 418.470588 -18.351754) (xy 418.458946 -18.355502) (xy 418.440781 -18.371829) (xy 418.43579 -18.382996)
			(xy 418.425071 -18.409751) (xy 418.396681 -18.459911) (xy 418.361076 -18.505236) (xy 418.319064 -18.544694)
			(xy 418.271599 -18.577391) (xy 418.21976 -18.602583) (xy 418.164723 -18.619699) (xy 418.107739 -18.628349)
			(xy 418.07892 -18.628868) (xy 418.05165 -18.62838) (xy 417.997664 -18.620621) (xy 417.945332 -18.605257)
			(xy 417.89572 -18.582602) (xy 417.849836 -18.553117) (xy 417.808616 -18.517403) (xy 417.772898 -18.476185)
			(xy 417.74341 -18.430303) (xy 417.720752 -18.380692) (xy 417.705385 -18.328361) (xy 417.697622 -18.274376)
			(xy 417.697158 -18.247106) (xy 417.697158 -18.246598) (xy 417.697517 -18.22298) (xy 417.703383 -18.176108)
			(xy 417.708842 -18.153126) (xy 417.711143 -18.141153) (xy 417.705728 -18.117422) (xy 417.698428 -18.10766)
			(xy 417.675971 -18.080752) (xy 417.635519 -18.023513) (xy 417.617656 -17.99336) (xy 417.59378 -17.994122)
			(xy 417.566509 -17.993714) (xy 417.512522 -17.985949) (xy 417.460189 -17.970581) (xy 417.410576 -17.947921)
			(xy 417.364693 -17.918431) (xy 417.323473 -17.882712) (xy 417.287757 -17.841491) (xy 417.258269 -17.795606)
			(xy 417.235612 -17.745992) (xy 417.220246 -17.693659) (xy 417.212484 -17.639671) (xy 414.315398 -17.639671)
			(xy 414.315398 -17.640369) (xy 414.307637 -17.694351) (xy 414.292273 -17.74668) (xy 414.269619 -17.79629)
			(xy 414.240136 -17.842171) (xy 414.204424 -17.88339) (xy 414.16321 -17.919107) (xy 414.117332 -17.948596)
			(xy 414.067725 -17.971256) (xy 414.015398 -17.986627) (xy 413.961417 -17.994394) (xy 413.934148 -17.994884)
			(xy 413.910272 -17.994122) (xy 413.892569 -18.024121) (xy 413.852501 -18.081105) (xy 413.830262 -18.107914)
			(xy 413.822926 -18.117664) (xy 413.817483 -18.14141) (xy 413.819848 -18.15338) (xy 413.82542 -18.176604)
			(xy 413.831403 -18.223988) (xy 413.831786 -18.247868) (xy 413.831269 -18.275137) (xy 413.823512 -18.329121)
			(xy 413.808151 -18.381451) (xy 413.785499 -18.431062) (xy 413.756017 -18.476945) (xy 413.720305 -18.518165)
			(xy 413.67909 -18.553883) (xy 413.633212 -18.583372) (xy 413.583604 -18.606031) (xy 413.531276 -18.6214)
			(xy 413.477293 -18.629165) (xy 413.450024 -18.62963) (xy 413.421234 -18.629086) (xy 413.364309 -18.620429)
			(xy 413.309329 -18.603322) (xy 413.257541 -18.578153) (xy 413.210119 -18.545494) (xy 413.16814 -18.506084)
			(xy 413.132553 -18.460818) (xy 413.104168 -18.410721) (xy 413.093408 -18.384012) (xy 413.088375 -18.372804)
			(xy 413.070069 -18.356477) (xy 413.058356 -18.35277) (xy 413.020578 -18.342544) (xy 412.947161 -18.315415)
			(xy 412.87691 -18.280907) (xy 412.843472 -18.260568) (xy 412.835211 -18.255872) (xy 412.816548 -18.252364)
			(xy 412.797885 -18.255872) (xy 412.789624 -18.260568) (xy 412.756483 -18.280722) (xy 412.686892 -18.31499)
			(xy 412.614187 -18.342032) (xy 412.576772 -18.352262) (xy 412.565195 -18.356053) (xy 412.547151 -18.372362)
			(xy 412.542228 -18.383504) (xy 412.531485 -18.410276) (xy 412.503092 -18.460489) (xy 412.467472 -18.505862)
			(xy 412.425435 -18.545364) (xy 412.377938 -18.578098) (xy 412.326059 -18.603318) (xy 412.270977 -18.620452)
			(xy 412.213946 -18.629111) (xy 412.185104 -18.62963) (xy 412.157832 -18.629195) (xy 412.103842 -18.621432)
			(xy 412.051507 -18.606065) (xy 412.001892 -18.583405) (xy 411.956006 -18.553915) (xy 411.914785 -18.518195)
			(xy 411.879068 -18.476971) (xy 411.849581 -18.431084) (xy 411.826925 -18.381467) (xy 411.811562 -18.329131)
			(xy 411.803803 -18.27514) (xy 411.803342 -18.247868) (xy 411.803342 -18.24736) (xy 411.803697 -18.223941)
			(xy 411.80943 -18.177454) (xy 411.814772 -18.15465) (xy 411.817032 -18.142649) (xy 411.811483 -18.118911)
			(xy 411.804104 -18.109184) (xy 411.781496 -18.082103) (xy 411.74079 -18.024482) (xy 411.722824 -17.994122)
			(xy 411.698948 -17.994884) (xy 411.671676 -17.99438) (xy 411.617687 -17.986624) (xy 411.565352 -17.971262)
			(xy 411.515736 -17.948609) (xy 411.469849 -17.919124) (xy 411.428625 -17.883409) (xy 411.392904 -17.84219)
			(xy 411.363414 -17.796307) (xy 411.340754 -17.746693) (xy 411.325387 -17.69436) (xy 411.317624 -17.640372)
			(xy 408.72852 -17.640372) (xy 408.72852 -17.640374) (xy 408.720757 -17.694367) (xy 408.705388 -17.746706)
			(xy 408.682726 -17.796324) (xy 408.653234 -17.842212) (xy 408.61751 -17.883436) (xy 408.576284 -17.919155)
			(xy 408.530393 -17.948644) (xy 408.480772 -17.9713) (xy 408.428432 -17.986664) (xy 408.374438 -17.994423)
			(xy 408.347164 -17.994884) (xy 408.322272 -17.994122) (xy 408.304569 -18.024121) (xy 408.264501 -18.081105)
			(xy 408.242262 -18.107914) (xy 408.234926 -18.117664) (xy 408.229483 -18.14141) (xy 408.231848 -18.15338)
			(xy 408.23742 -18.176604) (xy 408.243403 -18.223988) (xy 408.243786 -18.247868) (xy 408.243269 -18.275137)
			(xy 408.235512 -18.329121) (xy 408.220151 -18.381451) (xy 408.197499 -18.431062) (xy 408.168017 -18.476945)
			(xy 408.132305 -18.518165) (xy 408.09109 -18.553883) (xy 408.045212 -18.583372) (xy 407.995604 -18.606031)
			(xy 407.943276 -18.6214) (xy 407.889293 -18.629165) (xy 407.862024 -18.62963) (xy 407.833234 -18.629086)
			(xy 407.776309 -18.620429) (xy 407.721329 -18.603322) (xy 407.669541 -18.578153) (xy 407.622119 -18.545494)
			(xy 407.58014 -18.506084) (xy 407.544553 -18.460818) (xy 407.516168 -18.410721) (xy 407.505408 -18.384012)
			(xy 407.500375 -18.372804) (xy 407.482069 -18.356477) (xy 407.470356 -18.35277) (xy 407.432578 -18.342544)
			(xy 407.359161 -18.315415) (xy 407.28891 -18.280907) (xy 407.255472 -18.260568) (xy 407.247211 -18.255872)
			(xy 407.228548 -18.252364) (xy 407.209885 -18.255872) (xy 407.201624 -18.260568) (xy 407.168483 -18.280722)
			(xy 407.098892 -18.31499) (xy 407.026187 -18.342032) (xy 406.988772 -18.352262) (xy 406.977195 -18.356053)
			(xy 406.959151 -18.372362) (xy 406.954228 -18.383504) (xy 406.943485 -18.410276) (xy 406.915092 -18.460489)
			(xy 406.879472 -18.505862) (xy 406.837435 -18.545364) (xy 406.789938 -18.578098) (xy 406.738059 -18.603318)
			(xy 406.682977 -18.620452) (xy 406.625946 -18.629111) (xy 406.597104 -18.62963) (xy 406.569832 -18.629195)
			(xy 406.515842 -18.621432) (xy 406.463507 -18.606065) (xy 406.413892 -18.583405) (xy 406.368006 -18.553915)
			(xy 406.326785 -18.518195) (xy 406.291068 -18.476971) (xy 406.261581 -18.431084) (xy 406.238925 -18.381467)
			(xy 406.223562 -18.329131) (xy 406.215803 -18.27514) (xy 406.215342 -18.247868) (xy 406.215342 -18.24736)
			(xy 406.215697 -18.223941) (xy 406.22143 -18.177454) (xy 406.226772 -18.15465) (xy 406.229032 -18.142649)
			(xy 406.223483 -18.118911) (xy 406.216104 -18.109184) (xy 406.193496 -18.082103) (xy 406.15279 -18.024482)
			(xy 406.134824 -17.994122) (xy 406.111964 -17.994884) (xy 406.084698 -17.994351) (xy 406.030721 -17.986586)
			(xy 405.978399 -17.971218) (xy 405.928796 -17.948561) (xy 405.882923 -17.919076) (xy 405.841712 -17.883363)
			(xy 405.806002 -17.842149) (xy 405.776521 -17.796272) (xy 405.753869 -17.746667) (xy 405.738507 -17.694343)
			(xy 405.730746 -17.640366) (xy 403.140358 -17.640366) (xy 403.132696 -17.693654) (xy 403.11733 -17.745984)
			(xy 403.094672 -17.795595) (xy 403.065184 -17.841475) (xy 403.029466 -17.882692) (xy 402.988246 -17.918406)
			(xy 402.942363 -17.947889) (xy 402.89275 -17.970542) (xy 402.840419 -17.985904) (xy 402.786434 -17.993661)
			(xy 402.759164 -17.994122) (xy 402.735288 -17.99336) (xy 402.717429 -18.023516) (xy 402.676979 -18.080757)
			(xy 402.654516 -18.10766) (xy 402.647156 -18.117396) (xy 402.641724 -18.141154) (xy 402.644102 -18.153126)
			(xy 402.64955 -18.17611) (xy 402.655414 -18.22298) (xy 402.655786 -18.246598) (xy 402.655786 -18.247106)
			(xy 402.655281 -18.274374) (xy 402.647519 -18.328356) (xy 402.632154 -18.380684) (xy 402.609499 -18.430292)
			(xy 402.580015 -18.476172) (xy 402.544302 -18.517389) (xy 402.503087 -18.553104) (xy 402.457208 -18.582591)
			(xy 402.407601 -18.605248) (xy 402.355274 -18.620616) (xy 402.301292 -18.62838) (xy 402.274024 -18.628868)
			(xy 402.24521 -18.628339) (xy 402.18824 -18.619661) (xy 402.133218 -18.602527) (xy 402.081392 -18.577327)
			(xy 402.033938 -18.544631) (xy 401.99193 -18.505181) (xy 401.956321 -18.459871) (xy 401.927919 -18.409728)
			(xy 401.917154 -18.382996) (xy 401.912179 -18.371815) (xy 401.894009 -18.355486) (xy 401.882356 -18.351754)
			(xy 401.844758 -18.341528) (xy 401.771695 -18.314448) (xy 401.701773 -18.28006) (xy 401.668488 -18.259806)
			(xy 401.660227 -18.25511) (xy 401.641564 -18.251602) (xy 401.622901 -18.25511) (xy 401.61464 -18.259806)
			(xy 401.581349 -18.280049) (xy 401.511425 -18.314431) (xy 401.438368 -18.341524) (xy 401.400772 -18.351754)
			(xy 401.389128 -18.355495) (xy 401.370964 -18.371827) (xy 401.365974 -18.382996) (xy 401.355268 -18.409757)
			(xy 401.326877 -18.459918) (xy 401.29127 -18.505242) (xy 401.249256 -18.544701) (xy 401.201789 -18.577397)
			(xy 401.149948 -18.602588) (xy 401.094909 -18.619702) (xy 401.037923 -18.62835) (xy 401.009104 -18.628868)
			(xy 400.981835 -18.628372) (xy 400.927852 -18.620611) (xy 400.875523 -18.605246) (xy 400.825913 -18.582591)
			(xy 400.780033 -18.553106) (xy 400.738815 -18.517392) (xy 400.7031 -18.476175) (xy 400.673614 -18.430295)
			(xy 400.650957 -18.380686) (xy 400.635591 -18.328358) (xy 400.627829 -18.274375) (xy 400.627342 -18.247106)
			(xy 400.627342 -18.246598) (xy 400.627702 -18.22298) (xy 400.633567 -18.176108) (xy 400.639026 -18.153126)
			(xy 400.641331 -18.141153) (xy 400.635914 -18.117422) (xy 400.628612 -18.10766) (xy 400.606154 -18.080753)
			(xy 400.565703 -18.023514) (xy 400.54784 -17.99336) (xy 400.523964 -17.994122) (xy 400.496693 -17.993713)
			(xy 400.442708 -17.985946) (xy 400.390377 -17.970576) (xy 400.340767 -17.947916) (xy 400.294885 -17.918426)
			(xy 400.253668 -17.882707) (xy 400.217953 -17.841486) (xy 400.188467 -17.795602) (xy 400.165811 -17.745989)
			(xy 400.150446 -17.693657) (xy 400.142684 -17.639671) (xy 397.552458 -17.639671) (xy 397.544696 -17.693654)
			(xy 397.52933 -17.745984) (xy 397.506672 -17.795595) (xy 397.477184 -17.841475) (xy 397.441466 -17.882692)
			(xy 397.400246 -17.918406) (xy 397.354363 -17.947889) (xy 397.30475 -17.970542) (xy 397.252419 -17.985904)
			(xy 397.198434 -17.993661) (xy 397.171164 -17.994122) (xy 397.147288 -17.99336) (xy 397.129429 -18.023516)
			(xy 397.088979 -18.080757) (xy 397.066516 -18.10766) (xy 397.059156 -18.117396) (xy 397.053724 -18.141154)
			(xy 397.056102 -18.153126) (xy 397.06155 -18.17611) (xy 397.067414 -18.22298) (xy 397.067786 -18.246598)
			(xy 397.067786 -18.247106) (xy 397.067281 -18.274374) (xy 397.059519 -18.328356) (xy 397.044154 -18.380684)
			(xy 397.021499 -18.430292) (xy 396.992015 -18.476172) (xy 396.956302 -18.517389) (xy 396.915087 -18.553104)
			(xy 396.869208 -18.582591) (xy 396.819601 -18.605248) (xy 396.767274 -18.620616) (xy 396.713292 -18.62838)
			(xy 396.686024 -18.628868) (xy 396.65721 -18.628339) (xy 396.60024 -18.619661) (xy 396.545218 -18.602527)
			(xy 396.493392 -18.577327) (xy 396.445938 -18.544631) (xy 396.40393 -18.505181) (xy 396.368321 -18.459871)
			(xy 396.339919 -18.409728) (xy 396.329154 -18.382996) (xy 396.324179 -18.371815) (xy 396.306009 -18.355486)
			(xy 396.294356 -18.351754) (xy 396.256758 -18.341528) (xy 396.183695 -18.314448) (xy 396.113773 -18.28006)
			(xy 396.080488 -18.259806) (xy 396.072227 -18.25511) (xy 396.053564 -18.251602) (xy 396.034901 -18.25511)
			(xy 396.02664 -18.259806) (xy 395.993349 -18.280049) (xy 395.923425 -18.314431) (xy 395.850368 -18.341524)
			(xy 395.812772 -18.351754) (xy 395.801128 -18.355495) (xy 395.782964 -18.371827) (xy 395.777974 -18.382996)
			(xy 395.767268 -18.409757) (xy 395.738877 -18.459918) (xy 395.70327 -18.505242) (xy 395.661256 -18.544701)
			(xy 395.613789 -18.577397) (xy 395.561948 -18.602588) (xy 395.506909 -18.619702) (xy 395.449923 -18.62835)
			(xy 395.421104 -18.628868) (xy 395.393835 -18.628372) (xy 395.339852 -18.620611) (xy 395.287523 -18.605246)
			(xy 395.237913 -18.582591) (xy 395.192033 -18.553106) (xy 395.150815 -18.517392) (xy 395.1151 -18.476175)
			(xy 395.085614 -18.430295) (xy 395.062957 -18.380686) (xy 395.047591 -18.328358) (xy 395.039829 -18.274375)
			(xy 395.039342 -18.247106) (xy 395.039342 -18.246598) (xy 395.039702 -18.22298) (xy 395.045567 -18.176108)
			(xy 395.051026 -18.153126) (xy 395.053331 -18.141153) (xy 395.047914 -18.117422) (xy 395.040612 -18.10766)
			(xy 395.018154 -18.080753) (xy 394.977703 -18.023514) (xy 394.95984 -17.99336) (xy 394.935964 -17.994122)
			(xy 394.908693 -17.993713) (xy 394.854708 -17.985946) (xy 394.802377 -17.970576) (xy 394.752767 -17.947916)
			(xy 394.706885 -17.918426) (xy 394.665668 -17.882707) (xy 394.629953 -17.841486) (xy 394.600467 -17.795602)
			(xy 394.577811 -17.745989) (xy 394.562446 -17.693657) (xy 394.554684 -17.639671) (xy 391.964458 -17.639671)
			(xy 391.956696 -17.693654) (xy 391.94133 -17.745984) (xy 391.918672 -17.795595) (xy 391.889184 -17.841475)
			(xy 391.853466 -17.882692) (xy 391.812246 -17.918406) (xy 391.766363 -17.947889) (xy 391.71675 -17.970542)
			(xy 391.664419 -17.985904) (xy 391.610434 -17.993661) (xy 391.583164 -17.994122) (xy 391.559288 -17.99336)
			(xy 391.541429 -18.023516) (xy 391.500979 -18.080757) (xy 391.478516 -18.10766) (xy 391.471156 -18.117396)
			(xy 391.465724 -18.141154) (xy 391.468102 -18.153126) (xy 391.47355 -18.17611) (xy 391.479414 -18.22298)
			(xy 391.479786 -18.246598) (xy 391.479786 -18.247106) (xy 391.479281 -18.274374) (xy 391.471519 -18.328356)
			(xy 391.456154 -18.380684) (xy 391.433499 -18.430292) (xy 391.404015 -18.476172) (xy 391.368302 -18.517389)
			(xy 391.327087 -18.553104) (xy 391.281208 -18.582591) (xy 391.231601 -18.605248) (xy 391.179274 -18.620616)
			(xy 391.125292 -18.62838) (xy 391.098024 -18.628868) (xy 391.06921 -18.628339) (xy 391.01224 -18.619661)
			(xy 390.957218 -18.602527) (xy 390.905392 -18.577327) (xy 390.857938 -18.544631) (xy 390.81593 -18.505181)
			(xy 390.780321 -18.459871) (xy 390.751919 -18.409728) (xy 390.741154 -18.382996) (xy 390.736179 -18.371815)
			(xy 390.718009 -18.355486) (xy 390.706356 -18.351754) (xy 390.668758 -18.341528) (xy 390.595695 -18.314448)
			(xy 390.525773 -18.28006) (xy 390.492488 -18.259806) (xy 390.484227 -18.25511) (xy 390.465564 -18.251602)
			(xy 390.446901 -18.25511) (xy 390.43864 -18.259806) (xy 390.405349 -18.280049) (xy 390.335425 -18.314431)
			(xy 390.262368 -18.341524) (xy 390.224772 -18.351754) (xy 390.213128 -18.355495) (xy 390.194964 -18.371827)
			(xy 390.189974 -18.382996) (xy 390.179268 -18.409757) (xy 390.150877 -18.459918) (xy 390.11527 -18.505242)
			(xy 390.073256 -18.544701) (xy 390.025789 -18.577397) (xy 389.973948 -18.602588) (xy 389.918909 -18.619702)
			(xy 389.861923 -18.62835) (xy 389.833104 -18.628868) (xy 389.805835 -18.628372) (xy 389.751852 -18.620611)
			(xy 389.699523 -18.605246) (xy 389.649913 -18.582591) (xy 389.604033 -18.553106) (xy 389.562815 -18.517392)
			(xy 389.5271 -18.476175) (xy 389.497614 -18.430295) (xy 389.474957 -18.380686) (xy 389.459591 -18.328358)
			(xy 389.451829 -18.274375) (xy 389.451342 -18.247106) (xy 389.451342 -18.246598) (xy 389.451702 -18.22298)
			(xy 389.457567 -18.176108) (xy 389.463026 -18.153126) (xy 389.465331 -18.141153) (xy 389.459914 -18.117422)
			(xy 389.452612 -18.10766) (xy 389.430154 -18.080753) (xy 389.389703 -18.023514) (xy 389.37184 -17.99336)
			(xy 389.347964 -17.994122) (xy 389.320693 -17.993713) (xy 389.266708 -17.985946) (xy 389.214377 -17.970576)
			(xy 389.164767 -17.947916) (xy 389.118885 -17.918426) (xy 389.077668 -17.882707) (xy 389.041953 -17.841486)
			(xy 389.012467 -17.795602) (xy 388.989811 -17.745989) (xy 388.974446 -17.693657) (xy 388.966684 -17.639671)
			(xy 312.321724 -17.639671) (xy 312.317062 -17.650143) (xy 312.270556 -17.734738) (xy 312.217133 -17.815145)
			(xy 312.15717 -17.890799) (xy 312.091087 -17.961171) (xy 312.019347 -18.025766) (xy 311.942453 -18.084132)
			(xy 311.860945 -18.135858) (xy 311.775395 -18.180583) (xy 311.686402 -18.217992) (xy 311.59459 -18.247823)
			(xy 311.500605 -18.269867) (xy 311.405105 -18.28397) (xy 311.308759 -18.290031) (xy 311.212245 -18.28801)
			(xy 311.116237 -18.277919) (xy 311.021411 -18.25983) (xy 310.928432 -18.233869) (xy 310.83795 -18.20022)
			(xy 310.750602 -18.159117) (xy 310.666999 -18.110849) (xy 310.587729 -18.055754) (xy 310.513347 -17.99422)
			(xy 310.444374 -17.926677) (xy 310.381296 -17.8536) (xy 310.324553 -17.775501) (xy 310.274545 -17.692927)
			(xy 310.231622 -17.606459) (xy 310.196085 -17.516702) (xy 310.168183 -17.424286) (xy 310.148112 -17.32986)
			(xy 310.136013 -17.234085) (xy 310.13197 -17.137634) (xy 260.324092 -17.137634) (xy 260.324092 -19.164372)
			(xy 391.759624 -19.164372) (xy 391.759624 -19.109828) (xy 391.767387 -19.05584) (xy 391.782754 -19.003507)
			(xy 391.805414 -18.953893) (xy 391.834904 -18.90801) (xy 391.870625 -18.866791) (xy 391.911849 -18.831076)
			(xy 391.957736 -18.801591) (xy 392.007352 -18.778938) (xy 392.059687 -18.763576) (xy 392.113676 -18.75582)
			(xy 392.140948 -18.75536) (xy 392.164824 -18.756122) (xy 392.182721 -18.725764) (xy 392.223299 -18.66814)
			(xy 392.24585 -18.64106) (xy 392.253163 -18.631368) (xy 392.258751 -18.60778) (xy 392.256518 -18.595848)
			(xy 392.251292 -18.57335) (xy 392.245691 -18.527502) (xy 392.245342 -18.504408) (xy 392.245342 -18.5039)
			(xy 392.245801 -18.476629) (xy 392.253564 -18.422642) (xy 392.26893 -18.370309) (xy 392.291588 -18.320695)
			(xy 392.321076 -18.274811) (xy 392.356794 -18.233591) (xy 392.398015 -18.197874) (xy 392.443899 -18.168386)
			(xy 392.493512 -18.145729) (xy 392.545846 -18.130363) (xy 392.599833 -18.122601) (xy 392.627104 -18.122138)
			(xy 392.655832 -18.122652) (xy 392.712636 -18.131283) (xy 392.767508 -18.14832) (xy 392.819212 -18.173379)
			(xy 392.866581 -18.205896) (xy 392.90855 -18.245137) (xy 392.944171 -18.290218) (xy 392.972643 -18.340123)
			(xy 392.983466 -18.36674) (xy 392.988491 -18.37784) (xy 393.006658 -18.39402) (xy 393.018264 -18.397728)
			(xy 393.05577 -18.407926) (xy 393.128656 -18.434938) (xy 393.198414 -18.469227) (xy 393.231624 -18.489422)
			(xy 393.23988 -18.494136) (xy 393.258548 -18.497663) (xy 393.277216 -18.494136) (xy 393.285472 -18.489422)
			(xy 393.319022 -18.469008) (xy 393.389518 -18.434385) (xy 393.4632 -18.407193) (xy 393.501118 -18.396966)
			(xy 393.512685 -18.393299) (xy 393.530848 -18.377258) (xy 393.535916 -18.366232) (xy 393.546699 -18.339636)
			(xy 393.575184 -18.289813) (xy 393.610805 -18.244814) (xy 393.652758 -18.205652) (xy 393.700099 -18.17321)
			(xy 393.751762 -18.148217) (xy 393.806583 -18.131237) (xy 393.863329 -18.122652) (xy 393.892024 -18.122138)
			(xy 393.919294 -18.122602) (xy 393.973278 -18.130367) (xy 394.025608 -18.145735) (xy 394.075219 -18.168394)
			(xy 394.121099 -18.197883) (xy 394.162317 -18.2336) (xy 394.198032 -18.27482) (xy 394.227517 -18.320703)
			(xy 394.250173 -18.370314) (xy 394.265538 -18.422645) (xy 394.2733 -18.47663) (xy 394.273786 -18.5039)
			(xy 394.273425 -18.527518) (xy 394.267561 -18.57439) (xy 394.262102 -18.597372) (xy 394.259792 -18.609344)
			(xy 394.265211 -18.633077) (xy 394.272516 -18.642838) (xy 394.294678 -18.669528) (xy 394.334615 -18.72626)
			(xy 394.352272 -18.756122) (xy 394.376148 -18.75536) (xy 394.403417 -18.755806) (xy 394.457398 -18.763573)
			(xy 394.509725 -18.778944) (xy 394.559332 -18.801604) (xy 394.60521 -18.831093) (xy 394.646424 -18.86681)
			(xy 394.682136 -18.908029) (xy 394.711619 -18.95391) (xy 394.734273 -19.00352) (xy 394.749637 -19.055849)
			(xy 394.757398 -19.109831) (xy 394.757398 -19.163671) (xy 397.348684 -19.163671) (xy 397.348684 -19.109129)
			(xy 397.356446 -19.055143) (xy 397.371811 -19.002811) (xy 397.394467 -18.953198) (xy 397.423953 -18.907314)
			(xy 397.459668 -18.866093) (xy 397.500885 -18.830374) (xy 397.546767 -18.800884) (xy 397.596377 -18.778224)
			(xy 397.648708 -18.762854) (xy 397.702693 -18.755087) (xy 397.729964 -18.754598) (xy 397.75384 -18.75536)
			(xy 397.771578 -18.725218) (xy 397.811774 -18.667978) (xy 397.834104 -18.64106) (xy 397.841422 -18.631371)
			(xy 397.847005 -18.607781) (xy 397.844772 -18.595848) (xy 397.839447 -18.57317) (xy 397.833718 -18.526938)
			(xy 397.833342 -18.503646) (xy 397.833342 -18.503138) (xy 397.833837 -18.475868) (xy 397.841594 -18.421882)
			(xy 397.856956 -18.369549) (xy 397.879609 -18.319936) (xy 397.909093 -18.274052) (xy 397.944807 -18.232831)
			(xy 397.986025 -18.197113) (xy 398.031906 -18.167625) (xy 398.081518 -18.144967) (xy 398.133849 -18.129601)
			(xy 398.187834 -18.121839) (xy 398.215104 -18.121376) (xy 398.243805 -18.121968) (xy 398.300558 -18.130576)
			(xy 398.355383 -18.147581) (xy 398.407046 -18.172601) (xy 398.454381 -18.205071) (xy 398.496323 -18.244262)
			(xy 398.531927 -18.289288) (xy 398.56039 -18.339137) (xy 398.571212 -18.365724) (xy 398.57622 -18.376833)
			(xy 398.594399 -18.393011) (xy 398.60601 -18.396712) (xy 398.643734 -18.40692) (xy 398.717057 -18.433977)
			(xy 398.787232 -18.468382) (xy 398.82064 -18.48866) (xy 398.828896 -18.493374) (xy 398.847564 -18.496901)
			(xy 398.866232 -18.493374) (xy 398.874488 -18.48866) (xy 398.907896 -18.46838) (xy 398.97807 -18.433973)
			(xy 399.05139 -18.406908) (xy 399.089118 -18.396712) (xy 399.100728 -18.39301) (xy 399.118902 -18.37683)
			(xy 399.123916 -18.365724) (xy 399.13473 -18.339127) (xy 399.163173 -18.289256) (xy 399.198766 -18.244208)
			(xy 399.240705 -18.205) (xy 399.288045 -18.172517) (xy 399.339716 -18.147492) (xy 399.394553 -18.130489)
			(xy 399.451318 -18.121892) (xy 399.480024 -18.121376) (xy 399.507297 -18.121779) (xy 399.561288 -18.129546)
			(xy 399.613624 -18.144917) (xy 399.66324 -18.16758) (xy 399.709126 -18.197074) (xy 399.750346 -18.232798)
			(xy 399.786063 -18.274024) (xy 399.81555 -18.319914) (xy 399.838205 -18.369534) (xy 399.853568 -18.421872)
			(xy 399.861325 -18.475865) (xy 399.861786 -18.503138) (xy 399.861786 -18.503646) (xy 399.861408 -18.526938)
			(xy 399.855673 -18.573168) (xy 399.850356 -18.595848) (xy 399.84808 -18.607783) (xy 399.853658 -18.631396)
			(xy 399.861024 -18.64106) (xy 399.883353 -18.667979) (xy 399.92355 -18.725218) (xy 399.941288 -18.75536)
			(xy 399.965164 -18.754598) (xy 399.992434 -18.755139) (xy 400.046419 -18.762896) (xy 400.09875 -18.778258)
			(xy 400.148363 -18.800911) (xy 400.194246 -18.830394) (xy 400.235466 -18.866108) (xy 400.271184 -18.907325)
			(xy 400.300672 -18.953205) (xy 400.32333 -19.002816) (xy 400.338696 -19.055146) (xy 400.346459 -19.10913)
			(xy 400.346458 -19.16367) (xy 400.346458 -19.163671) (xy 402.936684 -19.163671) (xy 402.936684 -19.109129)
			(xy 402.944446 -19.055143) (xy 402.959811 -19.002811) (xy 402.982467 -18.953198) (xy 403.011953 -18.907314)
			(xy 403.047668 -18.866093) (xy 403.088885 -18.830374) (xy 403.134767 -18.800884) (xy 403.184377 -18.778224)
			(xy 403.236708 -18.762854) (xy 403.290693 -18.755087) (xy 403.317964 -18.754598) (xy 403.34184 -18.75536)
			(xy 403.359578 -18.725218) (xy 403.399774 -18.667978) (xy 403.422104 -18.64106) (xy 403.429422 -18.631371)
			(xy 403.435005 -18.607781) (xy 403.432772 -18.595848) (xy 403.427447 -18.57317) (xy 403.421718 -18.526938)
			(xy 403.421342 -18.503646) (xy 403.421342 -18.503138) (xy 403.421837 -18.475868) (xy 403.429594 -18.421882)
			(xy 403.444956 -18.369549) (xy 403.467609 -18.319936) (xy 403.497093 -18.274052) (xy 403.532807 -18.232831)
			(xy 403.574025 -18.197113) (xy 403.619906 -18.167625) (xy 403.669518 -18.144967) (xy 403.721849 -18.129601)
			(xy 403.775834 -18.121839) (xy 403.803104 -18.121376) (xy 403.831805 -18.121968) (xy 403.888558 -18.130576)
			(xy 403.943383 -18.147581) (xy 403.995046 -18.172601) (xy 404.042381 -18.205071) (xy 404.084323 -18.244262)
			(xy 404.119927 -18.289288) (xy 404.14839 -18.339137) (xy 404.159212 -18.365724) (xy 404.16422 -18.376833)
			(xy 404.182399 -18.393011) (xy 404.19401 -18.396712) (xy 404.231734 -18.40692) (xy 404.305057 -18.433977)
			(xy 404.375232 -18.468382) (xy 404.40864 -18.48866) (xy 404.416896 -18.493374) (xy 404.435564 -18.496901)
			(xy 404.454232 -18.493374) (xy 404.462488 -18.48866) (xy 404.495896 -18.46838) (xy 404.56607 -18.433973)
			(xy 404.63939 -18.406908) (xy 404.677118 -18.396712) (xy 404.688728 -18.39301) (xy 404.706902 -18.37683)
			(xy 404.711916 -18.365724) (xy 404.72273 -18.339127) (xy 404.751173 -18.289256) (xy 404.786766 -18.244208)
			(xy 404.828705 -18.205) (xy 404.876045 -18.172517) (xy 404.927716 -18.147492) (xy 404.982553 -18.130489)
			(xy 405.039318 -18.121892) (xy 405.068024 -18.121376) (xy 405.095297 -18.121779) (xy 405.149288 -18.129546)
			(xy 405.201624 -18.144917) (xy 405.25124 -18.16758) (xy 405.297126 -18.197074) (xy 405.338346 -18.232798)
			(xy 405.374063 -18.274024) (xy 405.40355 -18.319914) (xy 405.426205 -18.369534) (xy 405.441568 -18.421872)
			(xy 405.449325 -18.475865) (xy 405.449786 -18.503138) (xy 405.449786 -18.503646) (xy 405.449408 -18.526938)
			(xy 405.443673 -18.573168) (xy 405.438356 -18.595848) (xy 405.43608 -18.607783) (xy 405.441658 -18.631396)
			(xy 405.449024 -18.64106) (xy 405.471353 -18.667979) (xy 405.51155 -18.725218) (xy 405.529288 -18.75536)
			(xy 405.553164 -18.754598) (xy 405.580434 -18.755139) (xy 405.634419 -18.762896) (xy 405.68675 -18.778258)
			(xy 405.736363 -18.800911) (xy 405.782246 -18.830394) (xy 405.823466 -18.866108) (xy 405.859184 -18.907325)
			(xy 405.888672 -18.953205) (xy 405.91133 -19.002816) (xy 405.926696 -19.055146) (xy 405.934459 -19.10913)
			(xy 405.934458 -19.16367) (xy 405.934458 -19.163671) (xy 408.524684 -19.163671) (xy 408.524684 -19.109129)
			(xy 408.532446 -19.055143) (xy 408.547811 -19.002811) (xy 408.570467 -18.953198) (xy 408.599953 -18.907314)
			(xy 408.635668 -18.866093) (xy 408.676885 -18.830374) (xy 408.722767 -18.800884) (xy 408.772377 -18.778224)
			(xy 408.824708 -18.762854) (xy 408.878693 -18.755087) (xy 408.905964 -18.754598) (xy 408.92984 -18.75536)
			(xy 408.947578 -18.725218) (xy 408.987774 -18.667978) (xy 409.010104 -18.64106) (xy 409.017422 -18.631371)
			(xy 409.023005 -18.607781) (xy 409.020772 -18.595848) (xy 409.015447 -18.57317) (xy 409.009718 -18.526938)
			(xy 409.009342 -18.503646) (xy 409.009342 -18.503138) (xy 409.009837 -18.475868) (xy 409.017594 -18.421882)
			(xy 409.032956 -18.369549) (xy 409.055609 -18.319936) (xy 409.085093 -18.274052) (xy 409.120807 -18.232831)
			(xy 409.162025 -18.197113) (xy 409.207906 -18.167625) (xy 409.257518 -18.144967) (xy 409.309849 -18.129601)
			(xy 409.363834 -18.121839) (xy 409.391104 -18.121376) (xy 409.419805 -18.121968) (xy 409.476558 -18.130576)
			(xy 409.531383 -18.147581) (xy 409.583046 -18.172601) (xy 409.630381 -18.205071) (xy 409.672323 -18.244262)
			(xy 409.707927 -18.289288) (xy 409.73639 -18.339137) (xy 409.747212 -18.365724) (xy 409.75222 -18.376833)
			(xy 409.770399 -18.393011) (xy 409.78201 -18.396712) (xy 409.819734 -18.40692) (xy 409.893057 -18.433977)
			(xy 409.963232 -18.468382) (xy 409.99664 -18.48866) (xy 410.004896 -18.493374) (xy 410.023564 -18.496901)
			(xy 410.042232 -18.493374) (xy 410.050488 -18.48866) (xy 410.083896 -18.46838) (xy 410.15407 -18.433973)
			(xy 410.22739 -18.406908) (xy 410.265118 -18.396712) (xy 410.276728 -18.39301) (xy 410.294902 -18.37683)
			(xy 410.299916 -18.365724) (xy 410.31073 -18.339127) (xy 410.339173 -18.289256) (xy 410.374766 -18.244208)
			(xy 410.416705 -18.205) (xy 410.464045 -18.172517) (xy 410.515716 -18.147492) (xy 410.570553 -18.130489)
			(xy 410.627318 -18.121892) (xy 410.656024 -18.121376) (xy 410.683297 -18.121779) (xy 410.737288 -18.129546)
			(xy 410.789624 -18.144917) (xy 410.83924 -18.16758) (xy 410.885126 -18.197074) (xy 410.926346 -18.232798)
			(xy 410.962063 -18.274024) (xy 410.99155 -18.319914) (xy 411.014205 -18.369534) (xy 411.029568 -18.421872)
			(xy 411.037325 -18.475865) (xy 411.037786 -18.503138) (xy 411.037786 -18.503646) (xy 411.037408 -18.526938)
			(xy 411.031673 -18.573168) (xy 411.026356 -18.595848) (xy 411.02408 -18.607783) (xy 411.029658 -18.631396)
			(xy 411.037024 -18.64106) (xy 411.059353 -18.667979) (xy 411.09955 -18.725218) (xy 411.117288 -18.75536)
			(xy 411.141164 -18.754598) (xy 411.168434 -18.755139) (xy 411.222419 -18.762896) (xy 411.27475 -18.778258)
			(xy 411.324363 -18.800911) (xy 411.370246 -18.830394) (xy 411.411466 -18.866108) (xy 411.447184 -18.907325)
			(xy 411.476672 -18.953205) (xy 411.49933 -19.002816) (xy 411.514696 -19.055146) (xy 411.522459 -19.10913)
			(xy 411.522458 -19.16367) (xy 411.522458 -19.163671) (xy 414.418484 -19.163671) (xy 414.418484 -19.109129)
			(xy 414.426246 -19.055141) (xy 414.441612 -19.002808) (xy 414.464269 -18.953194) (xy 414.493757 -18.907309)
			(xy 414.529473 -18.866088) (xy 414.570693 -18.830369) (xy 414.616576 -18.800879) (xy 414.666189 -18.778219)
			(xy 414.718522 -18.762851) (xy 414.772509 -18.755086) (xy 414.79978 -18.754598) (xy 414.823656 -18.75536)
			(xy 414.841393 -18.725217) (xy 414.88159 -18.667978) (xy 414.90392 -18.64106) (xy 414.911239 -18.631372)
			(xy 414.91682 -18.607781) (xy 414.914588 -18.595848) (xy 414.909263 -18.57317) (xy 414.903534 -18.526938)
			(xy 414.903158 -18.503646) (xy 414.903158 -18.503138) (xy 414.903637 -18.475867) (xy 414.911394 -18.42188)
			(xy 414.926757 -18.369546) (xy 414.949411 -18.319932) (xy 414.978897 -18.274047) (xy 415.014613 -18.232826)
			(xy 415.055832 -18.197108) (xy 415.101716 -18.16762) (xy 415.151329 -18.144963) (xy 415.203662 -18.129598)
			(xy 415.257649 -18.121838) (xy 415.28492 -18.121376) (xy 415.313621 -18.121954) (xy 415.370375 -18.130564)
			(xy 415.425201 -18.147572) (xy 415.476863 -18.172594) (xy 415.524199 -18.205066) (xy 415.56614 -18.244258)
			(xy 415.601743 -18.289286) (xy 415.630206 -18.339136) (xy 415.641028 -18.365724) (xy 415.646078 -18.376809)
			(xy 415.664227 -18.392996) (xy 415.675826 -18.396712) (xy 415.713551 -18.406916) (xy 415.786874 -18.433975)
			(xy 415.857048 -18.468381) (xy 415.890456 -18.48866) (xy 415.898712 -18.493374) (xy 415.91738 -18.496901)
			(xy 415.936048 -18.493374) (xy 415.944304 -18.48866) (xy 415.97771 -18.468377) (xy 416.047885 -18.433971)
			(xy 416.121206 -18.406907) (xy 416.158934 -18.396712) (xy 416.170547 -18.393017) (xy 416.188719 -18.376832)
			(xy 416.193732 -18.365724) (xy 416.204533 -18.339122) (xy 416.232977 -18.28925) (xy 416.268572 -18.244202)
			(xy 416.310513 -18.204994) (xy 416.357855 -18.172511) (xy 416.409528 -18.147487) (xy 416.464367 -18.130486)
			(xy 416.521133 -18.121891) (xy 416.54984 -18.121376) (xy 416.577112 -18.121787) (xy 416.6311 -18.129555)
			(xy 416.683434 -18.144928) (xy 416.733046 -18.167591) (xy 416.778929 -18.197085) (xy 416.820147 -18.232808)
			(xy 416.855862 -18.274034) (xy 416.885346 -18.319922) (xy 416.907999 -18.36954) (xy 416.923361 -18.421876)
			(xy 416.931118 -18.475866) (xy 416.931602 -18.503138) (xy 416.931602 -18.503646) (xy 416.931223 -18.526938)
			(xy 416.925489 -18.573168) (xy 416.920172 -18.595848) (xy 416.917892 -18.607783) (xy 416.923472 -18.631396)
			(xy 416.93084 -18.64106) (xy 416.95317 -18.667978) (xy 416.993367 -18.725217) (xy 417.011104 -18.75536)
			(xy 417.03498 -18.754598) (xy 417.062249 -18.75514) (xy 417.116232 -18.762899) (xy 417.168562 -18.778262)
			(xy 417.218173 -18.800916) (xy 417.264054 -18.8304) (xy 417.305272 -18.866114) (xy 417.340988 -18.90733)
			(xy 417.370474 -18.95321) (xy 417.393131 -19.002819) (xy 417.408497 -19.055148) (xy 417.416259 -19.109131)
			(xy 417.416259 -19.163669) (xy 417.416159 -19.164366) (xy 420.005546 -19.164366) (xy 420.005546 -19.109834)
			(xy 420.013307 -19.055857) (xy 420.028669 -19.003533) (xy 420.051321 -18.953928) (xy 420.080802 -18.908051)
			(xy 420.116512 -18.866837) (xy 420.157723 -18.831124) (xy 420.203596 -18.801639) (xy 420.253199 -18.778982)
			(xy 420.305521 -18.763614) (xy 420.359498 -18.755849) (xy 420.386764 -18.75536) (xy 420.41064 -18.756122)
			(xy 420.428525 -18.725757) (xy 420.469105 -18.668133) (xy 420.491666 -18.64106) (xy 420.49898 -18.631369)
			(xy 420.504567 -18.60778) (xy 420.502334 -18.595848) (xy 420.497108 -18.57335) (xy 420.491507 -18.527502)
			(xy 420.491158 -18.504408) (xy 420.491158 -18.5039) (xy 420.491602 -18.476628) (xy 420.499364 -18.422639)
			(xy 420.514731 -18.370305) (xy 420.537391 -18.320691) (xy 420.56688 -18.274806) (xy 420.6026 -18.233585)
			(xy 420.643822 -18.197868) (xy 420.689708 -18.168381) (xy 420.739324 -18.145724) (xy 420.791659 -18.13036)
			(xy 420.845648 -18.1226) (xy 420.87292 -18.122138) (xy 420.901648 -18.122638) (xy 420.958453 -18.131272)
			(xy 421.013326 -18.148311) (xy 421.065029 -18.173372) (xy 421.112399 -18.20589) (xy 421.154367 -18.245133)
			(xy 421.189988 -18.290216) (xy 421.21846 -18.340123) (xy 421.229282 -18.36674) (xy 421.234299 -18.377844)
			(xy 421.252472 -18.394023) (xy 421.26408 -18.397728) (xy 421.301588 -18.407922) (xy 421.374473 -18.434935)
			(xy 421.44423 -18.469227) (xy 421.47744 -18.489422) (xy 421.485693 -18.494126) (xy 421.50433 -18.497727)
			(xy 421.523003 -18.494322) (xy 421.531288 -18.489676) (xy 421.568924 -18.466839) (xy 421.648421 -18.429011)
			(xy 421.731736 -18.400565) (xy 421.77462 -18.390616) (xy 421.786648 -18.387408) (xy 421.805694 -18.371424)
			(xy 421.810942 -18.360136) (xy 421.822064 -18.334135) (xy 421.850855 -18.285463) (xy 421.88651 -18.24157)
			(xy 421.928251 -18.203417) (xy 421.975163 -18.171839) (xy 422.02622 -18.147526) (xy 422.080306 -18.131012)
			(xy 422.136235 -18.122657) (xy 422.16451 -18.122138) (xy 422.19178 -18.122615) (xy 422.245764 -18.130378)
			(xy 422.298093 -18.145745) (xy 422.347703 -18.168402) (xy 422.393584 -18.197889) (xy 422.434802 -18.233605)
			(xy 422.470517 -18.274824) (xy 422.500003 -18.320705) (xy 422.522659 -18.370316) (xy 422.538024 -18.422646)
			(xy 422.545786 -18.47663) (xy 422.546272 -18.5039) (xy 422.546272 -18.504154) (xy 422.545694 -18.533325)
			(xy 422.536759 -18.590981) (xy 422.528492 -18.618962) (xy 422.525374 -18.630973) (xy 422.529915 -18.655345)
			(xy 422.537128 -18.665444) (xy 422.553774 -18.687137) (xy 422.584285 -18.732519) (xy 422.598088 -18.756122)
			(xy 422.621964 -18.75536) (xy 422.649238 -18.755777) (xy 422.703232 -18.763536) (xy 422.755572 -18.7789)
			(xy 422.805193 -18.801556) (xy 422.851084 -18.831045) (xy 422.89231 -18.866764) (xy 422.928034 -18.907988)
			(xy 422.957526 -18.953876) (xy 422.980188 -19.003494) (xy 422.995557 -19.055833) (xy 423.00332 -19.109826)
			(xy 423.00332 -19.163675) (xy 425.628462 -19.163675) (xy 425.628462 -19.109125) (xy 425.636225 -19.055131)
			(xy 425.651594 -19.002792) (xy 425.674255 -18.953173) (xy 425.703747 -18.907283) (xy 425.73947 -18.866059)
			(xy 425.780696 -18.830337) (xy 425.826587 -18.800847) (xy 425.876207 -18.778188) (xy 425.928547 -18.762822)
			(xy 425.982541 -18.75506) (xy 426.009816 -18.754598) (xy 426.033692 -18.75536) (xy 426.051426 -18.725215)
			(xy 426.091625 -18.667977) (xy 426.113956 -18.64106) (xy 426.12127 -18.631368) (xy 426.126857 -18.60778)
			(xy 426.124624 -18.595848) (xy 426.119298 -18.57317) (xy 426.11357 -18.526938) (xy 426.113194 -18.503646)
			(xy 426.113194 -18.503138) (xy 426.11376 -18.475872) (xy 426.121515 -18.421893) (xy 426.136873 -18.369568)
			(xy 426.159522 -18.319961) (xy 426.189 -18.274082) (xy 426.224707 -18.232865) (xy 426.265916 -18.197149)
			(xy 426.311789 -18.167661) (xy 426.361391 -18.145002) (xy 426.413713 -18.129632) (xy 426.46769 -18.121865)
			(xy 426.494956 -18.121376) (xy 426.523658 -18.121924) (xy 426.580413 -18.130539) (xy 426.63524 -18.147551)
			(xy 426.686903 -18.172578) (xy 426.734238 -18.205054) (xy 426.776179 -18.24425) (xy 426.811781 -18.289282)
			(xy 426.840242 -18.339135) (xy 426.851064 -18.365724) (xy 426.856096 -18.37682) (xy 426.874258 -18.393003)
			(xy 426.885862 -18.396712) (xy 426.92359 -18.406908) (xy 426.996911 -18.43397) (xy 427.067085 -18.468379)
			(xy 427.100492 -18.48866) (xy 427.108748 -18.493374) (xy 427.127416 -18.496901) (xy 427.146084 -18.493374)
			(xy 427.15434 -18.48866) (xy 427.187753 -18.46839) (xy 427.257925 -18.433979) (xy 427.331243 -18.40691)
			(xy 427.36897 -18.396712) (xy 427.38059 -18.393034) (xy 427.398758 -18.376836) (xy 427.403768 -18.365724)
			(xy 427.414539 -18.339109) (xy 427.442987 -18.289235) (xy 427.478586 -18.244187) (xy 427.520531 -18.204979)
			(xy 427.567877 -18.172498) (xy 427.619555 -18.147476) (xy 427.674397 -18.130479) (xy 427.731168 -18.121889)
			(xy 427.759876 -18.121376) (xy 427.787148 -18.121824) (xy 427.841138 -18.129584) (xy 427.893473 -18.144949)
			(xy 427.943088 -18.167606) (xy 427.988974 -18.197095) (xy 428.030195 -18.232814) (xy 428.065913 -18.274037)
			(xy 428.0954 -18.319924) (xy 428.118056 -18.36954) (xy 428.133419 -18.421876) (xy 428.141177 -18.475866)
			(xy 428.141638 -18.503138) (xy 428.141638 -18.503646) (xy 428.141258 -18.526938) (xy 428.135525 -18.573168)
			(xy 428.130208 -18.595848) (xy 428.12792 -18.607782) (xy 428.133504 -18.631398) (xy 428.140876 -18.64106)
			(xy 428.163208 -18.667976) (xy 428.203403 -18.725217) (xy 428.22114 -18.75536) (xy 428.245016 -18.754598)
			(xy 428.272282 -18.755165) (xy 428.326258 -18.762928) (xy 428.37858 -18.778293) (xy 428.428183 -18.800948)
			(xy 428.474057 -18.830431) (xy 428.515269 -18.866143) (xy 428.550978 -18.907356) (xy 428.58046 -18.953231)
			(xy 428.603112 -19.002835) (xy 428.618475 -19.055158) (xy 428.626236 -19.109134) (xy 428.626236 -19.163666)
			(xy 428.626235 -19.163675) (xy 431.216462 -19.163675) (xy 431.216462 -19.109125) (xy 431.224225 -19.055131)
			(xy 431.239594 -19.002792) (xy 431.262255 -18.953173) (xy 431.291747 -18.907283) (xy 431.32747 -18.866059)
			(xy 431.368696 -18.830337) (xy 431.414587 -18.800847) (xy 431.464207 -18.778188) (xy 431.516547 -18.762822)
			(xy 431.570541 -18.75506) (xy 431.597816 -18.754598) (xy 431.621692 -18.75536) (xy 431.639426 -18.725215)
			(xy 431.679625 -18.667977) (xy 431.701956 -18.64106) (xy 431.70927 -18.631368) (xy 431.714857 -18.60778)
			(xy 431.712624 -18.595848) (xy 431.707298 -18.57317) (xy 431.70157 -18.526938) (xy 431.701194 -18.503646)
			(xy 431.701194 -18.503138) (xy 431.70176 -18.475872) (xy 431.709515 -18.421893) (xy 431.724873 -18.369568)
			(xy 431.747522 -18.319961) (xy 431.777 -18.274082) (xy 431.812707 -18.232865) (xy 431.853916 -18.197149)
			(xy 431.899789 -18.167661) (xy 431.949391 -18.145002) (xy 432.001713 -18.129632) (xy 432.05569 -18.121865)
			(xy 432.082956 -18.121376) (xy 432.111658 -18.121924) (xy 432.168413 -18.130539) (xy 432.22324 -18.147551)
			(xy 432.274903 -18.172578) (xy 432.322238 -18.205054) (xy 432.364179 -18.24425) (xy 432.399781 -18.289282)
			(xy 432.428242 -18.339135) (xy 432.439064 -18.365724) (xy 432.444096 -18.37682) (xy 432.462258 -18.393003)
			(xy 432.473862 -18.396712) (xy 432.51159 -18.406908) (xy 432.584911 -18.43397) (xy 432.655085 -18.468379)
			(xy 432.688492 -18.48866) (xy 432.696748 -18.493374) (xy 432.715416 -18.496901) (xy 432.734084 -18.493374)
			(xy 432.74234 -18.48866) (xy 432.775753 -18.46839) (xy 432.845925 -18.433979) (xy 432.919243 -18.40691)
			(xy 432.95697 -18.396712) (xy 432.96859 -18.393034) (xy 432.986758 -18.376836) (xy 432.991768 -18.365724)
			(xy 433.002539 -18.339109) (xy 433.030987 -18.289235) (xy 433.066586 -18.244187) (xy 433.108531 -18.204979)
			(xy 433.155877 -18.172498) (xy 433.207555 -18.147476) (xy 433.262397 -18.130479) (xy 433.319168 -18.121889)
			(xy 433.347876 -18.121376) (xy 433.375148 -18.121824) (xy 433.429138 -18.129584) (xy 433.481473 -18.144949)
			(xy 433.531088 -18.167606) (xy 433.576974 -18.197095) (xy 433.618195 -18.232814) (xy 433.653913 -18.274037)
			(xy 433.6834 -18.319924) (xy 433.706056 -18.36954) (xy 433.721419 -18.421876) (xy 433.729177 -18.475866)
			(xy 433.729638 -18.503138) (xy 433.729638 -18.503646) (xy 433.729258 -18.526938) (xy 433.723525 -18.573168)
			(xy 433.718208 -18.595848) (xy 433.71592 -18.607782) (xy 433.721504 -18.631398) (xy 433.728876 -18.64106)
			(xy 433.751208 -18.667976) (xy 433.791403 -18.725217) (xy 433.80914 -18.75536) (xy 433.833016 -18.754598)
			(xy 433.860282 -18.755165) (xy 433.914258 -18.762928) (xy 433.96658 -18.778293) (xy 434.016183 -18.800948)
			(xy 434.062057 -18.830431) (xy 434.103269 -18.866143) (xy 434.138978 -18.907356) (xy 434.16846 -18.953231)
			(xy 434.191112 -19.002835) (xy 434.206475 -19.055158) (xy 434.214236 -19.109134) (xy 434.214236 -19.163666)
			(xy 434.206475 -19.217642) (xy 434.191112 -19.269965) (xy 434.16846 -19.319569) (xy 434.138978 -19.365444)
			(xy 434.103269 -19.406657) (xy 434.062057 -19.442369) (xy 434.016183 -19.471852) (xy 433.96658 -19.494507)
			(xy 433.914258 -19.509872) (xy 433.860282 -19.517635) (xy 433.833016 -19.518122) (xy 433.80914 -19.51736)
			(xy 433.791284 -19.547518) (xy 433.750832 -19.604758) (xy 433.728368 -19.63166) (xy 433.721005 -19.641393)
			(xy 433.715577 -19.665153) (xy 433.717954 -19.677126) (xy 433.723401 -19.70011) (xy 433.729266 -19.74698)
			(xy 433.729638 -19.770598) (xy 433.729638 -19.771106) (xy 433.729204 -19.798378) (xy 433.72144 -19.852367)
			(xy 433.706072 -19.904702) (xy 433.683412 -19.954317) (xy 433.653922 -20.000202) (xy 433.618201 -20.041422)
			(xy 433.576978 -20.07714) (xy 433.531091 -20.106627) (xy 433.481474 -20.129283) (xy 433.429138 -20.144647)
			(xy 433.375148 -20.152406) (xy 433.347876 -20.152868) (xy 433.319064 -20.152294) (xy 433.262095 -20.143623)
			(xy 433.207075 -20.126497) (xy 433.155249 -20.101303) (xy 433.107794 -20.068614) (xy 433.065785 -20.029169)
			(xy 433.030176 -19.983865) (xy 433.001772 -19.933726) (xy 432.991006 -19.906996) (xy 432.986056 -19.895802)
			(xy 432.967868 -19.879478) (xy 432.956208 -19.875754) (xy 432.918607 -19.865539) (xy 432.845545 -19.838454)
			(xy 432.775624 -19.804062) (xy 432.74234 -19.783806) (xy 432.734079 -19.77911) (xy 432.715416 -19.775602)
			(xy 432.696753 -19.77911) (xy 432.688492 -19.783806) (xy 432.655206 -19.804059) (xy 432.58528 -19.838437)
			(xy 432.512221 -19.865526) (xy 432.474624 -19.875754) (xy 432.462989 -19.879518) (xy 432.44482 -19.895833)
			(xy 432.439826 -19.906996) (xy 432.429077 -19.933738) (xy 432.400691 -19.983897) (xy 432.36509 -20.029221)
			(xy 432.323082 -20.06868) (xy 432.275622 -20.101378) (xy 432.223786 -20.126573) (xy 432.168753 -20.143692)
			(xy 432.111773 -20.152346) (xy 432.082956 -20.152868) (xy 432.055686 -20.152416) (xy 432.001701 -20.144649)
			(xy 431.949371 -20.129278) (xy 431.899762 -20.106617) (xy 431.853881 -20.077128) (xy 431.812664 -20.041409)
			(xy 431.77695 -20.000188) (xy 431.747464 -19.954305) (xy 431.724808 -19.904693) (xy 431.709443 -19.852362)
			(xy 431.701681 -19.798376) (xy 431.701194 -19.771106) (xy 431.701194 -19.770598) (xy 431.701555 -19.74698)
			(xy 431.707419 -19.700108) (xy 431.712878 -19.677126) (xy 431.715193 -19.665154) (xy 431.709771 -19.64142)
			(xy 431.702464 -19.63166) (xy 431.680004 -19.604755) (xy 431.639554 -19.547514) (xy 431.621692 -19.51736)
			(xy 431.597816 -19.518122) (xy 431.570541 -19.51774) (xy 431.516547 -19.509978) (xy 431.464207 -19.494612)
			(xy 431.414587 -19.471953) (xy 431.368696 -19.442463) (xy 431.32747 -19.406741) (xy 431.291747 -19.365517)
			(xy 431.262255 -19.319627) (xy 431.239594 -19.270008) (xy 431.224225 -19.217669) (xy 431.216462 -19.163675)
			(xy 428.626235 -19.163675) (xy 428.618475 -19.217642) (xy 428.603112 -19.269965) (xy 428.58046 -19.319569)
			(xy 428.550978 -19.365444) (xy 428.515269 -19.406657) (xy 428.474057 -19.442369) (xy 428.428183 -19.471852)
			(xy 428.37858 -19.494507) (xy 428.326258 -19.509872) (xy 428.272282 -19.517635) (xy 428.245016 -19.518122)
			(xy 428.22114 -19.51736) (xy 428.203284 -19.547518) (xy 428.162832 -19.604758) (xy 428.140368 -19.63166)
			(xy 428.133005 -19.641393) (xy 428.127577 -19.665153) (xy 428.129954 -19.677126) (xy 428.135401 -19.70011)
			(xy 428.141266 -19.74698) (xy 428.141638 -19.770598) (xy 428.141638 -19.771106) (xy 428.141204 -19.798378)
			(xy 428.13344 -19.852367) (xy 428.118072 -19.904702) (xy 428.095412 -19.954317) (xy 428.065922 -20.000202)
			(xy 428.030201 -20.041422) (xy 427.988978 -20.07714) (xy 427.943091 -20.106627) (xy 427.893474 -20.129283)
			(xy 427.841138 -20.144647) (xy 427.787148 -20.152406) (xy 427.759876 -20.152868) (xy 427.731064 -20.152294)
			(xy 427.674095 -20.143623) (xy 427.619075 -20.126497) (xy 427.567249 -20.101303) (xy 427.519794 -20.068614)
			(xy 427.477785 -20.029169) (xy 427.442176 -19.983865) (xy 427.413772 -19.933726) (xy 427.403006 -19.906996)
			(xy 427.398056 -19.895802) (xy 427.379868 -19.879478) (xy 427.368208 -19.875754) (xy 427.330607 -19.865539)
			(xy 427.257545 -19.838454) (xy 427.187624 -19.804062) (xy 427.15434 -19.783806) (xy 427.146079 -19.77911)
			(xy 427.127416 -19.775602) (xy 427.108753 -19.77911) (xy 427.100492 -19.783806) (xy 427.067206 -19.804059)
			(xy 426.99728 -19.838437) (xy 426.924221 -19.865526) (xy 426.886624 -19.875754) (xy 426.874989 -19.879518)
			(xy 426.85682 -19.895833) (xy 426.851826 -19.906996) (xy 426.841077 -19.933738) (xy 426.812691 -19.983897)
			(xy 426.77709 -20.029221) (xy 426.735082 -20.06868) (xy 426.687622 -20.101378) (xy 426.635786 -20.126573)
			(xy 426.580753 -20.143692) (xy 426.523773 -20.152346) (xy 426.494956 -20.152868) (xy 426.467686 -20.152416)
			(xy 426.413701 -20.144649) (xy 426.361371 -20.129278) (xy 426.311762 -20.106617) (xy 426.265881 -20.077128)
			(xy 426.224664 -20.041409) (xy 426.18895 -20.000188) (xy 426.159464 -19.954305) (xy 426.136808 -19.904693)
			(xy 426.121443 -19.852362) (xy 426.113681 -19.798376) (xy 426.113194 -19.771106) (xy 426.113194 -19.770598)
			(xy 426.113555 -19.74698) (xy 426.119419 -19.700108) (xy 426.124878 -19.677126) (xy 426.127193 -19.665154)
			(xy 426.121771 -19.64142) (xy 426.114464 -19.63166) (xy 426.092004 -19.604755) (xy 426.051554 -19.547514)
			(xy 426.033692 -19.51736) (xy 426.009816 -19.518122) (xy 425.982541 -19.51774) (xy 425.928547 -19.509978)
			(xy 425.876207 -19.494612) (xy 425.826587 -19.471953) (xy 425.780696 -19.442463) (xy 425.73947 -19.406741)
			(xy 425.703747 -19.365517) (xy 425.674255 -19.319627) (xy 425.651594 -19.270008) (xy 425.636225 -19.217669)
			(xy 425.628462 -19.163675) (xy 423.00332 -19.163675) (xy 423.00332 -19.164374) (xy 422.995557 -19.218367)
			(xy 422.980188 -19.270706) (xy 422.957526 -19.320324) (xy 422.928034 -19.366212) (xy 422.89231 -19.407436)
			(xy 422.851084 -19.443155) (xy 422.805193 -19.472644) (xy 422.755572 -19.4953) (xy 422.703232 -19.510664)
			(xy 422.649238 -19.518423) (xy 422.621964 -19.518884) (xy 422.598088 -19.518122) (xy 422.584167 -19.5418)
			(xy 422.553405 -19.587312) (xy 422.53662 -19.609054) (xy 422.52942 -19.619302) (xy 422.525034 -19.643935)
			(xy 422.528238 -19.656044) (xy 422.536682 -19.684251) (xy 422.545733 -19.742429) (xy 422.546272 -19.771868)
			(xy 422.545769 -19.799138) (xy 422.538011 -19.853123) (xy 422.52265 -19.905454) (xy 422.499996 -19.955066)
			(xy 422.470513 -20.00095) (xy 422.4348 -20.04217) (xy 422.393583 -20.077888) (xy 422.347703 -20.107376)
			(xy 422.298093 -20.130035) (xy 422.245764 -20.145402) (xy 422.19178 -20.153166) (xy 422.16451 -20.15363)
			(xy 422.136121 -20.15315) (xy 422.079966 -20.144755) (xy 422.025675 -20.128133) (xy 421.974446 -20.103651)
			(xy 421.927409 -20.071851) (xy 421.885602 -20.033432) (xy 421.849948 -19.989244) (xy 421.821234 -19.940262)
			(xy 421.81018 -19.914108) (xy 421.804901 -19.902842) (xy 421.785871 -19.886862) (xy 421.773858 -19.883628)
			(xy 421.731111 -19.873685) (xy 421.648062 -19.845299) (xy 421.568814 -19.807579) (xy 421.531288 -19.784822)
			(xy 421.523064 -19.780057) (xy 421.504408 -19.776472) (xy 421.485724 -19.779905) (xy 421.47744 -19.784568)
			(xy 421.444309 -19.804739) (xy 421.374713 -19.839001) (xy 421.302005 -19.866036) (xy 421.264588 -19.876262)
			(xy 421.253014 -19.88006) (xy 421.234968 -19.896364) (xy 421.230044 -19.907504) (xy 421.219288 -19.93427)
			(xy 421.190896 -19.984482) (xy 421.155278 -20.029855) (xy 421.113243 -20.069358) (xy 421.065748 -20.102092)
			(xy 421.013871 -20.127314) (xy 420.958791 -20.144449) (xy 420.901762 -20.153109) (xy 420.87292 -20.15363)
			(xy 420.845648 -20.15318) (xy 420.791659 -20.14542) (xy 420.739324 -20.130054) (xy 420.689709 -20.107397)
			(xy 420.643824 -20.077908) (xy 420.602602 -20.042189) (xy 420.566885 -20.000967) (xy 420.537398 -19.955081)
			(xy 420.514742 -19.905465) (xy 420.499378 -19.853129) (xy 420.491619 -19.79914) (xy 420.491158 -19.771868)
			(xy 420.491158 -19.77136) (xy 420.491513 -19.747941) (xy 420.497245 -19.701454) (xy 420.502588 -19.67865)
			(xy 420.504845 -19.666649) (xy 420.499298 -19.642911) (xy 420.49192 -19.633184) (xy 420.469313 -19.606102)
			(xy 420.428606 -19.548482) (xy 420.41064 -19.518122) (xy 420.386764 -19.518884) (xy 420.359498 -19.518351)
			(xy 420.305521 -19.510586) (xy 420.253199 -19.495218) (xy 420.203596 -19.472561) (xy 420.157723 -19.443076)
			(xy 420.116512 -19.407363) (xy 420.080802 -19.366149) (xy 420.051321 -19.320272) (xy 420.028669 -19.270667)
			(xy 420.013307 -19.218343) (xy 420.005546 -19.164366) (xy 417.416159 -19.164366) (xy 417.408497 -19.217652)
			(xy 417.393131 -19.269981) (xy 417.370474 -19.31959) (xy 417.340988 -19.36547) (xy 417.305272 -19.406686)
			(xy 417.264054 -19.4424) (xy 417.218173 -19.471884) (xy 417.168562 -19.494538) (xy 417.116232 -19.509901)
			(xy 417.062249 -19.51766) (xy 417.03498 -19.518122) (xy 417.011104 -19.51736) (xy 416.993243 -19.547515)
			(xy 416.952794 -19.604757) (xy 416.930332 -19.63166) (xy 416.922973 -19.641397) (xy 416.91754 -19.665154)
			(xy 416.919918 -19.677126) (xy 416.925366 -19.70011) (xy 416.93123 -19.74698) (xy 416.931602 -19.770598)
			(xy 416.931602 -19.771106) (xy 416.931081 -19.798374) (xy 416.92332 -19.852354) (xy 416.907956 -19.90468)
			(xy 416.885302 -19.954288) (xy 416.855819 -20.000167) (xy 416.820107 -20.041383) (xy 416.778894 -20.077099)
			(xy 416.733018 -20.106585) (xy 416.683412 -20.129244) (xy 416.631087 -20.144613) (xy 416.577108 -20.152379)
			(xy 416.54984 -20.152868) (xy 416.521027 -20.152325) (xy 416.464057 -20.143649) (xy 416.409035 -20.126518)
			(xy 416.35721 -20.101319) (xy 416.309755 -20.068626) (xy 416.267747 -20.029177) (xy 416.232138 -19.983869)
			(xy 416.203735 -19.933728) (xy 416.19297 -19.906996) (xy 416.187987 -19.89582) (xy 416.169822 -19.879489)
			(xy 416.158172 -19.875754) (xy 416.120575 -19.865525) (xy 416.047512 -19.838446) (xy 415.97759 -19.804059)
			(xy 415.944304 -19.783806) (xy 415.936043 -19.77911) (xy 415.91738 -19.775602) (xy 415.898717 -19.77911)
			(xy 415.890456 -19.783806) (xy 415.857163 -19.804046) (xy 415.78724 -19.838429) (xy 415.714183 -19.865523)
			(xy 415.676588 -19.875754) (xy 415.664946 -19.879502) (xy 415.646781 -19.895829) (xy 415.64179 -19.906996)
			(xy 415.631071 -19.933751) (xy 415.602681 -19.983911) (xy 415.567076 -20.029236) (xy 415.525064 -20.068694)
			(xy 415.477599 -20.101391) (xy 415.42576 -20.126583) (xy 415.370723 -20.143699) (xy 415.313739 -20.152349)
			(xy 415.28492 -20.152868) (xy 415.25765 -20.15238) (xy 415.203664 -20.144621) (xy 415.151332 -20.129257)
			(xy 415.10172 -20.106602) (xy 415.055836 -20.077117) (xy 415.014616 -20.041403) (xy 414.978898 -20.000185)
			(xy 414.94941 -19.954303) (xy 414.926752 -19.904692) (xy 414.911385 -19.852361) (xy 414.903622 -19.798376)
			(xy 414.903158 -19.771106) (xy 414.903158 -19.770598) (xy 414.903517 -19.74698) (xy 414.909383 -19.700108)
			(xy 414.914842 -19.677126) (xy 414.917143 -19.665153) (xy 414.911728 -19.641422) (xy 414.904428 -19.63166)
			(xy 414.881971 -19.604752) (xy 414.841519 -19.547513) (xy 414.823656 -19.51736) (xy 414.79978 -19.518122)
			(xy 414.772509 -19.517714) (xy 414.718522 -19.509949) (xy 414.666189 -19.494581) (xy 414.616576 -19.471921)
			(xy 414.570693 -19.442431) (xy 414.529473 -19.406712) (xy 414.493757 -19.365491) (xy 414.464269 -19.319606)
			(xy 414.441612 -19.269992) (xy 414.426246 -19.217659) (xy 414.418484 -19.163671) (xy 411.522458 -19.163671)
			(xy 411.514696 -19.217654) (xy 411.49933 -19.269984) (xy 411.476672 -19.319595) (xy 411.447184 -19.365475)
			(xy 411.411466 -19.406692) (xy 411.370246 -19.442406) (xy 411.324363 -19.471889) (xy 411.27475 -19.494542)
			(xy 411.222419 -19.509904) (xy 411.168434 -19.517661) (xy 411.141164 -19.518122) (xy 411.117288 -19.51736)
			(xy 411.099429 -19.547516) (xy 411.058979 -19.604757) (xy 411.036516 -19.63166) (xy 411.029156 -19.641396)
			(xy 411.023724 -19.665154) (xy 411.026102 -19.677126) (xy 411.03155 -19.70011) (xy 411.037414 -19.74698)
			(xy 411.037786 -19.770598) (xy 411.037786 -19.771106) (xy 411.037281 -19.798374) (xy 411.029519 -19.852356)
			(xy 411.014154 -19.904684) (xy 410.991499 -19.954292) (xy 410.962015 -20.000172) (xy 410.926302 -20.041389)
			(xy 410.885087 -20.077104) (xy 410.839208 -20.106591) (xy 410.789601 -20.129248) (xy 410.737274 -20.144616)
			(xy 410.683292 -20.15238) (xy 410.656024 -20.152868) (xy 410.62721 -20.152339) (xy 410.57024 -20.143661)
			(xy 410.515218 -20.126527) (xy 410.463392 -20.101327) (xy 410.415938 -20.068631) (xy 410.37393 -20.029181)
			(xy 410.338321 -19.983871) (xy 410.309919 -19.933728) (xy 410.299154 -19.906996) (xy 410.294179 -19.895815)
			(xy 410.276009 -19.879486) (xy 410.264356 -19.875754) (xy 410.226758 -19.865528) (xy 410.153695 -19.838448)
			(xy 410.083773 -19.80406) (xy 410.050488 -19.783806) (xy 410.042227 -19.77911) (xy 410.023564 -19.775602)
			(xy 410.004901 -19.77911) (xy 409.99664 -19.783806) (xy 409.963349 -19.804049) (xy 409.893425 -19.838431)
			(xy 409.820368 -19.865524) (xy 409.782772 -19.875754) (xy 409.771128 -19.879495) (xy 409.752964 -19.895827)
			(xy 409.747974 -19.906996) (xy 409.737268 -19.933757) (xy 409.708877 -19.983918) (xy 409.67327 -20.029242)
			(xy 409.631256 -20.068701) (xy 409.583789 -20.101397) (xy 409.531948 -20.126588) (xy 409.476909 -20.143702)
			(xy 409.419923 -20.15235) (xy 409.391104 -20.152868) (xy 409.363835 -20.152372) (xy 409.309852 -20.144611)
			(xy 409.257523 -20.129246) (xy 409.207913 -20.106591) (xy 409.162033 -20.077106) (xy 409.120815 -20.041392)
			(xy 409.0851 -20.000175) (xy 409.055614 -19.954295) (xy 409.032957 -19.904686) (xy 409.017591 -19.852358)
			(xy 409.009829 -19.798375) (xy 409.009342 -19.771106) (xy 409.009342 -19.770598) (xy 409.009702 -19.74698)
			(xy 409.015567 -19.700108) (xy 409.021026 -19.677126) (xy 409.023331 -19.665153) (xy 409.017914 -19.641422)
			(xy 409.010612 -19.63166) (xy 408.988154 -19.604753) (xy 408.947703 -19.547514) (xy 408.92984 -19.51736)
			(xy 408.905964 -19.518122) (xy 408.878693 -19.517713) (xy 408.824708 -19.509946) (xy 408.772377 -19.494576)
			(xy 408.722767 -19.471916) (xy 408.676885 -19.442426) (xy 408.635668 -19.406707) (xy 408.599953 -19.365486)
			(xy 408.570467 -19.319602) (xy 408.547811 -19.269989) (xy 408.532446 -19.217657) (xy 408.524684 -19.163671)
			(xy 405.934458 -19.163671) (xy 405.926696 -19.217654) (xy 405.91133 -19.269984) (xy 405.888672 -19.319595)
			(xy 405.859184 -19.365475) (xy 405.823466 -19.406692) (xy 405.782246 -19.442406) (xy 405.736363 -19.471889)
			(xy 405.68675 -19.494542) (xy 405.634419 -19.509904) (xy 405.580434 -19.517661) (xy 405.553164 -19.518122)
			(xy 405.529288 -19.51736) (xy 405.511429 -19.547516) (xy 405.470979 -19.604757) (xy 405.448516 -19.63166)
			(xy 405.441156 -19.641396) (xy 405.435724 -19.665154) (xy 405.438102 -19.677126) (xy 405.44355 -19.70011)
			(xy 405.449414 -19.74698) (xy 405.449786 -19.770598) (xy 405.449786 -19.771106) (xy 405.449281 -19.798374)
			(xy 405.441519 -19.852356) (xy 405.426154 -19.904684) (xy 405.403499 -19.954292) (xy 405.374015 -20.000172)
			(xy 405.338302 -20.041389) (xy 405.297087 -20.077104) (xy 405.251208 -20.106591) (xy 405.201601 -20.129248)
			(xy 405.149274 -20.144616) (xy 405.095292 -20.15238) (xy 405.068024 -20.152868) (xy 405.03921 -20.152339)
			(xy 404.98224 -20.143661) (xy 404.927218 -20.126527) (xy 404.875392 -20.101327) (xy 404.827938 -20.068631)
			(xy 404.78593 -20.029181) (xy 404.750321 -19.983871) (xy 404.721919 -19.933728) (xy 404.711154 -19.906996)
			(xy 404.706179 -19.895815) (xy 404.688009 -19.879486) (xy 404.676356 -19.875754) (xy 404.638758 -19.865528)
			(xy 404.565695 -19.838448) (xy 404.495773 -19.80406) (xy 404.462488 -19.783806) (xy 404.454227 -19.77911)
			(xy 404.435564 -19.775602) (xy 404.416901 -19.77911) (xy 404.40864 -19.783806) (xy 404.375349 -19.804049)
			(xy 404.305425 -19.838431) (xy 404.232368 -19.865524) (xy 404.194772 -19.875754) (xy 404.183128 -19.879495)
			(xy 404.164964 -19.895827) (xy 404.159974 -19.906996) (xy 404.149268 -19.933757) (xy 404.120877 -19.983918)
			(xy 404.08527 -20.029242) (xy 404.043256 -20.068701) (xy 403.995789 -20.101397) (xy 403.943948 -20.126588)
			(xy 403.888909 -20.143702) (xy 403.831923 -20.15235) (xy 403.803104 -20.152868) (xy 403.775835 -20.152372)
			(xy 403.721852 -20.144611) (xy 403.669523 -20.129246) (xy 403.619913 -20.106591) (xy 403.574033 -20.077106)
			(xy 403.532815 -20.041392) (xy 403.4971 -20.000175) (xy 403.467614 -19.954295) (xy 403.444957 -19.904686)
			(xy 403.429591 -19.852358) (xy 403.421829 -19.798375) (xy 403.421342 -19.771106) (xy 403.421342 -19.770598)
			(xy 403.421702 -19.74698) (xy 403.427567 -19.700108) (xy 403.433026 -19.677126) (xy 403.435331 -19.665153)
			(xy 403.429914 -19.641422) (xy 403.422612 -19.63166) (xy 403.400154 -19.604753) (xy 403.359703 -19.547514)
			(xy 403.34184 -19.51736) (xy 403.317964 -19.518122) (xy 403.290693 -19.517713) (xy 403.236708 -19.509946)
			(xy 403.184377 -19.494576) (xy 403.134767 -19.471916) (xy 403.088885 -19.442426) (xy 403.047668 -19.406707)
			(xy 403.011953 -19.365486) (xy 402.982467 -19.319602) (xy 402.959811 -19.269989) (xy 402.944446 -19.217657)
			(xy 402.936684 -19.163671) (xy 400.346458 -19.163671) (xy 400.338696 -19.217654) (xy 400.32333 -19.269984)
			(xy 400.300672 -19.319595) (xy 400.271184 -19.365475) (xy 400.235466 -19.406692) (xy 400.194246 -19.442406)
			(xy 400.148363 -19.471889) (xy 400.09875 -19.494542) (xy 400.046419 -19.509904) (xy 399.992434 -19.517661)
			(xy 399.965164 -19.518122) (xy 399.941288 -19.51736) (xy 399.923429 -19.547516) (xy 399.882979 -19.604757)
			(xy 399.860516 -19.63166) (xy 399.853156 -19.641396) (xy 399.847724 -19.665154) (xy 399.850102 -19.677126)
			(xy 399.85555 -19.70011) (xy 399.861414 -19.74698) (xy 399.861786 -19.770598) (xy 399.861786 -19.771106)
			(xy 399.861281 -19.798374) (xy 399.853519 -19.852356) (xy 399.838154 -19.904684) (xy 399.815499 -19.954292)
			(xy 399.786015 -20.000172) (xy 399.750302 -20.041389) (xy 399.709087 -20.077104) (xy 399.663208 -20.106591)
			(xy 399.613601 -20.129248) (xy 399.561274 -20.144616) (xy 399.507292 -20.15238) (xy 399.480024 -20.152868)
			(xy 399.45121 -20.152339) (xy 399.39424 -20.143661) (xy 399.339218 -20.126527) (xy 399.287392 -20.101327)
			(xy 399.239938 -20.068631) (xy 399.19793 -20.029181) (xy 399.162321 -19.983871) (xy 399.133919 -19.933728)
			(xy 399.123154 -19.906996) (xy 399.118179 -19.895815) (xy 399.100009 -19.879486) (xy 399.088356 -19.875754)
			(xy 399.050758 -19.865528) (xy 398.977695 -19.838448) (xy 398.907773 -19.80406) (xy 398.874488 -19.783806)
			(xy 398.866227 -19.77911) (xy 398.847564 -19.775602) (xy 398.828901 -19.77911) (xy 398.82064 -19.783806)
			(xy 398.787349 -19.804049) (xy 398.717425 -19.838431) (xy 398.644368 -19.865524) (xy 398.606772 -19.875754)
			(xy 398.595128 -19.879495) (xy 398.576964 -19.895827) (xy 398.571974 -19.906996) (xy 398.561268 -19.933757)
			(xy 398.532877 -19.983918) (xy 398.49727 -20.029242) (xy 398.455256 -20.068701) (xy 398.407789 -20.101397)
			(xy 398.355948 -20.126588) (xy 398.300909 -20.143702) (xy 398.243923 -20.15235) (xy 398.215104 -20.152868)
			(xy 398.187835 -20.152372) (xy 398.133852 -20.144611) (xy 398.081523 -20.129246) (xy 398.031913 -20.106591)
			(xy 397.986033 -20.077106) (xy 397.944815 -20.041392) (xy 397.9091 -20.000175) (xy 397.879614 -19.954295)
			(xy 397.856957 -19.904686) (xy 397.841591 -19.852358) (xy 397.833829 -19.798375) (xy 397.833342 -19.771106)
			(xy 397.833342 -19.770598) (xy 397.833702 -19.74698) (xy 397.839567 -19.700108) (xy 397.845026 -19.677126)
			(xy 397.847331 -19.665153) (xy 397.841914 -19.641422) (xy 397.834612 -19.63166) (xy 397.812154 -19.604753)
			(xy 397.771703 -19.547514) (xy 397.75384 -19.51736) (xy 397.729964 -19.518122) (xy 397.702693 -19.517713)
			(xy 397.648708 -19.509946) (xy 397.596377 -19.494576) (xy 397.546767 -19.471916) (xy 397.500885 -19.442426)
			(xy 397.459668 -19.406707) (xy 397.423953 -19.365486) (xy 397.394467 -19.319602) (xy 397.371811 -19.269989)
			(xy 397.356446 -19.217657) (xy 397.348684 -19.163671) (xy 394.757398 -19.163671) (xy 394.757398 -19.164369)
			(xy 394.749637 -19.218351) (xy 394.734273 -19.27068) (xy 394.711619 -19.32029) (xy 394.682136 -19.366171)
			(xy 394.646424 -19.40739) (xy 394.60521 -19.443107) (xy 394.559332 -19.472596) (xy 394.509725 -19.495256)
			(xy 394.457398 -19.510627) (xy 394.403417 -19.518394) (xy 394.376148 -19.518884) (xy 394.352272 -19.518122)
			(xy 394.334569 -19.548121) (xy 394.294501 -19.605105) (xy 394.272262 -19.631914) (xy 394.264926 -19.641664)
			(xy 394.259483 -19.66541) (xy 394.261848 -19.67738) (xy 394.26742 -19.700604) (xy 394.273403 -19.747988)
			(xy 394.273786 -19.771868) (xy 394.273269 -19.799137) (xy 394.265512 -19.853121) (xy 394.250151 -19.905451)
			(xy 394.227499 -19.955062) (xy 394.198017 -20.000945) (xy 394.162305 -20.042165) (xy 394.12109 -20.077883)
			(xy 394.075212 -20.107372) (xy 394.025604 -20.130031) (xy 393.973276 -20.1454) (xy 393.919293 -20.153165)
			(xy 393.892024 -20.15363) (xy 393.863234 -20.153086) (xy 393.806309 -20.144429) (xy 393.751329 -20.127322)
			(xy 393.699541 -20.102153) (xy 393.652119 -20.069494) (xy 393.61014 -20.030084) (xy 393.574553 -19.984818)
			(xy 393.546168 -19.934721) (xy 393.535408 -19.908012) (xy 393.530375 -19.896804) (xy 393.512069 -19.880477)
			(xy 393.500356 -19.87677) (xy 393.462578 -19.866544) (xy 393.389161 -19.839415) (xy 393.31891 -19.804907)
			(xy 393.285472 -19.784568) (xy 393.277211 -19.779872) (xy 393.258548 -19.776364) (xy 393.239885 -19.779872)
			(xy 393.231624 -19.784568) (xy 393.198483 -19.804722) (xy 393.128892 -19.83899) (xy 393.056187 -19.866032)
			(xy 393.018772 -19.876262) (xy 393.007195 -19.880053) (xy 392.989151 -19.896362) (xy 392.984228 -19.907504)
			(xy 392.973485 -19.934276) (xy 392.945092 -19.984489) (xy 392.909472 -20.029862) (xy 392.867435 -20.069364)
			(xy 392.819938 -20.102098) (xy 392.768059 -20.127318) (xy 392.712977 -20.144452) (xy 392.655946 -20.153111)
			(xy 392.627104 -20.15363) (xy 392.599832 -20.153195) (xy 392.545842 -20.145432) (xy 392.493507 -20.130065)
			(xy 392.443892 -20.107405) (xy 392.398006 -20.077915) (xy 392.356785 -20.042195) (xy 392.321068 -20.000971)
			(xy 392.291581 -19.955084) (xy 392.268925 -19.905467) (xy 392.253562 -19.853131) (xy 392.245803 -19.79914)
			(xy 392.245342 -19.771868) (xy 392.245342 -19.77136) (xy 392.245697 -19.747941) (xy 392.25143 -19.701454)
			(xy 392.256772 -19.67865) (xy 392.259032 -19.666649) (xy 392.253483 -19.642911) (xy 392.246104 -19.633184)
			(xy 392.223496 -19.606103) (xy 392.18279 -19.548482) (xy 392.164824 -19.518122) (xy 392.140948 -19.518884)
			(xy 392.113676 -19.51838) (xy 392.059687 -19.510624) (xy 392.007352 -19.495262) (xy 391.957736 -19.472609)
			(xy 391.911849 -19.443124) (xy 391.870625 -19.407409) (xy 391.834904 -19.36619) (xy 391.805414 -19.320307)
			(xy 391.782754 -19.270693) (xy 391.767387 -19.21836) (xy 391.759624 -19.164372) (xy 260.324092 -19.164372)
			(xy 260.324092 -20.40763) (xy 368.365788 -20.40763) (xy 368.369831 -20.311179) (xy 368.38193 -20.215404)
			(xy 368.402001 -20.120978) (xy 368.429903 -20.028562) (xy 368.46544 -19.938805) (xy 368.508363 -19.852337)
			(xy 368.558371 -19.769763) (xy 368.615114 -19.691664) (xy 368.678192 -19.618587) (xy 368.747165 -19.551044)
			(xy 368.821547 -19.48951) (xy 368.900817 -19.434415) (xy 368.98442 -19.386147) (xy 369.071768 -19.345044)
			(xy 369.16225 -19.311395) (xy 369.255229 -19.285434) (xy 369.350055 -19.267345) (xy 369.446063 -19.257254)
			(xy 369.542577 -19.255233) (xy 369.638923 -19.261294) (xy 369.734423 -19.275397) (xy 369.828408 -19.297441)
			(xy 369.92022 -19.327272) (xy 370.009213 -19.364681) (xy 370.094763 -19.409406) (xy 370.176271 -19.461132)
			(xy 370.253165 -19.519498) (xy 370.324905 -19.584093) (xy 370.390988 -19.654465) (xy 370.450951 -19.730119)
			(xy 370.504374 -19.810526) (xy 370.55088 -19.895121) (xy 370.590145 -19.983311) (xy 370.621892 -20.074477)
			(xy 370.6459 -20.167981) (xy 370.661999 -20.263165) (xy 370.670077 -20.359362) (xy 370.670582 -20.40763)
			(xy 370.670077 -20.455898) (xy 370.661999 -20.552095) (xy 370.6459 -20.647279) (xy 370.622976 -20.73656)
			(xy 440.464956 -20.73656) (xy 440.465378 -20.698271) (xy 440.471981 -20.621977) (xy 440.485126 -20.546534)
			(xy 440.504715 -20.472503) (xy 440.51728 -20.436332) (xy 440.51995 -20.4279) (xy 440.519937 -20.410225)
			(xy 440.51728 -20.401788) (xy 440.50475 -20.365606) (xy 440.485173 -20.291575) (xy 440.472022 -20.216136)
			(xy 440.465394 -20.139848) (xy 440.464956 -20.10156) (xy 440.46549 -20.057765) (xy 440.474106 -19.9706)
			(xy 440.49125 -19.884704) (xy 440.516756 -19.80091) (xy 440.550377 -19.72003) (xy 440.57062 -19.68119)
			(xy 440.576064 -19.669733) (xy 440.576046 -19.644397) (xy 440.57062 -19.63293) (xy 440.550398 -19.594081)
			(xy 440.51679 -19.513198) (xy 440.491286 -19.429406) (xy 440.474133 -19.343514) (xy 440.465497 -19.256354)
			(xy 440.464956 -19.21256) (xy 440.465378 -19.174271) (xy 440.471981 -19.097977) (xy 440.485126 -19.022534)
			(xy 440.504715 -18.948503) (xy 440.51728 -18.912332) (xy 440.51995 -18.9039) (xy 440.519937 -18.886225)
			(xy 440.51728 -18.877788) (xy 440.50475 -18.841606) (xy 440.485173 -18.767575) (xy 440.472022 -18.692136)
			(xy 440.465394 -18.615848) (xy 440.464956 -18.57756) (xy 440.465414 -18.53645) (xy 440.473005 -18.45458)
			(xy 440.488119 -18.373761) (xy 440.510626 -18.294681) (xy 440.540334 -18.218015) (xy 440.576991 -18.144418)
			(xy 440.620282 -18.074518) (xy 440.66984 -18.008911) (xy 440.72524 -17.948157) (xy 440.78601 -17.892775)
			(xy 440.851631 -17.843237) (xy 440.921544 -17.799965) (xy 440.995152 -17.76333) (xy 441.071826 -17.733644)
			(xy 441.150912 -17.71116) (xy 441.231736 -17.69607) (xy 441.313608 -17.688502) (xy 441.354718 -17.688052)
			(xy 441.395668 -17.688478) (xy 441.477223 -17.695989) (xy 441.557742 -17.710965) (xy 441.636544 -17.733279)
			(xy 441.712961 -17.762742) (xy 441.786347 -17.799105) (xy 441.856079 -17.842059) (xy 441.921567 -17.891241)
			(xy 441.982258 -17.946234) (xy 442.010292 -17.976088) (xy 442.017449 -17.983101) (xy 442.035585 -17.991562)
			(xy 442.055576 -17.99248) (xy 442.065156 -17.98955) (xy 442.102033 -17.976445) (xy 442.177582 -17.955997)
			(xy 442.254637 -17.94227) (xy 442.3326 -17.935373) (xy 442.371734 -17.93494) (xy 442.412849 -17.93538)
			(xy 442.494727 -17.942971) (xy 442.575557 -17.958083) (xy 442.654646 -17.980589) (xy 442.731323 -18.010296)
			(xy 442.804931 -18.046951) (xy 442.874843 -18.090241) (xy 442.940462 -18.139797) (xy 443.001229 -18.195196)
			(xy 443.056626 -18.255966) (xy 443.106179 -18.321587) (xy 443.149467 -18.391501) (xy 443.186119 -18.46511)
			(xy 443.213248 -18.535142) (xy 451.165468 -18.535142) (xy 451.165468 -18.534888) (xy 451.166052 -18.49015)
			(xy 451.175063 -18.401129) (xy 451.192964 -18.313462) (xy 451.219572 -18.228034) (xy 451.236588 -18.186654)
			(xy 451.240131 -18.177057) (xy 451.240147 -18.15662) (xy 451.236588 -18.14703) (xy 451.219555 -18.105656)
			(xy 451.192939 -18.020228) (xy 451.175038 -17.932559) (xy 451.166032 -17.843535) (xy 451.165468 -17.798796)
			(xy 451.165468 -17.798542) (xy 451.165972 -17.756194) (xy 451.174023 -17.67188) (xy 451.190052 -17.588714)
			(xy 451.213913 -17.507447) (xy 451.245392 -17.428817) (xy 451.284203 -17.353536) (xy 451.329993 -17.282284)
			(xy 451.382349 -17.215708) (xy 451.440797 -17.15441) (xy 451.504807 -17.098945) (xy 451.573799 -17.049816)
			(xy 451.647149 -17.007467) (xy 451.724192 -16.972283) (xy 451.804231 -16.944581) (xy 451.88654 -16.924613)
			(xy 451.970375 -16.91256) (xy 452.054976 -16.90853) (xy 452.139577 -16.91256) (xy 452.223412 -16.924613)
			(xy 452.305721 -16.944581) (xy 452.38576 -16.972283) (xy 452.462803 -17.007467) (xy 452.536153 -17.049816)
			(xy 452.605145 -17.098945) (xy 452.669155 -17.15441) (xy 452.727603 -17.215708) (xy 452.779959 -17.282284)
			(xy 452.825749 -17.353536) (xy 452.86456 -17.428817) (xy 452.896039 -17.507447) (xy 452.9199 -17.588714)
			(xy 452.935929 -17.67188) (xy 452.94398 -17.756194) (xy 452.944484 -17.798542) (xy 452.944484 -17.798796)
			(xy 452.943898 -17.843534) (xy 452.934888 -17.932555) (xy 452.916988 -18.020222) (xy 452.890379 -18.10565)
			(xy 452.873364 -18.14703) (xy 452.869775 -18.156614) (xy 452.869791 -18.177063) (xy 452.873364 -18.186654)
			(xy 452.890389 -18.228031) (xy 452.917007 -18.313458) (xy 452.934911 -18.401126) (xy 452.943919 -18.490149)
			(xy 452.944484 -18.534888) (xy 452.944484 -18.535142) (xy 452.94398 -18.57749) (xy 452.935929 -18.661804)
			(xy 452.9199 -18.74497) (xy 452.896039 -18.826237) (xy 452.86456 -18.904867) (xy 452.825749 -18.980148)
			(xy 452.779959 -19.0514) (xy 452.727603 -19.117976) (xy 452.669155 -19.179274) (xy 452.605145 -19.234739)
			(xy 452.536153 -19.283868) (xy 452.462803 -19.326217) (xy 452.38576 -19.361401) (xy 452.305721 -19.389103)
			(xy 452.223412 -19.409071) (xy 452.139577 -19.421124) (xy 452.054976 -19.425155) (xy 451.970375 -19.421124)
			(xy 451.88654 -19.409071) (xy 451.804231 -19.389103) (xy 451.724192 -19.361401) (xy 451.647149 -19.326217)
			(xy 451.573799 -19.283868) (xy 451.504807 -19.234739) (xy 451.440797 -19.179274) (xy 451.382349 -19.117976)
			(xy 451.329993 -19.0514) (xy 451.284203 -18.980148) (xy 451.245392 -18.904867) (xy 451.213913 -18.826237)
			(xy 451.190052 -18.74497) (xy 451.174023 -18.661804) (xy 451.165972 -18.57749) (xy 451.165468 -18.535142)
			(xy 443.213248 -18.535142) (xy 443.215823 -18.541788) (xy 443.238325 -18.620878) (xy 443.253434 -18.701708)
			(xy 443.261021 -18.783587) (xy 443.261496 -18.824702) (xy 443.261095 -18.862992) (xy 443.254486 -18.939286)
			(xy 443.241336 -19.014729) (xy 443.221741 -19.088759) (xy 443.209172 -19.12493) (xy 443.206519 -19.133366)
			(xy 443.20652 -19.151037) (xy 443.209172 -19.159474) (xy 443.221718 -19.195651) (xy 443.24129 -19.269684)
			(xy 443.254437 -19.345124) (xy 443.261061 -19.421414) (xy 443.261496 -19.459702) (xy 443.260982 -19.503497)
			(xy 443.252361 -19.590663) (xy 443.235212 -19.676559) (xy 443.209701 -19.760353) (xy 443.176076 -19.841233)
			(xy 443.155832 -19.880072) (xy 443.15041 -19.891537) (xy 443.150411 -19.916866) (xy 443.155832 -19.928332)
			(xy 443.176073 -19.967172) (xy 443.209679 -20.048057) (xy 443.235179 -20.131851) (xy 443.252328 -20.217745)
			(xy 443.260958 -20.304908) (xy 443.261496 -20.348702) (xy 443.261095 -20.386992) (xy 443.254486 -20.463286)
			(xy 443.241336 -20.538729) (xy 443.221741 -20.612759) (xy 443.209172 -20.64893) (xy 443.206519 -20.657366)
			(xy 443.20652 -20.675037) (xy 443.209172 -20.683474) (xy 443.221718 -20.719651) (xy 443.24129 -20.793684)
			(xy 443.254437 -20.869124) (xy 443.261061 -20.945414) (xy 443.261496 -20.983702) (xy 443.260989 -21.024815)
			(xy 443.253402 -21.106691) (xy 443.238293 -21.187518) (xy 443.215791 -21.266605) (xy 443.186088 -21.343279)
			(xy 443.149437 -21.416886) (xy 443.106152 -21.486797) (xy 443.0566 -21.552416) (xy 443.001205 -21.613183)
			(xy 442.94044 -21.66858) (xy 442.874823 -21.718133) (xy 442.804914 -21.761422) (xy 442.731309 -21.798075)
			(xy 442.654636 -21.827781) (xy 442.575549 -21.850286) (xy 442.494723 -21.865398) (xy 442.412847 -21.872988)
			(xy 442.371734 -21.873464) (xy 442.330778 -21.872996) (xy 442.249213 -21.865468) (xy 442.168686 -21.850472)
			(xy 442.089879 -21.828136) (xy 442.013459 -21.798648) (xy 441.940074 -21.762259) (xy 441.870346 -21.719277)
			(xy 441.804865 -21.670066) (xy 441.744186 -21.615042) (xy 441.71616 -21.585174) (xy 441.709037 -21.578124)
			(xy 441.690882 -21.569676) (xy 441.670879 -21.568774) (xy 441.661296 -21.571712) (xy 441.624502 -21.584749)
			(xy 441.549137 -21.605106) (xy 441.472276 -21.618771) (xy 441.394513 -21.625637) (xy 441.35548 -21.626068)
			(xy 441.354718 -21.626068) (xy 441.313612 -21.62557) (xy 441.23175 -21.617988) (xy 441.150936 -21.602885)
			(xy 441.07186 -21.580392) (xy 440.995197 -21.5507) (xy 440.9216 -21.514062) (xy 440.851696 -21.470791)
			(xy 440.786082 -21.421255) (xy 440.725318 -21.365878) (xy 440.669922 -21.305132) (xy 440.620366 -21.239533)
			(xy 440.577073 -21.169643) (xy 440.540412 -21.096058) (xy 440.510696 -21.019403) (xy 440.488178 -20.940335)
			(xy 440.473051 -20.859526) (xy 440.465443 -20.777666) (xy 440.464956 -20.73656) (xy 370.622976 -20.73656)
			(xy 370.621892 -20.740783) (xy 370.590145 -20.831949) (xy 370.55088 -20.920139) (xy 370.504374 -21.004734)
			(xy 370.450951 -21.085141) (xy 370.390988 -21.160795) (xy 370.324905 -21.231167) (xy 370.253165 -21.295762)
			(xy 370.176271 -21.354128) (xy 370.094763 -21.405854) (xy 370.009213 -21.450579) (xy 369.92022 -21.487988)
			(xy 369.828408 -21.517819) (xy 369.734423 -21.539863) (xy 369.638923 -21.553966) (xy 369.542577 -21.560027)
			(xy 369.446063 -21.558006) (xy 369.350055 -21.547915) (xy 369.255229 -21.529826) (xy 369.16225 -21.503865)
			(xy 369.071768 -21.470216) (xy 368.98442 -21.429113) (xy 368.900817 -21.380845) (xy 368.821547 -21.32575)
			(xy 368.747165 -21.264216) (xy 368.678192 -21.196673) (xy 368.615114 -21.123596) (xy 368.558371 -21.045497)
			(xy 368.508363 -20.962923) (xy 368.46544 -20.876455) (xy 368.429903 -20.786698) (xy 368.402001 -20.694282)
			(xy 368.38193 -20.599856) (xy 368.369831 -20.504081) (xy 368.365788 -20.40763) (xy 260.324092 -20.40763)
			(xy 260.324092 -25.982422) (xy 440.239912 -25.982422) (xy 440.240419 -25.939461) (xy 440.248702 -25.85394)
			(xy 440.265193 -25.769616) (xy 440.289738 -25.687275) (xy 440.322109 -25.607684) (xy 440.362003 -25.531586)
			(xy 440.40905 -25.459689) (xy 440.46281 -25.392664) (xy 440.522782 -25.331135) (xy 440.588408 -25.275676)
			(xy 440.659076 -25.226803) (xy 440.69635 -25.205436) (xy 440.704332 -25.200469) (xy 440.716316 -25.186006)
			(xy 440.719718 -25.177242) (xy 440.733823 -25.137039) (xy 440.768699 -25.059297) (xy 440.810847 -24.985247)
			(xy 440.859883 -24.915565) (xy 440.915357 -24.850891) (xy 440.97676 -24.791817) (xy 441.043529 -24.738885)
			(xy 441.115054 -24.692579) (xy 441.190679 -24.653323) (xy 441.26971 -24.621478) (xy 441.351424 -24.597336)
			(xy 441.435072 -24.581116) (xy 441.519887 -24.572969) (xy 441.56249 -24.572468) (xy 441.562998 -24.572468)
			(xy 441.606762 -24.572982) (xy 441.693869 -24.581557) (xy 441.77971 -24.598653) (xy 441.863455 -24.624106)
			(xy 441.944293 -24.657667) (xy 441.983114 -24.677878) (xy 441.994467 -24.683205) (xy 442.019513 -24.683205)
			(xy 442.030866 -24.677878) (xy 442.069745 -24.657673) (xy 442.150684 -24.6241) (xy 442.23453 -24.598641)
			(xy 442.320472 -24.581544) (xy 442.407677 -24.572973) (xy 442.45149 -24.572468) (xy 442.495305 -24.572971)
			(xy 442.582516 -24.581515) (xy 442.668462 -24.5986) (xy 442.752311 -24.62406) (xy 442.833246 -24.657648)
			(xy 442.872114 -24.677878) (xy 442.883467 -24.683205) (xy 442.908513 -24.683205) (xy 442.919866 -24.677878)
			(xy 442.959061 -24.657499) (xy 443.040701 -24.623735) (xy 443.125286 -24.598229) (xy 443.211982 -24.581233)
			(xy 443.255908 -24.576532) (xy 443.266358 -24.575008) (xy 443.284755 -24.564681) (xy 443.297434 -24.547819)
			(xy 443.300358 -24.53767) (xy 443.310609 -24.496358) (xy 443.337964 -24.415751) (xy 443.372893 -24.338124)
			(xy 443.415077 -24.264189) (xy 443.464129 -24.19462) (xy 443.519603 -24.130055) (xy 443.580989 -24.071084)
			(xy 443.647727 -24.018245) (xy 443.719207 -23.972023) (xy 443.794775 -23.932839) (xy 443.87374 -23.901052)
			(xy 443.955381 -23.876952) (xy 444.038949 -23.86076) (xy 444.123683 -23.852625) (xy 444.166244 -23.852124)
			(xy 444.207348 -23.852525) (xy 444.289205 -23.860114) (xy 444.370013 -23.875224) (xy 444.449082 -23.897725)
			(xy 444.525738 -23.927425) (xy 444.599326 -23.964072) (xy 444.669219 -24.007352) (xy 444.734821 -24.056897)
			(xy 444.795571 -24.112283) (xy 444.850952 -24.173038) (xy 444.900491 -24.238644) (xy 444.943765 -24.30854)
			(xy 444.980405 -24.382132) (xy 445.0101 -24.45879) (xy 445.032594 -24.537861) (xy 445.047697 -24.61867)
			(xy 445.055279 -24.700528) (xy 445.055752 -24.741632) (xy 445.055238 -24.782654) (xy 445.04768 -24.864348)
			(xy 445.032631 -24.944999) (xy 445.01022 -25.023921) (xy 444.980635 -25.100445) (xy 444.94413 -25.173919)
			(xy 444.901014 -25.243719) (xy 444.851653 -25.309252) (xy 444.796467 -25.369961) (xy 444.735925 -25.425331)
			(xy 444.670542 -25.47489) (xy 444.600873 -25.518217) (xy 444.52751 -25.554945) (xy 444.451076 -25.584761)
			(xy 444.372222 -25.607412) (xy 444.291617 -25.622705) (xy 444.250826 -25.627076) (xy 444.240379 -25.628618)
			(xy 444.221981 -25.638935) (xy 444.2093 -25.655791) (xy 444.206376 -25.665938) (xy 444.196473 -25.705794)
			(xy 444.170375 -25.783666) (xy 444.137208 -25.8588) (xy 444.097254 -25.930555) (xy 444.050854 -25.998321)
			(xy 443.998403 -26.061519) (xy 443.940348 -26.119612) (xy 443.877184 -26.172104) (xy 443.809448 -26.218548)
			(xy 443.773814 -26.238962) (xy 443.765845 -26.243946) (xy 443.753852 -26.258396) (xy 443.750446 -26.267156)
			(xy 443.736369 -26.307378) (xy 443.701515 -26.385148) (xy 443.659384 -26.459228) (xy 443.61036 -26.528939)
			(xy 443.554893 -26.593641) (xy 443.493492 -26.652741) (xy 443.42672 -26.705698) (xy 443.355189 -26.752025)
			(xy 443.279554 -26.791298) (xy 443.200511 -26.823158) (xy 443.118782 -26.847311) (xy 443.035118 -26.863536)
			(xy 442.950285 -26.871685) (xy 442.907674 -26.872184) (xy 442.863879 -26.871639) (xy 442.776715 -26.863025)
			(xy 442.690819 -26.845883) (xy 442.607025 -26.82038) (xy 442.526144 -26.786761) (xy 442.487304 -26.76652)
			(xy 442.475838 -26.761102) (xy 442.45051 -26.761102) (xy 442.439044 -26.76652) (xy 442.400209 -26.786769)
			(xy 442.319322 -26.820374) (xy 442.235526 -26.845873) (xy 442.149632 -26.863019) (xy 442.062468 -26.871647)
			(xy 442.018674 -26.872184) (xy 441.974879 -26.871639) (xy 441.887715 -26.863025) (xy 441.801819 -26.845883)
			(xy 441.718025 -26.82038) (xy 441.637144 -26.786761) (xy 441.598304 -26.76652) (xy 441.586838 -26.761102)
			(xy 441.56151 -26.761102) (xy 441.550044 -26.76652) (xy 441.511209 -26.786769) (xy 441.430322 -26.820374)
			(xy 441.346526 -26.845873) (xy 441.260632 -26.863019) (xy 441.173468 -26.871647) (xy 441.129674 -26.872184)
			(xy 441.08856 -26.871712) (xy 441.006683 -26.864123) (xy 440.925855 -26.849012) (xy 440.846767 -26.826507)
			(xy 440.770092 -26.796802) (xy 440.696485 -26.760149) (xy 440.626574 -26.71686) (xy 440.560955 -26.667306)
			(xy 440.500188 -26.61191) (xy 440.444791 -26.551142) (xy 440.395237 -26.485523) (xy 440.351949 -26.415612)
			(xy 440.315297 -26.342004) (xy 440.285592 -26.265329) (xy 440.263088 -26.186241) (xy 440.247977 -26.105413)
			(xy 440.240388 -26.023536) (xy 440.239912 -25.982422) (xy 260.324092 -25.982422) (xy 260.324092 -32.117846)
			(xy 455.218281 -32.117846) (xy 455.218281 -31.988706) (xy 455.226231 -31.859811) (xy 455.242101 -31.731651)
			(xy 455.26583 -31.60471) (xy 455.297329 -31.479471) (xy 455.336478 -31.356408) (xy 455.383129 -31.235989)
			(xy 455.437104 -31.11867) (xy 455.498199 -31.004896) (xy 455.566182 -30.895099) (xy 455.640796 -30.789696)
			(xy 455.721757 -30.689086) (xy 455.808757 -30.593651) (xy 455.901468 -30.503752) (xy 455.999538 -30.419731)
			(xy 456.102593 -30.341907) (xy 456.210244 -30.270575) (xy 456.322083 -30.206005) (xy 456.437684 -30.148443)
			(xy 456.556609 -30.098106) (xy 456.678408 -30.055186) (xy 456.802618 -30.019845) (xy 456.928767 -29.992218)
			(xy 457.056379 -29.972409) (xy 457.184968 -29.960493) (xy 457.314046 -29.956517) (xy 457.443124 -29.960493)
			(xy 457.571713 -29.972409) (xy 457.699325 -29.992218) (xy 457.825474 -30.019845) (xy 457.949684 -30.055186)
			(xy 458.071483 -30.098106) (xy 458.190408 -30.148443) (xy 458.306009 -30.206005) (xy 458.417848 -30.270575)
			(xy 458.525499 -30.341907) (xy 458.628554 -30.419731) (xy 458.726624 -30.503752) (xy 458.819335 -30.593651)
			(xy 458.906335 -30.689086) (xy 458.987296 -30.789696) (xy 459.06191 -30.895099) (xy 459.129893 -31.004896)
			(xy 459.190988 -31.11867) (xy 459.244963 -31.235989) (xy 459.291614 -31.356408) (xy 459.330763 -31.479471)
			(xy 459.362262 -31.60471) (xy 459.385991 -31.731651) (xy 459.401861 -31.859811) (xy 459.409811 -31.988706)
			(xy 459.410308 -32.053276) (xy 459.409811 -32.117846) (xy 459.401861 -32.246741) (xy 459.385991 -32.374901)
			(xy 459.362262 -32.501842) (xy 459.330763 -32.627081) (xy 459.291614 -32.750144) (xy 459.244963 -32.870563)
			(xy 459.190988 -32.987882) (xy 459.129893 -33.101656) (xy 459.06191 -33.211453) (xy 458.987296 -33.316856)
			(xy 458.906335 -33.417466) (xy 458.819335 -33.512901) (xy 458.726624 -33.6028) (xy 458.628554 -33.686821)
			(xy 458.525499 -33.764645) (xy 458.417848 -33.835977) (xy 458.307206 -33.899856) (xy 461.798924 -33.899856)
			(xy 461.798924 -32.299656) (xy 461.799422 -32.222373) (xy 461.807378 -32.068013) (xy 461.823271 -31.914267)
			(xy 461.847057 -31.761543) (xy 461.878674 -31.610247) (xy 461.918037 -31.460778) (xy 461.965042 -31.313534)
			(xy 462.019566 -31.168904) (xy 462.081462 -31.027274) (xy 462.150567 -30.889017) (xy 462.226698 -30.754502)
			(xy 462.309652 -30.624083) (xy 462.399211 -30.498108) (xy 462.495135 -30.376911) (xy 462.597172 -30.260812)
			(xy 462.705049 -30.15012) (xy 462.818482 -30.045128) (xy 462.93717 -29.946115) (xy 463.060797 -29.853342)
			(xy 463.189036 -29.767057) (xy 463.321547 -29.687488) (xy 463.457979 -29.614846) (xy 463.597969 -29.549324)
			(xy 463.741146 -29.491095) (xy 463.887131 -29.440314) (xy 464.035537 -29.397115) (xy 464.185969 -29.361613)
			(xy 464.33803 -29.333903) (xy 464.491316 -29.314057) (xy 464.64542 -29.302128) (xy 464.799934 -29.298149)
			(xy 464.954448 -29.302128) (xy 465.108552 -29.314057) (xy 465.261838 -29.333903) (xy 465.413899 -29.361613)
			(xy 465.564331 -29.397115) (xy 465.712737 -29.440314) (xy 465.858722 -29.491095) (xy 466.001899 -29.549324)
			(xy 466.141889 -29.614846) (xy 466.278321 -29.687488) (xy 466.410832 -29.767057) (xy 466.539071 -29.853342)
			(xy 466.662698 -29.946115) (xy 466.781386 -30.045128) (xy 466.894819 -30.15012) (xy 467.002696 -30.260812)
			(xy 467.104733 -30.376911) (xy 467.200657 -30.498108) (xy 467.290216 -30.624083) (xy 467.37317 -30.754502)
			(xy 467.449301 -30.889017) (xy 467.518406 -31.027274) (xy 467.580302 -31.168904) (xy 467.634826 -31.313534)
			(xy 467.681831 -31.460778) (xy 467.721194 -31.610247) (xy 467.752811 -31.761543) (xy 467.776597 -31.914267)
			(xy 467.79249 -32.068013) (xy 467.800446 -32.222373) (xy 467.800944 -32.299656) (xy 467.800944 -33.899856)
			(xy 467.800446 -33.977139) (xy 467.79249 -34.131499) (xy 467.776597 -34.285245) (xy 467.752811 -34.437969)
			(xy 467.721194 -34.589265) (xy 467.681831 -34.738734) (xy 467.634826 -34.885978) (xy 467.580302 -35.030608)
			(xy 467.518406 -35.172238) (xy 467.449301 -35.310495) (xy 467.37317 -35.44501) (xy 467.290216 -35.575429)
			(xy 467.200657 -35.701404) (xy 467.104733 -35.822601) (xy 467.002696 -35.9387) (xy 466.894819 -36.049392)
			(xy 466.781386 -36.154384) (xy 466.662698 -36.253397) (xy 466.539071 -36.34617) (xy 466.410832 -36.432455)
			(xy 466.278321 -36.512024) (xy 466.141889 -36.584666) (xy 466.001899 -36.650188) (xy 465.858722 -36.708417)
			(xy 465.712737 -36.759198) (xy 465.564331 -36.802397) (xy 465.413899 -36.837899) (xy 465.261838 -36.865609)
			(xy 465.108552 -36.885455) (xy 464.954448 -36.897384) (xy 464.799934 -36.901364) (xy 464.64542 -36.897384)
			(xy 464.491316 -36.885455) (xy 464.33803 -36.865609) (xy 464.185969 -36.837899) (xy 464.035537 -36.802397)
			(xy 463.887131 -36.759198) (xy 463.741146 -36.708417) (xy 463.597969 -36.650188) (xy 463.457979 -36.584666)
			(xy 463.321547 -36.512024) (xy 463.189036 -36.432455) (xy 463.060797 -36.34617) (xy 462.93717 -36.253397)
			(xy 462.818482 -36.154384) (xy 462.705049 -36.049392) (xy 462.597172 -35.9387) (xy 462.495135 -35.822601)
			(xy 462.399211 -35.701404) (xy 462.309652 -35.575429) (xy 462.226698 -35.44501) (xy 462.150567 -35.310495)
			(xy 462.081462 -35.172238) (xy 462.019566 -35.030608) (xy 461.965042 -34.885978) (xy 461.918037 -34.738734)
			(xy 461.878674 -34.589265) (xy 461.847057 -34.437969) (xy 461.823271 -34.285245) (xy 461.807378 -34.131499)
			(xy 461.799422 -33.977139) (xy 461.798924 -33.899856) (xy 458.307206 -33.899856) (xy 458.306009 -33.900547)
			(xy 458.190408 -33.958109) (xy 458.071483 -34.008446) (xy 457.949684 -34.051366) (xy 457.825474 -34.086707)
			(xy 457.699325 -34.114334) (xy 457.571713 -34.134143) (xy 457.443124 -34.146059) (xy 457.314046 -34.150036)
			(xy 457.184968 -34.146059) (xy 457.056379 -34.134143) (xy 456.928767 -34.114334) (xy 456.802618 -34.086707)
			(xy 456.678408 -34.051366) (xy 456.556609 -34.008446) (xy 456.437684 -33.958109) (xy 456.322083 -33.900547)
			(xy 456.210244 -33.835977) (xy 456.102593 -33.764645) (xy 455.999538 -33.686821) (xy 455.901468 -33.6028)
			(xy 455.808757 -33.512901) (xy 455.721757 -33.417466) (xy 455.640796 -33.316856) (xy 455.566182 -33.211453)
			(xy 455.498199 -33.101656) (xy 455.437104 -32.987882) (xy 455.383129 -32.870563) (xy 455.336478 -32.750144)
			(xy 455.297329 -32.627081) (xy 455.26583 -32.501842) (xy 455.242101 -32.374901) (xy 455.226231 -32.246741)
			(xy 455.218281 -32.117846) (xy 260.324092 -32.117846) (xy 260.324092 -34.120074) (xy 260.323601 -34.203949)
			(xy 260.315621 -34.37151) (xy 260.299676 -34.538502) (xy 260.275804 -34.704545) (xy 260.244058 -34.869265)
			(xy 260.20451 -35.032287) (xy 260.15725 -35.193243) (xy 260.102385 -35.351768) (xy 260.040039 -35.507503)
			(xy 259.970354 -35.660095) (xy 259.893487 -35.809198) (xy 259.809612 -35.954475) (xy 259.71892 -36.095596)
			(xy 259.621615 -36.232243) (xy 259.517919 -36.364104) (xy 259.408066 -36.490882) (xy 259.292305 -36.612289)
			(xy 259.170898 -36.728051) (xy 259.044121 -36.837905) (xy 258.91226 -36.941602) (xy 258.775615 -37.038907)
			(xy 258.634494 -37.1296) (xy 258.489217 -37.213476) (xy 258.340115 -37.290344) (xy 258.187523 -37.360031)
			(xy 258.031789 -37.422377) (xy 257.873264 -37.477243) (xy 257.712308 -37.524504) (xy 257.549286 -37.564053)
			(xy 257.384567 -37.5958) (xy 257.218524 -37.619674) (xy 257.051532 -37.635619) (xy 256.883971 -37.643601)
			(xy 256.800096 -37.64407) (xy 225.300032 -37.64407) (xy 225.216157 -37.64358) (xy 225.048596 -37.635599)
			(xy 224.881605 -37.619655) (xy 224.715561 -37.595783) (xy 224.550842 -37.564037) (xy 224.38782 -37.524489)
			(xy 224.226864 -37.477229) (xy 224.068339 -37.422364) (xy 223.912605 -37.360019) (xy 223.760013 -37.290333)
			(xy 223.61091 -37.213466) (xy 223.465633 -37.129591) (xy 223.324512 -37.038899) (xy 223.187866 -36.941594)
			(xy 223.056005 -36.837898) (xy 222.929228 -36.728045) (xy 222.807821 -36.612284) (xy 222.692059 -36.490877)
			(xy 222.582206 -36.364099) (xy 222.478509 -36.232239) (xy 222.381205 -36.095593) (xy 222.290512 -35.954472)
			(xy 222.206637 -35.809195) (xy 222.12977 -35.660093) (xy 222.060084 -35.507501) (xy 221.997738 -35.351766)
			(xy 221.942873 -35.193242) (xy 221.895612 -35.032286) (xy 221.856064 -34.869264) (xy 221.824318 -34.704544)
			(xy 221.800446 -34.538501) (xy 221.784501 -34.37151) (xy 221.776521 -34.203949) (xy 221.776036 -34.120074)
			(xy 221.776036 -13.780008) (xy 221.775527 -13.748842) (xy 221.767392 -13.687042) (xy 221.751261 -13.626833)
			(xy 221.727409 -13.569244) (xy 221.696245 -13.515262) (xy 221.658302 -13.465808) (xy 221.614228 -13.42173)
			(xy 221.564778 -13.383782) (xy 221.510799 -13.352612) (xy 221.453212 -13.328754) (xy 221.393005 -13.312617)
			(xy 221.331206 -13.304476) (xy 221.30004 -13.304012) (xy 196.701918 -13.304012) (xy 196.615946 -13.303495)
			(xy 196.444208 -13.295111) (xy 196.273082 -13.278362) (xy 196.102977 -13.253287) (xy 195.934297 -13.219948)
			(xy 195.767443 -13.178422) (xy 195.602813 -13.128808) (xy 195.440798 -13.071226) (xy 195.281785 -13.005811)
			(xy 195.12615 -12.932719) (xy 194.974265 -12.852125) (xy 194.826491 -12.76422) (xy 194.683179 -12.669213)
			(xy 194.544671 -12.56733) (xy 194.411297 -12.458814) (xy 194.283372 -12.343924) (xy 194.161203 -12.222931)
			(xy 194.04508 -12.096125) (xy 193.935278 -11.963807) (xy 193.83206 -11.826291) (xy 193.783458 -11.755374)
			(xy 193.776849 -11.746538) (xy 193.758022 -11.735076) (xy 193.747136 -11.733276) (xy 193.73342 -11.73353)
			(xy 193.642742 -11.747754) (xy 193.635754 -11.749136) (xy 193.622868 -11.755196) (xy 193.617342 -11.759692)
			(xy 193.612008 -11.764264) (xy 193.604388 -11.776202) (xy 193.602102 -11.783314) (xy 193.587006 -11.83201)
			(xy 193.549479 -11.92681) (xy 193.503839 -12.017983) (xy 193.450433 -12.104834) (xy 193.389666 -12.186705)
			(xy 193.322001 -12.262973) (xy 193.285364 -12.298426) (xy 193.277744 -12.305792) (xy 193.27368 -12.31519)
			(xy 193.271729 -12.320171) (xy 193.269687 -12.330669) (xy 193.269616 -12.336018) (xy 193.270378 -12.41044)
			(xy 193.270378 -12.41298) (xy 193.271476 -12.422807) (xy 193.280102 -12.44058) (xy 193.287142 -12.447524)
			(xy 193.317409 -12.475579) (xy 193.373175 -12.536421) (xy 193.423068 -12.602166) (xy 193.466658 -12.672249)
			(xy 193.50357 -12.746067) (xy 193.533488 -12.822986) (xy 193.556154 -12.902346) (xy 193.571374 -12.983463)
			(xy 193.579016 -13.065642) (xy 193.579496 -13.106908) (xy 193.579035 -13.148011) (xy 193.57145 -13.229865)
			(xy 193.556344 -13.310671) (xy 193.533846 -13.389738) (xy 193.50415 -13.466392) (xy 193.467507 -13.539979)
			(xy 193.42423 -13.609871) (xy 193.37469 -13.675472) (xy 193.319308 -13.736222) (xy 193.258557 -13.791603)
			(xy 193.192955 -13.841142) (xy 193.123062 -13.884416) (xy 193.049474 -13.921058) (xy 192.972819 -13.950753)
			(xy 192.893752 -13.973248) (xy 192.812946 -13.988353) (xy 192.731091 -13.995936) (xy 192.689988 -13.996416)
			(xy 192.68948 -13.996416) (xy 192.643115 -13.995821) (xy 192.550889 -13.986178) (xy 192.460167 -13.966989)
			(xy 192.371936 -13.938461) (xy 192.329308 -13.920216) (xy 192.319366 -13.91641) (xy 192.298102 -13.91641)
			(xy 192.28816 -13.920216) (xy 192.245554 -13.938428) (xy 192.157385 -13.966933) (xy 192.06673 -13.986122)
			(xy 191.974573 -13.995786) (xy 191.928242 -13.996416) (xy 191.927734 -13.996416) (xy 191.886627 -13.995943)
			(xy 191.804763 -13.988361) (xy 191.723948 -13.973259) (xy 191.644871 -13.950766) (xy 191.568206 -13.921074)
			(xy 191.494608 -13.884435) (xy 191.424704 -13.841162) (xy 191.35909 -13.791625) (xy 191.298326 -13.736246)
			(xy 191.24293 -13.675497) (xy 191.193375 -13.609896) (xy 191.150083 -13.540004) (xy 191.113424 -13.466415)
			(xy 191.083711 -13.389758) (xy 191.061196 -13.310687) (xy 191.046072 -13.229876) (xy 191.038468 -13.148015)
			(xy 191.037972 -13.106908) (xy 191.0385 -13.063026) (xy 191.047142 -12.975689) (xy 191.064341 -12.889627)
			(xy 191.089932 -12.805677) (xy 191.123665 -12.724654) (xy 191.165212 -12.647348) (xy 191.21417 -12.574508)
			(xy 191.270063 -12.506843) (xy 191.332347 -12.445011) (xy 191.400417 -12.389613) (xy 191.473611 -12.341187)
			(xy 191.51219 -12.32027) (xy 191.51694 -12.317586) (xy 191.525266 -12.31054) (xy 191.5287 -12.3063)
			(xy 191.5414 -12.28979) (xy 191.544688 -12.285338) (xy 191.549425 -12.275339) (xy 191.550798 -12.269978)
			(xy 191.565276 -12.2047) (xy 191.566368 -12.199299) (xy 191.566494 -12.188282) (xy 191.56553 -12.182856)
			(xy 191.56299 -12.17168) (xy 191.556132 -12.16279) (xy 191.52726 -12.12452) (xy 191.47517 -12.044031)
			(xy 191.429852 -11.959544) (xy 191.391611 -11.871626) (xy 191.360705 -11.78087) (xy 191.337341 -11.687886)
			(xy 191.321677 -11.593301) (xy 191.313818 -11.497749) (xy 191.313308 -11.449812) (xy 191.313807 -11.401496)
			(xy 191.321785 -11.305194) (xy 191.337689 -11.209879) (xy 191.36141 -11.116203) (xy 191.392785 -11.024806)
			(xy 191.4316 -10.936313) (xy 191.477591 -10.851326) (xy 191.530442 -10.770428) (xy 191.589793 -10.69417)
			(xy 191.655239 -10.623074) (xy 191.726332 -10.557626) (xy 191.802587 -10.498271) (xy 191.883483 -10.445416)
			(xy 191.968468 -10.399422) (xy 192.05696 -10.360603) (xy 192.148355 -10.329224) (xy 192.24203 -10.3055)
			(xy 192.337344 -10.289592) (xy 192.433646 -10.281609) (xy 192.481962 -10.281158) (xy 192.53335 -10.281753)
			(xy 192.635723 -10.29085) (xy 192.736902 -10.308898) (xy 192.836107 -10.335758) (xy 192.932571 -10.371223)
			(xy 193.025549 -10.415018) (xy 193.070226 -10.440416) (xy 193.070734 -10.440416) (xy 193.070734 -10.44067)
			(xy 193.07919 -10.445027) (xy 193.098002 -10.447749) (xy 193.116511 -10.44342) (xy 193.124582 -10.438384)
			(xy 193.200782 -10.386568) (xy 193.206632 -10.382287) (xy 193.215794 -10.37106) (xy 193.218816 -10.36447)
			(xy 193.224404 -10.351516) (xy 193.22288 -10.341864) (xy 193.208562 -10.249169) (xy 193.18859 -10.06265)
			(xy 193.178567 -9.875332) (xy 193.177922 -9.78154) (xy 193.177922 -6.854698) (xy 193.177434 -6.844689)
			(xy 193.169775 -6.826194) (xy 193.155623 -6.812036) (xy 193.137131 -6.80437) (xy 193.127122 -6.803898)
			(xy 127.67691 -6.803898) (xy 127.666887 -6.804316) (xy 127.648367 -6.811984) (xy 127.634191 -6.826156)
			(xy 127.626518 -6.844675) (xy 127.62611 -6.854698) (xy 127.62611 -9.32434) (xy 127.626465 -9.33304)
			(xy 127.632285 -9.349438) (xy 127.643244 -9.362953) (xy 127.650494 -9.367774) (xy 127.72517 -9.412986)
			(xy 127.731774 -9.416288) (xy 127.742331 -9.420131) (xy 127.76475 -9.41921) (xy 127.774954 -9.41451)
			(xy 127.816791 -9.393142) (xy 127.903258 -9.356394) (xy 127.992395 -9.326704) (xy 128.083628 -9.304263)
			(xy 128.176367 -9.289215) (xy 128.270014 -9.281659) (xy 128.31699 -9.28116) (xy 128.365305 -9.281645)
			(xy 128.461606 -9.289624) (xy 128.55692 -9.305528) (xy 128.650594 -9.329249) (xy 128.741989 -9.360625)
			(xy 128.830482 -9.39944) (xy 128.915466 -9.445431) (xy 128.996363 -9.498283) (xy 129.072618 -9.557634)
			(xy 129.143712 -9.62308) (xy 129.209159 -9.694174) (xy 129.268511 -9.770429) (xy 129.321364 -9.851325)
			(xy 129.367355 -9.936309) (xy 129.406172 -10.024801) (xy 129.437548 -10.116197) (xy 129.461269 -10.209871)
			(xy 129.477174 -10.305184) (xy 129.485154 -10.401485) (xy 129.485154 -10.498115) (xy 129.477174 -10.594416)
			(xy 129.461269 -10.689729) (xy 129.437548 -10.783403) (xy 129.406172 -10.874799) (xy 129.367355 -10.963291)
			(xy 129.321364 -11.048275) (xy 129.268511 -11.129171) (xy 129.209159 -11.205426) (xy 129.143712 -11.27652)
			(xy 129.072618 -11.341966) (xy 128.996363 -11.401317) (xy 128.915466 -11.454169) (xy 128.830482 -11.50016)
			(xy 128.741989 -11.538975) (xy 128.650594 -11.570351) (xy 128.55692 -11.594072) (xy 128.461606 -11.609976)
			(xy 128.365305 -11.617955) (xy 128.31699 -11.618468) (xy 128.268974 -11.617965) (xy 128.173269 -11.610054)
			(xy 128.078536 -11.594319) (xy 127.985413 -11.570865) (xy 127.894527 -11.539851) (xy 127.806492 -11.501487)
			(xy 127.721901 -11.456029) (xy 127.641324 -11.403786) (xy 127.565304 -11.345109) (xy 127.494353 -11.280394)
			(xy 127.461264 -11.245596) (xy 127.46101 -11.245342) (xy 127.452008 -11.236723) (xy 127.428436 -11.228718)
			(xy 127.416052 -11.230102) (xy 127.332994 -11.243056) (xy 127.326807 -11.244259) (xy 127.315251 -11.24928)
			(xy 127.310134 -11.252962) (xy 127.305308 -11.256518) (xy 127.297434 -11.26617) (xy 127.294894 -11.271758)
			(xy 127.259208 -11.346958) (xy 127.181684 -11.494278) (xy 127.09729 -11.637774) (xy 127.006215 -11.777125)
			(xy 126.960963 -11.8397) (xy 129.452596 -11.8397) (xy 129.456508 -11.762557) (xy 129.468205 -11.686205)
			(xy 129.487567 -11.611429) (xy 129.514394 -11.538994) (xy 129.548412 -11.469646) (xy 129.589272 -11.404096)
			(xy 129.636553 -11.343015) (xy 129.689772 -11.287031) (xy 129.748381 -11.236719) (xy 129.81178 -11.192594)
			(xy 129.879318 -11.15511) (xy 129.950302 -11.124652) (xy 130.024002 -11.101531) (xy 130.099664 -11.085985)
			(xy 130.176511 -11.078173) (xy 130.215132 -11.077702) (xy 130.215386 -11.077702) (xy 130.258051 -11.078335)
			(xy 130.342845 -11.087888) (xy 130.426044 -11.106842) (xy 130.506608 -11.134961) (xy 130.583532 -11.171893)
			(xy 130.620008 -11.194034) (xy 130.630439 -11.199827) (xy 130.654176 -11.201938) (xy 130.665474 -11.198098)
			(xy 130.696302 -11.178748) (xy 130.760988 -11.145367) (xy 130.828558 -11.118295) (xy 130.898398 -11.097779)
			(xy 130.969874 -11.084004) (xy 131.042336 -11.077097) (xy 131.078732 -11.076686) (xy 131.094754 -11.076793)
			(xy 131.126769 -11.078192) (xy 131.14274 -11.07948) (xy 131.166108 -11.067288) (xy 131.220718 -10.978388)
			(xy 131.225056 -10.970396) (xy 131.228454 -10.952547) (xy 131.225437 -10.93463) (xy 131.221226 -10.926572)
			(xy 131.221226 -10.926064) (xy 131.208774 -10.904056) (xy 131.18914 -10.857458) (xy 131.175834 -10.808674)
			(xy 131.169091 -10.75856) (xy 131.168648 -10.733278) (xy 131.169207 -10.705124) (xy 131.177522 -10.649433)
			(xy 131.193923 -10.595566) (xy 131.218057 -10.544691) (xy 131.249398 -10.497911) (xy 131.267962 -10.476738)
			(xy 131.27593 -10.466914) (xy 131.282075 -10.442413) (xy 131.279646 -10.430002) (xy 131.268831 -10.384218)
			(xy 131.257241 -10.290858) (xy 131.256532 -10.24382) (xy 131.256532 -10.243312) (xy 131.257039 -10.20331)
			(xy 131.2654 -10.123746) (xy 131.282033 -10.045491) (xy 131.306755 -9.969403) (xy 131.339294 -9.896316)
			(xy 131.379295 -9.827031) (xy 131.42632 -9.762307) (xy 131.479852 -9.702853) (xy 131.539306 -9.649321)
			(xy 131.60403 -9.602296) (xy 131.673314 -9.562295) (xy 131.746401 -9.529755) (xy 131.822489 -9.505034)
			(xy 131.900744 -9.488401) (xy 131.980308 -9.480039) (xy 132.02031 -9.479534) (xy 132.063 -9.480135)
			(xy 132.147843 -9.489699) (xy 132.231091 -9.508661) (xy 132.311706 -9.536786) (xy 132.388683 -9.573723)
			(xy 132.425186 -9.595866) (xy 132.433447 -9.600562) (xy 132.45211 -9.60407) (xy 132.470773 -9.600562)
			(xy 132.479034 -9.595866) (xy 132.515528 -9.573706) (xy 132.592504 -9.536763) (xy 132.673121 -9.508638)
			(xy 132.756373 -9.489684) (xy 132.841219 -9.480137) (xy 132.88391 -9.479534) (xy 132.923912 -9.480018)
			(xy 133.003478 -9.488382) (xy 133.081733 -9.505017) (xy 133.157821 -9.52974) (xy 133.230908 -9.562282)
			(xy 133.300193 -9.602285) (xy 133.364917 -9.649311) (xy 133.424371 -9.702845) (xy 133.477903 -9.7623)
			(xy 133.524927 -9.827026) (xy 133.564928 -9.896312) (xy 133.597468 -9.969399) (xy 133.622189 -10.045488)
			(xy 133.638822 -10.123744) (xy 133.647183 -10.20331) (xy 133.647688 -10.243312) (xy 133.647688 -10.24382)
			(xy 133.646924 -10.29158) (xy 133.634947 -10.386346) (xy 133.623812 -10.432796) (xy 133.621329 -10.445123)
			(xy 133.627324 -10.46951) (xy 133.635242 -10.479278) (xy 133.653357 -10.500376) (xy 133.683946 -10.546812)
			(xy 133.707473 -10.597195) (xy 133.723441 -10.650458) (xy 133.731512 -10.705475) (xy 133.732016 -10.733278)
			(xy 133.731578 -10.760551) (xy 133.727935 -10.7859) (xy 169.57315 -10.7859) (xy 169.577062 -10.708754)
			(xy 169.588759 -10.6324) (xy 169.608121 -10.55762) (xy 169.634949 -10.485183) (xy 169.668967 -10.415832)
			(xy 169.709827 -10.350279) (xy 169.75711 -10.289195) (xy 169.810329 -10.233209) (xy 169.86894 -10.182893)
			(xy 169.93234 -10.138766) (xy 169.999879 -10.101279) (xy 170.070864 -10.070817) (xy 170.144567 -10.047692)
			(xy 170.220231 -10.032143) (xy 170.297079 -10.024329) (xy 170.335702 -10.023856) (xy 170.378393 -10.02445)
			(xy 170.463241 -10.033993) (xy 170.546493 -10.052948) (xy 170.627109 -10.081079) (xy 170.704081 -10.118033)
			(xy 170.740578 -10.140188) (xy 170.748834 -10.144902) (xy 170.767502 -10.148429) (xy 170.78617 -10.144902)
			(xy 170.794426 -10.140188) (xy 170.830905 -10.117999) (xy 170.90787 -10.081018) (xy 170.988489 -10.05288)
			(xy 171.07175 -10.033938) (xy 171.156608 -10.02443) (xy 171.199302 -10.023856) (xy 171.237919 -10.024433)
			(xy 171.314757 -10.032247) (xy 171.390411 -10.047794) (xy 171.464103 -10.070916) (xy 171.535078 -10.101374)
			(xy 171.602607 -10.138856) (xy 171.665998 -10.182977) (xy 171.7246 -10.233286) (xy 171.777812 -10.289265)
			(xy 171.825088 -10.35034) (xy 171.865942 -10.415884) (xy 171.899955 -10.485226) (xy 171.926779 -10.557652)
			(xy 171.946138 -10.632421) (xy 171.957834 -10.708765) (xy 171.961746 -10.7859) (xy 171.957834 -10.863035)
			(xy 171.946138 -10.939379) (xy 171.926779 -11.014148) (xy 171.899955 -11.086574) (xy 171.865942 -11.155916)
			(xy 171.825088 -11.22146) (xy 171.777812 -11.282535) (xy 171.7246 -11.338514) (xy 171.665998 -11.388823)
			(xy 171.602607 -11.432944) (xy 171.535078 -11.470426) (xy 171.464103 -11.500884) (xy 171.390411 -11.524006)
			(xy 171.314757 -11.539553) (xy 171.237919 -11.547367) (xy 171.199302 -11.547856) (xy 171.15661 -11.547273)
			(xy 171.071762 -11.53773) (xy 170.988509 -11.518773) (xy 170.907893 -11.490639) (xy 170.830923 -11.453681)
			(xy 170.794426 -11.431524) (xy 170.78617 -11.42681) (xy 170.767502 -11.423283) (xy 170.748834 -11.42681)
			(xy 170.740578 -11.431524) (xy 170.704098 -11.453713) (xy 170.627133 -11.490693) (xy 170.546514 -11.518831)
			(xy 170.463254 -11.537773) (xy 170.378396 -11.547281) (xy 170.335702 -11.547856) (xy 170.297079 -11.547471)
			(xy 170.220231 -11.539657) (xy 170.144567 -11.524108) (xy 170.070864 -11.500983) (xy 169.999879 -11.470521)
			(xy 169.93234 -11.433034) (xy 169.86894 -11.388907) (xy 169.810329 -11.338591) (xy 169.75711 -11.282605)
			(xy 169.709827 -11.221521) (xy 169.668967 -11.155968) (xy 169.634949 -11.086617) (xy 169.608121 -11.01418)
			(xy 169.588759 -10.9394) (xy 169.577062 -10.863046) (xy 169.57315 -10.7859) (xy 133.727935 -10.7859)
			(xy 133.723818 -10.814541) (xy 133.708452 -10.866877) (xy 133.685793 -10.916493) (xy 133.656304 -10.962379)
			(xy 133.620583 -11.0036) (xy 133.57936 -11.039318) (xy 133.533472 -11.068805) (xy 133.483854 -11.09146)
			(xy 133.431517 -11.106823) (xy 133.377527 -11.11458) (xy 133.350254 -11.11504) (xy 133.320564 -11.11445)
			(xy 133.261901 -11.105245) (xy 133.205373 -11.087066) (xy 133.152342 -11.060349) (xy 133.104089 -11.025742)
			(xy 133.082538 -11.005312) (xy 133.073181 -10.996983) (xy 133.049214 -10.989791) (xy 133.036818 -10.991596)
			(xy 132.999007 -10.998842) (xy 132.922406 -11.006599) (xy 132.88391 -11.00709) (xy 132.841221 -11.006476)
			(xy 132.756378 -10.996915) (xy 132.67313 -10.977955) (xy 132.592515 -10.949833) (xy 132.515538 -10.9129)
			(xy 132.479034 -10.890758) (xy 132.470773 -10.886062) (xy 132.45211 -10.882554) (xy 132.433447 -10.886062)
			(xy 132.425186 -10.890758) (xy 132.388682 -10.912901) (xy 132.31171 -10.949849) (xy 132.231095 -10.977978)
			(xy 132.147846 -10.996936) (xy 132.063 -11.006486) (xy 132.02031 -11.00709) (xy 132.019802 -11.00709)
			(xy 131.980849 -11.006554) (xy 131.903354 -10.998538) (xy 131.865116 -10.991088) (xy 131.852654 -10.989216)
			(xy 131.828536 -10.996405) (xy 131.819142 -11.004804) (xy 131.797568 -11.025348) (xy 131.749189 -11.060112)
			(xy 131.696005 -11.086951) (xy 131.639301 -11.105216) (xy 131.58045 -11.114466) (xy 131.550664 -11.11504)
			(xy 131.55041 -11.11504) (xy 131.534662 -11.114786) (xy 131.524493 -11.114951) (xy 131.505496 -11.122139)
			(xy 131.490774 -11.136135) (xy 131.482635 -11.154745) (xy 131.482352 -11.175055) (xy 131.48997 -11.193884)
			(xy 131.496816 -11.2014) (xy 131.528192 -11.222509) (xy 131.587043 -11.270003) (xy 131.640908 -11.323086)
			(xy 131.689257 -11.381237) (xy 131.731616 -11.443886) (xy 131.767569 -11.510419) (xy 131.796765 -11.580181)
			(xy 131.818916 -11.65249) (xy 131.833805 -11.726635) (xy 131.841286 -11.801889) (xy 131.841748 -11.839702)
			(xy 131.841195 -11.879662) (xy 131.832841 -11.959143) (xy 131.816225 -12.037316) (xy 131.79153 -12.113323)
			(xy 131.759024 -12.186333) (xy 131.719065 -12.255546) (xy 131.672091 -12.320202) (xy 131.618616 -12.379595)
			(xy 131.559226 -12.433072) (xy 131.494571 -12.480049) (xy 131.468639 -12.495022) (xy 134.764018 -12.495022)
			(xy 134.764574 -12.465509) (xy 134.773662 -12.407188) (xy 134.791625 -12.350962) (xy 134.818034 -12.298174)
			(xy 134.852259 -12.250084) (xy 134.872476 -12.228576) (xy 134.878497 -12.221781) (xy 134.885815 -12.205181)
			(xy 134.886933 -12.187075) (xy 134.884668 -12.178284) (xy 134.874112 -12.142106) (xy 134.859315 -12.068207)
			(xy 134.851864 -11.993209) (xy 134.851394 -11.955526) (xy 134.851394 -11.955018) (xy 134.851962 -11.915019)
			(xy 134.860323 -11.835458) (xy 134.876953 -11.757208) (xy 134.901672 -11.681124) (xy 134.934208 -11.608041)
			(xy 134.974206 -11.538759) (xy 135.021226 -11.474038) (xy 135.074753 -11.414586) (xy 135.134202 -11.361055)
			(xy 135.198921 -11.314031) (xy 135.2682 -11.274029) (xy 135.341281 -11.241489) (xy 135.417363 -11.216765)
			(xy 135.495613 -11.20013) (xy 135.575173 -11.191765) (xy 135.615172 -11.19124) (xy 135.658037 -11.191827)
			(xy 135.743229 -11.201424) (xy 135.826811 -11.2205) (xy 135.90773 -11.248817) (xy 135.98497 -11.286017)
			(xy 136.021572 -11.308334) (xy 136.031867 -11.314075) (xy 136.055291 -11.316461) (xy 136.06653 -11.312906)
			(xy 136.097322 -11.293682) (xy 136.161861 -11.260447) (xy 136.229265 -11.233491) (xy 136.298924 -11.213057)
			(xy 136.370209 -11.19933) (xy 136.442475 -11.192434) (xy 136.478772 -11.192002) (xy 136.518734 -11.192516)
			(xy 136.598219 -11.200867) (xy 136.676396 -11.217482) (xy 136.752408 -11.242178) (xy 136.825422 -11.274684)
			(xy 136.894639 -11.314644) (xy 136.959298 -11.361621) (xy 137.018693 -11.4151) (xy 137.072173 -11.474494)
			(xy 137.11915 -11.539153) (xy 137.159112 -11.608369) (xy 137.191619 -11.681382) (xy 137.216316 -11.757394)
			(xy 137.232931 -11.835571) (xy 137.241284 -11.915056) (xy 137.241788 -11.955018) (xy 137.241316 -11.994475)
			(xy 137.233204 -12.07297) (xy 137.217026 -12.150208) (xy 137.205466 -12.187936) (xy 137.204752 -12.199206)
			(xy 137.212025 -12.22056) (xy 137.219436 -12.229084) (xy 137.239582 -12.250561) (xy 137.273645 -12.298593)
			(xy 137.299926 -12.351287) (xy 137.317799 -12.407394) (xy 137.326842 -12.46558) (xy 137.327386 -12.495022)
			(xy 137.326896 -12.522291) (xy 137.319132 -12.576273) (xy 137.303765 -12.628601) (xy 137.281108 -12.67821)
			(xy 137.251622 -12.724089) (xy 137.215907 -12.765306) (xy 137.174691 -12.801021) (xy 137.128811 -12.830507)
			(xy 137.079203 -12.853164) (xy 137.026875 -12.868532) (xy 136.972893 -12.876296) (xy 136.945624 -12.876784)
			(xy 136.916464 -12.876283) (xy 136.858823 -12.867409) (xy 136.803204 -12.849864) (xy 136.750905 -12.824056)
			(xy 136.703144 -12.790588) (xy 136.661034 -12.75024) (xy 136.642856 -12.727432) (xy 136.635612 -12.718959)
			(xy 136.615853 -12.708686) (xy 136.604756 -12.70762) (xy 136.573489 -12.712504) (xy 136.510416 -12.717721)
			(xy 136.478772 -12.718034) (xy 136.442474 -12.717605) (xy 136.370207 -12.71071) (xy 136.298921 -12.696985)
			(xy 136.22926 -12.676555) (xy 136.161854 -12.649602) (xy 136.097311 -12.616372) (xy 136.06653 -12.59713)
			(xy 136.055295 -12.593522) (xy 136.031849 -12.595904) (xy 136.021572 -12.601702) (xy 135.984977 -12.624031)
			(xy 135.907735 -12.66123) (xy 135.826814 -12.689546) (xy 135.743231 -12.708622) (xy 135.658038 -12.718219)
			(xy 135.615172 -12.718796) (xy 135.614156 -12.718796) (xy 135.584438 -12.718468) (xy 135.525189 -12.713763)
			(xy 135.495792 -12.709398) (xy 135.486762 -12.708385) (xy 135.468982 -12.712068) (xy 135.453603 -12.721722)
			(xy 135.447786 -12.728702) (xy 135.429581 -12.751334) (xy 135.387475 -12.791338) (xy 135.339798 -12.824506)
			(xy 135.287649 -12.850075) (xy 135.232231 -12.867454) (xy 135.17482 -12.876244) (xy 135.14578 -12.876784)
			(xy 135.118511 -12.876294) (xy 135.064529 -12.86853) (xy 135.012201 -12.853164) (xy 134.962592 -12.830507)
			(xy 134.916712 -12.801021) (xy 134.875495 -12.765306) (xy 134.83978 -12.724089) (xy 134.810294 -12.67821)
			(xy 134.787637 -12.628601) (xy 134.77227 -12.576273) (xy 134.764506 -12.522291) (xy 134.764018 -12.495022)
			(xy 131.468639 -12.495022) (xy 131.42536 -12.520011) (xy 131.352351 -12.552519) (xy 131.276345 -12.577218)
			(xy 131.198172 -12.593837) (xy 131.118692 -12.602193) (xy 131.078732 -12.602718) (xy 131.042335 -12.602339)
			(xy 130.96987 -12.595436) (xy 130.898392 -12.58166) (xy 130.828552 -12.561136) (xy 130.760984 -12.534053)
			(xy 130.696304 -12.500655) (xy 130.665474 -12.481306) (xy 130.654174 -12.477509) (xy 130.630459 -12.479635)
			(xy 130.620008 -12.48537) (xy 130.58354 -12.507528) (xy 130.506626 -12.544496) (xy 130.426062 -12.572632)
			(xy 130.342857 -12.591584) (xy 130.258054 -12.601113) (xy 130.215386 -12.601702) (xy 130.215132 -12.601702)
			(xy 130.176511 -12.601227) (xy 130.099664 -12.593415) (xy 130.024002 -12.577869) (xy 129.950302 -12.554748)
			(xy 129.879318 -12.52429) (xy 129.81178 -12.486806) (xy 129.748381 -12.442681) (xy 129.689772 -12.392369)
			(xy 129.636553 -12.336385) (xy 129.589272 -12.275304) (xy 129.548412 -12.209754) (xy 129.514394 -12.140406)
			(xy 129.487567 -12.067971) (xy 129.468205 -11.993195) (xy 129.456508 -11.916843) (xy 129.452596 -11.8397)
			(xy 126.960963 -11.8397) (xy 126.908663 -11.91202) (xy 126.80485 -12.042159) (xy 126.695009 -12.167251)
			(xy 126.579383 -12.287018) (xy 126.458232 -12.401192) (xy 126.331825 -12.509518) (xy 126.200445 -12.611755)
			(xy 126.064384 -12.707675) (xy 125.923945 -12.797064) (xy 125.779443 -12.879722) (xy 125.6312 -12.955465)
			(xy 125.479545 -13.024125) (xy 125.324818 -13.085547) (xy 125.167363 -13.139596) (xy 125.007532 -13.18615)
			(xy 124.845681 -13.225106) (xy 124.682172 -13.256376) (xy 124.517368 -13.279892) (xy 124.351638 -13.2956)
			(xy 124.18535 -13.303465) (xy 124.102114 -13.304012) (xy 83.70189 -13.304012) (xy 83.618015 -13.303513)
			(xy 83.450455 -13.29553) (xy 83.283465 -13.279584) (xy 83.117423 -13.255711) (xy 82.952705 -13.223964)
			(xy 82.789684 -13.184415) (xy 82.628729 -13.137154) (xy 82.470206 -13.082288) (xy 82.314472 -13.019942)
			(xy 82.161882 -12.950256) (xy 82.01278 -12.873388) (xy 81.867505 -12.789514) (xy 81.726385 -12.698821)
			(xy 81.58974 -12.601517) (xy 81.45788 -12.497821) (xy 81.331103 -12.387968) (xy 81.209696 -12.272208)
			(xy 81.093936 -12.150802) (xy 80.984083 -12.024025) (xy 80.880387 -11.892165) (xy 80.783082 -11.75552)
			(xy 80.69239 -11.6144) (xy 80.608514 -11.469125) (xy 80.531647 -11.320023) (xy 80.461961 -11.167433)
			(xy 80.399614 -11.0117) (xy 80.344748 -10.853176) (xy 80.297487 -10.692222) (xy 80.257938 -10.529201)
			(xy 80.22619 -10.364483) (xy 80.202316 -10.198441) (xy 80.18637 -10.031451) (xy 80.178388 -9.863891)
			(xy 80.177894 -9.780016) (xy 80.177894 -7.292594) (xy 80.177543 -7.283865) (xy 80.171662 -7.267428)
			(xy 80.160561 -7.253954) (xy 80.153256 -7.24916) (xy 80.07858 -7.203948) (xy 80.072859 -7.200702)
			(xy 80.060254 -7.196961) (xy 80.053688 -7.196582) (xy 80.040734 -7.196328) (xy 80.028796 -7.202678)
			(xy 79.986657 -7.224456) (xy 79.899501 -7.261909) (xy 79.809595 -7.292173) (xy 79.717531 -7.315048)
			(xy 79.623916 -7.330383) (xy 79.529365 -7.338077) (xy 79.481934 -7.338568) (xy 79.433617 -7.338084)
			(xy 79.337312 -7.330106) (xy 79.241995 -7.314203) (xy 79.148317 -7.290483) (xy 79.056918 -7.259108)
			(xy 78.968421 -7.220292) (xy 78.883433 -7.174301) (xy 78.802533 -7.121448) (xy 78.726274 -7.062096)
			(xy 78.655176 -6.996648) (xy 78.589726 -6.925552) (xy 78.530371 -6.849295) (xy 78.477516 -6.768396)
			(xy 78.431523 -6.683409) (xy 78.392704 -6.594914) (xy 78.361327 -6.503516) (xy 78.337604 -6.409838)
			(xy 78.321698 -6.314522) (xy 78.313718 -6.218217) (xy 78.313718 -6.121583) (xy 78.321698 -6.025278)
			(xy 78.337604 -5.929962) (xy 78.361327 -5.836284) (xy 78.392704 -5.744886) (xy 78.431523 -5.656391)
			(xy 78.477516 -5.571404) (xy 78.530371 -5.490505) (xy 78.589726 -5.414248) (xy 78.655176 -5.343152)
			(xy 78.726274 -5.277704) (xy 78.802533 -5.218352) (xy 78.883433 -5.165499) (xy 78.968421 -5.119508)
			(xy 79.056918 -5.080692) (xy 79.148317 -5.049317) (xy 79.241995 -5.025597) (xy 79.337312 -5.009694)
			(xy 79.433617 -5.001716) (xy 79.481934 -5.00126) (xy 79.529366 -5.001734) (xy 79.623919 -5.009422)
			(xy 79.717537 -5.024754) (xy 79.809603 -5.047628) (xy 79.899511 -5.077893) (xy 79.986668 -5.11535)
			(xy 80.028796 -5.13715) (xy 80.034733 -5.140039) (xy 80.047594 -5.14301) (xy 80.054196 -5.142992)
			(xy 80.06715 -5.142738) (xy 80.153256 -5.090668) (xy 80.16053 -5.085852) (xy 80.171569 -5.072356)
			(xy 80.177467 -5.05595) (xy 80.177894 -5.047234) (xy 80.177894 -1.5748) (xy 80.177474 -1.564779)
			(xy 80.169804 -1.546263) (xy 80.155632 -1.532092) (xy 80.137115 -1.524424) (xy 80.127094 -1.524)
			(xy 14.676882 -1.524) (xy 14.666877 -1.524491) (xy 14.648391 -1.532154) (xy 14.634244 -1.546306)
			(xy 14.626588 -1.564795) (xy 14.626082 -1.5748) (xy 14.626082 -4.044442) (xy 14.626439 -4.053139)
			(xy 14.632265 -4.06953) (xy 14.643232 -4.083033) (xy 14.650466 -4.087876) (xy 14.725142 -4.133088)
			(xy 14.731746 -4.13639) (xy 14.742304 -4.140239) (xy 14.764728 -4.13933) (xy 14.774926 -4.134612)
			(xy 14.816763 -4.113243) (xy 14.90323 -4.076493) (xy 14.992367 -4.0468) (xy 15.083599 -4.024357)
			(xy 15.176338 -4.009308) (xy 15.269986 -4.001749) (xy 15.316962 -4.001262) (xy 15.365277 -4.001761)
			(xy 15.461578 -4.009741) (xy 15.556891 -4.025646) (xy 15.650565 -4.049368) (xy 15.741959 -4.080744)
			(xy 15.830451 -4.11956) (xy 15.915435 -4.165551) (xy 15.996331 -4.218403) (xy 16.072586 -4.277755)
			(xy 16.14368 -4.343202) (xy 16.209126 -4.414295) (xy 16.268478 -4.49055) (xy 16.32133 -4.571446)
			(xy 16.367321 -4.656431) (xy 16.406137 -4.744922) (xy 16.437513 -4.836317) (xy 16.461234 -4.929991)
			(xy 16.477139 -5.025304) (xy 16.485119 -5.121605) (xy 16.485119 -5.218235) (xy 16.477139 -5.314536)
			(xy 16.461234 -5.409849) (xy 16.437513 -5.503523) (xy 16.406137 -5.594918) (xy 16.367321 -5.683409)
			(xy 16.32133 -5.768394) (xy 16.268478 -5.84929) (xy 16.209126 -5.925545) (xy 16.14368 -5.996638)
			(xy 16.072586 -6.062085) (xy 15.996331 -6.121437) (xy 15.915435 -6.174289) (xy 15.830451 -6.22028)
			(xy 15.741959 -6.259096) (xy 15.650565 -6.290472) (xy 15.556891 -6.314194) (xy 15.461578 -6.330099)
			(xy 15.365277 -6.338079) (xy 15.316962 -6.33857) (xy 15.269985 -6.338102) (xy 15.176334 -6.330558)
			(xy 15.083591 -6.315514) (xy 14.992358 -6.293068) (xy 14.903222 -6.263364) (xy 14.816762 -6.226594)
			(xy 14.774926 -6.20522) (xy 14.764708 -6.200573) (xy 14.742306 -6.19964) (xy 14.731746 -6.203442)
			(xy 14.725142 -6.206744) (xy 14.650466 -6.251956) (xy 14.643213 -6.256778) (xy 14.632234 -6.270282)
			(xy 14.626423 -6.286687) (xy 14.626082 -6.29539) (xy 14.626082 -6.598158) (xy 17.928336 -6.598158)
			(xy 17.928785 -6.570888) (xy 17.936553 -6.516903) (xy 17.951923 -6.464573) (xy 17.974584 -6.414963)
			(xy 18.004074 -6.369082) (xy 18.039793 -6.327865) (xy 18.081014 -6.29215) (xy 18.126898 -6.262665)
			(xy 18.17651 -6.240009) (xy 18.228842 -6.224644) (xy 18.282828 -6.216883) (xy 18.310098 -6.216396)
			(xy 18.310352 -6.216396) (xy 18.32991 -6.216904) (xy 18.340832 -6.217412) (xy 18.360898 -6.210046)
			(xy 18.429732 -6.140958) (xy 18.437352 -6.121146) (xy 18.436844 -6.110224) (xy 18.436336 -6.091174)
			(xy 18.4368 -6.063904) (xy 18.444565 -6.00992) (xy 18.459934 -5.95759) (xy 18.482593 -5.90798) (xy 18.512081 -5.862099)
			(xy 18.547799 -5.820882) (xy 18.589018 -5.785167) (xy 18.634901 -5.755682) (xy 18.684513 -5.733026)
			(xy 18.736843 -5.71766) (xy 18.790828 -5.709899) (xy 18.818098 -5.709412) (xy 18.846912 -5.709957)
			(xy 18.903884 -5.718626) (xy 18.958908 -5.735753) (xy 19.010736 -5.76095) (xy 19.058192 -5.793644)
			(xy 19.1002 -5.833094) (xy 19.135807 -5.878405) (xy 19.164205 -5.92855) (xy 19.174968 -5.955284)
			(xy 19.179948 -5.966342) (xy 19.197982 -5.98251) (xy 19.209512 -5.986272) (xy 19.246608 -5.996497)
			(xy 19.318699 -6.023417) (xy 19.387713 -6.057457) (xy 19.420586 -6.077458) (xy 19.428842 -6.082172)
			(xy 19.44751 -6.085699) (xy 19.466178 -6.082172) (xy 19.474434 -6.077458) (xy 19.507314 -6.05747)
			(xy 19.576331 -6.023439) (xy 19.648417 -5.99651) (xy 19.685508 -5.986272) (xy 19.697074 -5.982575)
			(xy 19.715116 -5.966379) (xy 19.720052 -5.955284) (xy 19.730809 -5.928545) (xy 19.759195 -5.878388)
			(xy 19.794796 -5.833065) (xy 19.836803 -5.793607) (xy 19.884262 -5.760909) (xy 19.936095 -5.735713)
			(xy 19.991127 -5.718592) (xy 20.048106 -5.709935) (xy 20.076922 -5.709412) (xy 20.087678 -5.709518)
			(xy 20.109154 -5.710789) (xy 20.119848 -5.711952) (xy 20.13077 -5.713222) (xy 20.151598 -5.706364)
			(xy 20.216368 -5.646674) (xy 20.224001 -5.639002) (xy 20.232543 -5.619137) (xy 20.232878 -5.60832)
			(xy 20.232878 -5.608066) (xy 20.232624 -5.597652) (xy 20.232624 -5.597398) (xy 20.233012 -5.572667)
			(xy 20.239384 -5.523618) (xy 20.245324 -5.499608) (xy 20.24796 -5.487606) (xy 20.242636 -5.463643)
			(xy 20.235164 -5.453888) (xy 20.218328 -5.43358) (xy 20.187184 -5.390997) (xy 20.172934 -5.368798)
			(xy 20.167913 -5.361485) (xy 20.153944 -5.350571) (xy 20.137101 -5.345041) (xy 20.12823 -5.344922)
			(xy 20.114768 -5.345176) (xy 20.087501 -5.344659) (xy 20.033523 -5.336894) (xy 19.981199 -5.321527)
			(xy 19.931595 -5.29887) (xy 19.88572 -5.269384) (xy 19.844507 -5.23367) (xy 19.808797 -5.192455)
			(xy 19.779315 -5.146577) (xy 19.756662 -5.096971) (xy 19.741299 -5.044646) (xy 19.733538 -4.990667)
			(xy 19.733538 -4.936133) (xy 19.741299 -4.882154) (xy 19.756662 -4.829829) (xy 19.779315 -4.780223)
			(xy 19.808797 -4.734345) (xy 19.844507 -4.69313) (xy 19.88572 -4.657416) (xy 19.931595 -4.62793)
			(xy 19.981199 -4.605273) (xy 20.033523 -4.589906) (xy 20.087501 -4.582141) (xy 20.114768 -4.581652)
			(xy 20.12823 -4.581906) (xy 20.137115 -4.581887) (xy 20.153993 -4.576362) (xy 20.167961 -4.565394)
			(xy 20.172934 -4.55803) (xy 20.187197 -4.53584) (xy 20.218338 -4.493256) (xy 20.235164 -4.47294)
			(xy 20.242454 -4.4631) (xy 20.247752 -4.439224) (xy 20.245324 -4.42722) (xy 20.239402 -4.403401)
			(xy 20.233034 -4.354733) (xy 20.232624 -4.330192) (xy 20.232624 -4.32943) (xy 20.233129 -4.30216)
			(xy 20.240887 -4.248176) (xy 20.256249 -4.195845) (xy 20.278902 -4.146233) (xy 20.308385 -4.100349)
			(xy 20.344098 -4.059129) (xy 20.385314 -4.023411) (xy 20.431194 -3.993923) (xy 20.480803 -3.971264)
			(xy 20.533133 -3.955896) (xy 20.587116 -3.948132) (xy 20.614386 -3.947668) (xy 20.643064 -3.948223)
			(xy 20.699774 -3.956808) (xy 20.754564 -3.973774) (xy 20.806203 -3.998738) (xy 20.85353 -4.03114)
			(xy 20.895483 -4.070252) (xy 20.931118 -4.115195) (xy 20.959635 -4.16496) (xy 20.970494 -4.191508)
			(xy 20.975545 -4.202654) (xy 20.99387 -4.218826) (xy 21.005546 -4.222496) (xy 21.044187 -4.232718)
			(xy 21.119277 -4.260121) (xy 21.191097 -4.295212) (xy 21.225256 -4.315968) (xy 21.233517 -4.320664)
			(xy 21.25218 -4.324172) (xy 21.270843 -4.320664) (xy 21.279104 -4.315968) (xy 21.3116 -4.29617) (xy 21.379787 -4.262386)
			(xy 21.450997 -4.235554) (xy 21.487638 -4.22529) (xy 21.499187 -4.221553) (xy 21.517238 -4.205386)
			(xy 21.522182 -4.194302) (xy 21.532946 -4.167515) (xy 21.561283 -4.117224) (xy 21.596866 -4.07177)
			(xy 21.638884 -4.032189) (xy 21.686379 -3.999381) (xy 21.738271 -3.974094) (xy 21.793378 -3.956905)
			(xy 21.850444 -3.948204) (xy 21.879306 -3.947668) (xy 21.906579 -3.948096) (xy 21.960568 -3.95586)
			(xy 22.012903 -3.971228) (xy 22.062519 -3.993889) (xy 22.108404 -4.02338) (xy 22.149624 -4.059101)
			(xy 22.185342 -4.100325) (xy 22.214829 -4.146213) (xy 22.237484 -4.19583) (xy 22.252848 -4.248167)
			(xy 22.260607 -4.302157) (xy 22.261068 -4.32943) (xy 22.261068 -4.329684) (xy 22.260713 -4.352127)
			(xy 22.255359 -4.396693) (xy 22.2504 -4.418584) (xy 22.248259 -4.430576) (xy 22.254089 -4.454188)
			(xy 22.261576 -4.463796) (xy 22.280605 -4.486153) (xy 22.31557 -4.533321) (xy 22.331426 -4.55803)
			(xy 22.336491 -4.56531) (xy 22.350438 -4.576235) (xy 22.367265 -4.581779) (xy 22.37613 -4.581906)
			(xy 22.389592 -4.581652) (xy 22.416864 -4.582087) (xy 22.470854 -4.589848) (xy 22.52319 -4.605215)
			(xy 22.572806 -4.627873) (xy 22.618692 -4.657361) (xy 22.659915 -4.69308) (xy 22.695634 -4.734302)
			(xy 22.725124 -4.780187) (xy 22.747783 -4.829803) (xy 22.76315 -4.882138) (xy 22.770912 -4.936128)
			(xy 22.770912 -4.990672) (xy 22.76315 -5.044662) (xy 22.747783 -5.096997) (xy 22.725124 -5.146613)
			(xy 22.695634 -5.192498) (xy 22.659915 -5.23372) (xy 22.618692 -5.269439) (xy 22.572806 -5.298927)
			(xy 22.52319 -5.321585) (xy 22.470854 -5.336952) (xy 22.416864 -5.344713) (xy 22.389592 -5.345176)
			(xy 22.37613 -5.344922) (xy 22.367246 -5.344972) (xy 22.350369 -5.35048) (xy 22.3364 -5.361438) (xy 22.331426 -5.368798)
			(xy 22.315577 -5.393512) (xy 22.280611 -5.44068) (xy 22.261576 -5.463032) (xy 22.254138 -5.472667)
			(xy 22.248292 -5.496257) (xy 22.2504 -5.508244) (xy 22.255355 -5.5302) (xy 22.260707 -5.574893) (xy 22.261068 -5.597398)
			(xy 22.261068 -5.597652) (xy 22.260814 -5.60832) (xy 22.261087 -5.619209) (xy 22.26963 -5.639219)
			(xy 22.277324 -5.646928) (xy 22.333966 -5.698998) (xy 22.342353 -5.705912) (xy 22.362998 -5.712636)
			(xy 22.373844 -5.711952) (xy 22.374352 -5.711952) (xy 22.385235 -5.710768) (xy 22.407093 -5.709497)
			(xy 22.41804 -5.709412) (xy 22.446855 -5.709921) (xy 22.503829 -5.718597) (xy 22.558854 -5.735729)
			(xy 22.610682 -5.760931) (xy 22.658138 -5.79363) (xy 22.700145 -5.833085) (xy 22.735751 -5.8784)
			(xy 22.764148 -5.928549) (xy 22.77491 -5.955284) (xy 22.77987 -5.966354) (xy 22.797917 -5.982517)
			(xy 22.809454 -5.986272) (xy 22.846546 -5.996509) (xy 22.918638 -6.023424) (xy 22.987654 -6.05746)
			(xy 23.020528 -6.077458) (xy 23.028784 -6.082172) (xy 23.047452 -6.085699) (xy 23.06612 -6.082172)
			(xy 23.074376 -6.077458) (xy 23.107251 -6.057462) (xy 23.17627 -6.023434) (xy 23.248358 -5.996508)
			(xy 23.28545 -5.986272) (xy 23.297006 -5.98255) (xy 23.315054 -5.966372) (xy 23.319994 -5.955284)
			(xy 23.330716 -5.92853) (xy 23.359106 -5.878371) (xy 23.394712 -5.833048) (xy 23.436723 -5.79359)
			(xy 23.484188 -5.760893) (xy 23.536027 -5.735701) (xy 23.591063 -5.718584) (xy 23.648046 -5.709932)
			(xy 23.676864 -5.709412) (xy 23.687684 -5.709512) (xy 23.709287 -5.710781) (xy 23.720044 -5.711952)
			(xy 23.730966 -5.713222) (xy 23.751794 -5.706364) (xy 23.816564 -5.646674) (xy 23.824196 -5.639002)
			(xy 23.832739 -5.619137) (xy 23.833074 -5.60832) (xy 23.833074 -5.608066) (xy 23.83282 -5.597398)
			(xy 23.83282 -5.59689) (xy 23.833164 -5.572356) (xy 23.83941 -5.523689) (xy 23.845266 -5.499862)
			(xy 23.84769 -5.487921) (xy 23.842376 -5.464176) (xy 23.835106 -5.454396) (xy 23.818263 -5.433961)
			(xy 23.787121 -5.391122) (xy 23.772876 -5.368798) (xy 23.76783 -5.361505) (xy 23.753872 -5.350587)
			(xy 23.737039 -5.345048) (xy 23.728172 -5.344922) (xy 23.71471 -5.345176) (xy 23.68744 -5.344685)
			(xy 23.633454 -5.336925) (xy 23.581122 -5.32156) (xy 23.531509 -5.298904) (xy 23.485626 -5.269417)
			(xy 23.444406 -5.233701) (xy 23.408689 -5.192482) (xy 23.379201 -5.1466) (xy 23.356544 -5.096988)
			(xy 23.341178 -5.044656) (xy 23.333415 -4.99067) (xy 23.333415 -4.93613) (xy 23.341178 -4.882144)
			(xy 23.356544 -4.829812) (xy 23.379201 -4.7802) (xy 23.408689 -4.734318) (xy 23.444406 -4.693099)
			(xy 23.485626 -4.657383) (xy 23.531509 -4.627896) (xy 23.581122 -4.60524) (xy 23.633454 -4.589875)
			(xy 23.68744 -4.582115) (xy 23.71471 -4.581652) (xy 23.728172 -4.581906) (xy 23.737055 -4.581845)
			(xy 23.75393 -4.576339) (xy 23.767901 -4.565388) (xy 23.772876 -4.55803) (xy 23.787116 -4.535702)
			(xy 23.818259 -4.492864) (xy 23.835106 -4.472432) (xy 23.842383 -4.462655) (xy 23.847696 -4.438909)
			(xy 23.845266 -4.426966) (xy 23.839442 -4.403133) (xy 23.8332 -4.354469) (xy 23.83282 -4.329938)
			(xy 23.83282 -4.32943) (xy 23.833329 -4.302161) (xy 23.841087 -4.248176) (xy 23.856448 -4.195846)
			(xy 23.879101 -4.146234) (xy 23.908584 -4.100351) (xy 23.944297 -4.059131) (xy 23.985512 -4.023413)
			(xy 24.031391 -3.993924) (xy 24.081 -3.971265) (xy 24.133329 -3.955897) (xy 24.187313 -3.948133)
			(xy 24.214582 -3.947668) (xy 24.24326 -3.948226) (xy 24.29997 -3.956811) (xy 24.35476 -3.973776)
			(xy 24.406398 -3.99874) (xy 24.453726 -4.031142) (xy 24.495678 -4.070253) (xy 24.531314 -4.115196)
			(xy 24.559831 -4.16496) (xy 24.57069 -4.191508) (xy 24.575743 -4.202653) (xy 24.594066 -4.218825)
			(xy 24.605742 -4.222496) (xy 24.644338 -4.232673) (xy 24.719335 -4.260005) (xy 24.791074 -4.295008)
			(xy 24.825198 -4.315714) (xy 24.833454 -4.320428) (xy 24.852122 -4.323955) (xy 24.87079 -4.320428)
			(xy 24.879046 -4.315714) (xy 24.911614 -4.295883) (xy 24.979971 -4.262085) (xy 25.051355 -4.235267)
			(xy 25.088088 -4.225036) (xy 25.09957 -4.221272) (xy 25.11747 -4.205091) (xy 25.122378 -4.194048)
			(xy 25.133104 -4.167257) (xy 25.161475 -4.117007) (xy 25.197082 -4.071595) (xy 25.239113 -4.032055)
			(xy 25.286614 -3.999287) (xy 25.338502 -3.974035) (xy 25.393598 -3.956874) (xy 25.450649 -3.948195)
			(xy 25.479502 -3.947668) (xy 25.506774 -3.9481) (xy 25.560764 -3.955863) (xy 25.613099 -3.971231)
			(xy 25.662714 -3.993891) (xy 25.708599 -4.023382) (xy 25.74982 -4.059102) (xy 25.785538 -4.100326)
			(xy 25.815024 -4.146214) (xy 25.83768 -4.195831) (xy 25.853044 -4.248167) (xy 25.860803 -4.302158)
			(xy 25.861264 -4.32943) (xy 25.861264 -4.330192) (xy 25.860889 -4.352571) (xy 25.855541 -4.397009)
			(xy 25.850596 -4.418838) (xy 25.84842 -4.430826) (xy 25.854274 -4.454444) (xy 25.861772 -4.46405)
			(xy 25.880728 -4.486352) (xy 25.915564 -4.533394) (xy 25.931368 -4.55803) (xy 25.936407 -4.56533)
			(xy 25.950366 -4.576252) (xy 25.967203 -4.581786) (xy 25.976072 -4.581906) (xy 25.989534 -4.581652)
			(xy 26.016803 -4.582113) (xy 26.070785 -4.589879) (xy 26.123112 -4.605248) (xy 26.17272 -4.627906)
			(xy 26.218598 -4.657394) (xy 26.259813 -4.693111) (xy 26.295526 -4.734329) (xy 26.32501 -4.78021)
			(xy 26.347664 -4.82982) (xy 26.363029 -4.882149) (xy 26.37079 -4.936131) (xy 26.37079 -4.990669)
			(xy 26.363029 -5.044651) (xy 26.347664 -5.09698) (xy 26.32501 -5.14659) (xy 26.295526 -5.192471)
			(xy 26.259813 -5.233689) (xy 26.218598 -5.269406) (xy 26.17272 -5.298894) (xy 26.123112 -5.321552)
			(xy 26.070785 -5.336921) (xy 26.016803 -5.344687) (xy 25.989534 -5.345176) (xy 25.976072 -5.344922)
			(xy 25.967186 -5.34493) (xy 25.950306 -5.350457) (xy 25.936339 -5.361431) (xy 25.931368 -5.368798)
			(xy 25.915572 -5.39344) (xy 25.880735 -5.440481) (xy 25.861772 -5.462778) (xy 25.854307 -5.472396)
			(xy 25.848478 -5.496) (xy 25.850596 -5.50799) (xy 25.855535 -5.52982) (xy 25.860884 -5.574258) (xy 25.861264 -5.596636)
			(xy 25.861264 -5.597398) (xy 25.86101 -5.608066) (xy 25.86101 -5.60832) (xy 25.861295 -5.619147)
			(xy 25.869856 -5.63902) (xy 25.87752 -5.646674) (xy 25.934162 -5.698998) (xy 25.94255 -5.70591) (xy 25.963194 -5.712636)
			(xy 25.97404 -5.711952) (xy 25.974548 -5.711952) (xy 25.985304 -5.710775) (xy 26.006908 -5.709507)
			(xy 26.017728 -5.709412) (xy 26.017982 -5.709412) (xy 26.046798 -5.709885) (xy 26.103774 -5.718566)
			(xy 26.1588 -5.735705) (xy 26.210628 -5.760912) (xy 26.258084 -5.793616) (xy 26.30009 -5.833075)
			(xy 26.335695 -5.878395) (xy 26.364091 -5.928547) (xy 26.374852 -5.955284) (xy 26.37984 -5.966337)
			(xy 26.397868 -5.982508) (xy 26.409396 -5.986272) (xy 26.446491 -5.9965) (xy 26.518582 -6.023419)
			(xy 26.587597 -6.057458) (xy 26.62047 -6.077458) (xy 26.628726 -6.082172) (xy 26.647394 -6.085699)
			(xy 26.666062 -6.082172) (xy 26.674318 -6.077458) (xy 26.7072 -6.057474) (xy 26.776216 -6.023441)
			(xy 26.848301 -5.996511) (xy 26.885392 -5.986272) (xy 26.896955 -5.982568) (xy 26.914999 -5.966377)
			(xy 26.919936 -5.955284) (xy 26.930706 -5.928551) (xy 26.959091 -5.878394) (xy 26.99469 -5.833072)
			(xy 27.036695 -5.793613) (xy 27.084152 -5.760914) (xy 27.135984 -5.735718) (xy 27.191013 -5.718596)
			(xy 27.24799 -5.709937) (xy 27.276806 -5.709412) (xy 27.287626 -5.709509) (xy 27.309229 -5.71078)
			(xy 27.319986 -5.711952) (xy 27.330908 -5.713222) (xy 27.351736 -5.706364) (xy 27.416506 -5.646674)
			(xy 27.424129 -5.638994) (xy 27.432679 -5.619136) (xy 27.433016 -5.60832) (xy 27.433016 -5.608066)
			(xy 27.432762 -5.597398) (xy 27.432762 -5.59689) (xy 27.433108 -5.572356) (xy 27.439353 -5.523689)
			(xy 27.445208 -5.499862) (xy 27.447623 -5.48792) (xy 27.442313 -5.464177) (xy 27.435048 -5.454396)
			(xy 27.418207 -5.433959) (xy 27.387064 -5.391122) (xy 27.372818 -5.368798) (xy 27.367807 -5.361477)
			(xy 27.353833 -5.350565) (xy 27.336986 -5.345039) (xy 27.328114 -5.344922) (xy 27.314652 -5.345176)
			(xy 27.287386 -5.344658) (xy 27.233409 -5.336891) (xy 27.181088 -5.321522) (xy 27.131485 -5.298864)
			(xy 27.085612 -5.269378) (xy 27.044402 -5.233664) (xy 27.008693 -5.192449) (xy 26.979213 -5.146573)
			(xy 26.956561 -5.096967) (xy 26.941198 -5.044644) (xy 26.933438 -4.990666) (xy 26.933438 -4.936134)
			(xy 26.941198 -4.882156) (xy 26.956561 -4.829833) (xy 26.979213 -4.780227) (xy 27.008693 -4.734351)
			(xy 27.044402 -4.693136) (xy 27.085612 -4.657422) (xy 27.131485 -4.627936) (xy 27.181088 -4.605278)
			(xy 27.233409 -4.589909) (xy 27.287386 -4.582142) (xy 27.314652 -4.581652) (xy 27.328114 -4.581906)
			(xy 27.336998 -4.581875) (xy 27.353876 -4.576356) (xy 27.367844 -4.565392) (xy 27.372818 -4.55803)
			(xy 27.387061 -4.535704) (xy 27.418202 -4.492865) (xy 27.435048 -4.472432) (xy 27.442321 -4.462652)
			(xy 27.447639 -4.438908) (xy 27.445208 -4.426966) (xy 27.439383 -4.403133) (xy 27.433142 -4.354469)
			(xy 27.432762 -4.329938) (xy 27.432762 -4.32943) (xy 27.433229 -4.302159) (xy 27.440988 -4.248171)
			(xy 27.456352 -4.195837) (xy 27.479008 -4.146222) (xy 27.508494 -4.100337) (xy 27.544212 -4.059116)
			(xy 27.585432 -4.023398) (xy 27.631317 -3.993911) (xy 27.680931 -3.971254) (xy 27.733265 -3.955889)
			(xy 27.787253 -3.94813) (xy 27.814524 -3.947668) (xy 27.843203 -3.94819) (xy 27.899915 -3.956781)
			(xy 27.954706 -3.973752) (xy 28.006345 -3.998721) (xy 28.053672 -4.031127) (xy 28.095623 -4.070244)
			(xy 28.131258 -4.11519) (xy 28.159774 -4.164958) (xy 28.170632 -4.191508) (xy 28.175713 -4.202637)
			(xy 28.194017 -4.218816) (xy 28.205684 -4.222496) (xy 28.244276 -4.232686) (xy 28.319274 -4.260013)
			(xy 28.391015 -4.29501) (xy 28.42514 -4.315714) (xy 28.433396 -4.320428) (xy 28.452064 -4.323955)
			(xy 28.470732 -4.320428) (xy 28.478988 -4.315714) (xy 28.511563 -4.295895) (xy 28.579917 -4.262092)
			(xy 28.651299 -4.235269) (xy 28.68803 -4.225036) (xy 28.699502 -4.221247) (xy 28.717408 -4.205084)
			(xy 28.72232 -4.194048) (xy 28.733011 -4.167242) (xy 28.761386 -4.11699) (xy 28.796998 -4.071578)
			(xy 28.839034 -4.032038) (xy 28.88654 -3.999271) (xy 28.938433 -3.974022) (xy 28.993534 -3.956866)
			(xy 29.050589 -3.948192) (xy 29.079444 -3.947668) (xy 29.106716 -3.948084) (xy 29.160704 -3.955852)
			(xy 29.213036 -3.971224) (xy 29.262649 -3.993888) (xy 29.308531 -4.023381) (xy 29.349749 -4.059104)
			(xy 29.385463 -4.100329) (xy 29.414948 -4.146217) (xy 29.437601 -4.195833) (xy 29.452964 -4.248169)
			(xy 29.460722 -4.302158) (xy 29.461206 -4.32943) (xy 29.461206 -4.330192) (xy 29.46083 -4.352571)
			(xy 29.455483 -4.397009) (xy 29.450538 -4.418838) (xy 29.448352 -4.430826) (xy 29.454211 -4.454445)
			(xy 29.461714 -4.46405) (xy 29.480672 -4.48635) (xy 29.515507 -4.533393) (xy 29.53131 -4.55803) (xy 29.536324 -4.56535)
			(xy 29.550294 -4.576268) (xy 29.567141 -4.581793) (xy 29.576014 -4.581906) (xy 29.589476 -4.581652)
			(xy 29.616749 -4.582086) (xy 29.670741 -4.589846) (xy 29.723078 -4.60521) (xy 29.772696 -4.627867)
			(xy 29.818584 -4.657355) (xy 29.859809 -4.693074) (xy 29.89553 -4.734296) (xy 29.925021 -4.780183)
			(xy 29.947681 -4.829799) (xy 29.963049 -4.882136) (xy 29.970812 -4.936127) (xy 29.970812 -4.990673)
			(xy 29.963049 -5.044664) (xy 29.947681 -5.097001) (xy 29.925021 -5.146617) (xy 29.89553 -5.192504)
			(xy 29.859809 -5.233726) (xy 29.818584 -5.269445) (xy 29.772696 -5.298933) (xy 29.723078 -5.32159)
			(xy 29.670741 -5.336954) (xy 29.616749 -5.344714) (xy 29.589476 -5.345176) (xy 29.576014 -5.344922)
			(xy 29.56713 -5.34496) (xy 29.550251 -5.350474) (xy 29.536283 -5.361435) (xy 29.53131 -5.368798)
			(xy 29.515512 -5.393438) (xy 29.480676 -5.440481) (xy 29.461714 -5.462778) (xy 29.454252 -5.472398)
			(xy 29.448419 -5.496001) (xy 29.450538 -5.50799) (xy 29.4555 -5.529945) (xy 29.460848 -5.574638)
			(xy 29.461206 -5.597144) (xy 29.461206 -5.597652) (xy 29.460952 -5.60832) (xy 29.461214 -5.619211)
			(xy 29.469764 -5.639221) (xy 29.477462 -5.646928) (xy 29.534104 -5.698998) (xy 29.542477 -5.705932)
			(xy 29.563133 -5.712644) (xy 29.573982 -5.711952) (xy 29.57449 -5.711952) (xy 29.585373 -5.710764)
			(xy 29.607231 -5.709496) (xy 29.618178 -5.709412) (xy 29.646994 -5.709888) (xy 29.70397 -5.718569)
			(xy 29.758995 -5.735707) (xy 29.810824 -5.760914) (xy 29.858279 -5.793617) (xy 29.900286 -5.833076)
			(xy 29.935891 -5.878395) (xy 29.964287 -5.928547) (xy 29.975048 -5.955284) (xy 29.980038 -5.966336)
			(xy 29.998065 -5.982507) (xy 30.009592 -5.986272) (xy 30.046687 -5.996501) (xy 30.118778 -6.023419)
			(xy 30.187793 -6.057458) (xy 30.220666 -6.077458) (xy 30.228922 -6.082172) (xy 30.24759 -6.085699)
			(xy 30.266258 -6.082172) (xy 30.274514 -6.077458) (xy 30.307396 -6.057474) (xy 30.376413 -6.023442)
			(xy 30.448497 -5.996511) (xy 30.485588 -5.986272) (xy 30.49715 -5.982567) (xy 30.515195 -5.966377)
			(xy 30.520132 -5.955284) (xy 30.530906 -5.928553) (xy 30.55929 -5.878396) (xy 30.594888 -5.833074)
			(xy 30.636893 -5.793615) (xy 30.684349 -5.760916) (xy 30.736181 -5.735719) (xy 30.791209 -5.718596)
			(xy 30.848186 -5.709937) (xy 30.877002 -5.709412) (xy 30.877256 -5.709412) (xy 30.88814 -5.709508)
			(xy 30.90987 -5.710777) (xy 30.92069 -5.711952) (xy 30.920944 -5.711952) (xy 30.931795 -5.712656)
			(xy 30.952457 -5.705945) (xy 30.960822 -5.698998) (xy 31.017464 -5.646674) (xy 31.025096 -5.639002)
			(xy 31.033639 -5.619137) (xy 31.033974 -5.60832) (xy 31.033974 -5.608066) (xy 31.03372 -5.597398)
			(xy 31.03372 -5.59689) (xy 31.034129 -5.572549) (xy 31.040367 -5.524268) (xy 31.046166 -5.500624)
			(xy 31.048485 -5.488652) (xy 31.043061 -5.464917) (xy 31.035752 -5.455158) (xy 31.018754 -5.434553)
			(xy 30.987355 -5.391333) (xy 30.973014 -5.368798) (xy 30.968005 -5.361475) (xy 30.95403 -5.350563)
			(xy 30.937182 -5.345038) (xy 30.92831 -5.344922) (xy 30.914848 -5.345176) (xy 30.887576 -5.344688)
			(xy 30.833586 -5.336932) (xy 30.781249 -5.32157) (xy 30.731632 -5.298916) (xy 30.685744 -5.269431)
			(xy 30.644519 -5.233715) (xy 30.608798 -5.192495) (xy 30.579307 -5.14661) (xy 30.556647 -5.096996)
			(xy 30.541279 -5.044661) (xy 30.533516 -4.990672) (xy 30.533516 -4.936128) (xy 30.541279 -4.882139)
			(xy 30.556647 -4.829804) (xy 30.579307 -4.78019) (xy 30.608798 -4.734305) (xy 30.644519 -4.693085)
			(xy 30.685744 -4.657369) (xy 30.731632 -4.627884) (xy 30.781249 -4.60523) (xy 30.833586 -4.589868)
			(xy 30.887576 -4.582112) (xy 30.914848 -4.581652) (xy 30.92831 -4.581906) (xy 30.937194 -4.581872)
			(xy 30.954071 -4.576354) (xy 30.96804 -4.565392) (xy 30.973014 -4.55803) (xy 30.987363 -4.5355) (xy 31.018763 -4.492283)
			(xy 31.035752 -4.47167) (xy 31.043099 -4.461927) (xy 31.048535 -4.438175) (xy 31.046166 -4.426204)
			(xy 31.040385 -4.402557) (xy 31.034139 -4.354278) (xy 31.03372 -4.329938) (xy 31.03372 -4.32943)
			(xy 31.034229 -4.302161) (xy 31.041987 -4.248176) (xy 31.057348 -4.195846) (xy 31.080001 -4.146234)
			(xy 31.109484 -4.100351) (xy 31.145197 -4.059131) (xy 31.186412 -4.023413) (xy 31.232291 -3.993924)
			(xy 31.2819 -3.971265) (xy 31.334229 -3.955897) (xy 31.388213 -3.948133) (xy 31.415482 -3.947668)
			(xy 31.44416 -3.948226) (xy 31.50087 -3.956811) (xy 31.55566 -3.973776) (xy 31.607298 -3.99874) (xy 31.654626 -4.031142)
			(xy 31.696578 -4.070253) (xy 31.732214 -4.115196) (xy 31.760731 -4.16496) (xy 31.77159 -4.191508)
			(xy 31.776488 -4.202765) (xy 31.794873 -4.218998) (xy 31.806642 -4.222496) (xy 31.845103 -4.232719)
			(xy 31.919839 -4.260073) (xy 31.99133 -4.295043) (xy 32.025336 -4.315714) (xy 32.033591 -4.320416)
			(xy 32.052227 -4.324018) (xy 32.0709 -4.320614) (xy 32.079184 -4.315968) (xy 32.111824 -4.296072)
			(xy 32.180345 -4.262174) (xy 32.251908 -4.235288) (xy 32.288734 -4.225036) (xy 32.300294 -4.221324)
			(xy 32.318342 -4.20514) (xy 32.323278 -4.194048) (xy 32.334004 -4.167257) (xy 32.362375 -4.117007)
			(xy 32.397982 -4.071595) (xy 32.440013 -4.032055) (xy 32.487514 -3.999287) (xy 32.539402 -3.974035)
			(xy 32.594498 -3.956874) (xy 32.651549 -3.948195) (xy 32.680402 -3.947668) (xy 32.707674 -3.9481)
			(xy 32.761664 -3.955863) (xy 32.813999 -3.971231) (xy 32.863614 -3.993891) (xy 32.909499 -4.023382)
			(xy 32.95072 -4.059102) (xy 32.986438 -4.100326) (xy 33.015924 -4.146214) (xy 33.03858 -4.195831)
			(xy 33.053944 -4.248167) (xy 33.061703 -4.302158) (xy 33.062164 -4.32943) (xy 33.062164 -4.329684)
			(xy 33.06185 -4.352318) (xy 33.0565 -4.39727) (xy 33.051496 -4.419346) (xy 33.04925 -4.431308) (xy 33.054971 -4.454929)
			(xy 33.062418 -4.464558) (xy 33.081235 -4.486744) (xy 33.115815 -4.533533) (xy 33.131506 -4.55803)
			(xy 33.136522 -4.565348) (xy 33.150491 -4.576267) (xy 33.167338 -4.581792) (xy 33.17621 -4.581906)
			(xy 33.189672 -4.581652) (xy 33.216945 -4.582086) (xy 33.270937 -4.589845) (xy 33.323275 -4.605209)
			(xy 33.372894 -4.627866) (xy 33.418782 -4.657354) (xy 33.460007 -4.693073) (xy 33.495729 -4.734295)
			(xy 33.525221 -4.780182) (xy 33.547881 -4.829799) (xy 33.563249 -4.882135) (xy 33.571012 -4.936127)
			(xy 33.571012 -4.990673) (xy 33.563249 -5.044665) (xy 33.547881 -5.097001) (xy 33.525221 -5.146618)
			(xy 33.495729 -5.192505) (xy 33.460007 -5.233727) (xy 33.418782 -5.269446) (xy 33.372894 -5.298934)
			(xy 33.323275 -5.321591) (xy 33.270937 -5.336955) (xy 33.216945 -5.344714) (xy 33.189672 -5.345176)
			(xy 33.17621 -5.344922) (xy 33.167325 -5.344957) (xy 33.150447 -5.350472) (xy 33.136479 -5.361435)
			(xy 33.131506 -5.368798) (xy 33.115819 -5.393297) (xy 33.081233 -5.440082) (xy 33.062418 -5.46227)
			(xy 33.054994 -5.471903) (xy 33.049306 -5.495517) (xy 33.051496 -5.507482) (xy 33.056478 -5.529562)
			(xy 33.061828 -5.574511) (xy 33.062164 -5.597144) (xy 33.062164 -5.597398) (xy 33.061674 -5.624667)
			(xy 33.053912 -5.678651) (xy 33.038547 -5.73098) (xy 33.015892 -5.78059) (xy 32.986406 -5.826471)
			(xy 32.950691 -5.867688) (xy 32.909474 -5.903404) (xy 32.863593 -5.93289) (xy 32.813984 -5.955546)
			(xy 32.761655 -5.970912) (xy 32.707671 -5.978673) (xy 32.680402 -5.97916) (xy 32.651551 -5.9786)
			(xy 32.594504 -5.969923) (xy 32.539411 -5.952764) (xy 32.487526 -5.927516) (xy 32.440028 -5.894751)
			(xy 32.397997 -5.855215) (xy 32.362391 -5.809809) (xy 32.334018 -5.759563) (xy 32.323278 -5.73278)
			(xy 32.318301 -5.721719) (xy 32.300267 -5.705549) (xy 32.288734 -5.701792) (xy 32.251903 -5.691556)
			(xy 32.18034 -5.664668) (xy 32.111823 -5.630759) (xy 32.079184 -5.61086) (xy 32.070921 -5.606153)
			(xy 32.052226 -5.602724) (xy 32.03357 -5.606353) (xy 32.025336 -5.611114) (xy 31.991332 -5.63179)
			(xy 31.919845 -5.666771) (xy 31.845106 -5.694122) (xy 31.806642 -5.704332) (xy 31.794981 -5.708029)
			(xy 31.776675 -5.724196) (xy 31.77159 -5.73532) (xy 31.760705 -5.76186) (xy 31.732208 -5.811642)
			(xy 31.696586 -5.856601) (xy 31.654641 -5.895726) (xy 31.607315 -5.928138) (xy 31.555673 -5.953106)
			(xy 31.500878 -5.97007) (xy 31.444162 -5.978646) (xy 31.415482 -5.97916) (xy 31.415228 -5.97916)
			(xy 31.404344 -5.979066) (xy 31.382614 -5.977796) (xy 31.371794 -5.97662) (xy 31.37154 -5.97662)
			(xy 31.360688 -5.975889) (xy 31.340024 -5.982616) (xy 31.331662 -5.989574) (xy 31.27502 -6.041898)
			(xy 31.267398 -6.049579) (xy 31.25885 -6.069437) (xy 31.25851 -6.080252) (xy 31.25851 -6.080506)
			(xy 31.258764 -6.09092) (xy 31.258764 -6.091428) (xy 31.258256 -6.110224) (xy 31.257748 -6.121146)
			(xy 31.265368 -6.140958) (xy 31.334202 -6.210046) (xy 31.354268 -6.217412) (xy 31.36519 -6.216904)
			(xy 31.384748 -6.216396) (xy 31.385002 -6.216396) (xy 31.41227 -6.216922) (xy 31.466249 -6.224683)
			(xy 31.518576 -6.240047) (xy 31.568183 -6.2627) (xy 31.614062 -6.292182) (xy 31.655278 -6.327893)
			(xy 31.690994 -6.369106) (xy 31.720481 -6.414982) (xy 31.743139 -6.464587) (xy 31.758508 -6.516911)
			(xy 31.766275 -6.570891) (xy 31.766764 -6.598158) (xy 37.83838 -6.598158) (xy 37.838786 -6.570886)
			(xy 37.846554 -6.516897) (xy 37.861927 -6.464563) (xy 37.884591 -6.41495) (xy 37.914085 -6.369068)
			(xy 37.949809 -6.327849) (xy 37.991035 -6.292135) (xy 38.036924 -6.262651) (xy 38.086542 -6.239997)
			(xy 38.138879 -6.224636) (xy 38.19287 -6.21688) (xy 38.220142 -6.216396) (xy 38.220396 -6.216396)
			(xy 38.239954 -6.216904) (xy 38.250876 -6.217412) (xy 38.270942 -6.210046) (xy 38.339776 -6.140958)
			(xy 38.347396 -6.121146) (xy 38.346888 -6.110224) (xy 38.34638 -6.091174) (xy 38.346777 -6.0639)
			(xy 38.354544 -6.009909) (xy 38.369916 -5.957573) (xy 38.39258 -5.907957) (xy 38.422074 -5.862071)
			(xy 38.457798 -5.82085) (xy 38.499025 -5.785133) (xy 38.544916 -5.755647) (xy 38.594536 -5.732992)
			(xy 38.646876 -5.71763) (xy 38.700868 -5.709873) (xy 38.728142 -5.709412) (xy 38.756957 -5.709919)
			(xy 38.813931 -5.718595) (xy 38.868956 -5.735728) (xy 38.920784 -5.76093) (xy 38.96824 -5.793629)
			(xy 39.010248 -5.833084) (xy 39.045853 -5.8784) (xy 39.07425 -5.928548) (xy 39.085012 -5.955284)
			(xy 39.089971 -5.966354) (xy 39.108019 -5.982518) (xy 39.119556 -5.986272) (xy 39.156649 -5.996509)
			(xy 39.22874 -6.023424) (xy 39.297756 -6.05746) (xy 39.33063 -6.077458) (xy 39.338886 -6.082172)
			(xy 39.357554 -6.085699) (xy 39.376222 -6.082172) (xy 39.384478 -6.077458) (xy 39.417353 -6.057462)
			(xy 39.486372 -6.023434) (xy 39.55846 -5.996508) (xy 39.595552 -5.986272) (xy 39.607108 -5.98255)
			(xy 39.625156 -5.966373) (xy 39.630096 -5.955284) (xy 39.640816 -5.92853) (xy 39.669207 -5.87837)
			(xy 39.704812 -5.833047) (xy 39.746824 -5.793589) (xy 39.794289 -5.760893) (xy 39.846128 -5.7357)
			(xy 39.901164 -5.718584) (xy 39.958148 -5.709932) (xy 39.986966 -5.709412) (xy 39.997722 -5.709514)
			(xy 40.019198 -5.710787) (xy 40.029892 -5.711952) (xy 40.040814 -5.713222) (xy 40.061642 -5.706364)
			(xy 40.126412 -5.646674) (xy 40.134036 -5.638995) (xy 40.142585 -5.619136) (xy 40.142922 -5.60832)
			(xy 40.142922 -5.608066) (xy 40.142668 -5.597652) (xy 40.142668 -5.597398) (xy 40.143057 -5.572667)
			(xy 40.149429 -5.523618) (xy 40.155368 -5.499608) (xy 40.158016 -5.487607) (xy 40.152686 -5.463641)
			(xy 40.145208 -5.453888) (xy 40.128369 -5.433582) (xy 40.097227 -5.390998) (xy 40.082978 -5.368798)
			(xy 40.07793 -5.361506) (xy 40.063973 -5.350588) (xy 40.047141 -5.345049) (xy 40.038274 -5.344922)
			(xy 40.024812 -5.345176) (xy 39.997541 -5.344685) (xy 39.943555 -5.336925) (xy 39.891223 -5.32156)
			(xy 39.84161 -5.298904) (xy 39.795727 -5.269418) (xy 39.754507 -5.233702) (xy 39.718789 -5.192483)
			(xy 39.689302 -5.1466) (xy 39.666644 -5.096988) (xy 39.651278 -5.044656) (xy 39.643515 -4.990671)
			(xy 39.643515 -4.936129) (xy 39.651278 -4.882144) (xy 39.666644 -4.829812) (xy 39.689302 -4.7802)
			(xy 39.718789 -4.734317) (xy 39.754507 -4.693098) (xy 39.795727 -4.657382) (xy 39.84161 -4.627896)
			(xy 39.891223 -4.60524) (xy 39.943555 -4.589875) (xy 39.997541 -4.582115) (xy 40.024812 -4.581652)
			(xy 40.038274 -4.581906) (xy 40.047157 -4.581847) (xy 40.064033 -4.57634) (xy 40.078003 -4.565388)
			(xy 40.082978 -4.55803) (xy 40.097239 -4.535838) (xy 40.128382 -4.493255) (xy 40.145208 -4.47294)
			(xy 40.152494 -4.463097) (xy 40.157797 -4.439224) (xy 40.155368 -4.42722) (xy 40.149448 -4.4034)
			(xy 40.143078 -4.354733) (xy 40.142668 -4.330192) (xy 40.142668 -4.32943) (xy 40.143129 -4.302158)
			(xy 40.150888 -4.24817) (xy 40.166252 -4.195835) (xy 40.188909 -4.14622) (xy 40.218396 -4.100335)
			(xy 40.254114 -4.059114) (xy 40.295335 -4.023396) (xy 40.34122 -3.993909) (xy 40.390835 -3.971252)
			(xy 40.44317 -3.955888) (xy 40.497158 -3.948129) (xy 40.52443 -3.947668) (xy 40.553109 -3.948184)
			(xy 40.609821 -3.956777) (xy 40.664612 -3.973748) (xy 40.716251 -3.998718) (xy 40.763578 -4.031126)
			(xy 40.80553 -4.070242) (xy 40.841164 -4.11519) (xy 40.86968 -4.164958) (xy 40.880538 -4.191508)
			(xy 40.885617 -4.202638) (xy 40.903922 -4.218816) (xy 40.91559 -4.222496) (xy 40.954234 -4.232708)
			(xy 41.029323 -4.260115) (xy 41.101142 -4.29521) (xy 41.1353 -4.315968) (xy 41.143561 -4.320664)
			(xy 41.162224 -4.324172) (xy 41.180887 -4.320664) (xy 41.189148 -4.315968) (xy 41.221638 -4.296161)
			(xy 41.289828 -4.26238) (xy 41.36104 -4.235552) (xy 41.397682 -4.22529) (xy 41.409239 -4.221573)
			(xy 41.427285 -4.205391) (xy 41.432226 -4.194302) (xy 41.442954 -4.1675) (xy 41.471295 -4.117207)
			(xy 41.506882 -4.071752) (xy 41.548905 -4.032171) (xy 41.596407 -3.999365) (xy 41.648304 -3.974081)
			(xy 41.703416 -3.956896) (xy 41.760486 -3.9482) (xy 41.78935 -3.947668) (xy 41.816622 -3.948078)
			(xy 41.87061 -3.955847) (xy 41.922943 -3.97122) (xy 41.972555 -3.993885) (xy 42.018437 -4.023379)
			(xy 42.059655 -4.059102) (xy 42.095369 -4.100327) (xy 42.124854 -4.146215) (xy 42.147507 -4.195832)
			(xy 42.16287 -4.248168) (xy 42.170628 -4.302158) (xy 42.171112 -4.32943) (xy 42.171112 -4.329684)
			(xy 42.170756 -4.352127) (xy 42.165403 -4.396693) (xy 42.160444 -4.418584) (xy 42.158317 -4.430577)
			(xy 42.16414 -4.454186) (xy 42.17162 -4.463796) (xy 42.190646 -4.486155) (xy 42.225613 -4.533322)
			(xy 42.24147 -4.55803) (xy 42.246508 -4.565331) (xy 42.260467 -4.576253) (xy 42.277305 -4.581786)
			(xy 42.286174 -4.581906) (xy 42.299636 -4.581652) (xy 42.326905 -4.582113) (xy 42.380886 -4.589879)
			(xy 42.433214 -4.605248) (xy 42.482821 -4.627907) (xy 42.528699 -4.657395) (xy 42.569914 -4.693112)
			(xy 42.605627 -4.73433) (xy 42.63511 -4.780211) (xy 42.657765 -4.82982) (xy 42.673129 -4.882149)
			(xy 42.68089 -4.936131) (xy 42.68089 -4.990669) (xy 42.673129 -5.044651) (xy 42.657765 -5.09698)
			(xy 42.63511 -5.146589) (xy 42.605627 -5.19247) (xy 42.569914 -5.233688) (xy 42.528699 -5.269405)
			(xy 42.482821 -5.298893) (xy 42.433213 -5.321552) (xy 42.380886 -5.336921) (xy 42.326905 -5.344687)
			(xy 42.299636 -5.345176) (xy 42.286174 -5.344922) (xy 42.277288 -5.344932) (xy 42.260408 -5.350458)
			(xy 42.246441 -5.361431) (xy 42.24147 -5.368798) (xy 42.225619 -5.39351) (xy 42.190654 -5.440679)
			(xy 42.17162 -5.463032) (xy 42.164186 -5.47267) (xy 42.158336 -5.496258) (xy 42.160444 -5.508244)
			(xy 42.165398 -5.5302) (xy 42.170751 -5.574893) (xy 42.171112 -5.597398) (xy 42.171112 -5.597652)
			(xy 42.170858 -5.60832) (xy 42.171118 -5.619211) (xy 42.179669 -5.639222) (xy 42.187368 -5.646928)
			(xy 42.24401 -5.698998) (xy 42.252381 -5.705935) (xy 42.273038 -5.712646) (xy 42.283888 -5.711952)
			(xy 42.284396 -5.711952) (xy 42.295279 -5.710764) (xy 42.317137 -5.709496) (xy 42.328084 -5.709412)
			(xy 42.3569 -5.709883) (xy 42.413876 -5.718565) (xy 42.468902 -5.735704) (xy 42.52073 -5.760911)
			(xy 42.568186 -5.793615) (xy 42.610192 -5.833075) (xy 42.645797 -5.878394) (xy 42.674193 -5.928547)
			(xy 42.684954 -5.955284) (xy 42.689941 -5.966338) (xy 42.70797 -5.982508) (xy 42.719498 -5.986272)
			(xy 42.756593 -5.9965) (xy 42.828684 -6.023419) (xy 42.897699 -6.057458) (xy 42.930572 -6.077458)
			(xy 42.938828 -6.082172) (xy 42.957496 -6.085699) (xy 42.976164 -6.082172) (xy 42.98442 -6.077458)
			(xy 43.017302 -6.057473) (xy 43.086318 -6.023441) (xy 43.158403 -5.996511) (xy 43.195494 -5.986272)
			(xy 43.207057 -5.982569) (xy 43.225101 -5.966377) (xy 43.230038 -5.955284) (xy 43.240807 -5.92855)
			(xy 43.269191 -5.878393) (xy 43.30479 -5.833071) (xy 43.346796 -5.793612) (xy 43.394253 -5.760914)
			(xy 43.446085 -5.735717) (xy 43.501115 -5.718595) (xy 43.558092 -5.709937) (xy 43.586908 -5.709412)
			(xy 43.597728 -5.709509) (xy 43.619331 -5.71078) (xy 43.630088 -5.711952) (xy 43.64101 -5.713222)
			(xy 43.661838 -5.706364) (xy 43.726608 -5.646674) (xy 43.734232 -5.638994) (xy 43.742781 -5.619136)
			(xy 43.743118 -5.60832) (xy 43.743118 -5.608066) (xy 43.742864 -5.597398) (xy 43.742864 -5.59689)
			(xy 43.74321 -5.572356) (xy 43.749455 -5.523689) (xy 43.75531 -5.499862) (xy 43.757724 -5.48792)
			(xy 43.752415 -5.464177) (xy 43.74515 -5.454396) (xy 43.728309 -5.433959) (xy 43.697166 -5.391122)
			(xy 43.68292 -5.368798) (xy 43.677908 -5.361478) (xy 43.663934 -5.350566) (xy 43.647088 -5.345039)
			(xy 43.638216 -5.344922) (xy 43.624754 -5.345176) (xy 43.597488 -5.344658) (xy 43.543511 -5.336892)
			(xy 43.491189 -5.321523) (xy 43.441586 -5.298865) (xy 43.395713 -5.269379) (xy 43.354502 -5.233665)
			(xy 43.318793 -5.19245) (xy 43.289313 -5.146573) (xy 43.266661 -5.096968) (xy 43.251298 -5.044644)
			(xy 43.243538 -4.990666) (xy 43.243538 -4.936134) (xy 43.251298 -4.882156) (xy 43.266661 -4.829832)
			(xy 43.289313 -4.780227) (xy 43.318793 -4.73435) (xy 43.354502 -4.693135) (xy 43.395713 -4.657421)
			(xy 43.441586 -4.627935) (xy 43.491189 -4.605277) (xy 43.543511 -4.589908) (xy 43.597488 -4.582142)
			(xy 43.624754 -4.581652) (xy 43.638216 -4.581906) (xy 43.647101 -4.581876) (xy 43.663978 -4.576356)
			(xy 43.677946 -4.565393) (xy 43.68292 -4.55803) (xy 43.697163 -4.535704) (xy 43.728304 -4.492865)
			(xy 43.74515 -4.472432) (xy 43.752423 -4.462652) (xy 43.75774 -4.438908) (xy 43.75531 -4.426966)
			(xy 43.749485 -4.403133) (xy 43.743244 -4.354469) (xy 43.742864 -4.329938) (xy 43.742864 -4.32943)
			(xy 43.743329 -4.302159) (xy 43.751088 -4.24817) (xy 43.766452 -4.195836) (xy 43.789108 -4.146221)
			(xy 43.818595 -4.100336) (xy 43.854312 -4.059115) (xy 43.895533 -4.023397) (xy 43.941418 -3.99391)
			(xy 43.991032 -3.971253) (xy 44.043366 -3.955889) (xy 44.097355 -3.94813) (xy 44.124626 -3.947668)
			(xy 44.153305 -3.948188) (xy 44.210017 -3.956779) (xy 44.264808 -3.97375) (xy 44.316447 -3.99872)
			(xy 44.363774 -4.031127) (xy 44.405726 -4.070243) (xy 44.44136 -4.11519) (xy 44.469876 -4.164958)
			(xy 44.480734 -4.191508) (xy 44.485814 -4.202637) (xy 44.504118 -4.218816) (xy 44.515786 -4.222496)
			(xy 44.554378 -4.232686) (xy 44.629376 -4.260013) (xy 44.701117 -4.29501) (xy 44.735242 -4.315714)
			(xy 44.743498 -4.320428) (xy 44.762166 -4.323955) (xy 44.780834 -4.320428) (xy 44.78909 -4.315714)
			(xy 44.821665 -4.295895) (xy 44.890019 -4.262092) (xy 44.9614 -4.235269) (xy 44.998132 -4.225036)
			(xy 45.009604 -4.221247) (xy 45.027511 -4.205085) (xy 45.032422 -4.194048) (xy 45.043111 -4.167242)
			(xy 45.071487 -4.116989) (xy 45.107098 -4.071577) (xy 45.149135 -4.032037) (xy 45.196641 -3.999271)
			(xy 45.248535 -3.974022) (xy 45.303636 -3.956866) (xy 45.360691 -3.948192) (xy 45.389546 -3.947668)
			(xy 45.416818 -3.948082) (xy 45.470806 -3.95585) (xy 45.523138 -3.971223) (xy 45.572751 -3.993887)
			(xy 45.618633 -4.02338) (xy 45.659851 -4.059103) (xy 45.695565 -4.100328) (xy 45.72505 -4.146216)
			(xy 45.747703 -4.195833) (xy 45.763066 -4.248169) (xy 45.770824 -4.302158) (xy 45.771308 -4.32943)
			(xy 45.771308 -4.330192) (xy 45.770932 -4.352571) (xy 45.765585 -4.397009) (xy 45.76064 -4.418838)
			(xy 45.758454 -4.430826) (xy 45.764313 -4.454445) (xy 45.771816 -4.46405) (xy 45.790775 -4.48635)
			(xy 45.825613 -4.533391) (xy 45.841412 -4.55803) (xy 45.846424 -4.565351) (xy 45.860395 -4.576269)
			(xy 45.877243 -4.581793) (xy 45.886116 -4.581906) (xy 45.899578 -4.581652) (xy 45.926851 -4.582086)
			(xy 45.980842 -4.589846) (xy 46.033179 -4.605211) (xy 46.082797 -4.627868) (xy 46.128685 -4.657356)
			(xy 46.16991 -4.693075) (xy 46.205631 -4.734297) (xy 46.235121 -4.780183) (xy 46.257781 -4.8298)
			(xy 46.273149 -4.882136) (xy 46.280912 -4.936127) (xy 46.280912 -4.990673) (xy 46.273149 -5.044664)
			(xy 46.257781 -5.097) (xy 46.235121 -5.146617) (xy 46.205631 -5.192503) (xy 46.16991 -5.233725) (xy 46.128685 -5.269444)
			(xy 46.082797 -5.298932) (xy 46.033179 -5.321589) (xy 45.980842 -5.336954) (xy 45.926851 -5.344714)
			(xy 45.899578 -5.345176) (xy 45.886116 -5.344922) (xy 45.877232 -5.344961) (xy 45.860353 -5.350474)
			(xy 45.846385 -5.361436) (xy 45.841412 -5.368798) (xy 45.825614 -5.393438) (xy 45.790778 -5.440481)
			(xy 45.771816 -5.462778) (xy 45.764354 -5.472398) (xy 45.758521 -5.496001) (xy 45.76064 -5.50799)
			(xy 45.765579 -5.52982) (xy 45.770927 -5.574258) (xy 45.771308 -5.596636) (xy 45.771308 -5.597398)
			(xy 45.770774 -5.624665) (xy 45.763014 -5.678645) (xy 45.747651 -5.730971) (xy 45.724998 -5.780578)
			(xy 45.695517 -5.826456) (xy 45.659807 -5.867673) (xy 45.618595 -5.903388) (xy 45.57272 -5.932875)
			(xy 45.523116 -5.955534) (xy 45.470792 -5.970903) (xy 45.416813 -5.97867) (xy 45.389546 -5.97916)
			(xy 45.360696 -5.978563) (xy 45.303651 -5.969891) (xy 45.248559 -5.952739) (xy 45.196674 -5.927496)
			(xy 45.149175 -5.894736) (xy 45.107144 -5.855206) (xy 45.071536 -5.809803) (xy 45.043162 -5.759561)
			(xy 45.032422 -5.73278) (xy 45.027489 -5.721756) (xy 45.009598 -5.705584) (xy 44.998132 -5.701792)
			(xy 44.961402 -5.691552) (xy 44.890018 -5.664735) (xy 44.82166 -5.630941) (xy 44.78909 -5.611114)
			(xy 44.780834 -5.6064) (xy 44.762166 -5.602873) (xy 44.743498 -5.6064) (xy 44.735242 -5.611114) (xy 44.701118 -5.63182)
			(xy 44.62938 -5.666824) (xy 44.554381 -5.694152) (xy 44.515786 -5.704332) (xy 44.504084 -5.707945)
			(xy 44.485775 -5.724156) (xy 44.480734 -5.73532) (xy 44.469895 -5.761881) (xy 44.441393 -5.811664)
			(xy 44.405765 -5.856624) (xy 44.363813 -5.895749) (xy 44.31648 -5.928158) (xy 44.264831 -5.953123)
			(xy 44.21003 -5.970081) (xy 44.153309 -5.97865) (xy 44.124626 -5.97916) (xy 44.113806 -5.979061)
			(xy 44.092203 -5.977791) (xy 44.081446 -5.97662) (xy 44.070524 -5.97535) (xy 44.049696 -5.982208)
			(xy 43.984926 -6.041898) (xy 43.977305 -6.049579) (xy 43.968756 -6.069437) (xy 43.968416 -6.080252)
			(xy 43.968416 -6.080506) (xy 43.96867 -6.09092) (xy 43.96867 -6.091428) (xy 43.968162 -6.110224)
			(xy 43.967654 -6.121146) (xy 43.975274 -6.140958) (xy 44.044108 -6.210046) (xy 44.064174 -6.217412)
			(xy 44.075096 -6.216904) (xy 44.094654 -6.216396) (xy 44.094908 -6.216396) (xy 44.122176 -6.216917)
			(xy 44.176156 -6.224679) (xy 44.228482 -6.240043) (xy 44.27809 -6.262697) (xy 44.323968 -6.29218)
			(xy 44.365185 -6.327891) (xy 44.4009 -6.369104) (xy 44.430387 -6.414981) (xy 44.453045 -6.464586)
			(xy 44.468414 -6.516911) (xy 44.476181 -6.57089) (xy 44.47667 -6.598158) (xy 49.048416 -6.598158)
			(xy 49.048885 -6.570889) (xy 49.056652 -6.516906) (xy 49.072022 -6.464577) (xy 49.094681 -6.414968)
			(xy 49.124169 -6.369089) (xy 49.159886 -6.327872) (xy 49.201105 -6.292157) (xy 49.246986 -6.262672)
			(xy 49.296596 -6.240015) (xy 49.348925 -6.224648) (xy 49.402909 -6.216884) (xy 49.430178 -6.216396)
			(xy 49.430432 -6.216396) (xy 49.44999 -6.216904) (xy 49.460912 -6.217412) (xy 49.480978 -6.210046)
			(xy 49.549812 -6.140958) (xy 49.557432 -6.121146) (xy 49.556924 -6.110224) (xy 49.556416 -6.091174)
			(xy 49.5569 -6.063905) (xy 49.564665 -6.009922) (xy 49.580032 -5.957594) (xy 49.60269 -5.907985)
			(xy 49.632177 -5.862106) (xy 49.667892 -5.820889) (xy 49.709109 -5.785174) (xy 49.754989 -5.755688)
			(xy 49.804598 -5.733031) (xy 49.856926 -5.717664) (xy 49.910909 -5.7099) (xy 49.938178 -5.709412)
			(xy 49.966994 -5.709888) (xy 50.02397 -5.718569) (xy 50.078995 -5.735707) (xy 50.130824 -5.760914)
			(xy 50.178279 -5.793617) (xy 50.220286 -5.833076) (xy 50.255891 -5.878395) (xy 50.284287 -5.928547)
			(xy 50.295048 -5.955284) (xy 50.300038 -5.966336) (xy 50.318065 -5.982507) (xy 50.329592 -5.986272)
			(xy 50.366687 -5.996501) (xy 50.438778 -6.023419) (xy 50.507793 -6.057458) (xy 50.540666 -6.077458)
			(xy 50.548922 -6.082172) (xy 50.56759 -6.085699) (xy 50.586258 -6.082172) (xy 50.594514 -6.077458)
			(xy 50.627396 -6.057474) (xy 50.696413 -6.023442) (xy 50.768497 -5.996511) (xy 50.805588 -5.986272)
			(xy 50.81715 -5.982567) (xy 50.835195 -5.966377) (xy 50.840132 -5.955284) (xy 50.850906 -5.928553)
			(xy 50.87929 -5.878396) (xy 50.914888 -5.833074) (xy 50.956893 -5.793615) (xy 51.004349 -5.760916)
			(xy 51.056181 -5.735719) (xy 51.111209 -5.718596) (xy 51.168186 -5.709937) (xy 51.197002 -5.709412)
			(xy 51.207758 -5.709519) (xy 51.229234 -5.710789) (xy 51.239928 -5.711952) (xy 51.25085 -5.713222)
			(xy 51.271678 -5.706364) (xy 51.336448 -5.646674) (xy 51.344078 -5.639) (xy 51.352622 -5.619137)
			(xy 51.352958 -5.60832) (xy 51.352958 -5.608066) (xy 51.352704 -5.597652) (xy 51.352704 -5.597398)
			(xy 51.353092 -5.572667) (xy 51.359464 -5.523618) (xy 51.365404 -5.499608) (xy 51.368044 -5.487606)
			(xy 51.362718 -5.463643) (xy 51.355244 -5.453888) (xy 51.338407 -5.433581) (xy 51.307264 -5.390997)
			(xy 51.293014 -5.368798) (xy 51.288005 -5.361475) (xy 51.27403 -5.350563) (xy 51.257182 -5.345038)
			(xy 51.24831 -5.344922) (xy 51.234848 -5.345176) (xy 51.207576 -5.344688) (xy 51.153586 -5.336932)
			(xy 51.101249 -5.32157) (xy 51.051632 -5.298916) (xy 51.005744 -5.269431) (xy 50.964519 -5.233715)
			(xy 50.928798 -5.192495) (xy 50.899307 -5.14661) (xy 50.876647 -5.096996) (xy 50.861279 -5.044661)
			(xy 50.853516 -4.990672) (xy 50.853516 -4.936128) (xy 50.861279 -4.882139) (xy 50.876647 -4.829804)
			(xy 50.899307 -4.78019) (xy 50.928798 -4.734305) (xy 50.964519 -4.693085) (xy 51.005744 -4.657369)
			(xy 51.051632 -4.627884) (xy 51.101249 -4.60523) (xy 51.153586 -4.589868) (xy 51.207576 -4.582112)
			(xy 51.234848 -4.581652) (xy 51.24831 -4.581906) (xy 51.257194 -4.581872) (xy 51.274071 -4.576354)
			(xy 51.28804 -4.565392) (xy 51.293014 -4.55803) (xy 51.307278 -4.535841) (xy 51.338419 -4.493256)
			(xy 51.355244 -4.47294) (xy 51.362533 -4.463099) (xy 51.367832 -4.439224) (xy 51.365404 -4.42722)
			(xy 51.359484 -4.4034) (xy 51.353114 -4.354733) (xy 51.352704 -4.330192) (xy 51.352704 -4.32943)
			(xy 51.353252 -4.302163) (xy 51.361009 -4.248183) (xy 51.376369 -4.195857) (xy 51.399019 -4.146249)
			(xy 51.428499 -4.10037) (xy 51.464207 -4.059153) (xy 51.505418 -4.023437) (xy 51.551293 -3.99395)
			(xy 51.600897 -3.971291) (xy 51.653221 -3.955923) (xy 51.707199 -3.948157) (xy 51.734466 -3.947668)
			(xy 51.763144 -3.94824) (xy 51.819853 -3.956823) (xy 51.874642 -3.973785) (xy 51.926281 -3.998747)
			(xy 51.973608 -4.031147) (xy 52.015561 -4.070257) (xy 52.051197 -4.115198) (xy 52.079715 -4.164961)
			(xy 52.090574 -4.191508) (xy 52.095635 -4.202648) (xy 52.113953 -4.218822) (xy 52.125626 -4.222496)
			(xy 52.164272 -4.2327) (xy 52.239361 -4.260111) (xy 52.311179 -4.295208) (xy 52.345336 -4.315968)
			(xy 52.353597 -4.320664) (xy 52.37226 -4.324172) (xy 52.390923 -4.320664) (xy 52.399184 -4.315968)
			(xy 52.431682 -4.296174) (xy 52.499868 -4.262388) (xy 52.571077 -4.235555) (xy 52.607718 -4.22529)
			(xy 52.619264 -4.221544) (xy 52.637317 -4.205384) (xy 52.642262 -4.194302) (xy 52.653043 -4.167523)
			(xy 52.681378 -4.117232) (xy 52.716958 -4.071778) (xy 52.758974 -4.032197) (xy 52.806467 -3.999388)
			(xy 52.858357 -3.9741) (xy 52.913461 -3.956909) (xy 52.970524 -3.948205) (xy 52.999386 -3.947668)
			(xy 53.026658 -3.948115) (xy 53.080647 -3.955876) (xy 53.132982 -3.971242) (xy 53.182597 -3.9939)
			(xy 53.228482 -4.023389) (xy 53.269703 -4.059108) (xy 53.305421 -4.100331) (xy 53.334908 -4.146217)
			(xy 53.357564 -4.195833) (xy 53.372928 -4.248169) (xy 53.380687 -4.302158) (xy 53.381148 -4.32943)
			(xy 53.381148 -4.329684) (xy 53.380793 -4.352127) (xy 53.375439 -4.396693) (xy 53.37048 -4.418584)
			(xy 53.368344 -4.430576) (xy 53.374172 -4.454187) (xy 53.381656 -4.463796) (xy 53.400684 -4.486154)
			(xy 53.43565 -4.533322) (xy 53.451506 -4.55803) (xy 53.456522 -4.565348) (xy 53.470491 -4.576267)
			(xy 53.487338 -4.581792) (xy 53.49621 -4.581906) (xy 53.509672 -4.581652) (xy 53.536945 -4.582086)
			(xy 53.590937 -4.589845) (xy 53.643275 -4.605209) (xy 53.692894 -4.627866) (xy 53.738782 -4.657354)
			(xy 53.780007 -4.693073) (xy 53.815729 -4.734295) (xy 53.845221 -4.780182) (xy 53.867881 -4.829799)
			(xy 53.883249 -4.882135) (xy 53.891012 -4.936127) (xy 53.891012 -4.990673) (xy 53.883249 -5.044665)
			(xy 53.867881 -5.097001) (xy 53.845221 -5.146618) (xy 53.815729 -5.192505) (xy 53.780007 -5.233727)
			(xy 53.738782 -5.269446) (xy 53.692894 -5.298934) (xy 53.643275 -5.321591) (xy 53.590937 -5.336955)
			(xy 53.536945 -5.344714) (xy 53.509672 -5.345176) (xy 53.49621 -5.344922) (xy 53.487325 -5.344957)
			(xy 53.470447 -5.350472) (xy 53.456479 -5.361435) (xy 53.451506 -5.368798) (xy 53.435659 -5.393513)
			(xy 53.400692 -5.44068) (xy 53.381656 -5.463032) (xy 53.374216 -5.472666) (xy 53.368373 -5.496257)
			(xy 53.37048 -5.508244) (xy 53.375434 -5.5302) (xy 53.380787 -5.574893) (xy 53.381148 -5.597398)
			(xy 53.381148 -5.597652) (xy 53.380894 -5.60832) (xy 53.381173 -5.619208) (xy 53.389713 -5.639218)
			(xy 53.397404 -5.646928) (xy 53.454046 -5.698998) (xy 53.46244 -5.705902) (xy 53.483079 -5.712632)
			(xy 53.493924 -5.711952) (xy 53.494432 -5.711952) (xy 53.505315 -5.710769) (xy 53.527173 -5.709498)
			(xy 53.53812 -5.709412) (xy 53.566934 -5.709938) (xy 53.623908 -5.718611) (xy 53.678932 -5.735741)
			(xy 53.73076 -5.76094) (xy 53.778216 -5.793636) (xy 53.820224 -5.833089) (xy 53.85583 -5.878403)
			(xy 53.884228 -5.92855) (xy 53.89499 -5.955284) (xy 53.899959 -5.966348) (xy 53.918 -5.982514) (xy 53.929534 -5.986272)
			(xy 53.966632 -5.996492) (xy 54.038722 -6.023414) (xy 54.107735 -6.057456) (xy 54.140608 -6.077458)
			(xy 54.148864 -6.082172) (xy 54.167532 -6.085699) (xy 54.1862 -6.082172) (xy 54.194456 -6.077458)
			(xy 54.227333 -6.057466) (xy 54.296352 -6.023437) (xy 54.368438 -5.996509) (xy 54.40553 -5.986272)
			(xy 54.417082 -5.98254) (xy 54.435132 -5.96637) (xy 54.440074 -5.955284) (xy 54.450813 -5.928538)
			(xy 54.479201 -5.878379) (xy 54.514804 -5.833056) (xy 54.556814 -5.793598) (xy 54.604275 -5.760901)
			(xy 54.656112 -5.735707) (xy 54.711145 -5.718588) (xy 54.768127 -5.709934) (xy 54.796944 -5.709412)
			(xy 54.807764 -5.709514) (xy 54.829367 -5.710782) (xy 54.840124 -5.711952) (xy 54.851046 -5.713222)
			(xy 54.871874 -5.706364) (xy 54.936644 -5.646674) (xy 54.944273 -5.638999) (xy 54.952818 -5.619137)
			(xy 54.953154 -5.60832) (xy 54.953154 -5.608066) (xy 54.9529 -5.597398) (xy 54.9529 -5.59689) (xy 54.953244 -5.572356)
			(xy 54.959491 -5.523689) (xy 54.965346 -5.499862) (xy 54.967775 -5.487921) (xy 54.962458 -5.464175)
			(xy 54.955186 -5.454396) (xy 54.938346 -5.433958) (xy 54.907202 -5.391121) (xy 54.892956 -5.368798)
			(xy 54.887922 -5.361495) (xy 54.873958 -5.35058) (xy 54.857121 -5.345045) (xy 54.848252 -5.344922)
			(xy 54.83479 -5.345176) (xy 54.807522 -5.344661) (xy 54.753542 -5.336898) (xy 54.701215 -5.321533)
			(xy 54.651608 -5.298877) (xy 54.60573 -5.269392) (xy 54.564515 -5.233678) (xy 54.528802 -5.192462)
			(xy 54.499318 -5.146583) (xy 54.476664 -5.096975) (xy 54.461299 -5.044649) (xy 54.453538 -4.990668)
			(xy 54.453538 -4.936132) (xy 54.461299 -4.882151) (xy 54.476664 -4.829825) (xy 54.499318 -4.780217)
			(xy 54.528802 -4.734338) (xy 54.564515 -4.693122) (xy 54.60573 -4.657408) (xy 54.651608 -4.627923)
			(xy 54.701215 -4.605267) (xy 54.753542 -4.589902) (xy 54.807522 -4.582139) (xy 54.83479 -4.581652)
			(xy 54.848252 -4.581906) (xy 54.857138 -4.581902) (xy 54.874017 -4.576371) (xy 54.887984 -4.565397)
			(xy 54.892956 -4.55803) (xy 54.907197 -4.535703) (xy 54.938339 -4.492864) (xy 54.955186 -4.472432)
			(xy 54.962462 -4.462654) (xy 54.967776 -4.438908) (xy 54.965346 -4.426966) (xy 54.959522 -4.403133)
			(xy 54.95328 -4.354469) (xy 54.9529 -4.329938) (xy 54.9529 -4.32943) (xy 54.953452 -4.302163) (xy 54.961209 -4.248184)
			(xy 54.976568 -4.195858) (xy 54.999218 -4.14625) (xy 55.028698 -4.100371) (xy 55.064406 -4.059154)
			(xy 55.105617 -4.023438) (xy 55.151491 -3.993951) (xy 55.201094 -3.971292) (xy 55.253417 -3.955923)
			(xy 55.307395 -3.948157) (xy 55.334662 -3.947668) (xy 55.363339 -3.948243) (xy 55.420049 -3.956825)
			(xy 55.474838 -3.973788) (xy 55.526477 -3.998749) (xy 55.573804 -4.031148) (xy 55.615757 -4.070258)
			(xy 55.651393 -4.115198) (xy 55.679911 -4.164961) (xy 55.69077 -4.191508) (xy 55.695833 -4.202647)
			(xy 55.714149 -4.218822) (xy 55.725822 -4.222496) (xy 55.764416 -4.232677) (xy 55.839414 -4.260008)
			(xy 55.911154 -4.295008) (xy 55.945278 -4.315714) (xy 55.953534 -4.320428) (xy 55.972202 -4.323955)
			(xy 55.99087 -4.320428) (xy 55.999126 -4.315714) (xy 56.031697 -4.295887) (xy 56.100052 -4.262087)
			(xy 56.171436 -4.235268) (xy 56.208168 -4.225036) (xy 56.219647 -4.221263) (xy 56.237549 -4.205088)
			(xy 56.242458 -4.194048) (xy 56.2532 -4.167264) (xy 56.28157 -4.117015) (xy 56.317174 -4.071603)
			(xy 56.359204 -4.032063) (xy 56.406701 -3.999294) (xy 56.458587 -3.974041) (xy 56.513681 -3.956878)
			(xy 56.570729 -3.948197) (xy 56.599582 -3.947668) (xy 56.626854 -3.948118) (xy 56.680843 -3.955879)
			(xy 56.733178 -3.971244) (xy 56.782793 -3.993902) (xy 56.828678 -4.02339) (xy 56.869899 -4.059109)
			(xy 56.905617 -4.100332) (xy 56.935104 -4.146218) (xy 56.95776 -4.195834) (xy 56.973124 -4.248169)
			(xy 56.980883 -4.302158) (xy 56.981344 -4.32943) (xy 56.981344 -4.330192) (xy 56.980967 -4.352571)
			(xy 56.975621 -4.397009) (xy 56.970676 -4.418838) (xy 56.968505 -4.430827) (xy 56.974357 -4.454443)
			(xy 56.981852 -4.46405) (xy 57.000807 -4.486353) (xy 57.035644 -4.533394) (xy 57.051448 -4.55803)
			(xy 57.0565 -4.56532) (xy 57.070452 -4.576244) (xy 57.087285 -4.581783) (xy 57.096152 -4.581906)
			(xy 57.109614 -4.581652) (xy 57.136884 -4.582111) (xy 57.190868 -4.589875) (xy 57.243198 -4.605242)
			(xy 57.292808 -4.6279) (xy 57.338689 -4.657387) (xy 57.379906 -4.693104) (xy 57.415621 -4.734323)
			(xy 57.445107 -4.780205) (xy 57.467763 -4.829816) (xy 57.483128 -4.882146) (xy 57.49089 -4.93613)
			(xy 57.49089 -4.99067) (xy 57.483128 -5.044654) (xy 57.467763 -5.096984) (xy 57.445107 -5.146595)
			(xy 57.415621 -5.192477) (xy 57.379906 -5.233696) (xy 57.338689 -5.269413) (xy 57.292808 -5.2989)
			(xy 57.243198 -5.321558) (xy 57.190868 -5.336925) (xy 57.136884 -5.344689) (xy 57.109614 -5.345176)
			(xy 57.096152 -5.344922) (xy 57.087265 -5.344915) (xy 57.070384 -5.350449) (xy 57.056418 -5.361428)
			(xy 57.051448 -5.368798) (xy 57.035654 -5.393441) (xy 57.000815 -5.440482) (xy 56.981852 -5.462778)
			(xy 56.974385 -5.472394) (xy 56.968558 -5.496) (xy 56.970676 -5.50799) (xy 56.975615 -5.52982) (xy 56.980963 -5.574258)
			(xy 56.981344 -5.596636) (xy 56.981344 -5.597398) (xy 56.980897 -5.62467) (xy 56.973134 -5.678658)
			(xy 56.957767 -5.730992) (xy 56.935109 -5.780607) (xy 56.90562 -5.826491) (xy 56.8699 -5.867712)
			(xy 56.828678 -5.903429) (xy 56.782793 -5.932916) (xy 56.733177 -5.955573) (xy 56.680842 -5.970938)
			(xy 56.626854 -5.978698) (xy 56.599582 -5.97916) (xy 56.57073 -5.978618) (xy 56.513683 -5.969937)
			(xy 56.45859 -5.952776) (xy 56.406704 -5.927524) (xy 56.359206 -5.894757) (xy 56.317176 -5.85522)
			(xy 56.28157 -5.809811) (xy 56.253198 -5.759564) (xy 56.242458 -5.73278) (xy 56.237556 -5.721739)
			(xy 56.219643 -5.705574) (xy 56.208168 -5.701792) (xy 56.171434 -5.691566) (xy 56.100051 -5.664743)
			(xy 56.031695 -5.630943) (xy 55.999126 -5.611114) (xy 55.99087 -5.6064) (xy 55.972202 -5.602873)
			(xy 55.953534 -5.6064) (xy 55.945278 -5.611114) (xy 55.911161 -5.631833) (xy 55.83942 -5.666832)
			(xy 55.764418 -5.694155) (xy 55.725822 -5.704332) (xy 55.714127 -5.70796) (xy 55.695813 -5.72416)
			(xy 55.69077 -5.73532) (xy 55.679902 -5.761868) (xy 55.651403 -5.81165) (xy 55.615779 -5.856609)
			(xy 55.573831 -5.895734) (xy 55.526502 -5.928145) (xy 55.474858 -5.953112) (xy 55.420061 -5.970073)
			(xy 55.363343 -5.978648) (xy 55.334662 -5.97916) (xy 55.323842 -5.979066) (xy 55.302239 -5.977793)
			(xy 55.291482 -5.97662) (xy 55.28056 -5.97535) (xy 55.259732 -5.982208) (xy 55.194962 -6.041898)
			(xy 55.187346 -6.049584) (xy 55.178793 -6.069438) (xy 55.178452 -6.080252) (xy 55.178452 -6.080506)
			(xy 55.178706 -6.09092) (xy 55.178706 -6.091428) (xy 55.178198 -6.110224) (xy 55.17769 -6.121146)
			(xy 55.18531 -6.140958) (xy 55.254144 -6.210046) (xy 55.27421 -6.217412) (xy 55.285132 -6.216904)
			(xy 55.30469 -6.216396) (xy 55.304944 -6.216396) (xy 55.332213 -6.216883) (xy 55.386194 -6.22465)
			(xy 55.438521 -6.240019) (xy 55.488128 -6.262677) (xy 55.534007 -6.292164) (xy 55.575223 -6.327878)
			(xy 55.610938 -6.369095) (xy 55.640424 -6.414973) (xy 55.663082 -6.464581) (xy 55.67845 -6.516908)
			(xy 55.686217 -6.570889) (xy 55.686706 -6.598158) (xy 55.686209 -6.624997) (xy 55.678676 -6.678144)
			(xy 55.66378 -6.729713) (xy 55.641815 -6.778691) (xy 55.613212 -6.824114) (xy 55.578535 -6.865087)
			(xy 55.538466 -6.900805) (xy 55.493792 -6.930565) (xy 55.46979 -6.942582) (xy 55.461154 -6.946646)
			(xy 55.447946 -6.96087) (xy 55.415942 -7.043928) (xy 55.416196 -7.063232) (xy 55.419752 -7.072122)
			(xy 55.428492 -7.094807) (xy 55.44079 -7.141841) (xy 55.447024 -7.190055) (xy 55.447438 -7.214362)
			(xy 55.447438 -7.215124) (xy 56.484012 -7.215124) (xy 56.484548 -7.186969) (xy 56.492869 -7.131277)
			(xy 56.509277 -7.077411) (xy 56.533415 -7.026536) (xy 56.564761 -6.979757) (xy 56.583326 -6.958584)
			(xy 56.591324 -6.948779) (xy 56.597452 -6.924263) (xy 56.59501 -6.911848) (xy 56.584203 -6.866063)
			(xy 56.572607 -6.772704) (xy 56.571896 -6.725666) (xy 56.571896 -6.725158) (xy 56.572406 -6.685158)
			(xy 56.580772 -6.605595) (xy 56.597408 -6.527344) (xy 56.622133 -6.451259) (xy 56.654674 -6.378176)
			(xy 56.694676 -6.308894) (xy 56.741701 -6.244173) (xy 56.795233 -6.184722) (xy 56.854685 -6.131191)
			(xy 56.919408 -6.084168) (xy 56.98869 -6.044167) (xy 57.061774 -6.011627) (xy 57.137859 -5.986904)
			(xy 57.216111 -5.970269) (xy 57.295674 -5.961905) (xy 57.335674 -5.96138) (xy 57.378363 -5.962006)
			(xy 57.463205 -5.971565) (xy 57.546452 -5.990523) (xy 57.627068 -6.018642) (xy 57.704046 -6.055572)
			(xy 57.74055 -6.077712) (xy 57.748811 -6.082408) (xy 57.767474 -6.085916) (xy 57.786137 -6.082408)
			(xy 57.794398 -6.077712) (xy 57.830904 -6.055572) (xy 57.907876 -6.018624) (xy 57.98849 -5.990495)
			(xy 58.071739 -5.971536) (xy 58.156584 -5.961985) (xy 58.199274 -5.96138) (xy 58.239273 -5.96197)
			(xy 58.318832 -5.970329) (xy 58.397081 -5.986959) (xy 58.473164 -6.011676) (xy 58.546247 -6.044211)
			(xy 58.615528 -6.084207) (xy 58.680249 -6.131225) (xy 58.739701 -6.184751) (xy 58.793232 -6.244198)
			(xy 58.840256 -6.308915) (xy 58.880258 -6.378193) (xy 58.912799 -6.451272) (xy 58.937524 -6.527353)
			(xy 58.950312 -6.5875) (xy 70.567784 -6.5875) (xy 70.571696 -6.510357) (xy 70.583393 -6.434005) (xy 70.602754 -6.359229)
			(xy 70.629581 -6.286795) (xy 70.663599 -6.217446) (xy 70.704457 -6.151895) (xy 70.751738 -6.090814)
			(xy 70.804956 -6.03483) (xy 70.863565 -5.984517) (xy 70.926963 -5.940391) (xy 70.9945 -5.902906)
			(xy 71.065483 -5.872446) (xy 71.139183 -5.849323) (xy 71.214845 -5.833775) (xy 71.291691 -5.825962)
			(xy 71.330312 -5.82549) (xy 71.330566 -5.82549) (xy 71.373232 -5.826087) (xy 71.458027 -5.835648)
			(xy 71.541227 -5.854611) (xy 71.621791 -5.882738) (xy 71.698713 -5.919678) (xy 71.735188 -5.941822)
			(xy 71.745624 -5.947602) (xy 71.769355 -5.949718) (xy 71.780654 -5.945886) (xy 71.811487 -5.926543)
			(xy 71.876171 -5.893161) (xy 71.94374 -5.866088) (xy 72.013579 -5.845571) (xy 72.085055 -5.831795)
			(xy 72.157517 -5.824886) (xy 72.193912 -5.824474) (xy 72.223435 -5.824754) (xy 72.282303 -5.829331)
			(xy 72.311514 -5.833618) (xy 72.32118 -5.832927) (xy 72.338941 -5.82521) (xy 72.346058 -5.818632)
			(xy 72.36773 -5.797565) (xy 72.416478 -5.76184) (xy 72.470243 -5.734236) (xy 72.527683 -5.71544)
			(xy 72.587366 -5.705923) (xy 72.617584 -5.705348) (xy 72.644855 -5.705816) (xy 72.698842 -5.713577)
			(xy 72.751175 -5.728941) (xy 72.800789 -5.751598) (xy 72.846673 -5.781085) (xy 72.887894 -5.816802)
			(xy 72.923612 -5.858022) (xy 72.953099 -5.903905) (xy 72.975757 -5.953519) (xy 72.991122 -6.005852)
			(xy 72.998883 -6.059839) (xy 72.999346 -6.08711) (xy 72.999346 -6.087364) (xy 72.998767 -6.11719)
			(xy 72.989471 -6.176114) (xy 72.971129 -6.232878) (xy 72.944188 -6.2861) (xy 72.92721 -6.31063) (xy 72.921932 -6.318552)
			(xy 72.917106 -6.336951) (xy 72.917812 -6.346444) (xy 72.930229 -6.385403) (xy 72.947642 -6.4653)
			(xy 72.956394 -6.546604) (xy 72.956928 -6.58749) (xy 72.956384 -6.62745) (xy 72.948031 -6.706932)
			(xy 72.931416 -6.785106) (xy 72.90672 -6.861115) (xy 72.874215 -6.934126) (xy 72.834256 -7.003339)
			(xy 72.787281 -7.067996) (xy 72.733805 -7.127389) (xy 72.674413 -7.180867) (xy 72.609757 -7.227844)
			(xy 72.540545 -7.267805) (xy 72.467535 -7.300312) (xy 72.391527 -7.32501) (xy 72.313354 -7.341627)
			(xy 72.233872 -7.349982) (xy 72.193912 -7.350506) (xy 72.157516 -7.35009) (xy 72.085052 -7.343194)
			(xy 72.013575 -7.329425) (xy 71.943734 -7.308908) (xy 71.876166 -7.281831) (xy 71.811485 -7.24844)
			(xy 71.780654 -7.229094) (xy 71.769357 -7.225285) (xy 71.745639 -7.227419) (xy 71.735188 -7.233158)
			(xy 71.698724 -7.255324) (xy 71.62181 -7.29229) (xy 71.541244 -7.320425) (xy 71.458038 -7.339375)
			(xy 71.373234 -7.348902) (xy 71.330566 -7.34949) (xy 71.330312 -7.34949) (xy 71.291691 -7.349038)
			(xy 71.214845 -7.341225) (xy 71.139183 -7.325677) (xy 71.065483 -7.302554) (xy 70.9945 -7.272094)
			(xy 70.926963 -7.234609) (xy 70.863565 -7.190483) (xy 70.804956 -7.14017) (xy 70.751738 -7.084186)
			(xy 70.704457 -7.023105) (xy 70.663599 -6.957554) (xy 70.629581 -6.888205) (xy 70.602754 -6.815771)
			(xy 70.583393 -6.740995) (xy 70.571696 -6.664643) (xy 70.567784 -6.5875) (xy 58.950312 -6.5875) (xy 58.95416 -6.605601)
			(xy 58.962526 -6.685159) (xy 58.963052 -6.725158) (xy 58.963052 -6.725666) (xy 58.962279 -6.773425)
			(xy 58.950309 -6.868192) (xy 58.939176 -6.914642) (xy 58.93667 -6.926966) (xy 58.942682 -6.951356)
			(xy 58.950606 -6.961124) (xy 58.968737 -6.982209) (xy 58.999324 -7.028648) (xy 59.022849 -7.079034)
			(xy 59.038814 -7.132301) (xy 59.04688 -7.18732) (xy 59.04738 -7.215124) (xy 59.046898 -7.242393)
			(xy 59.039133 -7.296376) (xy 59.023766 -7.348704) (xy 59.001108 -7.398314) (xy 58.971622 -7.444193)
			(xy 58.935906 -7.48541) (xy 58.894689 -7.521125) (xy 58.848808 -7.550611) (xy 58.799199 -7.573268)
			(xy 58.74687 -7.588635) (xy 58.692887 -7.596398) (xy 58.665618 -7.596886) (xy 58.635926 -7.596334)
			(xy 58.577261 -7.587122) (xy 58.520731 -7.568934) (xy 58.467701 -7.542209) (xy 58.419451 -7.507592)
			(xy 58.397902 -7.487158) (xy 58.388556 -7.478813) (xy 58.36458 -7.471628) (xy 58.352182 -7.473442)
			(xy 58.314369 -7.480678) (xy 58.23777 -7.488442) (xy 58.199274 -7.488936) (xy 58.156584 -7.488347)
			(xy 58.07174 -7.478781) (xy 57.988492 -7.459816) (xy 57.907877 -7.431688) (xy 57.830901 -7.394749)
			(xy 57.794398 -7.372604) (xy 57.786137 -7.367908) (xy 57.767474 -7.3644) (xy 57.748811 -7.367908)
			(xy 57.74055 -7.372604) (xy 57.704058 -7.394767) (xy 57.627082 -7.431711) (xy 57.546464 -7.459835)
			(xy 57.463212 -7.478788) (xy 57.378365 -7.488334) (xy 57.335674 -7.488936) (xy 57.335166 -7.488936)
			(xy 57.296212 -7.488407) (xy 57.218718 -7.480387) (xy 57.18048 -7.472934) (xy 57.168019 -7.471053)
			(xy 57.143901 -7.478251) (xy 57.134506 -7.48665) (xy 57.112895 -7.507154) (xy 57.064528 -7.541925)
			(xy 57.011353 -7.568773) (xy 56.954657 -7.587047) (xy 56.895812 -7.596307) (xy 56.866028 -7.596886)
			(xy 56.865774 -7.596886) (xy 56.838505 -7.5964) (xy 56.784523 -7.588635) (xy 56.732195 -7.573268)
			(xy 56.682586 -7.55061) (xy 56.636706 -7.521124) (xy 56.59549 -7.485409) (xy 56.559775 -7.444192)
			(xy 56.530289 -7.398312) (xy 56.507631 -7.348703) (xy 56.492264 -7.296375) (xy 56.4845 -7.242393)
			(xy 56.484012 -7.215124) (xy 55.447438 -7.215124) (xy 55.446998 -7.242395) (xy 55.439232 -7.296382)
			(xy 55.423863 -7.348713) (xy 55.401202 -7.398325) (xy 55.371711 -7.444207) (xy 55.335991 -7.485425)
			(xy 55.294769 -7.52114) (xy 55.248883 -7.550625) (xy 55.199268 -7.573279) (xy 55.146935 -7.588642)
			(xy 55.092947 -7.596401) (xy 55.065676 -7.596886) (xy 55.035986 -7.596298) (xy 54.977322 -7.587095)
			(xy 54.920793 -7.568916) (xy 54.867762 -7.542199) (xy 54.81951 -7.507589) (xy 54.79796 -7.487158)
			(xy 54.78859 -7.478846) (xy 54.764634 -7.471642) (xy 54.75224 -7.473442) (xy 54.714428 -7.480684)
			(xy 54.637828 -7.488444) (xy 54.599332 -7.488936) (xy 54.556643 -7.48832) (xy 54.4718 -7.47876) (xy 54.388552 -7.459801)
			(xy 54.307937 -7.43168) (xy 54.230959 -7.394746) (xy 54.194456 -7.372604) (xy 54.186195 -7.367908)
			(xy 54.167532 -7.3644) (xy 54.148869 -7.367908) (xy 54.140608 -7.372604) (xy 54.104102 -7.394743)
			(xy 54.02713 -7.431691) (xy 53.946516 -7.45982) (xy 53.863267 -7.478779) (xy 53.778422 -7.488331)
			(xy 53.735732 -7.488936) (xy 53.735224 -7.488936) (xy 53.696271 -7.488398) (xy 53.618776 -7.480384)
			(xy 53.580538 -7.472934) (xy 53.568075 -7.471092) (xy 53.543961 -7.478263) (xy 53.534564 -7.48665)
			(xy 53.512972 -7.507175) (xy 53.464599 -7.541943) (xy 53.411419 -7.568786) (xy 53.354719 -7.587056)
			(xy 53.295871 -7.59631) (xy 53.266086 -7.596886) (xy 53.265832 -7.596886) (xy 53.238563 -7.596369)
			(xy 53.184579 -7.588612) (xy 53.132249 -7.573251) (xy 53.082638 -7.550599) (xy 53.036755 -7.521117)
			(xy 52.995535 -7.485405) (xy 52.959817 -7.44419) (xy 52.930328 -7.398312) (xy 52.907669 -7.348704)
			(xy 52.8923 -7.296376) (xy 52.884535 -7.242393) (xy 52.88407 -7.215124) (xy 52.884458 -7.190503)
			(xy 52.890779 -7.141668) (xy 52.903333 -7.094053) (xy 52.912264 -7.071106) (xy 52.91582 -7.062216)
			(xy 52.916074 -7.042912) (xy 52.88788 -6.968744) (xy 52.884118 -6.959996) (xy 52.87133 -6.945904)
			(xy 52.862988 -6.941312) (xy 52.862734 -6.941312) (xy 52.838974 -6.929205) (xy 52.794776 -6.899372)
			(xy 52.755158 -6.863681) (xy 52.720889 -6.822825) (xy 52.692637 -6.7776) (xy 52.670951 -6.728884)
			(xy 52.656252 -6.677625) (xy 52.648826 -6.62482) (xy 52.648358 -6.598158) (xy 52.648785 -6.570887)
			(xy 52.656553 -6.5169) (xy 52.671925 -6.464568) (xy 52.694588 -6.414956) (xy 52.72408 -6.369075)
			(xy 52.759801 -6.327857) (xy 52.801024 -6.292142) (xy 52.846911 -6.262658) (xy 52.896526 -6.240003)
			(xy 52.948861 -6.22464) (xy 53.002849 -6.216881) (xy 53.03012 -6.216396) (xy 53.030374 -6.216396)
			(xy 53.049932 -6.216904) (xy 53.060854 -6.217412) (xy 53.08092 -6.210046) (xy 53.149754 -6.140958)
			(xy 53.157374 -6.121146) (xy 53.156866 -6.110224) (xy 53.156358 -6.091174) (xy 53.156358 -6.09092)
			(xy 53.156612 -6.080252) (xy 53.156347 -6.069362) (xy 53.147797 -6.049353) (xy 53.140102 -6.041644)
			(xy 53.08346 -5.989574) (xy 53.075102 -5.982619) (xy 53.054434 -5.97592) (xy 53.043582 -5.97662)
			(xy 53.043074 -5.97662) (xy 53.03219 -5.977801) (xy 53.010333 -5.979074) (xy 52.999386 -5.97916)
			(xy 52.970519 -5.978608) (xy 52.913441 -5.969939) (xy 52.858319 -5.952772) (xy 52.806413 -5.927498)
			(xy 52.758905 -5.894694) (xy 52.716881 -5.855107) (xy 52.681299 -5.809643) (xy 52.652971 -5.759338)
			(xy 52.642262 -5.732526) (xy 52.637263 -5.721478) (xy 52.619243 -5.705305) (xy 52.607718 -5.701538)
			(xy 52.571075 -5.69128) (xy 52.499867 -5.664443) (xy 52.431679 -5.630659) (xy 52.399184 -5.61086)
			(xy 52.390923 -5.606164) (xy 52.37226 -5.602656) (xy 52.353597 -5.606164) (xy 52.345336 -5.61086)
			(xy 52.31119 -5.631639) (xy 52.239371 -5.66674) (xy 52.164277 -5.694141) (xy 52.125626 -5.704332)
			(xy 52.113931 -5.707963) (xy 52.095618 -5.724161) (xy 52.090574 -5.73532) (xy 52.079702 -5.761866)
			(xy 52.051204 -5.811648) (xy 52.01558 -5.856608) (xy 51.973633 -5.895733) (xy 51.926305 -5.928144)
			(xy 51.874661 -5.953111) (xy 51.819864 -5.970073) (xy 51.763147 -5.978648) (xy 51.734466 -5.97916)
			(xy 51.72371 -5.979055) (xy 51.702234 -5.977783) (xy 51.69154 -5.97662) (xy 51.680618 -5.97535) (xy 51.65979 -5.982208)
			(xy 51.59502 -6.041898) (xy 51.587398 -6.049579) (xy 51.57885 -6.069437) (xy 51.57851 -6.080252)
			(xy 51.57851 -6.080506) (xy 51.578764 -6.090666) (xy 51.578764 -6.091174) (xy 51.578256 -6.110224)
			(xy 51.577748 -6.121146) (xy 51.585368 -6.140958) (xy 51.654202 -6.210046) (xy 51.674268 -6.217412)
			(xy 51.68519 -6.216904) (xy 51.704748 -6.216396) (xy 51.705002 -6.216396) (xy 51.73227 -6.216922)
			(xy 51.786249 -6.224683) (xy 51.838576 -6.240047) (xy 51.888183 -6.2627) (xy 51.934062 -6.292182)
			(xy 51.975278 -6.327893) (xy 52.010994 -6.369106) (xy 52.040481 -6.414982) (xy 52.063139 -6.464587)
			(xy 52.078508 -6.516911) (xy 52.086275 -6.570891) (xy 52.086764 -6.598158) (xy 52.086291 -6.624998)
			(xy 52.078757 -6.678147) (xy 52.063859 -6.729718) (xy 52.041891 -6.778697) (xy 52.013285 -6.82412)
			(xy 51.978604 -6.865093) (xy 51.93853 -6.900809) (xy 51.893853 -6.930566) (xy 51.869848 -6.942582)
			(xy 51.861212 -6.946646) (xy 51.848004 -6.96087) (xy 51.816 -7.043928) (xy 51.816254 -7.063232) (xy 51.81981 -7.072122)
			(xy 51.828553 -7.094806) (xy 51.840849 -7.141841) (xy 51.847082 -7.190055) (xy 51.847496 -7.214362)
			(xy 51.847496 -7.215124) (xy 51.846998 -7.242392) (xy 51.839234 -7.296374) (xy 51.823867 -7.348701)
			(xy 51.801211 -7.398309) (xy 51.771726 -7.444188) (xy 51.736012 -7.485405) (xy 51.694796 -7.52112)
			(xy 51.648918 -7.550606) (xy 51.59931 -7.573264) (xy 51.546984 -7.588632) (xy 51.493002 -7.596397)
			(xy 51.465734 -7.596886) (xy 51.436043 -7.596324) (xy 51.377378 -7.587115) (xy 51.320848 -7.568929)
			(xy 51.267818 -7.542206) (xy 51.219568 -7.507591) (xy 51.198018 -7.487158) (xy 51.188665 -7.478822)
			(xy 51.164695 -7.471632) (xy 51.152298 -7.473442) (xy 51.114485 -7.480675) (xy 51.037886 -7.488441)
			(xy 50.99939 -7.488936) (xy 50.9567 -7.48834) (xy 50.871857 -7.478775) (xy 50.788609 -7.459812) (xy 50.707994 -7.431686)
			(xy 50.631017 -7.394748) (xy 50.594514 -7.372604) (xy 50.586253 -7.367908) (xy 50.56759 -7.3644)
			(xy 50.548927 -7.367908) (xy 50.540666 -7.372604) (xy 50.50417 -7.39476) (xy 50.427195 -7.431705)
			(xy 50.346578 -7.459831) (xy 50.263327 -7.478786) (xy 50.178481 -7.488333) (xy 50.13579 -7.488936)
			(xy 50.096582 -7.488445) (xy 50.018577 -7.480425) (xy 49.980088 -7.472934) (xy 49.967597 -7.470977)
			(xy 49.94335 -7.478041) (xy 49.93386 -7.486396) (xy 49.912309 -7.506947) (xy 49.864012 -7.54178)
			(xy 49.810888 -7.568684) (xy 49.754228 -7.587004) (xy 49.69541 -7.596295) (xy 49.665636 -7.596886)
			(xy 49.638367 -7.596365) (xy 49.584383 -7.588609) (xy 49.532053 -7.573248) (xy 49.482442 -7.550596)
			(xy 49.436559 -7.521115) (xy 49.395339 -7.485403) (xy 49.359621 -7.444189) (xy 49.330132 -7.398311)
			(xy 49.307473 -7.348703) (xy 49.292104 -7.296375) (xy 49.284339 -7.242393) (xy 49.283874 -7.215124)
			(xy 49.284294 -7.190453) (xy 49.290699 -7.141529) (xy 49.303343 -7.093834) (xy 49.312322 -7.070852)
			(xy 49.312322 -7.070598) (xy 49.315411 -7.061658) (xy 49.315526 -7.042757) (xy 49.312576 -7.033768)
			(xy 49.284382 -6.959346) (xy 49.271682 -6.945376) (xy 49.262792 -6.941058) (xy 49.239019 -6.928999)
			(xy 49.194814 -6.89921) (xy 49.155188 -6.863556) (xy 49.120913 -6.822731) (xy 49.092657 -6.777531)
			(xy 49.070969 -6.728837) (xy 49.056274 -6.677598) (xy 49.048857 -6.624811) (xy 49.048416 -6.598158)
			(xy 44.47667 -6.598158) (xy 44.476194 -6.624998) (xy 44.46866 -6.678146) (xy 44.453762 -6.729717)
			(xy 44.431795 -6.778696) (xy 44.403189 -6.824119) (xy 44.368508 -6.865092) (xy 44.328435 -6.900809)
			(xy 44.283758 -6.930566) (xy 44.259754 -6.942582) (xy 44.251118 -6.946646) (xy 44.23791 -6.96087)
			(xy 44.205906 -7.043928) (xy 44.20616 -7.063232) (xy 44.209716 -7.072122) (xy 44.218459 -7.094806)
			(xy 44.230755 -7.141841) (xy 44.236988 -7.190055) (xy 44.237402 -7.214362) (xy 44.237402 -7.215124)
			(xy 44.236898 -7.242392) (xy 44.229134 -7.296373) (xy 44.213768 -7.3487) (xy 44.191112 -7.398307)
			(xy 44.161627 -7.444186) (xy 44.125914 -7.485403) (xy 44.084699 -7.521117) (xy 44.038821 -7.550604)
			(xy 43.989215 -7.573262) (xy 43.936889 -7.588631) (xy 43.882908 -7.596397) (xy 43.85564 -7.596886)
			(xy 43.825949 -7.59632) (xy 43.767285 -7.587112) (xy 43.710755 -7.568927) (xy 43.657724 -7.542205)
			(xy 43.609474 -7.507591) (xy 43.587924 -7.487158) (xy 43.578569 -7.478826) (xy 43.554601 -7.471633)
			(xy 43.542204 -7.473442) (xy 43.504391 -7.480674) (xy 43.427792 -7.48844) (xy 43.389296 -7.488936)
			(xy 43.346606 -7.488337) (xy 43.261763 -7.478773) (xy 43.178515 -7.459811) (xy 43.0979 -7.431685)
			(xy 43.020923 -7.394748) (xy 42.98442 -7.372604) (xy 42.976159 -7.367908) (xy 42.957496 -7.3644)
			(xy 42.938833 -7.367908) (xy 42.930572 -7.372604) (xy 42.894075 -7.394758) (xy 42.8171 -7.431703)
			(xy 42.736484 -7.459829) (xy 42.653233 -7.478785) (xy 42.568387 -7.488333) (xy 42.525696 -7.488936)
			(xy 42.525188 -7.488936) (xy 42.486235 -7.488403) (xy 42.40874 -7.480385) (xy 42.370502 -7.472934)
			(xy 42.35804 -7.471067) (xy 42.333924 -7.478255) (xy 42.324528 -7.48665) (xy 42.302908 -7.507144)
			(xy 42.254543 -7.541916) (xy 42.20137 -7.568766) (xy 42.144676 -7.587043) (xy 42.085833 -7.596305)
			(xy 42.05605 -7.596886) (xy 42.055796 -7.596886) (xy 42.028528 -7.596379) (xy 41.974546 -7.588618)
			(xy 41.922218 -7.573253) (xy 41.87261 -7.550598) (xy 41.82673 -7.521114) (xy 41.785513 -7.485401)
			(xy 41.749798 -7.444186) (xy 41.720311 -7.398308) (xy 41.697654 -7.3487) (xy 41.682286 -7.296374)
			(xy 41.674522 -7.242392) (xy 41.674034 -7.215124) (xy 41.674424 -7.190503) (xy 41.680745 -7.141668)
			(xy 41.693297 -7.094053) (xy 41.702228 -7.071106) (xy 41.705784 -7.062216) (xy 41.706038 -7.042912)
			(xy 41.677844 -6.968744) (xy 41.674095 -6.959989) (xy 41.661299 -6.9459) (xy 41.652952 -6.941312)
			(xy 41.652698 -6.941312) (xy 41.628953 -6.929177) (xy 41.584753 -6.89935) (xy 41.545131 -6.863665)
			(xy 41.51086 -6.822813) (xy 41.482606 -6.777592) (xy 41.460917 -6.728879) (xy 41.446217 -6.677622)
			(xy 41.43879 -6.624819) (xy 41.438322 -6.598158) (xy 41.438785 -6.570888) (xy 41.446552 -6.516905)
			(xy 41.461922 -6.464576) (xy 41.484582 -6.414966) (xy 41.514071 -6.369087) (xy 41.549788 -6.32787)
			(xy 41.591007 -6.292155) (xy 41.636889 -6.26267) (xy 41.6865 -6.240013) (xy 41.73883 -6.224647) (xy 41.792814 -6.216883)
			(xy 41.820084 -6.216396) (xy 41.820338 -6.216396) (xy 41.839896 -6.216904) (xy 41.850818 -6.217412)
			(xy 41.870884 -6.210046) (xy 41.939718 -6.140958) (xy 41.947338 -6.121146) (xy 41.94683 -6.110224)
			(xy 41.946322 -6.091174) (xy 41.946322 -6.09092) (xy 41.946576 -6.080252) (xy 41.946322 -6.069361)
			(xy 41.937766 -6.049351) (xy 41.930066 -6.041644) (xy 41.873424 -5.989574) (xy 41.865043 -5.982651)
			(xy 41.844393 -5.975933) (xy 41.833546 -5.97662) (xy 41.833038 -5.97662) (xy 41.822155 -5.977805)
			(xy 41.800297 -5.979075) (xy 41.78935 -5.97916) (xy 41.760482 -5.978639) (xy 41.703402 -5.969965)
			(xy 41.64828 -5.952793) (xy 41.596373 -5.927514) (xy 41.548866 -5.894705) (xy 41.506843 -5.855115)
			(xy 41.471262 -5.809647) (xy 41.442935 -5.759339) (xy 41.432226 -5.732526) (xy 41.427245 -5.721468)
			(xy 41.409212 -5.705299) (xy 41.397682 -5.701538) (xy 41.361043 -5.691267) (xy 41.289833 -5.664435)
			(xy 41.221645 -5.630656) (xy 41.189148 -5.61086) (xy 41.180887 -5.606164) (xy 41.162224 -5.602656)
			(xy 41.143561 -5.606164) (xy 41.1353 -5.61086) (xy 41.101158 -5.631647) (xy 41.029338 -5.666745)
			(xy 40.954242 -5.694143) (xy 40.91559 -5.704332) (xy 40.903889 -5.707946) (xy 40.885579 -5.724157)
			(xy 40.880538 -5.73532) (xy 40.869696 -5.761879) (xy 40.841194 -5.811663) (xy 40.805567 -5.856622)
			(xy 40.763615 -5.895747) (xy 40.716282 -5.928157) (xy 40.664634 -5.953121) (xy 40.609834 -5.97008)
			(xy 40.553113 -5.97865) (xy 40.52443 -5.97916) (xy 40.513674 -5.979058) (xy 40.492198 -5.977784)
			(xy 40.481504 -5.97662) (xy 40.470582 -5.97535) (xy 40.449754 -5.982208) (xy 40.384984 -6.041898)
			(xy 40.377372 -6.049587) (xy 40.368816 -6.069439) (xy 40.368474 -6.080252) (xy 40.368474 -6.080506)
			(xy 40.368728 -6.090666) (xy 40.368728 -6.091174) (xy 40.36822 -6.110224) (xy 40.367712 -6.121146)
			(xy 40.375332 -6.140958) (xy 40.444166 -6.210046) (xy 40.464232 -6.217412) (xy 40.475154 -6.216904)
			(xy 40.494712 -6.216396) (xy 40.494966 -6.216396) (xy 40.522233 -6.216956) (xy 40.576211 -6.224712)
			(xy 40.628537 -6.240071) (xy 40.678144 -6.26272) (xy 40.724023 -6.292198) (xy 40.76524 -6.327906)
			(xy 40.800956 -6.369116) (xy 40.830444 -6.414989) (xy 40.853103 -6.464592) (xy 40.868472 -6.516914)
			(xy 40.876239 -6.570891) (xy 40.876728 -6.598158) (xy 40.876275 -6.624999) (xy 40.86874 -6.678149)
			(xy 40.853841 -6.729722) (xy 40.831871 -6.778703) (xy 40.803262 -6.824126) (xy 40.768577 -6.865098)
			(xy 40.7285 -6.900813) (xy 40.683818 -6.930568) (xy 40.659812 -6.942582) (xy 40.651176 -6.946646)
			(xy 40.637968 -6.96087) (xy 40.605964 -7.043928) (xy 40.606218 -7.063232) (xy 40.609774 -7.072122)
			(xy 40.618515 -7.094807) (xy 40.630813 -7.141841) (xy 40.637046 -7.190055) (xy 40.63746 -7.214362)
			(xy 40.63746 -7.215124) (xy 40.636998 -7.242394) (xy 40.629233 -7.296379) (xy 40.613864 -7.348709)
			(xy 40.591205 -7.398319) (xy 40.561717 -7.4442) (xy 40.525999 -7.485417) (xy 40.484779 -7.521132)
			(xy 40.438896 -7.550618) (xy 40.389284 -7.573274) (xy 40.336953 -7.588638) (xy 40.282968 -7.5964)
			(xy 40.255698 -7.596886) (xy 40.226006 -7.596346) (xy 40.16734 -7.587132) (xy 40.11081 -7.568941)
			(xy 40.05778 -7.542213) (xy 40.009531 -7.507593) (xy 39.987982 -7.487158) (xy 39.978644 -7.478802)
			(xy 39.954662 -7.471623) (xy 39.942262 -7.473442) (xy 39.90445 -7.480681) (xy 39.82785 -7.488443)
			(xy 39.789354 -7.488936) (xy 39.746665 -7.488309) (xy 39.661823 -7.478752) (xy 39.578575 -7.459796)
			(xy 39.497959 -7.431677) (xy 39.420982 -7.394745) (xy 39.384478 -7.372604) (xy 39.376217 -7.367908)
			(xy 39.357554 -7.3644) (xy 39.338891 -7.367908) (xy 39.33063 -7.372604) (xy 39.294118 -7.394734)
			(xy 39.217148 -7.431683) (xy 39.136535 -7.459814) (xy 39.053287 -7.478775) (xy 38.968444 -7.48833)
			(xy 38.925754 -7.488936) (xy 38.886546 -7.488435) (xy 38.808541 -7.480422) (xy 38.770052 -7.472934)
			(xy 38.757562 -7.470953) (xy 38.733313 -7.478033) (xy 38.723824 -7.486396) (xy 38.702288 -7.506964)
			(xy 38.653987 -7.541795) (xy 38.600859 -7.568695) (xy 38.544196 -7.587011) (xy 38.485375 -7.596298)
			(xy 38.4556 -7.596886) (xy 38.428332 -7.596376) (xy 38.37435 -7.588615) (xy 38.322023 -7.57325) (xy 38.272414 -7.550596)
			(xy 38.226534 -7.521112) (xy 38.185317 -7.4854) (xy 38.149602 -7.444185) (xy 38.120115 -7.398307)
			(xy 38.097458 -7.3487) (xy 38.082091 -7.296373) (xy 38.074326 -7.242392) (xy 38.073838 -7.215124)
			(xy 38.07426 -7.190454) (xy 38.080665 -7.141529) (xy 38.093308 -7.093834) (xy 38.102286 -7.070852)
			(xy 38.102286 -7.070598) (xy 38.105377 -7.061658) (xy 38.105492 -7.042756) (xy 38.10254 -7.033768)
			(xy 38.074346 -6.959346) (xy 38.061646 -6.945376) (xy 38.052756 -6.941058) (xy 38.028998 -6.928971)
			(xy 37.984791 -6.899189) (xy 37.945162 -6.86354) (xy 37.910884 -6.82272) (xy 37.882625 -6.777524)
			(xy 37.860936 -6.728832) (xy 37.846239 -6.677595) (xy 37.838821 -6.62481) (xy 37.83838 -6.598158)
			(xy 31.766764 -6.598158) (xy 31.766291 -6.624998) (xy 31.758757 -6.678147) (xy 31.743859 -6.729718)
			(xy 31.721891 -6.778697) (xy 31.693285 -6.82412) (xy 31.658604 -6.865093) (xy 31.61853 -6.900809)
			(xy 31.573853 -6.930566) (xy 31.549848 -6.942582) (xy 31.541212 -6.946646) (xy 31.528004 -6.96087)
			(xy 31.496 -7.043928) (xy 31.496254 -7.063232) (xy 31.49981 -7.072122) (xy 31.508553 -7.094806) (xy 31.520849 -7.141841)
			(xy 31.527082 -7.190055) (xy 31.527496 -7.214362) (xy 31.527496 -7.215124) (xy 31.526998 -7.242392)
			(xy 31.519234 -7.296374) (xy 31.503867 -7.348701) (xy 31.481211 -7.398309) (xy 31.451726 -7.444188)
			(xy 31.416012 -7.485405) (xy 31.374796 -7.52112) (xy 31.328918 -7.550606) (xy 31.27931 -7.573264)
			(xy 31.226984 -7.588632) (xy 31.173002 -7.596397) (xy 31.145734 -7.596886) (xy 31.116043 -7.596324)
			(xy 31.057378 -7.587115) (xy 31.000848 -7.568929) (xy 30.947818 -7.542206) (xy 30.899568 -7.507591)
			(xy 30.878018 -7.487158) (xy 30.868665 -7.478822) (xy 30.844695 -7.471632) (xy 30.832298 -7.473442)
			(xy 30.794485 -7.480675) (xy 30.717886 -7.488441) (xy 30.67939 -7.488936) (xy 30.6367 -7.48834) (xy 30.551857 -7.478775)
			(xy 30.468609 -7.459812) (xy 30.387994 -7.431686) (xy 30.311017 -7.394748) (xy 30.274514 -7.372604)
			(xy 30.266253 -7.367908) (xy 30.24759 -7.3644) (xy 30.228927 -7.367908) (xy 30.220666 -7.372604)
			(xy 30.18417 -7.39476) (xy 30.107195 -7.431705) (xy 30.026578 -7.459831) (xy 29.943327 -7.478786)
			(xy 29.858481 -7.488333) (xy 29.81579 -7.488936) (xy 29.776582 -7.488445) (xy 29.698577 -7.480425)
			(xy 29.660088 -7.472934) (xy 29.647597 -7.470977) (xy 29.62335 -7.478041) (xy 29.61386 -7.486396)
			(xy 29.592309 -7.506947) (xy 29.544012 -7.54178) (xy 29.490888 -7.568684) (xy 29.434228 -7.587004)
			(xy 29.37541 -7.596295) (xy 29.345636 -7.596886) (xy 29.318367 -7.596365) (xy 29.264383 -7.588609)
			(xy 29.212053 -7.573248) (xy 29.162442 -7.550596) (xy 29.116559 -7.521115) (xy 29.075339 -7.485403)
			(xy 29.039621 -7.444189) (xy 29.010132 -7.398311) (xy 28.987473 -7.348703) (xy 28.972104 -7.296375)
			(xy 28.964339 -7.242393) (xy 28.963874 -7.215124) (xy 28.964294 -7.190453) (xy 28.970699 -7.141529)
			(xy 28.983343 -7.093834) (xy 28.992322 -7.070852) (xy 28.992322 -7.070598) (xy 28.995411 -7.061658)
			(xy 28.995526 -7.042757) (xy 28.992576 -7.033768) (xy 28.964382 -6.959346) (xy 28.951682 -6.945376)
			(xy 28.942792 -6.941058) (xy 28.919019 -6.928999) (xy 28.874814 -6.89921) (xy 28.835188 -6.863556)
			(xy 28.800913 -6.822731) (xy 28.772657 -6.777531) (xy 28.750969 -6.728837) (xy 28.736274 -6.677598)
			(xy 28.728857 -6.624811) (xy 28.728416 -6.598158) (xy 28.728885 -6.570889) (xy 28.736652 -6.516906)
			(xy 28.752022 -6.464577) (xy 28.774681 -6.414968) (xy 28.804169 -6.369089) (xy 28.839886 -6.327872)
			(xy 28.881105 -6.292157) (xy 28.926986 -6.262672) (xy 28.976596 -6.240015) (xy 29.028925 -6.224648)
			(xy 29.082909 -6.216884) (xy 29.110178 -6.216396) (xy 29.110432 -6.216396) (xy 29.12999 -6.216904)
			(xy 29.140912 -6.217412) (xy 29.160978 -6.210046) (xy 29.229812 -6.140958) (xy 29.237432 -6.121146)
			(xy 29.236924 -6.110224) (xy 29.236416 -6.091174) (xy 29.236416 -6.09092) (xy 29.23667 -6.080252)
			(xy 29.236417 -6.069361) (xy 29.22786 -6.04935) (xy 29.22016 -6.041644) (xy 29.163518 -5.989574)
			(xy 29.15514 -5.982648) (xy 29.134488 -5.975932) (xy 29.12364 -5.97662) (xy 29.123132 -5.97662) (xy 29.112249 -5.977805)
			(xy 29.090391 -5.979075) (xy 29.079444 -5.97916) (xy 29.050594 -5.978564) (xy 28.993549 -5.969893)
			(xy 28.938457 -5.95274) (xy 28.886572 -5.927497) (xy 28.839073 -5.894737) (xy 28.797042 -5.855206)
			(xy 28.761434 -5.809803) (xy 28.73306 -5.759562) (xy 28.72232 -5.73278) (xy 28.717388 -5.721756)
			(xy 28.699496 -5.705584) (xy 28.68803 -5.701792) (xy 28.6513 -5.691553) (xy 28.579916 -5.664735)
			(xy 28.511558 -5.630941) (xy 28.478988 -5.611114) (xy 28.470732 -5.6064) (xy 28.452064 -5.602873)
			(xy 28.433396 -5.6064) (xy 28.42514 -5.611114) (xy 28.391016 -5.63182) (xy 28.319278 -5.666824) (xy 28.244279 -5.694152)
			(xy 28.205684 -5.704332) (xy 28.193982 -5.707943) (xy 28.175672 -5.724156) (xy 28.170632 -5.73532)
			(xy 28.159795 -5.761881) (xy 28.131293 -5.811665) (xy 28.095664 -5.856625) (xy 28.053712 -5.89575)
			(xy 28.006378 -5.928159) (xy 27.95473 -5.953123) (xy 27.899928 -5.970081) (xy 27.843207 -5.978651)
			(xy 27.814524 -5.97916) (xy 27.803704 -5.979061) (xy 27.782101 -5.977791) (xy 27.771344 -5.97662)
			(xy 27.760422 -5.97535) (xy 27.739594 -5.982208) (xy 27.674824 -6.041898) (xy 27.667203 -6.049579)
			(xy 27.658654 -6.069437) (xy 27.658314 -6.080252) (xy 27.658314 -6.080506) (xy 27.658568 -6.09092)
			(xy 27.658568 -6.091428) (xy 27.65806 -6.110224) (xy 27.657552 -6.121146) (xy 27.665172 -6.140958)
			(xy 27.734006 -6.210046) (xy 27.754072 -6.217412) (xy 27.764994 -6.216904) (xy 27.784552 -6.216396)
			(xy 27.784806 -6.216396) (xy 27.812074 -6.216919) (xy 27.866054 -6.22468) (xy 27.91838 -6.240044)
			(xy 27.967987 -6.262698) (xy 28.013866 -6.292181) (xy 28.055083 -6.327892) (xy 28.090798 -6.369105)
			(xy 28.120285 -6.414981) (xy 28.142943 -6.464586) (xy 28.158312 -6.516911) (xy 28.166079 -6.57089)
			(xy 28.166568 -6.598158) (xy 28.166061 -6.624973) (xy 28.158548 -6.678075) (xy 28.143678 -6.729603)
			(xy 28.121744 -6.778544) (xy 28.093177 -6.823933) (xy 28.058539 -6.864878) (xy 28.018513 -6.900573)
			(xy 27.973885 -6.930316) (xy 27.949906 -6.942328) (xy 27.94127 -6.946392) (xy 27.928062 -6.960616)
			(xy 27.895804 -7.043928) (xy 27.896058 -7.062724) (xy 27.899614 -7.071614) (xy 27.899614 -7.072122)
			(xy 27.908419 -7.094882) (xy 27.920844 -7.142076) (xy 27.927136 -7.19047) (xy 27.927554 -7.21487)
			(xy 27.927554 -7.215124) (xy 27.927098 -7.242394) (xy 27.919333 -7.296379) (xy 27.903964 -7.34871)
			(xy 27.881304 -7.398321) (xy 27.851815 -7.444202) (xy 27.816097 -7.48542) (xy 27.774876 -7.521134)
			(xy 27.728993 -7.55062) (xy 27.67938 -7.573275) (xy 27.627048 -7.58864) (xy 27.573062 -7.5964) (xy 27.545792 -7.596886)
			(xy 27.516078 -7.596328) (xy 27.457368 -7.587116) (xy 27.400791 -7.568929) (xy 27.347709 -7.542207)
			(xy 27.299402 -7.507592) (xy 27.277822 -7.487158) (xy 27.268468 -7.478824) (xy 27.244499 -7.471633)
			(xy 27.232102 -7.473442) (xy 27.194289 -7.480675) (xy 27.11769 -7.488441) (xy 27.079194 -7.488936)
			(xy 27.036504 -7.488338) (xy 26.951661 -7.478774) (xy 26.868413 -7.459811) (xy 26.787798 -7.431685)
			(xy 26.710821 -7.394748) (xy 26.674318 -7.372604) (xy 26.666057 -7.367908) (xy 26.647394 -7.3644)
			(xy 26.628731 -7.367908) (xy 26.62047 -7.372604) (xy 26.583973 -7.394759) (xy 26.506998 -7.431704)
			(xy 26.426382 -7.45983) (xy 26.343131 -7.478785) (xy 26.258285 -7.488333) (xy 26.215594 -7.488936)
			(xy 26.215086 -7.488936) (xy 26.176133 -7.488403) (xy 26.098638 -7.480386) (xy 26.0604 -7.472934)
			(xy 26.047939 -7.471066) (xy 26.023822 -7.478255) (xy 26.014426 -7.48665) (xy 25.992807 -7.507145)
			(xy 25.944442 -7.541917) (xy 25.891268 -7.568766) (xy 25.834574 -7.587043) (xy 25.775731 -7.596305)
			(xy 25.745948 -7.596886) (xy 25.745694 -7.596886) (xy 25.718426 -7.596381) (xy 25.664444 -7.588619)
			(xy 25.612116 -7.573254) (xy 25.562508 -7.550599) (xy 25.516628 -7.521115) (xy 25.475411 -7.485402)
			(xy 25.439696 -7.444187) (xy 25.410209 -7.398308) (xy 25.387552 -7.348701) (xy 25.372184 -7.296374)
			(xy 25.36442 -7.242392) (xy 25.363932 -7.215124) (xy 25.364322 -7.190503) (xy 25.370643 -7.141668)
			(xy 25.383195 -7.094053) (xy 25.392126 -7.071106) (xy 25.395682 -7.062216) (xy 25.395936 -7.042912)
			(xy 25.367742 -6.968744) (xy 25.363994 -6.959989) (xy 25.351197 -6.9459) (xy 25.34285 -6.941312)
			(xy 25.342596 -6.941312) (xy 25.318851 -6.929178) (xy 25.27465 -6.899351) (xy 25.235029 -6.863665)
			(xy 25.200758 -6.822814) (xy 25.172503 -6.777592) (xy 25.150815 -6.728879) (xy 25.136115 -6.677623)
			(xy 25.128688 -6.624819) (xy 25.12822 -6.598158) (xy 25.128685 -6.570888) (xy 25.136452 -6.516905)
			(xy 25.151822 -6.464576) (xy 25.174482 -6.414967) (xy 25.20397 -6.369087) (xy 25.239688 -6.327871)
			(xy 25.280906 -6.292156) (xy 25.326788 -6.26267) (xy 25.376399 -6.240014) (xy 25.428728 -6.224647)
			(xy 25.482712 -6.216884) (xy 25.509982 -6.216396) (xy 25.510236 -6.216396) (xy 25.529794 -6.216904)
			(xy 25.540716 -6.217412) (xy 25.560782 -6.210046) (xy 25.629616 -6.140958) (xy 25.637236 -6.121146)
			(xy 25.636728 -6.110224) (xy 25.63622 -6.091428) (xy 25.63622 -6.09092) (xy 25.636474 -6.080506)
			(xy 25.636474 -6.080252) (xy 25.636153 -6.069429) (xy 25.627618 -6.049555) (xy 25.619964 -6.041898)
			(xy 25.563322 -5.989574) (xy 25.554942 -5.98265) (xy 25.534292 -5.975933) (xy 25.523444 -5.97662)
			(xy 25.522936 -5.97662) (xy 25.512179 -5.977789) (xy 25.490576 -5.979062) (xy 25.479756 -5.97916)
			(xy 25.479502 -5.97916) (xy 25.450651 -5.9786) (xy 25.393604 -5.969923) (xy 25.338511 -5.952764)
			(xy 25.286626 -5.927516) (xy 25.239128 -5.894751) (xy 25.197097 -5.855215) (xy 25.161491 -5.809809)
			(xy 25.133118 -5.759563) (xy 25.122378 -5.73278) (xy 25.117466 -5.721744) (xy 25.09956 -5.705577)
			(xy 25.088088 -5.701792) (xy 25.051355 -5.691562) (xy 24.979972 -5.66474) (xy 24.911615 -5.630943)
			(xy 24.879046 -5.611114) (xy 24.87079 -5.6064) (xy 24.852122 -5.602873) (xy 24.833454 -5.6064) (xy 24.825198 -5.611114)
			(xy 24.791079 -5.631829) (xy 24.719339 -5.66683) (xy 24.644338 -5.694154) (xy 24.605742 -5.704332)
			(xy 24.59405 -5.70797) (xy 24.575735 -5.724163) (xy 24.57069 -5.73532) (xy 24.559805 -5.76186) (xy 24.531308 -5.811642)
			(xy 24.495686 -5.856601) (xy 24.453741 -5.895726) (xy 24.406415 -5.928138) (xy 24.354773 -5.953106)
			(xy 24.299978 -5.97007) (xy 24.243262 -5.978646) (xy 24.214582 -5.97916) (xy 24.203762 -5.979064)
			(xy 24.182159 -5.977792) (xy 24.171402 -5.97662) (xy 24.16048 -5.97535) (xy 24.139652 -5.982208)
			(xy 24.074882 -6.041898) (xy 24.067269 -6.049587) (xy 24.058714 -6.069438) (xy 24.058372 -6.080252)
			(xy 24.058372 -6.080506) (xy 24.058626 -6.09092) (xy 24.058626 -6.091428) (xy 24.058118 -6.110224)
			(xy 24.05761 -6.121146) (xy 24.06523 -6.140958) (xy 24.134064 -6.210046) (xy 24.15413 -6.217412)
			(xy 24.165052 -6.216904) (xy 24.18461 -6.216396) (xy 24.184864 -6.216396) (xy 24.212131 -6.216958)
			(xy 24.266109 -6.224713) (xy 24.318435 -6.240072) (xy 24.368042 -6.262721) (xy 24.413921 -6.292199)
			(xy 24.455138 -6.327907) (xy 24.490854 -6.369116) (xy 24.520342 -6.414989) (xy 24.543001 -6.464592)
			(xy 24.55837 -6.516914) (xy 24.566137 -6.570892) (xy 24.566626 -6.598158) (xy 24.566174 -6.624999)
			(xy 24.558639 -6.67815) (xy 24.54374 -6.729723) (xy 24.52177 -6.778703) (xy 24.49316 -6.824126) (xy 24.458476 -6.865099)
			(xy 24.418398 -6.900813) (xy 24.373716 -6.930568) (xy 24.34971 -6.942582) (xy 24.341074 -6.946646)
			(xy 24.327866 -6.96087) (xy 24.295862 -7.043928) (xy 24.296116 -7.063232) (xy 24.299672 -7.072122)
			(xy 24.308413 -7.094807) (xy 24.320711 -7.141841) (xy 24.326944 -7.190055) (xy 24.327358 -7.214362)
			(xy 24.327358 -7.215124) (xy 24.326898 -7.242394) (xy 24.319133 -7.296379) (xy 24.303764 -7.348709)
			(xy 24.281105 -7.39832) (xy 24.251616 -7.444201) (xy 24.215898 -7.485418) (xy 24.174678 -7.521133)
			(xy 24.128795 -7.550618) (xy 24.079183 -7.573274) (xy 24.026851 -7.588639) (xy 23.972866 -7.5964)
			(xy 23.945596 -7.596886) (xy 23.915904 -7.596347) (xy 23.857238 -7.587133) (xy 23.800708 -7.568942)
			(xy 23.747678 -7.542213) (xy 23.699429 -7.507593) (xy 23.67788 -7.487158) (xy 23.668543 -7.4788)
			(xy 23.64456 -7.471623) (xy 23.63216 -7.473442) (xy 23.594348 -7.480681) (xy 23.517748 -7.488443)
			(xy 23.479252 -7.488936) (xy 23.436563 -7.48831) (xy 23.351721 -7.478753) (xy 23.268473 -7.459796)
			(xy 23.187857 -7.431677) (xy 23.11088 -7.394745) (xy 23.074376 -7.372604) (xy 23.066115 -7.367908)
			(xy 23.047452 -7.3644) (xy 23.028789 -7.367908) (xy 23.020528 -7.372604) (xy 22.984017 -7.394735)
			(xy 22.907046 -7.431684) (xy 22.826434 -7.459815) (xy 22.743186 -7.478776) (xy 22.658342 -7.48833)
			(xy 22.615652 -7.488936) (xy 22.615144 -7.488936) (xy 22.576191 -7.488395) (xy 22.498696 -7.480383)
			(xy 22.460458 -7.472934) (xy 22.447998 -7.471038) (xy 22.423878 -7.478246) (xy 22.414484 -7.48665)
			(xy 22.392883 -7.507165) (xy 22.344513 -7.541934) (xy 22.291335 -7.56878) (xy 22.234637 -7.587052)
			(xy 22.175791 -7.596308) (xy 22.146006 -7.596886) (xy 22.145752 -7.596886) (xy 22.118483 -7.59642)
			(xy 22.064499 -7.588653) (xy 22.012171 -7.573282) (xy 21.962562 -7.550622) (xy 21.916683 -7.521134)
			(xy 21.875466 -7.485417) (xy 21.839752 -7.444198) (xy 21.810266 -7.398317) (xy 21.787609 -7.348706)
			(xy 21.772242 -7.296377) (xy 21.764478 -7.242393) (xy 21.76399 -7.215124) (xy 21.764383 -7.190503)
			(xy 21.770703 -7.141669) (xy 21.783254 -7.094053) (xy 21.792184 -7.071106) (xy 21.79574 -7.062216)
			(xy 21.795994 -7.042912) (xy 21.7678 -6.968744) (xy 21.764067 -6.959981) (xy 21.75126 -6.945895)
			(xy 21.742908 -6.941312) (xy 21.742654 -6.941312) (xy 21.718899 -6.929197) (xy 21.6747 -6.899365)
			(xy 21.635081 -6.863676) (xy 21.600811 -6.822821) (xy 21.572559 -6.777597) (xy 21.550872 -6.728882)
			(xy 21.536172 -6.677624) (xy 21.528746 -6.62482) (xy 21.528278 -6.598158) (xy 21.528686 -6.570886)
			(xy 21.536454 -6.516897) (xy 21.551827 -6.464564) (xy 21.574491 -6.414951) (xy 21.603985 -6.369068)
			(xy 21.639708 -6.32785) (xy 21.680934 -6.292135) (xy 21.726823 -6.262651) (xy 21.776441 -6.239998)
			(xy 21.828778 -6.224636) (xy 21.882768 -6.21688) (xy 21.91004 -6.216396) (xy 21.910294 -6.216396)
			(xy 21.929852 -6.216904) (xy 21.940774 -6.217412) (xy 21.96084 -6.210046) (xy 22.029674 -6.140958)
			(xy 22.037294 -6.121146) (xy 22.036786 -6.110224) (xy 22.036278 -6.091174) (xy 22.036278 -6.09092)
			(xy 22.036532 -6.080252) (xy 22.036291 -6.069359) (xy 22.027727 -6.049348) (xy 22.020022 -6.041644)
			(xy 21.96338 -5.989574) (xy 21.955015 -5.982629) (xy 21.934353 -5.975924) (xy 21.923502 -5.97662)
			(xy 21.922994 -5.97662) (xy 21.91211 -5.9778) (xy 21.890253 -5.979073) (xy 21.879306 -5.97916) (xy 21.85044 -5.97859)
			(xy 21.793362 -5.969925) (xy 21.738241 -5.952761) (xy 21.686334 -5.927489) (xy 21.638827 -5.894687)
			(xy 21.596802 -5.855103) (xy 21.56122 -5.809641) (xy 21.532892 -5.759337) (xy 21.522182 -5.732526)
			(xy 21.517223 -5.721456) (xy 21.499175 -5.705292) (xy 21.487638 -5.701538) (xy 21.450996 -5.691276)
			(xy 21.379787 -5.664441) (xy 21.3116 -5.630658) (xy 21.279104 -5.61086) (xy 21.270843 -5.606164)
			(xy 21.25218 -5.602656) (xy 21.233517 -5.606164) (xy 21.225256 -5.61086) (xy 21.191098 -5.631619)
			(xy 21.119283 -5.666721) (xy 21.044191 -5.694123) (xy 21.005546 -5.704332) (xy 20.993855 -5.707971)
			(xy 20.975539 -5.724163) (xy 20.970494 -5.73532) (xy 20.959606 -5.761859) (xy 20.931109 -5.81164)
			(xy 20.895488 -5.856599) (xy 20.853543 -5.895725) (xy 20.806217 -5.928136) (xy 20.754576 -5.953105)
			(xy 20.699782 -5.970069) (xy 20.643066 -5.978646) (xy 20.614386 -5.97916) (xy 20.60363 -5.979053)
			(xy 20.582154 -5.977783) (xy 20.57146 -5.97662) (xy 20.560538 -5.97535) (xy 20.53971 -5.982208) (xy 20.47494 -6.041898)
			(xy 20.467321 -6.049581) (xy 20.45877 -6.069437) (xy 20.45843 -6.080252) (xy 20.45843 -6.080506)
			(xy 20.458684 -6.090666) (xy 20.458684 -6.091174) (xy 20.458176 -6.110224) (xy 20.457668 -6.121146)
			(xy 20.465288 -6.140958) (xy 20.534122 -6.210046) (xy 20.554188 -6.217412) (xy 20.56511 -6.216904)
			(xy 20.584668 -6.216396) (xy 20.584922 -6.216396) (xy 20.61219 -6.216904) (xy 20.666171 -6.224667)
			(xy 20.718497 -6.240033) (xy 20.768105 -6.262689) (xy 20.813983 -6.292173) (xy 20.8552 -6.327886)
			(xy 20.890915 -6.369101) (xy 20.920401 -6.414978) (xy 20.94306 -6.464584) (xy 20.958428 -6.51691)
			(xy 20.966195 -6.57089) (xy 20.966684 -6.598158) (xy 20.9662 -6.624997) (xy 20.958666 -6.678145)
			(xy 20.943769 -6.729716) (xy 20.921803 -6.778694) (xy 20.893198 -6.824117) (xy 20.858519 -6.86509)
			(xy 20.818447 -6.900807) (xy 20.773772 -6.930565) (xy 20.749768 -6.942582) (xy 20.741132 -6.946646)
			(xy 20.727924 -6.96087) (xy 20.69592 -7.043928) (xy 20.696174 -7.063232) (xy 20.69973 -7.072122)
			(xy 20.708469 -7.094807) (xy 20.720768 -7.141841) (xy 20.727002 -7.190055) (xy 20.727416 -7.214362)
			(xy 20.727416 -7.215124) (xy 20.727021 -7.242398) (xy 20.719254 -7.296389) (xy 20.703882 -7.348726)
			(xy 20.681219 -7.398342) (xy 20.651724 -7.444228) (xy 20.616 -7.485449) (xy 20.574772 -7.521166)
			(xy 20.528881 -7.550652) (xy 20.47926 -7.573307) (xy 20.426921 -7.588669) (xy 20.372928 -7.596426)
			(xy 20.345654 -7.596886) (xy 20.315963 -7.596311) (xy 20.257299 -7.587105) (xy 20.20077 -7.568923)
			(xy 20.147739 -7.542203) (xy 20.099488 -7.50759) (xy 20.077938 -7.487158) (xy 20.068577 -7.478834)
			(xy 20.044613 -7.471637) (xy 20.032218 -7.473442) (xy 19.994407 -7.480687) (xy 19.917806 -7.488445)
			(xy 19.87931 -7.488936) (xy 19.83662 -7.48833) (xy 19.751777 -7.478768) (xy 19.668529 -7.459807)
			(xy 19.587914 -7.431683) (xy 19.510937 -7.394747) (xy 19.474434 -7.372604) (xy 19.466173 -7.367908)
			(xy 19.44751 -7.3644) (xy 19.428847 -7.367908) (xy 19.420586 -7.372604) (xy 19.384085 -7.394752)
			(xy 19.307112 -7.431698) (xy 19.226496 -7.459825) (xy 19.143246 -7.478782) (xy 19.0584 -7.488332)
			(xy 19.01571 -7.488936) (xy 19.015202 -7.488936) (xy 18.976249 -7.488401) (xy 18.898754 -7.480385)
			(xy 18.860516 -7.472934) (xy 18.848054 -7.471077) (xy 18.823939 -7.478258) (xy 18.814542 -7.48665)
			(xy 18.792959 -7.507185) (xy 18.744584 -7.541952) (xy 18.691402 -7.568794) (xy 18.6347 -7.587061)
			(xy 18.57585 -7.596312) (xy 18.546064 -7.596886) (xy 18.54581 -7.596886) (xy 18.518542 -7.596366)
			(xy 18.464561 -7.588607) (xy 18.412233 -7.573244) (xy 18.362625 -7.550591) (xy 18.316745 -7.521108)
			(xy 18.275528 -7.485396) (xy 18.239812 -7.444182) (xy 18.210326 -7.398305) (xy 18.187668 -7.348699)
			(xy 18.172301 -7.296372) (xy 18.164536 -7.242392) (xy 18.164048 -7.215124) (xy 18.164437 -7.190503)
			(xy 18.170758 -7.141668) (xy 18.183311 -7.094053) (xy 18.192242 -7.071106) (xy 18.195798 -7.062216)
			(xy 18.196052 -7.042912) (xy 18.167858 -6.968744) (xy 18.164104 -6.959992) (xy 18.151311 -6.945901)
			(xy 18.142966 -6.941312) (xy 18.142712 -6.941312) (xy 18.118971 -6.92917) (xy 18.07477 -6.899345)
			(xy 18.035148 -6.863661) (xy 18.000876 -6.822811) (xy 17.972621 -6.77759) (xy 17.950932 -6.728878)
			(xy 17.936231 -6.677622) (xy 17.928805 -6.624819) (xy 17.928336 -6.598158) (xy 14.626082 -6.598158)
			(xy 14.626082 -9.780016) (xy 14.625583 -9.863891) (xy 14.617601 -10.03145) (xy 14.601655 -10.198441)
			(xy 14.577781 -10.364483) (xy 14.546034 -10.529201) (xy 14.506486 -10.692222) (xy 14.459225 -10.853176)
			(xy 14.404359 -11.0117) (xy 14.342013 -11.167433) (xy 14.272327 -11.320024) (xy 14.195459 -11.469125)
			(xy 14.111585 -11.614401) (xy 14.020892 -11.755521) (xy 13.923588 -11.892166) (xy 13.819892 -12.024026)
			(xy 13.710039 -12.150802) (xy 13.594279 -12.272209) (xy 13.4866 -12.37488) (xy 56.486552 -12.37488)
			(xy 56.487006 -12.34761) (xy 56.494771 -12.293624) (xy 56.510139 -12.241293) (xy 56.532799 -12.191682)
			(xy 56.562288 -12.1458) (xy 56.598007 -12.104583) (xy 56.639228 -12.068868) (xy 56.685112 -12.039382)
			(xy 56.734725 -12.016727) (xy 56.787057 -12.001363) (xy 56.841043 -11.993603) (xy 56.868314 -11.993118)
			(xy 56.898004 -11.993712) (xy 56.956667 -12.002913) (xy 57.013197 -12.021091) (xy 57.066228 -12.047807)
			(xy 57.11448 -12.082416) (xy 57.13603 -12.102846) (xy 57.145404 -12.111153) (xy 57.169357 -12.11836)
			(xy 57.18175 -12.116562) (xy 57.219562 -12.109322) (xy 57.296162 -12.101561) (xy 57.334658 -12.101068)
			(xy 57.377347 -12.101704) (xy 57.462188 -12.111261) (xy 57.545435 -12.130216) (xy 57.626051 -12.158333)
			(xy 57.70303 -12.195261) (xy 57.739534 -12.2174) (xy 57.747795 -12.222096) (xy 57.766458 -12.225604)
			(xy 57.785121 -12.222096) (xy 57.793382 -12.2174) (xy 57.829891 -12.195266) (xy 57.906862 -12.158317)
			(xy 57.987475 -12.130187) (xy 58.070724 -12.111227) (xy 58.155568 -12.101674) (xy 58.198258 -12.101068)
			(xy 58.198766 -12.101068) (xy 58.237719 -12.101608) (xy 58.315214 -12.109621) (xy 58.353452 -12.11707)
			(xy 58.365915 -12.118932) (xy 58.390033 -12.111751) (xy 58.399426 -12.103354) (xy 58.421023 -12.082835)
			(xy 58.469394 -12.048066) (xy 58.522573 -12.021221) (xy 58.579272 -12.00295) (xy 58.638119 -11.993695)
			(xy 58.667904 -11.993118) (xy 58.668158 -11.993118) (xy 58.695427 -11.99364) (xy 58.749411 -12.001396)
			(xy 58.801741 -12.016756) (xy 58.851353 -12.039408) (xy 58.897236 -12.068889) (xy 58.938456 -12.1046)
			(xy 58.974174 -12.145815) (xy 59.003663 -12.191693) (xy 59.026322 -12.241301) (xy 59.04169 -12.293629)
			(xy 59.049455 -12.347611) (xy 59.04992 -12.37488) (xy 59.049404 -12.403036) (xy 59.044311 -12.43711)
			(xy 62.309756 -12.43711) (xy 62.310222 -12.396003) (xy 62.317806 -12.314139) (xy 62.332909 -12.233324)
			(xy 62.355404 -12.154247) (xy 62.385098 -12.077583) (xy 62.421737 -12.003984) (xy 62.46501 -11.93408)
			(xy 62.514548 -11.868466) (xy 62.569927 -11.807701) (xy 62.630676 -11.752305) (xy 62.696277 -11.70275)
			(xy 62.766169 -11.659457) (xy 62.839757 -11.622797) (xy 62.916414 -11.593082) (xy 62.995485 -11.570566)
			(xy 63.076295 -11.55544) (xy 63.158157 -11.547833) (xy 63.199264 -11.547348) (xy 63.243059 -11.547873)
			(xy 63.330225 -11.556491) (xy 63.416121 -11.573637) (xy 63.499915 -11.599145) (xy 63.580795 -11.632768)
			(xy 63.619634 -11.653012) (xy 63.6311 -11.65843) (xy 63.656428 -11.65843) (xy 63.667894 -11.653012)
			(xy 63.706738 -11.632781) (xy 63.787623 -11.599174) (xy 63.871416 -11.573672) (xy 63.957309 -11.556521)
			(xy 64.04447 -11.547888) (xy 64.088264 -11.547348) (xy 64.132059 -11.547873) (xy 64.219225 -11.556491)
			(xy 64.305121 -11.573637) (xy 64.388915 -11.599145) (xy 64.469795 -11.632768) (xy 64.508634 -11.653012)
			(xy 64.5201 -11.65843) (xy 64.545428 -11.65843) (xy 64.556894 -11.653012) (xy 64.595738 -11.632781)
			(xy 64.676623 -11.599174) (xy 64.760416 -11.573672) (xy 64.846309 -11.556521) (xy 64.93347 -11.547888)
			(xy 64.977264 -11.547348) (xy 65.021059 -11.547873) (xy 65.108225 -11.556491) (xy 65.194121 -11.573637)
			(xy 65.277915 -11.599145) (xy 65.358795 -11.632768) (xy 65.397634 -11.653012) (xy 65.4091 -11.65843)
			(xy 65.434428 -11.65843) (xy 65.445894 -11.653012) (xy 65.484738 -11.632781) (xy 65.565623 -11.599174)
			(xy 65.649416 -11.573672) (xy 65.735309 -11.556521) (xy 65.82247 -11.547888) (xy 65.866264 -11.547348)
			(xy 65.904554 -11.547763) (xy 65.980848 -11.554368) (xy 66.05629 -11.567515) (xy 66.130321 -11.587105)
			(xy 66.166492 -11.599672) (xy 66.174929 -11.602323) (xy 66.192599 -11.602323) (xy 66.201036 -11.599672)
			(xy 66.237216 -11.587135) (xy 66.311248 -11.56756) (xy 66.386687 -11.554411) (xy 66.462976 -11.547785)
			(xy 66.501264 -11.547348) (xy 66.54268 -11.547848) (xy 66.625149 -11.555593) (xy 66.706543 -11.570964)
			(xy 66.786158 -11.593827) (xy 66.863305 -11.623986) (xy 66.937318 -11.661178) (xy 66.972688 -11.68273)
			(xy 66.980074 -11.686987) (xy 66.996689 -11.690769) (xy 67.013625 -11.688896) (xy 67.021456 -11.685524)
			(xy 67.057233 -11.668994) (xy 67.131154 -11.641645) (xy 67.207206 -11.620946) (xy 67.284791 -11.607058)
			(xy 67.363301 -11.600092) (xy 67.40271 -11.599672) (xy 67.443826 -11.600089) (xy 67.525707 -11.607677)
			(xy 67.606539 -11.622789) (xy 67.685632 -11.645294) (xy 67.76231 -11.675001) (xy 67.835921 -11.711656)
			(xy 67.905835 -11.754947) (xy 67.971457 -11.804505) (xy 68.032226 -11.859906) (xy 68.087623 -11.920677)
			(xy 68.137178 -11.986301) (xy 68.180465 -12.056218) (xy 68.217117 -12.12983) (xy 68.24682 -12.20651)
			(xy 68.269321 -12.285604) (xy 68.284429 -12.366436) (xy 68.285211 -12.37488) (xy 70.481444 -12.37488)
			(xy 70.481906 -12.34761) (xy 70.48967 -12.293625) (xy 70.505039 -12.241295) (xy 70.527698 -12.191684)
			(xy 70.557186 -12.145803) (xy 70.592904 -12.104585) (xy 70.634124 -12.06887) (xy 70.680007 -12.039385)
			(xy 70.729619 -12.016729) (xy 70.781951 -12.001365) (xy 70.835936 -11.993604) (xy 70.863206 -11.993118)
			(xy 70.89292 -11.993676) (xy 70.95163 -12.002888) (xy 71.008208 -12.021075) (xy 71.061289 -12.047797)
			(xy 71.109596 -12.082412) (xy 71.131176 -12.102846) (xy 71.140531 -12.111179) (xy 71.164499 -12.11837)
			(xy 71.176896 -12.116562) (xy 71.214709 -12.10933) (xy 71.291308 -12.101564) (xy 71.329804 -12.101068)
			(xy 71.372493 -12.101682) (xy 71.457336 -12.111244) (xy 71.540583 -12.130204) (xy 71.621198 -12.158326)
			(xy 71.698176 -12.195259) (xy 71.73468 -12.2174) (xy 71.742941 -12.222096) (xy 71.761604 -12.225604)
			(xy 71.780267 -12.222096) (xy 71.788528 -12.2174) (xy 71.825026 -12.195247) (xy 71.902 -12.158301)
			(xy 71.982616 -12.130175) (xy 72.065867 -12.111219) (xy 72.150713 -12.101671) (xy 72.193404 -12.101068)
			(xy 72.193912 -12.101068) (xy 72.232865 -12.101601) (xy 72.31036 -12.109618) (xy 72.348598 -12.11707)
			(xy 72.361059 -12.118963) (xy 72.385181 -12.111761) (xy 72.394572 -12.103354) (xy 72.416193 -12.082861)
			(xy 72.464557 -12.048088) (xy 72.51773 -12.021239) (xy 72.574424 -12.002961) (xy 72.633267 -11.993699)
			(xy 72.66305 -11.993118) (xy 72.663304 -11.993118) (xy 72.690573 -11.993621) (xy 72.744555 -12.001382)
			(xy 72.796883 -12.016747) (xy 72.846491 -12.039402) (xy 72.892371 -12.068887) (xy 72.933588 -12.1046)
			(xy 72.969304 -12.145816) (xy 72.99879 -12.191695) (xy 73.021447 -12.241302) (xy 73.036814 -12.29363)
			(xy 73.044578 -12.347611) (xy 73.045066 -12.37488) (xy 73.044538 -12.403035) (xy 73.036215 -12.458728)
			(xy 73.019806 -12.512595) (xy 72.995666 -12.563469) (xy 72.964318 -12.610248) (xy 72.945752 -12.63142)
			(xy 72.93775 -12.641221) (xy 72.931625 -12.665741) (xy 72.934068 -12.678156) (xy 72.944876 -12.723941)
			(xy 72.956471 -12.8173) (xy 72.957182 -12.864338) (xy 72.957182 -12.864846) (xy 72.956615 -12.906728)
			(xy 72.947438 -12.989988) (xy 72.9292 -13.071742) (xy 72.902121 -13.151008) (xy 72.866525 -13.226832)
			(xy 72.845168 -13.262864) (xy 72.840715 -13.270912) (xy 72.837355 -13.288984) (xy 72.840563 -13.307083)
			(xy 72.844914 -13.315188) (xy 72.85761 -13.337389) (xy 72.877642 -13.384446) (xy 72.891212 -13.433755)
			(xy 72.898078 -13.484435) (xy 72.898508 -13.510006) (xy 72.898508 -13.510514) (xy 72.897989 -13.537782)
			(xy 72.890226 -13.591762) (xy 72.874862 -13.644088) (xy 72.852207 -13.693695) (xy 72.822724 -13.739574)
			(xy 72.787012 -13.78079) (xy 72.745799 -13.816505) (xy 72.699923 -13.845992) (xy 72.650318 -13.86865)
			(xy 72.597993 -13.88402) (xy 72.544014 -13.891786) (xy 72.516746 -13.892276) (xy 72.488603 -13.891794)
			(xy 72.432928 -13.883522) (xy 72.379071 -13.867166) (xy 72.328198 -13.84308) (xy 72.281414 -13.811786)
			(xy 72.23973 -13.773962) (xy 72.204052 -13.730428) (xy 72.175152 -13.682128) (xy 72.16394 -13.65631)
			(xy 72.16002 -13.647995) (xy 72.147384 -13.634661) (xy 72.130881 -13.626592) (xy 72.121776 -13.625322)
			(xy 72.086458 -13.621561) (xy 72.01667 -13.608331) (xy 71.948413 -13.588672) (xy 71.88228 -13.562755)
			(xy 71.818841 -13.530802) (xy 71.788528 -13.512292) (xy 71.780267 -13.507596) (xy 71.761604 -13.504088)
			(xy 71.742941 -13.507596) (xy 71.73468 -13.512292) (xy 71.69818 -13.534441) (xy 71.621206 -13.571388)
			(xy 71.540591 -13.599515) (xy 71.45734 -13.618471) (xy 71.372495 -13.62802) (xy 71.329804 -13.628624)
			(xy 71.289805 -13.628051) (xy 71.210246 -13.61969) (xy 71.131996 -13.603058) (xy 71.055913 -13.578339)
			(xy 70.982831 -13.545802) (xy 70.91355 -13.505805) (xy 70.848829 -13.458785) (xy 70.789377 -13.405258)
			(xy 70.735846 -13.34581) (xy 70.688822 -13.281092) (xy 70.648821 -13.211814) (xy 70.616279 -13.138734)
			(xy 70.591555 -13.062653) (xy 70.574918 -12.984404) (xy 70.566552 -12.904845) (xy 70.566026 -12.864846)
			(xy 70.56678 -12.817023) (xy 70.578755 -12.722128) (xy 70.589902 -12.675616) (xy 70.592373 -12.663288)
			(xy 70.586386 -12.638903) (xy 70.578472 -12.629134) (xy 70.560306 -12.608033) (xy 70.529636 -12.561564)
			(xy 70.506046 -12.511131) (xy 70.490037 -12.457805) (xy 70.481948 -12.402719) (xy 70.481444 -12.37488)
			(xy 68.285211 -12.37488) (xy 68.292013 -12.448318) (xy 68.292472 -12.489434) (xy 68.291907 -12.533047)
			(xy 68.283357 -12.619854) (xy 68.266352 -12.705408) (xy 68.241056 -12.788886) (xy 68.207711 -12.869488)
			(xy 68.166638 -12.946439) (xy 68.118231 -13.019001) (xy 68.062955 -13.086478) (xy 68.00134 -13.14822)
			(xy 67.933978 -13.203636) (xy 67.861516 -13.252193) (xy 67.823334 -13.273278) (xy 67.814055 -13.278811)
			(xy 67.800889 -13.295908) (xy 67.797934 -13.306298) (xy 67.787525 -13.3474) (xy 67.759881 -13.427561)
			(xy 67.724737 -13.504728) (xy 67.682409 -13.578201) (xy 67.633283 -13.647314) (xy 67.577804 -13.711439)
			(xy 67.516475 -13.769995) (xy 67.449854 -13.82245) (xy 67.378544 -13.868328) (xy 67.303192 -13.907213)
			(xy 67.224482 -13.938753) (xy 67.143129 -13.96266) (xy 67.05987 -13.978719) (xy 66.975461 -13.986784)
			(xy 66.933064 -13.987272) (xy 66.894775 -13.986847) (xy 66.818481 -13.980245) (xy 66.743038 -13.967101)
			(xy 66.669007 -13.947513) (xy 66.632836 -13.934948) (xy 66.624399 -13.932297) (xy 66.606729 -13.932297)
			(xy 66.598292 -13.934948) (xy 66.56211 -13.947478) (xy 66.488079 -13.967055) (xy 66.41264 -13.980205)
			(xy 66.336352 -13.986834) (xy 66.298064 -13.987272) (xy 66.254269 -13.986733) (xy 66.167104 -13.978118)
			(xy 66.081208 -13.960975) (xy 65.997414 -13.93547) (xy 65.916534 -13.90185) (xy 65.877694 -13.881608)
			(xy 65.866228 -13.87619) (xy 65.8409 -13.87619) (xy 65.829434 -13.881608) (xy 65.790581 -13.901822)
			(xy 65.709699 -13.935433) (xy 65.625908 -13.96094) (xy 65.540018 -13.978094) (xy 65.452857 -13.986731)
			(xy 65.409064 -13.987272) (xy 65.365269 -13.986733) (xy 65.278104 -13.978118) (xy 65.192208 -13.960975)
			(xy 65.108414 -13.93547) (xy 65.027534 -13.90185) (xy 64.988694 -13.881608) (xy 64.977228 -13.87619)
			(xy 64.9519 -13.87619) (xy 64.940434 -13.881608) (xy 64.901581 -13.901822) (xy 64.820699 -13.935433)
			(xy 64.736908 -13.96094) (xy 64.651018 -13.978094) (xy 64.563857 -13.986731) (xy 64.520064 -13.987272)
			(xy 64.476269 -13.986733) (xy 64.389104 -13.978118) (xy 64.303208 -13.960975) (xy 64.219414 -13.93547)
			(xy 64.138534 -13.90185) (xy 64.099694 -13.881608) (xy 64.088228 -13.87619) (xy 64.0629 -13.87619)
			(xy 64.051434 -13.881608) (xy 64.012581 -13.901822) (xy 63.931699 -13.935433) (xy 63.847908 -13.96094)
			(xy 63.762018 -13.978094) (xy 63.674857 -13.986731) (xy 63.631064 -13.987272) (xy 63.588804 -13.98679)
			(xy 63.504665 -13.978779) (xy 63.421665 -13.962822) (xy 63.340553 -13.939064) (xy 63.26206 -13.907718)
			(xy 63.186895 -13.869068) (xy 63.115735 -13.823463) (xy 63.049222 -13.771312) (xy 62.987956 -13.713088)
			(xy 62.93249 -13.649314) (xy 62.883323 -13.580566) (xy 62.840899 -13.507464) (xy 62.805601 -13.430668)
			(xy 62.777747 -13.35087) (xy 62.757589 -13.268789) (xy 62.750954 -13.22705) (xy 62.748768 -13.216225)
			(xy 62.736658 -13.197787) (xy 62.727586 -13.19149) (xy 62.693115 -13.169417) (xy 62.628004 -13.119803)
			(xy 62.567725 -13.064419) (xy 62.512788 -13.003732) (xy 62.463657 -12.938255) (xy 62.420747 -12.868543)
			(xy 62.384422 -12.795185) (xy 62.354987 -12.7188) (xy 62.332693 -12.640034) (xy 62.317728 -12.559554)
			(xy 62.310218 -12.47804) (xy 62.309756 -12.43711) (xy 59.044311 -12.43711) (xy 59.04108 -12.458729)
			(xy 59.024669 -12.512597) (xy 59.000526 -12.563471) (xy 58.969174 -12.610249) (xy 58.950606 -12.63142)
			(xy 58.942601 -12.641218) (xy 58.93648 -12.66574) (xy 58.938922 -12.678156) (xy 58.949729 -12.723941)
			(xy 58.961325 -12.8173) (xy 58.962036 -12.864338) (xy 58.962036 -12.864846) (xy 58.961598 -12.904849)
			(xy 58.95323 -12.984415) (xy 58.936592 -13.062672) (xy 58.911864 -13.13876) (xy 58.879319 -13.211847)
			(xy 58.839312 -13.281131) (xy 58.792282 -13.345854) (xy 58.738745 -13.405307) (xy 58.679286 -13.458838)
			(xy 58.614557 -13.50586) (xy 58.545268 -13.545859) (xy 58.472178 -13.578396) (xy 58.396087 -13.603115)
			(xy 58.317828 -13.619744) (xy 58.238261 -13.628103) (xy 58.198258 -13.628624) (xy 58.155569 -13.627982)
			(xy 58.070728 -13.618427) (xy 57.987481 -13.599473) (xy 57.906865 -13.571357) (xy 57.829886 -13.53443)
			(xy 57.793382 -13.512292) (xy 57.785121 -13.507596) (xy 57.766458 -13.504088) (xy 57.747795 -13.507596)
			(xy 57.739534 -13.512292) (xy 57.703045 -13.53446) (xy 57.626068 -13.571403) (xy 57.54545 -13.599526)
			(xy 57.462197 -13.618478) (xy 57.377349 -13.628023) (xy 57.334658 -13.628624) (xy 57.294658 -13.628094)
			(xy 57.215097 -13.619728) (xy 57.136847 -13.603093) (xy 57.060764 -13.578369) (xy 56.987681 -13.545828)
			(xy 56.9184 -13.505828) (xy 56.85368 -13.458804) (xy 56.794229 -13.405274) (xy 56.740698 -13.345823)
			(xy 56.693675 -13.281103) (xy 56.653673 -13.211822) (xy 56.621133 -13.13874) (xy 56.596409 -13.062657)
			(xy 56.579772 -12.984407) (xy 56.571406 -12.904846) (xy 56.57088 -12.864846) (xy 56.57088 -12.864338)
			(xy 56.571655 -12.816579) (xy 56.583625 -12.721812) (xy 56.594756 -12.675362) (xy 56.597276 -12.663039)
			(xy 56.591257 -12.638645) (xy 56.583326 -12.62888) (xy 56.565202 -12.607789) (xy 56.534612 -12.561352)
			(xy 56.511086 -12.510968) (xy 56.49512 -12.457702) (xy 56.487053 -12.402683) (xy 56.486552 -12.37488)
			(xy 13.4866 -12.37488) (xy 13.472872 -12.387969) (xy 13.346096 -12.497822) (xy 13.214236 -12.601518)
			(xy 13.077591 -12.698822) (xy 12.936471 -12.789515) (xy 12.791195 -12.873389) (xy 12.642094 -12.950257)
			(xy 12.489503 -13.019943) (xy 12.33377 -13.082289) (xy 12.175246 -13.137155) (xy 12.014292 -13.184416)
			(xy 11.851271 -13.223964) (xy 11.686553 -13.255711) (xy 11.520511 -13.279585) (xy 11.35352 -13.295531)
			(xy 11.185961 -13.303513) (xy 11.102086 -13.304012) (xy 1.999996 -13.304012) (xy 1.96883 -13.3045)
			(xy 1.907031 -13.312637) (xy 1.846823 -13.32877) (xy 1.789236 -13.352624) (xy 1.735255 -13.383791)
			(xy 1.685804 -13.421737) (xy 1.641729 -13.465813) (xy 1.603784 -13.515265) (xy 1.572619 -13.569247)
			(xy 1.548766 -13.626834) (xy 1.532634 -13.687043) (xy 1.524499 -13.748842) (xy 1.524 -13.780008)
			(xy 1.524 -16.5207) (xy 76.28834 -16.5207) (xy 76.29237 -16.436094) (xy 76.304425 -16.352254) (xy 76.324394 -16.26994)
			(xy 76.352098 -16.189896) (xy 76.387284 -16.112849) (xy 76.429635 -16.039495) (xy 76.478768 -15.970499)
			(xy 76.534236 -15.906485) (xy 76.595538 -15.848035) (xy 76.662118 -15.795676) (xy 76.733375 -15.749883)
			(xy 76.808661 -15.711071) (xy 76.887296 -15.679591) (xy 76.968567 -15.655728) (xy 77.051738 -15.639698)
			(xy 77.136057 -15.631648) (xy 77.178408 -15.63116) (xy 77.178916 -15.63116) (xy 77.224101 -15.631724)
			(xy 77.314005 -15.640873) (xy 77.402518 -15.659097) (xy 77.488725 -15.686205) (xy 77.530452 -15.70355)
			(xy 77.539034 -15.706862) (xy 77.557395 -15.707764) (xy 77.566266 -15.705328) (xy 77.610936 -15.69133)
			(xy 77.702468 -15.671687) (xy 77.795557 -15.661772) (xy 77.842364 -15.661132) (xy 77.84338 -15.661132)
			(xy 77.885732 -15.661539) (xy 77.970052 -15.669589) (xy 78.053225 -15.685618) (xy 78.134498 -15.70948)
			(xy 78.213134 -15.74096) (xy 78.288422 -15.779772) (xy 78.35968 -15.825565) (xy 78.426262 -15.877924)
			(xy 78.487566 -15.936376) (xy 78.543035 -16.00039) (xy 78.592169 -16.069387) (xy 78.634521 -16.142742)
			(xy 78.669709 -16.219791) (xy 78.697413 -16.299835) (xy 78.717383 -16.382151) (xy 78.722326 -16.416528)
			(xy 191.571372 -16.416528) (xy 191.571784 -16.378238) (xy 191.57839 -16.301944) (xy 191.591537 -16.226502)
			(xy 191.611129 -16.152471) (xy 191.623696 -16.1163) (xy 191.626331 -16.10786) (xy 191.62634 -16.090193)
			(xy 191.623696 -16.081756) (xy 191.611158 -16.045577) (xy 191.591583 -15.971544) (xy 191.578434 -15.896105)
			(xy 191.571809 -15.819816) (xy 191.571372 -15.781528) (xy 191.571879 -15.740418) (xy 191.579464 -15.65855)
			(xy 191.594572 -15.577731) (xy 191.617074 -15.498651) (xy 191.646778 -15.421985) (xy 191.68343 -15.348387)
			(xy 191.726718 -15.278486) (xy 191.776272 -15.212878) (xy 191.831669 -15.152124) (xy 191.892437 -15.096741)
			(xy 191.958056 -15.047202) (xy 192.027967 -15.00393) (xy 192.101573 -14.967295) (xy 192.178246 -14.937609)
			(xy 192.257331 -14.915125) (xy 192.338154 -14.900036) (xy 192.420024 -14.89247) (xy 192.461134 -14.89202)
			(xy 192.499451 -14.892376) (xy 192.575804 -14.898912) (xy 192.651311 -14.912) (xy 192.72541 -14.931543)
			(xy 192.761616 -14.94409) (xy 192.769932 -14.946676) (xy 192.787336 -14.946676) (xy 192.795652 -14.94409)
			(xy 192.831863 -14.931562) (xy 192.905965 -14.912041) (xy 192.981469 -14.898959) (xy 193.057819 -14.892413)
			(xy 193.096134 -14.89202) (xy 193.134451 -14.892376) (xy 193.210804 -14.898912) (xy 193.286311 -14.912)
			(xy 193.36041 -14.931543) (xy 193.396616 -14.94409) (xy 193.404932 -14.946676) (xy 193.422336 -14.946676)
			(xy 193.430652 -14.94409) (xy 193.466772 -14.93159) (xy 193.540685 -14.912102) (xy 193.615997 -14.899021)
			(xy 193.692153 -14.892442) (xy 193.730372 -14.89202) (xy 193.731134 -14.89202) (xy 193.772241 -14.89248)
			(xy 193.854104 -14.900067) (xy 193.934917 -14.915174) (xy 194.013993 -14.937671) (xy 194.090656 -14.967367)
			(xy 194.164253 -15.004008) (xy 194.234156 -15.047282) (xy 194.299769 -15.09682) (xy 194.360532 -15.152199)
			(xy 194.415928 -15.212948) (xy 194.465484 -15.278547) (xy 194.508776 -15.348439) (xy 194.545437 -15.422026)
			(xy 194.575153 -15.498681) (xy 194.597672 -15.577751) (xy 194.6128 -15.658561) (xy 194.620409 -15.740421)
			(xy 194.620896 -15.781528) (xy 194.620451 -15.819809) (xy 194.613795 -15.896082) (xy 194.600605 -15.971499)
			(xy 194.591178 -16.008604) (xy 194.588893 -16.019174) (xy 194.592456 -16.040487) (xy 194.598036 -16.049752)
			(xy 194.621836 -16.08633) (xy 194.662956 -16.163308) (xy 194.696348 -16.24394) (xy 194.721691 -16.327453)
			(xy 194.738741 -16.413043) (xy 194.747336 -16.499892) (xy 194.747896 -16.543528) (xy 194.747474 -16.584639)
			(xy 194.739884 -16.666511) (xy 194.72477 -16.747333) (xy 194.702263 -16.826416) (xy 194.672553 -16.903083)
			(xy 194.635895 -16.976682) (xy 194.592602 -17.046584) (xy 194.543042 -17.112192) (xy 194.487639 -17.172947)
			(xy 194.426866 -17.22833) (xy 194.361241 -17.277868) (xy 194.291325 -17.321138) (xy 194.217714 -17.357772)
			(xy 194.141037 -17.387456) (xy 194.061947 -17.409938) (xy 193.98112 -17.425024) (xy 193.899246 -17.432588)
			(xy 193.858134 -17.433036) (xy 193.814503 -17.432505) (xy 193.727659 -17.42397) (xy 193.642069 -17.40697)
			(xy 193.558556 -17.381667) (xy 193.477923 -17.348306) (xy 193.400945 -17.307207) (xy 193.364358 -17.28343)
			(xy 193.355108 -17.277824) (xy 193.333785 -17.274289) (xy 193.32321 -17.276572) (xy 193.286097 -17.285942)
			(xy 193.210677 -17.299046) (xy 193.134409 -17.305624) (xy 193.096134 -17.306036) (xy 193.057818 -17.305656)
			(xy 192.981465 -17.299127) (xy 192.905958 -17.286046) (xy 192.831859 -17.26651) (xy 192.795652 -17.253966)
			(xy 192.787336 -17.25138) (xy 192.769932 -17.25138) (xy 192.761616 -17.253966) (xy 192.725489 -17.266445)
			(xy 192.651578 -17.285939) (xy 192.576269 -17.299026) (xy 192.500115 -17.305611) (xy 192.461896 -17.306036)
			(xy 192.461134 -17.306036) (xy 192.420027 -17.305555) (xy 192.338163 -17.297973) (xy 192.257348 -17.282872)
			(xy 192.178271 -17.260379) (xy 192.101606 -17.230687) (xy 192.028008 -17.194048) (xy 191.958103 -17.150776)
			(xy 191.892489 -17.10124) (xy 191.831724 -17.045861) (xy 191.776328 -16.985113) (xy 191.726772 -16.919513)
			(xy 191.683479 -16.849621) (xy 191.646819 -16.776033) (xy 191.617104 -16.699377) (xy 191.594588 -16.620307)
			(xy 191.579463 -16.539496) (xy 191.571857 -16.457635) (xy 191.571372 -16.416528) (xy 78.722326 -16.416528)
			(xy 78.729438 -16.465992) (xy 78.733468 -16.5506) (xy 78.729438 -16.635208) (xy 78.717383 -16.719049)
			(xy 78.697413 -16.801365) (xy 78.669709 -16.881409) (xy 78.634521 -16.958458) (xy 78.592169 -17.031813)
			(xy 78.543035 -17.10081) (xy 78.487566 -17.164824) (xy 78.426262 -17.223276) (xy 78.35968 -17.275635)
			(xy 78.288422 -17.321428) (xy 78.213134 -17.36024) (xy 78.134498 -17.39172) (xy 78.053225 -17.415582)
			(xy 77.970052 -17.431611) (xy 77.885732 -17.439661) (xy 77.84338 -17.440148) (xy 77.842872 -17.440148)
			(xy 77.797687 -17.439588) (xy 77.707782 -17.430437) (xy 77.61927 -17.412213) (xy 77.533063 -17.385103)
			(xy 77.491336 -17.367758) (xy 77.482756 -17.36444) (xy 77.464393 -17.363542) (xy 77.455522 -17.36598)
			(xy 77.410853 -17.379982) (xy 77.319321 -17.399623) (xy 77.226231 -17.409537) (xy 77.179424 -17.410176)
			(xy 77.178408 -17.410176) (xy 77.136057 -17.409752) (xy 77.051738 -17.401702) (xy 76.968567 -17.385672)
			(xy 76.887296 -17.361809) (xy 76.808661 -17.330329) (xy 76.733375 -17.291517) (xy 76.662118 -17.245724)
			(xy 76.595538 -17.193365) (xy 76.534236 -17.134915) (xy 76.478768 -17.070901) (xy 76.429635 -17.001905)
			(xy 76.387284 -16.928551) (xy 76.352098 -16.851504) (xy 76.324394 -16.77146) (xy 76.304425 -16.689146)
			(xy 76.29237 -16.605306) (xy 76.28834 -16.5207) (xy 1.524 -16.5207) (xy 1.524 -17.639629) (xy 14.466804 -17.639629)
			(xy 14.466804 -17.585091) (xy 14.474566 -17.531107) (xy 14.489931 -17.478778) (xy 14.512587 -17.429168)
			(xy 14.542073 -17.383287) (xy 14.577788 -17.342069) (xy 14.619005 -17.306354) (xy 14.664886 -17.276868)
			(xy 14.714496 -17.254212) (xy 14.766825 -17.238846) (xy 14.820809 -17.231085) (xy 14.848078 -17.230598)
			(xy 14.871954 -17.23136) (xy 14.889691 -17.201217) (xy 14.929888 -17.143978) (xy 14.952218 -17.11706)
			(xy 14.959537 -17.107372) (xy 14.965118 -17.083781) (xy 14.962886 -17.071848) (xy 14.957561 -17.04917)
			(xy 14.951832 -17.002938) (xy 14.951456 -16.979646) (xy 14.951456 -16.979138) (xy 14.951937 -16.951867)
			(xy 14.959694 -16.89788) (xy 14.975057 -16.845546) (xy 14.997711 -16.795932) (xy 15.027196 -16.750047)
			(xy 15.062912 -16.708826) (xy 15.104131 -16.673108) (xy 15.150015 -16.643621) (xy 15.199628 -16.620964)
			(xy 15.25196 -16.605599) (xy 15.305947 -16.597838) (xy 15.333218 -16.597376) (xy 15.361919 -16.597956)
			(xy 15.418673 -16.606566) (xy 15.473499 -16.623573) (xy 15.525161 -16.648594) (xy 15.572496 -16.681067)
			(xy 15.614438 -16.720259) (xy 15.650041 -16.765286) (xy 15.678504 -16.815136) (xy 15.689326 -16.841724)
			(xy 15.694327 -16.852837) (xy 15.712511 -16.869013) (xy 15.724124 -16.872712) (xy 15.761849 -16.882917)
			(xy 15.835171 -16.909975) (xy 15.905346 -16.944381) (xy 15.938754 -16.96466) (xy 15.94701 -16.969374)
			(xy 15.965678 -16.972901) (xy 15.984346 -16.969374) (xy 15.992602 -16.96466) (xy 16.026008 -16.944378)
			(xy 16.096183 -16.909971) (xy 16.169504 -16.882907) (xy 16.207232 -16.872712) (xy 16.218845 -16.869017)
			(xy 16.237017 -16.852832) (xy 16.24203 -16.841724) (xy 16.252832 -16.815122) (xy 16.281277 -16.76525)
			(xy 16.316871 -16.720202) (xy 16.358812 -16.680995) (xy 16.406154 -16.648512) (xy 16.457826 -16.623488)
			(xy 16.512665 -16.606486) (xy 16.569431 -16.597891) (xy 16.598138 -16.597376) (xy 16.62541 -16.597789)
			(xy 16.679398 -16.605557) (xy 16.731731 -16.620929) (xy 16.781344 -16.643593) (xy 16.827227 -16.673086)
			(xy 16.868445 -16.708809) (xy 16.90416 -16.750034) (xy 16.933644 -16.795922) (xy 16.956297 -16.84554)
			(xy 16.971659 -16.897876) (xy 16.979416 -16.951866) (xy 16.9799 -16.979138) (xy 16.9799 -16.979646)
			(xy 16.979521 -17.002938) (xy 16.973787 -17.049168) (xy 16.96847 -17.071848) (xy 16.96619 -17.083783)
			(xy 16.971771 -17.107396) (xy 16.979138 -17.11706) (xy 17.001468 -17.143978) (xy 17.041665 -17.201217)
			(xy 17.059402 -17.23136) (xy 17.083278 -17.230598) (xy 17.110549 -17.231061) (xy 17.164536 -17.238823)
			(xy 17.216869 -17.254189) (xy 17.266483 -17.276847) (xy 17.312366 -17.306334) (xy 17.353587 -17.342052)
			(xy 17.389304 -17.383272) (xy 17.418792 -17.429156) (xy 17.44145 -17.478769) (xy 17.456816 -17.531102)
			(xy 17.464579 -17.585089) (xy 17.464579 -17.639629) (xy 20.054804 -17.639629) (xy 20.054804 -17.585091)
			(xy 20.062566 -17.531107) (xy 20.077931 -17.478778) (xy 20.100587 -17.429168) (xy 20.130073 -17.383287)
			(xy 20.165788 -17.342069) (xy 20.207005 -17.306354) (xy 20.252886 -17.276868) (xy 20.302496 -17.254212)
			(xy 20.354825 -17.238846) (xy 20.408809 -17.231085) (xy 20.436078 -17.230598) (xy 20.459954 -17.23136)
			(xy 20.477691 -17.201217) (xy 20.517888 -17.143978) (xy 20.540218 -17.11706) (xy 20.547537 -17.107372)
			(xy 20.553118 -17.083781) (xy 20.550886 -17.071848) (xy 20.545561 -17.04917) (xy 20.539832 -17.002938)
			(xy 20.539456 -16.979646) (xy 20.539456 -16.979138) (xy 20.539937 -16.951867) (xy 20.547694 -16.89788)
			(xy 20.563057 -16.845546) (xy 20.585711 -16.795932) (xy 20.615196 -16.750047) (xy 20.650912 -16.708826)
			(xy 20.692131 -16.673108) (xy 20.738015 -16.643621) (xy 20.787628 -16.620964) (xy 20.83996 -16.605599)
			(xy 20.893947 -16.597838) (xy 20.921218 -16.597376) (xy 20.949919 -16.597956) (xy 21.006673 -16.606566)
			(xy 21.061499 -16.623573) (xy 21.113161 -16.648594) (xy 21.160496 -16.681067) (xy 21.202438 -16.720259)
			(xy 21.238041 -16.765286) (xy 21.266504 -16.815136) (xy 21.277326 -16.841724) (xy 21.282327 -16.852837)
			(xy 21.300511 -16.869013) (xy 21.312124 -16.872712) (xy 21.349849 -16.882917) (xy 21.423171 -16.909975)
			(xy 21.493346 -16.944381) (xy 21.526754 -16.96466) (xy 21.53501 -16.969374) (xy 21.553678 -16.972901)
			(xy 21.572346 -16.969374) (xy 21.580602 -16.96466) (xy 21.614008 -16.944378) (xy 21.684183 -16.909971)
			(xy 21.757504 -16.882907) (xy 21.795232 -16.872712) (xy 21.806845 -16.869017) (xy 21.825017 -16.852832)
			(xy 21.83003 -16.841724) (xy 21.840832 -16.815122) (xy 21.869277 -16.76525) (xy 21.904871 -16.720202)
			(xy 21.946812 -16.680995) (xy 21.994154 -16.648512) (xy 22.045826 -16.623488) (xy 22.100665 -16.606486)
			(xy 22.157431 -16.597891) (xy 22.186138 -16.597376) (xy 22.21341 -16.597789) (xy 22.267398 -16.605557)
			(xy 22.319731 -16.620929) (xy 22.369344 -16.643593) (xy 22.415227 -16.673086) (xy 22.456445 -16.708809)
			(xy 22.49216 -16.750034) (xy 22.521644 -16.795922) (xy 22.544297 -16.84554) (xy 22.559659 -16.897876)
			(xy 22.567416 -16.951866) (xy 22.5679 -16.979138) (xy 22.5679 -16.979646) (xy 22.567521 -17.002938)
			(xy 22.561787 -17.049168) (xy 22.55647 -17.071848) (xy 22.55419 -17.083783) (xy 22.559771 -17.107396)
			(xy 22.567138 -17.11706) (xy 22.589468 -17.143978) (xy 22.629665 -17.201217) (xy 22.647402 -17.23136)
			(xy 22.671278 -17.230598) (xy 22.698547 -17.23114) (xy 22.752531 -17.238899) (xy 22.804861 -17.254261)
			(xy 22.854471 -17.276915) (xy 22.900353 -17.306399) (xy 22.941571 -17.342113) (xy 22.977287 -17.383329)
			(xy 23.006774 -17.429209) (xy 23.029431 -17.478819) (xy 23.044797 -17.531148) (xy 23.052559 -17.585131)
			(xy 23.052559 -17.639669) (xy 23.052559 -17.639671) (xy 25.642784 -17.639671) (xy 25.642784 -17.585129)
			(xy 25.650546 -17.531141) (xy 25.665912 -17.478808) (xy 25.688569 -17.429194) (xy 25.718056 -17.38331)
			(xy 25.753773 -17.342088) (xy 25.794992 -17.306369) (xy 25.840875 -17.27688) (xy 25.890488 -17.25422)
			(xy 25.94282 -17.238851) (xy 25.996807 -17.231086) (xy 26.024078 -17.230598) (xy 26.047954 -17.23136)
			(xy 26.065691 -17.201217) (xy 26.105888 -17.143978) (xy 26.128218 -17.11706) (xy 26.135537 -17.107372)
			(xy 26.141118 -17.083781) (xy 26.138886 -17.071848) (xy 26.133561 -17.04917) (xy 26.127832 -17.002938)
			(xy 26.127456 -16.979646) (xy 26.127456 -16.979138) (xy 26.127937 -16.951867) (xy 26.135694 -16.89788)
			(xy 26.151057 -16.845546) (xy 26.173711 -16.795932) (xy 26.203196 -16.750047) (xy 26.238912 -16.708826)
			(xy 26.280131 -16.673108) (xy 26.326015 -16.643621) (xy 26.375628 -16.620964) (xy 26.42796 -16.605599)
			(xy 26.481947 -16.597838) (xy 26.509218 -16.597376) (xy 26.537919 -16.597956) (xy 26.594673 -16.606566)
			(xy 26.649499 -16.623573) (xy 26.701161 -16.648594) (xy 26.748496 -16.681067) (xy 26.790438 -16.720259)
			(xy 26.826041 -16.765286) (xy 26.854504 -16.815136) (xy 26.865326 -16.841724) (xy 26.870327 -16.852837)
			(xy 26.888511 -16.869013) (xy 26.900124 -16.872712) (xy 26.937849 -16.882917) (xy 27.011171 -16.909975)
			(xy 27.081346 -16.944381) (xy 27.114754 -16.96466) (xy 27.12301 -16.969374) (xy 27.141678 -16.972901)
			(xy 27.160346 -16.969374) (xy 27.168602 -16.96466) (xy 27.202008 -16.944378) (xy 27.272183 -16.909971)
			(xy 27.345504 -16.882907) (xy 27.383232 -16.872712) (xy 27.394845 -16.869017) (xy 27.413017 -16.852832)
			(xy 27.41803 -16.841724) (xy 27.428832 -16.815122) (xy 27.457277 -16.76525) (xy 27.492871 -16.720202)
			(xy 27.534812 -16.680995) (xy 27.582154 -16.648512) (xy 27.633826 -16.623488) (xy 27.688665 -16.606486)
			(xy 27.745431 -16.597891) (xy 27.774138 -16.597376) (xy 27.80141 -16.597789) (xy 27.855398 -16.605557)
			(xy 27.907731 -16.620929) (xy 27.957344 -16.643593) (xy 28.003227 -16.673086) (xy 28.044445 -16.708809)
			(xy 28.08016 -16.750034) (xy 28.109644 -16.795922) (xy 28.132297 -16.84554) (xy 28.147659 -16.897876)
			(xy 28.155416 -16.951866) (xy 28.1559 -16.979138) (xy 28.1559 -16.979646) (xy 28.155521 -17.002938)
			(xy 28.149787 -17.049168) (xy 28.14447 -17.071848) (xy 28.14219 -17.083783) (xy 28.147771 -17.107396)
			(xy 28.155138 -17.11706) (xy 28.177468 -17.143978) (xy 28.217665 -17.201217) (xy 28.235402 -17.23136)
			(xy 28.259278 -17.230598) (xy 28.286547 -17.23114) (xy 28.340531 -17.238899) (xy 28.392861 -17.254261)
			(xy 28.442471 -17.276915) (xy 28.488353 -17.306399) (xy 28.529571 -17.342113) (xy 28.565287 -17.383329)
			(xy 28.594774 -17.429209) (xy 28.617431 -17.478819) (xy 28.632797 -17.531148) (xy 28.640559 -17.585131)
			(xy 28.640559 -17.639669) (xy 28.640459 -17.640367) (xy 31.230846 -17.640367) (xy 31.230846 -17.585833)
			(xy 31.238607 -17.531855) (xy 31.25397 -17.47953) (xy 31.276624 -17.429924) (xy 31.306106 -17.384047)
			(xy 31.341817 -17.342832) (xy 31.383029 -17.307119) (xy 31.428905 -17.277634) (xy 31.478509 -17.254978)
			(xy 31.530833 -17.239612) (xy 31.584811 -17.231848) (xy 31.612078 -17.23136) (xy 31.634938 -17.232122)
			(xy 31.652824 -17.201757) (xy 31.693403 -17.144133) (xy 31.715964 -17.11706) (xy 31.723278 -17.107368)
			(xy 31.728865 -17.08378) (xy 31.726632 -17.071848) (xy 31.721406 -17.04935) (xy 31.715805 -17.003502)
			(xy 31.715456 -16.980408) (xy 31.715456 -16.9799) (xy 31.715902 -16.952628) (xy 31.723664 -16.89864)
			(xy 31.739031 -16.846306) (xy 31.76169 -16.796691) (xy 31.79118 -16.750807) (xy 31.826899 -16.709586)
			(xy 31.868121 -16.673869) (xy 31.914007 -16.644382) (xy 31.963623 -16.621725) (xy 32.015957 -16.60636)
			(xy 32.069946 -16.5986) (xy 32.097218 -16.598138) (xy 32.125946 -16.59864) (xy 32.182751 -16.607273)
			(xy 32.237623 -16.624312) (xy 32.289327 -16.649373) (xy 32.336697 -16.681891) (xy 32.378665 -16.721134)
			(xy 32.414286 -16.766216) (xy 32.442757 -16.816123) (xy 32.45358 -16.84274) (xy 32.458598 -16.853844)
			(xy 32.47677 -16.870023) (xy 32.488378 -16.873728) (xy 32.525885 -16.883922) (xy 32.598771 -16.910936)
			(xy 32.668528 -16.945227) (xy 32.701738 -16.965422) (xy 32.709994 -16.970136) (xy 32.728662 -16.973663)
			(xy 32.74733 -16.970136) (xy 32.755586 -16.965422) (xy 32.789134 -16.945005) (xy 32.859631 -16.910383)
			(xy 32.933314 -16.883192) (xy 32.971232 -16.872966) (xy 32.982802 -16.869305) (xy 33.000963 -16.853259)
			(xy 33.00603 -16.842232) (xy 33.016885 -16.815667) (xy 33.045361 -16.765847) (xy 33.080972 -16.72085)
			(xy 33.122915 -16.681687) (xy 33.170245 -16.649241) (xy 33.221898 -16.624242) (xy 33.27671 -16.607254)
			(xy 33.333446 -16.598659) (xy 33.362138 -16.598138) (xy 33.389408 -16.598589) (xy 33.443393 -16.606356)
			(xy 33.495723 -16.621726) (xy 33.545334 -16.644387) (xy 33.591214 -16.673877) (xy 33.632432 -16.709595)
			(xy 33.668146 -16.750816) (xy 33.697632 -16.7967) (xy 33.720287 -16.846312) (xy 33.735652 -16.898644)
			(xy 33.743414 -16.95263) (xy 33.7439 -16.9799) (xy 33.743539 -17.003518) (xy 33.737675 -17.05039)
			(xy 33.732216 -17.073372) (xy 33.729903 -17.085344) (xy 33.735324 -17.109078) (xy 33.74263 -17.118838)
			(xy 33.764791 -17.145529) (xy 33.804732 -17.202258) (xy 33.822386 -17.232122) (xy 33.847278 -17.23136)
			(xy 33.874552 -17.231778) (xy 33.928544 -17.239538) (xy 33.980882 -17.254903) (xy 34.030501 -17.277561)
			(xy 34.07639 -17.30705) (xy 34.117615 -17.342769) (xy 34.153337 -17.383992) (xy 34.182828 -17.42988)
			(xy 34.205489 -17.479497) (xy 34.220857 -17.531835) (xy 34.22862 -17.585826) (xy 34.22862 -17.640366)
			(xy 36.817846 -17.640366) (xy 36.817846 -17.585834) (xy 36.825606 -17.531857) (xy 36.840969 -17.479533)
			(xy 36.863621 -17.429928) (xy 36.893102 -17.384052) (xy 36.928811 -17.342838) (xy 36.970022 -17.307125)
			(xy 37.015895 -17.277639) (xy 37.065498 -17.254982) (xy 37.11782 -17.239615) (xy 37.171796 -17.231849)
			(xy 37.199062 -17.23136) (xy 37.222938 -17.232122) (xy 37.240824 -17.201757) (xy 37.281403 -17.144133)
			(xy 37.303964 -17.11706) (xy 37.311278 -17.107368) (xy 37.316865 -17.08378) (xy 37.314632 -17.071848)
			(xy 37.309406 -17.04935) (xy 37.303805 -17.003502) (xy 37.303456 -16.980408) (xy 37.303456 -16.9799)
			(xy 37.303902 -16.952628) (xy 37.311664 -16.89864) (xy 37.327031 -16.846306) (xy 37.34969 -16.796691)
			(xy 37.37918 -16.750807) (xy 37.414899 -16.709586) (xy 37.456121 -16.673869) (xy 37.502007 -16.644382)
			(xy 37.551623 -16.621725) (xy 37.603957 -16.60636) (xy 37.657946 -16.5986) (xy 37.685218 -16.598138)
			(xy 37.713946 -16.59864) (xy 37.770751 -16.607273) (xy 37.825623 -16.624312) (xy 37.877327 -16.649373)
			(xy 37.924697 -16.681891) (xy 37.966665 -16.721134) (xy 38.002286 -16.766216) (xy 38.030757 -16.816123)
			(xy 38.04158 -16.84274) (xy 38.046598 -16.853844) (xy 38.06477 -16.870023) (xy 38.076378 -16.873728)
			(xy 38.113885 -16.883922) (xy 38.186771 -16.910936) (xy 38.256528 -16.945227) (xy 38.289738 -16.965422)
			(xy 38.297994 -16.970136) (xy 38.316662 -16.973663) (xy 38.33533 -16.970136) (xy 38.343586 -16.965422)
			(xy 38.377134 -16.945005) (xy 38.447631 -16.910383) (xy 38.521314 -16.883192) (xy 38.559232 -16.872966)
			(xy 38.570802 -16.869305) (xy 38.588963 -16.853259) (xy 38.59403 -16.842232) (xy 38.604885 -16.815667)
			(xy 38.633361 -16.765847) (xy 38.668972 -16.72085) (xy 38.710915 -16.681687) (xy 38.758245 -16.649241)
			(xy 38.809898 -16.624242) (xy 38.86471 -16.607254) (xy 38.921446 -16.598659) (xy 38.950138 -16.598138)
			(xy 38.977408 -16.598589) (xy 39.031393 -16.606356) (xy 39.083723 -16.621726) (xy 39.133334 -16.644387)
			(xy 39.179214 -16.673877) (xy 39.220432 -16.709595) (xy 39.256146 -16.750816) (xy 39.285632 -16.7967)
			(xy 39.308287 -16.846312) (xy 39.323652 -16.898644) (xy 39.331414 -16.95263) (xy 39.3319 -16.9799)
			(xy 39.331539 -17.003518) (xy 39.325675 -17.05039) (xy 39.320216 -17.073372) (xy 39.317903 -17.085344)
			(xy 39.323324 -17.109078) (xy 39.33063 -17.118838) (xy 39.352791 -17.145529) (xy 39.392732 -17.202258)
			(xy 39.410386 -17.232122) (xy 39.434262 -17.23136) (xy 39.461536 -17.231777) (xy 39.51553 -17.239535)
			(xy 39.567871 -17.254899) (xy 39.617491 -17.277556) (xy 39.663383 -17.307044) (xy 39.70461 -17.342764)
			(xy 39.740333 -17.383987) (xy 39.769826 -17.429875) (xy 39.792488 -17.479494) (xy 39.807857 -17.531832)
			(xy 39.81562 -17.585826) (xy 39.81562 -17.639672) (xy 42.712585 -17.639672) (xy 42.712585 -17.585128)
			(xy 42.720347 -17.531139) (xy 42.735713 -17.478805) (xy 42.758372 -17.42919) (xy 42.78786 -17.383304)
			(xy 42.823578 -17.342083) (xy 42.8648 -17.306364) (xy 42.910685 -17.276875) (xy 42.960299 -17.254216)
			(xy 43.012633 -17.238848) (xy 43.066622 -17.231085) (xy 43.093894 -17.230598) (xy 43.11777 -17.23136)
			(xy 43.135506 -17.201216) (xy 43.175703 -17.143977) (xy 43.198034 -17.11706) (xy 43.205354 -17.107373)
			(xy 43.210934 -17.083781) (xy 43.208702 -17.071848) (xy 43.203376 -17.04917) (xy 43.197648 -17.002938)
			(xy 43.197272 -16.979646) (xy 43.197272 -16.979138) (xy 43.197737 -16.951866) (xy 43.205495 -16.897878)
			(xy 43.220858 -16.845543) (xy 43.243514 -16.795928) (xy 43.273 -16.750042) (xy 43.308718 -16.708821)
			(xy 43.349939 -16.673103) (xy 43.395824 -16.643615) (xy 43.445439 -16.620959) (xy 43.497774 -16.605596)
			(xy 43.551762 -16.597837) (xy 43.579034 -16.597376) (xy 43.607736 -16.597942) (xy 43.66449 -16.606554)
			(xy 43.719316 -16.623564) (xy 43.770979 -16.648587) (xy 43.818314 -16.681062) (xy 43.860255 -16.720255)
			(xy 43.895858 -16.765284) (xy 43.92432 -16.815135) (xy 43.935142 -16.841724) (xy 43.940185 -16.852813)
			(xy 43.958339 -16.868999) (xy 43.96994 -16.872712) (xy 44.007666 -16.882913) (xy 44.080988 -16.909973)
			(xy 44.151163 -16.94438) (xy 44.18457 -16.96466) (xy 44.192826 -16.969374) (xy 44.211494 -16.972901)
			(xy 44.230162 -16.969374) (xy 44.238418 -16.96466) (xy 44.271822 -16.944374) (xy 44.341998 -16.909969)
			(xy 44.41532 -16.882907) (xy 44.453048 -16.872712) (xy 44.464664 -16.869024) (xy 44.482834 -16.852834)
			(xy 44.487846 -16.841724) (xy 44.498635 -16.815117) (xy 44.527081 -16.765244) (xy 44.562677 -16.720196)
			(xy 44.60462 -16.680988) (xy 44.651964 -16.648506) (xy 44.703638 -16.623483) (xy 44.758479 -16.606483)
			(xy 44.815247 -16.59789) (xy 44.843954 -16.597376) (xy 44.871226 -16.597844) (xy 44.925214 -16.605601)
			(xy 44.977549 -16.620964) (xy 45.027165 -16.643619) (xy 45.07305 -16.673105) (xy 45.114272 -16.708822)
			(xy 45.14999 -16.750043) (xy 45.179478 -16.795928) (xy 45.202134 -16.845543) (xy 45.217497 -16.897878)
			(xy 45.225255 -16.951866) (xy 45.225716 -16.979138) (xy 45.225716 -16.979646) (xy 45.225337 -17.002938)
			(xy 45.219603 -17.049168) (xy 45.214286 -17.071848) (xy 45.212003 -17.083783) (xy 45.217585 -17.107397)
			(xy 45.224954 -17.11706) (xy 45.247284 -17.143977) (xy 45.287481 -17.201217) (xy 45.305218 -17.23136)
			(xy 45.329094 -17.230598) (xy 45.356362 -17.231141) (xy 45.410344 -17.238902) (xy 45.462672 -17.254266)
			(xy 45.512281 -17.276921) (xy 45.558161 -17.306405) (xy 45.599377 -17.342119) (xy 45.635091 -17.383335)
			(xy 45.664577 -17.429214) (xy 45.687232 -17.478822) (xy 45.702597 -17.53115) (xy 45.710359 -17.585132)
			(xy 45.710359 -17.639668) (xy 45.710358 -17.639672) (xy 48.300585 -17.639672) (xy 48.300585 -17.585128)
			(xy 48.308347 -17.531139) (xy 48.323713 -17.478805) (xy 48.346372 -17.42919) (xy 48.37586 -17.383304)
			(xy 48.411578 -17.342083) (xy 48.4528 -17.306364) (xy 48.498685 -17.276875) (xy 48.548299 -17.254216)
			(xy 48.600633 -17.238848) (xy 48.654622 -17.231085) (xy 48.681894 -17.230598) (xy 48.70577 -17.23136)
			(xy 48.723506 -17.201216) (xy 48.763703 -17.143977) (xy 48.786034 -17.11706) (xy 48.793354 -17.107373)
			(xy 48.798934 -17.083781) (xy 48.796702 -17.071848) (xy 48.791376 -17.04917) (xy 48.785648 -17.002938)
			(xy 48.785272 -16.979646) (xy 48.785272 -16.979138) (xy 48.785737 -16.951866) (xy 48.793495 -16.897878)
			(xy 48.808858 -16.845543) (xy 48.831514 -16.795928) (xy 48.861 -16.750042) (xy 48.896718 -16.708821)
			(xy 48.937939 -16.673103) (xy 48.983824 -16.643615) (xy 49.033439 -16.620959) (xy 49.085774 -16.605596)
			(xy 49.139762 -16.597837) (xy 49.167034 -16.597376) (xy 49.195736 -16.597942) (xy 49.25249 -16.606554)
			(xy 49.307316 -16.623564) (xy 49.358979 -16.648587) (xy 49.406314 -16.681062) (xy 49.448255 -16.720255)
			(xy 49.483858 -16.765284) (xy 49.51232 -16.815135) (xy 49.523142 -16.841724) (xy 49.528185 -16.852813)
			(xy 49.546339 -16.868999) (xy 49.55794 -16.872712) (xy 49.595666 -16.882913) (xy 49.668988 -16.909973)
			(xy 49.739163 -16.94438) (xy 49.77257 -16.96466) (xy 49.780826 -16.969374) (xy 49.799494 -16.972901)
			(xy 49.818162 -16.969374) (xy 49.826418 -16.96466) (xy 49.859822 -16.944374) (xy 49.929998 -16.909969)
			(xy 50.00332 -16.882907) (xy 50.041048 -16.872712) (xy 50.052664 -16.869024) (xy 50.070834 -16.852834)
			(xy 50.075846 -16.841724) (xy 50.086635 -16.815117) (xy 50.115081 -16.765244) (xy 50.150677 -16.720196)
			(xy 50.19262 -16.680988) (xy 50.239964 -16.648506) (xy 50.291638 -16.623483) (xy 50.346479 -16.606483)
			(xy 50.403247 -16.59789) (xy 50.431954 -16.597376) (xy 50.459226 -16.597844) (xy 50.513214 -16.605601)
			(xy 50.565549 -16.620964) (xy 50.615165 -16.643619) (xy 50.66105 -16.673105) (xy 50.702272 -16.708822)
			(xy 50.73799 -16.750043) (xy 50.767478 -16.795928) (xy 50.790134 -16.845543) (xy 50.805497 -16.897878)
			(xy 50.813255 -16.951866) (xy 50.813716 -16.979138) (xy 50.813716 -16.979646) (xy 50.813337 -17.002938)
			(xy 50.807603 -17.049168) (xy 50.802286 -17.071848) (xy 50.800003 -17.083783) (xy 50.805585 -17.107397)
			(xy 50.812954 -17.11706) (xy 50.835284 -17.143977) (xy 50.875481 -17.201217) (xy 50.893218 -17.23136)
			(xy 50.917094 -17.230598) (xy 50.944362 -17.231141) (xy 50.998344 -17.238902) (xy 51.050672 -17.254266)
			(xy 51.100281 -17.276921) (xy 51.146161 -17.306405) (xy 51.187377 -17.342119) (xy 51.223091 -17.383335)
			(xy 51.252577 -17.429214) (xy 51.275232 -17.478822) (xy 51.290597 -17.53115) (xy 51.298359 -17.585132)
			(xy 51.298359 -17.639668) (xy 51.298258 -17.64037) (xy 53.921623 -17.64037) (xy 53.921623 -17.58583)
			(xy 53.929386 -17.531845) (xy 53.944752 -17.479514) (xy 53.967409 -17.429903) (xy 53.996896 -17.384021)
			(xy 54.032613 -17.342803) (xy 54.073832 -17.307088) (xy 54.119715 -17.277602) (xy 54.169327 -17.254947)
			(xy 54.221659 -17.239583) (xy 54.275644 -17.231822) (xy 54.302914 -17.23136) (xy 54.32679 -17.232122)
			(xy 54.344672 -17.201754) (xy 54.385254 -17.144132) (xy 54.407816 -17.11706) (xy 54.415134 -17.107372)
			(xy 54.420716 -17.083781) (xy 54.418484 -17.071848) (xy 54.413259 -17.04935) (xy 54.407657 -17.003502)
			(xy 54.407308 -16.980408) (xy 54.407308 -16.9799) (xy 54.407824 -16.952632) (xy 54.415585 -16.898651)
			(xy 54.430949 -16.846324) (xy 54.453603 -16.796716) (xy 54.483086 -16.750836) (xy 54.518798 -16.709619)
			(xy 54.560012 -16.673904) (xy 54.605889 -16.644417) (xy 54.655496 -16.62176) (xy 54.707822 -16.606392)
			(xy 54.761802 -16.598626) (xy 54.78907 -16.598138) (xy 54.817797 -16.598681) (xy 54.8746 -16.607307)
			(xy 54.929471 -16.62434) (xy 54.981175 -16.649394) (xy 55.028545 -16.681907) (xy 55.070514 -16.721144)
			(xy 55.106136 -16.766222) (xy 55.134609 -16.816125) (xy 55.145432 -16.84274) (xy 55.150474 -16.85383)
			(xy 55.168629 -16.870014) (xy 55.18023 -16.873728) (xy 55.217734 -16.883933) (xy 55.290621 -16.910942)
			(xy 55.360379 -16.945229) (xy 55.39359 -16.965422) (xy 55.401846 -16.970136) (xy 55.420514 -16.973663)
			(xy 55.439182 -16.970136) (xy 55.447438 -16.965422) (xy 55.480992 -16.945015) (xy 55.551487 -16.91039)
			(xy 55.625167 -16.883194) (xy 55.663084 -16.872966) (xy 55.674645 -16.869284) (xy 55.692811 -16.853254)
			(xy 55.697882 -16.842232) (xy 55.708693 -16.815648) (xy 55.737175 -16.765827) (xy 55.772792 -16.720828)
			(xy 55.814741 -16.681666) (xy 55.862078 -16.649222) (xy 55.913737 -16.624227) (xy 55.968554 -16.607244)
			(xy 56.025296 -16.598655) (xy 56.05399 -16.598138) (xy 56.081261 -16.598611) (xy 56.135247 -16.606372)
			(xy 56.18758 -16.621737) (xy 56.237193 -16.644393) (xy 56.283077 -16.67388) (xy 56.324297 -16.709596)
			(xy 56.360014 -16.750815) (xy 56.389502 -16.796698) (xy 56.41216 -16.846311) (xy 56.427526 -16.898643)
			(xy 56.435289 -16.952629) (xy 56.435752 -16.9799) (xy 56.435392 -17.003518) (xy 56.429527 -17.05039)
			(xy 56.424068 -17.073372) (xy 56.421766 -17.085345) (xy 56.427181 -17.109076) (xy 56.434482 -17.118838)
			(xy 56.45664 -17.145531) (xy 56.496583 -17.202258) (xy 56.514238 -17.232122) (xy 56.538114 -17.23136)
			(xy 56.565384 -17.231803) (xy 56.619369 -17.239567) (xy 56.6717 -17.254935) (xy 56.721312 -17.277593)
			(xy 56.767193 -17.307081) (xy 56.808412 -17.342798) (xy 56.844128 -17.384018) (xy 56.873614 -17.429901)
			(xy 56.89627 -17.479513) (xy 56.911636 -17.531844) (xy 56.919398 -17.58583) (xy 56.919398 -17.64037)
			(xy 56.911636 -17.694356) (xy 56.89627 -17.746687) (xy 56.873614 -17.796299) (xy 56.844128 -17.842182)
			(xy 56.808412 -17.883402) (xy 56.767193 -17.919119) (xy 56.721312 -17.948607) (xy 56.6717 -17.971265)
			(xy 56.619369 -17.986633) (xy 56.565384 -17.994397) (xy 56.538114 -17.994884) (xy 56.514238 -17.994122)
			(xy 56.496538 -18.024122) (xy 56.456468 -18.081105) (xy 56.434228 -18.107914) (xy 56.426897 -18.117668)
			(xy 56.421447 -18.141411) (xy 56.423814 -18.15338) (xy 56.429387 -18.176604) (xy 56.435369 -18.223988)
			(xy 56.435752 -18.247868) (xy 56.435269 -18.275139) (xy 56.427511 -18.329125) (xy 56.412148 -18.381458)
			(xy 56.389493 -18.431072) (xy 56.360008 -18.476956) (xy 56.324293 -18.518177) (xy 56.283074 -18.553895)
			(xy 56.237191 -18.583383) (xy 56.187579 -18.60604) (xy 56.135247 -18.621406) (xy 56.081261 -18.629167)
			(xy 56.05399 -18.62963) (xy 56.025199 -18.629115) (xy 55.968273 -18.620453) (xy 55.913292 -18.603341)
			(xy 55.861504 -18.578169) (xy 55.814083 -18.545505) (xy 55.772103 -18.506092) (xy 55.736518 -18.460822)
			(xy 55.708133 -18.410722) (xy 55.697374 -18.384012) (xy 55.692358 -18.372794) (xy 55.67404 -18.356471)
			(xy 55.662322 -18.35277) (xy 55.624541 -18.342552) (xy 55.551125 -18.315419) (xy 55.480875 -18.280909)
			(xy 55.447438 -18.260568) (xy 55.439177 -18.255872) (xy 55.420514 -18.252364) (xy 55.401851 -18.255872)
			(xy 55.39359 -18.260568) (xy 55.360453 -18.280729) (xy 55.29086 -18.314995) (xy 55.218154 -18.342034)
			(xy 55.180738 -18.352262) (xy 55.169173 -18.356082) (xy 55.151122 -18.37237) (xy 55.146194 -18.383504)
			(xy 55.135396 -18.410252) (xy 55.107009 -18.460462) (xy 55.071397 -18.505835) (xy 55.029368 -18.545338)
			(xy 54.981879 -18.578074) (xy 54.930008 -18.603299) (xy 54.874934 -18.620439) (xy 54.81791 -18.629106)
			(xy 54.78907 -18.62963) (xy 54.761797 -18.629226) (xy 54.707806 -18.621459) (xy 54.65547 -18.606088)
			(xy 54.605855 -18.583424) (xy 54.55997 -18.55393) (xy 54.518749 -18.518207) (xy 54.483032 -18.47698)
			(xy 54.453546 -18.431091) (xy 54.430891 -18.381471) (xy 54.415528 -18.329133) (xy 54.407769 -18.275141)
			(xy 54.407308 -18.247868) (xy 54.407308 -18.24736) (xy 54.407661 -18.223941) (xy 54.413395 -18.177454)
			(xy 54.418738 -18.15465) (xy 54.421006 -18.14265) (xy 54.415454 -18.118909) (xy 54.40807 -18.109184)
			(xy 54.385466 -18.0821) (xy 54.344757 -18.024481) (xy 54.32679 -17.994122) (xy 54.302914 -17.994884)
			(xy 54.275644 -17.994378) (xy 54.221659 -17.986617) (xy 54.169327 -17.971253) (xy 54.119715 -17.948598)
			(xy 54.073832 -17.919112) (xy 54.032613 -17.883397) (xy 53.996896 -17.842179) (xy 53.967409 -17.796297)
			(xy 53.944752 -17.746686) (xy 53.929386 -17.694355) (xy 53.921623 -17.64037) (xy 51.298258 -17.64037)
			(xy 51.290597 -17.69365) (xy 51.275232 -17.745978) (xy 51.252577 -17.795586) (xy 51.223091 -17.841465)
			(xy 51.187377 -17.882681) (xy 51.146161 -17.918395) (xy 51.100281 -17.947879) (xy 51.050672 -17.970534)
			(xy 50.998344 -17.985898) (xy 50.944362 -17.993659) (xy 50.917094 -17.994122) (xy 50.893218 -17.99336)
			(xy 50.875363 -18.023519) (xy 50.83491 -18.080758) (xy 50.812446 -18.10766) (xy 50.805081 -18.117392)
			(xy 50.799656 -18.141153) (xy 50.802032 -18.153126) (xy 50.80748 -18.17611) (xy 50.813344 -18.22298)
			(xy 50.813716 -18.246598) (xy 50.813716 -18.247106) (xy 50.813304 -18.274379) (xy 50.80554 -18.32837)
			(xy 50.79017 -18.380707) (xy 50.767509 -18.430323) (xy 50.738016 -18.476209) (xy 50.702293 -18.51743)
			(xy 50.661067 -18.553147) (xy 50.615177 -18.582634) (xy 50.565558 -18.605289) (xy 50.513219 -18.620651)
			(xy 50.459227 -18.628408) (xy 50.431954 -18.628868) (xy 50.403141 -18.628313) (xy 50.346172 -18.619639)
			(xy 50.291151 -18.60251) (xy 50.239325 -18.577313) (xy 50.19187 -18.544621) (xy 50.149862 -18.505174)
			(xy 50.114253 -18.459867) (xy 50.08585 -18.409727) (xy 50.075084 -18.382996) (xy 50.070145 -18.371795)
			(xy 50.05195 -18.355474) (xy 50.040286 -18.351754) (xy 50.00269 -18.341522) (xy 49.929627 -18.314444)
			(xy 49.859704 -18.280059) (xy 49.826418 -18.259806) (xy 49.818157 -18.25511) (xy 49.799494 -18.251602)
			(xy 49.780831 -18.25511) (xy 49.77257 -18.259806) (xy 49.739275 -18.280043) (xy 49.669353 -18.314427)
			(xy 49.596297 -18.341522) (xy 49.558702 -18.351754) (xy 49.547063 -18.355508) (xy 49.528896 -18.371831)
			(xy 49.523904 -18.382996) (xy 49.513173 -18.409746) (xy 49.484785 -18.459906) (xy 49.449182 -18.50523)
			(xy 49.407171 -18.544689) (xy 49.359708 -18.577386) (xy 49.30787 -18.602579) (xy 49.252835 -18.619696)
			(xy 49.195852 -18.628348) (xy 49.167034 -18.628868) (xy 49.139764 -18.628367) (xy 49.085779 -18.62061)
			(xy 49.033447 -18.605248) (xy 48.983835 -18.582595) (xy 48.937951 -18.553111) (xy 48.896731 -18.517398)
			(xy 48.861013 -18.476181) (xy 48.831524 -18.430301) (xy 48.808866 -18.38069) (xy 48.793499 -18.32836)
			(xy 48.785736 -18.274376) (xy 48.785272 -18.247106) (xy 48.785272 -18.246598) (xy 48.785631 -18.22298)
			(xy 48.791496 -18.176108) (xy 48.796956 -18.153126) (xy 48.799276 -18.141154) (xy 48.793852 -18.117419)
			(xy 48.786542 -18.10766) (xy 48.764086 -18.080752) (xy 48.723634 -18.023513) (xy 48.70577 -17.99336)
			(xy 48.681894 -17.994122) (xy 48.654622 -17.993715) (xy 48.600633 -17.985952) (xy 48.548299 -17.970584)
			(xy 48.498685 -17.947925) (xy 48.4528 -17.918436) (xy 48.411578 -17.882717) (xy 48.37586 -17.841496)
			(xy 48.346372 -17.79561) (xy 48.323713 -17.745995) (xy 48.308347 -17.693661) (xy 48.300585 -17.639672)
			(xy 45.710358 -17.639672) (xy 45.702597 -17.69365) (xy 45.687232 -17.745978) (xy 45.664577 -17.795586)
			(xy 45.635091 -17.841465) (xy 45.599377 -17.882681) (xy 45.558161 -17.918395) (xy 45.512281 -17.947879)
			(xy 45.462672 -17.970534) (xy 45.410344 -17.985898) (xy 45.356362 -17.993659) (xy 45.329094 -17.994122)
			(xy 45.305218 -17.99336) (xy 45.287363 -18.023519) (xy 45.24691 -18.080758) (xy 45.224446 -18.10766)
			(xy 45.217081 -18.117392) (xy 45.211656 -18.141153) (xy 45.214032 -18.153126) (xy 45.21948 -18.17611)
			(xy 45.225344 -18.22298) (xy 45.225716 -18.246598) (xy 45.225716 -18.247106) (xy 45.225304 -18.274379)
			(xy 45.21754 -18.32837) (xy 45.20217 -18.380707) (xy 45.179509 -18.430323) (xy 45.150016 -18.476209)
			(xy 45.114293 -18.51743) (xy 45.073067 -18.553147) (xy 45.027177 -18.582634) (xy 44.977558 -18.605289)
			(xy 44.925219 -18.620651) (xy 44.871227 -18.628408) (xy 44.843954 -18.628868) (xy 44.815141 -18.628313)
			(xy 44.758172 -18.619639) (xy 44.703151 -18.60251) (xy 44.651325 -18.577313) (xy 44.60387 -18.544621)
			(xy 44.561862 -18.505174) (xy 44.526253 -18.459867) (xy 44.49785 -18.409727) (xy 44.487084 -18.382996)
			(xy 44.482145 -18.371795) (xy 44.46395 -18.355474) (xy 44.452286 -18.351754) (xy 44.41469 -18.341522)
			(xy 44.341627 -18.314444) (xy 44.271704 -18.280059) (xy 44.238418 -18.259806) (xy 44.230157 -18.25511)
			(xy 44.211494 -18.251602) (xy 44.192831 -18.25511) (xy 44.18457 -18.259806) (xy 44.151275 -18.280043)
			(xy 44.081353 -18.314427) (xy 44.008297 -18.341522) (xy 43.970702 -18.351754) (xy 43.959063 -18.355508)
			(xy 43.940896 -18.371831) (xy 43.935904 -18.382996) (xy 43.925173 -18.409746) (xy 43.896785 -18.459906)
			(xy 43.861182 -18.50523) (xy 43.819171 -18.544689) (xy 43.771708 -18.577386) (xy 43.71987 -18.602579)
			(xy 43.664835 -18.619696) (xy 43.607852 -18.628348) (xy 43.579034 -18.628868) (xy 43.551764 -18.628367)
			(xy 43.497779 -18.62061) (xy 43.445447 -18.605248) (xy 43.395835 -18.582595) (xy 43.349951 -18.553111)
			(xy 43.308731 -18.517398) (xy 43.273013 -18.476181) (xy 43.243524 -18.430301) (xy 43.220866 -18.38069)
			(xy 43.205499 -18.32836) (xy 43.197736 -18.274376) (xy 43.197272 -18.247106) (xy 43.197272 -18.246598)
			(xy 43.197631 -18.22298) (xy 43.203496 -18.176108) (xy 43.208956 -18.153126) (xy 43.211276 -18.141154)
			(xy 43.205852 -18.117419) (xy 43.198542 -18.10766) (xy 43.176086 -18.080752) (xy 43.135634 -18.023513)
			(xy 43.11777 -17.99336) (xy 43.093894 -17.994122) (xy 43.066622 -17.993715) (xy 43.012633 -17.985952)
			(xy 42.960299 -17.970584) (xy 42.910685 -17.947925) (xy 42.8648 -17.918436) (xy 42.823578 -17.882717)
			(xy 42.78786 -17.841496) (xy 42.758372 -17.79561) (xy 42.735713 -17.745995) (xy 42.720347 -17.693661)
			(xy 42.712585 -17.639672) (xy 39.81562 -17.639672) (xy 39.81562 -17.640374) (xy 39.807857 -17.694368)
			(xy 39.792488 -17.746706) (xy 39.769826 -17.796325) (xy 39.740333 -17.842213) (xy 39.70461 -17.883436)
			(xy 39.663383 -17.919156) (xy 39.617491 -17.948644) (xy 39.567871 -17.971301) (xy 39.51553 -17.986665)
			(xy 39.461536 -17.994423) (xy 39.434262 -17.994884) (xy 39.410386 -17.994122) (xy 39.392682 -18.02412)
			(xy 39.352615 -18.081105) (xy 39.330376 -18.107914) (xy 39.323041 -18.117665) (xy 39.317596 -18.14141)
			(xy 39.319962 -18.15338) (xy 39.325534 -18.176604) (xy 39.331517 -18.223988) (xy 39.3319 -18.247868)
			(xy 39.331346 -18.275135) (xy 39.32359 -18.329114) (xy 39.30823 -18.38144) (xy 39.285581 -18.431048)
			(xy 39.256102 -18.476927) (xy 39.220393 -18.518144) (xy 39.179183 -18.55386) (xy 39.133309 -18.583347)
			(xy 39.083706 -18.606006) (xy 39.031383 -18.621375) (xy 38.977405 -18.629141) (xy 38.950138 -18.62963)
			(xy 38.921349 -18.629074) (xy 38.864424 -18.620419) (xy 38.809444 -18.603314) (xy 38.757656 -18.578147)
			(xy 38.710235 -18.545489) (xy 38.668255 -18.506081) (xy 38.632668 -18.460816) (xy 38.604282 -18.41072)
			(xy 38.593522 -18.384012) (xy 38.588532 -18.372779) (xy 38.570196 -18.356462) (xy 38.55847 -18.35277)
			(xy 38.520686 -18.342564) (xy 38.447271 -18.315426) (xy 38.377022 -18.280911) (xy 38.343586 -18.260568)
			(xy 38.335325 -18.255872) (xy 38.316662 -18.252364) (xy 38.297999 -18.255872) (xy 38.289738 -18.260568)
			(xy 38.256607 -18.28074) (xy 38.187011 -18.315001) (xy 38.114303 -18.342036) (xy 38.076886 -18.352262)
			(xy 38.065311 -18.356059) (xy 38.047266 -18.372364) (xy 38.042342 -18.383504) (xy 38.031587 -18.410271)
			(xy 38.003195 -18.460483) (xy 37.967577 -18.505856) (xy 37.925542 -18.545359) (xy 37.878046 -18.578093)
			(xy 37.826169 -18.603314) (xy 37.771089 -18.62045) (xy 37.71406 -18.62911) (xy 37.685218 -18.62963)
			(xy 37.657946 -18.629182) (xy 37.603957 -18.621421) (xy 37.551622 -18.606056) (xy 37.502007 -18.583398)
			(xy 37.456121 -18.553909) (xy 37.4149 -18.51819) (xy 37.379183 -18.476967) (xy 37.349696 -18.431081)
			(xy 37.32704 -18.381465) (xy 37.311676 -18.329129) (xy 37.303917 -18.27514) (xy 37.303456 -18.247868)
			(xy 37.303456 -18.24736) (xy 37.303811 -18.223941) (xy 37.309543 -18.177454) (xy 37.314886 -18.15465)
			(xy 37.317143 -18.142649) (xy 37.311596 -18.118911) (xy 37.304218 -18.109184) (xy 37.281611 -18.082102)
			(xy 37.240904 -18.024482) (xy 37.222938 -17.994122) (xy 37.199062 -17.994884) (xy 37.171796 -17.994351)
			(xy 37.11782 -17.986585) (xy 37.065498 -17.971218) (xy 37.015895 -17.948561) (xy 36.970022 -17.919075)
			(xy 36.928811 -17.883362) (xy 36.893102 -17.842148) (xy 36.863621 -17.796272) (xy 36.840969 -17.746667)
			(xy 36.825606 -17.694343) (xy 36.817846 -17.640366) (xy 34.22862 -17.640366) (xy 34.22862 -17.640374)
			(xy 34.220857 -17.694365) (xy 34.205489 -17.746703) (xy 34.182828 -17.79632) (xy 34.153337 -17.842208)
			(xy 34.117615 -17.883431) (xy 34.07639 -17.91915) (xy 34.030501 -17.948639) (xy 33.980882 -17.971297)
			(xy 33.928544 -17.986662) (xy 33.874552 -17.994422) (xy 33.847278 -17.994884) (xy 33.822386 -17.994122)
			(xy 33.804682 -18.02412) (xy 33.764615 -18.081105) (xy 33.742376 -18.107914) (xy 33.735041 -18.117665)
			(xy 33.729596 -18.14141) (xy 33.731962 -18.15338) (xy 33.737534 -18.176604) (xy 33.743517 -18.223988)
			(xy 33.7439 -18.247868) (xy 33.743346 -18.275135) (xy 33.73559 -18.329114) (xy 33.72023 -18.38144)
			(xy 33.697581 -18.431048) (xy 33.668102 -18.476927) (xy 33.632393 -18.518144) (xy 33.591183 -18.55386)
			(xy 33.545309 -18.583347) (xy 33.495706 -18.606006) (xy 33.443383 -18.621375) (xy 33.389405 -18.629141)
			(xy 33.362138 -18.62963) (xy 33.333349 -18.629074) (xy 33.276424 -18.620419) (xy 33.221444 -18.603314)
			(xy 33.169656 -18.578147) (xy 33.122235 -18.545489) (xy 33.080255 -18.506081) (xy 33.044668 -18.460816)
			(xy 33.016282 -18.41072) (xy 33.005522 -18.384012) (xy 33.000532 -18.372779) (xy 32.982196 -18.356462)
			(xy 32.97047 -18.35277) (xy 32.932686 -18.342564) (xy 32.859271 -18.315426) (xy 32.789022 -18.280911)
			(xy 32.755586 -18.260568) (xy 32.747325 -18.255872) (xy 32.728662 -18.252364) (xy 32.709999 -18.255872)
			(xy 32.701738 -18.260568) (xy 32.668607 -18.28074) (xy 32.599011 -18.315001) (xy 32.526303 -18.342036)
			(xy 32.488886 -18.352262) (xy 32.477311 -18.356059) (xy 32.459266 -18.372364) (xy 32.454342 -18.383504)
			(xy 32.443587 -18.410271) (xy 32.415195 -18.460483) (xy 32.379577 -18.505856) (xy 32.337542 -18.545359)
			(xy 32.290046 -18.578093) (xy 32.238169 -18.603314) (xy 32.183089 -18.62045) (xy 32.12606 -18.62911)
			(xy 32.097218 -18.62963) (xy 32.069946 -18.629182) (xy 32.015957 -18.621421) (xy 31.963622 -18.606056)
			(xy 31.914007 -18.583398) (xy 31.868121 -18.553909) (xy 31.8269 -18.51819) (xy 31.791183 -18.476967)
			(xy 31.761696 -18.431081) (xy 31.73904 -18.381465) (xy 31.723676 -18.329129) (xy 31.715917 -18.27514)
			(xy 31.715456 -18.247868) (xy 31.715456 -18.24736) (xy 31.715811 -18.223941) (xy 31.721543 -18.177454)
			(xy 31.726886 -18.15465) (xy 31.729143 -18.142649) (xy 31.723596 -18.118911) (xy 31.716218 -18.109184)
			(xy 31.693611 -18.082102) (xy 31.652904 -18.024482) (xy 31.634938 -17.994122) (xy 31.612078 -17.994884)
			(xy 31.584811 -17.994352) (xy 31.530833 -17.986588) (xy 31.478509 -17.971222) (xy 31.428905 -17.948566)
			(xy 31.383029 -17.919081) (xy 31.341817 -17.883368) (xy 31.306106 -17.842153) (xy 31.276624 -17.796276)
			(xy 31.25397 -17.74667) (xy 31.238607 -17.694345) (xy 31.230846 -17.640367) (xy 28.640459 -17.640367)
			(xy 28.632797 -17.693652) (xy 28.617431 -17.745981) (xy 28.594774 -17.795591) (xy 28.565287 -17.841471)
			(xy 28.529571 -17.882687) (xy 28.488353 -17.918401) (xy 28.442471 -17.947885) (xy 28.392861 -17.970539)
			(xy 28.340531 -17.985901) (xy 28.286547 -17.99366) (xy 28.259278 -17.994122) (xy 28.235402 -17.99336)
			(xy 28.217542 -18.023515) (xy 28.177092 -18.080757) (xy 28.15463 -18.10766) (xy 28.147271 -18.117397)
			(xy 28.141838 -18.141154) (xy 28.144216 -18.153126) (xy 28.149664 -18.17611) (xy 28.155528 -18.22298)
			(xy 28.1559 -18.246598) (xy 28.1559 -18.247106) (xy 28.155381 -18.274374) (xy 28.14762 -18.328354)
			(xy 28.132256 -18.380681) (xy 28.109601 -18.430289) (xy 28.080118 -18.476168) (xy 28.044407 -18.517384)
			(xy 28.003193 -18.553099) (xy 27.957317 -18.582586) (xy 27.907711 -18.605244) (xy 27.855386 -18.620613)
			(xy 27.801406 -18.628379) (xy 27.774138 -18.628868) (xy 27.745325 -18.628327) (xy 27.688355 -18.619651)
			(xy 27.633333 -18.602519) (xy 27.581508 -18.57732) (xy 27.534053 -18.544626) (xy 27.492045 -18.505178)
			(xy 27.456436 -18.459869) (xy 27.428033 -18.409728) (xy 27.417268 -18.382996) (xy 27.412286 -18.371819)
			(xy 27.394121 -18.355489) (xy 27.38247 -18.351754) (xy 27.344873 -18.341525) (xy 27.27181 -18.314446)
			(xy 27.201888 -18.280059) (xy 27.168602 -18.259806) (xy 27.160341 -18.25511) (xy 27.141678 -18.251602)
			(xy 27.123015 -18.25511) (xy 27.114754 -18.259806) (xy 27.081461 -18.280046) (xy 27.011538 -18.314429)
			(xy 26.938481 -18.341523) (xy 26.900886 -18.351754) (xy 26.889244 -18.355501) (xy 26.871079 -18.371829)
			(xy 26.866088 -18.382996) (xy 26.85537 -18.409752) (xy 26.826981 -18.459912) (xy 26.791376 -18.505236)
			(xy 26.749363 -18.544695) (xy 26.701898 -18.577392) (xy 26.650058 -18.602584) (xy 26.595021 -18.619699)
			(xy 26.538037 -18.628349) (xy 26.509218 -18.628868) (xy 26.481948 -18.628382) (xy 26.427962 -18.620622)
			(xy 26.37563 -18.605259) (xy 26.326017 -18.582604) (xy 26.280134 -18.553118) (xy 26.238914 -18.517403)
			(xy 26.203196 -18.476185) (xy 26.173708 -18.430304) (xy 26.15105 -18.380692) (xy 26.135683 -18.328362)
			(xy 26.12792 -18.274376) (xy 26.127456 -18.247106) (xy 26.127456 -18.246598) (xy 26.127815 -18.22298)
			(xy 26.133681 -18.176108) (xy 26.13914 -18.153126) (xy 26.141442 -18.141153) (xy 26.136026 -18.117422)
			(xy 26.128726 -18.10766) (xy 26.106269 -18.080752) (xy 26.065817 -18.023513) (xy 26.047954 -17.99336)
			(xy 26.024078 -17.994122) (xy 25.996807 -17.993714) (xy 25.94282 -17.985949) (xy 25.890488 -17.97058)
			(xy 25.840875 -17.94792) (xy 25.794992 -17.918431) (xy 25.753773 -17.882712) (xy 25.718056 -17.84149)
			(xy 25.688569 -17.795606) (xy 25.665912 -17.745992) (xy 25.650546 -17.693659) (xy 25.642784 -17.639671)
			(xy 23.052559 -17.639671) (xy 23.044797 -17.693652) (xy 23.029431 -17.745981) (xy 23.006774 -17.795591)
			(xy 22.977287 -17.841471) (xy 22.941571 -17.882687) (xy 22.900353 -17.918401) (xy 22.854471 -17.947885)
			(xy 22.804861 -17.970539) (xy 22.752531 -17.985901) (xy 22.698547 -17.99366) (xy 22.671278 -17.994122)
			(xy 22.647402 -17.99336) (xy 22.629542 -18.023515) (xy 22.589092 -18.080757) (xy 22.56663 -18.10766)
			(xy 22.559271 -18.117397) (xy 22.553838 -18.141154) (xy 22.556216 -18.153126) (xy 22.561664 -18.17611)
			(xy 22.567528 -18.22298) (xy 22.5679 -18.246598) (xy 22.5679 -18.247106) (xy 22.567381 -18.274374)
			(xy 22.55962 -18.328354) (xy 22.544256 -18.380681) (xy 22.521601 -18.430289) (xy 22.492118 -18.476168)
			(xy 22.456407 -18.517384) (xy 22.415193 -18.553099) (xy 22.369317 -18.582586) (xy 22.319711 -18.605244)
			(xy 22.267386 -18.620613) (xy 22.213406 -18.628379) (xy 22.186138 -18.628868) (xy 22.157325 -18.628327)
			(xy 22.100355 -18.619651) (xy 22.045333 -18.602519) (xy 21.993508 -18.57732) (xy 21.946053 -18.544626)
			(xy 21.904045 -18.505178) (xy 21.868436 -18.459869) (xy 21.840033 -18.409728) (xy 21.829268 -18.382996)
			(xy 21.824286 -18.371819) (xy 21.806121 -18.355489) (xy 21.79447 -18.351754) (xy 21.756873 -18.341525)
			(xy 21.68381 -18.314446) (xy 21.613888 -18.280059) (xy 21.580602 -18.259806) (xy 21.572341 -18.25511)
			(xy 21.553678 -18.251602) (xy 21.535015 -18.25511) (xy 21.526754 -18.259806) (xy 21.493461 -18.280046)
			(xy 21.423538 -18.314429) (xy 21.350481 -18.341523) (xy 21.312886 -18.351754) (xy 21.301244 -18.355501)
			(xy 21.283079 -18.371829) (xy 21.278088 -18.382996) (xy 21.26737 -18.409752) (xy 21.238981 -18.459912)
			(xy 21.203376 -18.505236) (xy 21.161363 -18.544695) (xy 21.113898 -18.577392) (xy 21.062058 -18.602584)
			(xy 21.007021 -18.619699) (xy 20.950037 -18.628349) (xy 20.921218 -18.628868) (xy 20.893948 -18.628382)
			(xy 20.839962 -18.620622) (xy 20.78763 -18.605259) (xy 20.738017 -18.582604) (xy 20.692134 -18.553118)
			(xy 20.650914 -18.517403) (xy 20.615196 -18.476185) (xy 20.585708 -18.430304) (xy 20.56305 -18.380692)
			(xy 20.547683 -18.328362) (xy 20.53992 -18.274376) (xy 20.539456 -18.247106) (xy 20.539456 -18.246598)
			(xy 20.539815 -18.22298) (xy 20.545681 -18.176108) (xy 20.55114 -18.153126) (xy 20.553442 -18.141153)
			(xy 20.548026 -18.117422) (xy 20.540726 -18.10766) (xy 20.518269 -18.080752) (xy 20.477817 -18.023513)
			(xy 20.459954 -17.99336) (xy 20.436078 -17.994122) (xy 20.408809 -17.993635) (xy 20.354825 -17.985874)
			(xy 20.302496 -17.970508) (xy 20.252886 -17.947852) (xy 20.207005 -17.918366) (xy 20.165788 -17.882651)
			(xy 20.130073 -17.841433) (xy 20.100587 -17.795552) (xy 20.077931 -17.745942) (xy 20.062566 -17.693613)
			(xy 20.054804 -17.639629) (xy 17.464579 -17.639629) (xy 17.464579 -17.639631) (xy 17.456816 -17.693618)
			(xy 17.44145 -17.745951) (xy 17.418792 -17.795564) (xy 17.389304 -17.841448) (xy 17.353587 -17.882668)
			(xy 17.312366 -17.918386) (xy 17.266483 -17.947873) (xy 17.216869 -17.970531) (xy 17.164536 -17.985897)
			(xy 17.110549 -17.993659) (xy 17.083278 -17.994122) (xy 17.059402 -17.99336) (xy 17.041542 -18.023515)
			(xy 17.001092 -18.080757) (xy 16.97863 -18.10766) (xy 16.971271 -18.117397) (xy 16.965838 -18.141154)
			(xy 16.968216 -18.153126) (xy 16.973664 -18.17611) (xy 16.979528 -18.22298) (xy 16.9799 -18.246598)
			(xy 16.9799 -18.247106) (xy 16.979381 -18.274374) (xy 16.97162 -18.328354) (xy 16.956256 -18.380681)
			(xy 16.933601 -18.430289) (xy 16.904118 -18.476168) (xy 16.868407 -18.517384) (xy 16.827193 -18.553099)
			(xy 16.781317 -18.582586) (xy 16.731711 -18.605244) (xy 16.679386 -18.620613) (xy 16.625406 -18.628379)
			(xy 16.598138 -18.628868) (xy 16.569325 -18.628327) (xy 16.512355 -18.619651) (xy 16.457333 -18.602519)
			(xy 16.405508 -18.57732) (xy 16.358053 -18.544626) (xy 16.316045 -18.505178) (xy 16.280436 -18.459869)
			(xy 16.252033 -18.409728) (xy 16.241268 -18.382996) (xy 16.236286 -18.371819) (xy 16.218121 -18.355489)
			(xy 16.20647 -18.351754) (xy 16.168873 -18.341525) (xy 16.09581 -18.314446) (xy 16.025888 -18.280059)
			(xy 15.992602 -18.259806) (xy 15.984341 -18.25511) (xy 15.965678 -18.251602) (xy 15.947015 -18.25511)
			(xy 15.938754 -18.259806) (xy 15.905461 -18.280046) (xy 15.835538 -18.314429) (xy 15.762481 -18.341523)
			(xy 15.724886 -18.351754) (xy 15.713244 -18.355501) (xy 15.695079 -18.371829) (xy 15.690088 -18.382996)
			(xy 15.67937 -18.409752) (xy 15.650981 -18.459912) (xy 15.615376 -18.505236) (xy 15.573363 -18.544695)
			(xy 15.525898 -18.577392) (xy 15.474058 -18.602584) (xy 15.419021 -18.619699) (xy 15.362037 -18.628349)
			(xy 15.333218 -18.628868) (xy 15.305948 -18.628382) (xy 15.251962 -18.620622) (xy 15.19963 -18.605259)
			(xy 15.150017 -18.582604) (xy 15.104134 -18.553118) (xy 15.062914 -18.517403) (xy 15.027196 -18.476185)
			(xy 14.997708 -18.430304) (xy 14.97505 -18.380692) (xy 14.959683 -18.328362) (xy 14.95192 -18.274376)
			(xy 14.951456 -18.247106) (xy 14.951456 -18.246598) (xy 14.951815 -18.22298) (xy 14.957681 -18.176108)
			(xy 14.96314 -18.153126) (xy 14.965442 -18.141153) (xy 14.960026 -18.117422) (xy 14.952726 -18.10766)
			(xy 14.930269 -18.080752) (xy 14.889817 -18.023513) (xy 14.871954 -17.99336) (xy 14.848078 -17.994122)
			(xy 14.820809 -17.993635) (xy 14.766825 -17.985874) (xy 14.714496 -17.970508) (xy 14.664886 -17.947852)
			(xy 14.619005 -17.918366) (xy 14.577788 -17.882651) (xy 14.542073 -17.841433) (xy 14.512587 -17.795552)
			(xy 14.489931 -17.745942) (xy 14.474566 -17.693613) (xy 14.466804 -17.639629) (xy 1.524 -17.639629)
			(xy 1.524 -19.164391) (xy 17.259763 -19.164391) (xy 17.259763 -19.109849) (xy 17.267526 -19.055862)
			(xy 17.282892 -19.00353) (xy 17.30555 -18.953917) (xy 17.335037 -18.908033) (xy 17.370755 -18.866813)
			(xy 17.411975 -18.831096) (xy 17.457858 -18.801609) (xy 17.507472 -18.778951) (xy 17.559804 -18.763585)
			(xy 17.613791 -18.755823) (xy 17.641062 -18.75536) (xy 17.664938 -18.756122) (xy 17.682824 -18.725757)
			(xy 17.723403 -18.668133) (xy 17.745964 -18.64106) (xy 17.753278 -18.631368) (xy 17.758865 -18.60778)
			(xy 17.756632 -18.595848) (xy 17.751406 -18.57335) (xy 17.745805 -18.527502) (xy 17.745456 -18.504408)
			(xy 17.745456 -18.5039) (xy 17.745902 -18.476628) (xy 17.753664 -18.42264) (xy 17.769031 -18.370306)
			(xy 17.79169 -18.320691) (xy 17.82118 -18.274807) (xy 17.856899 -18.233586) (xy 17.898121 -18.197869)
			(xy 17.944007 -18.168382) (xy 17.993623 -18.145725) (xy 18.045957 -18.13036) (xy 18.099946 -18.1226)
			(xy 18.127218 -18.122138) (xy 18.155946 -18.12264) (xy 18.212751 -18.131273) (xy 18.267623 -18.148312)
			(xy 18.319327 -18.173373) (xy 18.366697 -18.205891) (xy 18.408665 -18.245134) (xy 18.444286 -18.290216)
			(xy 18.472757 -18.340123) (xy 18.48358 -18.36674) (xy 18.488598 -18.377844) (xy 18.50677 -18.394023)
			(xy 18.518378 -18.397728) (xy 18.555885 -18.407922) (xy 18.628771 -18.434936) (xy 18.698528 -18.469227)
			(xy 18.731738 -18.489422) (xy 18.739994 -18.494136) (xy 18.758662 -18.497663) (xy 18.77733 -18.494136)
			(xy 18.785586 -18.489422) (xy 18.819134 -18.469005) (xy 18.889631 -18.434383) (xy 18.963314 -18.407192)
			(xy 19.001232 -18.396966) (xy 19.012802 -18.393305) (xy 19.030963 -18.377259) (xy 19.03603 -18.366232)
			(xy 19.046885 -18.339667) (xy 19.075361 -18.289847) (xy 19.110972 -18.24485) (xy 19.152915 -18.205687)
			(xy 19.200245 -18.173241) (xy 19.251898 -18.148242) (xy 19.30671 -18.131254) (xy 19.363446 -18.122659)
			(xy 19.392138 -18.122138) (xy 19.419408 -18.122589) (xy 19.473393 -18.130356) (xy 19.525723 -18.145726)
			(xy 19.575334 -18.168387) (xy 19.621214 -18.197877) (xy 19.662432 -18.233595) (xy 19.698146 -18.274816)
			(xy 19.727632 -18.3207) (xy 19.750287 -18.370312) (xy 19.765652 -18.422644) (xy 19.773414 -18.47663)
			(xy 19.7739 -18.5039) (xy 19.773539 -18.527518) (xy 19.767675 -18.57439) (xy 19.762216 -18.597372)
			(xy 19.759903 -18.609344) (xy 19.765324 -18.633078) (xy 19.77263 -18.642838) (xy 19.794791 -18.669529)
			(xy 19.834732 -18.726258) (xy 19.852386 -18.756122) (xy 19.876262 -18.75536) (xy 19.903531 -18.755843)
			(xy 19.957515 -18.763605) (xy 20.009845 -18.77897) (xy 20.059455 -18.801627) (xy 20.105336 -18.831113)
			(xy 20.146553 -18.866828) (xy 20.182269 -18.908046) (xy 20.211754 -18.953927) (xy 20.234411 -19.003537)
			(xy 20.249776 -19.055867) (xy 20.257538 -19.109851) (xy 20.257538 -19.163671) (xy 22.848784 -19.163671)
			(xy 22.848784 -19.109129) (xy 22.856546 -19.055141) (xy 22.871912 -19.002808) (xy 22.894569 -18.953194)
			(xy 22.924056 -18.90731) (xy 22.959773 -18.866088) (xy 23.000992 -18.830369) (xy 23.046875 -18.80088)
			(xy 23.096488 -18.77822) (xy 23.14882 -18.762851) (xy 23.202807 -18.755086) (xy 23.230078 -18.754598)
			(xy 23.253954 -18.75536) (xy 23.271691 -18.725217) (xy 23.311888 -18.667978) (xy 23.334218 -18.64106)
			(xy 23.341537 -18.631372) (xy 23.347118 -18.607781) (xy 23.344886 -18.595848) (xy 23.339561 -18.57317)
			(xy 23.333832 -18.526938) (xy 23.333456 -18.503646) (xy 23.333456 -18.503138) (xy 23.333937 -18.475867)
			(xy 23.341694 -18.42188) (xy 23.357057 -18.369546) (xy 23.379711 -18.319932) (xy 23.409196 -18.274047)
			(xy 23.444912 -18.232826) (xy 23.486131 -18.197108) (xy 23.532015 -18.167621) (xy 23.581628 -18.144964)
			(xy 23.63396 -18.129599) (xy 23.687947 -18.121838) (xy 23.715218 -18.121376) (xy 23.743919 -18.121956)
			(xy 23.800673 -18.130566) (xy 23.855499 -18.147573) (xy 23.907161 -18.172594) (xy 23.954496 -18.205067)
			(xy 23.996438 -18.244259) (xy 24.032041 -18.289286) (xy 24.060504 -18.339136) (xy 24.071326 -18.365724)
			(xy 24.076327 -18.376837) (xy 24.094511 -18.393013) (xy 24.106124 -18.396712) (xy 24.143849 -18.406917)
			(xy 24.217171 -18.433975) (xy 24.287346 -18.468381) (xy 24.320754 -18.48866) (xy 24.32901 -18.493374)
			(xy 24.347678 -18.496901) (xy 24.366346 -18.493374) (xy 24.374602 -18.48866) (xy 24.408008 -18.468378)
			(xy 24.478183 -18.433971) (xy 24.551504 -18.406907) (xy 24.589232 -18.396712) (xy 24.600845 -18.393017)
			(xy 24.619017 -18.376832) (xy 24.62403 -18.365724) (xy 24.634832 -18.339122) (xy 24.663277 -18.28925)
			(xy 24.698871 -18.244202) (xy 24.740812 -18.204995) (xy 24.788154 -18.172512) (xy 24.839826 -18.147488)
			(xy 24.894665 -18.130486) (xy 24.951431 -18.121891) (xy 24.980138 -18.121376) (xy 25.00741 -18.121789)
			(xy 25.061398 -18.129557) (xy 25.113731 -18.144929) (xy 25.163344 -18.167593) (xy 25.209227 -18.197086)
			(xy 25.250445 -18.232809) (xy 25.28616 -18.274034) (xy 25.315644 -18.319922) (xy 25.338297 -18.36954)
			(xy 25.353659 -18.421876) (xy 25.361416 -18.475866) (xy 25.3619 -18.503138) (xy 25.3619 -18.503646)
			(xy 25.361521 -18.526938) (xy 25.355787 -18.573168) (xy 25.35047 -18.595848) (xy 25.34819 -18.607783)
			(xy 25.353771 -18.631396) (xy 25.361138 -18.64106) (xy 25.383468 -18.667978) (xy 25.423665 -18.725217)
			(xy 25.441402 -18.75536) (xy 25.465278 -18.754598) (xy 25.492547 -18.75514) (xy 25.546531 -18.762899)
			(xy 25.598861 -18.778261) (xy 25.648471 -18.800915) (xy 25.694353 -18.830399) (xy 25.735571 -18.866113)
			(xy 25.771287 -18.907329) (xy 25.800774 -18.953209) (xy 25.823431 -19.002819) (xy 25.838797 -19.055148)
			(xy 25.846559 -19.109131) (xy 25.846559 -19.163669) (xy 25.846559 -19.163671) (xy 28.436784 -19.163671)
			(xy 28.436784 -19.109129) (xy 28.444546 -19.055141) (xy 28.459912 -19.002808) (xy 28.482569 -18.953194)
			(xy 28.512056 -18.90731) (xy 28.547773 -18.866088) (xy 28.588992 -18.830369) (xy 28.634875 -18.80088)
			(xy 28.684488 -18.77822) (xy 28.73682 -18.762851) (xy 28.790807 -18.755086) (xy 28.818078 -18.754598)
			(xy 28.841954 -18.75536) (xy 28.859691 -18.725217) (xy 28.899888 -18.667978) (xy 28.922218 -18.64106)
			(xy 28.929537 -18.631372) (xy 28.935118 -18.607781) (xy 28.932886 -18.595848) (xy 28.927561 -18.57317)
			(xy 28.921832 -18.526938) (xy 28.921456 -18.503646) (xy 28.921456 -18.503138) (xy 28.921937 -18.475867)
			(xy 28.929694 -18.42188) (xy 28.945057 -18.369546) (xy 28.967711 -18.319932) (xy 28.997196 -18.274047)
			(xy 29.032912 -18.232826) (xy 29.074131 -18.197108) (xy 29.120015 -18.167621) (xy 29.169628 -18.144964)
			(xy 29.22196 -18.129599) (xy 29.275947 -18.121838) (xy 29.303218 -18.121376) (xy 29.331919 -18.121956)
			(xy 29.388673 -18.130566) (xy 29.443499 -18.147573) (xy 29.495161 -18.172594) (xy 29.542496 -18.205067)
			(xy 29.584438 -18.244259) (xy 29.620041 -18.289286) (xy 29.648504 -18.339136) (xy 29.659326 -18.365724)
			(xy 29.664327 -18.376837) (xy 29.682511 -18.393013) (xy 29.694124 -18.396712) (xy 29.731849 -18.406917)
			(xy 29.805171 -18.433975) (xy 29.875346 -18.468381) (xy 29.908754 -18.48866) (xy 29.91701 -18.493374)
			(xy 29.935678 -18.496901) (xy 29.954346 -18.493374) (xy 29.962602 -18.48866) (xy 29.996008 -18.468378)
			(xy 30.066183 -18.433971) (xy 30.139504 -18.406907) (xy 30.177232 -18.396712) (xy 30.188845 -18.393017)
			(xy 30.207017 -18.376832) (xy 30.21203 -18.365724) (xy 30.222832 -18.339122) (xy 30.251277 -18.28925)
			(xy 30.286871 -18.244202) (xy 30.328812 -18.204995) (xy 30.376154 -18.172512) (xy 30.427826 -18.147488)
			(xy 30.482665 -18.130486) (xy 30.539431 -18.121891) (xy 30.568138 -18.121376) (xy 30.59541 -18.121789)
			(xy 30.649398 -18.129557) (xy 30.701731 -18.144929) (xy 30.751344 -18.167593) (xy 30.797227 -18.197086)
			(xy 30.838445 -18.232809) (xy 30.87416 -18.274034) (xy 30.903644 -18.319922) (xy 30.926297 -18.36954)
			(xy 30.941659 -18.421876) (xy 30.949416 -18.475866) (xy 30.9499 -18.503138) (xy 30.9499 -18.503646)
			(xy 30.949521 -18.526938) (xy 30.943787 -18.573168) (xy 30.93847 -18.595848) (xy 30.93619 -18.607783)
			(xy 30.941771 -18.631396) (xy 30.949138 -18.64106) (xy 30.971468 -18.667978) (xy 31.011665 -18.725217)
			(xy 31.029402 -18.75536) (xy 31.053278 -18.754598) (xy 31.080547 -18.75514) (xy 31.134531 -18.762899)
			(xy 31.186861 -18.778261) (xy 31.236471 -18.800915) (xy 31.282353 -18.830399) (xy 31.323571 -18.866113)
			(xy 31.359287 -18.907329) (xy 31.388774 -18.953209) (xy 31.411431 -19.002819) (xy 31.426797 -19.055148)
			(xy 31.434559 -19.109131) (xy 31.434559 -19.163669) (xy 31.434559 -19.163671) (xy 34.024784 -19.163671)
			(xy 34.024784 -19.109129) (xy 34.032546 -19.055141) (xy 34.047912 -19.002808) (xy 34.070569 -18.953194)
			(xy 34.100056 -18.90731) (xy 34.135773 -18.866088) (xy 34.176992 -18.830369) (xy 34.222875 -18.80088)
			(xy 34.272488 -18.77822) (xy 34.32482 -18.762851) (xy 34.378807 -18.755086) (xy 34.406078 -18.754598)
			(xy 34.429954 -18.75536) (xy 34.447691 -18.725217) (xy 34.487888 -18.667978) (xy 34.510218 -18.64106)
			(xy 34.517537 -18.631372) (xy 34.523118 -18.607781) (xy 34.520886 -18.595848) (xy 34.515561 -18.57317)
			(xy 34.509832 -18.526938) (xy 34.509456 -18.503646) (xy 34.509456 -18.503138) (xy 34.509937 -18.475867)
			(xy 34.517694 -18.42188) (xy 34.533057 -18.369546) (xy 34.555711 -18.319932) (xy 34.585196 -18.274047)
			(xy 34.620912 -18.232826) (xy 34.662131 -18.197108) (xy 34.708015 -18.167621) (xy 34.757628 -18.144964)
			(xy 34.80996 -18.129599) (xy 34.863947 -18.121838) (xy 34.891218 -18.121376) (xy 34.919919 -18.121956)
			(xy 34.976673 -18.130566) (xy 35.031499 -18.147573) (xy 35.083161 -18.172594) (xy 35.130496 -18.205067)
			(xy 35.172438 -18.244259) (xy 35.208041 -18.289286) (xy 35.236504 -18.339136) (xy 35.247326 -18.365724)
			(xy 35.252327 -18.376837) (xy 35.270511 -18.393013) (xy 35.282124 -18.396712) (xy 35.319849 -18.406917)
			(xy 35.393171 -18.433975) (xy 35.463346 -18.468381) (xy 35.496754 -18.48866) (xy 35.50501 -18.493374)
			(xy 35.523678 -18.496901) (xy 35.542346 -18.493374) (xy 35.550602 -18.48866) (xy 35.584008 -18.468378)
			(xy 35.654183 -18.433971) (xy 35.727504 -18.406907) (xy 35.765232 -18.396712) (xy 35.776845 -18.393017)
			(xy 35.795017 -18.376832) (xy 35.80003 -18.365724) (xy 35.810832 -18.339122) (xy 35.839277 -18.28925)
			(xy 35.874871 -18.244202) (xy 35.916812 -18.204995) (xy 35.964154 -18.172512) (xy 36.015826 -18.147488)
			(xy 36.070665 -18.130486) (xy 36.127431 -18.121891) (xy 36.156138 -18.121376) (xy 36.18341 -18.121789)
			(xy 36.237398 -18.129557) (xy 36.289731 -18.144929) (xy 36.339344 -18.167593) (xy 36.385227 -18.197086)
			(xy 36.426445 -18.232809) (xy 36.46216 -18.274034) (xy 36.491644 -18.319922) (xy 36.514297 -18.36954)
			(xy 36.529659 -18.421876) (xy 36.537416 -18.475866) (xy 36.5379 -18.503138) (xy 36.5379 -18.503646)
			(xy 36.537521 -18.526938) (xy 36.531787 -18.573168) (xy 36.52647 -18.595848) (xy 36.52419 -18.607783)
			(xy 36.529771 -18.631396) (xy 36.537138 -18.64106) (xy 36.559468 -18.667978) (xy 36.599665 -18.725217)
			(xy 36.617402 -18.75536) (xy 36.641278 -18.754598) (xy 36.668547 -18.75514) (xy 36.722531 -18.762899)
			(xy 36.774861 -18.778261) (xy 36.824471 -18.800915) (xy 36.870353 -18.830399) (xy 36.911571 -18.866113)
			(xy 36.947287 -18.907329) (xy 36.976774 -18.953209) (xy 36.999431 -19.002819) (xy 37.014797 -19.055148)
			(xy 37.022559 -19.109131) (xy 37.022559 -19.163669) (xy 37.022559 -19.163672) (xy 39.918585 -19.163672)
			(xy 39.918585 -19.109128) (xy 39.926347 -19.055139) (xy 39.941713 -19.002805) (xy 39.964372 -18.95319)
			(xy 39.99386 -18.907304) (xy 40.029578 -18.866083) (xy 40.0708 -18.830364) (xy 40.116685 -18.800875)
			(xy 40.166299 -18.778216) (xy 40.218633 -18.762848) (xy 40.272622 -18.755085) (xy 40.299894 -18.754598)
			(xy 40.32377 -18.75536) (xy 40.341506 -18.725216) (xy 40.381703 -18.667977) (xy 40.404034 -18.64106)
			(xy 40.411354 -18.631373) (xy 40.416934 -18.607781) (xy 40.414702 -18.595848) (xy 40.409376 -18.57317)
			(xy 40.403648 -18.526938) (xy 40.403272 -18.503646) (xy 40.403272 -18.503138) (xy 40.403737 -18.475866)
			(xy 40.411495 -18.421878) (xy 40.426858 -18.369543) (xy 40.449514 -18.319928) (xy 40.479 -18.274042)
			(xy 40.514718 -18.232821) (xy 40.555939 -18.197103) (xy 40.601824 -18.167615) (xy 40.651439 -18.144959)
			(xy 40.703774 -18.129596) (xy 40.757762 -18.121837) (xy 40.785034 -18.121376) (xy 40.813736 -18.121942)
			(xy 40.87049 -18.130554) (xy 40.925316 -18.147564) (xy 40.976979 -18.172587) (xy 41.024314 -18.205062)
			(xy 41.066255 -18.244255) (xy 41.101858 -18.289284) (xy 41.13032 -18.339135) (xy 41.141142 -18.365724)
			(xy 41.146185 -18.376813) (xy 41.164339 -18.392999) (xy 41.17594 -18.396712) (xy 41.213666 -18.406913)
			(xy 41.286988 -18.433973) (xy 41.357163 -18.46838) (xy 41.39057 -18.48866) (xy 41.398826 -18.493374)
			(xy 41.417494 -18.496901) (xy 41.436162 -18.493374) (xy 41.444418 -18.48866) (xy 41.477822 -18.468374)
			(xy 41.547998 -18.433969) (xy 41.62132 -18.406907) (xy 41.659048 -18.396712) (xy 41.670664 -18.393024)
			(xy 41.688834 -18.376834) (xy 41.693846 -18.365724) (xy 41.704635 -18.339117) (xy 41.733081 -18.289244)
			(xy 41.768677 -18.244196) (xy 41.81062 -18.204988) (xy 41.857964 -18.172506) (xy 41.909638 -18.147483)
			(xy 41.964479 -18.130483) (xy 42.021247 -18.12189) (xy 42.049954 -18.121376) (xy 42.077226 -18.121844)
			(xy 42.131214 -18.129601) (xy 42.183549 -18.144964) (xy 42.233165 -18.167619) (xy 42.27905 -18.197105)
			(xy 42.320272 -18.232822) (xy 42.35599 -18.274043) (xy 42.385478 -18.319928) (xy 42.408134 -18.369543)
			(xy 42.423497 -18.421878) (xy 42.431255 -18.475866) (xy 42.431716 -18.503138) (xy 42.431716 -18.503646)
			(xy 42.431337 -18.526938) (xy 42.425603 -18.573168) (xy 42.420286 -18.595848) (xy 42.418003 -18.607783)
			(xy 42.423585 -18.631397) (xy 42.430954 -18.64106) (xy 42.453284 -18.667977) (xy 42.493481 -18.725217)
			(xy 42.511218 -18.75536) (xy 42.535094 -18.754598) (xy 42.562362 -18.755141) (xy 42.616344 -18.762902)
			(xy 42.668672 -18.778266) (xy 42.718281 -18.800921) (xy 42.764161 -18.830405) (xy 42.805377 -18.866119)
			(xy 42.841091 -18.907335) (xy 42.870577 -18.953214) (xy 42.893232 -19.002822) (xy 42.908597 -19.05515)
			(xy 42.916359 -19.109132) (xy 42.916359 -19.163668) (xy 42.916258 -19.164367) (xy 45.505646 -19.164367)
			(xy 45.505646 -19.109833) (xy 45.513407 -19.055855) (xy 45.52877 -19.00353) (xy 45.551424 -18.953924)
			(xy 45.580906 -18.908047) (xy 45.616617 -18.866832) (xy 45.657829 -18.831119) (xy 45.703705 -18.801634)
			(xy 45.753309 -18.778978) (xy 45.805633 -18.763612) (xy 45.859611 -18.755848) (xy 45.886878 -18.75536)
			(xy 45.910754 -18.756122) (xy 45.928638 -18.725756) (xy 45.969218 -18.668133) (xy 45.99178 -18.64106)
			(xy 45.999096 -18.63137) (xy 46.004681 -18.607781) (xy 46.002448 -18.595848) (xy 45.997222 -18.57335)
			(xy 45.991621 -18.527502) (xy 45.991272 -18.504408) (xy 45.991272 -18.5039) (xy 45.991702 -18.476627)
			(xy 45.999465 -18.422638) (xy 46.014833 -18.370302) (xy 46.037493 -18.320687) (xy 46.066983 -18.274801)
			(xy 46.102705 -18.23358) (xy 46.143929 -18.197863) (xy 46.189817 -18.168376) (xy 46.239434 -18.145721)
			(xy 46.291771 -18.130357) (xy 46.345761 -18.122599) (xy 46.373034 -18.122138) (xy 46.40176 -18.122712)
			(xy 46.458561 -18.131333) (xy 46.513432 -18.14836) (xy 46.565135 -18.17341) (xy 46.612506 -18.205918)
			(xy 46.654475 -18.245152) (xy 46.690099 -18.290227) (xy 46.718572 -18.340126) (xy 46.729396 -18.36674)
			(xy 46.734406 -18.377848) (xy 46.752584 -18.394025) (xy 46.764194 -18.397728) (xy 46.801702 -18.407919)
			(xy 46.874587 -18.434934) (xy 46.944345 -18.469226) (xy 46.977554 -18.489422) (xy 46.985802 -18.494137)
			(xy 47.004442 -18.497734) (xy 47.023117 -18.494325) (xy 47.031402 -18.489676) (xy 47.069036 -18.466836)
			(xy 47.148534 -18.429009) (xy 47.231849 -18.400564) (xy 47.274734 -18.390616) (xy 47.286764 -18.387415)
			(xy 47.305809 -18.371426) (xy 47.311056 -18.360136) (xy 47.322167 -18.33413) (xy 47.350959 -18.285457)
			(xy 47.386616 -18.241564) (xy 47.428358 -18.203411) (xy 47.475272 -18.171834) (xy 47.526331 -18.147522)
			(xy 47.580418 -18.131009) (xy 47.636348 -18.122656) (xy 47.664624 -18.122138) (xy 47.691894 -18.122602)
			(xy 47.745878 -18.130367) (xy 47.798208 -18.145735) (xy 47.847819 -18.168394) (xy 47.893699 -18.197883)
			(xy 47.934917 -18.2336) (xy 47.970632 -18.27482) (xy 48.000117 -18.320703) (xy 48.022773 -18.370314)
			(xy 48.038138 -18.422645) (xy 48.0459 -18.47663) (xy 48.046386 -18.5039) (xy 48.046386 -18.504154)
			(xy 48.045808 -18.533325) (xy 48.036873 -18.590981) (xy 48.028606 -18.618962) (xy 48.025505 -18.630975)
			(xy 48.030038 -18.655342) (xy 48.037242 -18.665444) (xy 48.053888 -18.687136) (xy 48.084399 -18.732518)
			(xy 48.098202 -18.756122) (xy 48.122078 -18.75536) (xy 48.149352 -18.755778) (xy 48.203344 -18.763538)
			(xy 48.255682 -18.778903) (xy 48.305301 -18.801561) (xy 48.35119 -18.83105) (xy 48.392415 -18.866769)
			(xy 48.428137 -18.907992) (xy 48.457628 -18.95388) (xy 48.480289 -19.003497) (xy 48.495657 -19.055835)
			(xy 48.50342 -19.109826) (xy 48.50342 -19.163675) (xy 51.128562 -19.163675) (xy 51.128562 -19.109125)
			(xy 51.136325 -19.05513) (xy 51.151695 -19.002789) (xy 51.174357 -18.953169) (xy 51.20385 -18.907279)
			(xy 51.239575 -18.866054) (xy 51.280803 -18.830332) (xy 51.326695 -18.800843) (xy 51.376317 -18.778184)
			(xy 51.428659 -18.762819) (xy 51.482655 -18.75506) (xy 51.50993 -18.754598) (xy 51.533806 -18.75536)
			(xy 51.551546 -18.725219) (xy 51.591741 -18.667978) (xy 51.61407 -18.64106) (xy 51.621385 -18.631369)
			(xy 51.626971 -18.60778) (xy 51.624738 -18.595848) (xy 51.619412 -18.57317) (xy 51.613684 -18.526938)
			(xy 51.613308 -18.503646) (xy 51.613308 -18.503138) (xy 51.613837 -18.475869) (xy 51.621593 -18.421886)
			(xy 51.636953 -18.369557) (xy 51.659604 -18.319946) (xy 51.689085 -18.274063) (xy 51.724795 -18.232843)
			(xy 51.766009 -18.197125) (xy 51.811886 -18.167636) (xy 51.861493 -18.144977) (xy 51.91382 -18.129607)
			(xy 51.967801 -18.121842) (xy 51.99507 -18.121376) (xy 52.023773 -18.121912) (xy 52.080528 -18.130529)
			(xy 52.135355 -18.147543) (xy 52.187018 -18.172571) (xy 52.234353 -18.20505) (xy 52.276294 -18.244247)
			(xy 52.311896 -18.28928) (xy 52.340357 -18.339134) (xy 52.351178 -18.365724) (xy 52.356203 -18.376824)
			(xy 52.37437 -18.393005) (xy 52.385976 -18.396712) (xy 52.423705 -18.406905) (xy 52.497026 -18.433968)
			(xy 52.567199 -18.468379) (xy 52.600606 -18.48866) (xy 52.608862 -18.493374) (xy 52.62753 -18.496901)
			(xy 52.646198 -18.493374) (xy 52.654454 -18.48866) (xy 52.687866 -18.468387) (xy 52.758039 -18.433977)
			(xy 52.831357 -18.40691) (xy 52.869084 -18.396712) (xy 52.880706 -18.39304) (xy 52.898873 -18.376838)
			(xy 52.903882 -18.365724) (xy 52.914641 -18.339104) (xy 52.943091 -18.28923) (xy 52.978691 -18.244181)
			(xy 53.020638 -18.204974) (xy 53.067986 -18.172493) (xy 53.119665 -18.147472) (xy 53.174509 -18.130476)
			(xy 53.231281 -18.121888) (xy 53.25999 -18.121376) (xy 53.287262 -18.121811) (xy 53.341252 -18.129573)
			(xy 53.393588 -18.14494) (xy 53.443204 -18.167599) (xy 53.489089 -18.197089) (xy 53.53031 -18.23281)
			(xy 53.566028 -18.274033) (xy 53.595515 -18.319921) (xy 53.61817 -18.369538) (xy 53.633533 -18.421875)
			(xy 53.641291 -18.475865) (xy 53.641752 -18.503138) (xy 53.641752 -18.503646) (xy 53.641372 -18.526938)
			(xy 53.635639 -18.573168) (xy 53.630322 -18.595848) (xy 53.62803 -18.607782) (xy 53.633616 -18.631398)
			(xy 53.64099 -18.64106) (xy 53.663323 -18.667976) (xy 53.703518 -18.725217) (xy 53.721254 -18.75536)
			(xy 53.74513 -18.754598) (xy 53.772395 -18.755166) (xy 53.82637 -18.762931) (xy 53.87869 -18.778297)
			(xy 53.928291 -18.800953) (xy 53.974164 -18.830436) (xy 54.015374 -18.866148) (xy 54.051082 -18.90736)
			(xy 54.080562 -18.953235) (xy 54.103213 -19.002838) (xy 54.118576 -19.05516) (xy 54.126336 -19.109135)
			(xy 54.126336 -19.163665) (xy 54.126335 -19.163675) (xy 56.716562 -19.163675) (xy 56.716562 -19.109125)
			(xy 56.724325 -19.05513) (xy 56.739695 -19.002789) (xy 56.762357 -18.953169) (xy 56.79185 -18.907279)
			(xy 56.827575 -18.866054) (xy 56.868803 -18.830332) (xy 56.914695 -18.800843) (xy 56.964317 -18.778184)
			(xy 57.016659 -18.762819) (xy 57.070655 -18.75506) (xy 57.09793 -18.754598) (xy 57.121806 -18.75536)
			(xy 57.139546 -18.725219) (xy 57.179741 -18.667978) (xy 57.20207 -18.64106) (xy 57.209385 -18.631369)
			(xy 57.214971 -18.60778) (xy 57.212738 -18.595848) (xy 57.207412 -18.57317) (xy 57.201684 -18.526938)
			(xy 57.201308 -18.503646) (xy 57.201308 -18.503138) (xy 57.201837 -18.475869) (xy 57.209593 -18.421886)
			(xy 57.224953 -18.369557) (xy 57.247604 -18.319946) (xy 57.277085 -18.274063) (xy 57.312795 -18.232843)
			(xy 57.354009 -18.197125) (xy 57.399886 -18.167636) (xy 57.449493 -18.144977) (xy 57.50182 -18.129607)
			(xy 57.555801 -18.121842) (xy 57.58307 -18.121376) (xy 57.611773 -18.121912) (xy 57.668528 -18.130529)
			(xy 57.723355 -18.147543) (xy 57.775018 -18.172571) (xy 57.822353 -18.20505) (xy 57.864294 -18.244247)
			(xy 57.899896 -18.28928) (xy 57.928357 -18.339134) (xy 57.939178 -18.365724) (xy 57.944203 -18.376824)
			(xy 57.96237 -18.393005) (xy 57.973976 -18.396712) (xy 58.011705 -18.406905) (xy 58.085026 -18.433968)
			(xy 58.155199 -18.468379) (xy 58.188606 -18.48866) (xy 58.196862 -18.493374) (xy 58.21553 -18.496901)
			(xy 58.234198 -18.493374) (xy 58.242454 -18.48866) (xy 58.275866 -18.468387) (xy 58.346039 -18.433977)
			(xy 58.419357 -18.40691) (xy 58.457084 -18.396712) (xy 58.468706 -18.39304) (xy 58.486873 -18.376838)
			(xy 58.491882 -18.365724) (xy 58.502641 -18.339104) (xy 58.531091 -18.28923) (xy 58.566691 -18.244181)
			(xy 58.608638 -18.204974) (xy 58.655986 -18.172493) (xy 58.707665 -18.147472) (xy 58.762509 -18.130476)
			(xy 58.819281 -18.121888) (xy 58.84799 -18.121376) (xy 58.875262 -18.121811) (xy 58.929252 -18.129573)
			(xy 58.981588 -18.14494) (xy 59.031204 -18.167599) (xy 59.077089 -18.197089) (xy 59.11831 -18.23281)
			(xy 59.154028 -18.274033) (xy 59.183515 -18.319921) (xy 59.20617 -18.369538) (xy 59.221533 -18.421875)
			(xy 59.229291 -18.475865) (xy 59.229752 -18.503138) (xy 59.229752 -18.503646) (xy 59.229372 -18.526938)
			(xy 59.223639 -18.573168) (xy 59.218322 -18.595848) (xy 59.21603 -18.607782) (xy 59.221616 -18.631398)
			(xy 59.22899 -18.64106) (xy 59.251323 -18.667976) (xy 59.291518 -18.725217) (xy 59.309254 -18.75536)
			(xy 59.33313 -18.754598) (xy 59.360395 -18.755166) (xy 59.41437 -18.762931) (xy 59.46669 -18.778297)
			(xy 59.516291 -18.800953) (xy 59.562164 -18.830436) (xy 59.603374 -18.866148) (xy 59.639082 -18.90736)
			(xy 59.668562 -18.953235) (xy 59.691213 -19.002838) (xy 59.706576 -19.05516) (xy 59.714336 -19.109135)
			(xy 59.714336 -19.163665) (xy 59.706576 -19.21764) (xy 59.691213 -19.269962) (xy 59.668562 -19.319565)
			(xy 59.639082 -19.36544) (xy 59.603374 -19.406652) (xy 59.562164 -19.442364) (xy 59.516291 -19.471847)
			(xy 59.46669 -19.494503) (xy 59.41437 -19.509869) (xy 59.360395 -19.517634) (xy 59.33313 -19.518122)
			(xy 59.309254 -19.51736) (xy 59.291397 -19.547517) (xy 59.250946 -19.604758) (xy 59.228482 -19.63166)
			(xy 59.22112 -19.641394) (xy 59.215691 -19.665153) (xy 59.218068 -19.677126) (xy 59.223515 -19.70011)
			(xy 59.22938 -19.74698) (xy 59.229752 -19.770598) (xy 59.229752 -19.771106) (xy 59.229304 -19.798378)
			(xy 59.221541 -19.852366) (xy 59.206173 -19.904699) (xy 59.183514 -19.954313) (xy 59.154025 -20.000197)
			(xy 59.118306 -20.041417) (xy 59.077084 -20.077135) (xy 59.031199 -20.106622) (xy 58.981584 -20.129279)
			(xy 58.92925 -20.144644) (xy 58.875262 -20.152405) (xy 58.84799 -20.152868) (xy 58.819178 -20.152282)
			(xy 58.76221 -20.143613) (xy 58.70719 -20.126489) (xy 58.655365 -20.101297) (xy 58.60791 -20.068609)
			(xy 58.565901 -20.029166) (xy 58.530291 -19.983863) (xy 58.501887 -19.933726) (xy 58.49112 -19.906996)
			(xy 58.486163 -19.895806) (xy 58.46798 -19.879481) (xy 58.456322 -19.875754) (xy 58.418722 -19.865536)
			(xy 58.34566 -19.838452) (xy 58.275739 -19.804061) (xy 58.242454 -19.783806) (xy 58.234193 -19.77911)
			(xy 58.21553 -19.775602) (xy 58.196867 -19.77911) (xy 58.188606 -19.783806) (xy 58.155319 -19.804056)
			(xy 58.085393 -19.838435) (xy 58.012334 -19.865525) (xy 57.974738 -19.875754) (xy 57.963105 -19.879524)
			(xy 57.944935 -19.895835) (xy 57.93994 -19.906996) (xy 57.929179 -19.933733) (xy 57.900795 -19.983892)
			(xy 57.865195 -20.029215) (xy 57.823189 -20.068674) (xy 57.77573 -20.101373) (xy 57.723897 -20.126569)
			(xy 57.668865 -20.143689) (xy 57.611886 -20.152345) (xy 57.58307 -20.152868) (xy 57.5558 -20.152403)
			(xy 57.501816 -20.144638) (xy 57.449487 -20.129269) (xy 57.399877 -20.10661) (xy 57.353996 -20.077121)
			(xy 57.312779 -20.041404) (xy 57.277064 -20.000185) (xy 57.247579 -19.954302) (xy 57.224923 -19.904691)
			(xy 57.209557 -19.85236) (xy 57.201795 -19.798376) (xy 57.201308 -19.771106) (xy 57.201308 -19.770598)
			(xy 57.201669 -19.74698) (xy 57.207533 -19.700108) (xy 57.212992 -19.677126) (xy 57.215305 -19.665154)
			(xy 57.209884 -19.64142) (xy 57.202578 -19.63166) (xy 57.180118 -19.604755) (xy 57.139668 -19.547514)
			(xy 57.121806 -19.51736) (xy 57.09793 -19.518122) (xy 57.070655 -19.51774) (xy 57.016659 -19.509981)
			(xy 56.964317 -19.494616) (xy 56.914695 -19.471957) (xy 56.868803 -19.442468) (xy 56.827575 -19.406746)
			(xy 56.79185 -19.365521) (xy 56.762357 -19.319631) (xy 56.739695 -19.270011) (xy 56.724325 -19.21767)
			(xy 56.716562 -19.163675) (xy 54.126335 -19.163675) (xy 54.118576 -19.21764) (xy 54.103213 -19.269962)
			(xy 54.080562 -19.319565) (xy 54.051082 -19.36544) (xy 54.015374 -19.406652) (xy 53.974164 -19.442364)
			(xy 53.928291 -19.471847) (xy 53.87869 -19.494503) (xy 53.82637 -19.509869) (xy 53.772395 -19.517634)
			(xy 53.74513 -19.518122) (xy 53.721254 -19.51736) (xy 53.703397 -19.547517) (xy 53.662946 -19.604758)
			(xy 53.640482 -19.63166) (xy 53.63312 -19.641394) (xy 53.627691 -19.665153) (xy 53.630068 -19.677126)
			(xy 53.635515 -19.70011) (xy 53.64138 -19.74698) (xy 53.641752 -19.770598) (xy 53.641752 -19.771106)
			(xy 53.641304 -19.798378) (xy 53.633541 -19.852366) (xy 53.618173 -19.904699) (xy 53.595514 -19.954313)
			(xy 53.566025 -20.000197) (xy 53.530306 -20.041417) (xy 53.489084 -20.077135) (xy 53.443199 -20.106622)
			(xy 53.393584 -20.129279) (xy 53.34125 -20.144644) (xy 53.287262 -20.152405) (xy 53.25999 -20.152868)
			(xy 53.231178 -20.152282) (xy 53.17421 -20.143613) (xy 53.11919 -20.126489) (xy 53.067365 -20.101297)
			(xy 53.01991 -20.068609) (xy 52.977901 -20.029166) (xy 52.942291 -19.983863) (xy 52.913887 -19.933726)
			(xy 52.90312 -19.906996) (xy 52.898163 -19.895806) (xy 52.87998 -19.879481) (xy 52.868322 -19.875754)
			(xy 52.830722 -19.865536) (xy 52.75766 -19.838452) (xy 52.687739 -19.804061) (xy 52.654454 -19.783806)
			(xy 52.646193 -19.77911) (xy 52.62753 -19.775602) (xy 52.608867 -19.77911) (xy 52.600606 -19.783806)
			(xy 52.567319 -19.804056) (xy 52.497393 -19.838435) (xy 52.424334 -19.865525) (xy 52.386738 -19.875754)
			(xy 52.375105 -19.879524) (xy 52.356935 -19.895835) (xy 52.35194 -19.906996) (xy 52.341179 -19.933733)
			(xy 52.312795 -19.983892) (xy 52.277195 -20.029215) (xy 52.235189 -20.068674) (xy 52.18773 -20.101373)
			(xy 52.135897 -20.126569) (xy 52.080865 -20.143689) (xy 52.023886 -20.152345) (xy 51.99507 -20.152868)
			(xy 51.9678 -20.152403) (xy 51.913816 -20.144638) (xy 51.861487 -20.129269) (xy 51.811877 -20.10661)
			(xy 51.765996 -20.077121) (xy 51.724779 -20.041404) (xy 51.689064 -20.000185) (xy 51.659579 -19.954302)
			(xy 51.636923 -19.904691) (xy 51.621557 -19.85236) (xy 51.613795 -19.798376) (xy 51.613308 -19.771106)
			(xy 51.613308 -19.770598) (xy 51.613669 -19.74698) (xy 51.619533 -19.700108) (xy 51.624992 -19.677126)
			(xy 51.627305 -19.665154) (xy 51.621884 -19.64142) (xy 51.614578 -19.63166) (xy 51.592118 -19.604755)
			(xy 51.551668 -19.547514) (xy 51.533806 -19.51736) (xy 51.50993 -19.518122) (xy 51.482655 -19.51774)
			(xy 51.428659 -19.509981) (xy 51.376317 -19.494616) (xy 51.326695 -19.471957) (xy 51.280803 -19.442468)
			(xy 51.239575 -19.406746) (xy 51.20385 -19.365521) (xy 51.174357 -19.319631) (xy 51.151695 -19.270011)
			(xy 51.136325 -19.21767) (xy 51.128562 -19.163675) (xy 48.50342 -19.163675) (xy 48.50342 -19.164374)
			(xy 48.495657 -19.218365) (xy 48.480289 -19.270703) (xy 48.457628 -19.32032) (xy 48.428137 -19.366208)
			(xy 48.392415 -19.407431) (xy 48.35119 -19.44315) (xy 48.305301 -19.472639) (xy 48.255682 -19.495297)
			(xy 48.203344 -19.510662) (xy 48.149352 -19.518422) (xy 48.122078 -19.518884) (xy 48.098202 -19.518122)
			(xy 48.08428 -19.5418) (xy 48.053519 -19.587312) (xy 48.036734 -19.609054) (xy 48.029535 -19.619303)
			(xy 48.025148 -19.643935) (xy 48.028352 -19.656044) (xy 48.036796 -19.684251) (xy 48.045847 -19.742429)
			(xy 48.046386 -19.771868) (xy 48.045869 -19.799137) (xy 48.038112 -19.853121) (xy 48.022751 -19.905451)
			(xy 48.000099 -19.955062) (xy 47.970617 -20.000945) (xy 47.934905 -20.042165) (xy 47.89369 -20.077883)
			(xy 47.847812 -20.107372) (xy 47.798204 -20.130031) (xy 47.745876 -20.1454) (xy 47.691893 -20.153165)
			(xy 47.664624 -20.15363) (xy 47.636235 -20.153138) (xy 47.580081 -20.144745) (xy 47.525791 -20.128125)
			(xy 47.474561 -20.103645) (xy 47.427524 -20.071846) (xy 47.385717 -20.033429) (xy 47.350063 -19.989243)
			(xy 47.321348 -19.940261) (xy 47.310294 -19.914108) (xy 47.305008 -19.902847) (xy 47.285982 -19.886865)
			(xy 47.273972 -19.883628) (xy 47.231226 -19.873682) (xy 47.148177 -19.845297) (xy 47.068929 -19.807579)
			(xy 47.031402 -19.784822) (xy 47.023173 -19.780068) (xy 47.00452 -19.77648) (xy 46.985838 -19.779908)
			(xy 46.977554 -19.784568) (xy 46.944421 -19.804736) (xy 46.874826 -19.838999) (xy 46.802118 -19.866035)
			(xy 46.764702 -19.876262) (xy 46.75313 -19.880067) (xy 46.735084 -19.896366) (xy 46.730158 -19.907504)
			(xy 46.71939 -19.934265) (xy 46.691 -19.984477) (xy 46.655383 -20.02985) (xy 46.61335 -20.069352)
			(xy 46.565856 -20.102087) (xy 46.513981 -20.127309) (xy 46.458903 -20.144446) (xy 46.401875 -20.153108)
			(xy 46.373034 -20.15363) (xy 46.345762 -20.153167) (xy 46.291774 -20.145408) (xy 46.239439 -20.130045)
			(xy 46.189824 -20.107389) (xy 46.143939 -20.077902) (xy 46.102717 -20.042184) (xy 46.066999 -20.000963)
			(xy 46.037512 -19.955078) (xy 46.014856 -19.905463) (xy 45.999492 -19.853128) (xy 45.991733 -19.79914)
			(xy 45.991272 -19.771868) (xy 45.991272 -19.77136) (xy 45.991626 -19.747941) (xy 45.997359 -19.701454)
			(xy 46.002702 -19.67865) (xy 46.004955 -19.666649) (xy 45.99941 -19.642912) (xy 45.992034 -19.633184)
			(xy 45.969428 -19.606102) (xy 45.92872 -19.548481) (xy 45.910754 -19.518122) (xy 45.886878 -19.518884)
			(xy 45.859611 -19.518352) (xy 45.805633 -19.510588) (xy 45.753309 -19.495222) (xy 45.703705 -19.472566)
			(xy 45.657829 -19.443081) (xy 45.616617 -19.407368) (xy 45.580906 -19.366153) (xy 45.551424 -19.320276)
			(xy 45.52877 -19.27067) (xy 45.513407 -19.218345) (xy 45.505646 -19.164367) (xy 42.916258 -19.164367)
			(xy 42.908597 -19.21765) (xy 42.893232 -19.269978) (xy 42.870577 -19.319586) (xy 42.841091 -19.365465)
			(xy 42.805377 -19.406681) (xy 42.764161 -19.442395) (xy 42.718281 -19.471879) (xy 42.668672 -19.494534)
			(xy 42.616344 -19.509898) (xy 42.562362 -19.517659) (xy 42.535094 -19.518122) (xy 42.511218 -19.51736)
			(xy 42.493363 -19.547519) (xy 42.45291 -19.604758) (xy 42.430446 -19.63166) (xy 42.423081 -19.641392)
			(xy 42.417656 -19.665153) (xy 42.420032 -19.677126) (xy 42.42548 -19.70011) (xy 42.431344 -19.74698)
			(xy 42.431716 -19.770598) (xy 42.431716 -19.771106) (xy 42.431304 -19.798379) (xy 42.42354 -19.85237)
			(xy 42.40817 -19.904707) (xy 42.385509 -19.954323) (xy 42.356016 -20.000209) (xy 42.320293 -20.04143)
			(xy 42.279067 -20.077147) (xy 42.233177 -20.106634) (xy 42.183558 -20.129289) (xy 42.131219 -20.144651)
			(xy 42.077227 -20.152408) (xy 42.049954 -20.152868) (xy 42.021141 -20.152313) (xy 41.964172 -20.143639)
			(xy 41.909151 -20.12651) (xy 41.857325 -20.101313) (xy 41.80987 -20.068621) (xy 41.767862 -20.029174)
			(xy 41.732253 -19.983867) (xy 41.70385 -19.933727) (xy 41.693084 -19.906996) (xy 41.688145 -19.895795)
			(xy 41.66995 -19.879474) (xy 41.658286 -19.875754) (xy 41.62069 -19.865522) (xy 41.547627 -19.838444)
			(xy 41.477704 -19.804059) (xy 41.444418 -19.783806) (xy 41.436157 -19.77911) (xy 41.417494 -19.775602)
			(xy 41.398831 -19.77911) (xy 41.39057 -19.783806) (xy 41.357275 -19.804043) (xy 41.287353 -19.838427)
			(xy 41.214297 -19.865522) (xy 41.176702 -19.875754) (xy 41.165063 -19.879508) (xy 41.146896 -19.895831)
			(xy 41.141904 -19.906996) (xy 41.131173 -19.933746) (xy 41.102785 -19.983906) (xy 41.067182 -20.02923)
			(xy 41.025171 -20.068689) (xy 40.977708 -20.101386) (xy 40.92587 -20.126579) (xy 40.870835 -20.143696)
			(xy 40.813852 -20.152348) (xy 40.785034 -20.152868) (xy 40.757764 -20.152367) (xy 40.703779 -20.14461)
			(xy 40.651447 -20.129248) (xy 40.601835 -20.106595) (xy 40.555951 -20.077111) (xy 40.514731 -20.041398)
			(xy 40.479013 -20.000181) (xy 40.449524 -19.954301) (xy 40.426866 -19.90469) (xy 40.411499 -19.85236)
			(xy 40.403736 -19.798376) (xy 40.403272 -19.771106) (xy 40.403272 -19.770598) (xy 40.403631 -19.74698)
			(xy 40.409496 -19.700108) (xy 40.414956 -19.677126) (xy 40.417276 -19.665154) (xy 40.411852 -19.641419)
			(xy 40.404542 -19.63166) (xy 40.382086 -19.604752) (xy 40.341634 -19.547513) (xy 40.32377 -19.51736)
			(xy 40.299894 -19.518122) (xy 40.272622 -19.517715) (xy 40.218633 -19.509952) (xy 40.166299 -19.494584)
			(xy 40.116685 -19.471925) (xy 40.0708 -19.442436) (xy 40.029578 -19.406717) (xy 39.99386 -19.365496)
			(xy 39.964372 -19.31961) (xy 39.941713 -19.269995) (xy 39.926347 -19.217661) (xy 39.918585 -19.163672)
			(xy 37.022559 -19.163672) (xy 37.014797 -19.217652) (xy 36.999431 -19.269981) (xy 36.976774 -19.319591)
			(xy 36.947287 -19.365471) (xy 36.911571 -19.406687) (xy 36.870353 -19.442401) (xy 36.824471 -19.471885)
			(xy 36.774861 -19.494539) (xy 36.722531 -19.509901) (xy 36.668547 -19.51766) (xy 36.641278 -19.518122)
			(xy 36.617402 -19.51736) (xy 36.599542 -19.547515) (xy 36.559092 -19.604757) (xy 36.53663 -19.63166)
			(xy 36.529271 -19.641397) (xy 36.523838 -19.665154) (xy 36.526216 -19.677126) (xy 36.531664 -19.70011)
			(xy 36.537528 -19.74698) (xy 36.5379 -19.770598) (xy 36.5379 -19.771106) (xy 36.537381 -19.798374)
			(xy 36.52962 -19.852354) (xy 36.514256 -19.904681) (xy 36.491601 -19.954289) (xy 36.462118 -20.000168)
			(xy 36.426407 -20.041384) (xy 36.385193 -20.077099) (xy 36.339317 -20.106586) (xy 36.289711 -20.129244)
			(xy 36.237386 -20.144613) (xy 36.183406 -20.152379) (xy 36.156138 -20.152868) (xy 36.127325 -20.152327)
			(xy 36.070355 -20.143651) (xy 36.015333 -20.126519) (xy 35.963508 -20.10132) (xy 35.916053 -20.068626)
			(xy 35.874045 -20.029178) (xy 35.838436 -19.983869) (xy 35.810033 -19.933728) (xy 35.799268 -19.906996)
			(xy 35.794286 -19.895819) (xy 35.776121 -19.879489) (xy 35.76447 -19.875754) (xy 35.726873 -19.865525)
			(xy 35.65381 -19.838446) (xy 35.583888 -19.804059) (xy 35.550602 -19.783806) (xy 35.542341 -19.77911)
			(xy 35.523678 -19.775602) (xy 35.505015 -19.77911) (xy 35.496754 -19.783806) (xy 35.463461 -19.804046)
			(xy 35.393538 -19.838429) (xy 35.320481 -19.865523) (xy 35.282886 -19.875754) (xy 35.271244 -19.879501)
			(xy 35.253079 -19.895829) (xy 35.248088 -19.906996) (xy 35.23737 -19.933752) (xy 35.208981 -19.983912)
			(xy 35.173376 -20.029236) (xy 35.131363 -20.068695) (xy 35.083898 -20.101392) (xy 35.032058 -20.126584)
			(xy 34.977021 -20.143699) (xy 34.920037 -20.152349) (xy 34.891218 -20.152868) (xy 34.863948 -20.152382)
			(xy 34.809962 -20.144622) (xy 34.75763 -20.129259) (xy 34.708017 -20.106604) (xy 34.662134 -20.077118)
			(xy 34.620914 -20.041403) (xy 34.585196 -20.000185) (xy 34.555708 -19.954304) (xy 34.53305 -19.904692)
			(xy 34.517683 -19.852362) (xy 34.50992 -19.798376) (xy 34.509456 -19.771106) (xy 34.509456 -19.770598)
			(xy 34.509815 -19.74698) (xy 34.515681 -19.700108) (xy 34.52114 -19.677126) (xy 34.523442 -19.665153)
			(xy 34.518026 -19.641422) (xy 34.510726 -19.63166) (xy 34.488269 -19.604752) (xy 34.447817 -19.547513)
			(xy 34.429954 -19.51736) (xy 34.406078 -19.518122) (xy 34.378807 -19.517714) (xy 34.32482 -19.509949)
			(xy 34.272488 -19.49458) (xy 34.222875 -19.47192) (xy 34.176992 -19.442431) (xy 34.135773 -19.406712)
			(xy 34.100056 -19.36549) (xy 34.070569 -19.319606) (xy 34.047912 -19.269992) (xy 34.032546 -19.217659)
			(xy 34.024784 -19.163671) (xy 31.434559 -19.163671) (xy 31.426797 -19.217652) (xy 31.411431 -19.269981)
			(xy 31.388774 -19.319591) (xy 31.359287 -19.365471) (xy 31.323571 -19.406687) (xy 31.282353 -19.442401)
			(xy 31.236471 -19.471885) (xy 31.186861 -19.494539) (xy 31.134531 -19.509901) (xy 31.080547 -19.51766)
			(xy 31.053278 -19.518122) (xy 31.029402 -19.51736) (xy 31.011542 -19.547515) (xy 30.971092 -19.604757)
			(xy 30.94863 -19.63166) (xy 30.941271 -19.641397) (xy 30.935838 -19.665154) (xy 30.938216 -19.677126)
			(xy 30.943664 -19.70011) (xy 30.949528 -19.74698) (xy 30.9499 -19.770598) (xy 30.9499 -19.771106)
			(xy 30.949381 -19.798374) (xy 30.94162 -19.852354) (xy 30.926256 -19.904681) (xy 30.903601 -19.954289)
			(xy 30.874118 -20.000168) (xy 30.838407 -20.041384) (xy 30.797193 -20.077099) (xy 30.751317 -20.106586)
			(xy 30.701711 -20.129244) (xy 30.649386 -20.144613) (xy 30.595406 -20.152379) (xy 30.568138 -20.152868)
			(xy 30.539325 -20.152327) (xy 30.482355 -20.143651) (xy 30.427333 -20.126519) (xy 30.375508 -20.10132)
			(xy 30.328053 -20.068626) (xy 30.286045 -20.029178) (xy 30.250436 -19.983869) (xy 30.222033 -19.933728)
			(xy 30.211268 -19.906996) (xy 30.206286 -19.895819) (xy 30.188121 -19.879489) (xy 30.17647 -19.875754)
			(xy 30.138873 -19.865525) (xy 30.06581 -19.838446) (xy 29.995888 -19.804059) (xy 29.962602 -19.783806)
			(xy 29.954341 -19.77911) (xy 29.935678 -19.775602) (xy 29.917015 -19.77911) (xy 29.908754 -19.783806)
			(xy 29.875461 -19.804046) (xy 29.805538 -19.838429) (xy 29.732481 -19.865523) (xy 29.694886 -19.875754)
			(xy 29.683244 -19.879501) (xy 29.665079 -19.895829) (xy 29.660088 -19.906996) (xy 29.64937 -19.933752)
			(xy 29.620981 -19.983912) (xy 29.585376 -20.029236) (xy 29.543363 -20.068695) (xy 29.495898 -20.101392)
			(xy 29.444058 -20.126584) (xy 29.389021 -20.143699) (xy 29.332037 -20.152349) (xy 29.303218 -20.152868)
			(xy 29.275948 -20.152382) (xy 29.221962 -20.144622) (xy 29.16963 -20.129259) (xy 29.120017 -20.106604)
			(xy 29.074134 -20.077118) (xy 29.032914 -20.041403) (xy 28.997196 -20.000185) (xy 28.967708 -19.954304)
			(xy 28.94505 -19.904692) (xy 28.929683 -19.852362) (xy 28.92192 -19.798376) (xy 28.921456 -19.771106)
			(xy 28.921456 -19.770598) (xy 28.921815 -19.74698) (xy 28.927681 -19.700108) (xy 28.93314 -19.677126)
			(xy 28.935442 -19.665153) (xy 28.930026 -19.641422) (xy 28.922726 -19.63166) (xy 28.900269 -19.604752)
			(xy 28.859817 -19.547513) (xy 28.841954 -19.51736) (xy 28.818078 -19.518122) (xy 28.790807 -19.517714)
			(xy 28.73682 -19.509949) (xy 28.684488 -19.49458) (xy 28.634875 -19.47192) (xy 28.588992 -19.442431)
			(xy 28.547773 -19.406712) (xy 28.512056 -19.36549) (xy 28.482569 -19.319606) (xy 28.459912 -19.269992)
			(xy 28.444546 -19.217659) (xy 28.436784 -19.163671) (xy 25.846559 -19.163671) (xy 25.838797 -19.217652)
			(xy 25.823431 -19.269981) (xy 25.800774 -19.319591) (xy 25.771287 -19.365471) (xy 25.735571 -19.406687)
			(xy 25.694353 -19.442401) (xy 25.648471 -19.471885) (xy 25.598861 -19.494539) (xy 25.546531 -19.509901)
			(xy 25.492547 -19.51766) (xy 25.465278 -19.518122) (xy 25.441402 -19.51736) (xy 25.423542 -19.547515)
			(xy 25.383092 -19.604757) (xy 25.36063 -19.63166) (xy 25.353271 -19.641397) (xy 25.347838 -19.665154)
			(xy 25.350216 -19.677126) (xy 25.355664 -19.70011) (xy 25.361528 -19.74698) (xy 25.3619 -19.770598)
			(xy 25.3619 -19.771106) (xy 25.361381 -19.798374) (xy 25.35362 -19.852354) (xy 25.338256 -19.904681)
			(xy 25.315601 -19.954289) (xy 25.286118 -20.000168) (xy 25.250407 -20.041384) (xy 25.209193 -20.077099)
			(xy 25.163317 -20.106586) (xy 25.113711 -20.129244) (xy 25.061386 -20.144613) (xy 25.007406 -20.152379)
			(xy 24.980138 -20.152868) (xy 24.951325 -20.152327) (xy 24.894355 -20.143651) (xy 24.839333 -20.126519)
			(xy 24.787508 -20.10132) (xy 24.740053 -20.068626) (xy 24.698045 -20.029178) (xy 24.662436 -19.983869)
			(xy 24.634033 -19.933728) (xy 24.623268 -19.906996) (xy 24.618286 -19.895819) (xy 24.600121 -19.879489)
			(xy 24.58847 -19.875754) (xy 24.550873 -19.865525) (xy 24.47781 -19.838446) (xy 24.407888 -19.804059)
			(xy 24.374602 -19.783806) (xy 24.366341 -19.77911) (xy 24.347678 -19.775602) (xy 24.329015 -19.77911)
			(xy 24.320754 -19.783806) (xy 24.287461 -19.804046) (xy 24.217538 -19.838429) (xy 24.144481 -19.865523)
			(xy 24.106886 -19.875754) (xy 24.095244 -19.879501) (xy 24.077079 -19.895829) (xy 24.072088 -19.906996)
			(xy 24.06137 -19.933752) (xy 24.032981 -19.983912) (xy 23.997376 -20.029236) (xy 23.955363 -20.068695)
			(xy 23.907898 -20.101392) (xy 23.856058 -20.126584) (xy 23.801021 -20.143699) (xy 23.744037 -20.152349)
			(xy 23.715218 -20.152868) (xy 23.687948 -20.152382) (xy 23.633962 -20.144622) (xy 23.58163 -20.129259)
			(xy 23.532017 -20.106604) (xy 23.486134 -20.077118) (xy 23.444914 -20.041403) (xy 23.409196 -20.000185)
			(xy 23.379708 -19.954304) (xy 23.35705 -19.904692) (xy 23.341683 -19.852362) (xy 23.33392 -19.798376)
			(xy 23.333456 -19.771106) (xy 23.333456 -19.770598) (xy 23.333815 -19.74698) (xy 23.339681 -19.700108)
			(xy 23.34514 -19.677126) (xy 23.347442 -19.665153) (xy 23.342026 -19.641422) (xy 23.334726 -19.63166)
			(xy 23.312269 -19.604752) (xy 23.271817 -19.547513) (xy 23.253954 -19.51736) (xy 23.230078 -19.518122)
			(xy 23.202807 -19.517714) (xy 23.14882 -19.509949) (xy 23.096488 -19.49458) (xy 23.046875 -19.47192)
			(xy 23.000992 -19.442431) (xy 22.959773 -19.406712) (xy 22.924056 -19.36549) (xy 22.894569 -19.319606)
			(xy 22.871912 -19.269992) (xy 22.856546 -19.217659) (xy 22.848784 -19.163671) (xy 20.257538 -19.163671)
			(xy 20.257538 -19.164389) (xy 20.249776 -19.218373) (xy 20.234411 -19.270703) (xy 20.211754 -19.320313)
			(xy 20.182269 -19.366194) (xy 20.146553 -19.407412) (xy 20.105336 -19.443127) (xy 20.059455 -19.472613)
			(xy 20.009845 -19.49527) (xy 19.957515 -19.510635) (xy 19.903531 -19.518397) (xy 19.876262 -19.518884)
			(xy 19.852386 -19.518122) (xy 19.834682 -19.54812) (xy 19.794615 -19.605105) (xy 19.772376 -19.631914)
			(xy 19.765041 -19.641665) (xy 19.759596 -19.66541) (xy 19.761962 -19.67738) (xy 19.767534 -19.700604)
			(xy 19.773517 -19.747988) (xy 19.7739 -19.771868) (xy 19.773346 -19.799135) (xy 19.76559 -19.853114)
			(xy 19.75023 -19.90544) (xy 19.727581 -19.955048) (xy 19.698102 -20.000927) (xy 19.662393 -20.042144)
			(xy 19.621183 -20.07786) (xy 19.575309 -20.107347) (xy 19.525706 -20.130006) (xy 19.473383 -20.145375)
			(xy 19.419405 -20.153141) (xy 19.392138 -20.15363) (xy 19.363349 -20.153074) (xy 19.306424 -20.144419)
			(xy 19.251444 -20.127314) (xy 19.199656 -20.102147) (xy 19.152235 -20.069489) (xy 19.110255 -20.030081)
			(xy 19.074668 -19.984816) (xy 19.046282 -19.93472) (xy 19.035522 -19.908012) (xy 19.030532 -19.896779)
			(xy 19.012196 -19.880462) (xy 19.00047 -19.87677) (xy 18.962686 -19.866564) (xy 18.889271 -19.839426)
			(xy 18.819022 -19.804911) (xy 18.785586 -19.784568) (xy 18.777325 -19.779872) (xy 18.758662 -19.776364)
			(xy 18.739999 -19.779872) (xy 18.731738 -19.784568) (xy 18.698607 -19.80474) (xy 18.629011 -19.839001)
			(xy 18.556303 -19.866036) (xy 18.518886 -19.876262) (xy 18.507311 -19.880059) (xy 18.489266 -19.896364)
			(xy 18.484342 -19.907504) (xy 18.473587 -19.934271) (xy 18.445195 -19.984483) (xy 18.409577 -20.029856)
			(xy 18.367542 -20.069359) (xy 18.320046 -20.102093) (xy 18.268169 -20.127314) (xy 18.213089 -20.14445)
			(xy 18.15606 -20.15311) (xy 18.127218 -20.15363) (xy 18.099946 -20.153182) (xy 18.045957 -20.145421)
			(xy 17.993622 -20.130056) (xy 17.944007 -20.107398) (xy 17.898121 -20.077909) (xy 17.8569 -20.04219)
			(xy 17.821183 -20.000967) (xy 17.791696 -19.955081) (xy 17.76904 -19.905465) (xy 17.753676 -19.853129)
			(xy 17.745917 -19.79914) (xy 17.745456 -19.771868) (xy 17.745456 -19.77136) (xy 17.745811 -19.747941)
			(xy 17.751543 -19.701454) (xy 17.756886 -19.67865) (xy 17.759143 -19.666649) (xy 17.753596 -19.642911)
			(xy 17.746218 -19.633184) (xy 17.723611 -19.606102) (xy 17.682904 -19.548482) (xy 17.664938 -19.518122)
			(xy 17.641062 -19.518884) (xy 17.613791 -19.518417) (xy 17.559804 -19.510655) (xy 17.507472 -19.495289)
			(xy 17.457858 -19.472631) (xy 17.411975 -19.443144) (xy 17.370755 -19.407427) (xy 17.335037 -19.366207)
			(xy 17.30555 -19.320323) (xy 17.282892 -19.27071) (xy 17.267526 -19.218378) (xy 17.259763 -19.164391)
			(xy 1.524 -19.164391) (xy 1.524 -20.327366) (xy 65.88506 -20.327366) (xy 65.885484 -20.289077) (xy 65.892086 -20.212783)
			(xy 65.90523 -20.13734) (xy 65.924819 -20.063309) (xy 65.937384 -20.027138) (xy 65.940051 -20.018705)
			(xy 65.94004 -20.001031) (xy 65.937384 -19.992594) (xy 65.924856 -19.956411) (xy 65.905279 -19.88238)
			(xy 65.892127 -19.806942) (xy 65.885498 -19.730654) (xy 65.88506 -19.692366) (xy 65.885582 -19.650174)
			(xy 65.893576 -19.56617) (xy 65.909488 -19.483301) (xy 65.933176 -19.402311) (xy 65.964427 -19.323927)
			(xy 66.00296 -19.248856) (xy 66.048429 -19.17777) (xy 66.074036 -19.144234) (xy 66.079883 -19.13601)
			(xy 66.085128 -19.116537) (xy 66.082515 -19.096539) (xy 66.077846 -19.087592) (xy 66.058798 -19.053767)
			(xy 66.026006 -18.983399) (xy 65.999468 -18.910441) (xy 65.979384 -18.83545) (xy 65.965909 -18.758994)
			(xy 65.959144 -18.681655) (xy 65.95872 -18.642838) (xy 65.95872 -18.642584) (xy 65.959137 -18.60148)
			(xy 65.966724 -18.519622) (xy 65.981831 -18.438814) (xy 66.00433 -18.359744) (xy 66.034029 -18.283087)
			(xy 66.070674 -18.209498) (xy 66.113953 -18.139604) (xy 66.163496 -18.074001) (xy 66.218881 -18.01325)
			(xy 66.279635 -17.957868) (xy 66.34524 -17.908328) (xy 66.415137 -17.865053) (xy 66.488728 -17.828411)
			(xy 66.565386 -17.798716) (xy 66.644456 -17.776221) (xy 66.725266 -17.761118) (xy 66.807124 -17.753535)
			(xy 66.848228 -17.753076) (xy 66.889911 -17.753577) (xy 66.972911 -17.761363) (xy 67.054819 -17.776882)
			(xy 67.134915 -17.799999) (xy 67.212496 -17.830511) (xy 67.286881 -17.868149) (xy 67.357417 -17.912584)
			(xy 67.423485 -17.963425) (xy 67.484504 -18.020226) (xy 67.53994 -18.082488) (xy 67.565016 -18.115788)
			(xy 67.56527 -18.116042) (xy 67.570757 -18.122776) (xy 67.585223 -18.132372) (xy 67.602063 -18.136587)
			(xy 67.610736 -18.136108) (xy 67.697858 -18.127726) (xy 67.706567 -18.126584) (xy 67.722478 -18.119178)
			(xy 67.734922 -18.1068) (xy 67.739006 -18.099024) (xy 67.739006 -18.098516) (xy 67.757258 -18.060702)
			(xy 67.799884 -17.988356) (xy 67.849141 -17.920351) (xy 67.90459 -17.857291) (xy 67.965736 -17.79974)
			(xy 68.032035 -17.748209) (xy 68.102897 -17.703158) (xy 68.17769 -17.664987) (xy 68.255748 -17.634037)
			(xy 68.336377 -17.610583) (xy 68.418857 -17.594835) (xy 68.502455 -17.586933) (xy 68.54444 -17.586452)
			(xy 68.5868 -17.58693) (xy 68.671136 -17.594986) (xy 68.754325 -17.611023) (xy 68.835612 -17.634895)
			(xy 68.914262 -17.666384) (xy 68.989563 -17.705208) (xy 69.060833 -17.751013) (xy 69.127426 -17.803385)
			(xy 69.18874 -17.86185) (xy 69.244218 -17.925878) (xy 69.293359 -17.99489) (xy 69.335718 -18.068261)
			(xy 69.370911 -18.145325) (xy 69.39862 -18.225386) (xy 69.401856 -18.238724) (xy 79.0321 -18.238724)
			(xy 79.032651 -18.193954) (xy 79.041664 -18.104869) (xy 79.059573 -18.017137) (xy 79.086195 -17.931647)
			(xy 79.10322 -17.890236) (xy 79.106772 -17.880641) (xy 79.106781 -17.860202) (xy 79.10322 -17.850612)
			(xy 79.086184 -17.809205) (xy 79.059551 -17.723717) (xy 79.041646 -17.635983) (xy 79.032653 -17.546895)
			(xy 79.0321 -17.502124) (xy 79.032604 -17.459763) (xy 79.040657 -17.375426) (xy 79.056691 -17.292236)
			(xy 79.080559 -17.210946) (xy 79.112047 -17.132294) (xy 79.150869 -17.056991) (xy 79.196672 -16.985719)
			(xy 79.249043 -16.919123) (xy 79.307508 -16.857808) (xy 79.371536 -16.802327) (xy 79.440548 -16.753184)
			(xy 79.513918 -16.710824) (xy 79.590983 -16.675629) (xy 79.671045 -16.64792) (xy 79.753378 -16.627946)
			(xy 79.837237 -16.615889) (xy 79.921862 -16.611858) (xy 80.006487 -16.615889) (xy 80.090346 -16.627946)
			(xy 80.172679 -16.64792) (xy 80.252741 -16.675629) (xy 80.329806 -16.710824) (xy 80.403176 -16.753184)
			(xy 80.472188 -16.802327) (xy 80.536216 -16.857808) (xy 80.594681 -16.919123) (xy 80.647052 -16.985719)
			(xy 80.692855 -17.056991) (xy 80.731677 -17.132294) (xy 80.763165 -17.210946) (xy 80.787033 -17.292236)
			(xy 80.803067 -17.375426) (xy 80.81112 -17.459763) (xy 80.811624 -17.502124) (xy 80.811054 -17.546893)
			(xy 80.802046 -17.635978) (xy 80.79821 -17.654778) (xy 131.166616 -17.654778) (xy 131.167104 -17.627509)
			(xy 131.174868 -17.573527) (xy 131.190235 -17.521199) (xy 131.212892 -17.47159) (xy 131.242378 -17.42571)
			(xy 131.278093 -17.384493) (xy 131.31931 -17.348778) (xy 131.36519 -17.319292) (xy 131.414799 -17.296635)
			(xy 131.467127 -17.281268) (xy 131.521109 -17.273504) (xy 131.548378 -17.273016) (xy 131.57807 -17.27357)
			(xy 131.636735 -17.282781) (xy 131.693264 -17.300968) (xy 131.746295 -17.327693) (xy 131.794545 -17.36231)
			(xy 131.816094 -17.382744) (xy 131.825442 -17.391087) (xy 131.849416 -17.398273) (xy 131.861814 -17.39646)
			(xy 131.899627 -17.389225) (xy 131.976226 -17.381461) (xy 132.014722 -17.380966) (xy 132.057412 -17.381557)
			(xy 132.142256 -17.391122) (xy 132.225504 -17.410087) (xy 132.306119 -17.438214) (xy 132.383095 -17.475153)
			(xy 132.419598 -17.497298) (xy 132.427859 -17.501994) (xy 132.446522 -17.505502) (xy 132.465185 -17.501994)
			(xy 132.473446 -17.497298) (xy 132.509939 -17.475137) (xy 132.586915 -17.438193) (xy 132.667532 -17.410068)
			(xy 132.750784 -17.391115) (xy 132.835631 -17.381568) (xy 132.878322 -17.380966) (xy 132.87883 -17.380966)
			(xy 132.917784 -17.381496) (xy 132.995278 -17.389516) (xy 133.033516 -17.396968) (xy 133.045976 -17.398874)
			(xy 133.0701 -17.391664) (xy 133.07949 -17.383252) (xy 133.101103 -17.36275) (xy 133.14947 -17.327979)
			(xy 133.202644 -17.301131) (xy 133.25934 -17.282855) (xy 133.318184 -17.273596) (xy 133.347968 -17.273016)
			(xy 133.348222 -17.273016) (xy 133.375491 -17.273504) (xy 133.429473 -17.281268) (xy 133.481801 -17.296635)
			(xy 133.53141 -17.319292) (xy 133.57729 -17.348778) (xy 133.618507 -17.384493) (xy 133.654222 -17.42571)
			(xy 133.683708 -17.47159) (xy 133.706365 -17.521199) (xy 133.721732 -17.573527) (xy 133.729496 -17.627509)
			(xy 133.729984 -17.654778) (xy 133.72945 -17.682933) (xy 133.721128 -17.738625) (xy 133.70472 -17.792492)
			(xy 133.680582 -17.843366) (xy 133.649235 -17.890145) (xy 133.63067 -17.911318) (xy 133.622671 -17.921122)
			(xy 133.616543 -17.945639) (xy 133.618986 -17.958054) (xy 133.629794 -18.003839) (xy 133.641389 -18.097198)
			(xy 133.6421 -18.144236) (xy 133.6421 -18.144744) (xy 133.641757 -18.171946) (xy 137.033822 -18.171946)
			(xy 137.033822 -18.117454) (xy 137.041577 -18.063516) (xy 137.056928 -18.01123) (xy 137.079564 -17.961661)
			(xy 137.109023 -17.915818) (xy 137.144706 -17.874633) (xy 137.185887 -17.838946) (xy 137.231728 -17.809482)
			(xy 137.281294 -17.786841) (xy 137.333578 -17.771485) (xy 137.387516 -17.763725) (xy 137.414762 -17.763236)
			(xy 138.278362 -17.763236) (xy 138.30562 -17.763608) (xy 138.359581 -17.771362) (xy 138.41189 -17.786716)
			(xy 138.46148 -17.809359) (xy 138.507344 -17.83883) (xy 138.548546 -17.874528) (xy 138.584247 -17.915726)
			(xy 138.613722 -17.961586) (xy 138.63637 -18.011175) (xy 138.65173 -18.063482) (xy 138.659489 -18.117442)
			(xy 138.659489 -18.17195) (xy 140.633699 -18.17195) (xy 140.633699 -18.11745) (xy 140.641455 -18.063505)
			(xy 140.65681 -18.011213) (xy 140.67945 -17.961638) (xy 140.708915 -17.91579) (xy 140.744605 -17.874602)
			(xy 140.785793 -17.838913) (xy 140.831642 -17.809448) (xy 140.881217 -17.786808) (xy 140.933509 -17.771455)
			(xy 140.987454 -17.763699) (xy 141.014704 -17.763236) (xy 141.878304 -17.763236) (xy 141.905558 -17.763634)
			(xy 141.959512 -17.771392) (xy 142.011812 -17.786749) (xy 142.061394 -17.809393) (xy 142.10725 -17.838863)
			(xy 142.148444 -17.874559) (xy 142.184139 -17.915754) (xy 142.213609 -17.961609) (xy 142.236252 -18.011192)
			(xy 142.251609 -18.063492) (xy 142.259366 -18.117446) (xy 142.259366 -18.171954) (xy 142.251609 -18.225908)
			(xy 142.236252 -18.278208) (xy 142.213609 -18.327791) (xy 142.184139 -18.373646) (xy 142.148444 -18.414841)
			(xy 142.10725 -18.450537) (xy 142.061394 -18.480007) (xy 142.011812 -18.502651) (xy 141.959512 -18.518008)
			(xy 141.905558 -18.525766) (xy 141.878304 -18.526252) (xy 141.014704 -18.526252) (xy 140.987454 -18.525701)
			(xy 140.933509 -18.517945) (xy 140.881217 -18.502592) (xy 140.831642 -18.479952) (xy 140.785793 -18.450487)
			(xy 140.744605 -18.414798) (xy 140.708915 -18.37361) (xy 140.67945 -18.327762) (xy 140.65681 -18.278187)
			(xy 140.641455 -18.225895) (xy 140.633699 -18.17195) (xy 138.659489 -18.17195) (xy 138.659489 -18.171958)
			(xy 138.65173 -18.225918) (xy 138.63637 -18.278225) (xy 138.613722 -18.327814) (xy 138.584247 -18.373674)
			(xy 138.548546 -18.414872) (xy 138.507344 -18.45057) (xy 138.46148 -18.480041) (xy 138.41189 -18.502684)
			(xy 138.359581 -18.518038) (xy 138.30562 -18.525792) (xy 138.278362 -18.526252) (xy 137.414762 -18.526252)
			(xy 137.387516 -18.525675) (xy 137.333578 -18.517915) (xy 137.281294 -18.502559) (xy 137.231728 -18.479918)
			(xy 137.185887 -18.450454) (xy 137.144706 -18.414767) (xy 137.109023 -18.373582) (xy 137.079564 -18.327739)
			(xy 137.056928 -18.27817) (xy 137.041577 -18.225884) (xy 137.033822 -18.171946) (xy 133.641757 -18.171946)
			(xy 133.641596 -18.184745) (xy 133.63323 -18.264307) (xy 133.616593 -18.342559) (xy 133.591868 -18.418644)
			(xy 133.559326 -18.491727) (xy 133.519324 -18.561009) (xy 133.472299 -18.625731) (xy 133.418766 -18.685182)
			(xy 133.359313 -18.738713) (xy 133.294591 -18.785736) (xy 133.225308 -18.825736) (xy 133.152223 -18.858276)
			(xy 133.076138 -18.882999) (xy 132.997885 -18.899633) (xy 132.918323 -18.907997) (xy 132.878322 -18.908522)
			(xy 132.835633 -18.907897) (xy 132.750791 -18.898338) (xy 132.667544 -18.87938) (xy 132.586928 -18.851261)
			(xy 132.50995 -18.81433) (xy 132.473446 -18.79219) (xy 132.465185 -18.787494) (xy 132.446522 -18.783986)
			(xy 132.427859 -18.787494) (xy 132.419598 -18.79219) (xy 132.383093 -18.814332) (xy 132.306121 -18.851279)
			(xy 132.225507 -18.879408) (xy 132.142257 -18.898366) (xy 132.057412 -18.907917) (xy 132.014722 -18.908522)
			(xy 131.974723 -18.907934) (xy 131.895164 -18.899574) (xy 131.816915 -18.882944) (xy 131.740832 -18.858227)
			(xy 131.66775 -18.825691) (xy 131.598469 -18.785696) (xy 131.533748 -18.738677) (xy 131.474296 -18.685151)
			(xy 131.420765 -18.625704) (xy 131.37374 -18.560987) (xy 131.333739 -18.491709) (xy 131.301197 -18.41863)
			(xy 131.276473 -18.342549) (xy 131.259836 -18.264301) (xy 131.25147 -18.184743) (xy 131.250944 -18.144744)
			(xy 131.250944 -18.144236) (xy 131.251717 -18.096477) (xy 131.263688 -18.00171) (xy 131.27482 -17.95526)
			(xy 131.277326 -17.942936) (xy 131.271314 -17.918546) (xy 131.26339 -17.908778) (xy 131.24526 -17.887693)
			(xy 131.214672 -17.841254) (xy 131.191147 -17.790868) (xy 131.175183 -17.737601) (xy 131.167117 -17.682582)
			(xy 131.166616 -17.654778) (xy 80.79821 -17.654778) (xy 80.784143 -17.723709) (xy 80.757526 -17.809201)
			(xy 80.740504 -17.850612) (xy 80.736924 -17.860198) (xy 80.736933 -17.880645) (xy 80.740504 -17.890236)
			(xy 80.757551 -17.931638) (xy 80.784182 -18.017129) (xy 80.802084 -18.104863) (xy 80.811074 -18.193953)
			(xy 80.811624 -18.238724) (xy 80.81112 -18.281085) (xy 80.803067 -18.365422) (xy 80.787033 -18.448612)
			(xy 80.763165 -18.529902) (xy 80.731677 -18.608554) (xy 80.692855 -18.683857) (xy 80.647052 -18.755129)
			(xy 80.594681 -18.821725) (xy 80.536216 -18.88304) (xy 80.472188 -18.938521) (xy 80.403176 -18.987664)
			(xy 80.329806 -19.030024) (xy 80.252741 -19.065219) (xy 80.172679 -19.092928) (xy 80.090346 -19.112902)
			(xy 80.006487 -19.124959) (xy 79.921862 -19.128991) (xy 79.837237 -19.124959) (xy 79.753378 -19.112902)
			(xy 79.671045 -19.092928) (xy 79.590983 -19.065219) (xy 79.513918 -19.030024) (xy 79.440548 -18.987664)
			(xy 79.371536 -18.938521) (xy 79.307508 -18.88304) (xy 79.249043 -18.821725) (xy 79.196672 -18.755129)
			(xy 79.150869 -18.683857) (xy 79.112047 -18.608554) (xy 79.080559 -18.529902) (xy 79.056691 -18.448612)
			(xy 79.040657 -18.365422) (xy 79.032604 -18.281085) (xy 79.0321 -18.238724) (xy 69.401856 -18.238724)
			(xy 69.418593 -18.307718) (xy 69.430649 -18.391576) (xy 69.434681 -18.4762) (xy 69.430649 -18.560824)
			(xy 69.418593 -18.644682) (xy 69.39862 -18.727014) (xy 69.370911 -18.807075) (xy 69.335718 -18.884139)
			(xy 69.293359 -18.95751) (xy 69.244218 -19.026522) (xy 69.18874 -19.09055) (xy 69.127426 -19.149015)
			(xy 69.060833 -19.201387) (xy 68.989563 -19.247192) (xy 68.914262 -19.286016) (xy 68.835612 -19.317505)
			(xy 68.754325 -19.341377) (xy 68.671136 -19.357414) (xy 68.5868 -19.36547) (xy 68.54444 -19.365976)
			(xy 68.502753 -19.365468) (xy 68.419745 -19.357644) (xy 68.337834 -19.342089) (xy 68.257737 -19.31894)
			(xy 68.180157 -19.288398) (xy 68.105774 -19.250734) (xy 68.035242 -19.206275) (xy 67.969177 -19.155414)
			(xy 67.90816 -19.098595) (xy 67.852727 -19.036317) (xy 67.827652 -19.00301) (xy 67.827398 -19.002756)
			(xy 67.821873 -18.996058) (xy 67.807425 -18.986454) (xy 67.790601 -18.982223) (xy 67.781932 -18.98269)
			(xy 67.69481 -18.991072) (xy 67.686098 -18.992195) (xy 67.670187 -18.999611) (xy 67.657745 -19.011995)
			(xy 67.653662 -19.019774) (xy 67.653662 -19.020282) (xy 67.63179 -19.065383) (xy 67.579339 -19.150805)
			(xy 67.549014 -19.190716) (xy 67.543272 -19.198996) (xy 67.538026 -19.218428) (xy 67.540615 -19.238388)
			(xy 67.545204 -19.247358) (xy 67.564269 -19.281203) (xy 67.597117 -19.351604) (xy 67.623706 -19.424598)
			(xy 67.643834 -19.499632) (xy 67.657349 -19.576134) (xy 67.664146 -19.653523) (xy 67.664584 -19.692366)
			(xy 67.664167 -19.730656) (xy 67.657563 -19.806949) (xy 67.644416 -19.882392) (xy 67.624826 -19.956423)
			(xy 67.61226 -19.992594) (xy 67.609626 -20.001035) (xy 67.609615 -20.018702) (xy 67.61226 -20.027138)
			(xy 67.624799 -20.063317) (xy 67.644373 -20.13735) (xy 67.653158 -20.187755) (xy 138.765443 -20.187755)
			(xy 138.765443 -20.133245) (xy 138.773201 -20.079289) (xy 138.788559 -20.026987) (xy 138.811205 -19.977403)
			(xy 138.840677 -19.931547) (xy 138.876376 -19.890352) (xy 138.917574 -19.854657) (xy 138.963433 -19.825189)
			(xy 139.013019 -19.802547) (xy 139.065322 -19.787194) (xy 139.119279 -19.779441) (xy 139.146534 -19.77898)
			(xy 140.137134 -19.77898) (xy 140.164383 -19.779493) (xy 140.218325 -19.787253) (xy 140.270614 -19.80261)
			(xy 140.320185 -19.825253) (xy 140.36603 -19.854719) (xy 140.407215 -19.890409) (xy 140.442901 -19.931597)
			(xy 140.449617 -19.942048) (xy 175.988472 -19.942048) (xy 175.988976 -19.899687) (xy 175.997029 -19.81535)
			(xy 176.013063 -19.73216) (xy 176.036931 -19.65087) (xy 176.068419 -19.572218) (xy 176.107241 -19.496915)
			(xy 176.153044 -19.425643) (xy 176.205415 -19.359047) (xy 176.26388 -19.297732) (xy 176.327908 -19.242251)
			(xy 176.39692 -19.193108) (xy 176.47029 -19.150748) (xy 176.547355 -19.115553) (xy 176.627417 -19.087844)
			(xy 176.70975 -19.06787) (xy 176.793609 -19.055813) (xy 176.878234 -19.051782) (xy 176.962859 -19.055813)
			(xy 177.046718 -19.06787) (xy 177.129051 -19.087844) (xy 177.209113 -19.115553) (xy 177.286178 -19.150748)
			(xy 177.359548 -19.193108) (xy 177.42856 -19.242251) (xy 177.492588 -19.297732) (xy 177.551053 -19.359047)
			(xy 177.603424 -19.425643) (xy 177.649227 -19.496915) (xy 177.688049 -19.572218) (xy 177.719537 -19.65087)
			(xy 177.743405 -19.73216) (xy 177.759439 -19.81535) (xy 177.767492 -19.899687) (xy 177.767996 -19.942048)
			(xy 177.767398 -19.98792) (xy 177.757891 -20.079169) (xy 177.739034 -20.168954) (xy 177.725578 -20.212812)
			(xy 177.722752 -20.223379) (xy 177.72523 -20.245087) (xy 177.730404 -20.254722) (xy 177.750836 -20.289402)
			(xy 177.786035 -20.361795) (xy 177.814552 -20.437071) (xy 177.836153 -20.514616) (xy 177.850661 -20.593794)
			(xy 177.857958 -20.67396) (xy 177.85842 -20.714208) (xy 177.85842 -20.715224) (xy 177.857839 -20.760561)
			(xy 177.84856 -20.850758) (xy 177.830152 -20.939544) (xy 177.817018 -20.98294) (xy 177.81462 -20.991841)
			(xy 177.815621 -21.010233) (xy 177.823067 -21.02708) (xy 177.835994 -21.040201) (xy 177.844196 -21.044408)
			(xy 177.8824 -21.062505) (xy 177.955518 -21.104946) (xy 178.024281 -21.15413) (xy 178.088069 -21.209614)
			(xy 178.146306 -21.270898) (xy 178.198469 -21.337429) (xy 178.244087 -21.408608) (xy 178.282748 -21.483792)
			(xy 178.314103 -21.562305) (xy 178.337871 -21.643437) (xy 178.353837 -21.726458) (xy 178.361856 -21.810619)
			(xy 178.362356 -21.85289) (xy 178.361892 -21.894005) (xy 178.354306 -21.975884) (xy 178.339197 -22.056714)
			(xy 178.316694 -22.135805) (xy 178.28699 -22.212482) (xy 178.250337 -22.286091) (xy 178.207049 -22.356005)
			(xy 178.157495 -22.421626) (xy 178.102097 -22.482394) (xy 178.041329 -22.537792) (xy 177.975708 -22.587347)
			(xy 177.905795 -22.630635) (xy 177.832186 -22.667288) (xy 177.755509 -22.696993) (xy 177.676418 -22.719496)
			(xy 177.595588 -22.734605) (xy 177.513709 -22.742192) (xy 177.472594 -22.742652) (xy 177.429071 -22.742084)
			(xy 177.34244 -22.73358) (xy 177.257055 -22.716655) (xy 177.173731 -22.69147) (xy 177.093266 -22.658267)
			(xy 177.016429 -22.617362) (xy 176.943956 -22.569146) (xy 176.876538 -22.514083) (xy 176.814822 -22.452697)
			(xy 176.759398 -22.385575) (xy 176.710795 -22.313361) (xy 176.669479 -22.236745) (xy 176.652174 -22.196806)
			(xy 176.647921 -22.187866) (xy 176.633936 -22.17388) (xy 176.624996 -22.169628) (xy 176.585068 -22.152314)
			(xy 176.508472 -22.110985) (xy 176.436278 -22.062372) (xy 176.369178 -22.006941) (xy 176.307813 -21.945221)
			(xy 176.252769 -21.877802) (xy 176.204574 -21.80533) (xy 176.163687 -21.728496) (xy 176.1305 -21.648037)
			(xy 176.105331 -21.564721) (xy 176.088419 -21.479345) (xy 176.079928 -21.392725) (xy 176.079404 -21.349208)
			(xy 176.079404 -21.348446) (xy 176.079814 -21.310226) (xy 176.086378 -21.234067) (xy 176.099462 -21.158755)
			(xy 176.118968 -21.084845) (xy 176.131474 -21.048726) (xy 176.134055 -21.040409) (xy 176.134058 -21.023006)
			(xy 176.131474 -21.01469) (xy 176.118957 -20.978475) (xy 176.099434 -20.904375) (xy 176.086349 -20.828871)
			(xy 176.079799 -20.752523) (xy 176.079404 -20.714208) (xy 176.07999 -20.668344) (xy 176.089425 -20.577104)
			(xy 176.108186 -20.487316) (xy 176.121568 -20.443444) (xy 176.124428 -20.432883) (xy 176.121929 -20.411168)
			(xy 176.116742 -20.401534) (xy 176.096312 -20.366847) (xy 176.06107 -20.294464) (xy 176.032509 -20.219194)
			(xy 176.010862 -20.141652) (xy 175.996306 -20.062472) (xy 175.988959 -19.982301) (xy 175.988472 -19.942048)
			(xy 140.449617 -19.942048) (xy 140.472364 -19.977445) (xy 140.495002 -20.027018) (xy 140.510354 -20.079308)
			(xy 140.51811 -20.133251) (xy 140.51811 -20.187749) (xy 140.510354 -20.241692) (xy 140.495002 -20.293982)
			(xy 140.472364 -20.343555) (xy 140.442901 -20.389403) (xy 140.407215 -20.430591) (xy 140.36603 -20.466281)
			(xy 140.320185 -20.495747) (xy 140.270614 -20.51839) (xy 140.218325 -20.533747) (xy 140.164383 -20.541507)
			(xy 140.137134 -20.541996) (xy 139.146534 -20.541996) (xy 139.119279 -20.541559) (xy 139.065322 -20.533806)
			(xy 139.013019 -20.518453) (xy 138.963433 -20.495811) (xy 138.917574 -20.466343) (xy 138.876376 -20.430648)
			(xy 138.840677 -20.389453) (xy 138.811205 -20.343597) (xy 138.788559 -20.294013) (xy 138.773201 -20.241711)
			(xy 138.765443 -20.187755) (xy 67.653158 -20.187755) (xy 67.657521 -20.212789) (xy 67.664147 -20.289078)
			(xy 67.664584 -20.327366) (xy 67.66408 -20.369727) (xy 67.656027 -20.454064) (xy 67.639993 -20.537254)
			(xy 67.616125 -20.618544) (xy 67.584637 -20.697196) (xy 67.545815 -20.772499) (xy 67.500012 -20.843771)
			(xy 67.447641 -20.910367) (xy 67.389176 -20.971682) (xy 67.325148 -21.027163) (xy 67.256136 -21.076306)
			(xy 67.182766 -21.118666) (xy 67.105701 -21.153861) (xy 67.025639 -21.18157) (xy 66.943306 -21.201544)
			(xy 66.859447 -21.213601) (xy 66.774822 -21.217633) (xy 66.690197 -21.213601) (xy 66.606338 -21.201544)
			(xy 66.524005 -21.18157) (xy 66.443943 -21.153861) (xy 66.366878 -21.118666) (xy 66.293508 -21.076306)
			(xy 66.224496 -21.027163) (xy 66.160468 -20.971682) (xy 66.102003 -20.910367) (xy 66.049632 -20.843771)
			(xy 66.003829 -20.772499) (xy 65.965007 -20.697196) (xy 65.933519 -20.618544) (xy 65.909651 -20.537254)
			(xy 65.893617 -20.454064) (xy 65.885564 -20.369727) (xy 65.88506 -20.327366) (xy 1.524 -20.327366)
			(xy 1.524 -22.309271) (xy 65.993006 -22.309271) (xy 65.993006 -22.224549) (xy 66.001059 -22.140212)
			(xy 66.017093 -22.057022) (xy 66.040961 -21.975732) (xy 66.072449 -21.89708) (xy 66.111271 -21.821777)
			(xy 66.157074 -21.750505) (xy 66.209445 -21.683909) (xy 66.26791 -21.622594) (xy 66.331938 -21.567113)
			(xy 66.40095 -21.51797) (xy 66.47432 -21.47561) (xy 66.551385 -21.440415) (xy 66.631447 -21.412706)
			(xy 66.71378 -21.392732) (xy 66.797639 -21.380675) (xy 66.882264 -21.376644) (xy 66.966889 -21.380675)
			(xy 67.050748 -21.392732) (xy 67.133081 -21.412706) (xy 67.213143 -21.440415) (xy 67.290208 -21.47561)
			(xy 67.363578 -21.51797) (xy 67.43259 -21.567113) (xy 67.496618 -21.622594) (xy 67.555083 -21.683909)
			(xy 67.607454 -21.750505) (xy 67.653257 -21.821777) (xy 67.692079 -21.89708) (xy 67.723567 -21.975732)
			(xy 67.747435 -22.057022) (xy 67.755872 -22.100794) (xy 113.944146 -22.100794) (xy 113.944596 -22.073522)
			(xy 113.952359 -22.019535) (xy 113.967727 -21.967201) (xy 113.990385 -21.917588) (xy 114.019874 -21.871704)
			(xy 114.055593 -21.830483) (xy 114.096815 -21.794766) (xy 114.1427 -21.765279) (xy 114.192314 -21.742622)
			(xy 114.244648 -21.727256) (xy 114.298636 -21.719495) (xy 114.325908 -21.719032) (xy 114.326162 -21.719032)
			(xy 114.351127 -21.719444) (xy 114.400629 -21.725969) (xy 114.448859 -21.738886) (xy 114.494995 -21.757977)
			(xy 114.538252 -21.782914) (xy 114.558318 -21.797772) (xy 114.568495 -21.804638) (xy 114.592638 -21.808884)
			(xy 114.604546 -21.8059) (xy 114.641649 -21.794704) (xy 114.717549 -21.779017) (xy 114.794648 -21.771102)
			(xy 114.8334 -21.770594) (xy 114.833908 -21.770594) (xy 114.876509 -21.771197) (xy 114.96118 -21.780683)
			(xy 115.044267 -21.799546) (xy 115.124734 -21.827551) (xy 115.201578 -21.86435) (xy 115.238022 -21.886418)
			(xy 115.246278 -21.891132) (xy 115.264946 -21.894659) (xy 115.283614 -21.891132) (xy 115.29187 -21.886418)
			(xy 115.328407 -21.86415) (xy 115.405501 -21.82702) (xy 115.486268 -21.798759) (xy 115.569692 -21.779723)
			(xy 115.654724 -21.77015) (xy 115.697508 -21.769578) (xy 115.697762 -21.769578) (xy 115.736732 -21.770084)
			(xy 115.814264 -21.778043) (xy 115.890583 -21.793853) (xy 115.927886 -21.805138) (xy 115.93973 -21.808095)
			(xy 115.963735 -21.803834) (xy 115.97386 -21.79701) (xy 115.998952 -21.778645) (xy 116.053876 -21.749498)
			(xy 116.1128 -21.729646) (xy 116.174164 -21.719617) (xy 116.205254 -21.719032) (xy 116.205508 -21.719032)
			(xy 116.232777 -21.719517) (xy 116.286761 -21.72728) (xy 116.33909 -21.742646) (xy 116.3887 -21.765302)
			(xy 116.43458 -21.794788) (xy 116.475798 -21.830504) (xy 116.511513 -21.871721) (xy 116.540999 -21.917602)
			(xy 116.563655 -21.967212) (xy 116.579021 -22.019541) (xy 116.586783 -22.073525) (xy 116.58727 -22.100794)
			(xy 116.586815 -22.126656) (xy 116.579834 -22.177906) (xy 116.565987 -22.227741) (xy 116.545527 -22.275245)
			(xy 116.518831 -22.319547) (xy 116.486389 -22.359831) (xy 116.46789 -22.377908) (xy 116.459429 -22.386861)
			(xy 116.451334 -22.410085) (xy 116.452396 -22.422358) (xy 116.456178 -22.449761) (xy 116.460249 -22.504933)
			(xy 116.460524 -22.532594) (xy 116.460132 -22.569503) (xy 116.453003 -22.642975) (xy 116.438812 -22.715415)
			(xy 116.417691 -22.786146) (xy 116.389838 -22.854507) (xy 116.355512 -22.919858) (xy 116.315035 -22.981588)
			(xy 116.28659 -23.016972) (xy 135.942324 -23.016972) (xy 135.942784 -22.97749) (xy 135.950922 -22.898947)
			(xy 135.967131 -22.821665) (xy 135.991235 -22.746471) (xy 136.022978 -22.674168) (xy 136.062019 -22.605531)
			(xy 136.107941 -22.541294) (xy 136.160253 -22.482144) (xy 136.218395 -22.428714) (xy 136.281744 -22.381576)
			(xy 136.349625 -22.341233) (xy 136.421309 -22.308118) (xy 136.49603 -22.282585) (xy 136.534398 -22.27326)
			(xy 136.543557 -22.270706) (xy 136.559251 -22.260005) (xy 136.569976 -22.244325) (xy 136.572498 -22.23516)
			(xy 136.581857 -22.196805) (xy 136.60741 -22.1221) (xy 136.640539 -22.050432) (xy 136.68089 -21.982567)
			(xy 136.728032 -21.919231) (xy 136.781461 -21.861101) (xy 136.840606 -21.808797) (xy 136.904834 -21.762879)
			(xy 136.97346 -21.723837) (xy 137.04575 -21.692089) (xy 137.120932 -21.667973) (xy 137.198201 -21.651749)
			(xy 137.276733 -21.643588) (xy 137.31621 -21.643086) (xy 137.356684 -21.643608) (xy 137.437176 -21.652188)
			(xy 137.516308 -21.669239) (xy 137.59319 -21.694571) (xy 137.666959 -21.727899) (xy 137.736785 -21.768848)
			(xy 137.801885 -21.816958) (xy 137.861527 -21.871688) (xy 137.915041 -21.932424) (xy 137.961825 -21.998483)
			(xy 138.001354 -22.069123) (xy 138.017758 -22.106128) (xy 138.02342 -22.117541) (xy 138.043436 -22.133258)
			(xy 138.055858 -22.1361) (xy 138.082217 -22.140996) (xy 138.133316 -22.157218) (xy 138.181642 -22.180431)
			(xy 138.226245 -22.210177) (xy 138.266247 -22.245872) (xy 138.30086 -22.286813) (xy 138.329405 -22.332194)
			(xy 138.351319 -22.381123) (xy 138.366171 -22.432637) (xy 138.373668 -22.485722) (xy 138.37412 -22.512528)
			(xy 138.373724 -22.539802) (xy 138.365957 -22.593793) (xy 138.350585 -22.64613) (xy 138.327922 -22.695746)
			(xy 138.298427 -22.741631) (xy 138.262702 -22.782852) (xy 138.221475 -22.818569) (xy 138.175584 -22.848055)
			(xy 138.125964 -22.87071) (xy 138.073625 -22.886072) (xy 138.019632 -22.893829) (xy 137.992358 -22.89429)
			(xy 137.991596 -22.89429) (xy 137.97796 -22.894197) (xy 137.950756 -22.892287) (xy 137.93724 -22.89048)
			(xy 137.924556 -22.889324) (xy 137.900692 -22.898147) (xy 137.891774 -22.907244) (xy 137.865133 -22.937054)
			(xy 137.806596 -22.991514) (xy 137.742689 -23.039561) (xy 137.674112 -23.080668) (xy 137.601617 -23.114387)
			(xy 137.525995 -23.140346) (xy 137.487152 -23.149814) (xy 137.477967 -23.152291) (xy 137.462272 -23.163026)
			(xy 137.451561 -23.178736) (xy 137.449052 -23.187914) (xy 137.439539 -23.226989) (xy 137.413339 -23.30303)
			(xy 137.379296 -23.375898) (xy 137.337786 -23.444786) (xy 137.28927 -23.508932) (xy 137.234283 -23.567627)
			(xy 137.205055 -23.593552) (xy 189.619128 -23.593552) (xy 189.619128 -23.593298) (xy 189.619711 -23.54856)
			(xy 189.628722 -23.459539) (xy 189.646623 -23.371871) (xy 189.673232 -23.286444) (xy 189.690248 -23.245064)
			(xy 189.69384 -23.235481) (xy 189.693822 -23.215031) (xy 189.690248 -23.20544) (xy 189.673222 -23.164064)
			(xy 189.646604 -23.078637) (xy 189.6287 -22.990968) (xy 189.619692 -22.901945) (xy 189.619128 -22.857206)
			(xy 189.619128 -22.856952) (xy 189.619632 -22.814604) (xy 189.627683 -22.73029) (xy 189.643712 -22.647124)
			(xy 189.667573 -22.565857) (xy 189.699052 -22.487227) (xy 189.737863 -22.411946) (xy 189.783653 -22.340694)
			(xy 189.836009 -22.274118) (xy 189.894457 -22.21282) (xy 189.958467 -22.157355) (xy 190.027459 -22.108226)
			(xy 190.100809 -22.065877) (xy 190.177852 -22.030693) (xy 190.257891 -22.002991) (xy 190.3402 -21.983023)
			(xy 190.424035 -21.97097) (xy 190.508636 -21.96694) (xy 190.593237 -21.97097) (xy 190.677072 -21.983023)
			(xy 190.759381 -22.002991) (xy 190.83942 -22.030693) (xy 190.916463 -22.065877) (xy 190.989813 -22.108226)
			(xy 191.058805 -22.157355) (xy 191.122815 -22.21282) (xy 191.181263 -22.274118) (xy 191.233619 -22.340694)
			(xy 191.279409 -22.411946) (xy 191.31822 -22.487227) (xy 191.349699 -22.565857) (xy 191.37356 -22.647124)
			(xy 191.389589 -22.73029) (xy 191.39764 -22.814604) (xy 191.398144 -22.856952) (xy 191.398144 -22.857206)
			(xy 191.397557 -22.901944) (xy 191.388547 -22.990965) (xy 191.370647 -23.078632) (xy 191.344039 -23.16406)
			(xy 191.327024 -23.20544) (xy 191.323489 -23.215039) (xy 191.323471 -23.235473) (xy 191.327024 -23.245064)
			(xy 191.344055 -23.286438) (xy 191.370671 -23.371866) (xy 191.388573 -23.459535) (xy 191.39758 -23.548559)
			(xy 191.398144 -23.593298) (xy 191.398144 -23.593552) (xy 191.39764 -23.6359) (xy 191.389589 -23.720214)
			(xy 191.37356 -23.80338) (xy 191.349699 -23.884647) (xy 191.31822 -23.963277) (xy 191.279409 -24.038558)
			(xy 191.233619 -24.10981) (xy 191.181263 -24.176386) (xy 191.122815 -24.237684) (xy 191.058805 -24.293149)
			(xy 190.989813 -24.342278) (xy 190.916463 -24.384627) (xy 190.83942 -24.419811) (xy 190.759381 -24.447513)
			(xy 190.677072 -24.467481) (xy 190.593237 -24.479534) (xy 190.508636 -24.483565) (xy 190.424035 -24.479534)
			(xy 190.3402 -24.467481) (xy 190.257891 -24.447513) (xy 190.177852 -24.419811) (xy 190.100809 -24.384627)
			(xy 190.027459 -24.342278) (xy 189.958467 -24.293149) (xy 189.894457 -24.237684) (xy 189.836009 -24.176386)
			(xy 189.783653 -24.10981) (xy 189.737863 -24.038558) (xy 189.699052 -23.963277) (xy 189.667573 -23.884647)
			(xy 189.643712 -23.80338) (xy 189.627683 -23.720214) (xy 189.619632 -23.6359) (xy 189.619128 -23.593552)
			(xy 137.205055 -23.593552) (xy 137.204196 -23.594314) (xy 137.19793 -23.600084) (xy 137.189428 -23.614837)
			(xy 137.186249 -23.631565) (xy 137.187178 -23.640034) (xy 137.189076 -23.653798) (xy 137.191108 -23.681512)
			(xy 137.191242 -23.695406) (xy 137.190804 -23.722678) (xy 137.183041 -23.776667) (xy 137.167673 -23.829001)
			(xy 137.145013 -23.878616) (xy 137.115523 -23.9245) (xy 137.079803 -23.965721) (xy 137.03858 -24.001438)
			(xy 136.992693 -24.030925) (xy 136.943077 -24.053582) (xy 136.890741 -24.068946) (xy 136.836752 -24.076706)
			(xy 136.80948 -24.077168) (xy 136.78252 -24.076708) (xy 136.729138 -24.069118) (xy 136.677354 -24.054093)
			(xy 136.628199 -24.031932) (xy 136.582652 -24.003074) (xy 136.541618 -23.968095) (xy 136.505914 -23.927691)
			(xy 136.47625 -23.882664) (xy 136.453217 -23.833912) (xy 136.437272 -23.782404) (xy 136.432544 -23.755858)
			(xy 136.430855 -23.747498) (xy 136.422804 -23.732476) (xy 136.410262 -23.720935) (xy 136.402572 -23.71725)
			(xy 136.365758 -23.700764) (xy 136.295503 -23.661125) (xy 136.229822 -23.614294) (xy 136.169448 -23.560795)
			(xy 136.115056 -23.501225) (xy 136.067252 -23.436249) (xy 136.02657 -23.366592) (xy 135.993464 -23.293032)
			(xy 135.968304 -23.21639) (xy 135.951371 -23.137521) (xy 135.942852 -23.057305) (xy 135.942324 -23.016972)
			(xy 116.28659 -23.016972) (xy 116.268786 -23.03912) (xy 116.217197 -23.091917) (xy 116.189252 -23.116032)
			(xy 116.182705 -23.12205) (xy 116.173861 -23.137463) (xy 116.170806 -23.154969) (xy 116.17198 -23.163784)
			(xy 116.190014 -23.262844) (xy 116.207794 -23.283418) (xy 116.220494 -23.28799) (xy 116.243348 -23.296557)
			(xy 116.286862 -23.318661) (xy 116.327195 -23.346144) (xy 116.363686 -23.378554) (xy 116.380006 -23.396702)
			(xy 116.386314 -23.403343) (xy 116.402399 -23.412071) (xy 116.420525 -23.41459) (xy 116.429536 -23.412958)
			(xy 116.471439 -23.403945) (xy 116.556605 -23.394267) (xy 116.599462 -23.393654) (xy 116.600224 -23.393654)
			(xy 116.642916 -23.394238) (xy 116.727764 -23.403783) (xy 116.811016 -23.422741) (xy 116.891632 -23.450874)
			(xy 116.968603 -23.48783) (xy 117.0051 -23.509986) (xy 117.013356 -23.5147) (xy 117.032024 -23.518227)
			(xy 117.050692 -23.5147) (xy 117.058948 -23.509986) (xy 117.095446 -23.487829) (xy 117.172406 -23.450843)
			(xy 117.25302 -23.422698) (xy 117.336277 -23.403749) (xy 117.421131 -23.394233) (xy 117.463824 -23.393654)
			(xy 117.464586 -23.393654) (xy 117.507443 -23.394265) (xy 117.59261 -23.40394) (xy 117.634512 -23.412958)
			(xy 117.643528 -23.414579) (xy 117.661658 -23.412076) (xy 117.677751 -23.403359) (xy 117.684042 -23.396702)
			(xy 117.702268 -23.376545) (xy 117.743441 -23.341077) (xy 117.789226 -23.311804) (xy 117.838698 -23.289316)
			(xy 117.890858 -23.274069) (xy 117.944652 -23.266369) (xy 117.971824 -23.265892) (xy 117.999092 -23.266402)
			(xy 118.053072 -23.274166) (xy 118.105398 -23.289532) (xy 118.155006 -23.312187) (xy 118.200884 -23.341672)
			(xy 118.2421 -23.377384) (xy 118.277815 -23.418598) (xy 118.307302 -23.464475) (xy 118.329961 -23.514081)
			(xy 118.34533 -23.566406) (xy 118.353096 -23.620386) (xy 118.353586 -23.647654) (xy 118.353103 -23.674825)
			(xy 118.345397 -23.728617) (xy 118.330146 -23.780774) (xy 118.30766 -23.830245) (xy 118.278391 -23.87603)
			(xy 118.24293 -23.917207) (xy 118.222776 -23.935436) (xy 118.216114 -23.941724) (xy 118.207393 -23.957819)
			(xy 118.204883 -23.975952) (xy 118.20652 -23.984966) (xy 118.215538 -24.026868) (xy 118.225213 -24.112035)
			(xy 118.225824 -24.154892) (xy 118.225824 -24.155654) (xy 118.225252 -24.195561) (xy 118.216914 -24.274937)
			(xy 118.200324 -24.353007) (xy 118.175665 -24.428915) (xy 118.143205 -24.50183) (xy 118.103302 -24.570952)
			(xy 118.056392 -24.635525) (xy 118.00299 -24.69484) (xy 117.994649 -24.702351) (xy 130.235962 -24.702351)
			(xy 130.235962 -24.647849) (xy 130.243717 -24.593903) (xy 130.259071 -24.541609) (xy 130.28171 -24.492033)
			(xy 130.311174 -24.446182) (xy 130.346863 -24.404991) (xy 130.38805 -24.369298) (xy 130.433897 -24.33983)
			(xy 130.483472 -24.317185) (xy 130.535764 -24.301826) (xy 130.589709 -24.294065) (xy 130.61696 -24.293576)
			(xy 131.48056 -24.293576) (xy 131.507814 -24.294069) (xy 131.561767 -24.301821) (xy 131.614067 -24.317173)
			(xy 131.66365 -24.339812) (xy 131.709506 -24.369277) (xy 131.750702 -24.40497) (xy 131.786399 -24.446162)
			(xy 131.815869 -24.492015) (xy 131.838513 -24.541595) (xy 131.853871 -24.593894) (xy 131.861629 -24.647846)
			(xy 131.861629 -24.702354) (xy 131.853871 -24.756306) (xy 131.838513 -24.808605) (xy 131.815869 -24.858185)
			(xy 131.786399 -24.904038) (xy 131.750702 -24.94523) (xy 131.709506 -24.980923) (xy 131.66365 -25.010388)
			(xy 131.614067 -25.033027) (xy 131.561767 -25.048379) (xy 131.507814 -25.056131) (xy 131.48056 -25.056592)
			(xy 130.61696 -25.056592) (xy 130.589709 -25.056135) (xy 130.535764 -25.048374) (xy 130.483472 -25.033015)
			(xy 130.433897 -25.01037) (xy 130.38805 -24.980902) (xy 130.346863 -24.945209) (xy 130.311174 -24.904018)
			(xy 130.28171 -24.858167) (xy 130.259071 -24.808591) (xy 130.243717 -24.756297) (xy 130.235962 -24.702351)
			(xy 117.994649 -24.702351) (xy 117.943679 -24.748248) (xy 117.879111 -24.795164) (xy 117.809993 -24.835074)
			(xy 117.737081 -24.867539) (xy 117.661175 -24.892206) (xy 117.583106 -24.908803) (xy 117.503731 -24.917148)
			(xy 117.463824 -24.917654) (xy 117.421133 -24.917046) (xy 117.336286 -24.907506) (xy 117.253034 -24.888554)
			(xy 117.172418 -24.860427) (xy 117.095446 -24.823476) (xy 117.058948 -24.801322) (xy 117.050692 -24.796608)
			(xy 117.032024 -24.793081) (xy 117.013356 -24.796608) (xy 117.0051 -24.801322) (xy 116.968615 -24.823502)
			(xy 116.891651 -24.860484) (xy 116.811034 -24.888623) (xy 116.727774 -24.907568) (xy 116.642918 -24.917078)
			(xy 116.600224 -24.917654) (xy 116.560315 -24.917173) (xy 116.480933 -24.908831) (xy 116.402858 -24.892238)
			(xy 116.326946 -24.867573) (xy 116.254027 -24.835109) (xy 116.184902 -24.795199) (xy 116.120328 -24.748283)
			(xy 116.061012 -24.694873) (xy 116.007604 -24.635555) (xy 115.960689 -24.570979) (xy 115.920781 -24.501853)
			(xy 115.888319 -24.428934) (xy 115.863657 -24.353021) (xy 115.847065 -24.274945) (xy 115.838726 -24.195563)
			(xy 115.838224 -24.155654) (xy 115.838224 -24.154892) (xy 115.838832 -24.112035) (xy 115.848509 -24.026868)
			(xy 115.857528 -23.984966) (xy 115.859177 -23.975954) (xy 115.856665 -23.957818) (xy 115.847936 -23.941724)
			(xy 115.841272 -23.935436) (xy 115.821098 -23.917227) (xy 115.785633 -23.87605) (xy 115.756363 -23.830261)
			(xy 115.733878 -23.780786) (xy 115.718634 -23.728623) (xy 115.710937 -23.674826) (xy 115.710462 -23.647654)
			(xy 115.711037 -23.617471) (xy 115.720524 -23.557855) (xy 115.739272 -23.500473) (xy 115.766812 -23.446755)
			(xy 115.80246 -23.398039) (xy 115.823492 -23.376382) (xy 115.830046 -23.36933) (xy 115.837713 -23.351681)
			(xy 115.838349 -23.33245) (xy 115.831863 -23.314334) (xy 115.819166 -23.299876) (xy 115.80204 -23.291104)
			(xy 115.792504 -23.289768) (xy 115.768853 -23.29253) (xy 115.72132 -23.295452) (xy 115.697508 -23.29561)
			(xy 115.654727 -23.295008) (xy 115.569705 -23.285402) (xy 115.486289 -23.266355) (xy 115.405525 -23.238105)
			(xy 115.328423 -23.201007) (xy 115.29187 -23.17877) (xy 115.283614 -23.174056) (xy 115.264946 -23.170529)
			(xy 115.246278 -23.174056) (xy 115.238022 -23.17877) (xy 115.201578 -23.200841) (xy 115.124741 -23.237662)
			(xy 115.044275 -23.26568) (xy 114.961186 -23.284544) (xy 114.87651 -23.294019) (xy 114.833908 -23.294594)
			(xy 114.794 -23.294088) (xy 114.71462 -23.285746) (xy 114.636547 -23.269152) (xy 114.560637 -23.244488)
			(xy 114.487721 -23.212024) (xy 114.418597 -23.172116) (xy 114.354024 -23.125201) (xy 114.294708 -23.071793)
			(xy 114.241301 -23.012478) (xy 114.194386 -22.947905) (xy 114.154477 -22.878781) (xy 114.122013 -22.805865)
			(xy 114.097349 -22.729955) (xy 114.080754 -22.651882) (xy 114.072412 -22.572502) (xy 114.071908 -22.532594)
			(xy 114.071908 -22.531832) (xy 114.072167 -22.504557) (xy 114.076109 -22.450148) (xy 114.079782 -22.42312)
			(xy 114.080869 -22.410845) (xy 114.072766 -22.387614) (xy 114.064288 -22.37867) (xy 114.04569 -22.360564)
			(xy 114.013044 -22.320212) (xy 113.986172 -22.275806) (xy 113.965571 -22.228165) (xy 113.951622 -22.178171)
			(xy 113.944583 -22.126746) (xy 113.944146 -22.100794) (xy 67.755872 -22.100794) (xy 67.763469 -22.140212)
			(xy 67.771522 -22.224549) (xy 67.772026 -22.26691) (xy 67.771522 -22.309271) (xy 67.763469 -22.393608)
			(xy 67.747435 -22.476798) (xy 67.723567 -22.558088) (xy 67.692079 -22.63674) (xy 67.653257 -22.712043)
			(xy 67.607454 -22.783315) (xy 67.555083 -22.849911) (xy 67.496618 -22.911226) (xy 67.43259 -22.966707)
			(xy 67.363578 -23.01585) (xy 67.290208 -23.05821) (xy 67.213143 -23.093405) (xy 67.133081 -23.121114)
			(xy 67.050748 -23.141088) (xy 66.966889 -23.153145) (xy 66.882264 -23.157177) (xy 66.797639 -23.153145)
			(xy 66.71378 -23.141088) (xy 66.631447 -23.121114) (xy 66.551385 -23.093405) (xy 66.47432 -23.05821)
			(xy 66.40095 -23.01585) (xy 66.331938 -22.966707) (xy 66.26791 -22.911226) (xy 66.209445 -22.849911)
			(xy 66.157074 -22.783315) (xy 66.111271 -22.712043) (xy 66.072449 -22.63674) (xy 66.040961 -22.558088)
			(xy 66.017093 -22.476798) (xy 66.001059 -22.393608) (xy 65.993006 -22.309271) (xy 1.524 -22.309271)
			(xy 1.524 -25.56891) (xy 65.510156 -25.56891) (xy 65.510621 -25.527206) (xy 65.518403 -25.444163)
			(xy 65.533928 -25.362214) (xy 65.557059 -25.282079) (xy 65.587593 -25.204462) (xy 65.625262 -25.130046)
			(xy 65.669734 -25.059485) (xy 65.720619 -24.993398) (xy 65.777469 -24.932368) (xy 65.839786 -24.876929)
			(xy 65.873122 -24.851868) (xy 65.88167 -24.844931) (xy 65.892346 -24.825708) (xy 65.893696 -24.814784)
			(xy 65.897332 -24.773398) (xy 65.911399 -24.69151) (xy 65.933041 -24.611291) (xy 65.962067 -24.53344)
			(xy 65.998226 -24.458634) (xy 66.041203 -24.387525) (xy 66.090622 -24.320733) (xy 66.146054 -24.25884)
			(xy 66.207015 -24.202385) (xy 66.272974 -24.15186) (xy 66.343357 -24.107705) (xy 66.41755 -24.070304)
			(xy 66.494907 -24.039985) (xy 66.574755 -24.01701) (xy 66.656396 -24.00158) (xy 66.739121 -23.99383)
			(xy 66.780664 -23.993348) (xy 66.824459 -23.993873) (xy 66.911625 -24.002491) (xy 66.997521 -24.019637)
			(xy 67.081315 -24.045145) (xy 67.162195 -24.078768) (xy 67.201034 -24.099012) (xy 67.2125 -24.10443)
			(xy 67.237828 -24.10443) (xy 67.249294 -24.099012) (xy 67.288138 -24.078781) (xy 67.369023 -24.045174)
			(xy 67.452816 -24.019672) (xy 67.538709 -24.002521) (xy 67.62587 -23.993888) (xy 67.669664 -23.993348)
			(xy 67.713459 -23.993873) (xy 67.800625 -24.002491) (xy 67.886521 -24.019637) (xy 67.970315 -24.045145)
			(xy 68.051195 -24.078768) (xy 68.090034 -24.099012) (xy 68.1015 -24.10443) (xy 68.126828 -24.10443)
			(xy 68.138294 -24.099012) (xy 68.177138 -24.078781) (xy 68.258023 -24.045174) (xy 68.341816 -24.019672)
			(xy 68.427709 -24.002521) (xy 68.51487 -23.993888) (xy 68.558664 -23.993348) (xy 68.607651 -23.994055)
			(xy 68.705028 -24.00487) (xy 68.752974 -24.014938) (xy 68.762324 -24.016604) (xy 68.781086 -24.013776)
			(xy 68.797533 -24.004314) (xy 68.803774 -23.997158) (xy 68.831851 -23.962886) (xy 68.893786 -23.899527)
			(xy 68.961714 -23.842641) (xy 69.034963 -23.792791) (xy 69.112805 -23.750472) (xy 69.19447 -23.716104)
			(xy 69.279148 -23.690027) (xy 69.365999 -23.672499) (xy 69.454163 -23.663695) (xy 69.498464 -23.663148)
			(xy 69.540827 -23.663615) (xy 69.625169 -23.671665) (xy 69.708365 -23.687697) (xy 69.789659 -23.711564)
			(xy 69.868317 -23.743051) (xy 69.943625 -23.781873) (xy 70.014902 -23.827677) (xy 70.081502 -23.880049)
			(xy 70.142823 -23.938516) (xy 70.198307 -24.002546) (xy 70.247454 -24.071561) (xy 70.250564 -24.076947)
			(xy 112.652614 -24.076947) (xy 112.652614 -24.022453) (xy 112.660369 -23.968515) (xy 112.67572 -23.916228)
			(xy 112.698356 -23.866659) (xy 112.727815 -23.820815) (xy 112.763499 -23.77963) (xy 112.80468 -23.743942)
			(xy 112.85052 -23.714477) (xy 112.900087 -23.691836) (xy 112.952372 -23.676478) (xy 113.006309 -23.668717)
			(xy 113.033556 -23.668228) (xy 113.897156 -23.668228) (xy 113.924413 -23.668616) (xy 113.978374 -23.676369)
			(xy 114.030682 -23.691722) (xy 114.080273 -23.714364) (xy 114.126136 -23.743834) (xy 114.167338 -23.779531)
			(xy 114.20304 -23.820729) (xy 114.232514 -23.866588) (xy 114.255162 -23.916176) (xy 114.270522 -23.968483)
			(xy 114.278281 -24.022443) (xy 114.278281 -24.076957) (xy 114.270522 -24.130917) (xy 114.255162 -24.183224)
			(xy 114.232514 -24.232812) (xy 114.20304 -24.278671) (xy 114.167338 -24.319869) (xy 114.126136 -24.355566)
			(xy 114.080273 -24.385036) (xy 114.030682 -24.407678) (xy 113.978374 -24.423031) (xy 113.924414 -24.430784)
			(xy 113.897156 -24.431244) (xy 113.033556 -24.431244) (xy 113.006309 -24.430683) (xy 112.952372 -24.422922)
			(xy 112.900087 -24.407564) (xy 112.85052 -24.384923) (xy 112.80468 -24.355458) (xy 112.763499 -24.31977)
			(xy 112.727815 -24.278585) (xy 112.698356 -24.232741) (xy 112.67572 -24.183172) (xy 112.660369 -24.130885)
			(xy 112.652614 -24.076947) (xy 70.250564 -24.076947) (xy 70.289818 -24.144935) (xy 70.325015 -24.222004)
			(xy 70.352727 -24.302069) (xy 70.372702 -24.384407) (xy 70.38476 -24.46827) (xy 70.388792 -24.5529)
			(xy 70.38476 -24.63753) (xy 70.372702 -24.721393) (xy 70.352727 -24.803731) (xy 70.325015 -24.883796)
			(xy 70.289818 -24.960865) (xy 70.247454 -25.034239) (xy 70.198307 -25.103254) (xy 70.142823 -25.167284)
			(xy 70.081502 -25.225751) (xy 70.014902 -25.278123) (xy 69.943625 -25.323927) (xy 69.868317 -25.362749)
			(xy 69.789659 -25.394236) (xy 69.708365 -25.418103) (xy 69.625169 -25.434135) (xy 69.540827 -25.442185)
			(xy 69.498464 -25.442672) (xy 69.449476 -25.441976) (xy 69.3521 -25.431154) (xy 69.304154 -25.421082)
			(xy 69.294812 -25.41935) (xy 69.276039 -25.422204) (xy 69.259591 -25.431693) (xy 69.253354 -25.438862)
			(xy 69.228687 -25.46901) (xy 69.174875 -25.52534) (xy 69.116354 -25.57676) (xy 69.085206 -25.600152)
			(xy 69.076637 -25.607067) (xy 69.065975 -25.626306) (xy 69.065849 -25.62733) (xy 133.339332 -25.62733)
			(xy 133.339332 -24.76373) (xy 133.339818 -24.736479) (xy 133.347574 -24.682531) (xy 133.362929 -24.630236)
			(xy 133.385571 -24.580659) (xy 133.415037 -24.534809) (xy 133.450728 -24.493618) (xy 133.491919 -24.457927)
			(xy 133.537769 -24.428461) (xy 133.587346 -24.405819) (xy 133.639641 -24.390464) (xy 133.693589 -24.382708)
			(xy 133.748091 -24.382708) (xy 133.802039 -24.390464) (xy 133.854334 -24.405819) (xy 133.903911 -24.428461)
			(xy 133.949761 -24.457927) (xy 133.990952 -24.493618) (xy 134.026643 -24.534809) (xy 134.056109 -24.580659)
			(xy 134.078751 -24.630236) (xy 134.094106 -24.682531) (xy 134.101862 -24.736479) (xy 134.102348 -24.76373)
			(xy 134.102348 -25.62733) (xy 134.101862 -25.654581) (xy 134.094106 -25.708529) (xy 134.078751 -25.760824)
			(xy 134.056109 -25.810401) (xy 134.026643 -25.856251) (xy 133.990952 -25.897442) (xy 133.949761 -25.933133)
			(xy 133.903911 -25.962599) (xy 133.854334 -25.985241) (xy 133.802039 -26.000596) (xy 133.748091 -26.008352)
			(xy 133.693589 -26.008352) (xy 133.639641 -26.000596) (xy 133.587346 -25.985241) (xy 133.537769 -25.962599)
			(xy 133.491919 -25.933133) (xy 133.450728 -25.897442) (xy 133.415037 -25.856251) (xy 133.385571 -25.810401)
			(xy 133.362929 -25.760824) (xy 133.347574 -25.708529) (xy 133.339818 -25.654581) (xy 133.339332 -25.62733)
			(xy 69.065849 -25.62733) (xy 69.064632 -25.637236) (xy 69.060986 -25.678621) (xy 69.046917 -25.760507)
			(xy 69.025275 -25.840725) (xy 68.996248 -25.918575) (xy 68.960089 -25.99338) (xy 68.917113 -26.064488)
			(xy 68.867694 -26.131279) (xy 68.812263 -26.193171) (xy 68.751303 -26.249626) (xy 68.685345 -26.300151)
			(xy 68.614964 -26.344307) (xy 68.540772 -26.381708) (xy 68.463416 -26.412028) (xy 68.38357 -26.435004)
			(xy 68.30193 -26.450436) (xy 68.219207 -26.458189) (xy 68.177664 -26.458672) (xy 68.133869 -26.458133)
			(xy 68.046704 -26.449518) (xy 67.960808 -26.432375) (xy 67.877014 -26.40687) (xy 67.796134 -26.37325)
			(xy 67.757294 -26.353008) (xy 67.745828 -26.34759) (xy 67.7205 -26.34759) (xy 67.709034 -26.353008)
			(xy 67.670181 -26.373222) (xy 67.589299 -26.406833) (xy 67.505508 -26.43234) (xy 67.419618 -26.449494)
			(xy 67.332457 -26.458131) (xy 67.288664 -26.458672) (xy 67.244869 -26.458133) (xy 67.157704 -26.449518)
			(xy 67.071808 -26.432375) (xy 66.988014 -26.40687) (xy 66.907134 -26.37325) (xy 66.868294 -26.353008)
			(xy 66.856828 -26.34759) (xy 66.8315 -26.34759) (xy 66.820034 -26.353008) (xy 66.781181 -26.373222)
			(xy 66.700299 -26.406833) (xy 66.616508 -26.43234) (xy 66.530618 -26.449494) (xy 66.443457 -26.458131)
			(xy 66.399664 -26.458672) (xy 66.358552 -26.458282) (xy 66.276678 -26.45069) (xy 66.195855 -26.435576)
			(xy 66.116771 -26.413067) (xy 66.040102 -26.383356) (xy 65.966502 -26.346696) (xy 65.8966 -26.3034)
			(xy 65.830991 -26.253838) (xy 65.770236 -26.198433) (xy 65.714853 -26.137658) (xy 65.665316 -26.072031)
			(xy 65.622046 -26.002113) (xy 65.585413 -25.928499) (xy 65.55573 -25.85182) (xy 65.53325 -25.772728)
			(xy 65.518165 -25.691899) (xy 65.510603 -25.610022) (xy 65.510156 -25.56891) (xy 1.524 -25.56891)
			(xy 1.524 -29.026161) (xy 11.140205 -29.026161) (xy 11.147539 -28.866724) (xy 11.162812 -28.70785)
			(xy 11.185984 -28.549934) (xy 11.216999 -28.39337) (xy 11.255779 -28.238547) (xy 11.302228 -28.085849)
			(xy 11.35623 -27.935656) (xy 11.417652 -27.788341) (xy 11.48634 -27.644271) (xy 11.562123 -27.503804)
			(xy 11.644814 -27.367289) (xy 11.734207 -27.235065) (xy 11.830079 -27.107461) (xy 11.932193 -26.984794)
			(xy 12.040293 -26.86737) (xy 12.154112 -26.75548) (xy 12.273367 -26.649402) (xy 12.397761 -26.5494)
			(xy 12.526985 -26.455723) (xy 12.660717 -26.368604) (xy 12.798626 -26.288258) (xy 12.940368 -26.214886)
			(xy 13.085591 -26.148671) (xy 13.233934 -26.089776) (xy 13.385028 -26.038349) (xy 13.538498 -25.994517)
			(xy 13.693962 -25.958388) (xy 13.851033 -25.930054) (xy 14.009321 -25.909584) (xy 14.168433 -25.897029)
			(xy 14.327973 -25.892421) (xy 14.487544 -25.895771) (xy 14.64675 -25.90707) (xy 14.805195 -25.92629)
			(xy 14.962485 -25.953385) (xy 15.118229 -25.988285) (xy 15.272039 -26.030905) (xy 15.423535 -26.081139)
			(xy 15.572338 -26.138862) (xy 15.718078 -26.203929) (xy 15.860395 -26.27618) (xy 15.998933 -26.355436)
			(xy 16.133349 -26.441497) (xy 16.263308 -26.534152) (xy 16.388487 -26.633169) (xy 16.508575 -26.738303)
			(xy 16.623273 -26.849292) (xy 16.678148 -26.907236) (xy 17.770856 -28.07589) (xy 17.824996 -28.134528)
			(xy 17.928078 -28.256394) (xy 18.024957 -28.383247) (xy 18.115392 -28.514772) (xy 18.199158 -28.650641)
			(xy 18.276047 -28.790516) (xy 18.345869 -28.934051) (xy 18.408448 -29.080887) (xy 18.463631 -29.230661)
			(xy 18.511279 -29.382999) (xy 18.551274 -29.537523) (xy 18.583516 -29.693848) (xy 18.607926 -29.851586)
			(xy 18.624443 -30.010345) (xy 18.633025 -30.16973) (xy 18.633652 -30.329344) (xy 18.626321 -30.488792)
			(xy 18.611051 -30.647675) (xy 18.587881 -30.8056) (xy 18.556867 -30.962174) (xy 18.518086 -31.117007)
			(xy 18.471636 -31.269714) (xy 18.417631 -31.419917) (xy 18.356206 -31.56724) (xy 18.287514 -31.711318)
			(xy 18.211725 -31.851793) (xy 18.129028 -31.988316) (xy 18.039629 -32.120546) (xy 17.943749 -32.248156)
			(xy 17.841627 -32.370828) (xy 17.733517 -32.488256) (xy 17.619688 -32.60015) (xy 17.500423 -32.70623)
			(xy 17.376019 -32.806234) (xy 17.246784 -32.899911) (xy 17.11304 -32.98703) (xy 16.975119 -33.067374)
			(xy 16.833366 -33.140743) (xy 16.688131 -33.206955) (xy 16.539776 -33.265845) (xy 16.38867 -33.317266)
			(xy 16.235188 -33.361091) (xy 16.079713 -33.397211) (xy 15.922631 -33.425536) (xy 15.764332 -33.445995)
			(xy 15.605209 -33.458538) (xy 15.44566 -33.463134) (xy 15.286079 -33.459771) (xy 15.126865 -33.448457)
			(xy 14.968413 -33.42922) (xy 14.811116 -33.402109) (xy 14.655367 -33.367191) (xy 14.501552 -33.324553)
			(xy 14.350053 -33.2743) (xy 14.201248 -33.216557) (xy 14.055506 -33.151469) (xy 13.91319 -33.079197)
			(xy 13.774653 -32.999921) (xy 13.64024 -32.913837) (xy 13.510286 -32.82116) (xy 13.385112 -32.72212)
			(xy 13.265032 -32.616964) (xy 13.150342 -32.505953) (xy 13.095478 -32.447992) (xy 12.00277 -31.279592)
			(xy 11.948692 -31.220903) (xy 11.845626 -31.099035) (xy 11.748763 -30.972182) (xy 11.658343 -30.840658)
			(xy 11.574591 -30.704792) (xy 11.497716 -30.564919) (xy 11.427907 -30.421388) (xy 11.36534 -30.274557)
			(xy 11.310169 -30.124789) (xy 11.262532 -29.972457) (xy 11.222547 -29.81794) (xy 11.190314 -29.661623)
			(xy 11.165912 -29.503893) (xy 11.149402 -29.345143) (xy 11.140826 -29.185767) (xy 11.140205 -29.026161)
			(xy 1.524 -29.026161) (xy 1.524 -39.23137) (xy 9.080235 -39.23137) (xy 9.080235 -39.10223) (xy 9.088185 -38.973335)
			(xy 9.104055 -38.845175) (xy 9.127784 -38.718234) (xy 9.159283 -38.592995) (xy 9.198432 -38.469932)
			(xy 9.245083 -38.349513) (xy 9.299058 -38.232194) (xy 9.360153 -38.11842) (xy 9.428136 -38.008623)
			(xy 9.50275 -37.90322) (xy 9.583711 -37.80261) (xy 9.670711 -37.707175) (xy 9.763422 -37.617276)
			(xy 9.861492 -37.533255) (xy 9.964547 -37.455431) (xy 10.072198 -37.384099) (xy 10.184037 -37.319529)
			(xy 10.299638 -37.261967) (xy 10.418563 -37.21163) (xy 10.540362 -37.16871) (xy 10.664572 -37.133369)
			(xy 10.790721 -37.105742) (xy 10.918333 -37.085933) (xy 11.046922 -37.074017) (xy 11.176 -37.070041)
			(xy 11.305078 -37.074017) (xy 11.433667 -37.085933) (xy 11.561279 -37.105742) (xy 11.687428 -37.133369)
			(xy 11.811638 -37.16871) (xy 11.933437 -37.21163) (xy 12.052362 -37.261967) (xy 12.167963 -37.319529)
			(xy 12.279802 -37.384099) (xy 12.387453 -37.455431) (xy 12.490508 -37.533255) (xy 12.588578 -37.617276)
			(xy 12.681289 -37.707175) (xy 12.768289 -37.80261) (xy 12.84925 -37.90322) (xy 12.923864 -38.008623)
			(xy 12.991847 -38.11842) (xy 13.052942 -38.232194) (xy 13.106917 -38.349513) (xy 13.153568 -38.469932)
			(xy 13.192717 -38.592995) (xy 13.224216 -38.718234) (xy 13.247945 -38.845175) (xy 13.263815 -38.973335)
			(xy 13.271765 -39.10223) (xy 13.272262 -39.1668) (xy 13.271765 -39.23137) (xy 13.263815 -39.360265)
			(xy 13.247945 -39.488425) (xy 13.224216 -39.615366) (xy 13.192717 -39.740605) (xy 13.153568 -39.863668)
			(xy 13.106917 -39.984087) (xy 13.052942 -40.101406) (xy 12.991847 -40.21518) (xy 12.923864 -40.324977)
			(xy 12.84925 -40.43038) (xy 12.768289 -40.53099) (xy 12.681289 -40.626425) (xy 12.588578 -40.716324)
			(xy 12.490508 -40.800345) (xy 12.413317 -40.858637) (xy 24.936192 -40.858637) (xy 24.936192 -40.773915)
			(xy 24.944245 -40.689578) (xy 24.960279 -40.606388) (xy 24.984147 -40.525098) (xy 25.015635 -40.446446)
			(xy 25.054457 -40.371143) (xy 25.10026 -40.299871) (xy 25.152631 -40.233275) (xy 25.211096 -40.17196)
			(xy 25.275124 -40.116479) (xy 25.344136 -40.067336) (xy 25.417506 -40.024976) (xy 25.494571 -39.989781)
			(xy 25.574633 -39.962072) (xy 25.656966 -39.942098) (xy 25.740825 -39.930041) (xy 25.82545 -39.92601)
			(xy 25.910075 -39.930041) (xy 25.993934 -39.942098) (xy 26.076267 -39.962072) (xy 26.156329 -39.989781)
			(xy 26.233394 -40.024976) (xy 26.306764 -40.067336) (xy 26.375776 -40.116479) (xy 26.439804 -40.17196)
			(xy 26.498269 -40.233275) (xy 26.55064 -40.299871) (xy 26.596443 -40.371143) (xy 26.635265 -40.446446)
			(xy 26.666753 -40.525098) (xy 26.690621 -40.606388) (xy 26.706655 -40.689578) (xy 26.714708 -40.773915)
			(xy 26.715212 -40.816276) (xy 26.714708 -40.858637) (xy 26.706655 -40.942974) (xy 26.690621 -41.026164)
			(xy 26.666753 -41.107454) (xy 26.635265 -41.186106) (xy 26.596443 -41.261409) (xy 26.55064 -41.332681)
			(xy 26.498269 -41.399277) (xy 26.439804 -41.460592) (xy 26.375776 -41.516073) (xy 26.306764 -41.565216)
			(xy 26.233394 -41.607576) (xy 26.156329 -41.642771) (xy 26.076267 -41.67048) (xy 25.993934 -41.690454)
			(xy 25.910075 -41.702511) (xy 25.82545 -41.706543) (xy 25.740825 -41.702511) (xy 25.656966 -41.690454)
			(xy 25.574633 -41.67048) (xy 25.494571 -41.642771) (xy 25.417506 -41.607576) (xy 25.344136 -41.565216)
			(xy 25.275124 -41.516073) (xy 25.211096 -41.460592) (xy 25.152631 -41.399277) (xy 25.10026 -41.332681)
			(xy 25.054457 -41.261409) (xy 25.015635 -41.186106) (xy 24.984147 -41.107454) (xy 24.960279 -41.026164)
			(xy 24.944245 -40.942974) (xy 24.936192 -40.858637) (xy 12.413317 -40.858637) (xy 12.387453 -40.878169)
			(xy 12.279802 -40.949501) (xy 12.167963 -41.014071) (xy 12.052362 -41.071633) (xy 11.933437 -41.12197)
			(xy 11.811638 -41.16489) (xy 11.687428 -41.200231) (xy 11.561279 -41.227858) (xy 11.433667 -41.247667)
			(xy 11.305078 -41.259583) (xy 11.176 -41.26356) (xy 11.046922 -41.259583) (xy 10.918333 -41.247667)
			(xy 10.790721 -41.227858) (xy 10.664572 -41.200231) (xy 10.540362 -41.16489) (xy 10.418563 -41.12197)
			(xy 10.299638 -41.071633) (xy 10.184037 -41.014071) (xy 10.072198 -40.949501) (xy 9.964547 -40.878169)
			(xy 9.861492 -40.800345) (xy 9.763422 -40.716324) (xy 9.670711 -40.626425) (xy 9.583711 -40.53099)
			(xy 9.50275 -40.43038) (xy 9.428136 -40.324977) (xy 9.360153 -40.21518) (xy 9.299058 -40.101406)
			(xy 9.245083 -39.984087) (xy 9.198432 -39.863668) (xy 9.159283 -39.740605) (xy 9.127784 -39.615366)
			(xy 9.104055 -39.488425) (xy 9.088185 -39.360265) (xy 9.080235 -39.23137) (xy 1.524 -39.23137) (xy 1.524 -74.760836)
			(xy 39.554404 -74.760836) (xy 39.554404 -66.060828) (xy 39.554909 -65.955304) (xy 39.562993 -65.74441)
			(xy 39.579149 -65.533981) (xy 39.603352 -65.324324) (xy 39.635569 -65.115749) (xy 39.675751 -64.908561)
			(xy 39.723839 -64.703064) (xy 39.779763 -64.49956) (xy 39.84344 -64.298347) (xy 39.914778 -64.09972)
			(xy 39.993672 -63.903972) (xy 40.080005 -63.71139) (xy 40.173652 -63.522255) (xy 40.274474 -63.336846)
			(xy 40.382324 -63.155435) (xy 40.497043 -62.978288) (xy 40.618463 -62.805666) (xy 40.746406 -62.63782)
			(xy 40.880684 -62.474998) (xy 41.0211 -62.317439) (xy 41.167448 -62.165374) (xy 41.319513 -62.019026)
			(xy 41.477072 -61.87861) (xy 41.639894 -61.744332) (xy 41.80774 -61.616389) (xy 41.980362 -61.494969)
			(xy 42.157509 -61.38025) (xy 42.33892 -61.2724) (xy 42.524329 -61.171578) (xy 42.713464 -61.077931)
			(xy 42.906046 -60.991598) (xy 43.101794 -60.912704) (xy 43.300421 -60.841366) (xy 43.501634 -60.777689)
			(xy 43.705138 -60.721765) (xy 43.910635 -60.673677) (xy 44.117823 -60.633495) (xy 44.326398 -60.601278)
			(xy 44.536055 -60.577075) (xy 44.746484 -60.560919) (xy 44.957378 -60.552835) (xy 45.168426 -60.552835)
			(xy 45.37932 -60.560919) (xy 45.589749 -60.577075) (xy 45.799406 -60.601278) (xy 46.007981 -60.633495)
			(xy 46.215169 -60.673677) (xy 46.420666 -60.721765) (xy 46.62417 -60.777689) (xy 46.825383 -60.841366)
			(xy 47.02401 -60.912704) (xy 47.219758 -60.991598) (xy 47.41234 -61.077931) (xy 47.601475 -61.171578)
			(xy 47.786884 -61.2724) (xy 47.968295 -61.38025) (xy 48.145442 -61.494969) (xy 48.318064 -61.616389)
			(xy 48.48591 -61.744332) (xy 48.648732 -61.87861) (xy 48.806291 -62.019026) (xy 48.958356 -62.165374)
			(xy 49.104704 -62.317439) (xy 49.24512 -62.474998) (xy 49.379398 -62.63782) (xy 49.507341 -62.805666)
			(xy 49.628761 -62.978288) (xy 49.74348 -63.155435) (xy 49.85133 -63.336846) (xy 49.952152 -63.522255)
			(xy 50.045799 -63.71139) (xy 50.132132 -63.903972) (xy 50.211026 -64.09972) (xy 50.282364 -64.298347)
			(xy 50.346041 -64.49956) (xy 50.401965 -64.703064) (xy 50.450053 -64.908561) (xy 50.490235 -65.115749)
			(xy 50.522452 -65.324324) (xy 50.546655 -65.533981) (xy 50.562811 -65.74441) (xy 50.570895 -65.955304)
			(xy 50.5714 -66.060828) (xy 50.5714 -74.760836) (xy 50.570895 -74.86636) (xy 50.562811 -75.077254)
			(xy 50.546655 -75.287683) (xy 50.522452 -75.49734) (xy 50.490235 -75.705915) (xy 50.450053 -75.913103)
			(xy 50.401965 -76.1186) (xy 50.346041 -76.322104) (xy 50.282364 -76.523317) (xy 50.211026 -76.721944)
			(xy 50.132132 -76.917692) (xy 50.045799 -77.110274) (xy 49.952152 -77.299409) (xy 49.85133 -77.484818)
			(xy 49.74348 -77.666229) (xy 49.628761 -77.843376) (xy 49.507341 -78.015998) (xy 49.379398 -78.183844)
			(xy 49.24512 -78.346666) (xy 49.104704 -78.504225) (xy 48.958356 -78.65629) (xy 48.806291 -78.802638)
			(xy 48.648732 -78.943054) (xy 48.48591 -79.077332) (xy 48.318064 -79.205275) (xy 48.145442 -79.326695)
			(xy 47.968295 -79.441414) (xy 47.786884 -79.549264) (xy 47.601475 -79.650086) (xy 47.41234 -79.743733)
			(xy 47.219758 -79.830066) (xy 47.02401 -79.90896) (xy 46.825383 -79.980298) (xy 46.62417 -80.043975)
			(xy 46.420666 -80.099899) (xy 46.215169 -80.147987) (xy 46.007981 -80.188169) (xy 45.799406 -80.220386)
			(xy 45.589749 -80.244589) (xy 45.37932 -80.260745) (xy 45.168426 -80.268829) (xy 44.957378 -80.268829)
			(xy 44.746484 -80.260745) (xy 44.536055 -80.244589) (xy 44.326398 -80.220386) (xy 44.117823 -80.188169)
			(xy 43.910635 -80.147987) (xy 43.705138 -80.099899) (xy 43.501634 -80.043975) (xy 43.300421 -79.980298)
			(xy 43.101794 -79.90896) (xy 42.906046 -79.830066) (xy 42.713464 -79.743733) (xy 42.524329 -79.650086)
			(xy 42.33892 -79.549264) (xy 42.157509 -79.441414) (xy 41.980362 -79.326695) (xy 41.80774 -79.205275)
			(xy 41.639894 -79.077332) (xy 41.477072 -78.943054) (xy 41.319513 -78.802638) (xy 41.167448 -78.65629)
			(xy 41.0211 -78.504225) (xy 40.880684 -78.346666) (xy 40.746406 -78.183844) (xy 40.618463 -78.015998)
			(xy 40.497043 -77.843376) (xy 40.382324 -77.666229) (xy 40.274474 -77.484818) (xy 40.173652 -77.299409)
			(xy 40.080005 -77.110274) (xy 39.993672 -76.917692) (xy 39.914778 -76.721944) (xy 39.84344 -76.523317)
			(xy 39.779763 -76.322104) (xy 39.723839 -76.1186) (xy 39.675751 -75.913103) (xy 39.635569 -75.705915)
			(xy 39.603352 -75.49734) (xy 39.579149 -75.287683) (xy 39.562993 -75.077254) (xy 39.554909 -74.86636)
			(xy 39.554404 -74.760836) (xy 1.524 -74.760836) (xy 1.524 -77.671676) (xy 1.524528 -77.702818) (xy 1.532691 -77.764566)
			(xy 1.548839 -77.824722) (xy 1.572695 -77.882257) (xy 1.603853 -77.936189) (xy 1.64178 -77.985596)
			(xy 1.663446 -78.007972) (xy 2.49174 -78.836266) (xy 2.492248 -78.836774) (xy 2.506726 -78.851506)
			(xy 2.566693 -78.91292) (xy 2.681269 -79.040756) (xy 2.789483 -79.17402) (xy 2.891079 -79.312396)
			(xy 2.985816 -79.455556) (xy 3.073468 -79.603159) (xy 3.153829 -79.754856) (xy 3.226706 -79.910286)
			(xy 3.291927 -80.069081) (xy 3.349338 -80.230864) (xy 3.398801 -80.395251) (xy 3.440201 -80.561852)
			(xy 3.473438 -80.730271) (xy 3.498433 -80.900109) (xy 3.515128 -81.070962) (xy 3.523482 -81.242426)
			(xy 3.523996 -81.32826) (xy 3.523996 -90.854276) (xy 57.149492 -90.854276) (xy 57.149492 -30.10662)
			(xy 57.149903 -30.096549) (xy 57.157631 -30.077949) (xy 57.164478 -30.070552) (xy 58.356246 -28.879038)
			(xy 58.360056 -28.869894) (xy 58.374793 -28.836236) (xy 58.409783 -28.77162) (xy 58.450827 -28.710671)
			(xy 58.497543 -28.653952) (xy 58.5495 -28.601991) (xy 58.606214 -28.555269) (xy 58.66716 -28.51422)
			(xy 58.731772 -28.479224) (xy 58.76544 -28.46451) (xy 58.774584 -28.4607) (xy 59.009534 -28.22575)
			(xy 59.013344 -28.21432) (xy 59.026183 -28.17696) (xy 59.058603 -28.104915) (xy 59.0983 -28.03661)
			(xy 59.144847 -27.972775) (xy 59.197746 -27.914096) (xy 59.25643 -27.861203) (xy 59.320269 -27.814661)
			(xy 59.388578 -27.774971) (xy 59.460626 -27.742558) (xy 59.497976 -27.729688) (xy 59.503496 -27.727672)
			(xy 59.513502 -27.721516) (xy 59.517788 -27.717496) (xy 59.823604 -27.411426) (xy 59.831012 -27.404596)
			(xy 59.849605 -27.39687) (xy 59.859672 -27.39644) (xy 64.219328 -27.39644) (xy 64.2294 -27.39684)
			(xy 64.247998 -27.404577) (xy 64.255396 -27.411426) (xy 64.457072 -27.613102) (xy 64.464363 -27.619762)
			(xy 64.482522 -27.627475) (xy 64.492378 -27.628088) (xy 64.492632 -27.628088) (xy 64.531985 -27.629034)
			(xy 64.610191 -27.638031) (xy 64.687054 -27.655036) (xy 64.761756 -27.67987) (xy 64.833502 -27.712269)
			(xy 64.901528 -27.751887) (xy 64.905217 -27.75458) (xy 130.305302 -27.75458) (xy 130.30588 -27.712975)
			(xy 130.314932 -27.630259) (xy 130.332926 -27.549018) (xy 130.359649 -27.470216) (xy 130.394784 -27.394788)
			(xy 130.437914 -27.323628) (xy 130.462782 -27.290268) (xy 130.469143 -27.28108) (xy 130.473968 -27.259284)
			(xy 130.469129 -27.237491) (xy 130.462782 -27.228292) (xy 130.437901 -27.194943) (xy 130.394789 -27.123772)
			(xy 130.359664 -27.04834) (xy 130.332942 -26.969537) (xy 130.314939 -26.888299) (xy 130.305869 -26.805585)
			(xy 130.305302 -26.76398) (xy 130.305801 -26.725155) (xy 130.313687 -26.647905) (xy 130.329376 -26.571856)
			(xy 130.352705 -26.497793) (xy 130.383434 -26.426481) (xy 130.421245 -26.358658) (xy 130.465746 -26.295024)
			(xy 130.516479 -26.236237) (xy 130.572918 -26.182906) (xy 130.63448 -26.13558) (xy 130.667252 -26.114756)
			(xy 130.676537 -26.108282) (xy 130.688814 -26.089308) (xy 130.690874 -26.07818) (xy 130.694998 -26.051051)
			(xy 130.710017 -25.998274) (xy 130.732441 -25.948192) (xy 130.761807 -25.901838) (xy 130.79751 -25.860169)
			(xy 130.838813 -25.824042) (xy 130.884865 -25.794205) (xy 130.934715 -25.771271) (xy 130.987336 -25.755714)
			(xy 131.041644 -25.747854) (xy 131.096516 -25.747854) (xy 131.150824 -25.755714) (xy 131.203445 -25.771271)
			(xy 131.253295 -25.794205) (xy 131.299347 -25.824042) (xy 131.34065 -25.860169) (xy 131.376353 -25.901838)
			(xy 131.405719 -25.948192) (xy 131.428143 -25.998274) (xy 131.443162 -26.051051) (xy 131.447286 -26.07818)
			(xy 131.449384 -26.089293) (xy 131.461644 -26.108268) (xy 131.470908 -26.114756) (xy 131.503657 -26.135617)
			(xy 131.565225 -26.182934) (xy 131.621671 -26.236258) (xy 131.672409 -26.295038) (xy 131.716916 -26.358667)
			(xy 131.754732 -26.426487) (xy 131.785465 -26.497797) (xy 131.808797 -26.571858) (xy 131.824489 -26.647906)
			(xy 131.832376 -26.725155) (xy 131.832858 -26.76398) (xy 131.832807 -26.76779) (xy 141.239748 -26.76779)
			(xy 141.240347 -26.7251) (xy 141.249911 -26.640257) (xy 141.268874 -26.557009) (xy 141.296999 -26.476394)
			(xy 141.333936 -26.399417) (xy 141.35608 -26.362914) (xy 141.360784 -26.354657) (xy 141.36429 -26.335991)
			(xy 141.360778 -26.317327) (xy 141.35608 -26.309066) (xy 141.333922 -26.272571) (xy 141.296978 -26.195596)
			(xy 141.268853 -26.114979) (xy 141.249898 -26.031727) (xy 141.240351 -25.946881) (xy 141.239748 -25.90419)
			(xy 141.240218 -25.864188) (xy 141.248582 -25.784621) (xy 141.265217 -25.706365) (xy 141.289941 -25.630276)
			(xy 141.322484 -25.557188) (xy 141.362488 -25.487903) (xy 141.409515 -25.423178) (xy 141.46305 -25.363724)
			(xy 141.522506 -25.310192) (xy 141.587233 -25.263168) (xy 141.65652 -25.223167) (xy 141.729609 -25.190628)
			(xy 141.805699 -25.165908) (xy 141.883957 -25.149276) (xy 141.963524 -25.140916) (xy 142.003526 -25.140412)
			(xy 142.004034 -25.140412) (xy 142.040445 -25.140846) (xy 142.112937 -25.147779) (xy 142.184441 -25.161578)
			(xy 142.254306 -25.182119) (xy 142.28826 -25.195276) (xy 142.296243 -25.198111) (xy 142.313148 -25.198984)
			(xy 142.329415 -25.194298) (xy 142.33652 -25.189688) (xy 142.360823 -25.173138) (xy 142.413459 -25.146939)
			(xy 142.469492 -25.129126) (xy 142.527594 -25.120119) (xy 142.556992 -25.119584) (xy 142.584265 -25.120009)
			(xy 142.638256 -25.127771) (xy 142.690592 -25.143139) (xy 142.740208 -25.165799) (xy 142.786094 -25.19529)
			(xy 142.827315 -25.231012) (xy 142.863033 -25.272237) (xy 142.892519 -25.318125) (xy 142.915174 -25.367744)
			(xy 142.930537 -25.420082) (xy 142.938294 -25.474073) (xy 142.938754 -25.501346) (xy 142.938161 -25.530911)
			(xy 142.929033 -25.589334) (xy 142.911016 -25.645653) (xy 142.88454 -25.698526) (xy 142.850238 -25.746691)
			(xy 142.808927 -25.788999) (xy 142.785592 -25.807162) (xy 142.779066 -25.812543) (xy 142.769642 -25.826573)
			(xy 142.765283 -25.842903) (xy 142.765526 -25.851358) (xy 142.767304 -25.903936) (xy 142.767304 -25.90419)
			(xy 142.766688 -25.946879) (xy 142.757127 -26.031722) (xy 142.738167 -26.114969) (xy 142.710046 -26.195584)
			(xy 142.673113 -26.272562) (xy 142.650972 -26.309066) (xy 142.646288 -26.317332) (xy 142.642779 -26.335991)
			(xy 142.646281 -26.354652) (xy 142.650972 -26.362914) (xy 142.673117 -26.399417) (xy 142.710064 -26.47639)
			(xy 142.738192 -26.557004) (xy 142.755942 -26.634948) (xy 175.442372 -26.634948) (xy 175.442817 -26.593237)
			(xy 175.450618 -26.510181) (xy 175.466165 -26.428221) (xy 175.489321 -26.348077) (xy 175.519883 -26.270455)
			(xy 175.557582 -26.196038) (xy 175.602086 -26.125479) (xy 175.653004 -26.059399) (xy 175.709888 -25.99838)
			(xy 175.772239 -25.942957) (xy 175.805592 -25.917906) (xy 175.814178 -25.911009) (xy 175.82483 -25.891756)
			(xy 175.826166 -25.880822) (xy 175.829855 -25.839448) (xy 175.843941 -25.757582) (xy 175.865598 -25.677385)
			(xy 175.894637 -25.599556) (xy 175.930804 -25.524774) (xy 175.973785 -25.453688) (xy 176.023205 -25.386918)
			(xy 176.078634 -25.325046) (xy 176.13959 -25.268611) (xy 176.205541 -25.218103) (xy 176.275913 -25.173964)
			(xy 176.350094 -25.136576) (xy 176.427436 -25.106267) (xy 176.507267 -25.083299) (xy 176.588892 -25.067873)
			(xy 176.671599 -25.060123) (xy 176.713134 -25.05964) (xy 176.713642 -25.05964) (xy 176.757406 -25.060139)
			(xy 176.844513 -25.068717) (xy 176.930355 -25.085818) (xy 177.0141 -25.111273) (xy 177.094937 -25.144838)
			(xy 177.133758 -25.16505) (xy 177.145111 -25.170377) (xy 177.170157 -25.170377) (xy 177.18151 -25.16505)
			(xy 177.22038 -25.144826) (xy 177.301322 -25.111257) (xy 177.38517 -25.085803) (xy 177.471113 -25.068709)
			(xy 177.55832 -25.060143) (xy 177.602134 -25.05964) (xy 177.645949 -25.060116) (xy 177.733161 -25.068665)
			(xy 177.819109 -25.085756) (xy 177.902957 -25.111222) (xy 177.983891 -25.144816) (xy 178.022758 -25.16505)
			(xy 178.034111 -25.170377) (xy 178.059157 -25.170377) (xy 178.07051 -25.16505) (xy 178.10938 -25.144826)
			(xy 178.190322 -25.111257) (xy 178.27417 -25.085803) (xy 178.360113 -25.068709) (xy 178.44732 -25.060143)
			(xy 178.491134 -25.05964) (xy 178.541288 -25.060291) (xy 178.640969 -25.071493) (xy 178.690016 -25.081992)
			(xy 178.700529 -25.083816) (xy 178.72144 -25.079687) (xy 178.7389 -25.067462) (xy 178.74488 -25.058624)
			(xy 178.766746 -25.023211) (xy 178.816155 -24.956227) (xy 178.871604 -24.894151) (xy 178.932608 -24.837525)
			(xy 178.998633 -24.786843) (xy 179.069104 -24.742549) (xy 179.143403 -24.705031) (xy 179.220882 -24.674615)
			(xy 179.300862 -24.651569) (xy 179.382645 -24.636093) (xy 179.465517 -24.628322) (xy 179.507134 -24.62784)
			(xy 179.549484 -24.628249) (xy 179.633799 -24.636303) (xy 179.716968 -24.652336) (xy 179.798236 -24.676201)
			(xy 179.876867 -24.707683) (xy 179.95215 -24.746496) (xy 180.023403 -24.79229) (xy 180.08998 -24.844649)
			(xy 180.151278 -24.9031) (xy 180.206744 -24.967112) (xy 180.255873 -25.036107) (xy 180.298222 -25.10946)
			(xy 180.333407 -25.186506) (xy 180.361109 -25.266547) (xy 180.381077 -25.348859) (xy 180.39313 -25.432696)
			(xy 180.397161 -25.5173) (xy 180.39313 -25.601904) (xy 180.381077 -25.685741) (xy 180.361109 -25.768053)
			(xy 180.333407 -25.848094) (xy 180.298222 -25.92514) (xy 180.255873 -25.998493) (xy 180.206744 -26.067488)
			(xy 180.151278 -26.1315) (xy 180.08998 -26.189951) (xy 180.023403 -26.24231) (xy 179.95215 -26.288104)
			(xy 179.876867 -26.326917) (xy 179.798236 -26.358399) (xy 179.716968 -26.382264) (xy 179.633799 -26.398297)
			(xy 179.549484 -26.406351) (xy 179.507134 -26.406856) (xy 179.505864 -26.406856) (xy 179.456029 -26.406131)
			(xy 179.35699 -26.394927) (xy 179.308252 -26.384504) (xy 179.297742 -26.382653) (xy 179.276827 -26.386794)
			(xy 179.259367 -26.39903) (xy 179.253388 -26.407872) (xy 179.230217 -26.445289) (xy 179.177598 -26.515842)
			(xy 179.118275 -26.58086) (xy 179.052827 -26.639708) (xy 179.017676 -26.66619) (xy 179.009104 -26.673102)
			(xy 178.998441 -26.692343) (xy 178.997102 -26.703274) (xy 178.993441 -26.744651) (xy 178.979354 -26.826519)
			(xy 178.957697 -26.906717) (xy 178.928657 -26.984547) (xy 178.892489 -27.059331) (xy 178.849506 -27.130418)
			(xy 178.835198 -27.149749) (xy 180.032656 -27.149749) (xy 180.032656 -27.065027) (xy 180.040709 -26.98069)
			(xy 180.056743 -26.8975) (xy 180.080611 -26.81621) (xy 180.112099 -26.737558) (xy 180.150921 -26.662255)
			(xy 180.196724 -26.590983) (xy 180.249095 -26.524387) (xy 180.30756 -26.463072) (xy 180.371588 -26.407591)
			(xy 180.4406 -26.358448) (xy 180.51397 -26.316088) (xy 180.591035 -26.280893) (xy 180.671097 -26.253184)
			(xy 180.75343 -26.23321) (xy 180.837289 -26.221153) (xy 180.921914 -26.217122) (xy 181.006539 -26.221153)
			(xy 181.090398 -26.23321) (xy 181.172731 -26.253184) (xy 181.252793 -26.280893) (xy 181.329858 -26.316088)
			(xy 181.403228 -26.358448) (xy 181.47224 -26.407591) (xy 181.536268 -26.463072) (xy 181.594733 -26.524387)
			(xy 181.647104 -26.590983) (xy 181.692907 -26.662255) (xy 181.731729 -26.737558) (xy 181.763217 -26.81621)
			(xy 181.787085 -26.8975) (xy 181.803119 -26.98069) (xy 181.811172 -27.065027) (xy 181.811676 -27.107388)
			(xy 181.811172 -27.149749) (xy 181.803119 -27.234086) (xy 181.787085 -27.317276) (xy 181.763217 -27.398566)
			(xy 181.731729 -27.477218) (xy 181.692907 -27.552521) (xy 181.647104 -27.623793) (xy 181.594733 -27.690389)
			(xy 181.536268 -27.751704) (xy 181.47224 -27.807185) (xy 181.403228 -27.856328) (xy 181.329858 -27.898688)
			(xy 181.252793 -27.933883) (xy 181.172731 -27.961592) (xy 181.090398 -27.981566) (xy 181.006539 -27.993623)
			(xy 180.921914 -27.997655) (xy 180.837289 -27.993623) (xy 180.75343 -27.981566) (xy 180.671097 -27.961592)
			(xy 180.591035 -27.933883) (xy 180.51397 -27.898688) (xy 180.4406 -27.856328) (xy 180.371588 -27.807185)
			(xy 180.30756 -27.751704) (xy 180.249095 -27.690389) (xy 180.196724 -27.623793) (xy 180.150921 -27.552521)
			(xy 180.112099 -27.477218) (xy 180.080611 -27.398566) (xy 180.056743 -27.317276) (xy 180.040709 -27.234086)
			(xy 180.032656 -27.149749) (xy 178.835198 -27.149749) (xy 178.800084 -27.197189) (xy 178.744653 -27.259061)
			(xy 178.683695 -27.315497) (xy 178.617742 -27.366004) (xy 178.547367 -27.410143) (xy 178.473184 -27.447529)
			(xy 178.395839 -27.477837) (xy 178.316006 -27.500803) (xy 178.234379 -27.516227) (xy 178.15167 -27.523974)
			(xy 178.110134 -27.524456) (xy 178.109626 -27.524456) (xy 178.065862 -27.523929) (xy 177.978756 -27.515357)
			(xy 177.892915 -27.498263) (xy 177.809169 -27.472814) (xy 177.728331 -27.439255) (xy 177.68951 -27.419046)
			(xy 177.678157 -27.413719) (xy 177.653111 -27.413719) (xy 177.641758 -27.419046) (xy 177.602894 -27.439282)
			(xy 177.521951 -27.472849) (xy 177.438101 -27.498301) (xy 177.352156 -27.515391) (xy 177.264948 -27.523955)
			(xy 177.221134 -27.524456) (xy 177.177318 -27.523994) (xy 177.090106 -27.515442) (xy 177.004158 -27.498348)
			(xy 176.920311 -27.472879) (xy 176.839376 -27.439281) (xy 176.80051 -27.419046) (xy 176.789157 -27.413719)
			(xy 176.764111 -27.413719) (xy 176.752758 -27.419046) (xy 176.713921 -27.439222) (xy 176.633081 -27.472767)
			(xy 176.549339 -27.498216) (xy 176.463504 -27.515325) (xy 176.376404 -27.523927) (xy 176.332642 -27.524456)
			(xy 176.332134 -27.524456) (xy 176.291028 -27.523955) (xy 176.209165 -27.516374) (xy 176.128351 -27.501273)
			(xy 176.049275 -27.47878) (xy 175.972611 -27.449089) (xy 175.899013 -27.412452) (xy 175.829109 -27.369181)
			(xy 175.763495 -27.319646) (xy 175.702731 -27.264268) (xy 175.647335 -27.203522) (xy 175.597779 -27.137923)
			(xy 175.554486 -27.068033) (xy 175.517825 -26.994447) (xy 175.488109 -26.917792) (xy 175.465592 -26.838723)
			(xy 175.450465 -26.757914) (xy 175.442858 -26.676054) (xy 175.442372 -26.634948) (xy 142.755942 -26.634948)
			(xy 142.75715 -26.640254) (xy 142.7667 -26.7251) (xy 142.767304 -26.76779) (xy 142.767243 -26.781773)
			(xy 142.766226 -26.80972) (xy 142.765272 -26.82367) (xy 142.764947 -26.832178) (xy 142.769236 -26.848641)
			(xy 142.778724 -26.862761) (xy 142.785338 -26.86812) (xy 142.808723 -26.886274) (xy 142.850119 -26.928594)
			(xy 142.884492 -26.976793) (xy 142.911018 -27.029717) (xy 142.929064 -27.086099) (xy 142.938197 -27.14459)
			(xy 142.938754 -27.17419) (xy 142.938289 -27.201461) (xy 142.930528 -27.255448) (xy 142.915163 -27.307782)
			(xy 142.892506 -27.357395) (xy 142.863018 -27.403279) (xy 142.827301 -27.4445) (xy 142.786081 -27.480217)
			(xy 142.740197 -27.509705) (xy 142.690583 -27.532362) (xy 142.63825 -27.547728) (xy 142.584263 -27.555489)
			(xy 142.556992 -27.555952) (xy 142.527164 -27.555371) (xy 142.468235 -27.546096) (xy 142.411468 -27.527758)
			(xy 142.35825 -27.500804) (xy 142.333726 -27.483816) (xy 142.326655 -27.479026) (xy 142.310312 -27.474099)
			(xy 142.293258 -27.474852) (xy 142.285212 -27.47772) (xy 142.251526 -27.490621) (xy 142.182266 -27.510792)
			(xy 142.111411 -27.524342) (xy 142.039595 -27.531148) (xy 142.003526 -27.531568) (xy 141.963525 -27.531048)
			(xy 141.88396 -27.522688) (xy 141.805705 -27.506056) (xy 141.729618 -27.481336) (xy 141.656531 -27.448798)
			(xy 141.587246 -27.408798) (xy 141.522522 -27.361775) (xy 141.463068 -27.308243) (xy 141.409536 -27.24879)
			(xy 141.362511 -27.184067) (xy 141.322509 -27.114783) (xy 141.28997 -27.041697) (xy 141.265248 -26.96561)
			(xy 141.248615 -26.887356) (xy 141.240253 -26.807791) (xy 141.239748 -26.76779) (xy 131.832807 -26.76779)
			(xy 131.832301 -26.805585) (xy 131.823244 -26.888302) (xy 131.805244 -26.969543) (xy 131.778517 -27.048345)
			(xy 131.743379 -27.123773) (xy 131.700246 -27.194932) (xy 131.675378 -27.228292) (xy 131.669056 -27.237502)
			(xy 131.664224 -27.259284) (xy 131.669043 -27.281068) (xy 131.675378 -27.290268) (xy 131.700235 -27.323635)
			(xy 131.743351 -27.394801) (xy 131.778481 -27.470229) (xy 131.805207 -27.549028) (xy 131.823214 -27.630264)
			(xy 131.832289 -27.712976) (xy 131.832858 -27.75458) (xy 131.832379 -27.793406) (xy 131.824487 -27.870655)
			(xy 131.808794 -27.946704) (xy 131.785461 -28.020766) (xy 131.754729 -28.092077) (xy 131.716917 -28.1599)
			(xy 131.672414 -28.223533) (xy 131.621681 -28.28232) (xy 131.565242 -28.335652) (xy 131.50368 -28.382979)
			(xy 131.470908 -28.403804) (xy 131.461593 -28.410241) (xy 131.449333 -28.429243) (xy 131.447286 -28.44038)
			(xy 131.443162 -28.467509) (xy 131.428143 -28.520286) (xy 131.405719 -28.570368) (xy 131.376353 -28.616722)
			(xy 131.34065 -28.658391) (xy 131.299347 -28.694518) (xy 131.253295 -28.724355) (xy 131.203445 -28.747289)
			(xy 131.150824 -28.762846) (xy 131.096516 -28.770706) (xy 131.041644 -28.770706) (xy 130.987336 -28.762846)
			(xy 130.934715 -28.747289) (xy 130.884865 -28.724355) (xy 130.838813 -28.694518) (xy 130.79751 -28.658391)
			(xy 130.761807 -28.616722) (xy 130.732441 -28.570368) (xy 130.710017 -28.520286) (xy 130.694998 -28.467509)
			(xy 130.690874 -28.44038) (xy 130.688761 -28.42927) (xy 130.676513 -28.410293) (xy 130.667252 -28.403804)
			(xy 130.634476 -28.382985) (xy 130.572909 -28.335663) (xy 130.516465 -28.282333) (xy 130.465729 -28.223547)
			(xy 130.421224 -28.159913) (xy 130.383412 -28.092089) (xy 130.352682 -28.020775) (xy 130.329353 -27.946709)
			(xy 130.313665 -27.870658) (xy 130.305782 -27.793406) (xy 130.305302 -27.75458) (xy 64.905217 -27.75458)
			(xy 64.965111 -27.798302) (xy 65.023573 -27.851021) (xy 65.076293 -27.909483) (xy 65.122709 -27.973065)
			(xy 65.162327 -28.041091) (xy 65.194727 -28.112836) (xy 65.219562 -28.187538) (xy 65.236568 -28.264401)
			(xy 65.245565 -28.342607) (xy 65.246504 -28.38196) (xy 65.246504 -28.382214) (xy 65.247086 -28.392076)
			(xy 65.254807 -28.410243) (xy 65.26149 -28.41752) (xy 66.511424 -29.667454) (xy 66.518827 -29.674291)
			(xy 66.537424 -29.682014) (xy 66.547492 -29.68244) (xy 100.466398 -29.68244) (xy 100.477293 -29.681941)
			(xy 100.497163 -29.673001) (xy 100.504752 -29.665168) (xy 100.56241 -29.599382) (xy 100.56876 -29.578554)
			(xy 100.567236 -29.567886) (xy 100.565793 -29.555682) (xy 100.564265 -29.531153) (xy 100.564188 -29.518864)
			(xy 100.564188 -29.51861) (xy 100.564657 -29.491321) (xy 100.572423 -29.437298) (xy 100.587798 -29.38493)
			(xy 100.61047 -29.335284) (xy 100.639977 -29.28937) (xy 100.675718 -29.248122) (xy 100.716965 -29.21238)
			(xy 100.762879 -29.182873) (xy 100.812525 -29.160201) (xy 100.864892 -29.144824) (xy 100.918915 -29.137057)
			(xy 100.946204 -29.136594) (xy 100.961574 -29.136723) (xy 100.992218 -29.13914) (xy 101.007418 -29.14142)
			(xy 101.017368 -29.142597) (xy 101.036861 -29.13804) (xy 101.053109 -29.126347) (xy 101.058726 -29.118052)
			(xy 101.062028 -29.112972) (xy 101.066703 -29.104697) (xy 101.070243 -29.086041) (xy 101.066733 -29.06738)
			(xy 101.062028 -29.059124) (xy 101.039958 -29.022679) (xy 101.003136 -28.945843) (xy 100.975118 -28.865377)
			(xy 100.956254 -28.782288) (xy 100.946779 -28.697612) (xy 100.946204 -28.65501) (xy 100.946693 -28.616391)
			(xy 100.954507 -28.539548) (xy 100.970055 -28.46389) (xy 100.993178 -28.390193) (xy 101.023637 -28.319214)
			(xy 101.061122 -28.25168) (xy 101.105246 -28.188286) (xy 101.155557 -28.12968) (xy 101.211539 -28.076465)
			(xy 101.272618 -28.029186) (xy 101.338166 -27.98833) (xy 101.407512 -27.954314) (xy 101.479943 -27.927489)
			(xy 101.554716 -27.908129) (xy 101.631064 -27.896433) (xy 101.708204 -27.892521) (xy 101.785344 -27.896433)
			(xy 101.861692 -27.908129) (xy 101.936465 -27.927489) (xy 102.008896 -27.954314) (xy 102.078242 -27.98833)
			(xy 102.14379 -28.029186) (xy 102.204869 -28.076465) (xy 102.260851 -28.12968) (xy 102.311162 -28.188286)
			(xy 102.355286 -28.25168) (xy 102.392771 -28.319214) (xy 102.42323 -28.390193) (xy 102.446353 -28.46389)
			(xy 102.461901 -28.539548) (xy 102.469715 -28.616391) (xy 102.470204 -28.65501) (xy 102.469602 -28.697611)
			(xy 102.460116 -28.782282) (xy 102.441253 -28.865369) (xy 102.413247 -28.945836) (xy 102.376448 -29.02268)
			(xy 102.35438 -29.059124) (xy 102.349626 -29.067361) (xy 102.346112 -29.086041) (xy 102.349656 -29.104716)
			(xy 102.35438 -29.112972) (xy 102.376649 -29.149509) (xy 102.413779 -29.226602) (xy 102.442039 -29.307369)
			(xy 102.461076 -29.390794) (xy 102.470648 -29.475826) (xy 102.47122 -29.51861) (xy 102.47122 -29.519118)
			(xy 102.471151 -29.532974) (xy 102.470135 -29.560667) (xy 102.469188 -29.57449) (xy 102.468426 -29.584904)
			(xy 102.475284 -29.605224) (xy 102.532434 -29.666184) (xy 102.539938 -29.673472) (xy 102.559073 -29.68187)
			(xy 102.569518 -29.68244) (xy 121.488962 -29.68244) (xy 121.493646 -29.682274) (xy 121.502845 -29.680486)
			(xy 121.50725 -29.678884) (xy 121.540384 -29.666454) (xy 121.608439 -29.647034) (xy 121.678 -29.633999)
			(xy 121.74847 -29.627461) (xy 121.783856 -29.627068) (xy 121.784364 -29.627068) (xy 121.819751 -29.627448)
			(xy 121.890224 -29.633972) (xy 121.959788 -29.647004) (xy 122.027844 -29.666431) (xy 122.06097 -29.678884)
			(xy 122.065365 -29.680523) (xy 122.074569 -29.682317) (xy 122.079258 -29.68244) (xy 135.138414 -29.68244)
			(xy 135.150953 -29.681743) (xy 135.173061 -29.669894) (xy 135.180578 -29.659834) (xy 135.23468 -29.578554)
			(xy 135.236966 -29.553154) (xy 135.231886 -29.541216) (xy 135.217333 -29.505814) (xy 135.1946 -29.432719)
			(xy 135.17932 -29.357711) (xy 135.171647 -29.281548) (xy 135.17118 -29.243274) (xy 135.17118 -29.242512)
			(xy 135.17174 -29.201073) (xy 135.180776 -29.118689) (xy 135.198698 -29.037772) (xy 135.225295 -28.959278)
			(xy 135.260253 -28.884134) (xy 135.303159 -28.813227) (xy 135.327898 -28.779978) (xy 135.334286 -28.770792)
			(xy 135.339055 -28.748953) (xy 135.334075 -28.727161) (xy 135.327644 -28.718002) (xy 135.302658 -28.684572)
			(xy 135.259316 -28.613246) (xy 135.224005 -28.53762) (xy 135.197146 -28.458597) (xy 135.17906 -28.377117)
			(xy 135.169962 -28.294151) (xy 135.169402 -28.25242) (xy 135.169853 -28.213594) (xy 135.177745 -28.136343)
			(xy 135.19344 -28.060292) (xy 135.216775 -27.986228) (xy 135.247509 -27.914916) (xy 135.285325 -27.847093)
			(xy 135.329831 -27.78346) (xy 135.380568 -27.724674) (xy 135.437012 -27.671344) (xy 135.498578 -27.624019)
			(xy 135.531352 -27.603196) (xy 135.540659 -27.596749) (xy 135.552925 -27.577755) (xy 135.554974 -27.56662)
			(xy 135.559098 -27.539491) (xy 135.574117 -27.486714) (xy 135.596541 -27.436632) (xy 135.625907 -27.390278)
			(xy 135.66161 -27.348609) (xy 135.702913 -27.312482) (xy 135.748965 -27.282645) (xy 135.798815 -27.259711)
			(xy 135.851436 -27.244154) (xy 135.905744 -27.236294) (xy 135.960616 -27.236294) (xy 136.014924 -27.244154)
			(xy 136.067545 -27.259711) (xy 136.117395 -27.282645) (xy 136.163447 -27.312482) (xy 136.20475 -27.348609)
			(xy 136.240453 -27.390278) (xy 136.269819 -27.436632) (xy 136.292243 -27.486714) (xy 136.307262 -27.539491)
			(xy 136.311386 -27.56662) (xy 136.313514 -27.577726) (xy 136.325752 -27.596704) (xy 136.335008 -27.603196)
			(xy 136.367775 -27.62403) (xy 136.429344 -27.671349) (xy 136.485788 -27.724676) (xy 136.536526 -27.78346)
			(xy 136.581032 -27.847092) (xy 136.618846 -27.914915) (xy 136.649576 -27.986228) (xy 136.672906 -28.060292)
			(xy 136.688594 -28.136343) (xy 136.696478 -28.213594) (xy 136.696958 -28.25242) (xy 136.696407 -28.294152)
			(xy 136.687308 -28.377118) (xy 136.669221 -28.458598) (xy 136.642361 -28.537622) (xy 136.607048 -28.613247)
			(xy 136.563703 -28.684573) (xy 136.538716 -28.718002) (xy 136.532387 -28.727202) (xy 136.527467 -28.748953)
			(xy 136.532179 -28.77075) (xy 136.538462 -28.779978) (xy 136.563182 -28.813239) (xy 136.606075 -28.88415)
			(xy 136.641026 -28.959294) (xy 136.667623 -29.037784) (xy 136.671001 -29.053028) (xy 139.446508 -29.053028)
			(xy 139.447064 -29.023199) (xy 139.456347 -28.964269) (xy 139.474693 -28.907503) (xy 139.501653 -28.854285)
			(xy 139.518644 -28.829762) (xy 139.523407 -28.822675) (xy 139.528346 -28.806341) (xy 139.527603 -28.789292)
			(xy 139.52474 -28.781248) (xy 139.511818 -28.74757) (xy 139.491652 -28.678306) (xy 139.478109 -28.60745)
			(xy 139.471309 -28.535632) (xy 139.470892 -28.499562) (xy 139.471409 -28.459562) (xy 139.479775 -28.38)
			(xy 139.496411 -28.301748) (xy 139.521135 -28.225664) (xy 139.553676 -28.152581) (xy 139.593678 -28.0833)
			(xy 139.640702 -28.018579) (xy 139.694233 -27.959127) (xy 139.753685 -27.905597) (xy 139.818406 -27.858573)
			(xy 139.887688 -27.818572) (xy 139.960772 -27.786032) (xy 140.036856 -27.761309) (xy 140.115108 -27.744674)
			(xy 140.19467 -27.736309) (xy 140.23467 -27.735784) (xy 140.277359 -27.736411) (xy 140.362201 -27.74597)
			(xy 140.445448 -27.764927) (xy 140.526064 -27.793046) (xy 140.603042 -27.829976) (xy 140.639546 -27.852116)
			(xy 140.647807 -27.856812) (xy 140.66647 -27.86032) (xy 140.685133 -27.856812) (xy 140.693394 -27.852116)
			(xy 140.729901 -27.829978) (xy 140.806873 -27.79303) (xy 140.887486 -27.7649) (xy 140.970735 -27.745941)
			(xy 141.05558 -27.736389) (xy 141.09827 -27.735784) (xy 141.138269 -27.736374) (xy 141.217828 -27.744733)
			(xy 141.296078 -27.761362) (xy 141.372161 -27.786079) (xy 141.445243 -27.818614) (xy 141.514525 -27.85861)
			(xy 141.579246 -27.905628) (xy 141.638698 -27.959154) (xy 141.692229 -28.018601) (xy 141.739253 -28.083318)
			(xy 141.779255 -28.152596) (xy 141.811796 -28.225676) (xy 141.836521 -28.301756) (xy 141.853157 -28.380005)
			(xy 141.861523 -28.459563) (xy 141.862048 -28.499562) (xy 141.862048 -28.50007) (xy 141.861621 -28.536481)
			(xy 141.854686 -28.608973) (xy 141.840884 -28.680477) (xy 141.820342 -28.750342) (xy 141.807184 -28.784296)
			(xy 141.804312 -28.792269) (xy 141.803449 -28.809183) (xy 141.808151 -28.825453) (xy 141.812772 -28.832556)
			(xy 141.829332 -28.856852) (xy 141.85553 -28.90949) (xy 141.873341 -28.965525) (xy 141.882343 -29.023629)
			(xy 141.882876 -29.053028) (xy 141.882402 -29.080297) (xy 141.874637 -29.134281) (xy 141.859268 -29.18661)
			(xy 141.83661 -29.236219) (xy 141.807122 -29.282099) (xy 141.771406 -29.323316) (xy 141.730188 -29.359031)
			(xy 141.684307 -29.388517) (xy 141.634696 -29.411173) (xy 141.582367 -29.42654) (xy 141.528383 -29.434303)
			(xy 141.501114 -29.43479) (xy 141.471546 -29.434252) (xy 141.41312 -29.425115) (xy 141.356798 -29.407089)
			(xy 141.303925 -29.380603) (xy 141.255762 -29.34629) (xy 141.213458 -29.304969) (xy 141.195298 -29.281628)
			(xy 141.187038 -29.271911) (xy 141.163853 -29.261372) (xy 141.151102 -29.261562) (xy 141.098524 -29.26334)
			(xy 141.09827 -29.26334) (xy 141.05558 -29.262752) (xy 140.970736 -29.253186) (xy 140.887488 -29.234221)
			(xy 140.806873 -29.206093) (xy 140.729897 -29.169153) (xy 140.693394 -29.147008) (xy 140.685133 -29.142312)
			(xy 140.66647 -29.138804) (xy 140.647807 -29.142312) (xy 140.639546 -29.147008) (xy 140.603055 -29.169173)
			(xy 140.526079 -29.206116) (xy 140.445461 -29.23424) (xy 140.362208 -29.253193) (xy 140.277361 -29.262738)
			(xy 140.23467 -29.26334) (xy 140.220687 -29.263281) (xy 140.19274 -29.262263) (xy 140.17879 -29.261308)
			(xy 140.170281 -29.26094) (xy 140.153814 -29.265245) (xy 140.139695 -29.274751) (xy 140.13434 -29.281374)
			(xy 140.116192 -29.304765) (xy 140.073873 -29.346163) (xy 140.025673 -29.380537) (xy 139.972748 -29.407064)
			(xy 139.916363 -29.425107) (xy 139.857871 -29.434236) (xy 139.82827 -29.43479) (xy 139.801001 -29.434304)
			(xy 139.747019 -29.426539) (xy 139.694691 -29.411171) (xy 139.645083 -29.388513) (xy 139.599203 -29.359027)
			(xy 139.557987 -29.323312) (xy 139.522272 -29.282095) (xy 139.492786 -29.236215) (xy 139.470129 -29.186607)
			(xy 139.454761 -29.134279) (xy 139.446996 -29.080297) (xy 139.446508 -29.053028) (xy 136.671001 -29.053028)
			(xy 136.685552 -29.118696) (xy 136.694602 -29.201075) (xy 136.69518 -29.242512) (xy 136.69518 -29.243274)
			(xy 136.694686 -29.281546) (xy 136.686994 -29.357703) (xy 136.671714 -29.432708) (xy 136.649001 -29.505805)
			(xy 136.634474 -29.541216) (xy 136.630152 -29.553113) (xy 136.632409 -29.578292) (xy 136.638792 -29.589222)
			(xy 136.685782 -29.659834) (xy 136.693293 -29.669909) (xy 136.715399 -29.681784) (xy 136.727946 -29.68244)
			(xy 144.898364 -29.68244) (xy 144.90446 -29.680916) (xy 144.927504 -29.675447) (xy 144.974504 -29.669589)
			(xy 144.998186 -29.669232) (xy 144.998694 -29.669232) (xy 145.022376 -29.669587) (xy 145.069376 -29.675445)
			(xy 145.09242 -29.680916) (xy 145.098516 -29.68244) (xy 156.526738 -29.68244) (xy 156.531555 -29.682354)
			(xy 156.54102 -29.680567) (xy 156.545534 -29.678884) (xy 156.578906 -29.666207) (xy 156.647503 -29.646423)
			(xy 156.717649 -29.633137) (xy 156.78873 -29.626467) (xy 156.824426 -29.626052) (xy 156.824934 -29.626052)
			(xy 156.860631 -29.626452) (xy 156.931711 -29.633129) (xy 157.001856 -29.646421) (xy 157.070451 -29.666213)
			(xy 157.103826 -29.678884) (xy 157.108355 -29.680515) (xy 157.11781 -29.682313) (xy 157.122622 -29.68244)
			(xy 171.321476 -29.68244) (xy 171.333438 -29.681726) (xy 171.354766 -29.670872) (xy 171.36237 -29.661612)
			(xy 171.41825 -29.585666) (xy 171.42206 -29.562044) (xy 171.41825 -29.550106) (xy 171.406903 -29.512682)
			(xy 171.390976 -29.436115) (xy 171.38295 -29.358323) (xy 171.382436 -29.31922) (xy 171.382436 -29.318712)
			(xy 171.382925 -29.280041) (xy 171.39075 -29.203096) (xy 171.406319 -29.127337) (xy 171.429472 -29.053542)
			(xy 171.459972 -28.982468) (xy 171.497507 -28.914845) (xy 171.54169 -28.851365) (xy 171.592068 -28.792681)
			(xy 171.648125 -28.739395) (xy 171.709285 -28.692054) (xy 171.774921 -28.651143) (xy 171.844359 -28.617082)
			(xy 171.916886 -28.59022) (xy 171.991759 -28.570835) (xy 172.068209 -28.559123) (xy 172.145452 -28.555206)
			(xy 172.222695 -28.559123) (xy 172.299145 -28.570835) (xy 172.374018 -28.59022) (xy 172.446545 -28.617082)
			(xy 172.515983 -28.651143) (xy 172.581619 -28.692054) (xy 172.642779 -28.739395) (xy 172.698836 -28.792681)
			(xy 172.749214 -28.851365) (xy 172.793397 -28.914845) (xy 172.830932 -28.982468) (xy 172.861432 -29.053542)
			(xy 172.884585 -29.127337) (xy 172.900154 -29.203096) (xy 172.907979 -29.280041) (xy 172.908468 -29.318712)
			(xy 172.908468 -29.318966) (xy 172.907987 -29.358113) (xy 172.899989 -29.435997) (xy 172.884041 -29.512649)
			(xy 172.872654 -29.550106) (xy 172.869578 -29.561748) (xy 172.873438 -29.585486) (xy 172.88002 -29.595572)
			(xy 172.92828 -29.661612) (xy 172.935912 -29.670949) (xy 172.957386 -29.681834) (xy 172.969428 -29.68244)
			(xy 174.12208 -29.68244) (xy 174.12823 -29.682243) (xy 174.14017 -29.679292) (xy 174.145702 -29.676598)
			(xy 174.178371 -29.660093) (xy 174.246245 -29.632686) (xy 174.316431 -29.611905) (xy 174.388286 -29.597943)
			(xy 174.461147 -29.590926) (xy 174.497746 -29.590492) (xy 174.498254 -29.590492) (xy 174.534854 -29.590917)
			(xy 174.607718 -29.597921) (xy 174.679575 -29.61188) (xy 174.749762 -29.632664) (xy 174.817633 -29.660083)
			(xy 174.850298 -29.676598) (xy 174.855823 -29.679312) (xy 174.867767 -29.682269) (xy 174.87392 -29.68244)
			(xy 177.249328 -29.68244) (xy 177.2594 -29.68284) (xy 177.277998 -29.690577) (xy 177.285396 -29.697426)
			(xy 177.72177 -30.1338) (xy 197.595716 -30.1338) (xy 197.599747 -30.049172) (xy 197.611805 -29.965311)
			(xy 197.631779 -29.882976) (xy 197.65949 -29.802912) (xy 197.694686 -29.725844) (xy 197.737048 -29.652472)
			(xy 197.786193 -29.583458) (xy 197.841676 -29.519429) (xy 197.902994 -29.460963) (xy 197.969592 -29.408591)
			(xy 198.040866 -29.362787) (xy 198.116172 -29.323965) (xy 198.194827 -29.292477) (xy 198.276119 -29.268609)
			(xy 198.359312 -29.252576) (xy 198.443652 -29.244524) (xy 198.486014 -29.244036) (xy 198.524304 -29.244437)
			(xy 198.600598 -29.251046) (xy 198.676041 -29.264197) (xy 198.750071 -29.283791) (xy 198.786242 -29.29636)
			(xy 198.794679 -29.299011) (xy 198.812349 -29.299011) (xy 198.820786 -29.29636) (xy 198.856961 -29.283808)
			(xy 198.930995 -29.264238) (xy 199.006435 -29.251093) (xy 199.082726 -29.244471) (xy 199.121014 -29.244036)
			(xy 199.159304 -29.244437) (xy 199.235598 -29.251046) (xy 199.311041 -29.264197) (xy 199.385071 -29.283791)
			(xy 199.421242 -29.29636) (xy 199.429679 -29.299011) (xy 199.447349 -29.299011) (xy 199.455786 -29.29636)
			(xy 199.491961 -29.283808) (xy 199.565995 -29.264238) (xy 199.641435 -29.251093) (xy 199.717726 -29.244471)
			(xy 199.756014 -29.244036) (xy 199.794304 -29.244437) (xy 199.870598 -29.251046) (xy 199.946041 -29.264197)
			(xy 200.020071 -29.283791) (xy 200.056242 -29.29636) (xy 200.064679 -29.299011) (xy 200.082349 -29.299011)
			(xy 200.090786 -29.29636) (xy 200.126961 -29.283808) (xy 200.200995 -29.264238) (xy 200.276435 -29.251093)
			(xy 200.352726 -29.244471) (xy 200.391014 -29.244036) (xy 200.431702 -29.244422) (xy 200.512738 -29.251848)
			(xy 200.592757 -29.266645) (xy 200.67109 -29.288689) (xy 200.747082 -29.317797) (xy 200.820096 -29.353725)
			(xy 200.889524 -29.396173) (xy 200.954784 -29.444785) (xy 201.015331 -29.499155) (xy 201.070657 -29.558829)
			(xy 201.120302 -29.623307) (xy 201.163849 -29.69205) (xy 201.200934 -29.764484) (xy 201.216514 -29.802074)
			(xy 201.22098 -29.811942) (xy 201.236608 -29.826918) (xy 201.256995 -29.83419) (xy 201.267822 -29.833824)
			(xy 201.286077 -29.832403) (xy 201.322664 -29.83088) (xy 201.340974 -29.830776) (xy 201.383338 -29.831187)
			(xy 201.467682 -29.839239) (xy 201.550879 -29.855272) (xy 201.632176 -29.87914) (xy 201.710835 -29.910629)
			(xy 201.786145 -29.949452) (xy 201.857423 -29.995258) (xy 201.924025 -30.047632) (xy 201.985346 -30.1061)
			(xy 202.040832 -30.170132) (xy 202.08998 -30.239149) (xy 202.132344 -30.312525) (xy 202.167542 -30.389596)
			(xy 202.195254 -30.469663) (xy 202.21523 -30.552003) (xy 202.227288 -30.635868) (xy 202.23132 -30.7205)
			(xy 202.227288 -30.805132) (xy 202.21523 -30.888997) (xy 202.195254 -30.971337) (xy 202.167542 -31.051404)
			(xy 202.132344 -31.128475) (xy 202.08998 -31.201851) (xy 202.040832 -31.270868) (xy 201.985346 -31.3349)
			(xy 201.924025 -31.393368) (xy 201.857423 -31.445742) (xy 201.786145 -31.491548) (xy 201.710835 -31.530371)
			(xy 201.632176 -31.56186) (xy 201.550879 -31.585728) (xy 201.467682 -31.601761) (xy 201.383338 -31.609813)
			(xy 201.340974 -31.6103) (xy 201.302684 -31.609905) (xy 201.226389 -31.603295) (xy 201.150947 -31.590142)
			(xy 201.076917 -31.570546) (xy 201.040746 -31.557976) (xy 201.032309 -31.555325) (xy 201.014639 -31.555325)
			(xy 201.006202 -31.557976) (xy 200.970027 -31.570528) (xy 200.895993 -31.590099) (xy 200.820553 -31.603244)
			(xy 200.744262 -31.609866) (xy 200.705974 -31.6103) (xy 200.667684 -31.609905) (xy 200.591389 -31.603295)
			(xy 200.515947 -31.590142) (xy 200.441917 -31.570546) (xy 200.405746 -31.557976) (xy 200.397309 -31.555325)
			(xy 200.379639 -31.555325) (xy 200.371202 -31.557976) (xy 200.335027 -31.570528) (xy 200.260993 -31.590099)
			(xy 200.185553 -31.603244) (xy 200.109262 -31.609866) (xy 200.070974 -31.6103) (xy 200.032684 -31.609905)
			(xy 199.956389 -31.603295) (xy 199.880947 -31.590142) (xy 199.806917 -31.570546) (xy 199.770746 -31.557976)
			(xy 199.762309 -31.555325) (xy 199.744639 -31.555325) (xy 199.736202 -31.557976) (xy 199.700027 -31.570528)
			(xy 199.625993 -31.590099) (xy 199.550553 -31.603244) (xy 199.474262 -31.609866) (xy 199.435974 -31.6103)
			(xy 199.395288 -31.609814) (xy 199.314256 -31.602396) (xy 199.23424 -31.587608) (xy 199.15591 -31.565572)
			(xy 199.07992 -31.536472) (xy 199.006906 -31.500553) (xy 198.937478 -31.458114) (xy 198.872217 -31.40951)
			(xy 198.81167 -31.355148) (xy 198.756341 -31.295482) (xy 198.706694 -31.231012) (xy 198.663144 -31.162275)
			(xy 198.626056 -31.089848) (xy 198.610474 -31.052262) (xy 198.605924 -31.042441) (xy 198.590335 -31.027459)
			(xy 198.569982 -31.020164) (xy 198.559166 -31.020512) (xy 198.540911 -31.021927) (xy 198.504324 -31.023454)
			(xy 198.486014 -31.02356) (xy 198.443652 -31.023076) (xy 198.359312 -31.015024) (xy 198.276119 -30.998991)
			(xy 198.194827 -30.975123) (xy 198.116172 -30.943635) (xy 198.040866 -30.904813) (xy 197.969592 -30.859009)
			(xy 197.902994 -30.806637) (xy 197.841676 -30.748171) (xy 197.786193 -30.684142) (xy 197.737048 -30.615128)
			(xy 197.694686 -30.541756) (xy 197.65949 -30.464688) (xy 197.631779 -30.384624) (xy 197.611805 -30.302289)
			(xy 197.599747 -30.218428) (xy 197.595716 -30.1338) (xy 177.72177 -30.1338) (xy 178.749452 -31.161482)
			(xy 178.776376 -31.168594) (xy 178.78933 -31.164784) (xy 178.822909 -31.155741) (xy 178.891296 -31.143091)
			(xy 178.960551 -31.136732) (xy 178.995324 -31.136336) (xy 178.996086 -31.136336) (xy 179.036022 -31.13681)
			(xy 179.115457 -31.145158) (xy 179.193584 -31.161764) (xy 179.269547 -31.186445) (xy 179.342514 -31.218932)
			(xy 179.411685 -31.258869) (xy 179.476302 -31.305817) (xy 179.535658 -31.359263) (xy 179.589101 -31.418621)
			(xy 179.636047 -31.48324) (xy 179.675981 -31.552413) (xy 179.708465 -31.625381) (xy 179.733144 -31.701345)
			(xy 179.749747 -31.779473) (xy 179.758091 -31.858908) (xy 179.758594 -31.898844) (xy 179.758594 -31.899606)
			(xy 179.758172 -31.934378) (xy 179.751804 -32.00363) (xy 179.739166 -32.072016) (xy 179.730146 -32.1056)
			(xy 179.726336 -32.118554) (xy 179.733448 -32.145478) (xy 184.915973 -37.328094) (xy 197.270624 -37.328094)
			(xy 197.271107 -37.28698) (xy 197.278695 -37.205103) (xy 197.293804 -37.124275) (xy 197.316307 -37.045187)
			(xy 197.346011 -36.968512) (xy 197.382664 -36.894904) (xy 197.425951 -36.824993) (xy 197.475504 -36.759373)
			(xy 197.5309 -36.698606) (xy 197.591667 -36.643209) (xy 197.657286 -36.593655) (xy 197.727197 -36.550367)
			(xy 197.800804 -36.513715) (xy 197.877479 -36.48401) (xy 197.956568 -36.461506) (xy 198.037395 -36.446396)
			(xy 198.119272 -36.438808) (xy 198.160386 -36.438332) (xy 198.203952 -36.438853) (xy 198.290667 -36.447372)
			(xy 198.376134 -36.464329) (xy 198.459533 -36.489562) (xy 198.540065 -36.522829) (xy 198.616958 -36.563811)
			(xy 198.689475 -36.612116) (xy 198.756921 -36.66728) (xy 198.81865 -36.728775) (xy 198.87407 -36.796011)
			(xy 198.922649 -36.868345) (xy 198.963923 -36.945081) (xy 198.997496 -37.025486) (xy 199.010778 -37.066982)
			(xy 199.013703 -37.075249) (xy 199.024271 -37.089233) (xy 199.038923 -37.098854) (xy 199.047354 -37.101272)
			(xy 199.088321 -37.111837) (xy 199.168226 -37.13965) (xy 199.24513 -37.174922) (xy 199.318339 -37.217334)
			(xy 199.387193 -37.266504) (xy 199.451068 -37.321986) (xy 199.509389 -37.383281) (xy 199.529427 -37.408809)
			(xy 207.619596 -37.408809) (xy 207.619596 -37.324087) (xy 207.627649 -37.23975) (xy 207.643683 -37.15656)
			(xy 207.667551 -37.07527) (xy 207.699039 -36.996618) (xy 207.737861 -36.921315) (xy 207.783664 -36.850043)
			(xy 207.836035 -36.783447) (xy 207.8945 -36.722132) (xy 207.958528 -36.666651) (xy 208.02754 -36.617508)
			(xy 208.10091 -36.575148) (xy 208.177975 -36.539953) (xy 208.258037 -36.512244) (xy 208.34037 -36.49227)
			(xy 208.424229 -36.480213) (xy 208.508854 -36.476182) (xy 208.593479 -36.480213) (xy 208.677338 -36.49227)
			(xy 208.759671 -36.512244) (xy 208.839733 -36.539953) (xy 208.916798 -36.575148) (xy 208.990168 -36.617508)
			(xy 209.05918 -36.666651) (xy 209.123208 -36.722132) (xy 209.181673 -36.783447) (xy 209.234044 -36.850043)
			(xy 209.279847 -36.921315) (xy 209.318669 -36.996618) (xy 209.350157 -37.07527) (xy 209.374025 -37.15656)
			(xy 209.390059 -37.23975) (xy 209.398112 -37.324087) (xy 209.398616 -37.366448) (xy 209.398112 -37.408809)
			(xy 209.390059 -37.493146) (xy 209.374025 -37.576336) (xy 209.350157 -37.657626) (xy 209.318669 -37.736278)
			(xy 209.279847 -37.811581) (xy 209.234044 -37.882853) (xy 209.181673 -37.949449) (xy 209.123208 -38.010764)
			(xy 209.05918 -38.066245) (xy 208.990168 -38.115388) (xy 208.916798 -38.157748) (xy 208.839733 -38.192943)
			(xy 208.759671 -38.220652) (xy 208.677338 -38.240626) (xy 208.593479 -38.252683) (xy 208.508854 -38.256715)
			(xy 208.424229 -38.252683) (xy 208.34037 -38.240626) (xy 208.258037 -38.220652) (xy 208.177975 -38.192943)
			(xy 208.10091 -38.157748) (xy 208.02754 -38.115388) (xy 207.958528 -38.066245) (xy 207.8945 -38.010764)
			(xy 207.836035 -37.949449) (xy 207.783664 -37.882853) (xy 207.737861 -37.811581) (xy 207.699039 -37.736278)
			(xy 207.667551 -37.657626) (xy 207.643683 -37.576336) (xy 207.627649 -37.493146) (xy 207.619596 -37.408809)
			(xy 199.529427 -37.408809) (xy 199.561629 -37.449835) (xy 199.607316 -37.521047) (xy 199.646037 -37.596273)
			(xy 199.677444 -37.674835) (xy 199.701252 -37.756024) (xy 199.717247 -37.839106) (xy 199.725284 -37.92333)
			(xy 199.725788 -37.965634) (xy 199.72532 -38.006748) (xy 199.71773 -38.088625) (xy 199.702618 -38.169453)
			(xy 199.680113 -38.248541) (xy 199.650407 -38.325216) (xy 199.613754 -38.398823) (xy 199.570465 -38.468734)
			(xy 199.520911 -38.534353) (xy 199.465514 -38.595119) (xy 199.404746 -38.650516) (xy 199.339127 -38.70007)
			(xy 199.269216 -38.743357) (xy 199.195608 -38.78001) (xy 199.118933 -38.809716) (xy 199.039845 -38.83222)
			(xy 198.959017 -38.847331) (xy 198.87714 -38.85492) (xy 198.836026 -38.855396) (xy 198.792461 -38.854844)
			(xy 198.705747 -38.846327) (xy 198.620282 -38.829372) (xy 198.536884 -38.804141) (xy 198.456353 -38.770876)
			(xy 198.379461 -38.729896) (xy 198.306944 -38.681594) (xy 198.239498 -38.626432) (xy 198.177769 -38.56494)
			(xy 198.122348 -38.497707) (xy 198.073767 -38.425377) (xy 198.032492 -38.348643) (xy 197.998917 -38.26824)
			(xy 197.985634 -38.226746) (xy 197.982688 -38.218487) (xy 197.97213 -38.204501) (xy 197.957486 -38.194877)
			(xy 197.949058 -38.192456) (xy 197.908101 -38.181857) (xy 197.828197 -38.154046) (xy 197.751293 -38.118776)
			(xy 197.678085 -38.076367) (xy 197.609232 -38.0272) (xy 197.545356 -37.97172) (xy 197.487035 -37.910428)
			(xy 197.434795 -37.843877) (xy 197.389107 -37.772668) (xy 197.350384 -37.697444) (xy 197.318976 -37.618885)
			(xy 197.295165 -37.537699) (xy 197.279169 -37.454619) (xy 197.271129 -37.370397) (xy 197.270624 -37.328094)
			(xy 184.915973 -37.328094) (xy 187.011125 -39.423283) (xy 254.45872 -39.423283) (xy 254.45872 -39.338561)
			(xy 254.466773 -39.254224) (xy 254.482807 -39.171034) (xy 254.506675 -39.089744) (xy 254.538163 -39.011092)
			(xy 254.576985 -38.935789) (xy 254.622788 -38.864517) (xy 254.675159 -38.797921) (xy 254.733624 -38.736606)
			(xy 254.797652 -38.681125) (xy 254.866664 -38.631982) (xy 254.940034 -38.589622) (xy 255.017099 -38.554427)
			(xy 255.097161 -38.526718) (xy 255.179494 -38.506744) (xy 255.263353 -38.494687) (xy 255.347978 -38.490656)
			(xy 255.432603 -38.494687) (xy 255.516462 -38.506744) (xy 255.598795 -38.526718) (xy 255.678857 -38.554427)
			(xy 255.755922 -38.589622) (xy 255.829292 -38.631982) (xy 255.898304 -38.681125) (xy 255.962332 -38.736606)
			(xy 256.020797 -38.797921) (xy 256.073168 -38.864517) (xy 256.118971 -38.935789) (xy 256.157793 -39.011092)
			(xy 256.189281 -39.089744) (xy 256.213149 -39.171034) (xy 256.229183 -39.254224) (xy 256.237236 -39.338561)
			(xy 256.23774 -39.380922) (xy 256.237236 -39.423283) (xy 256.229183 -39.50762) (xy 256.213149 -39.59081)
			(xy 256.189281 -39.6721) (xy 256.157793 -39.750752) (xy 256.118971 -39.826055) (xy 256.073168 -39.897327)
			(xy 256.020797 -39.963923) (xy 255.962332 -40.025238) (xy 255.898304 -40.080719) (xy 255.829292 -40.129862)
			(xy 255.755922 -40.172222) (xy 255.678857 -40.207417) (xy 255.598795 -40.235126) (xy 255.516462 -40.2551)
			(xy 255.432603 -40.267157) (xy 255.347978 -40.271189) (xy 255.263353 -40.267157) (xy 255.179494 -40.2551)
			(xy 255.097161 -40.235126) (xy 255.017099 -40.207417) (xy 254.940034 -40.172222) (xy 254.866664 -40.129862)
			(xy 254.797652 -40.080719) (xy 254.733624 -40.025238) (xy 254.675159 -39.963923) (xy 254.622788 -39.897327)
			(xy 254.576985 -39.826055) (xy 254.538163 -39.750752) (xy 254.506675 -39.6721) (xy 254.482807 -39.59081)
			(xy 254.466773 -39.50762) (xy 254.45872 -39.423283) (xy 187.011125 -39.423283) (xy 188.381025 -40.793207)
			(xy 234.882173 -40.793207) (xy 234.882173 -40.696597) (xy 234.890151 -40.600318) (xy 234.906052 -40.505026)
			(xy 234.929769 -40.411373) (xy 234.961138 -40.319998) (xy 234.999945 -40.231525) (xy 235.045926 -40.14656)
			(xy 235.098767 -40.065682) (xy 235.158105 -39.989443) (xy 235.223537 -39.918365) (xy 235.294615 -39.852933)
			(xy 235.370854 -39.793595) (xy 235.451732 -39.740754) (xy 235.536697 -39.694773) (xy 235.62517 -39.655966)
			(xy 235.716545 -39.624597) (xy 235.810198 -39.60088) (xy 235.90549 -39.584979) (xy 236.001769 -39.577001)
			(xy 236.098379 -39.577001) (xy 236.194658 -39.584979) (xy 236.28995 -39.60088) (xy 236.383603 -39.624597)
			(xy 236.474978 -39.655966) (xy 236.563451 -39.694773) (xy 236.648416 -39.740754) (xy 236.729294 -39.793595)
			(xy 236.805533 -39.852933) (xy 236.876611 -39.918365) (xy 236.942043 -39.989443) (xy 237.001381 -40.065682)
			(xy 237.054222 -40.14656) (xy 237.100203 -40.231525) (xy 237.13901 -40.319998) (xy 237.170379 -40.411373)
			(xy 237.194096 -40.505026) (xy 237.209997 -40.600318) (xy 237.217975 -40.696597) (xy 237.218474 -40.744902)
			(xy 237.217975 -40.793207) (xy 237.209997 -40.889486) (xy 237.199916 -40.9499) (xy 246.935452 -40.9499)
			(xy 246.939482 -40.865295) (xy 246.951537 -40.781456) (xy 246.971506 -40.699142) (xy 246.999209 -40.619099)
			(xy 247.034396 -40.542053) (xy 247.076747 -40.468699) (xy 247.125879 -40.399704) (xy 247.181347 -40.335692)
			(xy 247.242648 -40.277242) (xy 247.309228 -40.224883) (xy 247.380484 -40.179091) (xy 247.45577 -40.14028)
			(xy 247.534404 -40.1088) (xy 247.615675 -40.084938) (xy 247.698846 -40.06891) (xy 247.783163 -40.060859)
			(xy 247.825514 -40.060372) (xy 247.868043 -40.060872) (xy 247.952713 -40.068982) (xy 248.036223 -40.085137)
			(xy 248.11781 -40.109189) (xy 248.196728 -40.140918) (xy 248.272258 -40.180035) (xy 248.343709 -40.226182)
			(xy 248.41043 -40.278938) (xy 248.441464 -40.308022) (xy 248.441718 -40.308276) (xy 248.44904 -40.314652)
			(xy 248.467069 -40.321822) (xy 248.47677 -40.322246) (xy 248.557288 -40.321992) (xy 248.575576 -40.314626)
			(xy 248.582688 -40.307514) (xy 248.613778 -40.278057) (xy 248.680689 -40.224588) (xy 248.752429 -40.177798)
			(xy 248.828335 -40.13812) (xy 248.907704 -40.105923) (xy 248.9898 -40.081504) (xy 249.073863 -40.065089)
			(xy 249.159115 -40.056831) (xy 249.20194 -40.056308) (xy 249.202448 -40.056308) (xy 249.244796 -40.056782)
			(xy 249.329107 -40.064837) (xy 249.412272 -40.08087) (xy 249.493536 -40.104735) (xy 249.572163 -40.136216)
			(xy 249.647442 -40.175029) (xy 249.718691 -40.220821) (xy 249.785265 -40.273178) (xy 249.84656 -40.331627)
			(xy 249.902022 -40.395637) (xy 249.951149 -40.464629) (xy 249.993496 -40.537978) (xy 250.028678 -40.615021)
			(xy 250.056379 -40.695058) (xy 250.076346 -40.777367) (xy 250.088399 -40.8612) (xy 250.092429 -40.9458)
			(xy 250.088399 -41.0304) (xy 250.076346 -41.114233) (xy 250.056379 -41.196542) (xy 250.028678 -41.276579)
			(xy 249.993496 -41.353622) (xy 249.951149 -41.426971) (xy 249.902022 -41.495963) (xy 249.84656 -41.559973)
			(xy 249.785265 -41.618422) (xy 249.718691 -41.670779) (xy 249.647442 -41.716571) (xy 249.572163 -41.755384)
			(xy 249.493536 -41.786865) (xy 249.412272 -41.81073) (xy 249.329107 -41.826763) (xy 249.244796 -41.834818)
			(xy 249.202448 -41.835324) (xy 249.159919 -41.834822) (xy 249.07525 -41.826709) (xy 248.991741 -41.810552)
			(xy 248.910155 -41.7865) (xy 248.831237 -41.754771) (xy 248.755707 -41.715655) (xy 248.684255 -41.66951)
			(xy 248.617533 -41.616756) (xy 248.586498 -41.587674) (xy 248.586244 -41.58742) (xy 248.578903 -41.58107)
			(xy 248.560888 -41.573885) (xy 248.551192 -41.57345) (xy 248.470674 -41.573704) (xy 248.452386 -41.58107)
			(xy 248.445274 -41.588182) (xy 248.414201 -41.617657) (xy 248.347287 -41.671125) (xy 248.275544 -41.717913)
			(xy 248.199635 -41.757589) (xy 248.120264 -41.789784) (xy 248.038166 -41.8142) (xy 247.954101 -41.830612)
			(xy 247.868848 -41.838866) (xy 247.826022 -41.839388) (xy 247.825514 -41.839388) (xy 247.783163 -41.838941)
			(xy 247.698846 -41.83089) (xy 247.615675 -41.814862) (xy 247.534404 -41.791) (xy 247.45577 -41.75952)
			(xy 247.380484 -41.720709) (xy 247.309228 -41.674917) (xy 247.242648 -41.622558) (xy 247.181347 -41.564108)
			(xy 247.125879 -41.500096) (xy 247.076747 -41.431101) (xy 247.034396 -41.357747) (xy 246.999209 -41.280701)
			(xy 246.971506 -41.200658) (xy 246.951537 -41.118344) (xy 246.939482 -41.034505) (xy 246.935452 -40.9499)
			(xy 237.199916 -40.9499) (xy 237.194096 -40.984778) (xy 237.170379 -41.078431) (xy 237.13901 -41.169806)
			(xy 237.100203 -41.258279) (xy 237.054222 -41.343244) (xy 237.001381 -41.424122) (xy 236.942043 -41.500361)
			(xy 236.876611 -41.571439) (xy 236.805533 -41.636871) (xy 236.729294 -41.696209) (xy 236.648416 -41.74905)
			(xy 236.563451 -41.795031) (xy 236.474978 -41.833838) (xy 236.383603 -41.865207) (xy 236.28995 -41.888924)
			(xy 236.194658 -41.904825) (xy 236.098379 -41.912803) (xy 236.001769 -41.912803) (xy 235.90549 -41.904825)
			(xy 235.810198 -41.888924) (xy 235.716545 -41.865207) (xy 235.62517 -41.833838) (xy 235.536697 -41.795031)
			(xy 235.451732 -41.74905) (xy 235.370854 -41.696209) (xy 235.294615 -41.636871) (xy 235.223537 -41.571439)
			(xy 235.158105 -41.500361) (xy 235.098767 -41.424122) (xy 235.045926 -41.343244) (xy 234.999945 -41.258279)
			(xy 234.961138 -41.169806) (xy 234.929769 -41.078431) (xy 234.906052 -40.984778) (xy 234.890151 -40.889486)
			(xy 234.882173 -40.793207) (xy 188.381025 -40.793207) (xy 191.613327 -44.025566) (xy 236.740192 -44.025566)
			(xy 236.74068 -43.984453) (xy 236.74827 -43.902577) (xy 236.763381 -43.82175) (xy 236.785886 -43.742663)
			(xy 236.815591 -43.665989) (xy 236.852243 -43.592383) (xy 236.895531 -43.522473) (xy 236.945083 -43.456854)
			(xy 237.000479 -43.396088) (xy 237.061245 -43.340691) (xy 237.126863 -43.291137) (xy 237.196773 -43.247849)
			(xy 237.270378 -43.211196) (xy 237.347052 -43.181489) (xy 237.426139 -43.158984) (xy 237.506965 -43.143872)
			(xy 237.588841 -43.136281) (xy 237.629954 -43.135804) (xy 237.672596 -43.136331) (xy 237.757484 -43.144543)
			(xy 237.841197 -43.160838) (xy 237.922968 -43.185068) (xy 237.962694 -43.200574) (xy 237.971356 -43.203655)
			(xy 237.989722 -43.204046) (xy 237.998508 -43.201336) (xy 238.034032 -43.189272) (xy 238.106663 -43.170452)
			(xy 238.18062 -43.157817) (xy 238.25538 -43.151455) (xy 238.292894 -43.151044) (xy 238.332166 -43.151496)
			(xy 238.410399 -43.158477) (xy 238.487712 -43.172332) (xy 238.563501 -43.192954) (xy 238.600488 -43.206162)
			(xy 238.609037 -43.208926) (xy 238.626991 -43.208926) (xy 238.63554 -43.206162) (xy 238.672533 -43.192975)
			(xy 238.748323 -43.172363) (xy 238.825633 -43.158506) (xy 238.903863 -43.151512) (xy 238.943134 -43.151044)
			(xy 238.981423 -43.151469) (xy 239.057717 -43.158071) (xy 239.133159 -43.171215) (xy 239.207191 -43.190803)
			(xy 239.243362 -43.203368) (xy 239.251799 -43.206019) (xy 239.269469 -43.206019) (xy 239.277906 -43.203368)
			(xy 239.314089 -43.190839) (xy 239.38812 -43.171262) (xy 239.463558 -43.158111) (xy 239.539846 -43.151482)
			(xy 239.578134 -43.151044) (xy 239.616423 -43.151469) (xy 239.692717 -43.158071) (xy 239.768159 -43.171215)
			(xy 239.842191 -43.190803) (xy 239.878362 -43.203368) (xy 239.886799 -43.206019) (xy 239.904469 -43.206019)
			(xy 239.912906 -43.203368) (xy 239.949089 -43.190839) (xy 240.02312 -43.171262) (xy 240.098558 -43.158111)
			(xy 240.174846 -43.151482) (xy 240.213134 -43.151044) (xy 240.25606 -43.151581) (xy 240.341511 -43.159862)
			(xy 240.425768 -43.176335) (xy 240.508046 -43.200846) (xy 240.587581 -43.233168) (xy 240.613613 -43.246802)
			(xy 243.62918 -43.246802) (xy 243.629584 -43.208512) (xy 243.636192 -43.132218) (xy 243.649342 -43.056775)
			(xy 243.668936 -42.982745) (xy 243.681504 -42.946574) (xy 243.684156 -42.938137) (xy 243.684156 -42.920466)
			(xy 243.681504 -42.91203) (xy 243.668959 -42.875853) (xy 243.649386 -42.80182) (xy 243.636239 -42.72638)
			(xy 243.629616 -42.65009) (xy 243.62918 -42.611802) (xy 243.629684 -42.569441) (xy 243.637737 -42.485104)
			(xy 243.653771 -42.401914) (xy 243.677639 -42.320624) (xy 243.709127 -42.241972) (xy 243.747949 -42.166669)
			(xy 243.793752 -42.095397) (xy 243.846123 -42.028801) (xy 243.904588 -41.967486) (xy 243.968616 -41.912005)
			(xy 244.037628 -41.862862) (xy 244.110998 -41.820502) (xy 244.188063 -41.785307) (xy 244.268125 -41.757598)
			(xy 244.350458 -41.737624) (xy 244.434317 -41.725567) (xy 244.518942 -41.721536) (xy 244.603567 -41.725567)
			(xy 244.687426 -41.737624) (xy 244.769759 -41.757598) (xy 244.849821 -41.785307) (xy 244.926886 -41.820502)
			(xy 245.000256 -41.862862) (xy 245.069268 -41.912005) (xy 245.133296 -41.967486) (xy 245.191761 -42.028801)
			(xy 245.244132 -42.095397) (xy 245.289935 -42.166669) (xy 245.328757 -42.241972) (xy 245.360245 -42.320624)
			(xy 245.384113 -42.401914) (xy 245.400147 -42.485104) (xy 245.4082 -42.569441) (xy 245.408704 -42.611802)
			(xy 245.408302 -42.650092) (xy 245.401694 -42.726386) (xy 245.388543 -42.801829) (xy 245.368949 -42.875859)
			(xy 245.35638 -42.91203) (xy 245.353727 -42.920466) (xy 245.353728 -42.938137) (xy 245.35638 -42.946574)
			(xy 245.368926 -42.982751) (xy 245.388499 -43.056784) (xy 245.401645 -43.132224) (xy 245.408269 -43.208514)
			(xy 245.408704 -43.246802) (xy 245.4082 -43.289163) (xy 245.400147 -43.3735) (xy 245.384113 -43.45669)
			(xy 245.360245 -43.53798) (xy 245.328757 -43.616632) (xy 245.289935 -43.691935) (xy 245.244132 -43.763207)
			(xy 245.191761 -43.829803) (xy 245.133296 -43.891118) (xy 245.069268 -43.946599) (xy 245.000256 -43.995742)
			(xy 244.926886 -44.038102) (xy 244.849821 -44.073297) (xy 244.769759 -44.101006) (xy 244.687426 -44.12098)
			(xy 244.603567 -44.133037) (xy 244.518942 -44.137069) (xy 244.434317 -44.133037) (xy 244.350458 -44.12098)
			(xy 244.268125 -44.101006) (xy 244.188063 -44.073297) (xy 244.110998 -44.038102) (xy 244.037628 -43.995742)
			(xy 243.968616 -43.946599) (xy 243.904588 -43.891118) (xy 243.846123 -43.829803) (xy 243.793752 -43.763207)
			(xy 243.747949 -43.691935) (xy 243.709127 -43.616632) (xy 243.677639 -43.53798) (xy 243.653771 -43.45669)
			(xy 243.637737 -43.3735) (xy 243.629684 -43.289163) (xy 243.62918 -43.246802) (xy 240.613613 -43.246802)
			(xy 240.663633 -43.272999) (xy 240.735496 -43.31997) (xy 240.802501 -43.373643) (xy 240.864025 -43.433521)
			(xy 240.919496 -43.499046) (xy 240.968398 -43.569608) (xy 241.010277 -43.644552) (xy 241.044744 -43.723182)
			(xy 241.071477 -43.804765) (xy 241.090229 -43.888544) (xy 241.096038 -43.931078) (xy 241.097792 -43.94092)
			(xy 241.107661 -43.958279) (xy 241.123386 -43.970587) (xy 241.132868 -43.97375) (xy 241.172506 -43.985287)
			(xy 241.249638 -44.014728) (xy 241.32371 -44.051189) (xy 241.394086 -44.094356) (xy 241.460159 -44.143858)
			(xy 241.521362 -44.199269) (xy 241.577167 -44.260112) (xy 241.627095 -44.325864) (xy 241.670716 -44.395959)
			(xy 241.707655 -44.469795) (xy 241.737594 -44.546735) (xy 241.760276 -44.626118) (xy 241.775505 -44.707261)
			(xy 241.78315 -44.789466) (xy 241.783616 -44.830746) (xy 241.783231 -44.871862) (xy 241.775639 -44.953744)
			(xy 241.760525 -45.034576) (xy 241.738017 -45.113668) (xy 241.708307 -45.190346) (xy 241.671649 -45.263956)
			(xy 241.628355 -45.333869) (xy 241.578796 -45.39949) (xy 241.523393 -45.460258) (xy 241.462619 -45.515654)
			(xy 241.396993 -45.565207) (xy 241.327075 -45.608494) (xy 241.253462 -45.645144) (xy 241.176781 -45.674846)
			(xy 241.097686 -45.697346) (xy 241.016853 -45.712452) (xy 240.93497 -45.720035) (xy 240.893854 -45.720508)
			(xy 240.848047 -45.719908) (xy 240.756919 -45.710469) (xy 240.667241 -45.691726) (xy 240.579961 -45.663878)
			(xy 240.537746 -45.646086) (xy 240.528923 -45.642621) (xy 240.509997 -45.641842) (xy 240.500916 -45.644562)
			(xy 240.454475 -45.659757) (xy 240.359116 -45.681105) (xy 240.261993 -45.691873) (xy 240.213134 -45.692568)
			(xy 240.174844 -45.692152) (xy 240.09855 -45.685547) (xy 240.023108 -45.672401) (xy 239.949077 -45.652811)
			(xy 239.912906 -45.640244) (xy 239.904469 -45.637593) (xy 239.886799 -45.637593) (xy 239.878362 -45.640244)
			(xy 239.842183 -45.652782) (xy 239.76815 -45.672357) (xy 239.692711 -45.685505) (xy 239.616422 -45.692131)
			(xy 239.578134 -45.692568) (xy 239.539844 -45.692152) (xy 239.46355 -45.685547) (xy 239.388108 -45.672401)
			(xy 239.314077 -45.652811) (xy 239.277906 -45.640244) (xy 239.269469 -45.637593) (xy 239.251799 -45.637593)
			(xy 239.243362 -45.640244) (xy 239.207183 -45.652782) (xy 239.13315 -45.672357) (xy 239.057711 -45.685505)
			(xy 238.981422 -45.692131) (xy 238.943134 -45.692568) (xy 238.903862 -45.692107) (xy 238.825629 -45.685129)
			(xy 238.748316 -45.671276) (xy 238.672527 -45.650657) (xy 238.63554 -45.63745) (xy 238.626991 -45.634686)
			(xy 238.609037 -45.634686) (xy 238.600488 -45.63745) (xy 238.563502 -45.650659) (xy 238.48771 -45.671265)
			(xy 238.410397 -45.685115) (xy 238.332165 -45.692103) (xy 238.292894 -45.692568) (xy 238.24936 -45.692039)
			(xy 238.16271 -45.683524) (xy 238.077306 -45.666586) (xy 237.993965 -45.641387) (xy 237.913484 -45.608168)
			(xy 237.87481 -45.588174) (xy 237.86657 -45.584248) (xy 237.848476 -45.581916) (xy 237.839504 -45.583602)
			(xy 237.790336 -45.594179) (xy 237.690402 -45.605511) (xy 237.640114 -45.606208) (xy 237.599001 -45.605674)
			(xy 237.517127 -45.598088) (xy 237.436301 -45.582981) (xy 237.357214 -45.560481) (xy 237.280541 -45.53078)
			(xy 237.206935 -45.494131) (xy 237.137024 -45.450847) (xy 237.071406 -45.401297) (xy 237.010639 -45.345904)
			(xy 236.955242 -45.285141) (xy 236.905687 -45.219525) (xy 236.862399 -45.149618) (xy 236.825745 -45.076014)
			(xy 236.796038 -44.999343) (xy 236.773533 -44.920257) (xy 236.75842 -44.839433) (xy 236.750829 -44.757559)
			(xy 236.750352 -44.716446) (xy 236.750814 -44.676228) (xy 236.758123 -44.596123) (xy 236.772622 -44.517004)
			(xy 236.794193 -44.439513) (xy 236.80801 -44.40174) (xy 236.811025 -44.392621) (xy 236.810769 -44.373433)
			(xy 236.807502 -44.364402) (xy 236.791394 -44.324025) (xy 236.766206 -44.240819) (xy 236.749266 -44.15555)
			(xy 236.740738 -44.069034) (xy 236.740192 -44.025566) (xy 191.613327 -44.025566) (xy 194.186302 -46.598586)
			(xy 194.194757 -46.606142) (xy 194.216125 -46.613652) (xy 194.22745 -46.613064) (xy 194.227958 -46.613064)
			(xy 194.248403 -46.610951) (xy 194.289447 -46.608663) (xy 194.31 -46.608492) (xy 194.349934 -46.609015)
			(xy 194.429364 -46.617363) (xy 194.507487 -46.633969) (xy 194.583446 -46.658649) (xy 194.656409 -46.691134)
			(xy 194.725576 -46.731068) (xy 194.790191 -46.778014) (xy 194.849544 -46.831456) (xy 194.902986 -46.890809)
			(xy 194.949932 -46.955424) (xy 194.989866 -47.024591) (xy 195.022351 -47.097554) (xy 195.047031 -47.173513)
			(xy 195.063637 -47.251636) (xy 195.071985 -47.331066) (xy 195.072508 -47.371) (xy 195.072338 -47.390915)
			(xy 195.070177 -47.430686) (xy 195.06819 -47.450502) (xy 195.067936 -47.453042) (xy 195.067936 -47.45355)
			(xy 195.067364 -47.464873) (xy 195.074872 -47.486234) (xy 195.082414 -47.494698) (xy 201.566272 -53.978302)
			(xy 201.574415 -53.985759) (xy 201.595112 -53.993386) (xy 201.60615 -53.993034) (xy 201.645266 -53.99151)
			(xy 201.675998 -53.99197) (xy 201.737014 -53.999375) (xy 201.796693 -54.014081) (xy 201.854164 -54.035874)
			(xy 201.908589 -54.064436) (xy 201.959174 -54.09935) (xy 202.005181 -54.140107) (xy 202.04594 -54.186113)
			(xy 202.080856 -54.236697) (xy 202.109419 -54.291121) (xy 202.131214 -54.348591) (xy 202.145922 -54.40827)
			(xy 202.153329 -54.469286) (xy 202.153774 -54.500018) (xy 202.15225 -54.539134) (xy 202.151939 -54.550161)
			(xy 202.159579 -54.570833) (xy 202.166982 -54.579012) (xy 202.909424 -55.321454) (xy 202.916827 -55.328291)
			(xy 202.935424 -55.336014) (xy 202.945492 -55.33644) (xy 203.670154 -55.33644) (xy 203.679243 -55.336109)
			(xy 203.696282 -55.329775) (xy 203.710034 -55.317888) (xy 203.718769 -55.301947) (xy 203.720446 -55.293006)
			(xy 203.737972 -55.17515) (xy 203.717652 -55.1434) (xy 203.699618 -55.137812) (xy 203.622621 -55.114136)
			(xy 203.470842 -55.060112) (xy 203.321901 -54.998696) (xy 203.176158 -54.930035) (xy 203.033964 -54.854297)
			(xy 202.895663 -54.771664) (xy 202.761589 -54.682335) (xy 202.632066 -54.586526) (xy 202.507408 -54.48447)
			(xy 202.387914 -54.376411) (xy 202.273873 -54.262612) (xy 202.165562 -54.143347) (xy 202.063242 -54.018905)
			(xy 201.967159 -53.889585) (xy 201.877547 -53.755701) (xy 201.794621 -53.617575) (xy 201.718582 -53.475542)
			(xy 201.649613 -53.329944) (xy 201.587882 -53.181133) (xy 201.533536 -53.029469) (xy 201.486708 -52.875318)
			(xy 201.447511 -52.719052) (xy 201.416039 -52.561049) (xy 201.392368 -52.401691) (xy 201.376556 -52.241362)
			(xy 201.36864 -52.080449) (xy 201.368152 -51.999896) (xy 201.368646 -51.91946) (xy 201.376539 -51.758781)
			(xy 201.392308 -51.598683) (xy 201.415913 -51.439551) (xy 201.447297 -51.281769) (xy 201.486386 -51.125718)
			(xy 201.533085 -50.971772) (xy 201.587281 -50.820303) (xy 201.648845 -50.671676) (xy 201.717627 -50.526249)
			(xy 201.793462 -50.384372) (xy 201.876167 -50.246387) (xy 201.965543 -50.112626) (xy 202.061375 -49.983412)
			(xy 202.163431 -49.859056) (xy 202.271467 -49.739857) (xy 202.385221 -49.626103) (xy 202.50442 -49.518067)
			(xy 202.628776 -49.416011) (xy 202.75799 -49.320179) (xy 202.891751 -49.230803) (xy 203.029736 -49.148098)
			(xy 203.171613 -49.072263) (xy 203.31704 -49.003481) (xy 203.465667 -48.941917) (xy 203.617136 -48.887721)
			(xy 203.771082 -48.841022) (xy 203.927133 -48.801933) (xy 204.084915 -48.770549) (xy 204.244047 -48.746944)
			(xy 204.404145 -48.731175) (xy 204.564824 -48.723282) (xy 204.725696 -48.723282) (xy 204.886375 -48.731175)
			(xy 205.046473 -48.746944) (xy 205.205605 -48.770549) (xy 205.363387 -48.801933) (xy 205.519438 -48.841022)
			(xy 205.673384 -48.887721) (xy 205.824853 -48.941917) (xy 205.97348 -49.003481) (xy 206.118907 -49.072263)
			(xy 206.260784 -49.148098) (xy 206.398769 -49.230803) (xy 206.53253 -49.320179) (xy 206.661744 -49.416011)
			(xy 206.7861 -49.518067) (xy 206.905299 -49.626103) (xy 207.019053 -49.739857) (xy 207.127089 -49.859056)
			(xy 207.229145 -49.983412) (xy 207.324977 -50.112626) (xy 207.414353 -50.246387) (xy 207.497058 -50.384372)
			(xy 207.572893 -50.526249) (xy 207.641675 -50.671676) (xy 207.703239 -50.820303) (xy 207.757435 -50.971772)
			(xy 207.804134 -51.125718) (xy 207.843223 -51.281769) (xy 207.874607 -51.439551) (xy 207.898212 -51.598683)
			(xy 207.913981 -51.758781) (xy 207.921874 -51.91946) (xy 207.922368 -51.999896) (xy 207.921892 -52.080449)
			(xy 207.920844 -52.10175) (xy 244.67947 -52.10175) (xy 244.679975 -52.075243) (xy 244.687334 -52.022743)
			(xy 244.701889 -51.971767) (xy 244.723361 -51.923297) (xy 244.751335 -51.878265) (xy 244.785274 -51.837539)
			(xy 244.824523 -51.801903) (xy 244.868327 -51.772043) (xy 244.915843 -51.748534) (xy 244.966156 -51.731829)
			(xy 244.992144 -51.726592) (xy 245.000543 -51.724726) (xy 245.015476 -51.716197) (xy 245.026755 -51.703216)
			(xy 245.030244 -51.69535) (xy 245.045663 -51.657494) (xy 245.082559 -51.584546) (xy 245.125992 -51.515291)
			(xy 245.175596 -51.450313) (xy 245.230952 -51.39016) (xy 245.291595 -51.335341) (xy 245.357011 -51.286316)
			(xy 245.426649 -51.2435) (xy 245.499922 -51.207254) (xy 245.576211 -51.177884) (xy 245.654873 -51.155637)
			(xy 245.735245 -51.140701) (xy 245.816648 -51.133203) (xy 245.857522 -51.13274) (xy 245.899843 -51.133258)
			(xy 245.984099 -51.14133) (xy 246.067208 -51.157371) (xy 246.148416 -51.181236) (xy 246.226989 -51.212708)
			(xy 246.302217 -51.251503) (xy 246.33809 -51.273964) (xy 246.346484 -51.278827) (xy 246.365522 -51.28248)
			(xy 246.38456 -51.278827) (xy 246.392954 -51.273964) (xy 246.42883 -51.25151) (xy 246.504063 -51.212731)
			(xy 246.582638 -51.181268) (xy 246.663845 -51.157405) (xy 246.74695 -51.141356) (xy 246.831202 -51.133268)
			(xy 246.873522 -51.13274) (xy 246.926862 -51.134518) (xy 246.938638 -51.134618) (xy 246.960306 -51.125466)
			(xy 246.975671 -51.107657) (xy 246.979186 -51.096418) (xy 246.990138 -51.056039) (xy 247.018713 -50.977397)
			(xy 247.054545 -50.901785) (xy 247.097317 -50.829872) (xy 247.146653 -50.762292) (xy 247.202115 -50.699642)
			(xy 247.263214 -50.642477) (xy 247.329411 -50.5913) (xy 247.40012 -50.546564) (xy 247.474717 -50.508665)
			(xy 247.552542 -50.477936) (xy 247.632909 -50.45465) (xy 247.715107 -50.439012) (xy 247.79841 -50.431161)
			(xy 247.840246 -50.430684) (xy 247.883752 -50.431235) (xy 247.970347 -50.439729) (xy 248.055699 -50.456641)
			(xy 248.138991 -50.481809) (xy 248.219426 -50.514992) (xy 248.296235 -50.555874) (xy 248.332752 -50.579528)
			(xy 248.341308 -50.584744) (xy 248.360946 -50.588653) (xy 248.380584 -50.584744) (xy 248.38914 -50.579528)
			(xy 248.425663 -50.555885) (xy 248.50248 -50.515022) (xy 248.582916 -50.481847) (xy 248.666204 -50.456676)
			(xy 248.751551 -50.439749) (xy 248.838142 -50.431227) (xy 248.881646 -50.430684) (xy 248.926403 -50.431259)
			(xy 249.015462 -50.440266) (xy 249.103167 -50.458165) (xy 249.188634 -50.484775) (xy 249.270999 -50.519828)
			(xy 249.349431 -50.562968) (xy 249.386598 -50.58791) (xy 249.394939 -50.593062) (xy 249.414052 -50.597328)
			(xy 249.433374 -50.594144) (xy 249.44197 -50.589434) (xy 249.4758 -50.569354) (xy 249.546346 -50.534523)
			(xy 249.619688 -50.506051) (xy 249.695257 -50.484158) (xy 249.772462 -50.469016) (xy 249.850701 -50.460742)
			(xy 249.890026 -50.45964) (xy 249.889772 -50.4444) (xy 249.889772 -50.443892) (xy 249.89024 -50.405527)
			(xy 249.896983 -50.329093) (xy 249.903234 -50.291238) (xy 249.904413 -50.282319) (xy 249.901131 -50.26464)
			(xy 249.891952 -50.249179) (xy 249.8852 -50.243232) (xy 249.851748 -50.215094) (xy 249.789907 -50.153305)
			(xy 249.734424 -50.08575) (xy 249.685833 -50.01308) (xy 249.644603 -49.935995) (xy 249.61113 -49.855239)
			(xy 249.585738 -49.771589) (xy 249.568671 -49.685852) (xy 249.560094 -49.598855) (xy 249.559572 -49.555146)
			(xy 249.560076 -49.512785) (xy 249.568129 -49.428448) (xy 249.584163 -49.345258) (xy 249.608031 -49.263968)
			(xy 249.639519 -49.185316) (xy 249.678341 -49.110013) (xy 249.724144 -49.038741) (xy 249.776515 -48.972145)
			(xy 249.83498 -48.91083) (xy 249.899008 -48.855349) (xy 249.96802 -48.806206) (xy 250.04139 -48.763846)
			(xy 250.118455 -48.728651) (xy 250.198517 -48.700942) (xy 250.28085 -48.680968) (xy 250.364709 -48.668911)
			(xy 250.449334 -48.66488) (xy 250.533959 -48.668911) (xy 250.617818 -48.680968) (xy 250.700151 -48.700942)
			(xy 250.780213 -48.728651) (xy 250.857278 -48.763846) (xy 250.930648 -48.806206) (xy 250.99966 -48.855349)
			(xy 251.063688 -48.91083) (xy 251.122153 -48.972145) (xy 251.174524 -49.038741) (xy 251.220327 -49.110013)
			(xy 251.259149 -49.185316) (xy 251.290637 -49.263968) (xy 251.314505 -49.345258) (xy 251.330539 -49.428448)
			(xy 251.338592 -49.512785) (xy 251.339096 -49.555146) (xy 251.338636 -49.593574) (xy 251.331894 -49.670136)
			(xy 251.325634 -49.708054) (xy 251.324473 -49.716974) (xy 251.32775 -49.73465) (xy 251.336921 -49.750111)
			(xy 251.343668 -49.75606) (xy 251.362142 -49.771471) (xy 251.397596 -49.803999) (xy 251.414534 -49.821084)
			(xy 251.422676 -49.828571) (xy 251.443355 -49.836348) (xy 251.454412 -49.83607) (xy 251.469822 -49.835031)
			(xy 251.50069 -49.833886) (xy 251.516134 -49.833784) (xy 251.557251 -49.834166) (xy 251.639133 -49.841757)
			(xy 251.719966 -49.85687) (xy 251.79906 -49.879378) (xy 251.875739 -49.909087) (xy 251.94935 -49.945745)
			(xy 252.019265 -49.989039) (xy 252.084886 -50.038598) (xy 252.145655 -50.094001) (xy 252.201053 -50.154775)
			(xy 252.250607 -50.220401) (xy 252.293894 -50.29032) (xy 252.330545 -50.363934) (xy 252.360248 -50.440616)
			(xy 252.382748 -50.519712) (xy 252.397854 -50.600546) (xy 252.405438 -50.682429) (xy 252.405896 -50.723546)
			(xy 252.405358 -50.767341) (xy 252.396743 -50.854506) (xy 252.379599 -50.940401) (xy 252.354094 -51.024196)
			(xy 252.320474 -51.105076) (xy 252.300232 -51.143916) (xy 252.29478 -51.15537) (xy 252.2948 -51.18071)
			(xy 252.300232 -51.192176) (xy 252.320452 -51.231026) (xy 252.354062 -51.311909) (xy 252.379567 -51.3957)
			(xy 252.39672 -51.481592) (xy 252.405355 -51.568752) (xy 252.405896 -51.612546) (xy 252.405358 -51.656341)
			(xy 252.396743 -51.743506) (xy 252.379599 -51.829401) (xy 252.354094 -51.913196) (xy 252.320474 -51.994076)
			(xy 252.300232 -52.032916) (xy 252.29478 -52.04437) (xy 252.2948 -52.06971) (xy 252.300232 -52.081176)
			(xy 252.320452 -52.120026) (xy 252.354062 -52.200909) (xy 252.379567 -52.2847) (xy 252.39672 -52.370592)
			(xy 252.405355 -52.457752) (xy 252.405896 -52.501546) (xy 252.405431 -52.54266) (xy 252.39784 -52.624537)
			(xy 252.382728 -52.705364) (xy 252.360222 -52.784452) (xy 252.330515 -52.861127) (xy 252.293861 -52.934733)
			(xy 252.250573 -53.004644) (xy 252.201018 -53.070263) (xy 252.145621 -53.131029) (xy 252.084853 -53.186426)
			(xy 252.019234 -53.235979) (xy 251.949323 -53.279267) (xy 251.875716 -53.31592) (xy 251.799041 -53.345626)
			(xy 251.719952 -53.36813) (xy 251.639125 -53.383242) (xy 251.557248 -53.390832) (xy 251.516134 -53.391308)
			(xy 251.471924 -53.390745) (xy 251.383942 -53.381965) (xy 251.297264 -53.3645) (xy 251.212747 -53.33852)
			(xy 251.131225 -53.304282) (xy 251.053503 -53.262125) (xy 250.980346 -53.212465) (xy 250.912478 -53.15579)
			(xy 250.881134 -53.124608) (xy 250.873005 -53.117104) (xy 250.852316 -53.109337) (xy 250.841256 -53.109622)
			(xy 250.825846 -53.110663) (xy 250.794978 -53.111806) (xy 250.779534 -53.111908) (xy 250.737779 -53.111492)
			(xy 250.654637 -53.103677) (xy 250.572592 -53.088104) (xy 250.492369 -53.064909) (xy 250.414673 -53.034297)
			(xy 250.340188 -52.996537) (xy 250.269571 -52.951961) (xy 250.203442 -52.900963) (xy 250.142385 -52.843991)
			(xy 250.086937 -52.781547) (xy 250.037585 -52.714181) (xy 249.994765 -52.642486) (xy 249.958854 -52.567092)
			(xy 249.930167 -52.488665) (xy 249.908958 -52.407894) (xy 249.895413 -52.32549) (xy 249.892058 -52.283868)
			(xy 249.891061 -52.274773) (xy 249.88348 -52.258135) (xy 249.870549 -52.245209) (xy 249.853908 -52.237634)
			(xy 249.844814 -52.236624) (xy 249.805225 -52.23352) (xy 249.726783 -52.221122) (xy 249.649759 -52.201775)
			(xy 249.574769 -52.175634) (xy 249.50241 -52.142907) (xy 249.433259 -52.103855) (xy 249.400314 -52.081684)
			(xy 249.392012 -52.076461) (xy 249.372875 -52.072218) (xy 249.353539 -52.075433) (xy 249.344942 -52.08016)
			(xy 249.312459 -52.099495) (xy 249.244799 -52.133223) (xy 249.174522 -52.161088) (xy 249.13844 -52.172362)
			(xy 249.128616 -52.175851) (xy 249.112727 -52.189319) (xy 249.103444 -52.207965) (xy 249.102372 -52.218336)
			(xy 249.099675 -52.260463) (xy 249.087279 -52.34397) (xy 249.067027 -52.425926) (xy 249.039099 -52.505595)
			(xy 249.003748 -52.582258) (xy 248.961291 -52.655227) (xy 248.912112 -52.723845) (xy 248.856651 -52.787493)
			(xy 248.795409 -52.8456) (xy 248.728936 -52.897642) (xy 248.657831 -52.943151) (xy 248.582733 -52.981717)
			(xy 248.504319 -53.012994) (xy 248.423294 -53.036699) (xy 248.340387 -53.052621) (xy 248.256345 -53.060614)
			(xy 248.214134 -53.061108) (xy 248.171669 -53.060607) (xy 248.087125 -53.052507) (xy 248.003739 -53.036385)
			(xy 247.922268 -53.01239) (xy 247.843456 -52.98074) (xy 247.768018 -52.941722) (xy 247.696643 -52.895693)
			(xy 247.629979 -52.84307) (xy 247.568634 -52.784334) (xy 247.540526 -52.752498) (xy 247.534176 -52.745132)
			(xy 247.517412 -52.736496) (xy 247.429274 -52.726336) (xy 247.410986 -52.731416) (xy 247.403112 -52.737258)
			(xy 247.370277 -52.761024) (xy 247.301045 -52.803187) (xy 247.228263 -52.838875) (xy 247.152535 -52.867791)
			(xy 247.07449 -52.889697) (xy 246.994775 -52.904409) (xy 246.914052 -52.911805) (xy 246.873522 -52.912264)
			(xy 246.831202 -52.911724) (xy 246.746946 -52.903656) (xy 246.663838 -52.887619) (xy 246.58263 -52.863758)
			(xy 246.504056 -52.83229) (xy 246.428827 -52.793499) (xy 246.392954 -52.77104) (xy 246.38456 -52.766177)
			(xy 246.365522 -52.762524) (xy 246.346484 -52.766177) (xy 246.33809 -52.77104) (xy 246.302222 -52.793507)
			(xy 246.226987 -52.832285) (xy 246.148411 -52.863747) (xy 246.067203 -52.887609) (xy 245.984096 -52.903654)
			(xy 245.899842 -52.911738) (xy 245.857522 -52.912264) (xy 245.813221 -52.911666) (xy 245.725058 -52.90285)
			(xy 245.638208 -52.885314) (xy 245.553531 -52.85923) (xy 245.471867 -52.824858) (xy 245.394025 -52.782538)
			(xy 245.320775 -52.732689) (xy 245.252843 -52.675806) (xy 245.190903 -52.61245) (xy 245.135568 -52.543252)
			(xy 245.111016 -52.506372) (xy 245.106055 -52.499361) (xy 245.092457 -52.488884) (xy 245.076169 -52.483465)
			(xy 245.067582 -52.483258) (xy 245.060978 -52.483258) (xy 245.033722 -52.482865) (xy 244.979766 -52.475104)
			(xy 244.927464 -52.459743) (xy 244.87788 -52.437094) (xy 244.832025 -52.407619) (xy 244.790831 -52.371918)
			(xy 244.755138 -52.330717) (xy 244.725671 -52.284856) (xy 244.703032 -52.235269) (xy 244.68768 -52.182963)
			(xy 244.679929 -52.129006) (xy 244.67947 -52.10175) (xy 207.920844 -52.10175) (xy 207.913976 -52.241361)
			(xy 207.898164 -52.40169) (xy 207.874493 -52.561048) (xy 207.84302 -52.71905) (xy 207.803822 -52.875315)
			(xy 207.756994 -53.029466) (xy 207.702647 -53.181129) (xy 207.640915 -53.329939) (xy 207.571945 -53.475536)
			(xy 207.495905 -53.617568) (xy 207.412978 -53.755693) (xy 207.323364 -53.889576) (xy 207.22728 -54.018894)
			(xy 207.124959 -54.143335) (xy 207.016646 -54.262598) (xy 206.902605 -54.376396) (xy 206.783109 -54.484452)
			(xy 206.658449 -54.586506) (xy 206.528925 -54.682312) (xy 206.39485 -54.771639) (xy 206.256548 -54.854269)
			(xy 206.114353 -54.930005) (xy 205.968608 -54.998662) (xy 205.819666 -55.060075) (xy 205.667886 -55.114095)
			(xy 205.590902 -55.137812) (xy 205.572868 -55.1434) (xy 205.552548 -55.17515) (xy 205.570074 -55.293006)
			(xy 205.571789 -55.301931) (xy 205.580529 -55.31785) (xy 205.594269 -55.329724) (xy 205.611286 -55.336064)
			(xy 205.620366 -55.33644) (xy 211.837778 -55.33644) (xy 211.846696 -55.336107) (xy 211.863445 -55.329974)
			(xy 211.877083 -55.318477) (xy 211.885959 -55.303006) (xy 211.887816 -55.294276) (xy 211.895118 -55.255481)
			(xy 211.916702 -55.179542) (xy 211.946017 -55.10624) (xy 211.982749 -55.03636) (xy 212.026505 -54.970648)
			(xy 212.076816 -54.90981) (xy 212.133144 -54.854495) (xy 212.194886 -54.805297) (xy 212.261381 -54.762741)
			(xy 212.331917 -54.727284) (xy 212.405739 -54.699304) (xy 212.482056 -54.679102) (xy 212.560053 -54.666894)
			(xy 212.638894 -54.66281) (xy 212.717735 -54.666894) (xy 212.795732 -54.679102) (xy 212.872049 -54.699304)
			(xy 212.945871 -54.727284) (xy 213.016407 -54.762741) (xy 213.082902 -54.805297) (xy 213.144644 -54.854495)
			(xy 213.200972 -54.90981) (xy 213.251283 -54.970648) (xy 213.295039 -55.03636) (xy 213.331771 -55.10624)
			(xy 213.361086 -55.179542) (xy 213.38267 -55.255481) (xy 213.389972 -55.294276) (xy 213.391835 -55.303005)
			(xy 213.400699 -55.318484) (xy 213.414337 -55.32998) (xy 213.431091 -55.336098) (xy 213.44001 -55.33644)
			(xy 248.620788 -55.33644) (xy 248.63096 -55.335983) (xy 248.649699 -55.328059) (xy 248.663897 -55.313487)
			(xy 248.668032 -55.304182) (xy 248.67829 -55.279357) (xy 248.704771 -55.232624) (xy 248.737544 -55.190066)
			(xy 248.775961 -55.152525) (xy 248.819263 -55.120742) (xy 248.866595 -55.095346) (xy 248.91702 -55.076839)
			(xy 248.969543 -55.065586) (xy 249.023124 -55.06181) (xy 249.076705 -55.065586) (xy 249.129228 -55.076839)
			(xy 249.179653 -55.095346) (xy 249.226985 -55.120742) (xy 249.270287 -55.152525) (xy 249.308704 -55.190066)
			(xy 249.341477 -55.232624) (xy 249.367958 -55.279357) (xy 249.378216 -55.304182) (xy 249.382334 -55.3135)
			(xy 249.396527 -55.328089) (xy 249.415282 -55.335996) (xy 249.42546 -55.33644) (xy 253.111508 -55.33644)
			(xy 253.12158 -55.336035) (xy 253.140179 -55.328302) (xy 253.147576 -55.321454) (xy 253.470664 -54.998366)
			(xy 253.475998 -54.966616) (xy 253.468886 -54.951884) (xy 253.450704 -54.912967) (xy 253.422198 -54.831933)
			(xy 253.402978 -54.74821) (xy 253.39329 -54.662856) (xy 253.392686 -54.619906) (xy 253.39322 -54.579972)
			(xy 253.401568 -54.500543) (xy 253.418173 -54.42242) (xy 253.442853 -54.346462) (xy 253.475337 -54.273499)
			(xy 253.51527 -54.204332) (xy 253.562214 -54.139717) (xy 253.615656 -54.080364) (xy 253.675008 -54.026922)
			(xy 253.739622 -53.979977) (xy 253.808789 -53.940042) (xy 253.881751 -53.907557) (xy 253.957709 -53.882876)
			(xy 254.035831 -53.86627) (xy 254.11526 -53.857921) (xy 254.155194 -53.857398) (xy 254.194125 -53.857863)
			(xy 254.271583 -53.865801) (xy 254.347827 -53.881594) (xy 254.422064 -53.905078) (xy 254.49352 -53.936008)
			(xy 254.56145 -53.974062) (xy 254.625146 -54.018843) (xy 254.683946 -54.069885) (xy 254.710946 -54.097936)
			(xy 254.711708 -54.098698) (xy 254.711962 -54.098952) (xy 254.719536 -54.106188) (xy 254.73883 -54.114303)
			(xy 254.7493 -54.1147) (xy 254.824738 -54.113684) (xy 254.835323 -54.112975) (xy 254.85461 -54.104201)
			(xy 254.862076 -54.096666) (xy 254.889232 -54.066856) (xy 254.948768 -54.012465) (xy 255.01371 -53.964657)
			(xy 255.083333 -53.923966) (xy 255.156859 -53.890846) (xy 255.233468 -53.865667) (xy 255.312307 -53.848709)
			(xy 255.392494 -53.840162) (xy 255.432814 -53.839618) (xy 255.471407 -53.840114) (xy 255.548199 -53.847895)
			(xy 255.623812 -53.863396) (xy 255.697471 -53.886458) (xy 255.768423 -53.916846) (xy 255.835941 -53.954248)
			(xy 255.899335 -53.998281) (xy 255.957954 -54.048494) (xy 256.011198 -54.104374) (xy 256.058524 -54.165348)
			(xy 256.099446 -54.230793) (xy 256.133545 -54.300038) (xy 256.160473 -54.372373) (xy 256.170684 -54.409594)
			(xy 256.175002 -54.426358) (xy 256.202434 -54.44744) (xy 265.095482 -54.44744) (xy 265.107307 -54.4469)
			(xy 265.128498 -54.436412) (xy 265.142756 -54.417549) (xy 265.14552 -54.406038) (xy 265.151928 -54.374659)
			(xy 265.1716 -54.313709) (xy 265.198766 -54.25571) (xy 265.232999 -54.20158) (xy 265.273755 -54.152176)
			(xy 265.320391 -54.108278) (xy 265.372168 -54.070582) (xy 265.428268 -54.039683) (xy 265.487802 -54.016071)
			(xy 265.54983 -54.000119) (xy 265.613369 -53.99208) (xy 265.677415 -53.99208) (xy 265.740954 -54.000119)
			(xy 265.802982 -54.016071) (xy 265.862516 -54.039683) (xy 265.918616 -54.070582) (xy 265.970393 -54.108278)
			(xy 266.017029 -54.152176) (xy 266.057785 -54.20158) (xy 266.092018 -54.25571) (xy 266.119184 -54.313709)
			(xy 266.138856 -54.374659) (xy 266.145264 -54.406038) (xy 266.148093 -54.417512) (xy 266.162369 -54.436308)
			(xy 266.183502 -54.446819) (xy 266.195302 -54.44744) (xy 266.213844 -54.44744) (xy 266.223775 -54.446937)
			(xy 266.242144 -54.439378) (xy 266.256266 -54.42541) (xy 266.26058 -54.416452) (xy 266.303252 -54.316376)
			(xy 266.297664 -54.286404) (xy 266.286996 -54.275482) (xy 266.232723 -54.218611) (xy 266.129107 -54.100364)
			(xy 266.031279 -53.977284) (xy 265.939466 -53.849656) (xy 265.853877 -53.717773) (xy 265.774709 -53.581937)
			(xy 265.702146 -53.442462) (xy 265.636353 -53.299669) (xy 265.577481 -53.153885) (xy 265.525668 -53.005446)
			(xy 265.48103 -52.854694) (xy 265.443672 -52.701975) (xy 265.413679 -52.54764) (xy 265.39112 -52.392045)
			(xy 265.376047 -52.235547) (xy 265.368495 -52.078507) (xy 265.368024 -51.999896) (xy 265.368518 -51.919453)
			(xy 265.376412 -51.758762) (xy 265.392181 -51.598651) (xy 265.415788 -51.439508) (xy 265.447175 -51.281714)
			(xy 265.486267 -51.12565) (xy 265.53297 -50.971693) (xy 265.58717 -50.820212) (xy 265.648739 -50.671574)
			(xy 265.717526 -50.526135) (xy 265.793367 -50.384247) (xy 265.876078 -50.246251) (xy 265.965461 -50.11248)
			(xy 266.0613 -49.983256) (xy 266.163365 -49.85889) (xy 266.271409 -49.739682) (xy 266.385172 -49.625919)
			(xy 266.50438 -49.517875) (xy 266.628746 -49.41581) (xy 266.75797 -49.319971) (xy 266.891741 -49.230588)
			(xy 267.029737 -49.147877) (xy 267.171625 -49.072036) (xy 267.317064 -49.003249) (xy 267.465702 -48.94168)
			(xy 267.617183 -48.88748) (xy 267.77114 -48.840777) (xy 267.927204 -48.801685) (xy 268.084998 -48.770298)
			(xy 268.244141 -48.746691) (xy 268.404252 -48.730922) (xy 268.564943 -48.723028) (xy 268.725829 -48.723028)
			(xy 268.88652 -48.730922) (xy 269.046631 -48.746691) (xy 269.205774 -48.770298) (xy 269.363568 -48.801685)
			(xy 269.519632 -48.840777) (xy 269.673589 -48.88748) (xy 269.82507 -48.94168) (xy 269.973708 -49.003249)
			(xy 270.119147 -49.072036) (xy 270.261035 -49.147877) (xy 270.399031 -49.230588) (xy 270.532802 -49.319971)
			(xy 270.662026 -49.41581) (xy 270.786392 -49.517875) (xy 270.9056 -49.625919) (xy 271.019363 -49.739682)
			(xy 271.127407 -49.85889) (xy 271.229472 -49.983256) (xy 271.325311 -50.11248) (xy 271.414694 -50.246251)
			(xy 271.497405 -50.384247) (xy 271.573246 -50.526135) (xy 271.642033 -50.671574) (xy 271.703602 -50.820212)
			(xy 271.757802 -50.971693) (xy 271.804505 -51.12565) (xy 271.843597 -51.281714) (xy 271.874984 -51.439508)
			(xy 271.898591 -51.598651) (xy 271.91436 -51.758762) (xy 271.922254 -51.919453) (xy 271.922748 -51.999896)
			(xy 271.922313 -52.078508) (xy 271.914769 -52.23555) (xy 271.899702 -52.39205) (xy 271.877147 -52.547648)
			(xy 271.847157 -52.701985) (xy 271.809799 -52.854705) (xy 271.765161 -53.005459) (xy 271.713345 -53.153899)
			(xy 271.654469 -53.299683) (xy 271.58867 -53.442476) (xy 271.516099 -53.581949) (xy 271.436923 -53.717781)
			(xy 271.351325 -53.84966) (xy 271.2595 -53.977283) (xy 271.161661 -54.100355) (xy 271.058032 -54.218593)
			(xy 271.003776 -54.275482) (xy 270.993108 -54.286404) (xy 270.98752 -54.316376) (xy 271.030192 -54.416452)
			(xy 271.034517 -54.42541) (xy 271.04862 -54.439405) (xy 271.066993 -54.446967) (xy 271.076928 -54.44744)
			(xy 271.09547 -54.44744) (xy 271.107294 -54.446891) (xy 271.128485 -54.436407) (xy 271.142743 -54.417548)
			(xy 271.145508 -54.406038) (xy 271.151916 -54.374659) (xy 271.171588 -54.313709) (xy 271.198754 -54.25571)
			(xy 271.232987 -54.20158) (xy 271.273743 -54.152176) (xy 271.320379 -54.108278) (xy 271.372156 -54.070582)
			(xy 271.428256 -54.039683) (xy 271.48779 -54.016071) (xy 271.549818 -54.000119) (xy 271.613357 -53.99208)
			(xy 271.677403 -53.99208) (xy 271.740942 -54.000119) (xy 271.80297 -54.016071) (xy 271.862504 -54.039683)
			(xy 271.918604 -54.070582) (xy 271.970381 -54.108278) (xy 272.017017 -54.152176) (xy 272.057773 -54.20158)
			(xy 272.092006 -54.25571) (xy 272.119172 -54.313709) (xy 272.138844 -54.374659) (xy 272.145252 -54.406038)
			(xy 272.148091 -54.417508) (xy 272.162363 -54.436303) (xy 272.183492 -54.446817) (xy 272.19529 -54.44744)
			(xy 297.540172 -54.44744) (xy 297.54877 -54.447065) (xy 297.564996 -54.44137) (xy 297.571922 -54.436264)
			(xy 297.60527 -54.410148) (xy 297.675879 -54.363348) (xy 297.75041 -54.323087) (xy 297.82826 -54.289693)
			(xy 297.908797 -54.263434) (xy 297.991369 -54.244524) (xy 298.075308 -54.233117) (xy 298.159932 -54.229304)
			(xy 298.244556 -54.233117) (xy 298.328495 -54.244524) (xy 298.411067 -54.263434) (xy 298.491604 -54.289693)
			(xy 298.569454 -54.323087) (xy 298.643985 -54.363348) (xy 298.714594 -54.410148) (xy 298.747942 -54.436264)
			(xy 298.754873 -54.441369) (xy 298.771092 -54.447097) (xy 298.779692 -54.44744) (xy 300.080172 -54.44744)
			(xy 300.08877 -54.447065) (xy 300.104996 -54.44137) (xy 300.111922 -54.436264) (xy 300.14527 -54.410148)
			(xy 300.215879 -54.363348) (xy 300.29041 -54.323087) (xy 300.36826 -54.289693) (xy 300.448797 -54.263434)
			(xy 300.531369 -54.244524) (xy 300.615308 -54.233117) (xy 300.699932 -54.229304) (xy 300.784556 -54.233117)
			(xy 300.868495 -54.244524) (xy 300.951067 -54.263434) (xy 301.031604 -54.289693) (xy 301.109454 -54.323087)
			(xy 301.183985 -54.363348) (xy 301.254594 -54.410148) (xy 301.287942 -54.436264) (xy 301.294873 -54.441369)
			(xy 301.311092 -54.447097) (xy 301.319692 -54.44744) (xy 302.620172 -54.44744) (xy 302.62877 -54.447065)
			(xy 302.644996 -54.44137) (xy 302.651922 -54.436264) (xy 302.68527 -54.410148) (xy 302.755879 -54.363348)
			(xy 302.83041 -54.323087) (xy 302.90826 -54.289693) (xy 302.988797 -54.263434) (xy 303.071369 -54.244524)
			(xy 303.155308 -54.233117) (xy 303.239932 -54.229304) (xy 303.324556 -54.233117) (xy 303.408495 -54.244524)
			(xy 303.491067 -54.263434) (xy 303.571604 -54.289693) (xy 303.649454 -54.323087) (xy 303.723985 -54.363348)
			(xy 303.794594 -54.410148) (xy 303.827942 -54.436264) (xy 303.834873 -54.441369) (xy 303.851092 -54.447097)
			(xy 303.859692 -54.44744) (xy 384.943858 -54.44744) (xy 384.953412 -54.447037) (xy 384.971168 -54.439978)
			(xy 384.978402 -54.433724) (xy 385.008675 -54.406368) (xy 385.074041 -54.357529) (xy 385.144245 -54.315943)
			(xy 385.218486 -54.282088) (xy 385.295916 -54.256349) (xy 385.375651 -54.23902) (xy 385.45678 -54.230299)
			(xy 385.497578 -54.229762) (xy 385.498086 -54.229762) (xy 385.538888 -54.230265) (xy 385.620026 -54.23896)
			(xy 385.699771 -54.256275) (xy 385.77721 -54.28201) (xy 385.851456 -54.315871) (xy 385.92166 -54.35747)
			(xy 385.987018 -54.406332) (xy 386.017262 -54.433724) (xy 386.024509 -54.439953) (xy 386.04226 -54.446996)
			(xy 386.051806 -54.44744) (xy 421.740584 -54.44744) (xy 421.750301 -54.44704) (xy 421.768342 -54.439812)
			(xy 421.782395 -54.426388) (xy 421.786812 -54.417722) (xy 421.803709 -54.381864) (xy 421.843888 -54.313529)
			(xy 421.890939 -54.24973) (xy 421.944355 -54.191156) (xy 422.003559 -54.13844) (xy 422.067913 -54.09215)
			(xy 422.136721 -54.052786) (xy 422.209242 -54.020772) (xy 422.284693 -53.996455) (xy 422.362259 -53.980096)
			(xy 422.441104 -53.971873) (xy 422.520376 -53.971873) (xy 422.599221 -53.980096) (xy 422.676787 -53.996455)
			(xy 422.752238 -54.020772) (xy 422.824759 -54.052786) (xy 422.893567 -54.09215) (xy 422.957921 -54.13844)
			(xy 423.017125 -54.191156) (xy 423.070541 -54.24973) (xy 423.117592 -54.313529) (xy 423.157771 -54.381864)
			(xy 423.174668 -54.417722) (xy 423.179085 -54.426384) (xy 423.193146 -54.439789) (xy 423.211182 -54.44701)
			(xy 423.220896 -54.44744) (xy 442.696854 -54.44744) (xy 442.706922 -54.447879) (xy 442.725521 -54.455589)
			(xy 442.732922 -54.462426) (xy 449.829682 -61.559186) (xy 449.837096 -61.566009) (xy 449.855684 -61.573739)
			(xy 449.86575 -61.574172) (xy 457.902056 -61.574172) (xy 457.912125 -61.574601) (xy 457.930724 -61.582317)
			(xy 457.938124 -61.589158) (xy 459.913482 -63.56477) (xy 459.920299 -63.572188) (xy 459.928033 -63.590773)
			(xy 459.928468 -63.600838) (xy 459.928468 -71.825358) (xy 459.928029 -71.835426) (xy 459.920319 -71.854024)
			(xy 459.913482 -71.861426) (xy 457.658978 -74.11593) (xy 457.651583 -74.122776) (xy 457.63298 -74.130492)
			(xy 457.62291 -74.130916) (xy 453.393556 -74.130916) (xy 453.383484 -74.131314) (xy 453.364886 -74.139053)
			(xy 453.357488 -74.145902) (xy 452.561198 -74.942192) (xy 452.554369 -74.949601) (xy 452.546643 -74.968193)
			(xy 452.546212 -74.97826) (xy 452.546212 -95.875602) (xy 452.545811 -95.885674) (xy 452.538076 -95.904273)
			(xy 452.531226 -95.91167) (xy 449.370704 -99.072446) (xy 449.363302 -99.079283) (xy 449.344704 -99.087003)
			(xy 449.334636 -99.087432) (xy 436.775352 -99.087432) (xy 436.764717 -99.087814) (xy 436.745252 -99.096382)
			(xy 436.73776 -99.103942) (xy 436.710653 -99.132915) (xy 436.651429 -99.185719) (xy 436.587043 -99.232089)
			(xy 436.51819 -99.271524) (xy 436.445615 -99.303598) (xy 436.370103 -99.327963) (xy 436.292469 -99.344358)
			(xy 436.213553 -99.352604) (xy 436.17388 -99.353116) (xy 436.137124 -99.352674) (xy 436.063949 -99.345634)
			(xy 435.991794 -99.331573) (xy 435.921331 -99.310622) (xy 435.853215 -99.282977) (xy 435.788081 -99.248895)
			(xy 435.757066 -99.229164) (xy 435.748614 -99.224186) (xy 435.72938 -99.220432) (xy 435.710146 -99.224186)
			(xy 435.701694 -99.229164) (xy 435.670663 -99.248864) (xy 435.605518 -99.282915) (xy 435.537401 -99.310546)
			(xy 435.466944 -99.3315) (xy 435.394799 -99.345585) (xy 435.321634 -99.352668) (xy 435.28488 -99.353116)
			(xy 435.245204 -99.35265) (xy 435.166281 -99.344415) (xy 435.088639 -99.328027) (xy 435.013121 -99.303663)
			(xy 434.940541 -99.271585) (xy 434.871687 -99.232142) (xy 434.807301 -99.185761) (xy 434.748083 -99.132941)
			(xy 434.721 -99.103942) (xy 434.713422 -99.096508) (xy 434.694009 -99.087978) (xy 434.683408 -99.087432)
			(xy 332.337918 -99.087432) (xy 332.311248 -99.10699) (xy 332.306168 -99.122992) (xy 332.293675 -99.16133)
			(xy 332.261699 -99.235357) (xy 332.222089 -99.305596) (xy 332.175288 -99.371262) (xy 332.121818 -99.431623)
			(xy 332.062276 -99.486003) (xy 331.997328 -99.533797) (xy 331.927699 -99.574469) (xy 331.854166 -99.607565)
			(xy 331.777552 -99.632717) (xy 331.69871 -99.649642) (xy 331.618523 -99.658153) (xy 331.578204 -99.658678)
			(xy 331.538294 -99.658174) (xy 331.458911 -99.649842) (xy 331.380836 -99.63325) (xy 331.304925 -99.608578)
			(xy 331.232014 -99.576098) (xy 331.197204 -99.55657) (xy 331.189309 -99.552473) (xy 331.171804 -99.549398)
			(xy 331.154299 -99.552473) (xy 331.146404 -99.55657) (xy 331.111578 -99.57606) (xy 331.03866 -99.608503)
			(xy 330.962751 -99.633151) (xy 330.884683 -99.649734) (xy 330.805309 -99.658072) (xy 330.725499 -99.658072)
			(xy 330.646125 -99.649734) (xy 330.568057 -99.633151) (xy 330.492148 -99.608503) (xy 330.41923 -99.57606)
			(xy 330.384404 -99.55657) (xy 330.376509 -99.552473) (xy 330.359004 -99.549398) (xy 330.341499 -99.552473)
			(xy 330.333604 -99.55657) (xy 330.298776 -99.576058) (xy 330.225856 -99.608503) (xy 330.149948 -99.633163)
			(xy 330.071882 -99.649768) (xy 329.99251 -99.658138) (xy 329.952604 -99.658678) (xy 329.912785 -99.658191)
			(xy 329.833582 -99.649887) (xy 329.755676 -99.633368) (xy 329.679918 -99.608815) (xy 329.607133 -99.576496)
			(xy 329.572366 -99.557078) (xy 329.563587 -99.552561) (xy 329.544034 -99.54994) (xy 329.524933 -99.554868)
			(xy 329.51674 -99.56038) (xy 329.483829 -99.584217) (xy 329.413833 -99.625506) (xy 329.339841 -99.659112)
			(xy 329.262693 -99.684655) (xy 329.183265 -99.701843) (xy 329.102459 -99.710482) (xy 329.061826 -99.711002)
			(xy 329.022655 -99.71053) (xy 328.944727 -99.70248) (xy 328.868034 -99.686483) (xy 328.793386 -99.662708)
			(xy 328.721569 -99.631405) (xy 328.65334 -99.592905) (xy 328.589417 -99.547612) (xy 328.530474 -99.496004)
			(xy 328.477133 -99.438625) (xy 328.429956 -99.37608) (xy 328.38944 -99.309028) (xy 328.356011 -99.238175)
			(xy 328.330023 -99.164268) (xy 328.3204 -99.126294) (xy 328.317169 -99.115413) (xy 328.30292 -99.097786)
			(xy 328.282458 -99.088035) (xy 328.271124 -99.087432) (xy 320.737484 -99.087432) (xy 320.726418 -99.087922)
			(xy 320.706312 -99.097162) (xy 320.691961 -99.114005) (xy 320.688462 -99.124516) (xy 320.688462 -99.12477)
			(xy 320.677403 -99.162909) (xy 320.648428 -99.236847) (xy 320.611925 -99.307374) (xy 320.568291 -99.373725)
			(xy 320.517997 -99.435182) (xy 320.461589 -99.49108) (xy 320.399677 -99.540813) (xy 320.332931 -99.583842)
			(xy 320.262075 -99.619702) (xy 320.187877 -99.648003) (xy 320.111138 -99.668441) (xy 320.032692 -99.680792)
			(xy 319.953386 -99.684925) (xy 319.87408 -99.680792) (xy 319.795634 -99.668441) (xy 319.718895 -99.648003)
			(xy 319.644697 -99.619702) (xy 319.573841 -99.583842) (xy 319.507095 -99.540813) (xy 319.445183 -99.49108)
			(xy 319.388775 -99.435182) (xy 319.338481 -99.373725) (xy 319.294847 -99.307374) (xy 319.258344 -99.236847)
			(xy 319.229369 -99.162909) (xy 319.21831 -99.12477) (xy 319.21831 -99.124516) (xy 319.214773 -99.114035)
			(xy 319.200402 -99.097247) (xy 319.180336 -99.087988) (xy 319.169288 -99.087432) (xy 304.14976 -99.087432)
			(xy 304.139687 -99.087828) (xy 304.121089 -99.095568) (xy 304.113692 -99.102418) (xy 300.670214 -102.545896)
			(xy 300.666404 -102.554024) (xy 300.64988 -102.588842) (xy 300.610749 -102.655244) (xy 300.56512 -102.71736)
			(xy 300.513457 -102.774557) (xy 300.456289 -102.826251) (xy 300.394198 -102.871915) (xy 300.327818 -102.911083)
			(xy 300.293024 -102.927658) (xy 300.284642 -102.931468) (xy 298.872442 -104.343651) (xy 326.803 -104.343651)
			(xy 326.803 -104.258929) (xy 326.811053 -104.174592) (xy 326.827087 -104.091402) (xy 326.850955 -104.010112)
			(xy 326.882443 -103.93146) (xy 326.921265 -103.856157) (xy 326.967068 -103.784885) (xy 327.019439 -103.718289)
			(xy 327.077904 -103.656974) (xy 327.141932 -103.601493) (xy 327.210944 -103.55235) (xy 327.284314 -103.50999)
			(xy 327.361379 -103.474795) (xy 327.441441 -103.447086) (xy 327.523774 -103.427112) (xy 327.607633 -103.415055)
			(xy 327.692258 -103.411024) (xy 327.776883 -103.415055) (xy 327.860742 -103.427112) (xy 327.943075 -103.447086)
			(xy 328.023137 -103.474795) (xy 328.100202 -103.50999) (xy 328.173572 -103.55235) (xy 328.242584 -103.601493)
			(xy 328.306612 -103.656974) (xy 328.365077 -103.718289) (xy 328.417448 -103.784885) (xy 328.463251 -103.856157)
			(xy 328.502073 -103.93146) (xy 328.533561 -104.010112) (xy 328.557429 -104.091402) (xy 328.573463 -104.174592)
			(xy 328.581516 -104.258929) (xy 328.58202 -104.30129) (xy 328.581516 -104.343651) (xy 328.573463 -104.427988)
			(xy 328.557429 -104.511178) (xy 328.533561 -104.592468) (xy 328.502073 -104.67112) (xy 328.463251 -104.746423)
			(xy 328.417448 -104.817695) (xy 328.365077 -104.884291) (xy 328.306612 -104.945606) (xy 328.242584 -105.001087)
			(xy 328.173572 -105.05023) (xy 328.100202 -105.09259) (xy 328.023137 -105.127785) (xy 327.943075 -105.155494)
			(xy 327.860742 -105.175468) (xy 327.776883 -105.187525) (xy 327.692258 -105.191557) (xy 327.607633 -105.187525)
			(xy 327.523774 -105.175468) (xy 327.441441 -105.155494) (xy 327.361379 -105.127785) (xy 327.284314 -105.09259)
			(xy 327.210944 -105.05023) (xy 327.141932 -105.001087) (xy 327.077904 -104.945606) (xy 327.019439 -104.884291)
			(xy 326.967068 -104.817695) (xy 326.921265 -104.746423) (xy 326.882443 -104.67112) (xy 326.850955 -104.592468)
			(xy 326.827087 -104.511178) (xy 326.811053 -104.427988) (xy 326.803 -104.343651) (xy 298.872442 -104.343651)
			(xy 278.897588 -124.318268) (xy 278.89178 -124.324493) (xy 278.884392 -124.339822) (xy 278.88311 -124.34824)
			(xy 278.88311 -124.348494) (xy 278.879334 -124.376737) (xy 278.864533 -124.43176) (xy 278.841712 -124.483968)
			(xy 278.811378 -124.532201) (xy 278.774207 -124.575385) (xy 278.731026 -124.61256) (xy 278.682796 -124.642897)
			(xy 278.630589 -124.665723) (xy 278.575568 -124.680528) (xy 278.547322 -124.684282) (xy 278.547068 -124.684282)
			(xy 278.538674 -124.685633) (xy 278.523377 -124.693029) (xy 278.517096 -124.69876) (xy 274.99564 -128.22047)
			(xy 274.988217 -128.227281) (xy 274.969635 -128.235018) (xy 274.959572 -128.235456) (xy 251.619004 -128.235456)
			(xy 251.609642 -128.235921) (xy 251.592168 -128.242646) (xy 251.578277 -128.255199) (xy 251.569823 -128.271905)
			(xy 251.568458 -128.281176) (xy 251.564097 -128.319596) (xy 251.548572 -128.39535) (xy 251.525459 -128.469144)
			(xy 251.494997 -128.540219) (xy 251.457498 -128.607847) (xy 251.413347 -128.671332) (xy 251.362997 -128.730023)
			(xy 251.306966 -128.783316) (xy 251.245829 -128.830665) (xy 251.180214 -128.871583) (xy 251.110794 -128.905651)
			(xy 251.038283 -128.932517) (xy 250.963425 -128.951908) (xy 250.886989 -128.963622) (xy 250.80976 -128.96754)
			(xy 250.732531 -128.963622) (xy 250.656095 -128.951908) (xy 250.581237 -128.932517) (xy 250.508726 -128.905651)
			(xy 250.439306 -128.871583) (xy 250.373691 -128.830665) (xy 250.312554 -128.783316) (xy 250.256523 -128.730023)
			(xy 250.206173 -128.671332) (xy 250.162022 -128.607847) (xy 250.124523 -128.540219) (xy 250.094061 -128.469144)
			(xy 250.070948 -128.39535) (xy 250.055423 -128.319596) (xy 250.051062 -128.281176) (xy 250.04972 -128.271897)
			(xy 250.041263 -128.25518) (xy 250.027366 -128.242616) (xy 250.009883 -128.235881) (xy 250.000516 -128.235456)
			(xy 235.485178 -128.235456) (xy 235.476471 -128.235755) (xy 235.46006 -128.241579) (xy 235.44656 -128.252577)
			(xy 235.441744 -128.25984) (xy 235.421049 -128.293095) (xy 235.373869 -128.355623) (xy 235.320527 -128.412984)
			(xy 235.261585 -128.464574) (xy 235.197664 -128.509849) (xy 235.129438 -128.548331) (xy 235.057626 -128.579616)
			(xy 234.982985 -128.603373) (xy 234.906301 -128.619352) (xy 234.828383 -128.627385) (xy 234.789218 -128.627886)
			(xy 234.75204 -128.627447) (xy 234.678039 -128.620196) (xy 234.605097 -128.605772) (xy 234.533906 -128.584311)
			(xy 234.465143 -128.556019) (xy 234.432094 -128.538986) (xy 234.420738 -128.533677) (xy 234.395698 -128.533677)
			(xy 234.384342 -128.538986) (xy 234.35129 -128.556012) (xy 234.282523 -128.584286) (xy 234.211332 -128.605737)
			(xy 234.138392 -128.620162) (xy 234.064394 -128.627425) (xy 234.027218 -128.627886) (xy 233.988053 -128.627396)
			(xy 233.910135 -128.619358) (xy 233.833453 -128.603375) (xy 233.758812 -128.579615) (xy 233.687001 -128.548328)
			(xy 233.618775 -128.509845) (xy 233.554854 -128.464571) (xy 233.49591 -128.412982) (xy 233.442566 -128.355623)
			(xy 233.395382 -128.293098) (xy 233.374692 -128.25984) (xy 233.369847 -128.252608) (xy 233.356344 -128.241642)
			(xy 233.339955 -128.235815) (xy 233.331258 -128.235456) (xy 219.179648 -128.235456) (xy 219.167704 -128.236074)
			(xy 219.146367 -128.246806) (xy 219.138754 -128.25603) (xy 219.114795 -128.287416) (xy 219.061384 -128.345576)
			(xy 219.00225 -128.397907) (xy 218.938026 -128.443849) (xy 218.8694 -128.48291) (xy 218.797106 -128.514673)
			(xy 218.721917 -128.538797) (xy 218.644638 -128.555025) (xy 218.566096 -128.563183) (xy 218.487132 -128.563183)
			(xy 218.40859 -128.555025) (xy 218.331311 -128.538797) (xy 218.256122 -128.514673) (xy 218.183828 -128.48291)
			(xy 218.115202 -128.443849) (xy 218.050978 -128.397907) (xy 217.991844 -128.345576) (xy 217.938433 -128.287416)
			(xy 217.914474 -128.25603) (xy 217.906833 -128.246839) (xy 217.885514 -128.236104) (xy 217.87358 -128.235456)
			(xy 216.09812 -128.235456) (xy 216.089661 -128.235782) (xy 216.073654 -128.241246) (xy 216.060314 -128.251646)
			(xy 216.055448 -128.25857) (xy 216.033232 -128.29167) (xy 215.982942 -128.353528) (xy 215.926474 -128.409803)
			(xy 215.864445 -128.459882) (xy 215.797531 -128.503218) (xy 215.726461 -128.539338) (xy 215.652012 -128.567848)
			(xy 215.574995 -128.588438) (xy 215.496251 -128.600882) (xy 215.416638 -128.605046) (xy 215.337025 -128.600882)
			(xy 215.258281 -128.588438) (xy 215.181264 -128.567848) (xy 215.106815 -128.539338) (xy 215.035745 -128.503218)
			(xy 214.968831 -128.459882) (xy 214.906802 -128.409803) (xy 214.850334 -128.353528) (xy 214.800044 -128.29167)
			(xy 214.777828 -128.25857) (xy 214.770285 -128.248287) (xy 214.74789 -128.236155) (xy 214.735156 -128.235456)
			(xy 212.291676 -128.235456) (xy 212.282661 -128.235842) (xy 212.26573 -128.242038) (xy 212.251977 -128.253695)
			(xy 212.247226 -128.261364) (xy 212.227997 -128.294729) (xy 212.183796 -128.357796) (xy 212.133461 -128.416085)
			(xy 212.077506 -128.469001) (xy 212.016501 -128.516006) (xy 211.951067 -128.556621) (xy 211.881871 -128.590431)
			(xy 211.809619 -128.617092) (xy 211.735047 -128.636332) (xy 211.658916 -128.647954) (xy 211.582 -128.651842)
			(xy 211.505084 -128.647954) (xy 211.428953 -128.636332) (xy 211.354381 -128.617092) (xy 211.282129 -128.590431)
			(xy 211.212933 -128.556621) (xy 211.147499 -128.516006) (xy 211.086494 -128.469001) (xy 211.030539 -128.416085)
			(xy 210.980204 -128.357796) (xy 210.936003 -128.294729) (xy 210.916774 -128.261364) (xy 210.912092 -128.253634)
			(xy 210.898334 -128.24193) (xy 210.881358 -128.235757) (xy 210.872324 -128.235456) (xy 206.712566 -128.235456)
			(xy 206.701156 -128.23614) (xy 206.680579 -128.246006) (xy 206.672942 -128.254506) (xy 206.65471 -128.276413)
			(xy 206.612853 -128.315096) (xy 206.565712 -128.347128) (xy 206.514333 -128.371796) (xy 206.459858 -128.388552)
			(xy 206.403497 -128.397024) (xy 206.346503 -128.397024) (xy 206.290142 -128.388552) (xy 206.235667 -128.371796)
			(xy 206.184288 -128.347128) (xy 206.137147 -128.315096) (xy 206.09529 -128.276413) (xy 206.077058 -128.254506)
			(xy 206.069513 -128.245884) (xy 206.04888 -128.235973) (xy 206.037434 -128.235456) (xy 204.132434 -128.235456)
			(xy 204.10551 -128.255268) (xy 204.100684 -128.271524) (xy 204.088872 -128.308587) (xy 204.058718 -128.3803)
			(xy 204.021421 -128.448571) (xy 203.977367 -128.51269) (xy 203.927015 -128.571991) (xy 203.870887 -128.625858)
			(xy 203.809567 -128.673731) (xy 203.743692 -128.715113) (xy 203.673947 -128.749574) (xy 203.601055 -128.776755)
			(xy 203.525775 -128.796375) (xy 203.448889 -128.808228) (xy 203.371196 -128.812193) (xy 203.293503 -128.808228)
			(xy 203.216617 -128.796375) (xy 203.141337 -128.776755) (xy 203.068445 -128.749574) (xy 202.9987 -128.715113)
			(xy 202.932825 -128.673731) (xy 202.871505 -128.625858) (xy 202.815377 -128.571991) (xy 202.765025 -128.51269)
			(xy 202.720971 -128.448571) (xy 202.683674 -128.3803) (xy 202.65352 -128.308587) (xy 202.641708 -128.271524)
			(xy 202.636882 -128.255268) (xy 202.609958 -128.235456) (xy 198.199756 -128.235456) (xy 198.187935 -128.236028)
			(xy 198.166745 -128.246501) (xy 198.152485 -128.265351) (xy 198.149718 -128.276858) (xy 198.142318 -128.313895)
			(xy 198.121217 -128.386419) (xy 198.093047 -128.456501) (xy 198.058084 -128.523453) (xy 198.016672 -128.58662)
			(xy 197.969216 -128.645381) (xy 197.916182 -128.699162) (xy 197.858089 -128.747434) (xy 197.795507 -128.789725)
			(xy 197.729049 -128.825619) (xy 197.659368 -128.854766) (xy 197.587146 -128.876879) (xy 197.513091 -128.891741)
			(xy 197.43793 -128.899207) (xy 197.400164 -128.899666) (xy 197.361243 -128.899143) (xy 197.283807 -128.891208)
			(xy 197.207583 -128.875426) (xy 197.133363 -128.85196) (xy 197.06192 -128.821054) (xy 196.993997 -128.78303)
			(xy 196.930302 -128.738284) (xy 196.871497 -128.687282) (xy 196.818195 -128.630554) (xy 196.770949 -128.56869)
			(xy 196.730252 -128.502335) (xy 196.696527 -128.432178) (xy 196.682868 -128.39573) (xy 196.67823 -128.384803)
			(xy 196.661017 -128.368504) (xy 196.649848 -128.364488) (xy 196.608205 -128.35098) (xy 196.528086 -128.315682)
			(xy 196.45254 -128.271434) (xy 196.417184 -128.245616) (xy 196.410446 -128.240944) (xy 196.394898 -128.235765)
			(xy 196.386704 -128.235456) (xy 191.933068 -128.235456) (xy 191.906398 -128.255014) (xy 191.901318 -128.271016)
			(xy 191.889278 -128.30775) (xy 191.85879 -128.378791) (xy 191.82127 -128.446384) (xy 191.777105 -128.509834)
			(xy 191.726748 -128.568491) (xy 191.670715 -128.621752) (xy 191.609582 -128.669071) (xy 191.543975 -128.709963)
			(xy 191.474567 -128.744008) (xy 191.402072 -128.770857) (xy 191.327232 -128.790233) (xy 191.250816 -128.80194)
			(xy 191.173608 -128.805855) (xy 191.0964 -128.80194) (xy 191.019984 -128.790233) (xy 190.945144 -128.770857)
			(xy 190.872649 -128.744008) (xy 190.803241 -128.709963) (xy 190.737634 -128.669071) (xy 190.676501 -128.621752)
			(xy 190.620468 -128.568491) (xy 190.570111 -128.509834) (xy 190.525946 -128.446384) (xy 190.488426 -128.378791)
			(xy 190.457938 -128.30775) (xy 190.445898 -128.271016) (xy 190.440818 -128.255014) (xy 190.414148 -128.235456)
			(xy 173.6344 -128.235456) (xy 173.605444 -128.262126) (xy 173.603666 -128.281684) (xy 173.599771 -128.320511)
			(xy 173.585058 -128.39715) (xy 173.562594 -128.471885) (xy 173.532616 -128.543935) (xy 173.495436 -128.612547)
			(xy 173.451444 -128.677003) (xy 173.401098 -128.736629) (xy 173.344927 -128.790802) (xy 173.283517 -128.838955)
			(xy 173.21751 -128.880584) (xy 173.147597 -128.915255) (xy 173.074508 -128.942605) (xy 172.999009 -128.962347)
			(xy 172.921888 -128.974276) (xy 172.843952 -128.978266) (xy 172.766016 -128.974276) (xy 172.688895 -128.962347)
			(xy 172.613396 -128.942605) (xy 172.540307 -128.915255) (xy 172.470394 -128.880584) (xy 172.404387 -128.838955)
			(xy 172.342977 -128.790802) (xy 172.286806 -128.736629) (xy 172.23646 -128.677003) (xy 172.192468 -128.612547)
			(xy 172.155288 -128.543935) (xy 172.12531 -128.471885) (xy 172.102846 -128.39715) (xy 172.088133 -128.320511)
			(xy 172.084238 -128.281684) (xy 172.08246 -128.262126) (xy 172.053504 -128.235456) (xy 163.93287 -128.235456)
			(xy 163.922348 -128.235951) (xy 163.903056 -128.244341) (xy 163.895532 -128.251712) (xy 163.868483 -128.280256)
			(xy 163.809444 -128.332209) (xy 163.745372 -128.37781) (xy 163.676948 -128.416576) (xy 163.604897 -128.448095)
			(xy 163.529986 -128.472031) (xy 163.453009 -128.488132) (xy 163.374783 -128.496225) (xy 163.296141 -128.496225)
			(xy 163.217915 -128.488132) (xy 163.140938 -128.472031) (xy 163.066027 -128.448095) (xy 162.993976 -128.416576)
			(xy 162.925552 -128.37781) (xy 162.86148 -128.332209) (xy 162.802441 -128.280256) (xy 162.775392 -128.251712)
			(xy 162.767863 -128.244354) (xy 162.74857 -128.235973) (xy 162.738054 -128.235456) (xy 161.384488 -128.235456)
			(xy 161.374417 -128.235049) (xy 161.355818 -128.227317) (xy 161.34842 -128.22047) (xy 156.031438 -122.903234)
			(xy 156.024015 -122.896423) (xy 156.005433 -122.888685) (xy 155.99537 -122.888248) (xy 152.56764 -122.888248)
			(xy 152.558694 -122.888571) (xy 152.541907 -122.894765) (xy 152.528265 -122.906343) (xy 152.519424 -122.9219)
			(xy 152.517602 -122.930666) (xy 152.517602 -122.93092) (xy 152.510989 -122.968756) (xy 152.491143 -123.042961)
			(xy 152.463936 -123.114795) (xy 152.429643 -123.183528) (xy 152.388612 -123.248465) (xy 152.341259 -123.308946)
			(xy 152.288065 -123.364359) (xy 152.229568 -123.414143) (xy 152.166361 -123.457791) (xy 152.099086 -123.494863)
			(xy 152.028423 -123.524981) (xy 151.95509 -123.547841) (xy 151.879831 -123.563211) (xy 151.803407 -123.570935)
			(xy 151.726593 -123.570935) (xy 151.650169 -123.563211) (xy 151.57491 -123.547841) (xy 151.501577 -123.524981)
			(xy 151.430914 -123.494863) (xy 151.363639 -123.457791) (xy 151.300432 -123.414143) (xy 151.241935 -123.364359)
			(xy 151.188741 -123.308946) (xy 151.141388 -123.248465) (xy 151.100357 -123.183528) (xy 151.066064 -123.114795)
			(xy 151.038857 -123.042961) (xy 151.019011 -122.968756) (xy 151.012398 -122.93092) (xy 151.012398 -122.930666)
			(xy 151.010578 -122.921897) (xy 151.001759 -122.906325) (xy 150.988111 -122.89475) (xy 150.971308 -122.888592)
			(xy 150.96236 -122.888248) (xy 142.479776 -122.888248) (xy 142.467925 -122.888836) (xy 142.446734 -122.899452)
			(xy 142.439136 -122.908568) (xy 142.415181 -122.93982) (xy 142.361811 -122.997722) (xy 142.302756 -123.049815)
			(xy 142.238646 -123.095542) (xy 142.170164 -123.134418) (xy 142.098039 -123.166027) (xy 142.023041 -123.190033)
			(xy 141.945967 -123.206181) (xy 141.86764 -123.214298) (xy 141.788892 -123.214298) (xy 141.710565 -123.206181)
			(xy 141.633491 -123.190033) (xy 141.558493 -123.166027) (xy 141.486368 -123.134418) (xy 141.417886 -123.095542)
			(xy 141.353776 -123.049815) (xy 141.294721 -122.997722) (xy 141.241351 -122.93982) (xy 141.217396 -122.908568)
			(xy 141.209804 -122.899451) (xy 141.188605 -122.888859) (xy 141.176756 -122.888248) (xy 130.331718 -122.888248)
			(xy 130.321648 -122.887827) (xy 130.303049 -122.880105) (xy 130.29565 -122.873262) (xy 103.795576 -96.373442)
			(xy 103.788173 -96.366605) (xy 103.769576 -96.358882) (xy 103.759508 -96.358456) (xy 65.444878 -96.358456)
			(xy 65.418716 -96.377252) (xy 65.413382 -96.392746) (xy 65.400132 -96.42985) (xy 65.366965 -96.501322)
			(xy 65.326603 -96.568993) (xy 65.279479 -96.632141) (xy 65.226095 -96.690092) (xy 65.167019 -96.74223)
			(xy 65.102881 -96.787998) (xy 65.034366 -96.826908) (xy 64.962203 -96.858545) (xy 64.887163 -96.882573)
			(xy 64.810046 -96.898734) (xy 64.731672 -96.906857) (xy 64.692276 -96.90735) (xy 64.651247 -96.906808)
			(xy 64.569664 -96.898) (xy 64.4895 -96.88048) (xy 64.411681 -96.854448) (xy 64.33711 -96.820207)
			(xy 64.266648 -96.778153) (xy 64.201112 -96.728772) (xy 64.170814 -96.701102) (xy 64.163496 -96.694862)
			(xy 64.145623 -96.687807) (xy 64.136016 -96.687386) (xy 64.105536 -96.687386) (xy 64.095922 -96.687792)
			(xy 64.078032 -96.694828) (xy 64.070738 -96.701102) (xy 64.040423 -96.728753) (xy 63.974886 -96.778127)
			(xy 63.904425 -96.820177) (xy 63.829857 -96.854418) (xy 63.752042 -96.880454) (xy 63.671882 -96.897983)
			(xy 63.590303 -96.906802) (xy 63.549276 -96.90735) (xy 63.511035 -96.906847) (xy 63.434941 -96.899153)
			(xy 63.36 -96.883875) (xy 63.286967 -96.861167) (xy 63.251588 -96.846644) (xy 63.241995 -96.843091)
			(xy 63.221557 -96.843091) (xy 63.211964 -96.846644) (xy 63.17658 -96.861153) (xy 63.103546 -96.883859)
			(xy 63.028608 -96.899143) (xy 62.952516 -96.906853) (xy 62.914276 -96.90735) (xy 62.874343 -96.906808)
			(xy 62.794915 -96.898458) (xy 62.716794 -96.881851) (xy 62.640838 -96.85717) (xy 62.567877 -96.824685)
			(xy 62.498711 -96.784752) (xy 62.434098 -96.737808) (xy 62.374745 -96.684368) (xy 62.321303 -96.625016)
			(xy 62.274358 -96.560404) (xy 62.234423 -96.49124) (xy 62.201936 -96.418279) (xy 62.177253 -96.342323)
			(xy 62.160645 -96.264203) (xy 62.152293 -96.184775) (xy 62.151768 -96.144842) (xy 62.152166 -96.110552)
			(xy 62.15835 -96.042252) (xy 62.170655 -95.974786) (xy 62.179454 -95.941642) (xy 62.179454 -95.941388)
			(xy 62.18145 -95.932684) (xy 62.179998 -95.914899) (xy 62.172539 -95.898689) (xy 62.1665 -95.892112)
			(xy 57.164478 -90.890344) (xy 57.157661 -90.882926) (xy 57.149929 -90.86434) (xy 57.149492 -90.854276)
			(xy 3.523996 -90.854276) (xy 3.523996 -105.457244) (xy 11.331956 -105.457244) (xy 11.331956 -105.456736)
			(xy 11.332424 -105.418096) (xy 11.340242 -105.341211) (xy 11.355792 -105.265511) (xy 11.378914 -105.19177)
			(xy 11.409372 -105.120744) (xy 11.446853 -105.05316) (xy 11.490973 -104.989712) (xy 11.541281 -104.931048)
			(xy 11.597261 -104.87777) (xy 11.65834 -104.830423) (xy 11.690858 -104.809544) (xy 11.700548 -104.802778)
			(xy 11.712868 -104.782644) (xy 11.71448 -104.770936) (xy 11.717264 -104.74406) (xy 11.729441 -104.691418)
			(xy 11.748916 -104.641018) (xy 11.7753 -104.593867) (xy 11.808067 -104.550905) (xy 11.846563 -104.51299)
			(xy 11.890018 -104.480879) (xy 11.937565 -104.455214) (xy 11.988255 -104.436507) (xy 12.041075 -104.425131)
			(xy 12.094972 -104.421314) (xy 12.148869 -104.425131) (xy 12.201689 -104.436507) (xy 12.252379 -104.455214)
			(xy 12.299926 -104.480879) (xy 12.343381 -104.51299) (xy 12.381877 -104.550905) (xy 12.414644 -104.593867)
			(xy 12.441028 -104.641018) (xy 12.453737 -104.673908) (xy 15.191232 -104.673908) (xy 15.191232 -104.6734)
			(xy 15.191695 -104.634324) (xy 15.199684 -104.556582) (xy 15.215579 -104.480064) (xy 15.239212 -104.405571)
			(xy 15.270336 -104.333885) (xy 15.308626 -104.265756) (xy 15.353679 -104.201897) (xy 15.405024 -104.142979)
			(xy 15.462123 -104.089619) (xy 15.524378 -104.042374) (xy 15.5575 -104.021636) (xy 15.566798 -104.015228)
			(xy 15.579196 -103.996392) (xy 15.581376 -103.985314) (xy 15.585608 -103.958266) (xy 15.600787 -103.905666)
			(xy 15.623323 -103.855773) (xy 15.652753 -103.80961) (xy 15.688475 -103.768124) (xy 15.729756 -103.732165)
			(xy 15.775749 -103.702471) (xy 15.825512 -103.67965) (xy 15.878024 -103.664169) (xy 15.932209 -103.656348)
			(xy 15.959582 -103.655876) (xy 15.98727 -103.656456) (xy 16.042064 -103.664455) (xy 16.095128 -103.680286)
			(xy 16.145348 -103.703619) (xy 16.19167 -103.733963) (xy 16.233121 -103.770682) (xy 16.268831 -103.813004)
			(xy 16.298052 -103.860042) (xy 16.32017 -103.910808) (xy 16.334721 -103.964238) (xy 16.33855 -103.991664)
			(xy 16.340492 -104.002796) (xy 16.352478 -104.021915) (xy 16.361664 -104.028494) (xy 16.39393 -104.049387)
			(xy 16.45448 -104.096751) (xy 16.509958 -104.149967) (xy 16.5598 -104.208494) (xy 16.603501 -104.271739)
			(xy 16.640618 -104.339059) (xy 16.670773 -104.409772) (xy 16.693662 -104.48316) (xy 16.709051 -104.558478)
			(xy 16.716785 -104.634963) (xy 16.717264 -104.6734) (xy 16.716727 -104.714986) (xy 16.707666 -104.797664)
			(xy 16.689663 -104.878866) (xy 16.662932 -104.957626) (xy 16.62779 -105.03301) (xy 16.584653 -105.104123)
			(xy 16.559784 -105.137458) (xy 16.553403 -105.146633) (xy 16.548589 -105.168437) (xy 16.553434 -105.190234)
			(xy 16.559784 -105.199434) (xy 16.584672 -105.232763) (xy 16.627841 -105.30387) (xy 16.663019 -105.37925)
			(xy 16.689789 -105.45801) (xy 16.707833 -105.539215) (xy 16.716937 -105.6219) (xy 16.717518 -105.663492)
			(xy 16.717518 -105.664) (xy 16.717009 -105.704049) (xy 16.708618 -105.783708) (xy 16.691928 -105.862048)
			(xy 16.667123 -105.93821) (xy 16.634477 -106.011354) (xy 16.594348 -106.080675) (xy 16.547177 -106.145411)
			(xy 16.493485 -106.20485) (xy 16.433861 -106.258337) (xy 16.368962 -106.305283) (xy 16.334486 -106.32567)
			(xy 16.334994 -106.343196) (xy 16.334994 -106.343704) (xy 16.334505 -106.370961) (xy 16.326708 -106.424916)
			(xy 16.311316 -106.477214) (xy 16.288642 -106.52679) (xy 16.259147 -106.572637) (xy 16.22343 -106.613823)
			(xy 16.182219 -106.64951) (xy 16.136351 -106.678972) (xy 16.086758 -106.701611) (xy 16.03445 -106.716966)
			(xy 15.98049 -106.724724) (xy 15.953232 -106.725212) (xy 15.925966 -106.724646) (xy 15.871988 -106.71689)
			(xy 15.819663 -106.701531) (xy 15.770056 -106.678882) (xy 15.724177 -106.649404) (xy 15.68296 -106.613698)
			(xy 15.647245 -106.572489) (xy 15.617757 -106.526616) (xy 15.595097 -106.477014) (xy 15.579727 -106.424693)
			(xy 15.57196 -106.370716) (xy 15.57147 -106.34345) (xy 15.571978 -106.324146) (xy 15.537713 -106.303696)
			(xy 15.473213 -106.256709) (xy 15.41397 -106.203246) (xy 15.360632 -106.14389) (xy 15.313783 -106.07929)
			(xy 15.273933 -106.010152) (xy 15.241519 -105.937232) (xy 15.216895 -105.861326) (xy 15.200329 -105.783265)
			(xy 15.192003 -105.7039) (xy 15.191486 -105.664) (xy 15.192013 -105.622413) (xy 15.201074 -105.539735)
			(xy 15.219078 -105.458533) (xy 15.245811 -105.379772) (xy 15.280956 -105.304389) (xy 15.324095 -105.233277)
			(xy 15.348966 -105.199942) (xy 15.355352 -105.190768) (xy 15.360171 -105.168963) (xy 15.355321 -105.147165)
			(xy 15.348966 -105.137966) (xy 15.324085 -105.104632) (xy 15.280914 -105.033527) (xy 15.245734 -104.958148)
			(xy 15.218962 -104.879389) (xy 15.200917 -104.798185) (xy 15.191813 -104.7155) (xy 15.191232 -104.673908)
			(xy 12.453737 -104.673908) (xy 12.460503 -104.691418) (xy 12.47268 -104.74406) (xy 12.475464 -104.770936)
			(xy 12.477095 -104.782635) (xy 12.489417 -104.802758) (xy 12.499086 -104.809544) (xy 12.531623 -104.830393)
			(xy 12.592702 -104.877742) (xy 12.648682 -104.931023) (xy 12.698988 -104.98969) (xy 12.743106 -105.053143)
			(xy 12.780583 -105.12073) (xy 12.811035 -105.19176) (xy 12.834151 -105.265504) (xy 12.849693 -105.341208)
			(xy 12.857502 -105.418095) (xy 12.857988 -105.456736) (xy 12.857411 -105.498321) (xy 12.848357 -105.580998)
			(xy 12.830362 -105.662198) (xy 12.803638 -105.740958) (xy 12.768503 -105.816343) (xy 12.725374 -105.887457)
			(xy 12.700508 -105.920794) (xy 12.694182 -105.930003) (xy 12.689347 -105.951786) (xy 12.69417 -105.973571)
			(xy 12.700508 -105.98277) (xy 12.725402 -106.016095) (xy 12.768572 -106.087202) (xy 12.803751 -106.162583)
			(xy 12.83052 -106.241344) (xy 12.848562 -106.322549) (xy 12.857663 -106.405236) (xy 12.858242 -106.446828)
			(xy 12.858242 -106.447336) (xy 12.857752 -106.485976) (xy 12.849937 -106.56286) (xy 12.83439 -106.63856)
			(xy 12.81127 -106.7123) (xy 12.780815 -106.783326) (xy 12.743337 -106.85091) (xy 12.699218 -106.914359)
			(xy 12.648912 -106.973023) (xy 12.592934 -107.026302) (xy 12.531857 -107.073649) (xy 12.49934 -107.094528)
			(xy 12.489661 -107.101307) (xy 12.477335 -107.121431) (xy 12.475718 -107.133136) (xy 12.472934 -107.160012)
			(xy 12.460757 -107.212654) (xy 12.441282 -107.263054) (xy 12.414898 -107.310205) (xy 12.382131 -107.353167)
			(xy 12.343635 -107.391082) (xy 12.30018 -107.423193) (xy 12.252633 -107.448858) (xy 12.201943 -107.467565)
			(xy 12.149123 -107.478941) (xy 12.095226 -107.482758) (xy 12.041329 -107.478941) (xy 11.988509 -107.467565)
			(xy 11.937819 -107.448858) (xy 11.890272 -107.423193) (xy 11.846817 -107.391082) (xy 11.808321 -107.353167)
			(xy 11.775554 -107.310205) (xy 11.74917 -107.263054) (xy 11.729695 -107.212654) (xy 11.717518 -107.160012)
			(xy 11.714734 -107.133136) (xy 11.713119 -107.121433) (xy 11.700786 -107.101312) (xy 11.691112 -107.094528)
			(xy 11.658597 -107.073646) (xy 11.597516 -107.026302) (xy 11.541534 -106.973026) (xy 11.491226 -106.914363)
			(xy 11.447106 -106.850914) (xy 11.409627 -106.783331) (xy 11.379172 -106.712304) (xy 11.356054 -106.638562)
			(xy 11.340509 -106.562861) (xy 11.332698 -106.485976) (xy 11.33221 -106.447336) (xy 11.332772 -106.40575)
			(xy 11.341829 -106.323073) (xy 11.359827 -106.241873) (xy 11.386554 -106.163113) (xy 11.421692 -106.087728)
			(xy 11.464823 -106.016614) (xy 11.48969 -105.983278) (xy 11.496041 -105.974084) (xy 11.500868 -105.952292)
			(xy 11.496034 -105.930501) (xy 11.48969 -105.921302) (xy 11.464829 -105.887953) (xy 11.421654 -105.816852)
			(xy 11.386471 -105.741476) (xy 11.359696 -105.66272) (xy 11.341647 -105.581518) (xy 11.332539 -105.498835)
			(xy 11.331956 -105.457244) (xy 3.523996 -105.457244) (xy 3.523996 -108.91672) (xy 10.911355 -108.91672)
			(xy 10.915267 -108.839581) (xy 10.926963 -108.763233) (xy 10.946323 -108.68846) (xy 10.973148 -108.616029)
			(xy 11.007163 -108.546684) (xy 11.04802 -108.481136) (xy 11.095298 -108.420058) (xy 11.148513 -108.364076)
			(xy 11.207118 -108.313765) (xy 11.270513 -108.269641) (xy 11.338046 -108.232157) (xy 11.409025 -108.201698)
			(xy 11.482721 -108.178575) (xy 11.558379 -108.163027) (xy 11.635221 -108.155213) (xy 11.67384 -108.154724)
			(xy 11.716531 -108.155337) (xy 11.801378 -108.164874) (xy 11.884631 -108.183824) (xy 11.965247 -108.211951)
			(xy 12.042218 -108.248902) (xy 12.078716 -108.271056) (xy 12.086972 -108.27577) (xy 12.10564 -108.279297)
			(xy 12.124308 -108.27577) (xy 12.132564 -108.271056) (xy 12.169057 -108.248889) (xy 12.246018 -108.211905)
			(xy 12.326634 -108.183763) (xy 12.409892 -108.164816) (xy 12.494746 -108.155302) (xy 12.53744 -108.154724)
			(xy 12.57606 -108.155205) (xy 12.652903 -108.163019) (xy 12.728561 -108.178567) (xy 12.802258 -108.20169)
			(xy 12.873238 -108.23215) (xy 12.940772 -108.269634) (xy 13.004167 -108.313759) (xy 13.062773 -108.36407)
			(xy 13.115988 -108.420053) (xy 13.163267 -108.481132) (xy 13.204124 -108.54668) (xy 13.238139 -108.616026)
			(xy 13.264965 -108.688458) (xy 13.284325 -108.763231) (xy 13.296021 -108.83958) (xy 13.299934 -108.91672)
			(xy 13.296021 -108.99386) (xy 13.284325 -109.070209) (xy 13.264965 -109.144982) (xy 13.238139 -109.217414)
			(xy 13.204124 -109.28676) (xy 13.163267 -109.352308) (xy 13.115988 -109.413387) (xy 13.105215 -109.42472)
			(xy 14.711428 -109.42472) (xy 14.71534 -109.347579) (xy 14.727037 -109.271229) (xy 14.746397 -109.196454)
			(xy 14.773223 -109.124022) (xy 14.80724 -109.054675) (xy 14.848097 -108.989126) (xy 14.895377 -108.928046)
			(xy 14.948593 -108.872063) (xy 15.0072 -108.82175) (xy 15.070596 -108.777626) (xy 15.138131 -108.740141)
			(xy 15.209112 -108.709681) (xy 15.28281 -108.686558) (xy 15.35847 -108.67101) (xy 15.435314 -108.663196)
			(xy 15.473934 -108.662724) (xy 15.515549 -108.663267) (xy 15.598284 -108.672338) (xy 15.679539 -108.690368)
			(xy 15.758345 -108.717142) (xy 15.833766 -108.752342) (xy 15.904904 -108.795549) (xy 15.938246 -108.820458)
			(xy 15.947436 -108.826826) (xy 15.969234 -108.831681) (xy 15.991032 -108.826826) (xy 16.000222 -108.820458)
			(xy 16.033551 -108.795531) (xy 16.104692 -108.752329) (xy 16.180116 -108.717134) (xy 16.258925 -108.690366)
			(xy 16.340182 -108.672342) (xy 16.422918 -108.663279) (xy 16.464534 -108.662724) (xy 16.503154 -108.663205)
			(xy 16.579996 -108.67102) (xy 16.655654 -108.686568) (xy 16.729351 -108.709691) (xy 16.80033 -108.740151)
			(xy 16.867864 -108.777636) (xy 16.931259 -108.82176) (xy 16.989864 -108.872072) (xy 17.043079 -108.928054)
			(xy 17.090358 -108.989133) (xy 17.131214 -109.054682) (xy 17.16523 -109.124027) (xy 17.192055 -109.196458)
			(xy 17.211415 -109.271232) (xy 17.223111 -109.34758) (xy 17.227024 -109.42472) (xy 17.223111 -109.50186)
			(xy 17.211415 -109.578208) (xy 17.192055 -109.652982) (xy 17.16523 -109.725413) (xy 17.131214 -109.794758)
			(xy 17.090358 -109.860307) (xy 17.043079 -109.921386) (xy 16.989864 -109.977368) (xy 16.931259 -110.02768)
			(xy 16.867864 -110.071804) (xy 16.80033 -110.109289) (xy 16.729351 -110.139749) (xy 16.655654 -110.162872)
			(xy 16.579996 -110.17842) (xy 16.503154 -110.186235) (xy 16.464534 -110.186724) (xy 16.422919 -110.186154)
			(xy 16.340185 -110.17709) (xy 16.258931 -110.159066) (xy 16.180124 -110.132297) (xy 16.104702 -110.097101)
			(xy 16.033565 -110.053897) (xy 16.000222 -110.02899) (xy 15.991032 -110.022622) (xy 15.969234 -110.017767)
			(xy 15.947436 -110.022622) (xy 15.938246 -110.02899) (xy 15.904889 -110.053878) (xy 15.833755 -110.097087)
			(xy 15.758338 -110.132288) (xy 15.679533 -110.159064) (xy 15.598281 -110.177095) (xy 15.515548 -110.186166)
			(xy 15.473934 -110.186724) (xy 15.435314 -110.186244) (xy 15.35847 -110.17843) (xy 15.28281 -110.162882)
			(xy 15.209112 -110.139759) (xy 15.138131 -110.109299) (xy 15.070596 -110.071814) (xy 15.0072 -110.02769)
			(xy 14.948593 -109.977377) (xy 14.895377 -109.921394) (xy 14.848097 -109.860314) (xy 14.80724 -109.794765)
			(xy 14.773223 -109.725418) (xy 14.746397 -109.652986) (xy 14.727037 -109.578211) (xy 14.71534 -109.501861)
			(xy 14.711428 -109.42472) (xy 13.105215 -109.42472) (xy 13.062773 -109.46937) (xy 13.004167 -109.519681)
			(xy 12.940772 -109.563806) (xy 12.873238 -109.60129) (xy 12.802258 -109.63175) (xy 12.728561 -109.654873)
			(xy 12.652903 -109.670421) (xy 12.57606 -109.678235) (xy 12.53744 -109.678724) (xy 12.494749 -109.678113)
			(xy 12.409902 -109.668574) (xy 12.32665 -109.649623) (xy 12.246034 -109.621496) (xy 12.169062 -109.584546)
			(xy 12.132564 -109.562392) (xy 12.124308 -109.557678) (xy 12.10564 -109.554151) (xy 12.086972 -109.557678)
			(xy 12.078716 -109.562392) (xy 12.042225 -109.584562) (xy 11.965263 -109.621546) (xy 11.884647 -109.649688)
			(xy 11.801389 -109.668635) (xy 11.716534 -109.678147) (xy 11.67384 -109.678724) (xy 11.635221 -109.678227)
			(xy 11.558379 -109.670413) (xy 11.482721 -109.654865) (xy 11.409025 -109.631742) (xy 11.338046 -109.601283)
			(xy 11.270513 -109.563799) (xy 11.207118 -109.519675) (xy 11.148513 -109.469364) (xy 11.095298 -109.413382)
			(xy 11.04802 -109.352304) (xy 11.007163 -109.286756) (xy 10.973148 -109.217411) (xy 10.946323 -109.14498)
			(xy 10.926963 -109.070207) (xy 10.915267 -108.993859) (xy 10.911355 -108.91672) (xy 3.523996 -108.91672)
			(xy 3.523996 -114.706908) (xy 10.87247 -114.706908) (xy 10.87247 -114.706654) (xy 10.87298 -114.66817)
			(xy 10.880745 -114.591595) (xy 10.896173 -114.516189) (xy 10.919107 -114.442718) (xy 10.949314 -114.371925)
			(xy 10.986488 -114.30453) (xy 11.030251 -114.241214) (xy 11.054842 -114.211608) (xy 11.062165 -114.20185)
			(xy 11.067616 -114.17811) (xy 11.065256 -114.166142) (xy 11.059881 -114.143214) (xy 11.054145 -114.096471)
			(xy 11.053826 -114.072924) (xy 11.054324 -114.045654) (xy 11.062082 -113.991669) (xy 11.077445 -113.939338)
			(xy 11.100099 -113.889726) (xy 11.129583 -113.843842) (xy 11.165297 -113.802622) (xy 11.206513 -113.766904)
			(xy 11.252394 -113.737416) (xy 11.302004 -113.714758) (xy 11.354334 -113.69939) (xy 11.408318 -113.691626)
			(xy 11.435588 -113.691162) (xy 11.464348 -113.691607) (xy 11.521219 -113.700227) (xy 11.57615 -113.71729)
			(xy 11.627897 -113.742408) (xy 11.675284 -113.775011) (xy 11.717239 -113.814361) (xy 11.75281 -113.859564)
			(xy 11.781189 -113.909596) (xy 11.79195 -113.936272) (xy 11.796971 -113.947373) (xy 11.815142 -113.963552)
			(xy 11.826748 -113.96726) (xy 11.86443 -113.977473) (xy 11.937662 -114.004548) (xy 12.007754 -114.038944)
			(xy 12.041124 -114.059208) (xy 12.04938 -114.063922) (xy 12.068048 -114.067449) (xy 12.086716 -114.063922)
			(xy 12.094972 -114.059208) (xy 12.128342 -114.038941) (xy 12.198427 -114.00453) (xy 12.271662 -113.97746)
			(xy 12.309348 -113.96726) (xy 12.320954 -113.963549) (xy 12.339127 -113.947374) (xy 12.344146 -113.936272)
			(xy 12.354927 -113.909611) (xy 12.383331 -113.859608) (xy 12.418914 -113.814432) (xy 12.460871 -113.775104)
			(xy 12.508252 -113.742514) (xy 12.559985 -113.7174) (xy 12.6149 -113.70033) (xy 12.671755 -113.69169)
			(xy 12.700508 -113.691162) (xy 12.72778 -113.691594) (xy 12.78177 -113.699358) (xy 12.834104 -113.714726)
			(xy 12.883719 -113.737387) (xy 12.929604 -113.766877) (xy 12.970824 -113.802598) (xy 13.006542 -113.843822)
			(xy 13.036029 -113.889709) (xy 13.058685 -113.939326) (xy 13.074049 -113.991662) (xy 13.081808 -114.045652)
			(xy 13.08227 -114.072924) (xy 13.081951 -114.096471) (xy 13.076219 -114.143215) (xy 13.07084 -114.166142)
			(xy 13.068475 -114.178109) (xy 13.07393 -114.201851) (xy 13.081254 -114.211608) (xy 13.105842 -114.241217)
			(xy 13.149611 -114.30453) (xy 13.18679 -114.371924) (xy 13.217001 -114.442716) (xy 13.239938 -114.516187)
			(xy 13.255368 -114.591594) (xy 13.263134 -114.66817) (xy 13.263626 -114.706654) (xy 13.263626 -114.706908)
			(xy 13.263062 -114.746907) (xy 13.2547 -114.826467) (xy 13.238067 -114.904717) (xy 13.213347 -114.980799)
			(xy 13.180809 -115.053882) (xy 13.140811 -115.123163) (xy 13.093791 -115.187883) (xy 13.040263 -115.247335)
			(xy 12.980814 -115.300865) (xy 12.916096 -115.347889) (xy 12.846817 -115.387891) (xy 12.773737 -115.420432)
			(xy 12.697655 -115.445157) (xy 12.619406 -115.461793) (xy 12.539847 -115.47016) (xy 12.499848 -115.470686)
			(xy 12.457159 -115.470054) (xy 12.372317 -115.460497) (xy 12.28907 -115.441542) (xy 12.208454 -115.413424)
			(xy 12.131476 -115.376494) (xy 12.094972 -115.354354) (xy 12.086711 -115.349658) (xy 12.068048 -115.34615)
			(xy 12.049385 -115.349658) (xy 12.041124 -115.354354) (xy 12.004617 -115.376492) (xy 11.927645 -115.413439)
			(xy 11.847031 -115.441568) (xy 11.763782 -115.460527) (xy 11.678938 -115.47008) (xy 11.636248 -115.470686)
			(xy 11.596248 -115.470127) (xy 11.516685 -115.461769) (xy 11.438432 -115.445141) (xy 11.362346 -115.420423)
			(xy 11.28926 -115.387888) (xy 11.219976 -115.347891) (xy 11.155252 -115.30087) (xy 11.095798 -115.247342)
			(xy 11.042265 -115.187892) (xy 10.99524 -115.123171) (xy 10.955238 -115.05389) (xy 10.922697 -114.980807)
			(xy 10.897974 -114.904722) (xy 10.881339 -114.82647) (xy 10.872976 -114.746908) (xy 10.87247 -114.706908)
			(xy 3.523996 -114.706908) (xy 3.523996 -133.480302) (xy 19.798792 -133.480302) (xy 19.799341 -133.438687)
			(xy 19.808409 -133.355951) (xy 19.826436 -133.274697) (xy 19.85321 -133.19589) (xy 19.88841 -133.120469)
			(xy 19.931617 -133.049332) (xy 19.956526 -133.01599) (xy 19.962893 -133.006799) (xy 19.967749 -132.985002)
			(xy 19.962894 -132.963204) (xy 19.956526 -132.954014) (xy 19.931625 -132.920666) (xy 19.888418 -132.849531)
			(xy 19.853218 -132.774111) (xy 19.826445 -132.695305) (xy 19.808417 -132.614051) (xy 19.799349 -132.531317)
			(xy 19.798792 -132.489702) (xy 19.799281 -132.451083) (xy 19.807095 -132.37424) (xy 19.822643 -132.298582)
			(xy 19.845766 -132.224885) (xy 19.876225 -132.153906) (xy 19.91371 -132.086372) (xy 19.957834 -132.022978)
			(xy 20.008145 -131.964372) (xy 20.064127 -131.911157) (xy 20.125206 -131.863878) (xy 20.190754 -131.823022)
			(xy 20.2601 -131.789006) (xy 20.332531 -131.762181) (xy 20.407304 -131.742821) (xy 20.483652 -131.731125)
			(xy 20.560792 -131.727213) (xy 20.637932 -131.731125) (xy 20.71428 -131.742821) (xy 20.789053 -131.762181)
			(xy 20.861484 -131.789006) (xy 20.93083 -131.823022) (xy 20.996378 -131.863878) (xy 21.057457 -131.911157)
			(xy 21.113439 -131.964372) (xy 21.16375 -132.022978) (xy 21.207874 -132.086372) (xy 21.245359 -132.153906)
			(xy 21.275818 -132.224885) (xy 21.298941 -132.298582) (xy 21.314489 -132.37424) (xy 21.322303 -132.451083)
			(xy 21.322792 -132.489702) (xy 21.322228 -132.531317) (xy 21.313161 -132.614051) (xy 21.295135 -132.695305)
			(xy 21.268364 -132.774112) (xy 21.233168 -132.849533) (xy 21.189965 -132.920671) (xy 21.165058 -132.954014)
			(xy 21.158689 -132.963204) (xy 21.153835 -132.985002) (xy 21.158691 -133.006799) (xy 21.165058 -133.01599)
			(xy 21.189973 -133.049328) (xy 21.233176 -133.120467) (xy 21.268372 -133.195889) (xy 21.295143 -133.274697)
			(xy 21.313169 -133.355952) (xy 21.322236 -133.438687) (xy 21.322792 -133.480302) (xy 21.322303 -133.518921)
			(xy 21.314489 -133.595764) (xy 21.298941 -133.671422) (xy 21.275818 -133.745119) (xy 21.245359 -133.816098)
			(xy 21.207874 -133.883632) (xy 21.16375 -133.947026) (xy 21.113439 -134.005632) (xy 21.057457 -134.058847)
			(xy 20.996378 -134.106126) (xy 20.93083 -134.146982) (xy 20.861484 -134.180998) (xy 20.789053 -134.207823)
			(xy 20.71428 -134.227183) (xy 20.637932 -134.238879) (xy 20.560792 -134.242792) (xy 20.483652 -134.238879)
			(xy 20.407304 -134.227183) (xy 20.332531 -134.207823) (xy 20.2601 -134.180998) (xy 20.190754 -134.146982)
			(xy 20.125206 -134.106126) (xy 20.064127 -134.058847) (xy 20.008145 -134.005632) (xy 19.957834 -133.947026)
			(xy 19.91371 -133.883632) (xy 19.876225 -133.816098) (xy 19.845766 -133.745119) (xy 19.822643 -133.671422)
			(xy 19.807095 -133.595764) (xy 19.799281 -133.518921) (xy 19.798792 -133.480302) (xy 3.523996 -133.480302)
			(xy 3.523996 -138.293856) (xy 19.36242 -138.293856) (xy 19.362914 -138.264803) (xy 19.371712 -138.207366)
			(xy 19.389113 -138.151926) (xy 19.414716 -138.099764) (xy 19.447928 -138.052085) (xy 19.487983 -138.00999)
			(xy 19.533956 -137.974452) (xy 19.584783 -137.946292) (xy 19.611848 -137.935716) (xy 19.620314 -137.932186)
			(xy 19.634173 -137.92019) (xy 19.642948 -137.904096) (xy 19.644614 -137.895076) (xy 19.650568 -137.856288)
			(xy 19.669396 -137.780102) (xy 19.695946 -137.706251) (xy 19.729938 -137.635517) (xy 19.771012 -137.568646)
			(xy 19.794474 -137.53719) (xy 19.800816 -137.527991) (xy 19.805648 -137.506202) (xy 19.800818 -137.484412)
			(xy 19.794474 -137.475214) (xy 19.769602 -137.441858) (xy 19.726489 -137.370689) (xy 19.691363 -137.295258)
			(xy 19.664639 -137.216457) (xy 19.646634 -137.135219) (xy 19.637562 -137.052506) (xy 19.636994 -137.010902)
			(xy 19.636994 -137.000742) (xy 19.636639 -136.990778) (xy 19.629277 -136.972268) (xy 19.615443 -136.957936)
			(xy 19.606514 -136.953498) (xy 19.581281 -136.942013) (xy 19.534172 -136.912787) (xy 19.491784 -136.877056)
			(xy 19.455008 -136.835572) (xy 19.424616 -136.789206) (xy 19.401248 -136.738933) (xy 19.385394 -136.685809)
			(xy 19.377388 -136.630951) (xy 19.376898 -136.603232) (xy 19.377454 -136.575965) (xy 19.38521 -136.521986)
			(xy 19.40057 -136.46966) (xy 19.423219 -136.420053) (xy 19.452698 -136.374174) (xy 19.488406 -136.332957)
			(xy 19.529616 -136.297241) (xy 19.57549 -136.267754) (xy 19.625093 -136.245095) (xy 19.677416 -136.229726)
			(xy 19.731393 -136.221959) (xy 19.75866 -136.22147) (xy 19.786202 -136.221975) (xy 19.840708 -136.229942)
			(xy 19.893503 -136.245658) (xy 19.943492 -136.268798) (xy 19.989637 -136.298881) (xy 20.010628 -136.31672)
			(xy 20.018435 -136.322974) (xy 20.037347 -136.329438) (xy 20.057298 -136.328248) (xy 20.066508 -136.32434)
			(xy 20.105658 -136.305913) (xy 20.187222 -136.277019) (xy 20.271533 -136.257544) (xy 20.357507 -136.247735)
			(xy 20.400772 -136.247124) (xy 20.440773 -136.247654) (xy 20.520337 -136.256014) (xy 20.598591 -136.272645)
			(xy 20.674678 -136.297364) (xy 20.747764 -136.329902) (xy 20.817049 -136.369902) (xy 20.881773 -136.416924)
			(xy 20.941227 -136.470455) (xy 20.99476 -136.529907) (xy 21.041784 -136.594629) (xy 21.081786 -136.663912)
			(xy 21.114326 -136.736998) (xy 21.139049 -136.813084) (xy 21.155682 -136.891337) (xy 21.164045 -136.970901)
			(xy 21.16455 -137.010902) (xy 21.164007 -137.052508) (xy 21.154947 -137.135225) (xy 21.136945 -137.216466)
			(xy 21.110215 -137.295268) (xy 21.075075 -137.370696) (xy 21.03194 -137.441855) (xy 21.00707 -137.475214)
			(xy 21.00073 -137.484413) (xy 20.995904 -137.506202) (xy 21.000731 -137.52799) (xy 21.00707 -137.53719)
			(xy 21.031936 -137.57055) (xy 21.075051 -137.641717) (xy 21.110179 -137.717148) (xy 21.136904 -137.795948)
			(xy 21.15491 -137.877185) (xy 21.163982 -137.959898) (xy 21.16455 -138.001502) (xy 21.164074 -138.041504)
			(xy 21.155711 -138.121071) (xy 21.139077 -138.199327) (xy 21.114353 -138.275416) (xy 21.081811 -138.348504)
			(xy 21.041808 -138.417789) (xy 20.994781 -138.482514) (xy 20.941247 -138.541968) (xy 20.88179 -138.5955)
			(xy 20.817064 -138.642524) (xy 20.747777 -138.682525) (xy 20.674688 -138.715064) (xy 20.598598 -138.739784)
			(xy 20.520341 -138.756416) (xy 20.440774 -138.764776) (xy 20.400772 -138.76528) (xy 20.363005 -138.764817)
			(xy 20.287841 -138.757356) (xy 20.21378 -138.74251) (xy 20.141547 -138.720424) (xy 20.071848 -138.691313)
			(xy 20.005364 -138.655463) (xy 19.973798 -138.634724) (xy 19.965977 -138.629959) (xy 19.948169 -138.625746)
			(xy 19.930011 -138.628024) (xy 19.921728 -138.63193) (xy 19.894232 -138.64571) (xy 19.835893 -138.66518)
			(xy 19.775187 -138.675037) (xy 19.744436 -138.675618) (xy 19.744182 -138.675618) (xy 19.716909 -138.675215)
			(xy 19.662917 -138.667449) (xy 19.610581 -138.652079) (xy 19.560965 -138.629416) (xy 19.515079 -138.599922)
			(xy 19.473858 -138.564198) (xy 19.438141 -138.522971) (xy 19.408655 -138.477081) (xy 19.386 -138.427461)
			(xy 19.370637 -138.375122) (xy 19.36288 -138.32113) (xy 19.36242 -138.293856) (xy 3.523996 -138.293856)
			(xy 3.523996 -178.618388) (xy 8.34263 -178.618388) (xy 8.343231 -178.575698) (xy 8.352795 -178.490855)
			(xy 8.371757 -178.407607) (xy 8.399882 -178.326992) (xy 8.436819 -178.250015) (xy 8.458962 -178.213512)
			(xy 8.463669 -178.205256) (xy 8.467176 -178.18659) (xy 8.463662 -178.167925) (xy 8.458962 -178.159664)
			(xy 8.436801 -178.123171) (xy 8.399858 -178.046195) (xy 8.371734 -177.965577) (xy 8.35278 -177.882326)
			(xy 8.343233 -177.797479) (xy 8.34263 -177.754788) (xy 8.343169 -177.715964) (xy 8.351054 -177.638717)
			(xy 8.36674 -177.56267) (xy 8.390066 -177.488608) (xy 8.420791 -177.417298) (xy 8.458597 -177.349475)
			(xy 8.503094 -177.285841) (xy 8.553821 -177.227053) (xy 8.610254 -177.173719) (xy 8.671811 -177.12639)
			(xy 8.70458 -177.105564) (xy 8.713867 -177.099093) (xy 8.726142 -177.080116) (xy 8.728202 -177.068988)
			(xy 8.732385 -177.041468) (xy 8.747702 -176.987954) (xy 8.770643 -176.93724) (xy 8.800721 -176.890403)
			(xy 8.818626 -176.86909) (xy 8.81888 -176.868836) (xy 8.824467 -176.86175) (xy 8.830711 -176.844832)
			(xy 8.831072 -176.835816) (xy 8.831072 -176.76876) (xy 8.83074 -176.75974) (xy 8.824476 -176.742823)
			(xy 8.81888 -176.73574) (xy 8.818626 -176.735486) (xy 8.800579 -176.714037) (xy 8.770345 -176.666837)
			(xy 8.747339 -176.615722) (xy 8.732054 -176.561793) (xy 8.727948 -176.534064) (xy 8.725926 -176.522923)
			(xy 8.713637 -176.503935) (xy 8.704326 -176.497488) (xy 8.671573 -176.476649) (xy 8.610045 -176.429304)
			(xy 8.553639 -176.375959) (xy 8.502938 -176.317166) (xy 8.458466 -176.25353) (xy 8.420682 -176.18571)
			(xy 8.389975 -176.114405) (xy 8.366664 -176.040353) (xy 8.350988 -175.964316) (xy 8.343109 -175.887082)
			(xy 8.34263 -175.848264) (xy 8.343219 -175.805574) (xy 8.352786 -175.72073) (xy 8.371751 -175.637482)
			(xy 8.399879 -175.556868) (xy 8.436818 -175.479891) (xy 8.458962 -175.443388) (xy 8.463688 -175.435141)
			(xy 8.467189 -175.416469) (xy 8.463666 -175.397801) (xy 8.458962 -175.38954) (xy 8.436791 -175.353053)
			(xy 8.39985 -175.276075) (xy 8.371728 -175.195456) (xy 8.352776 -175.112203) (xy 8.343231 -175.027355)
			(xy 8.34263 -174.984664) (xy 8.34311 -174.945847) (xy 8.350992 -174.868613) (xy 8.36667 -174.792578)
			(xy 8.389983 -174.718526) (xy 8.42069 -174.647222) (xy 8.458474 -174.579402) (xy 8.502945 -174.515766)
			(xy 8.553644 -174.456972) (xy 8.610047 -174.403625) (xy 8.671572 -174.356278) (xy 8.704326 -174.33544)
			(xy 8.713613 -174.328974) (xy 8.725874 -174.309988) (xy 8.727948 -174.298864) (xy 8.73204 -174.271133)
			(xy 8.747328 -174.217204) (xy 8.770342 -174.166092) (xy 8.800587 -174.118898) (xy 8.818626 -174.097442)
			(xy 8.81888 -174.097188) (xy 8.824487 -174.090116) (xy 8.830719 -174.073188) (xy 8.831072 -174.064168)
			(xy 8.831072 -173.997112) (xy 8.830715 -173.988095) (xy 8.824468 -173.971178) (xy 8.81888 -173.964092)
			(xy 8.818626 -173.963838) (xy 8.800759 -173.942498) (xy 8.770706 -173.895654) (xy 8.747763 -173.844948)
			(xy 8.732414 -173.791452) (xy 8.728202 -173.76394) (xy 8.726098 -173.752828) (xy 8.713843 -173.733853)
			(xy 8.70458 -173.727364) (xy 8.671806 -173.706542) (xy 8.610238 -173.65922) (xy 8.553794 -173.605891)
			(xy 8.503058 -173.547106) (xy 8.458553 -173.483472) (xy 8.42074 -173.415648) (xy 8.39001 -173.344334)
			(xy 8.366681 -173.270269) (xy 8.350994 -173.194218) (xy 8.34311 -173.116966) (xy 8.34263 -173.07814)
			(xy 8.343255 -173.035451) (xy 8.352813 -172.950609) (xy 8.37177 -172.867361) (xy 8.39989 -172.786746)
			(xy 8.436821 -172.709768) (xy 8.458962 -172.673264) (xy 8.463627 -172.664987) (xy 8.467148 -172.646334)
			(xy 8.463652 -172.627677) (xy 8.458962 -172.619416) (xy 8.436823 -172.58291) (xy 8.399876 -172.505938)
			(xy 8.371747 -172.425324) (xy 8.352788 -172.342075) (xy 8.343235 -172.25723) (xy 8.34263 -172.21454)
			(xy 8.343131 -172.175715) (xy 8.35102 -172.098467) (xy 8.366711 -172.022419) (xy 8.390042 -171.948357)
			(xy 8.420771 -171.877046) (xy 8.458582 -171.809223) (xy 8.503082 -171.745589) (xy 8.553813 -171.686802)
			(xy 8.61025 -171.633469) (xy 8.67181 -171.586142) (xy 8.70458 -171.565316) (xy 8.713885 -171.558867)
			(xy 8.726151 -171.539874) (xy 8.728202 -171.52874) (xy 8.732408 -171.501224) (xy 8.747717 -171.44771)
			(xy 8.770652 -171.396994) (xy 8.800724 -171.350157) (xy 8.818626 -171.328842) (xy 8.81888 -171.328588)
			(xy 8.824487 -171.321516) (xy 8.830719 -171.304588) (xy 8.831072 -171.295568) (xy 8.831072 -171.228766)
			(xy 8.830684 -171.219576) (xy 8.824156 -171.202392) (xy 8.818372 -171.195238) (xy 8.799035 -171.172234)
			(xy 8.767134 -171.121308) (xy 8.743622 -171.066006) (xy 8.729082 -171.007699) (xy 8.725916 -170.977814)
			(xy 8.724266 -170.966119) (xy 8.711958 -170.945994) (xy 8.702294 -170.939206) (xy 8.669874 -170.918316)
			(xy 8.60896 -170.871006) (xy 8.553135 -170.817787) (xy 8.502969 -170.759203) (xy 8.458976 -170.695852)
			(xy 8.421605 -170.628383) (xy 8.391239 -170.557484) (xy 8.368188 -170.483882) (xy 8.352687 -170.408327)
			(xy 8.344895 -170.331594) (xy 8.344408 -170.29303) (xy 8.345009 -170.250339) (xy 8.35455 -170.165491)
			(xy 8.373503 -170.082239) (xy 8.401632 -170.001623) (xy 8.438585 -169.924651) (xy 8.46074 -169.888154)
			(xy 8.465429 -169.879886) (xy 8.468963 -169.861226) (xy 8.465448 -169.842562) (xy 8.46074 -169.834306)
			(xy 8.438569 -169.797815) (xy 8.401584 -169.720854) (xy 8.373442 -169.640238) (xy 8.354496 -169.556979)
			(xy 8.344984 -169.472124) (xy 8.344408 -169.42943) (xy 8.344872 -169.390864) (xy 8.352659 -169.314127)
			(xy 8.368157 -169.238569) (xy 8.391206 -169.164963) (xy 8.421573 -169.09406) (xy 8.458945 -169.026588)
			(xy 8.50294 -168.963235) (xy 8.553109 -168.904649) (xy 8.608939 -168.85143) (xy 8.669859 -168.804122)
			(xy 8.702294 -168.783254) (xy 8.711987 -168.776492) (xy 8.724304 -168.756355) (xy 8.725916 -168.744646)
			(xy 8.7289 -168.716453) (xy 8.742132 -168.661328) (xy 8.763368 -168.608763) (xy 8.792139 -168.559916)
			(xy 8.827815 -168.515857) (xy 8.869612 -168.477556) (xy 8.916611 -168.445854) (xy 8.967779 -168.421447)
			(xy 9.021994 -168.404872) (xy 9.078062 -168.396492) (xy 9.134754 -168.396492) (xy 9.190822 -168.404872)
			(xy 9.245037 -168.421447) (xy 9.296205 -168.445854) (xy 9.343204 -168.477556) (xy 9.385001 -168.515857)
			(xy 9.420677 -168.559916) (xy 9.449448 -168.608763) (xy 9.470684 -168.661328) (xy 9.483916 -168.716453)
			(xy 9.4869 -168.744646) (xy 9.488551 -168.75634) (xy 9.500861 -168.776462) (xy 9.510522 -168.783254)
			(xy 9.542955 -168.804125) (xy 9.603868 -168.851437) (xy 9.659692 -168.904659) (xy 9.709856 -168.963246)
			(xy 9.753847 -169.026599) (xy 9.791217 -169.094071) (xy 9.821581 -169.164971) (xy 9.844631 -169.238575)
			(xy 9.860131 -169.314131) (xy 9.867922 -169.390866) (xy 9.868408 -169.42943) (xy 9.867833 -169.472122)
			(xy 9.858286 -169.556971) (xy 9.839327 -169.640223) (xy 9.811192 -169.720839) (xy 9.774233 -169.797809)
			(xy 9.752076 -169.834306) (xy 9.747337 -169.84255) (xy 9.743818 -169.861226) (xy 9.747356 -169.879898)
			(xy 9.752076 -169.888154) (xy 9.774232 -169.924653) (xy 9.811219 -170.001612) (xy 9.839364 -170.082226)
			(xy 9.858314 -170.165483) (xy 9.86783 -170.250337) (xy 9.868408 -170.29303) (xy 9.867905 -170.331595)
			(xy 9.860122 -170.40833) (xy 9.844629 -170.483887) (xy 9.821583 -170.557493) (xy 9.791221 -170.628395)
			(xy 9.753853 -170.695867) (xy 9.709862 -170.759221) (xy 9.659697 -170.817807) (xy 9.603871 -170.871027)
			(xy 9.542956 -170.918337) (xy 9.510522 -170.939206) (xy 9.500808 -170.945944) (xy 9.488501 -170.966099)
			(xy 9.4869 -170.977814) (xy 9.483637 -171.00768) (xy 9.469062 -171.065961) (xy 9.445561 -171.121248)
			(xy 9.41371 -171.172185) (xy 9.394444 -171.195238) (xy 9.388642 -171.202379) (xy 9.382132 -171.219573)
			(xy 9.381744 -171.228766) (xy 9.381744 -171.295568) (xy 9.382107 -171.304584) (xy 9.388349 -171.321502)
			(xy 9.393936 -171.328588) (xy 9.39419 -171.328842) (xy 9.412089 -171.350157) (xy 9.442134 -171.397009)
			(xy 9.465069 -171.447723) (xy 9.480408 -171.501226) (xy 9.484614 -171.52874) (xy 9.486721 -171.539851)
			(xy 9.498973 -171.558828) (xy 9.508236 -171.565316) (xy 9.541018 -171.586126) (xy 9.602586 -171.633449)
			(xy 9.65903 -171.686779) (xy 9.709766 -171.745566) (xy 9.754271 -171.809201) (xy 9.792083 -171.877027)
			(xy 9.822811 -171.948342) (xy 9.846139 -172.022408) (xy 9.861825 -172.098461) (xy 9.869707 -172.175713)
			(xy 9.870186 -172.21454) (xy 9.869596 -172.25723) (xy 9.860029 -172.342073) (xy 9.841064 -172.425321)
			(xy 9.812937 -172.505936) (xy 9.775998 -172.582913) (xy 9.753854 -172.619416) (xy 9.749123 -172.627661)
			(xy 9.745623 -172.646334) (xy 9.749148 -172.665003) (xy 9.753854 -172.673264) (xy 9.776028 -172.709749)
			(xy 9.812969 -172.786728) (xy 9.84109 -172.867347) (xy 9.860041 -172.950601) (xy 9.869585 -173.035449)
			(xy 9.870186 -173.07814) (xy 9.869709 -173.116966) (xy 9.86182 -173.194216) (xy 9.846129 -173.270266)
			(xy 9.822798 -173.34433) (xy 9.792067 -173.415642) (xy 9.754254 -173.483465) (xy 9.70975 -173.547099)
			(xy 9.659015 -173.605885) (xy 9.602574 -173.659216) (xy 9.541009 -173.70654) (xy 9.508236 -173.727364)
			(xy 9.498941 -173.733826) (xy 9.48667 -173.752809) (xy 9.484614 -173.76394) (xy 9.48044 -173.791461)
			(xy 9.46512 -173.844975) (xy 9.442176 -173.895689) (xy 9.412096 -173.942525) (xy 9.39419 -173.963838)
			(xy 9.393936 -173.964092) (xy 9.388339 -173.971171) (xy 9.3821 -173.988094) (xy 9.381744 -173.997112)
			(xy 9.381744 -174.064168) (xy 9.382107 -174.073184) (xy 9.388349 -174.090102) (xy 9.393936 -174.097188)
			(xy 9.39419 -174.097442) (xy 9.412213 -174.11891) (xy 9.442451 -174.166104) (xy 9.465464 -174.217213)
			(xy 9.480757 -174.271137) (xy 9.484868 -174.298864) (xy 9.486959 -174.309986) (xy 9.499201 -174.328979)
			(xy 9.50849 -174.33544) (xy 9.541248 -174.356271) (xy 9.602776 -174.403617) (xy 9.659182 -174.456963)
			(xy 9.709882 -174.515758) (xy 9.754354 -174.579394) (xy 9.792137 -174.647215) (xy 9.822843 -174.71852)
			(xy 9.846154 -174.792574) (xy 9.861829 -174.868611) (xy 9.869707 -174.945846) (xy 9.870186 -174.984664)
			(xy 9.86956 -175.027353) (xy 9.860002 -175.112195) (xy 9.841045 -175.195443) (xy 9.812925 -175.276058)
			(xy 9.775995 -175.353036) (xy 9.753854 -175.38954) (xy 9.749185 -175.397815) (xy 9.745664 -175.416469)
			(xy 9.749162 -175.435128) (xy 9.753854 -175.443388) (xy 9.775997 -175.479892) (xy 9.812943 -175.556865)
			(xy 9.841071 -175.63748) (xy 9.860029 -175.720729) (xy 9.869581 -175.805574) (xy 9.870186 -175.848264)
			(xy 9.869721 -175.887082) (xy 9.861836 -175.964316) (xy 9.846156 -176.040351) (xy 9.822841 -176.114403)
			(xy 9.792132 -176.185707) (xy 9.754347 -176.253526) (xy 9.709874 -176.317162) (xy 9.659174 -176.375956)
			(xy 9.60277 -176.429303) (xy 9.541244 -176.47665) (xy 9.50849 -176.497488) (xy 9.499196 -176.503946)
			(xy 9.486938 -176.522937) (xy 9.484868 -176.534064) (xy 9.48074 -176.561789) (xy 9.465463 -176.615718)
			(xy 9.442459 -176.666831) (xy 9.412225 -176.714028) (xy 9.39419 -176.735486) (xy 9.393936 -176.73574)
			(xy 9.388361 -176.742834) (xy 9.382109 -176.759745) (xy 9.381744 -176.76876) (xy 9.381744 -176.835816)
			(xy 9.382084 -176.844835) (xy 9.388342 -176.861752) (xy 9.393936 -176.868836) (xy 9.39419 -176.86909)
			(xy 9.41207 -176.89042) (xy 9.44212 -176.937267) (xy 9.465059 -176.987976) (xy 9.480404 -177.041475)
			(xy 9.484614 -177.068988) (xy 9.486697 -177.080106) (xy 9.498967 -177.099079) (xy 9.508236 -177.105564)
			(xy 9.541013 -177.126382) (xy 9.602581 -177.173704) (xy 9.659025 -177.227034) (xy 9.709761 -177.28582)
			(xy 9.754266 -177.349454) (xy 9.792078 -177.417278) (xy 9.822808 -177.488592) (xy 9.846137 -177.562658)
			(xy 9.861824 -177.63871) (xy 9.869706 -177.715962) (xy 9.870186 -177.754788) (xy 9.869572 -177.797477)
			(xy 9.86001 -177.88232) (xy 9.841051 -177.965568) (xy 9.812929 -178.046183) (xy 9.775996 -178.12316)
			(xy 9.753854 -178.159664) (xy 9.749166 -178.167929) (xy 9.745651 -178.18659) (xy 9.749158 -178.205251)
			(xy 9.753854 -178.213512) (xy 9.776007 -178.25001) (xy 9.812951 -178.326985) (xy 9.841077 -178.407601)
			(xy 9.860033 -178.490852) (xy 9.869582 -178.575697) (xy 9.870186 -178.618388) (xy 9.86966 -178.657204)
			(xy 9.861783 -178.734436) (xy 9.84611 -178.81047) (xy 9.822802 -178.884521) (xy 9.792101 -178.955824)
			(xy 9.754322 -179.023644) (xy 9.709856 -179.087281) (xy 9.659161 -179.146076) (xy 9.602763 -179.199424)
			(xy 9.541242 -179.246773) (xy 9.50849 -179.267612) (xy 9.499187 -179.274059) (xy 9.486934 -179.293058)
			(xy 9.484868 -179.304188) (xy 9.480838 -179.331413) (xy 9.465967 -179.3844) (xy 9.44364 -179.434703)
			(xy 9.414319 -179.481276) (xy 9.378613 -179.523155) (xy 9.337261 -179.559472) (xy 9.291123 -179.589472)
			(xy 9.241153 -179.612534) (xy 9.188389 -179.62818) (xy 9.133925 -179.636085) (xy 9.078891 -179.636085)
			(xy 9.024427 -179.62818) (xy 8.971663 -179.612534) (xy 8.921693 -179.589472) (xy 8.875555 -179.559472)
			(xy 8.834203 -179.523155) (xy 8.798497 -179.481276) (xy 8.769176 -179.434703) (xy 8.746849 -179.3844)
			(xy 8.731978 -179.331413) (xy 8.727948 -179.304188) (xy 8.725914 -179.29305) (xy 8.713634 -179.274061)
			(xy 8.704326 -179.267612) (xy 8.671575 -179.24677) (xy 8.610046 -179.199426) (xy 8.55364 -179.146082)
			(xy 8.502938 -179.087289) (xy 8.458466 -179.023654) (xy 8.420681 -178.955834) (xy 8.389974 -178.884529)
			(xy 8.366663 -178.810477) (xy 8.350987 -178.73444) (xy 8.343109 -178.657206) (xy 8.34263 -178.618388)
			(xy 3.523996 -178.618388) (xy 3.523996 -194.581526) (xy 13.285216 -194.581526) (xy 13.285216 -185.851546)
			(xy 13.285662 -185.841479) (xy 13.293368 -185.822881) (xy 13.300202 -185.815478) (xy 15.518638 -183.597042)
			(xy 15.526036 -183.590199) (xy 15.544637 -183.58248) (xy 15.554706 -183.582056) (xy 24.49576 -183.582056)
			(xy 24.505828 -183.581621) (xy 24.524427 -183.573908) (xy 24.531828 -183.56707) (xy 33.543494 -174.555404)
			(xy 33.549844 -174.527464) (xy 33.545018 -174.513494) (xy 33.531554 -174.473086) (xy 33.512677 -174.390029)
			(xy 33.503185 -174.305384) (xy 33.5026 -174.262796) (xy 33.503093 -174.222861) (xy 33.511442 -174.143428)
			(xy 33.528049 -174.065303) (xy 33.55273 -173.989342) (xy 33.585217 -173.916377) (xy 33.625153 -173.847207)
			(xy 33.6721 -173.782591) (xy 33.725544 -173.723236) (xy 33.7849 -173.669792) (xy 33.849517 -173.622846)
			(xy 33.918687 -173.582912) (xy 33.991653 -173.550426) (xy 34.067614 -173.525746) (xy 34.14574 -173.50914)
			(xy 34.225173 -173.500792) (xy 34.265108 -173.500288) (xy 34.307694 -173.500894) (xy 34.392335 -173.510397)
			(xy 34.475393 -173.529263) (xy 34.515806 -173.542706) (xy 34.529776 -173.547532) (xy 34.557716 -173.541182)
			(xy 35.01517 -173.083982) (xy 35.022006 -173.076579) (xy 35.029729 -173.057982) (xy 35.030156 -173.047914)
			(xy 35.030156 -170.706542) (xy 35.029946 -170.699732) (xy 35.026334 -170.6866) (xy 35.023044 -170.680634)
			(xy 35.002814 -170.645345) (xy 34.969134 -170.571299) (xy 34.943535 -170.494087) (xy 34.926308 -170.414586)
			(xy 34.917648 -170.333703) (xy 34.917126 -170.29303) (xy 34.917666 -170.252359) (xy 34.926345 -170.171481)
			(xy 34.943578 -170.091984) (xy 34.969167 -170.014772) (xy 35.002824 -169.940719) (xy 35.023044 -169.905426)
			(xy 35.026327 -169.899457) (xy 35.029936 -169.886327) (xy 35.030156 -169.879518) (xy 35.030156 -156.369766)
			(xy 35.029501 -156.35848) (xy 35.019828 -156.338085) (xy 35.002357 -156.323792) (xy 34.991548 -156.32049)
			(xy 34.895536 -156.296614) (xy 34.884393 -156.294413) (xy 34.862169 -156.298975) (xy 34.84411 -156.312708)
			(xy 34.838386 -156.322522) (xy 34.789966 -156.41394) (xy 34.68718 -156.593497) (xy 34.577728 -156.769072)
			(xy 34.461766 -156.940415) (xy 34.339457 -157.107287) (xy 34.210971 -157.269452) (xy 34.076492 -157.426682)
			(xy 33.936208 -157.578755) (xy 33.790316 -157.725457) (xy 33.639022 -157.866582) (xy 33.482539 -158.00193)
			(xy 33.321088 -158.131311) (xy 33.154897 -158.254543) (xy 32.984198 -158.371452) (xy 32.809232 -158.481874)
			(xy 32.630247 -158.585653) (xy 32.447493 -158.682643) (xy 32.261229 -158.772708) (xy 32.071716 -158.855719)
			(xy 31.879222 -158.931561) (xy 31.684018 -159.000127) (xy 31.486379 -159.06132) (xy 31.286583 -159.115055)
			(xy 31.084911 -159.161254) (xy 30.881648 -159.199853) (xy 30.677079 -159.230799) (xy 30.471493 -159.254047)
			(xy 30.26518 -159.269564) (xy 30.05843 -159.277329) (xy 29.954982 -159.277812) (xy 29.849385 -159.277307)
			(xy 29.638345 -159.269217) (xy 29.42777 -159.25305) (xy 29.217969 -159.22883) (xy 29.00925 -159.196591)
			(xy 28.801918 -159.156382) (xy 28.596279 -159.10826) (xy 28.392634 -159.052298) (xy 28.191282 -158.988576)
			(xy 27.992518 -158.917188) (xy 27.796634 -158.83824) (xy 27.603919 -158.751847) (xy 27.414653 -158.658136)
			(xy 27.229116 -158.557244) (xy 27.04758 -158.44932) (xy 26.87031 -158.334521) (xy 26.697568 -158.213017)
			(xy 26.529606 -158.084986) (xy 26.366672 -157.950615) (xy 26.209004 -157.810101) (xy 26.056834 -157.663652)
			(xy 25.910385 -157.511482) (xy 25.769871 -157.353814) (xy 25.6355 -157.19088) (xy 25.507469 -157.022918)
			(xy 25.385965 -156.850176) (xy 25.271166 -156.672906) (xy 25.163242 -156.49137) (xy 25.06235 -156.305833)
			(xy 24.968639 -156.116567) (xy 24.882246 -155.923852) (xy 24.803298 -155.727968) (xy 24.73191 -155.529204)
			(xy 24.668188 -155.327852) (xy 24.612226 -155.124207) (xy 24.564104 -154.918568) (xy 24.523895 -154.711236)
			(xy 24.491656 -154.502517) (xy 24.467436 -154.292716) (xy 24.451269 -154.082141) (xy 24.443179 -153.871101)
			(xy 24.443179 -153.659907) (xy 24.451269 -153.448867) (xy 24.467436 -153.238292) (xy 24.491656 -153.028491)
			(xy 24.523895 -152.819772) (xy 24.564104 -152.61244) (xy 24.612226 -152.406801) (xy 24.668188 -152.203156)
			(xy 24.73191 -152.001804) (xy 24.803298 -151.80304) (xy 24.882246 -151.607156) (xy 24.968639 -151.414441)
			(xy 25.06235 -151.225175) (xy 25.163242 -151.039638) (xy 25.271166 -150.858102) (xy 25.385965 -150.680832)
			(xy 25.507469 -150.50809) (xy 25.6355 -150.340128) (xy 25.769871 -150.177194) (xy 25.910385 -150.019526)
			(xy 26.056834 -149.867356) (xy 26.209004 -149.720907) (xy 26.366672 -149.580393) (xy 26.529606 -149.446022)
			(xy 26.697568 -149.317991) (xy 26.87031 -149.196487) (xy 27.04758 -149.081688) (xy 27.229116 -148.973764)
			(xy 27.414653 -148.872872) (xy 27.603919 -148.779161) (xy 27.796634 -148.692768) (xy 27.992518 -148.61382)
			(xy 28.191282 -148.542432) (xy 28.392634 -148.47871) (xy 28.596279 -148.422748) (xy 28.801918 -148.374626)
			(xy 29.00925 -148.334417) (xy 29.217969 -148.302178) (xy 29.42777 -148.277958) (xy 29.638345 -148.261791)
			(xy 29.849385 -148.253701) (xy 29.954982 -148.253196) (xy 30.06136 -148.253701) (xy 30.273959 -148.261904)
			(xy 30.486082 -148.278305) (xy 30.697415 -148.302878) (xy 30.907642 -148.335588) (xy 31.11645 -148.376384)
			(xy 31.323529 -148.425207) (xy 31.52857 -148.481983) (xy 31.731268 -148.546629) (xy 31.93132 -148.619047)
			(xy 32.128429 -148.699131) (xy 32.322301 -148.78676) (xy 32.512648 -148.881804) (xy 32.699186 -148.984123)
			(xy 32.881637 -149.093562) (xy 33.059729 -149.20996) (xy 33.233198 -149.333143) (xy 33.401784 -149.462927)
			(xy 33.565238 -149.599119) (xy 33.723314 -149.741517) (xy 33.875779 -149.889908) (xy 34.022404 -150.044072)
			(xy 34.162972 -150.203778) (xy 34.297273 -150.368789) (xy 34.425107 -150.538859) (xy 34.546283 -150.713734)
			(xy 34.660622 -150.893156) (xy 34.767953 -151.076855) (xy 34.868116 -151.264559) (xy 34.960962 -151.455987)
			(xy 35.046353 -151.650856) (xy 35.124161 -151.848874) (xy 35.194271 -152.049747) (xy 35.256578 -152.253176)
			(xy 35.310989 -152.458857) (xy 35.334702 -152.56256) (xy 35.33775 -152.576022) (xy 35.356546 -152.596596)
			(xy 35.455606 -152.625044) (xy 35.464428 -152.627194) (xy 35.482519 -152.625863) (xy 35.498994 -152.618269)
			(xy 35.505644 -152.61209) (xy 42.28084 -145.836894) (xy 42.288232 -145.830043) (xy 42.306837 -145.82233)
			(xy 42.316908 -145.821908) (xy 60.03036 -145.821908) (xy 60.040427 -145.822352) (xy 60.059025 -145.830059)
			(xy 60.066428 -145.836894) (xy 66.962528 -152.732994) (xy 66.969925 -152.739838) (xy 66.988527 -152.747556)
			(xy 66.998596 -152.74798) (xy 76.569316 -152.74798) (xy 76.579389 -152.748376) (xy 76.597988 -152.756115)
			(xy 76.605384 -152.762966) (xy 78.299056 -154.456892) (xy 78.303328 -154.460929) (xy 78.313341 -154.467082)
			(xy 78.318868 -154.469084) (xy 78.34657 -154.478943) (xy 78.398796 -154.505952) (xy 78.44626 -154.540655)
			(xy 78.487836 -154.582231) (xy 78.522541 -154.629693) (xy 78.549552 -154.681919) (xy 78.559406 -154.709622)
			(xy 78.561437 -154.715136) (xy 78.567583 -154.725145) (xy 78.571598 -154.729434) (xy 81.52892 -157.686502)
			(xy 81.536319 -157.693344) (xy 81.554919 -157.701062) (xy 81.564988 -157.701488) (xy 91.850464 -157.701488)
			(xy 91.860532 -157.701047) (xy 91.87913 -157.693338) (xy 91.886532 -157.686502) (xy 97.582736 -151.990298)
			(xy 97.590656 -151.981484) (xy 97.598151 -151.959036) (xy 97.594806 -151.935608) (xy 97.588578 -151.925528)
			(xy 97.572635 -151.901516) (xy 97.54742 -151.849687) (xy 97.530267 -151.794661) (xy 97.521564 -151.737684)
			(xy 97.521014 -151.708866) (xy 97.521446 -151.681613) (xy 97.529208 -151.627662) (xy 97.544569 -151.575365)
			(xy 97.567215 -151.525786) (xy 97.596687 -151.479935) (xy 97.632384 -151.438745) (xy 97.67358 -151.403053)
			(xy 97.719435 -151.373588) (xy 97.769018 -151.350949) (xy 97.821317 -151.335596) (xy 97.875269 -151.327842)
			(xy 97.902522 -151.327358) (xy 97.931341 -151.327922) (xy 97.988322 -151.336598) (xy 98.043348 -151.353749)
			(xy 98.095168 -151.378984) (xy 98.119184 -151.394922) (xy 98.119438 -151.395176) (xy 98.129564 -151.401333)
			(xy 98.153004 -151.404597) (xy 98.175429 -151.397038) (xy 98.184208 -151.38908) (xy 102.748334 -146.824954)
			(xy 102.756429 -146.815988) (xy 102.763839 -146.793027) (xy 102.762558 -146.781012) (xy 102.75829 -146.751799)
			(xy 102.753711 -146.692932) (xy 102.753414 -146.66341) (xy 102.753917 -146.624739) (xy 102.761736 -146.547792)
			(xy 102.777306 -146.472033) (xy 102.800465 -146.398239) (xy 102.830976 -146.327169) (xy 102.868526 -146.259553)
			(xy 102.912728 -146.196086) (xy 102.963129 -146.137421) (xy 103.01921 -146.084159) (xy 103.080395 -146.036849)
			(xy 103.146056 -145.995977) (xy 103.215517 -145.961962) (xy 103.288065 -145.935154) (xy 103.362955 -145.915829)
			(xy 103.401114 -145.909538) (xy 103.413306 -145.90776) (xy 103.432356 -145.894044) (xy 103.476552 -145.811494)
			(xy 103.481561 -145.800803) (xy 103.48223 -145.777234) (xy 103.477822 -145.766282) (xy 103.477822 -145.765774)
			(xy 103.460601 -145.72773) (xy 103.433602 -145.648703) (xy 103.415415 -145.567196) (xy 103.406259 -145.484188)
			(xy 103.405686 -145.442432) (xy 103.406227 -145.402498) (xy 103.414572 -145.323067) (xy 103.431175 -145.244943)
			(xy 103.455853 -145.168983) (xy 103.488336 -145.096019) (xy 103.528268 -145.02685) (xy 103.575211 -144.962234)
			(xy 103.628652 -144.902879) (xy 103.688004 -144.849435) (xy 103.752618 -144.802489) (xy 103.821785 -144.762553)
			(xy 103.894748 -144.730067) (xy 103.970707 -144.705385) (xy 104.048829 -144.688778) (xy 104.12826 -144.680429)
			(xy 104.168194 -144.679924) (xy 104.205804 -144.680375) (xy 104.280661 -144.687769) (xy 104.354426 -144.702495)
			(xy 104.426383 -144.724411) (xy 104.495834 -144.753303) (xy 104.562103 -144.788892) (xy 104.624547 -144.83083)
			(xy 104.653842 -144.854422) (xy 104.66132 -144.860087) (xy 104.679085 -144.866061) (xy 104.69781 -144.865222)
			(xy 104.71497 -144.857682) (xy 104.721914 -144.851374) (xy 106.73588 -142.837154) (xy 106.743288 -142.830324)
			(xy 106.761881 -142.8226) (xy 106.771948 -142.822168) (xy 113.754408 -142.822168) (xy 113.76448 -142.822571)
			(xy 113.783079 -142.830306) (xy 113.790476 -142.837154) (xy 115.415822 -144.4625) (xy 115.422658 -144.469903)
			(xy 115.430379 -144.4885) (xy 115.430808 -144.498568) (xy 115.430808 -146.553428) (xy 115.431217 -146.563499)
			(xy 115.438949 -146.582097) (xy 115.445794 -146.589496) (xy 115.863624 -147.007326) (xy 115.871019 -147.014173)
			(xy 115.889622 -147.021888) (xy 115.899692 -147.022312) (xy 121.046748 -147.022312) (xy 121.056817 -147.021883)
			(xy 121.075417 -147.014167) (xy 121.082816 -147.007326) (xy 121.386346 -146.703796) (xy 121.393187 -146.696397)
			(xy 121.400905 -146.677797) (xy 121.401332 -146.667728) (xy 121.401332 -143.042132) (xy 121.401766 -143.032064)
			(xy 121.40948 -143.013465) (xy 121.416318 -143.006064) (xy 123.138438 -141.284198) (xy 123.145831 -141.277349)
			(xy 123.164436 -141.269634) (xy 123.174506 -141.269212) (xy 138.633454 -141.269212) (xy 138.643521 -141.269659)
			(xy 138.662119 -141.277364) (xy 138.669522 -141.284198) (xy 142.462257 -145.0769) (xy 162.918736 -145.0769)
			(xy 162.922648 -144.999766) (xy 162.934343 -144.923423) (xy 162.953701 -144.848655) (xy 162.980524 -144.776228)
			(xy 163.014536 -144.706887) (xy 163.055388 -144.641343) (xy 163.102662 -144.580267) (xy 163.155871 -144.524288)
			(xy 163.214471 -144.473978) (xy 163.27786 -144.429855) (xy 163.345387 -144.392371) (xy 163.41636 -144.36191)
			(xy 163.490051 -144.338786) (xy 163.565703 -144.323235) (xy 163.642539 -144.315417) (xy 163.681156 -144.314926)
			(xy 163.72277 -144.315512) (xy 163.805504 -144.324574) (xy 163.886757 -144.342596) (xy 163.965564 -144.369362)
			(xy 164.040986 -144.404555) (xy 164.112125 -144.447755) (xy 164.145468 -144.47266) (xy 164.154658 -144.479028)
			(xy 164.176456 -144.483883) (xy 164.198254 -144.479028) (xy 164.207444 -144.47266) (xy 164.240799 -144.447769)
			(xy 164.311934 -144.404562) (xy 164.387352 -144.369362) (xy 164.466157 -144.342587) (xy 164.547409 -144.324556)
			(xy 164.630142 -144.315485) (xy 164.671756 -144.314926) (xy 164.710379 -144.315345) (xy 164.787229 -144.323155)
			(xy 164.862895 -144.338701) (xy 164.936599 -144.361822) (xy 165.007587 -144.392282) (xy 165.075128 -144.429767)
			(xy 165.13853 -144.473893) (xy 165.197143 -144.524207) (xy 165.250364 -144.580193) (xy 165.297649 -144.641276)
			(xy 165.33851 -144.706829) (xy 165.37253 -144.776181) (xy 165.399359 -144.848618) (xy 165.418722 -144.923398)
			(xy 165.430419 -144.999753) (xy 165.434332 -145.0769) (xy 165.430419 -145.154047) (xy 165.418722 -145.230402)
			(xy 165.399359 -145.305182) (xy 165.37253 -145.377619) (xy 165.33851 -145.446971) (xy 165.297649 -145.512524)
			(xy 165.250364 -145.573607) (xy 165.197143 -145.629593) (xy 165.13853 -145.679907) (xy 165.075128 -145.724033)
			(xy 165.007587 -145.761518) (xy 164.936599 -145.791978) (xy 164.862895 -145.815099) (xy 164.787229 -145.830645)
			(xy 164.710379 -145.838455) (xy 164.671756 -145.838926) (xy 164.63014 -145.838399) (xy 164.547404 -145.829326)
			(xy 164.466149 -145.811294) (xy 164.387342 -145.784517) (xy 164.311922 -145.749313) (xy 164.240786 -145.706102)
			(xy 164.207444 -145.681192) (xy 164.198254 -145.674824) (xy 164.176456 -145.669969) (xy 164.154658 -145.674824)
			(xy 164.145468 -145.681192) (xy 164.112137 -145.706116) (xy 164.040997 -145.74932) (xy 163.965574 -145.784516)
			(xy 163.886765 -145.811285) (xy 163.805508 -145.829309) (xy 163.722772 -145.838372) (xy 163.681156 -145.838926)
			(xy 163.642539 -145.838383) (xy 163.565703 -145.830565) (xy 163.490051 -145.815014) (xy 163.41636 -145.79189)
			(xy 163.345387 -145.761429) (xy 163.27786 -145.723945) (xy 163.214471 -145.679822) (xy 163.155871 -145.629512)
			(xy 163.102662 -145.573533) (xy 163.055388 -145.512457) (xy 163.014536 -145.446913) (xy 162.980524 -145.377572)
			(xy 162.953701 -145.305145) (xy 162.934343 -145.230377) (xy 162.922648 -145.154034) (xy 162.918736 -145.0769)
			(xy 142.462257 -145.0769) (xy 147.373399 -149.988) (xy 160.475226 -149.988) (xy 160.479138 -149.910863)
			(xy 160.490834 -149.834518) (xy 160.510193 -149.759748) (xy 160.537017 -149.68732) (xy 160.57103 -149.617977)
			(xy 160.611884 -149.552431) (xy 160.65916 -149.491354) (xy 160.712372 -149.435373) (xy 160.770974 -149.385063)
			(xy 160.834366 -149.340939) (xy 160.901896 -149.303455) (xy 160.972872 -149.272995) (xy 161.046565 -149.249872)
			(xy 161.122219 -149.234322) (xy 161.199058 -149.226506) (xy 161.237676 -149.226016) (xy 161.27929 -149.226593)
			(xy 161.362024 -149.235657) (xy 161.443278 -149.253681) (xy 161.522085 -149.280449) (xy 161.597506 -149.315643)
			(xy 161.668645 -149.358844) (xy 161.701988 -149.38375) (xy 161.711178 -149.390118) (xy 161.732976 -149.394973)
			(xy 161.754774 -149.390118) (xy 161.763964 -149.38375) (xy 161.797311 -149.358849) (xy 161.868448 -149.315643)
			(xy 161.943868 -149.280445) (xy 162.022674 -149.253672) (xy 162.103927 -149.235643) (xy 162.186661 -149.226574)
			(xy 162.228276 -149.226016) (xy 162.266898 -149.226456) (xy 162.343746 -149.234268) (xy 162.419409 -149.249815)
			(xy 162.49311 -149.272937) (xy 162.564095 -149.303397) (xy 162.631634 -149.340882) (xy 162.695033 -149.385008)
			(xy 162.753643 -149.435321) (xy 162.806863 -149.491306) (xy 162.854145 -149.552388) (xy 162.895005 -149.61794)
			(xy 162.929023 -149.687289) (xy 162.955851 -149.759725) (xy 162.975213 -149.834502) (xy 162.98691 -149.910855)
			(xy 162.988403 -149.9403) (xy 163.412358 -149.9403) (xy 163.416271 -149.863153) (xy 163.427968 -149.786797)
			(xy 163.447331 -149.712017) (xy 163.474159 -149.63958) (xy 163.508179 -149.570228) (xy 163.54904 -149.504674)
			(xy 163.596324 -149.44359) (xy 163.649546 -149.387604) (xy 163.708158 -149.337289) (xy 163.77156 -149.293162)
			(xy 163.839101 -149.255676) (xy 163.910088 -149.225216) (xy 163.983793 -149.202094) (xy 164.059459 -149.186547)
			(xy 164.136309 -149.178735) (xy 164.174932 -149.178264) (xy 164.216548 -149.1788) (xy 164.299283 -149.187871)
			(xy 164.380538 -149.205902) (xy 164.459345 -149.232677) (xy 164.534765 -149.267879) (xy 164.605902 -149.311088)
			(xy 164.639244 -149.335998) (xy 164.648434 -149.342366) (xy 164.670232 -149.347221) (xy 164.69203 -149.342366)
			(xy 164.70122 -149.335998) (xy 164.734553 -149.311078) (xy 164.805693 -149.267874) (xy 164.881116 -149.232677)
			(xy 164.959924 -149.205907) (xy 165.04118 -149.187883) (xy 165.123916 -149.178819) (xy 165.165532 -149.178264)
			(xy 165.204149 -149.178827) (xy 165.280985 -149.186643) (xy 165.356637 -149.202193) (xy 165.430327 -149.225316)
			(xy 165.5013 -149.255776) (xy 165.568828 -149.293259) (xy 165.632217 -149.337382) (xy 165.690817 -149.387691)
			(xy 165.744027 -149.44367) (xy 165.791301 -149.504745) (xy 165.832154 -149.570289) (xy 165.866166 -149.63963)
			(xy 165.892989 -149.712055) (xy 165.912347 -149.786823) (xy 165.924042 -149.863166) (xy 165.927954 -149.9403)
			(xy 165.924042 -150.017434) (xy 165.912347 -150.093777) (xy 165.892989 -150.168545) (xy 165.866166 -150.24097)
			(xy 165.832154 -150.310311) (xy 165.791301 -150.375855) (xy 165.744027 -150.43693) (xy 165.690817 -150.492909)
			(xy 165.632217 -150.543218) (xy 165.568828 -150.587341) (xy 165.5013 -150.624824) (xy 165.430327 -150.655284)
			(xy 165.356637 -150.678407) (xy 165.280985 -150.693957) (xy 165.204149 -150.701773) (xy 165.165532 -150.702264)
			(xy 165.123918 -150.701687) (xy 165.041184 -150.692623) (xy 164.95993 -150.6746) (xy 164.881123 -150.647832)
			(xy 164.805701 -150.612638) (xy 164.734563 -150.569436) (xy 164.70122 -150.54453) (xy 164.69203 -150.538162)
			(xy 164.670232 -150.533307) (xy 164.648434 -150.538162) (xy 164.639244 -150.54453) (xy 164.605892 -150.569425)
			(xy 164.534757 -150.612632) (xy 164.459338 -150.647832) (xy 164.380533 -150.674606) (xy 164.29928 -150.692635)
			(xy 164.216547 -150.701706) (xy 164.174932 -150.702264) (xy 164.136309 -150.701865) (xy 164.059459 -150.694053)
			(xy 163.983793 -150.678506) (xy 163.910088 -150.655384) (xy 163.839101 -150.624924) (xy 163.77156 -150.587438)
			(xy 163.708158 -150.543311) (xy 163.649546 -150.492996) (xy 163.596324 -150.43701) (xy 163.54904 -150.375926)
			(xy 163.508179 -150.310372) (xy 163.474159 -150.24102) (xy 163.447331 -150.168583) (xy 163.427968 -150.093803)
			(xy 163.416271 -150.017447) (xy 163.412358 -149.9403) (xy 162.988403 -149.9403) (xy 162.990822 -149.988)
			(xy 162.98691 -150.065145) (xy 162.975213 -150.141498) (xy 162.955851 -150.216275) (xy 162.929023 -150.288711)
			(xy 162.895005 -150.35806) (xy 162.854145 -150.423612) (xy 162.806863 -150.484694) (xy 162.753643 -150.540679)
			(xy 162.695033 -150.590992) (xy 162.631634 -150.635118) (xy 162.564095 -150.672603) (xy 162.49311 -150.703063)
			(xy 162.419409 -150.726185) (xy 162.343746 -150.741732) (xy 162.266898 -150.749544) (xy 162.228276 -150.750016)
			(xy 162.18666 -150.74948) (xy 162.103925 -150.740409) (xy 162.02267 -150.722379) (xy 161.943863 -150.695603)
			(xy 161.868442 -150.660401) (xy 161.797306 -150.617192) (xy 161.763964 -150.592282) (xy 161.754774 -150.585914)
			(xy 161.732976 -150.581059) (xy 161.711178 -150.585914) (xy 161.701988 -150.592282) (xy 161.66865 -150.617196)
			(xy 161.597512 -150.660401) (xy 161.52209 -150.695599) (xy 161.443282 -150.72237) (xy 161.362027 -150.740395)
			(xy 161.279291 -150.749461) (xy 161.237676 -150.750016) (xy 161.199058 -150.749494) (xy 161.122219 -150.741678)
			(xy 161.046565 -150.726128) (xy 160.972872 -150.703005) (xy 160.901896 -150.672545) (xy 160.834366 -150.635061)
			(xy 160.770974 -150.590937) (xy 160.712372 -150.540627) (xy 160.65916 -150.484646) (xy 160.611884 -150.423569)
			(xy 160.57103 -150.358023) (xy 160.537017 -150.28868) (xy 160.510193 -150.216252) (xy 160.490834 -150.141482)
			(xy 160.479138 -150.065137) (xy 160.475226 -149.988) (xy 147.373399 -149.988) (xy 151.160334 -153.774902)
			(xy 188.441847 -153.774902) (xy 188.445843 -153.565016) (xy 188.457828 -153.355434) (xy 188.477782 -153.14646)
			(xy 188.505678 -152.938398) (xy 188.541475 -152.731548) (xy 188.58512 -152.526211) (xy 188.636552 -152.322685)
			(xy 188.695694 -152.121264) (xy 188.762462 -151.922241) (xy 188.836758 -151.725904) (xy 188.918476 -151.532538)
			(xy 189.007495 -151.342423) (xy 189.103688 -151.155835) (xy 189.206915 -150.973044) (xy 189.317026 -150.794316)
			(xy 189.433861 -150.619909) (xy 189.557251 -150.450077) (xy 189.687018 -150.285065) (xy 189.822972 -150.125114)
			(xy 189.964918 -149.970454) (xy 190.112648 -149.82131) (xy 190.26595 -149.677899) (xy 190.4246 -149.540428)
			(xy 190.588369 -149.409096) (xy 190.757019 -149.284095) (xy 190.930305 -149.165604) (xy 191.107977 -149.053797)
			(xy 191.289777 -148.948835) (xy 191.475441 -148.85087) (xy 191.664699 -148.760045) (xy 191.857279 -148.676491)
			(xy 192.0529 -148.600328) (xy 192.251278 -148.531669) (xy 192.452127 -148.470612) (xy 192.655154 -148.417245)
			(xy 192.860067 -148.371647) (xy 193.066566 -148.333882) (xy 193.274353 -148.304007) (xy 193.483128 -148.282064)
			(xy 193.692586 -148.268085) (xy 193.902425 -148.26209) (xy 194.112339 -148.264089) (xy 194.322026 -148.274077)
			(xy 194.53118 -148.292042) (xy 194.739498 -148.317956) (xy 194.946679 -148.351781) (xy 195.152423 -148.39347)
			(xy 195.356429 -148.442962) (xy 195.558404 -148.500184) (xy 195.758054 -148.565054) (xy 195.955089 -148.637478)
			(xy 196.149225 -148.717351) (xy 196.340178 -148.804557) (xy 196.527674 -148.898969) (xy 196.711439 -149.000451)
			(xy 196.891207 -149.108855) (xy 197.066718 -149.224025) (xy 197.237717 -149.345793) (xy 197.403957 -149.473982)
			(xy 197.565196 -149.608408) (xy 197.7212 -149.748875) (xy 197.871743 -149.895179) (xy 198.016607 -150.047108)
			(xy 198.155582 -150.204442) (xy 198.288467 -150.366953) (xy 198.415068 -150.534406) (xy 198.535203 -150.706556)
			(xy 198.648697 -150.883156) (xy 198.755385 -151.063948) (xy 198.855112 -151.248671) (xy 198.947735 -151.437057)
			(xy 199.033119 -151.628832) (xy 199.11114 -151.823719) (xy 199.181685 -152.021435) (xy 199.244652 -152.221693)
			(xy 199.299949 -152.424203) (xy 199.347496 -152.628672) (xy 199.387224 -152.834803) (xy 199.419076 -153.042296)
			(xy 199.443006 -153.250852) (xy 199.458978 -153.460168) (xy 199.46697 -153.66994) (xy 199.467428 -153.766012)
			(xy 272.382243 -153.766012) (xy 272.386239 -153.556126) (xy 272.398224 -153.346544) (xy 272.418178 -153.13757)
			(xy 272.446074 -152.929508) (xy 272.481871 -152.722658) (xy 272.525516 -152.517321) (xy 272.576948 -152.313795)
			(xy 272.63609 -152.112374) (xy 272.702858 -151.913351) (xy 272.777154 -151.717014) (xy 272.858872 -151.523648)
			(xy 272.947891 -151.333533) (xy 273.044084 -151.146945) (xy 273.147311 -150.964154) (xy 273.257422 -150.785426)
			(xy 273.374257 -150.611019) (xy 273.497647 -150.441187) (xy 273.627414 -150.276175) (xy 273.763368 -150.116224)
			(xy 273.905314 -149.961564) (xy 274.053044 -149.81242) (xy 274.206346 -149.669009) (xy 274.364996 -149.531538)
			(xy 274.528765 -149.400206) (xy 274.697415 -149.275205) (xy 274.870701 -149.156714) (xy 275.048373 -149.044907)
			(xy 275.230173 -148.939945) (xy 275.415837 -148.84198) (xy 275.605095 -148.751155) (xy 275.797675 -148.667601)
			(xy 275.993296 -148.591438) (xy 276.191674 -148.522779) (xy 276.392523 -148.461722) (xy 276.59555 -148.408355)
			(xy 276.800463 -148.362757) (xy 277.006962 -148.324992) (xy 277.214749 -148.295117) (xy 277.423524 -148.273174)
			(xy 277.632982 -148.259195) (xy 277.842821 -148.2532) (xy 278.052735 -148.255199) (xy 278.262422 -148.265187)
			(xy 278.471576 -148.283152) (xy 278.679894 -148.309066) (xy 278.887075 -148.342891) (xy 279.092819 -148.38458)
			(xy 279.296825 -148.434072) (xy 279.4988 -148.491294) (xy 279.69845 -148.556164) (xy 279.895485 -148.628588)
			(xy 280.089621 -148.708461) (xy 280.280574 -148.795667) (xy 280.46807 -148.890079) (xy 280.651835 -148.991561)
			(xy 280.831603 -149.099965) (xy 281.007114 -149.215135) (xy 281.178113 -149.336903) (xy 281.344353 -149.465092)
			(xy 281.505592 -149.599518) (xy 281.661596 -149.739985) (xy 281.812139 -149.886289) (xy 281.957003 -150.038218)
			(xy 282.095978 -150.195552) (xy 282.228863 -150.358063) (xy 282.355464 -150.525516) (xy 282.475599 -150.697666)
			(xy 282.589093 -150.874266) (xy 282.695781 -151.055058) (xy 282.795508 -151.239781) (xy 282.888131 -151.428167)
			(xy 282.973515 -151.619942) (xy 283.051536 -151.814829) (xy 283.122081 -152.012545) (xy 283.185048 -152.212803)
			(xy 283.240345 -152.415313) (xy 283.287892 -152.619782) (xy 283.32762 -152.825913) (xy 283.359472 -153.033406)
			(xy 283.383402 -153.241962) (xy 283.399374 -153.451278) (xy 283.407366 -153.66105) (xy 283.407866 -153.766012)
			(xy 283.407366 -153.870974) (xy 283.399374 -154.080746) (xy 283.383402 -154.290062) (xy 283.359472 -154.498618)
			(xy 283.32762 -154.706111) (xy 283.287892 -154.912242) (xy 283.240345 -155.116711) (xy 283.185048 -155.319221)
			(xy 283.122081 -155.519479) (xy 283.051536 -155.717195) (xy 282.973515 -155.912082) (xy 282.888131 -156.103857)
			(xy 282.795508 -156.292243) (xy 282.695781 -156.476966) (xy 282.589093 -156.657758) (xy 282.475599 -156.834358)
			(xy 282.355464 -157.006508) (xy 282.228863 -157.173961) (xy 282.095978 -157.336472) (xy 281.957003 -157.493806)
			(xy 281.812139 -157.645735) (xy 281.661596 -157.792039) (xy 281.505592 -157.932506) (xy 281.344353 -158.066932)
			(xy 281.178113 -158.195121) (xy 281.007114 -158.316889) (xy 280.831603 -158.432059) (xy 280.651835 -158.540463)
			(xy 280.46807 -158.641945) (xy 280.280574 -158.736357) (xy 280.089621 -158.823563) (xy 279.895485 -158.903436)
			(xy 279.69845 -158.97586) (xy 279.4988 -159.04073) (xy 279.296825 -159.097952) (xy 279.092819 -159.147444)
			(xy 278.887075 -159.189133) (xy 278.679894 -159.222958) (xy 278.471576 -159.248872) (xy 278.262422 -159.266837)
			(xy 278.052735 -159.276825) (xy 277.842821 -159.278824) (xy 277.632982 -159.272829) (xy 277.423524 -159.25885)
			(xy 277.214749 -159.236907) (xy 277.006962 -159.207032) (xy 276.800463 -159.169267) (xy 276.59555 -159.123669)
			(xy 276.392523 -159.070302) (xy 276.191674 -159.009245) (xy 275.993296 -158.940586) (xy 275.797675 -158.864423)
			(xy 275.605095 -158.780869) (xy 275.415837 -158.690044) (xy 275.230173 -158.592079) (xy 275.048373 -158.487117)
			(xy 274.870701 -158.37531) (xy 274.697415 -158.256819) (xy 274.528765 -158.131818) (xy 274.364996 -158.000486)
			(xy 274.206346 -157.863015) (xy 274.053044 -157.719604) (xy 273.905314 -157.57046) (xy 273.763368 -157.4158)
			(xy 273.627414 -157.255849) (xy 273.497647 -157.090837) (xy 273.374257 -156.921005) (xy 273.257422 -156.746598)
			(xy 273.147311 -156.56787) (xy 273.044084 -156.385079) (xy 272.947891 -156.198491) (xy 272.858872 -156.008376)
			(xy 272.777154 -155.81501) (xy 272.702858 -155.618673) (xy 272.63609 -155.41965) (xy 272.576948 -155.218229)
			(xy 272.525516 -155.014703) (xy 272.481871 -154.809366) (xy 272.446074 -154.602516) (xy 272.418178 -154.394454)
			(xy 272.398224 -154.18548) (xy 272.386239 -153.975898) (xy 272.382243 -153.766012) (xy 199.467428 -153.766012)
			(xy 199.46747 -153.774902) (xy 199.46697 -153.879864) (xy 199.458978 -154.089636) (xy 199.443006 -154.298952)
			(xy 199.419076 -154.507508) (xy 199.387224 -154.715001) (xy 199.347496 -154.921132) (xy 199.299949 -155.125601)
			(xy 199.244652 -155.328111) (xy 199.181685 -155.528369) (xy 199.11114 -155.726085) (xy 199.033119 -155.920972)
			(xy 198.947735 -156.112747) (xy 198.855112 -156.301133) (xy 198.755385 -156.485856) (xy 198.648697 -156.666648)
			(xy 198.535203 -156.843248) (xy 198.415068 -157.015398) (xy 198.288467 -157.182851) (xy 198.155582 -157.345362)
			(xy 198.016607 -157.502696) (xy 197.871743 -157.654625) (xy 197.7212 -157.800929) (xy 197.565196 -157.941396)
			(xy 197.403957 -158.075822) (xy 197.237717 -158.204011) (xy 197.066718 -158.325779) (xy 196.891207 -158.440949)
			(xy 196.711439 -158.549353) (xy 196.527674 -158.650835) (xy 196.340178 -158.745247) (xy 196.149225 -158.832453)
			(xy 195.955089 -158.912326) (xy 195.758054 -158.98475) (xy 195.558404 -159.04962) (xy 195.356429 -159.106842)
			(xy 195.152423 -159.156334) (xy 194.946679 -159.198023) (xy 194.739498 -159.231848) (xy 194.53118 -159.257762)
			(xy 194.322026 -159.275727) (xy 194.112339 -159.285715) (xy 193.902425 -159.287714) (xy 193.692586 -159.281719)
			(xy 193.483128 -159.26774) (xy 193.274353 -159.245797) (xy 193.066566 -159.215922) (xy 192.860067 -159.178157)
			(xy 192.655154 -159.132559) (xy 192.452127 -159.079192) (xy 192.251278 -159.018135) (xy 192.0529 -158.949476)
			(xy 191.857279 -158.873313) (xy 191.664699 -158.789759) (xy 191.475441 -158.698934) (xy 191.289777 -158.600969)
			(xy 191.107977 -158.496007) (xy 190.930305 -158.3842) (xy 190.757019 -158.265709) (xy 190.588369 -158.140708)
			(xy 190.4246 -158.009376) (xy 190.26595 -157.871905) (xy 190.112648 -157.728494) (xy 189.964918 -157.57935)
			(xy 189.822972 -157.42469) (xy 189.687018 -157.264739) (xy 189.557251 -157.099727) (xy 189.433861 -156.929895)
			(xy 189.317026 -156.755488) (xy 189.206915 -156.57676) (xy 189.103688 -156.393969) (xy 189.007495 -156.207381)
			(xy 188.918476 -156.017266) (xy 188.836758 -155.8239) (xy 188.762462 -155.627563) (xy 188.695694 -155.42854)
			(xy 188.636552 -155.227119) (xy 188.58512 -155.023593) (xy 188.541475 -154.818256) (xy 188.505678 -154.611406)
			(xy 188.477782 -154.403344) (xy 188.457828 -154.19437) (xy 188.445843 -153.984788) (xy 188.441847 -153.774902)
			(xy 151.160334 -153.774902) (xy 168.043352 -170.657774) (xy 168.070276 -170.664378) (xy 168.083992 -170.660314)
			(xy 168.12028 -170.649658) (xy 168.19443 -170.634738) (xy 168.269694 -170.627246) (xy 168.307512 -170.626786)
			(xy 168.347446 -170.627303) (xy 168.426876 -170.635653) (xy 168.504999 -170.652259) (xy 168.580957 -170.676941)
			(xy 168.65392 -170.709427) (xy 168.723088 -170.749361) (xy 168.787702 -170.796307) (xy 168.847055 -170.849749)
			(xy 168.900497 -170.909103) (xy 168.947442 -170.973718) (xy 168.987376 -171.042885) (xy 169.019861 -171.115848)
			(xy 169.044542 -171.191807) (xy 169.061148 -171.26993) (xy 169.069497 -171.34936) (xy 169.07002 -171.389294)
			(xy 169.069543 -171.427111) (xy 169.062039 -171.502371) (xy 169.047133 -171.576522) (xy 169.036492 -171.612814)
			(xy 169.034166 -171.621729) (xy 169.035313 -171.6401) (xy 169.042932 -171.656856) (xy 169.049192 -171.663614)
			(xy 182.548022 -185.162698) (xy 182.555421 -185.16954) (xy 182.574021 -185.177259) (xy 182.58409 -185.177684)
			(xy 205.71333 -185.177684) (xy 205.723404 -185.178071) (xy 205.742003 -185.185816) (xy 205.749398 -185.19267)
			(xy 208.219294 -187.662312) (xy 208.226131 -187.669715) (xy 208.233853 -187.688312) (xy 208.23428 -187.69838)
			(xy 208.23428 -190.6199) (xy 220.033398 -190.6199) (xy 220.03731 -190.542762) (xy 220.049006 -190.466416)
			(xy 220.068364 -190.391644) (xy 220.095188 -190.319215) (xy 220.129202 -190.249871) (xy 220.170056 -190.184323)
			(xy 220.217331 -190.123245) (xy 220.270543 -190.067262) (xy 220.329145 -190.01695) (xy 220.392537 -189.972825)
			(xy 220.460067 -189.935338) (xy 220.531043 -189.904876) (xy 220.604736 -189.88175) (xy 220.680391 -189.866198)
			(xy 220.757232 -189.85838) (xy 220.79585 -189.857888) (xy 220.837466 -189.858409) (xy 220.920202 -189.867482)
			(xy 221.001458 -189.885515) (xy 221.080264 -189.912294) (xy 221.155685 -189.947499) (xy 221.226821 -189.990711)
			(xy 221.260162 -190.015622) (xy 221.269352 -190.02199) (xy 221.29115 -190.026845) (xy 221.312948 -190.02199)
			(xy 221.322138 -190.015622) (xy 221.355468 -189.990697) (xy 221.426608 -189.947493) (xy 221.502032 -189.912297)
			(xy 221.580841 -189.885528) (xy 221.662098 -189.867505) (xy 221.744834 -189.858442) (xy 221.78645 -189.857888)
			(xy 221.826358 -189.858375) (xy 221.905736 -189.866722) (xy 221.983807 -189.883321) (xy 222.059715 -189.90799)
			(xy 222.132629 -189.940457) (xy 222.20175 -189.980367) (xy 222.266321 -190.027284) (xy 222.325634 -190.080693)
			(xy 222.37904 -190.140009) (xy 222.425953 -190.204582) (xy 222.465861 -190.273705) (xy 222.498324 -190.346621)
			(xy 222.522989 -190.42253) (xy 222.539584 -190.500602) (xy 222.547927 -190.57998) (xy 222.54845 -190.619888)
			(xy 222.548035 -190.657331) (xy 222.54069 -190.731856) (xy 222.52607 -190.805302) (xy 222.504315 -190.876959)
			(xy 222.475635 -190.946136) (xy 222.440308 -191.012165) (xy 222.398674 -191.074411) (xy 222.351134 -191.132273)
			(xy 222.298147 -191.185191) (xy 222.240225 -191.232657) (xy 222.177926 -191.274211) (xy 222.145098 -191.292226)
			(xy 222.136576 -191.297399) (xy 222.123923 -191.312776) (xy 222.118027 -191.331797) (xy 222.118428 -191.341756)
			(xy 222.120206 -191.376554) (xy 222.11972 -191.403823) (xy 222.111958 -191.457807) (xy 222.096593 -191.510137)
			(xy 222.073936 -191.559747) (xy 222.04445 -191.605628) (xy 222.008735 -191.646845) (xy 221.967518 -191.68256)
			(xy 221.921637 -191.712046) (xy 221.872027 -191.734703) (xy 221.819697 -191.750068) (xy 221.765713 -191.75783)
			(xy 221.711175 -191.75783) (xy 221.657191 -191.750068) (xy 221.604861 -191.734703) (xy 221.555251 -191.712046)
			(xy 221.50937 -191.68256) (xy 221.468153 -191.646845) (xy 221.432438 -191.605628) (xy 221.402952 -191.559747)
			(xy 221.380295 -191.510137) (xy 221.36493 -191.457807) (xy 221.357168 -191.403823) (xy 221.356682 -191.376554)
			(xy 221.356682 -191.375792) (xy 221.356934 -191.355115) (xy 221.36139 -191.314001) (xy 221.365572 -191.29375)
			(xy 221.367257 -191.28395) (xy 221.363905 -191.264374) (xy 221.353327 -191.247565) (xy 221.345506 -191.241426)
			(xy 221.322138 -191.224154) (xy 221.312948 -191.217786) (xy 221.29115 -191.212931) (xy 221.269352 -191.217786)
			(xy 221.260162 -191.224154) (xy 221.22684 -191.24909) (xy 221.155697 -191.292291) (xy 221.080272 -191.327484)
			(xy 221.001461 -191.354251) (xy 220.920203 -191.372272) (xy 220.837466 -191.381334) (xy 220.79585 -191.381888)
			(xy 220.757232 -191.38142) (xy 220.680391 -191.373602) (xy 220.604736 -191.35805) (xy 220.531043 -191.334924)
			(xy 220.460067 -191.304462) (xy 220.392537 -191.266975) (xy 220.329145 -191.22285) (xy 220.270543 -191.172538)
			(xy 220.217331 -191.116555) (xy 220.170056 -191.055477) (xy 220.129202 -190.989929) (xy 220.095188 -190.920585)
			(xy 220.068364 -190.848156) (xy 220.049006 -190.773384) (xy 220.03731 -190.697038) (xy 220.033398 -190.6199)
			(xy 208.23428 -190.6199) (xy 208.23428 -192.589912) (xy 208.233866 -192.599983) (xy 208.226138 -192.618581)
			(xy 208.219294 -192.62598) (xy 207.67802 -193.167254) (xy 207.671321 -193.174548) (xy 207.663665 -193.192795)
			(xy 207.663503 -193.212583) (xy 207.67086 -193.230953) (xy 207.684634 -193.24516) (xy 207.693514 -193.24955)
			(xy 207.729332 -193.265891) (xy 207.79762 -193.305075) (xy 207.861425 -193.351201) (xy 207.920046 -193.40376)
			(xy 207.972835 -193.462172) (xy 208.019213 -193.525795) (xy 208.058667 -193.593928) (xy 208.090764 -193.665821)
			(xy 208.115149 -193.740681) (xy 208.131555 -193.817685) (xy 208.139801 -193.895984) (xy 208.1403 -193.93535)
			(xy 208.139804 -193.97299) (xy 208.13226 -194.047892) (xy 208.117242 -194.121659) (xy 208.094903 -194.193548)
			(xy 208.065468 -194.262835) (xy 208.029232 -194.328821) (xy 207.986562 -194.39084) (xy 207.937888 -194.448268)
			(xy 207.8837 -194.500525) (xy 207.824545 -194.547085) (xy 207.76102 -194.587478) (xy 207.693763 -194.621297)
			(xy 207.623455 -194.648201) (xy 207.550802 -194.667919) (xy 207.476539 -194.680251) (xy 207.439006 -194.683126)
			(xy 207.429453 -194.684189) (xy 207.412107 -194.692435) (xy 207.39899 -194.706464) (xy 207.391926 -194.724324)
			(xy 207.391508 -194.733926) (xy 207.391508 -194.803268) (xy 207.391 -194.803776) (xy 207.391 -210.116166)
			(xy 207.414368 -210.14436) (xy 207.432656 -210.147662) (xy 207.459064 -210.153096) (xy 207.510086 -210.170509)
			(xy 207.55803 -210.195166) (xy 207.601873 -210.226539) (xy 207.640681 -210.263961) (xy 207.673628 -210.306634)
			(xy 207.700012 -210.353649) (xy 207.719269 -210.404005) (xy 207.730991 -210.456627) (xy 207.734926 -210.510395)
			(xy 207.730992 -210.564164) (xy 207.719272 -210.616786) (xy 207.700016 -210.667142) (xy 207.673634 -210.714158)
			(xy 207.640688 -210.756832) (xy 207.60188 -210.794255) (xy 207.558038 -210.825629) (xy 207.510095 -210.850287)
			(xy 207.459073 -210.867702) (xy 207.432656 -210.873086) (xy 207.414368 -210.876388) (xy 207.391 -210.904582)
			(xy 207.391 -213.806024) (xy 255.16332 -213.806024) (xy 255.163939 -213.763335) (xy 255.173499 -213.678492)
			(xy 255.192458 -213.595245) (xy 255.220578 -213.514629) (xy 255.257511 -213.437652) (xy 255.279652 -213.401148)
			(xy 255.28433 -213.392878) (xy 255.287848 -213.374221) (xy 255.284345 -213.355561) (xy 255.279652 -213.3473)
			(xy 255.257505 -213.310799) (xy 255.22056 -213.233825) (xy 255.192433 -213.15321) (xy 255.173475 -213.06996)
			(xy 255.163925 -212.985114) (xy 255.16332 -212.942424) (xy 255.163766 -212.903597) (xy 255.171658 -212.826346)
			(xy 255.187352 -212.750295) (xy 255.210688 -212.676231) (xy 255.241422 -212.604918) (xy 255.279239 -212.537095)
			(xy 255.323746 -212.473462) (xy 255.374484 -212.414677) (xy 255.430928 -212.361347) (xy 255.492496 -212.314023)
			(xy 255.52527 -212.2932) (xy 255.534579 -212.286756) (xy 255.546843 -212.26776) (xy 255.548892 -212.256624)
			(xy 255.553093 -212.229107) (xy 255.568404 -212.175594) (xy 255.591341 -212.124878) (xy 255.621414 -212.07804)
			(xy 255.639316 -212.056726) (xy 255.63957 -212.056472) (xy 255.645141 -212.049375) (xy 255.651395 -212.032466)
			(xy 255.651762 -212.023452) (xy 255.651762 -211.956396) (xy 255.651415 -211.947378) (xy 255.645162 -211.930461)
			(xy 255.63957 -211.923376) (xy 255.639316 -211.923122) (xy 255.619442 -211.899446) (xy 255.586881 -211.846907)
			(xy 255.563219 -211.789803) (xy 255.549076 -211.729631) (xy 255.546352 -211.69884) (xy 255.5448 -211.686853)
			(xy 255.532356 -211.666175) (xy 255.522476 -211.659216) (xy 255.489925 -211.638335) (xy 255.428804 -211.590946)
			(xy 255.372787 -211.537622) (xy 255.322446 -211.478909) (xy 255.278297 -211.415408) (xy 255.240794 -211.34777)
			(xy 255.210319 -211.276687) (xy 255.187185 -211.202889) (xy 255.171628 -211.127129) (xy 255.163809 -211.050186)
			(xy 255.16332 -211.011516) (xy 255.163935 -210.968827) (xy 255.173496 -210.883984) (xy 255.192455 -210.800736)
			(xy 255.220577 -210.720121) (xy 255.25751 -210.643144) (xy 255.279652 -210.60664) (xy 255.284337 -210.598373)
			(xy 255.287852 -210.579714) (xy 255.284347 -210.561053) (xy 255.279652 -210.552792) (xy 255.257502 -210.516293)
			(xy 255.220557 -210.439318) (xy 255.192431 -210.358703) (xy 255.173474 -210.275452) (xy 255.163924 -210.190607)
			(xy 255.16332 -210.147916) (xy 255.163795 -210.109245) (xy 255.171604 -210.032298) (xy 255.187153 -209.956536)
			(xy 255.210285 -209.882734) (xy 255.24076 -209.811649) (xy 255.278267 -209.74401) (xy 255.322422 -209.680511)
			(xy 255.372771 -209.621802) (xy 255.428798 -209.568486) (xy 255.48993 -209.521108) (xy 255.522476 -209.500216)
			(xy 255.532389 -209.493286) (xy 255.544847 -209.472594) (xy 255.546352 -209.460592) (xy 255.549098 -209.429807)
			(xy 255.563274 -209.36965) (xy 255.58694 -209.312557) (xy 255.61948 -209.260013) (xy 255.639316 -209.23631)
			(xy 255.63957 -209.236056) (xy 255.645147 -209.228964) (xy 255.651398 -209.212051) (xy 255.651762 -209.203036)
			(xy 255.651762 -209.13598) (xy 255.651423 -209.126961) (xy 255.645164 -209.110044) (xy 255.63957 -209.10296)
			(xy 255.639316 -209.102706) (xy 255.621436 -209.081376) (xy 255.591386 -209.034529) (xy 255.568446 -208.98382)
			(xy 255.553101 -208.930321) (xy 255.548892 -208.902808) (xy 255.546808 -208.891691) (xy 255.534539 -208.872717)
			(xy 255.52527 -208.866232) (xy 255.492511 -208.845387) (xy 255.430943 -208.798068) (xy 255.374498 -208.744742)
			(xy 255.323761 -208.685959) (xy 255.279255 -208.622328) (xy 255.241441 -208.554507) (xy 255.210709 -208.483196)
			(xy 255.187377 -208.409133) (xy 255.171688 -208.333083) (xy 255.163801 -208.255834) (xy 255.16332 -208.217008)
			(xy 255.163932 -208.174318) (xy 255.173493 -208.089476) (xy 255.192453 -208.006228) (xy 255.220576 -207.925613)
			(xy 255.25751 -207.848635) (xy 255.279652 -207.812132) (xy 255.284343 -207.803868) (xy 255.287856 -207.785207)
			(xy 255.284348 -207.766545) (xy 255.279652 -207.758284) (xy 255.257498 -207.721786) (xy 255.220554 -207.644812)
			(xy 255.192428 -207.564195) (xy 255.173473 -207.480945) (xy 255.163924 -207.396099) (xy 255.16332 -207.353408)
			(xy 255.163753 -207.314581) (xy 255.171646 -207.237329) (xy 255.187343 -207.161278) (xy 255.21068 -207.087213)
			(xy 255.241416 -207.015901) (xy 255.279233 -206.948078) (xy 255.323742 -206.884445) (xy 255.374481 -206.82566)
			(xy 255.430927 -206.77233) (xy 255.492495 -206.725007) (xy 255.52527 -206.704184) (xy 255.534585 -206.697747)
			(xy 255.546846 -206.678746) (xy 255.548892 -206.667608) (xy 255.553086 -206.64009) (xy 255.568399 -206.586576)
			(xy 255.591338 -206.535861) (xy 255.621413 -206.489024) (xy 255.639316 -206.46771) (xy 255.63957 -206.467456)
			(xy 255.645147 -206.460364) (xy 255.651398 -206.443451) (xy 255.651762 -206.434436) (xy 255.651762 -206.367634)
			(xy 255.651322 -206.35845) (xy 255.644828 -206.341266) (xy 255.639062 -206.334106) (xy 255.620353 -206.311792)
			(xy 255.589219 -206.262588) (xy 255.565924 -206.209223) (xy 255.551009 -206.152938) (xy 255.547368 -206.124048)
			(xy 255.546084 -206.115048) (xy 255.537998 -206.098778) (xy 255.53162 -206.092298) (xy 255.498385 -206.071602)
			(xy 255.435934 -206.024373) (xy 255.378648 -205.970997) (xy 255.32713 -205.912035) (xy 255.281921 -205.848106)
			(xy 255.243497 -205.779884) (xy 255.212263 -205.708085) (xy 255.188545 -205.633465) (xy 255.172594 -205.556809)
			(xy 255.164578 -205.478921) (xy 255.164082 -205.439772) (xy 255.16448 -205.403376) (xy 255.17138 -205.330911)
			(xy 255.185153 -205.259433) (xy 255.205672 -205.189593) (xy 255.232752 -205.122025) (xy 255.266147 -205.057345)
			(xy 255.285494 -205.026514) (xy 255.288632 -205.017506) (xy 255.288622 -204.998443) (xy 255.285494 -204.98943)
			(xy 255.266145 -204.958601) (xy 255.232764 -204.893915) (xy 255.205692 -204.826346) (xy 255.185175 -204.756506)
			(xy 255.171401 -204.68503) (xy 255.164493 -204.612568) (xy 255.164082 -204.576172) (xy 255.164559 -204.537023)
			(xy 255.17258 -204.459137) (xy 255.188536 -204.382481) (xy 255.212258 -204.307863) (xy 255.243497 -204.236067)
			(xy 255.281924 -204.167847) (xy 255.327136 -204.103921) (xy 255.378657 -204.044961) (xy 255.435945 -203.991588)
			(xy 255.498398 -203.944363) (xy 255.53162 -203.923646) (xy 255.537978 -203.917154) (xy 255.546046 -203.900886)
			(xy 255.547368 -203.891896) (xy 255.551019 -203.863009) (xy 255.565954 -203.806732) (xy 255.589248 -203.753371)
			(xy 255.620365 -203.704159) (xy 255.639062 -203.681838) (xy 255.644875 -203.674705) (xy 255.651378 -203.657505)
			(xy 255.651762 -203.64831) (xy 255.651762 -203.581508) (xy 255.651409 -203.572491) (xy 255.645159 -203.555573)
			(xy 255.63957 -203.548488) (xy 255.639316 -203.548234) (xy 255.621446 -203.526896) (xy 255.591394 -203.480052)
			(xy 255.568451 -203.429345) (xy 255.553103 -203.375848) (xy 255.548892 -203.348336) (xy 255.546794 -203.337222)
			(xy 255.534535 -203.318247) (xy 255.52527 -203.31176) (xy 255.492478 -203.290965) (xy 255.43091 -203.24364)
			(xy 255.374466 -203.190308) (xy 255.32373 -203.13152) (xy 255.279227 -203.067883) (xy 255.241416 -203.000056)
			(xy 255.210688 -202.928739) (xy 255.187361 -202.854671) (xy 255.171677 -202.778617) (xy 255.163798 -202.701363)
			(xy 255.16332 -202.662536) (xy 255.163945 -202.619847) (xy 255.173503 -202.535005) (xy 255.192461 -202.451757)
			(xy 255.22058 -202.371142) (xy 255.257511 -202.294164) (xy 255.279652 -202.25766) (xy 255.284321 -202.249385)
			(xy 255.287841 -202.230731) (xy 255.284343 -202.212073) (xy 255.279652 -202.203812) (xy 255.25751 -202.167308)
			(xy 255.220564 -202.090335) (xy 255.192436 -202.00972) (xy 255.173477 -201.926471) (xy 255.163925 -201.841626)
			(xy 255.16332 -201.798936) (xy 255.163775 -201.76011) (xy 255.171666 -201.682858) (xy 255.18736 -201.606808)
			(xy 255.210694 -201.532744) (xy 255.241427 -201.461431) (xy 255.279243 -201.393608) (xy 255.323749 -201.329975)
			(xy 255.374486 -201.271189) (xy 255.430929 -201.217859) (xy 255.492496 -201.170535) (xy 255.52527 -201.149712)
			(xy 255.534575 -201.143263) (xy 255.546841 -201.12427) (xy 255.548892 -201.113136) (xy 255.553098 -201.08562)
			(xy 255.568408 -201.032107) (xy 255.591343 -200.981391) (xy 255.621414 -200.934553) (xy 255.639316 -200.913238)
			(xy 255.63957 -200.912984) (xy 255.645178 -200.905912) (xy 255.65141 -200.888984) (xy 255.651762 -200.879964)
			(xy 255.651762 -200.812908) (xy 255.651409 -200.803891) (xy 255.645159 -200.786973) (xy 255.63957 -200.779888)
			(xy 255.639316 -200.779634) (xy 255.619447 -200.755955) (xy 255.586884 -200.703416) (xy 255.563221 -200.646314)
			(xy 255.549077 -200.586143) (xy 255.546352 -200.555352) (xy 255.544794 -200.543367) (xy 255.532354 -200.522688)
			(xy 255.522476 -200.515728) (xy 255.489931 -200.494839) (xy 255.42881 -200.447451) (xy 255.372792 -200.394128)
			(xy 255.322451 -200.335415) (xy 255.278302 -200.271915) (xy 255.240798 -200.204278) (xy 255.210322 -200.133197)
			(xy 255.187187 -200.059399) (xy 255.17163 -199.98364) (xy 255.16381 -199.906698) (xy 255.16332 -199.868028)
			(xy 255.163941 -199.825339) (xy 255.173501 -199.740497) (xy 255.192459 -199.657249) (xy 255.220579 -199.576634)
			(xy 255.257511 -199.499656) (xy 255.279652 -199.463152) (xy 255.284327 -199.45488) (xy 255.287846 -199.436224)
			(xy 255.284345 -199.417565) (xy 255.279652 -199.409304) (xy 255.257507 -199.372802) (xy 255.220561 -199.295828)
			(xy 255.192434 -199.215213) (xy 255.173476 -199.131963) (xy 255.163925 -199.047118) (xy 255.16332 -199.004428)
			(xy 255.163804 -198.965757) (xy 255.171612 -198.888811) (xy 255.187161 -198.813048) (xy 255.210291 -198.739247)
			(xy 255.240765 -198.668162) (xy 255.278271 -198.600523) (xy 255.322425 -198.537024) (xy 255.372773 -198.478315)
			(xy 255.4288 -198.424998) (xy 255.489931 -198.37762) (xy 255.522476 -198.356728) (xy 255.532384 -198.349793)
			(xy 255.544845 -198.329104) (xy 255.546352 -198.317104) (xy 255.549104 -198.286319) (xy 255.563279 -198.226163)
			(xy 255.586943 -198.16907) (xy 255.619481 -198.116525) (xy 255.639316 -198.092822) (xy 255.63957 -198.092568)
			(xy 255.645142 -198.085472) (xy 255.651396 -198.068562) (xy 255.651762 -198.059548) (xy 255.651762 -197.992492)
			(xy 255.651417 -197.983474) (xy 255.645162 -197.966556) (xy 255.63957 -197.959472) (xy 255.639316 -197.959218)
			(xy 255.62144 -197.937885) (xy 255.591389 -197.891039) (xy 255.568448 -197.840331) (xy 255.553102 -197.786832)
			(xy 255.548892 -197.75932) (xy 255.546803 -197.748204) (xy 255.534537 -197.72923) (xy 255.52527 -197.722744)
			(xy 255.492516 -197.701891) (xy 255.430948 -197.654573) (xy 255.374504 -197.601247) (xy 255.323766 -197.542466)
			(xy 255.27926 -197.478836) (xy 255.241445 -197.411015) (xy 255.210712 -197.339705) (xy 255.18738 -197.265643)
			(xy 255.171689 -197.189594) (xy 255.163802 -197.112345) (xy 255.16332 -197.07352) (xy 255.163937 -197.030831)
			(xy 255.173498 -196.945988) (xy 255.192457 -196.862741) (xy 255.220578 -196.782125) (xy 255.257511 -196.705148)
			(xy 255.279652 -196.668644) (xy 255.284334 -196.660375) (xy 255.28785 -196.641717) (xy 255.284346 -196.623057)
			(xy 255.279652 -196.614796) (xy 255.257503 -196.578296) (xy 255.220558 -196.501322) (xy 255.192432 -196.420706)
			(xy 255.173475 -196.337456) (xy 255.163924 -196.25261) (xy 255.16332 -196.20992) (xy 255.163762 -196.171093)
			(xy 255.171655 -196.093842) (xy 255.18735 -196.017791) (xy 255.210686 -195.943726) (xy 255.241421 -195.872414)
			(xy 255.279237 -195.804591) (xy 255.323745 -195.740958) (xy 255.374483 -195.682172) (xy 255.430928 -195.628842)
			(xy 255.492496 -195.581519) (xy 255.52527 -195.560696) (xy 255.534581 -195.554254) (xy 255.546844 -195.535256)
			(xy 255.548892 -195.52412) (xy 255.553091 -195.496603) (xy 255.568403 -195.443089) (xy 255.59134 -195.392374)
			(xy 255.621413 -195.345536) (xy 255.639316 -195.324222) (xy 255.63957 -195.323968) (xy 255.645142 -195.316872)
			(xy 255.651396 -195.299962) (xy 255.651762 -195.290948) (xy 255.651762 -195.224146) (xy 255.651316 -195.214963)
			(xy 255.644826 -195.197779) (xy 255.639062 -195.190618) (xy 255.620358 -195.168301) (xy 255.589223 -195.119097)
			(xy 255.565926 -195.065734) (xy 255.55101 -195.00945) (xy 255.547368 -194.98056) (xy 255.546079 -194.971561)
			(xy 255.537996 -194.955291) (xy 255.53162 -194.94881) (xy 255.498391 -194.928105) (xy 255.43594 -194.880878)
			(xy 255.378654 -194.827503) (xy 255.327135 -194.768541) (xy 255.281926 -194.704614) (xy 255.243502 -194.636392)
			(xy 255.212266 -194.564595) (xy 255.188548 -194.489975) (xy 255.172596 -194.41332) (xy 255.164579 -194.335433)
			(xy 255.164082 -194.296284) (xy 255.164514 -194.259986) (xy 255.171408 -194.187719) (xy 255.185132 -194.116433)
			(xy 255.205562 -194.046772) (xy 255.232514 -193.979366) (xy 255.265744 -193.914823) (xy 255.284986 -193.884042)
			(xy 255.288584 -193.872805) (xy 255.286207 -193.849362) (xy 255.280414 -193.839084) (xy 255.258091 -193.802485)
			(xy 255.220891 -193.725245) (xy 255.192574 -193.644324) (xy 255.173496 -193.560742) (xy 255.163898 -193.47555)
			(xy 255.16332 -193.432684) (xy 255.163873 -193.392157) (xy 255.172446 -193.311559) (xy 255.189503 -193.232321)
			(xy 255.214854 -193.155334) (xy 255.248213 -193.081464) (xy 255.289205 -193.01154) (xy 255.33737 -192.94635)
			(xy 255.392166 -192.886626) (xy 255.452978 -192.833038) (xy 255.519121 -192.78619) (xy 255.554226 -192.765934)
			(xy 255.56392 -192.759704) (xy 255.57712 -192.740858) (xy 255.579626 -192.729612) (xy 255.584278 -192.703006)
			(xy 255.600108 -192.651367) (xy 255.623062 -192.602476) (xy 255.652679 -192.55731) (xy 255.688369 -192.516772)
			(xy 255.729419 -192.48167) (xy 255.775007 -192.452707) (xy 255.824224 -192.430461) (xy 255.876086 -192.415377)
			(xy 255.929557 -192.407757) (xy 255.956562 -192.407286) (xy 255.985332 -192.407765) (xy 256.04222 -192.416394)
			(xy 256.097169 -192.433464) (xy 256.148934 -192.458586) (xy 256.196343 -192.491193) (xy 256.238321 -192.530545)
			(xy 256.273918 -192.575751) (xy 256.302327 -192.625787) (xy 256.322906 -192.679521) (xy 256.335187 -192.735734)
			(xy 256.337562 -192.76441) (xy 256.338811 -192.775907) (xy 256.350203 -192.796011) (xy 256.359406 -192.803018)
			(xy 256.392994 -192.826768) (xy 256.455417 -192.880349) (xy 256.511721 -192.940328) (xy 256.561252 -193.006012)
			(xy 256.603436 -193.076638) (xy 256.637786 -193.151389) (xy 256.663903 -193.229398) (xy 256.681485 -193.309763)
			(xy 256.690329 -193.391551) (xy 256.690876 -193.432684) (xy 256.690293 -193.47555) (xy 256.680694 -193.560742)
			(xy 256.661617 -193.644323) (xy 256.6333 -193.725242) (xy 256.5961 -193.802482) (xy 256.573782 -193.839084)
			(xy 256.568034 -193.849375) (xy 256.565656 -193.872802) (xy 256.56921 -193.884042) (xy 256.588441 -193.91483)
			(xy 256.621674 -193.97937) (xy 256.648629 -194.046775) (xy 256.669062 -194.116435) (xy 256.682788 -194.18772)
			(xy 256.689683 -194.259987) (xy 256.690114 -194.296284) (xy 256.689604 -194.335432) (xy 256.681587 -194.413317)
			(xy 256.665636 -194.489972) (xy 256.664792 -194.492626) (xy 259.713222 -194.492626) (xy 259.713799 -194.451012)
			(xy 259.722863 -194.368278) (xy 259.740886 -194.287024) (xy 259.767655 -194.208217) (xy 259.802849 -194.132796)
			(xy 259.84605 -194.061657) (xy 259.870956 -194.028314) (xy 259.877298 -194.019109) (xy 259.882159 -193.997321)
			(xy 259.877316 -193.975529) (xy 259.870956 -193.966338) (xy 259.846056 -193.93299) (xy 259.802851 -193.861853)
			(xy 259.767652 -193.786433) (xy 259.740878 -193.707628) (xy 259.72285 -193.626374) (xy 259.71378 -193.543641)
			(xy 259.713222 -193.502026) (xy 259.713711 -193.463407) (xy 259.721525 -193.386564) (xy 259.737073 -193.310906)
			(xy 259.760196 -193.237209) (xy 259.790655 -193.16623) (xy 259.82814 -193.098696) (xy 259.872264 -193.035302)
			(xy 259.922575 -192.976696) (xy 259.978557 -192.923481) (xy 260.039636 -192.876202) (xy 260.105184 -192.835346)
			(xy 260.17453 -192.80133) (xy 260.246961 -192.774505) (xy 260.321734 -192.755145) (xy 260.398082 -192.743449)
			(xy 260.475222 -192.739537) (xy 260.552362 -192.743449) (xy 260.62871 -192.755145) (xy 260.703483 -192.774505)
			(xy 260.775914 -192.80133) (xy 260.84526 -192.835346) (xy 260.910808 -192.876202) (xy 260.971887 -192.923481)
			(xy 261.027869 -192.976696) (xy 261.07818 -193.035302) (xy 261.122304 -193.098696) (xy 261.159789 -193.16623)
			(xy 261.190248 -193.237209) (xy 261.213371 -193.310906) (xy 261.228919 -193.386564) (xy 261.236733 -193.463407)
			(xy 261.237222 -193.502026) (xy 261.236686 -193.543642) (xy 261.227615 -193.626377) (xy 261.209585 -193.707632)
			(xy 261.182809 -193.786439) (xy 261.147607 -193.86186) (xy 261.104398 -193.932996) (xy 261.079488 -193.966338)
			(xy 261.073095 -193.975514) (xy 261.068245 -193.997321) (xy 261.073112 -194.019124) (xy 261.079488 -194.028314)
			(xy 261.104404 -194.061651) (xy 261.147609 -194.132789) (xy 261.182806 -194.208212) (xy 261.209577 -194.28702)
			(xy 261.227602 -194.368275) (xy 261.236667 -194.451011) (xy 261.237222 -194.492626) (xy 261.236733 -194.531245)
			(xy 261.228919 -194.608088) (xy 261.213371 -194.683746) (xy 261.190248 -194.757443) (xy 261.159789 -194.828422)
			(xy 261.122304 -194.895956) (xy 261.07818 -194.95935) (xy 261.027869 -195.017956) (xy 260.971887 -195.071171)
			(xy 260.910808 -195.11845) (xy 260.84526 -195.159306) (xy 260.775914 -195.193322) (xy 260.703483 -195.220147)
			(xy 260.62871 -195.239507) (xy 260.552362 -195.251203) (xy 260.475222 -195.255116) (xy 260.398082 -195.251203)
			(xy 260.321734 -195.239507) (xy 260.246961 -195.220147) (xy 260.17453 -195.193322) (xy 260.105184 -195.159306)
			(xy 260.039636 -195.11845) (xy 259.978557 -195.071171) (xy 259.922575 -195.017956) (xy 259.872264 -194.95935)
			(xy 259.82814 -194.895956) (xy 259.790655 -194.828422) (xy 259.760196 -194.757443) (xy 259.737073 -194.683746)
			(xy 259.721525 -194.608088) (xy 259.713711 -194.531245) (xy 259.713222 -194.492626) (xy 256.664792 -194.492626)
			(xy 256.641918 -194.56459) (xy 256.610683 -194.636386) (xy 256.572259 -194.704606) (xy 256.52705 -194.768533)
			(xy 256.475532 -194.827493) (xy 256.418247 -194.880867) (xy 256.355797 -194.928093) (xy 256.322576 -194.94881)
			(xy 256.316234 -194.955315) (xy 256.308157 -194.971573) (xy 256.306828 -194.98056) (xy 256.303157 -195.009444)
			(xy 256.288229 -195.065721) (xy 256.26494 -195.119083) (xy 256.233829 -195.168296) (xy 256.215134 -195.190618)
			(xy 256.209339 -195.197764) (xy 256.202825 -195.214954) (xy 256.202434 -195.224146) (xy 256.202434 -195.290948)
			(xy 256.202809 -195.299963) (xy 256.209043 -195.316881) (xy 256.214626 -195.323968) (xy 256.21488 -195.324222)
			(xy 256.23277 -195.345544) (xy 256.262818 -195.392394) (xy 256.285755 -195.443105) (xy 256.301096 -195.496607)
			(xy 256.305304 -195.52412) (xy 256.307425 -195.535227) (xy 256.319668 -195.554205) (xy 256.328926 -195.560696)
			(xy 256.361697 -195.581523) (xy 256.423265 -195.628844) (xy 256.479709 -195.682172) (xy 256.530447 -195.740957)
			(xy 256.574952 -195.80459) (xy 256.612765 -195.872414) (xy 256.643495 -195.943727) (xy 256.666825 -196.017792)
			(xy 256.682512 -196.093843) (xy 256.690396 -196.171094) (xy 256.690876 -196.20992) (xy 256.690278 -196.25261)
			(xy 256.680713 -196.337453) (xy 256.66175 -196.420701) (xy 256.633625 -196.501316) (xy 256.596687 -196.578293)
			(xy 256.574544 -196.614796) (xy 256.56983 -196.623049) (xy 256.566325 -196.641717) (xy 256.569843 -196.660383)
			(xy 256.574544 -196.668644) (xy 256.596709 -196.705135) (xy 256.633651 -196.782112) (xy 256.661775 -196.86273)
			(xy 256.680728 -196.945982) (xy 256.690274 -197.030829) (xy 256.690876 -197.07352) (xy 256.69034 -197.112344)
			(xy 256.682455 -197.189591) (xy 256.666768 -197.265638) (xy 256.643441 -197.3397) (xy 256.612716 -197.41101)
			(xy 256.57491 -197.478833) (xy 256.530413 -197.542467) (xy 256.479685 -197.601255) (xy 256.423252 -197.654589)
			(xy 256.361695 -197.701918) (xy 256.328926 -197.722744) (xy 256.319637 -197.729213) (xy 256.307363 -197.748191)
			(xy 256.305304 -197.75932) (xy 256.301124 -197.78684) (xy 256.285806 -197.840354) (xy 256.262863 -197.891069)
			(xy 256.232785 -197.937905) (xy 256.21488 -197.959218) (xy 256.214626 -197.959472) (xy 256.209036 -197.966556)
			(xy 256.202793 -197.983475) (xy 256.202434 -197.992492) (xy 256.202434 -198.059548) (xy 256.202809 -198.068563)
			(xy 256.209043 -198.085481) (xy 256.214626 -198.092568) (xy 256.21488 -198.092822) (xy 256.23473 -198.116516)
			(xy 256.267297 -198.16905) (xy 256.290965 -198.226147) (xy 256.305116 -198.286314) (xy 256.307844 -198.317104)
			(xy 256.309373 -198.329095) (xy 256.321834 -198.349771) (xy 256.33172 -198.356728) (xy 256.364245 -198.377649)
			(xy 256.425365 -198.425033) (xy 256.481384 -198.478353) (xy 256.531726 -198.537061) (xy 256.575876 -198.600557)
			(xy 256.613383 -198.668191) (xy 256.643861 -198.739269) (xy 256.666999 -198.813064) (xy 256.68256 -198.888819)
			(xy 256.690384 -198.965759) (xy 256.690876 -199.004428) (xy 256.690282 -199.047118) (xy 256.680716 -199.131961)
			(xy 256.661752 -199.215209) (xy 256.633626 -199.295824) (xy 256.596688 -199.372801) (xy 256.574544 -199.409304)
			(xy 256.569824 -199.417554) (xy 256.566321 -199.436224) (xy 256.569841 -199.454891) (xy 256.574544 -199.463152)
			(xy 256.596712 -199.499641) (xy 256.633654 -199.576618) (xy 256.661777 -199.657237) (xy 256.680729 -199.740489)
			(xy 256.690274 -199.825337) (xy 256.690876 -199.868028) (xy 256.690438 -199.9067) (xy 256.682625 -199.983648)
			(xy 256.667071 -200.059412) (xy 256.643935 -200.133214) (xy 256.613456 -200.204299) (xy 256.575945 -200.271937)
			(xy 256.531786 -200.335436) (xy 256.481433 -200.394144) (xy 256.425402 -200.44746) (xy 256.364267 -200.494837)
			(xy 256.33172 -200.515728) (xy 256.321829 -200.522684) (xy 256.309359 -200.543357) (xy 256.307844 -200.555352)
			(xy 256.305121 -200.58614) (xy 256.290938 -200.646297) (xy 256.267265 -200.70339) (xy 256.234719 -200.755932)
			(xy 256.21488 -200.779634) (xy 256.214626 -200.779888) (xy 256.20903 -200.786968) (xy 256.202791 -200.80389)
			(xy 256.202434 -200.812908) (xy 256.202434 -200.879964) (xy 256.202801 -200.88898) (xy 256.209041 -200.905897)
			(xy 256.214626 -200.912984) (xy 256.21488 -200.913238) (xy 256.232776 -200.934555) (xy 256.262822 -200.981407)
			(xy 256.285758 -201.032119) (xy 256.301097 -201.085622) (xy 256.305304 -201.113136) (xy 256.307417 -201.124246)
			(xy 256.319665 -201.143222) (xy 256.328926 -201.149712) (xy 256.361704 -201.170528) (xy 256.423272 -201.21785)
			(xy 256.479717 -201.27118) (xy 256.530453 -201.329966) (xy 256.574958 -201.3936) (xy 256.61277 -201.461425)
			(xy 256.6435 -201.532739) (xy 256.666828 -201.606805) (xy 256.682515 -201.682857) (xy 256.690397 -201.760109)
			(xy 256.690876 -201.798936) (xy 256.690286 -201.841626) (xy 256.680719 -201.926469) (xy 256.661754 -202.009717)
			(xy 256.633627 -202.090332) (xy 256.596688 -202.167309) (xy 256.574544 -202.203812) (xy 256.569817 -202.212059)
			(xy 256.566317 -202.230731) (xy 256.56984 -202.249399) (xy 256.574544 -202.25766) (xy 256.596715 -202.294147)
			(xy 256.633657 -202.371125) (xy 256.661779 -202.451744) (xy 256.68073 -202.534997) (xy 256.690275 -202.619845)
			(xy 256.690876 -202.662536) (xy 256.690353 -202.70136) (xy 256.682466 -202.778608) (xy 256.666778 -202.854655)
			(xy 256.643449 -202.928717) (xy 256.612723 -203.000028) (xy 256.574915 -203.06785) (xy 256.530417 -203.131484)
			(xy 256.479688 -203.190272) (xy 256.423253 -203.243605) (xy 256.361696 -203.290934) (xy 256.328926 -203.31176)
			(xy 256.319631 -203.318221) (xy 256.30736 -203.337205) (xy 256.305304 -203.348336) (xy 256.301131 -203.375857)
			(xy 256.285811 -203.429371) (xy 256.262866 -203.480085) (xy 256.232786 -203.526921) (xy 256.21488 -203.548234)
			(xy 256.214626 -203.548488) (xy 256.20903 -203.555568) (xy 256.202791 -203.57249) (xy 256.202434 -203.581508)
			(xy 256.202434 -203.64831) (xy 256.202854 -203.657496) (xy 256.209363 -203.674679) (xy 256.215134 -203.681838)
			(xy 256.233859 -203.704139) (xy 256.26499 -203.753348) (xy 256.288281 -203.806716) (xy 256.30319 -203.863004)
			(xy 256.306828 -203.891896) (xy 256.308138 -203.90089) (xy 256.316206 -203.917162) (xy 256.322576 -203.923646)
			(xy 256.355785 -203.944383) (xy 256.418236 -203.991607) (xy 256.475522 -204.044978) (xy 256.527042 -204.103936)
			(xy 256.572252 -204.167859) (xy 256.610679 -204.236077) (xy 256.641917 -204.307871) (xy 256.665638 -204.382487)
			(xy 256.681594 -204.45914) (xy 256.689615 -204.537024) (xy 256.690114 -204.576172) (xy 256.689738 -204.612569)
			(xy 256.682834 -204.685034) (xy 256.669057 -204.756512) (xy 256.648534 -204.826353) (xy 256.621449 -204.89392)
			(xy 256.588051 -204.9586) (xy 256.568702 -204.98943) (xy 256.565594 -204.998447) (xy 256.565585 -205.017502)
			(xy 256.568702 -205.026514) (xy 256.588026 -205.057358) (xy 256.621411 -205.12204) (xy 256.648487 -205.189606)
			(xy 256.669008 -205.259443) (xy 256.682788 -205.330917) (xy 256.689701 -205.403377) (xy 256.690114 -205.439772)
			(xy 256.689594 -205.47892) (xy 256.681579 -205.556805) (xy 256.665628 -205.633459) (xy 256.641912 -205.708077)
			(xy 256.610678 -205.779873) (xy 256.572255 -205.848093) (xy 256.527047 -205.91202) (xy 256.47553 -205.97098)
			(xy 256.418246 -206.024354) (xy 256.355797 -206.071581) (xy 256.322576 -206.092298) (xy 256.316201 -206.098775)
			(xy 256.308143 -206.115054) (xy 256.306828 -206.124048) (xy 256.303152 -206.152932) (xy 256.288225 -206.209208)
			(xy 256.264938 -206.26257) (xy 256.233828 -206.311784) (xy 256.215134 -206.334106) (xy 256.209344 -206.341256)
			(xy 256.202827 -206.358443) (xy 256.202434 -206.367634) (xy 256.202434 -206.434436) (xy 256.202766 -206.443456)
			(xy 256.20903 -206.460373) (xy 256.214626 -206.467456) (xy 256.21488 -206.46771) (xy 256.232766 -206.489036)
			(xy 256.262814 -206.535884) (xy 256.285753 -206.586594) (xy 256.301096 -206.640095) (xy 256.305304 -206.667608)
			(xy 256.307431 -206.678714) (xy 256.319669 -206.697692) (xy 256.328926 -206.704184) (xy 256.361692 -206.725019)
			(xy 256.42326 -206.772339) (xy 256.479704 -206.825667) (xy 256.530441 -206.88445) (xy 256.574947 -206.948083)
			(xy 256.612761 -207.015905) (xy 256.643492 -207.087217) (xy 256.666822 -207.161281) (xy 256.682511 -207.237332)
			(xy 256.690395 -207.314582) (xy 256.690876 -207.353408) (xy 256.690273 -207.396098) (xy 256.680709 -207.480941)
			(xy 256.661747 -207.564188) (xy 256.633623 -207.644804) (xy 256.596687 -207.721781) (xy 256.574544 -207.758284)
			(xy 256.56984 -207.766542) (xy 256.566331 -207.785207) (xy 256.569845 -207.803871) (xy 256.574544 -207.812132)
			(xy 256.596704 -207.848626) (xy 256.633647 -207.925602) (xy 256.661771 -208.006219) (xy 256.680726 -208.089471)
			(xy 256.690273 -208.174317) (xy 256.690876 -208.217008) (xy 256.690331 -208.255832) (xy 256.682447 -208.333078)
			(xy 256.666761 -208.409125) (xy 256.643435 -208.483187) (xy 256.612711 -208.554497) (xy 256.574906 -208.62232)
			(xy 256.53041 -208.685954) (xy 256.479683 -208.744742) (xy 256.423251 -208.798076) (xy 256.361695 -208.845406)
			(xy 256.328926 -208.866232) (xy 256.319604 -208.87266) (xy 256.307347 -208.891668) (xy 256.305304 -208.902808)
			(xy 256.301118 -208.930327) (xy 256.285802 -208.983841) (xy 256.262861 -209.034556) (xy 256.232784 -209.081392)
			(xy 256.21488 -209.102706) (xy 256.214626 -209.10296) (xy 256.209041 -209.110048) (xy 256.202795 -209.126964)
			(xy 256.202434 -209.13598) (xy 256.202434 -209.203036) (xy 256.202766 -209.212056) (xy 256.20903 -209.228973)
			(xy 256.214626 -209.236056) (xy 256.21488 -209.23631) (xy 256.234725 -209.260008) (xy 256.267293 -209.31254)
			(xy 256.290963 -209.369637) (xy 256.305115 -209.429803) (xy 256.307844 -209.460592) (xy 256.30938 -209.472582)
			(xy 256.321836 -209.493258) (xy 256.33172 -209.500216) (xy 256.364239 -209.521145) (xy 256.42536 -209.568528)
			(xy 256.481378 -209.621847) (xy 256.531721 -209.680555) (xy 256.575872 -209.74405) (xy 256.613379 -209.811682)
			(xy 256.643858 -209.88276) (xy 256.666996 -209.956553) (xy 256.682558 -210.032308) (xy 256.690383 -210.109248)
			(xy 256.690876 -210.147916) (xy 256.690276 -210.190606) (xy 256.680712 -210.275449) (xy 256.661749 -210.358697)
			(xy 256.633624 -210.439312) (xy 256.596687 -210.516289) (xy 256.574544 -210.552792) (xy 256.569833 -210.561046)
			(xy 256.566327 -210.579714) (xy 256.569843 -210.598379) (xy 256.574544 -210.60664) (xy 256.596707 -210.643132)
			(xy 256.63365 -210.720108) (xy 256.661773 -210.800726) (xy 256.680727 -210.883978) (xy 256.690274 -210.968825)
			(xy 256.690876 -211.011516) (xy 256.690429 -211.050188) (xy 256.682617 -211.127135) (xy 256.667064 -211.202899)
			(xy 256.643929 -211.276701) (xy 256.613451 -211.347786) (xy 256.575941 -211.415425) (xy 256.531783 -211.478923)
			(xy 256.481431 -211.537632) (xy 256.425401 -211.590948) (xy 256.364267 -211.638325) (xy 256.33172 -211.659216)
			(xy 256.321793 -211.666129) (xy 256.309342 -211.686834) (xy 256.307844 -211.69884) (xy 256.305115 -211.729627)
			(xy 256.290934 -211.789784) (xy 256.267263 -211.846877) (xy 256.234718 -211.89942) (xy 256.21488 -211.923122)
			(xy 256.214626 -211.923376) (xy 256.209035 -211.930459) (xy 256.202793 -211.947379) (xy 256.202434 -211.956396)
			(xy 256.202434 -212.023452) (xy 256.202807 -212.032467) (xy 256.209043 -212.049385) (xy 256.214626 -212.056472)
			(xy 256.21488 -212.056726) (xy 256.232772 -212.078047) (xy 256.262819 -212.124897) (xy 256.285756 -212.175609)
			(xy 256.301097 -212.22911) (xy 256.305304 -212.256624) (xy 256.307423 -212.267732) (xy 256.319667 -212.286709)
			(xy 256.328926 -212.2932) (xy 256.361699 -212.314024) (xy 256.423267 -212.361345) (xy 256.479711 -212.414674)
			(xy 256.530448 -212.473459) (xy 256.574953 -212.537093) (xy 256.612766 -212.604916) (xy 256.643496 -212.67623)
			(xy 256.666826 -212.750295) (xy 256.682513 -212.826346) (xy 256.690396 -212.903598) (xy 256.690876 -212.942424)
			(xy 256.69028 -212.985114) (xy 256.680715 -213.069957) (xy 256.661751 -213.153205) (xy 256.633625 -213.23382)
			(xy 256.596688 -213.310797) (xy 256.574544 -213.3473) (xy 256.569827 -213.355551) (xy 256.566323 -213.374221)
			(xy 256.569842 -213.392887) (xy 256.574544 -213.401148) (xy 256.59671 -213.437638) (xy 256.633653 -213.514615)
			(xy 256.661776 -213.595233) (xy 256.680728 -213.678486) (xy 256.690274 -213.763333) (xy 256.690876 -213.806024)
			(xy 256.690343 -213.844848) (xy 256.682458 -213.922095) (xy 256.66677 -213.998142) (xy 256.643443 -214.072204)
			(xy 256.612718 -214.143515) (xy 256.574911 -214.211338) (xy 256.530414 -214.274972) (xy 256.479686 -214.333759)
			(xy 256.423252 -214.387093) (xy 256.361695 -214.434422) (xy 256.328926 -214.455248) (xy 256.319635 -214.461715)
			(xy 256.307362 -214.480695) (xy 256.305304 -214.491824) (xy 256.30118 -214.518953) (xy 256.286161 -214.57173)
			(xy 256.263737 -214.621812) (xy 256.234371 -214.668166) (xy 256.198668 -214.709835) (xy 256.157365 -214.745962)
			(xy 256.111313 -214.775799) (xy 256.061463 -214.798733) (xy 256.008842 -214.81429) (xy 255.954534 -214.82215)
			(xy 255.899662 -214.82215) (xy 255.845354 -214.81429) (xy 255.792733 -214.798733) (xy 255.742883 -214.775799)
			(xy 255.696831 -214.745962) (xy 255.655528 -214.709835) (xy 255.619825 -214.668166) (xy 255.590459 -214.621812)
			(xy 255.568035 -214.57173) (xy 255.553016 -214.518953) (xy 255.548892 -214.491824) (xy 255.5468 -214.480709)
			(xy 255.534536 -214.461735) (xy 255.52527 -214.455248) (xy 255.492518 -214.434392) (xy 255.43095 -214.387074)
			(xy 255.374505 -214.333749) (xy 255.323768 -214.274968) (xy 255.279261 -214.211338) (xy 255.241446 -214.143518)
			(xy 255.210713 -214.072208) (xy 255.187381 -213.998146) (xy 255.17169 -213.922098) (xy 255.163802 -213.844849)
			(xy 255.16332 -213.806024) (xy 207.391 -213.806024) (xy 207.391 -219.46616) (xy 207.414368 -219.494354)
			(xy 207.432656 -219.497656) (xy 207.459062 -219.503101) (xy 207.510083 -219.520514) (xy 207.558026 -219.54517)
			(xy 207.601868 -219.576543) (xy 207.640676 -219.613964) (xy 207.673623 -219.656637) (xy 207.700006 -219.703651)
			(xy 207.719263 -219.754005) (xy 207.730985 -219.806627) (xy 207.73492 -219.860394) (xy 207.730986 -219.914162)
			(xy 207.719267 -219.966783) (xy 207.700011 -220.017138) (xy 207.673629 -220.064154) (xy 207.640684 -220.106827)
			(xy 207.601877 -220.14425) (xy 207.558036 -220.175624) (xy 207.510094 -220.200281) (xy 207.459073 -220.217696)
			(xy 207.432656 -220.22308) (xy 207.414368 -220.226382) (xy 207.391 -220.254576) (xy 207.391 -228.816154)
			(xy 207.414368 -228.844348) (xy 207.432656 -228.84765) (xy 207.459059 -228.853107) (xy 207.51008 -228.870519)
			(xy 207.558022 -228.895175) (xy 207.601864 -228.926547) (xy 207.640671 -228.963967) (xy 207.673617 -229.006639)
			(xy 207.7 -229.053653) (xy 207.719257 -229.104006) (xy 207.730979 -229.156627) (xy 207.734915 -229.210393)
			(xy 207.730981 -229.26416) (xy 207.719261 -229.316781) (xy 207.700006 -229.367135) (xy 207.673625 -229.414149)
			(xy 207.64068 -229.456822) (xy 207.601874 -229.494244) (xy 207.558034 -229.525618) (xy 207.510093 -229.550275)
			(xy 207.459073 -229.56769) (xy 207.432656 -229.573074) (xy 207.414368 -229.576376) (xy 207.391 -229.60457)
			(xy 207.391 -238.166148) (xy 207.414368 -238.194342) (xy 207.432656 -238.197644) (xy 207.459057 -238.203112)
			(xy 207.510077 -238.220524) (xy 207.558018 -238.245179) (xy 207.601859 -238.276551) (xy 207.640666 -238.31397)
			(xy 207.673612 -238.356641) (xy 207.699994 -238.403654) (xy 207.719251 -238.454007) (xy 207.730973 -238.506626)
			(xy 207.734909 -238.560392) (xy 207.730975 -238.614158) (xy 207.719256 -238.666778) (xy 207.700001 -238.717131)
			(xy 207.673621 -238.764145) (xy 207.640677 -238.806818) (xy 207.601871 -238.844239) (xy 207.558032 -238.875613)
			(xy 207.510091 -238.900269) (xy 207.459072 -238.917684) (xy 207.432656 -238.923068) (xy 207.414368 -238.92637)
			(xy 207.391 -238.954564) (xy 207.391 -275.566124) (xy 207.414368 -275.594318) (xy 207.432656 -275.59762)
			(xy 207.459089 -275.602943) (xy 207.510118 -275.620361) (xy 207.558069 -275.645023) (xy 207.601918 -275.676402)
			(xy 207.640731 -275.713831) (xy 207.673682 -275.756512) (xy 207.700068 -275.803535) (xy 207.719327 -275.853898)
			(xy 207.731049 -275.906529) (xy 207.734983 -275.960306) (xy 207.731047 -276.014082) (xy 207.719324 -276.066713)
			(xy 207.700063 -276.117076) (xy 207.673675 -276.164098) (xy 207.640723 -276.206778) (xy 207.601909 -276.244205)
			(xy 207.558059 -276.275584) (xy 207.510108 -276.300243) (xy 207.459078 -276.31766) (xy 207.432656 -276.323044)
			(xy 207.414368 -276.326346) (xy 207.391 -276.35454) (xy 207.391 -284.916118) (xy 207.414368 -284.944312)
			(xy 207.432656 -284.947614) (xy 207.459086 -284.952949) (xy 207.510115 -284.970366) (xy 207.558065 -284.995027)
			(xy 207.601913 -285.026406) (xy 207.640726 -285.063834) (xy 207.673676 -285.106514) (xy 207.700062 -285.153536)
			(xy 207.719321 -285.203899) (xy 207.731043 -285.256529) (xy 207.734977 -285.310305) (xy 207.731041 -285.36408)
			(xy 207.719318 -285.41671) (xy 207.700058 -285.467072) (xy 207.673671 -285.514094) (xy 207.64072 -285.556773)
			(xy 207.601906 -285.5942) (xy 207.558057 -285.625578) (xy 207.510106 -285.650238) (xy 207.459077 -285.667654)
			(xy 207.432656 -285.673038) (xy 207.414368 -285.67634) (xy 207.391 -285.704534) (xy 207.391 -294.266112)
			(xy 207.414368 -294.294306) (xy 207.432656 -294.297608) (xy 207.459084 -294.302954) (xy 207.510112 -294.320371)
			(xy 207.558061 -294.345031) (xy 207.601908 -294.37641) (xy 207.640721 -294.413837) (xy 207.673671 -294.456516)
			(xy 207.700056 -294.503538) (xy 207.719315 -294.5539) (xy 207.731037 -294.606529) (xy 207.734972 -294.660304)
			(xy 207.731036 -294.714078) (xy 207.719313 -294.766707) (xy 207.700053 -294.817069) (xy 207.673667 -294.86409)
			(xy 207.640716 -294.906768) (xy 207.601903 -294.944195) (xy 207.558054 -294.975572) (xy 207.510105 -295.000232)
			(xy 207.459077 -295.017648) (xy 207.432656 -295.023032) (xy 207.414368 -295.026334) (xy 207.391 -295.054528)
			(xy 207.391 -303.616106) (xy 207.414368 -303.6443) (xy 207.432656 -303.647602) (xy 207.459081 -303.652959)
			(xy 207.510109 -303.670376) (xy 207.558057 -303.695036) (xy 207.601904 -303.726414) (xy 207.640716 -303.76384)
			(xy 207.673665 -303.806519) (xy 207.70005 -303.853539) (xy 207.719309 -303.9039) (xy 207.731031 -303.956529)
			(xy 207.734966 -304.010303) (xy 207.73103 -304.064076) (xy 207.719308 -304.116704) (xy 207.700048 -304.167065)
			(xy 207.673662 -304.214086) (xy 207.640712 -304.256763) (xy 207.6019 -304.29419) (xy 207.558052 -304.325567)
			(xy 207.510104 -304.350226) (xy 207.459076 -304.367642) (xy 207.432656 -304.373026) (xy 207.414368 -304.376328)
			(xy 207.391 -304.404522) (xy 207.391 -312.9661) (xy 207.414368 -312.994294) (xy 207.432656 -312.997596)
			(xy 207.459079 -313.002965) (xy 207.510105 -313.020381) (xy 207.558053 -313.04504) (xy 207.601899 -313.076417)
			(xy 207.64071 -313.113843) (xy 207.67366 -313.156521) (xy 207.700045 -313.203541) (xy 207.719303 -313.253901)
			(xy 207.731025 -313.306528) (xy 207.73496 -313.360301) (xy 207.731024 -313.414075) (xy 207.719302 -313.466702)
			(xy 207.700043 -313.517062) (xy 207.673658 -313.564081) (xy 207.640709 -313.606759) (xy 207.601897 -313.644184)
			(xy 207.55805 -313.675561) (xy 207.510103 -313.70022) (xy 207.459076 -313.717636) (xy 207.432656 -313.72302)
			(xy 207.414368 -313.726322) (xy 207.391 -313.754516) (xy 207.391 -317.924749) (xy 262.863443 -317.924749)
			(xy 262.863443 -317.845855) (xy 262.871587 -317.767383) (xy 262.88779 -317.69017) (xy 262.911877 -317.615043)
			(xy 262.943591 -317.542804) (xy 262.982594 -317.474225) (xy 263.028468 -317.410039) (xy 263.080724 -317.350932)
			(xy 263.138802 -317.297535) (xy 263.202083 -317.25042) (xy 263.269889 -317.210089) (xy 263.341497 -317.176975)
			(xy 263.416141 -317.151429) (xy 263.493023 -317.133726) (xy 263.532112 -317.128398) (xy 263.551416 -317.126112)
			(xy 263.576816 -317.09741) (xy 263.576816 -197.575932) (xy 263.576435 -197.566311) (xy 263.569329 -197.548429)
			(xy 263.556141 -197.534418) (xy 263.547606 -197.529958) (xy 263.512372 -197.512737) (xy 263.445217 -197.472229)
			(xy 263.382574 -197.425043) (xy 263.325103 -197.371677) (xy 263.273413 -197.312696) (xy 263.228047 -197.248722)
			(xy 263.189486 -197.180431) (xy 263.158137 -197.108542) (xy 263.134331 -197.033817) (xy 263.118318 -196.957042)
			(xy 263.110268 -196.87903) (xy 263.110266 -196.800604) (xy 263.118312 -196.722591) (xy 263.134322 -196.645816)
			(xy 263.158125 -196.57109) (xy 263.189471 -196.4992) (xy 263.228029 -196.430906) (xy 263.273392 -196.36693)
			(xy 263.32508 -196.307947) (xy 263.382548 -196.254579) (xy 263.445189 -196.20739) (xy 263.512342 -196.166879)
			(xy 263.547606 -196.149722) (xy 263.556167 -196.14531) (xy 263.569339 -196.131275) (xy 263.576413 -196.113373)
			(xy 263.576816 -196.103748) (xy 263.576816 -195.151248) (xy 263.576308 -195.151502) (xy 263.576308 -183.39562)
			(xy 263.576742 -183.385552) (xy 263.584456 -183.366954) (xy 263.591294 -183.359552) (xy 265.956288 -180.994558)
			(xy 265.963693 -180.987725) (xy 265.982289 -180.980002) (xy 265.992356 -180.979572) (xy 291.681916 -180.979572)
			(xy 291.691987 -180.979162) (xy 291.710585 -180.971431) (xy 291.717984 -180.964586) (xy 296.282618 -176.400206)
			(xy 296.28945 -176.3928) (xy 296.297174 -176.374205) (xy 296.297604 -176.364138) (xy 296.297604 -145.846546)
			(xy 296.298026 -145.836476) (xy 296.305746 -145.817876) (xy 296.31259 -145.810478) (xy 307.646832 -134.475982)
			(xy 307.654225 -134.469133) (xy 307.67283 -134.461419) (xy 307.6829 -134.460996) (xy 329.5904 -134.460996)
			(xy 329.599333 -134.460712) (xy 329.616131 -134.454627) (xy 329.629829 -134.443158) (xy 329.634596 -134.435596)
			(xy 329.649308 -134.411077) (xy 329.684921 -134.366342) (xy 329.726809 -134.32742) (xy 329.774034 -134.295184)
			(xy 329.82554 -134.270353) (xy 329.880175 -134.253483) (xy 329.936714 -134.244953) (xy 329.993894 -134.244953)
			(xy 330.050433 -134.253483) (xy 330.105068 -134.270353) (xy 330.156574 -134.295184) (xy 330.203799 -134.32742)
			(xy 330.245687 -134.366342) (xy 330.2813 -134.411077) (xy 330.296012 -134.435596) (xy 330.300771 -134.443165)
			(xy 330.314463 -134.454644) (xy 330.331272 -134.4607) (xy 330.340208 -134.460996) (xy 330.733146 -134.460996)
			(xy 330.74276 -134.460586) (xy 330.76065 -134.453554) (xy 330.767944 -134.44728) (xy 330.789304 -134.427895)
			(xy 330.836772 -134.395125) (xy 330.888631 -134.369872) (xy 330.9437 -134.35271) (xy 331.000724 -134.34403)
			(xy 331.058404 -134.34403) (xy 331.115428 -134.35271) (xy 331.170497 -134.369872) (xy 331.222356 -134.395125)
			(xy 331.269824 -134.427895) (xy 331.291184 -134.44728) (xy 331.298504 -134.453516) (xy 331.316376 -134.460575)
			(xy 331.325982 -134.460996) (xy 344.944446 -134.460996) (xy 344.954516 -134.461424) (xy 344.973115 -134.46914)
			(xy 344.980514 -134.475982) (xy 361.352846 -150.848568) (xy 361.359613 -150.856019) (xy 361.367329 -150.874584)
			(xy 361.367832 -150.884636) (xy 361.367832 -152.648412) (xy 361.367578 -152.648412) (xy 361.367578 -152.776428)
			(xy 361.367832 -152.776428) (xy 361.367832 -154.367992) (xy 361.368253 -154.378062) (xy 361.375976 -154.39666)
			(xy 361.382818 -154.40406) (xy 365.527844 -158.549086) (xy 365.535236 -158.555936) (xy 365.553841 -158.56365)
			(xy 365.563912 -158.564072) (xy 380.58979 -158.564072) (xy 380.59986 -158.563649) (xy 380.618458 -158.555927)
			(xy 380.625858 -158.549086) (xy 386.45211 -152.723088) (xy 388.152132 -151.022558) (xy 388.159522 -151.015706)
			(xy 388.178129 -151.007994) (xy 388.1882 -151.007572) (xy 424.751246 -151.007572) (xy 424.761315 -151.008007)
			(xy 424.779914 -151.015719) (xy 424.787314 -151.022558) (xy 425.835826 -152.071324) (xy 425.870878 -152.075388)
			(xy 425.886118 -152.065736) (xy 425.909032 -152.051909) (xy 425.957886 -152.03006) (xy 426.009314 -152.01525)
			(xy 426.062305 -152.007769) (xy 426.089064 -152.007316) (xy 426.116317 -152.007789) (xy 426.170269 -152.015542)
			(xy 426.222568 -152.030894) (xy 426.27215 -152.053534) (xy 426.318004 -152.083001) (xy 426.359198 -152.118694)
			(xy 426.394892 -152.159886) (xy 426.42436 -152.20574) (xy 426.447002 -152.255321) (xy 426.462356 -152.307619)
			(xy 426.47011 -152.361571) (xy 426.470572 -152.388824) (xy 426.47011 -152.415583) (xy 426.462634 -152.468576)
			(xy 426.447832 -152.520006) (xy 426.425994 -152.568865) (xy 426.412152 -152.59177) (xy 426.4025 -152.60701)
			(xy 426.406564 -152.642062) (xy 427.538896 -153.774394) (xy 436.382169 -153.774394) (xy 436.386165 -153.564508)
			(xy 436.39815 -153.354926) (xy 436.418104 -153.145952) (xy 436.446 -152.93789) (xy 436.481797 -152.73104)
			(xy 436.525442 -152.525703) (xy 436.576874 -152.322177) (xy 436.636016 -152.120756) (xy 436.702784 -151.921733)
			(xy 436.77708 -151.725396) (xy 436.858798 -151.53203) (xy 436.947817 -151.341915) (xy 437.04401 -151.155327)
			(xy 437.147237 -150.972536) (xy 437.257348 -150.793808) (xy 437.374183 -150.619401) (xy 437.497573 -150.449569)
			(xy 437.62734 -150.284557) (xy 437.763294 -150.124606) (xy 437.90524 -149.969946) (xy 438.05297 -149.820802)
			(xy 438.206272 -149.677391) (xy 438.364922 -149.53992) (xy 438.528691 -149.408588) (xy 438.697341 -149.283587)
			(xy 438.870627 -149.165096) (xy 439.048299 -149.053289) (xy 439.230099 -148.948327) (xy 439.415763 -148.850362)
			(xy 439.605021 -148.759537) (xy 439.797601 -148.675983) (xy 439.993222 -148.59982) (xy 440.1916 -148.531161)
			(xy 440.392449 -148.470104) (xy 440.595476 -148.416737) (xy 440.800389 -148.371139) (xy 441.006888 -148.333374)
			(xy 441.214675 -148.303499) (xy 441.42345 -148.281556) (xy 441.632908 -148.267577) (xy 441.842747 -148.261582)
			(xy 442.052661 -148.263581) (xy 442.262348 -148.273569) (xy 442.471502 -148.291534) (xy 442.67982 -148.317448)
			(xy 442.887001 -148.351273) (xy 443.092745 -148.392962) (xy 443.296751 -148.442454) (xy 443.498726 -148.499676)
			(xy 443.698376 -148.564546) (xy 443.895411 -148.63697) (xy 444.089547 -148.716843) (xy 444.2805 -148.804049)
			(xy 444.467996 -148.898461) (xy 444.651761 -148.999943) (xy 444.831529 -149.108347) (xy 445.00704 -149.223517)
			(xy 445.178039 -149.345285) (xy 445.344279 -149.473474) (xy 445.505518 -149.6079) (xy 445.661522 -149.748367)
			(xy 445.812065 -149.894671) (xy 445.956929 -150.0466) (xy 446.095904 -150.203934) (xy 446.228789 -150.366445)
			(xy 446.35539 -150.533898) (xy 446.475525 -150.706048) (xy 446.589019 -150.882648) (xy 446.695707 -151.06344)
			(xy 446.795434 -151.248163) (xy 446.888057 -151.436549) (xy 446.973441 -151.628324) (xy 447.051462 -151.823211)
			(xy 447.122007 -152.020927) (xy 447.184974 -152.221185) (xy 447.240271 -152.423695) (xy 447.287818 -152.628164)
			(xy 447.327546 -152.834295) (xy 447.359398 -153.041788) (xy 447.383328 -153.250344) (xy 447.3993 -153.45966)
			(xy 447.407292 -153.669432) (xy 447.407792 -153.774394) (xy 447.407292 -153.879356) (xy 447.3993 -154.089128)
			(xy 447.383328 -154.298444) (xy 447.359398 -154.507) (xy 447.327546 -154.714493) (xy 447.287818 -154.920624)
			(xy 447.240271 -155.125093) (xy 447.184974 -155.327603) (xy 447.122007 -155.527861) (xy 447.051462 -155.725577)
			(xy 446.973441 -155.920464) (xy 446.888057 -156.112239) (xy 446.795434 -156.300625) (xy 446.695707 -156.485348)
			(xy 446.589019 -156.66614) (xy 446.475525 -156.84274) (xy 446.35539 -157.01489) (xy 446.228789 -157.182343)
			(xy 446.095904 -157.344854) (xy 445.956929 -157.502188) (xy 445.812065 -157.654117) (xy 445.661522 -157.800421)
			(xy 445.505518 -157.940888) (xy 445.344279 -158.075314) (xy 445.178039 -158.203503) (xy 445.00704 -158.325271)
			(xy 444.831529 -158.440441) (xy 444.651761 -158.548845) (xy 444.467996 -158.650327) (xy 444.2805 -158.744739)
			(xy 444.089547 -158.831945) (xy 443.895411 -158.911818) (xy 443.698376 -158.984242) (xy 443.498726 -159.049112)
			(xy 443.296751 -159.106334) (xy 443.092745 -159.155826) (xy 442.887001 -159.197515) (xy 442.67982 -159.23134)
			(xy 442.471502 -159.257254) (xy 442.262348 -159.275219) (xy 442.052661 -159.285207) (xy 441.842747 -159.287206)
			(xy 441.632908 -159.281211) (xy 441.42345 -159.267232) (xy 441.214675 -159.245289) (xy 441.006888 -159.215414)
			(xy 440.800389 -159.177649) (xy 440.595476 -159.132051) (xy 440.392449 -159.078684) (xy 440.1916 -159.017627)
			(xy 439.993222 -158.948968) (xy 439.797601 -158.872805) (xy 439.605021 -158.789251) (xy 439.415763 -158.698426)
			(xy 439.230099 -158.600461) (xy 439.048299 -158.495499) (xy 438.870627 -158.383692) (xy 438.697341 -158.265201)
			(xy 438.528691 -158.1402) (xy 438.364922 -158.008868) (xy 438.206272 -157.871397) (xy 438.05297 -157.727986)
			(xy 437.90524 -157.578842) (xy 437.763294 -157.424182) (xy 437.62734 -157.264231) (xy 437.497573 -157.099219)
			(xy 437.374183 -156.929387) (xy 437.257348 -156.75498) (xy 437.147237 -156.576252) (xy 437.04401 -156.393461)
			(xy 436.947817 -156.206873) (xy 436.858798 -156.016758) (xy 436.77708 -155.823392) (xy 436.702784 -155.627055)
			(xy 436.636016 -155.428032) (xy 436.576874 -155.226611) (xy 436.525442 -155.023085) (xy 436.481797 -154.817748)
			(xy 436.446 -154.610898) (xy 436.418104 -154.402836) (xy 436.39815 -154.193862) (xy 436.386165 -153.98428)
			(xy 436.382169 -153.774394) (xy 427.538896 -153.774394) (xy 439.922666 -166.158164) (xy 439.929444 -166.164386)
			(xy 439.946205 -166.171949) (xy 439.964553 -166.173152) (xy 439.973466 -166.170864) (xy 440.009129 -166.1606)
			(xy 440.081947 -166.146254) (xy 440.155813 -166.139048) (xy 440.192922 -166.138606) (xy 440.232857 -166.139094)
			(xy 440.312289 -166.147445) (xy 440.390413 -166.164053) (xy 440.466373 -166.188736) (xy 440.539336 -166.221224)
			(xy 440.608504 -166.26116) (xy 440.673119 -166.308108) (xy 440.732473 -166.361553) (xy 440.785915 -166.420909)
			(xy 440.832859 -166.485526) (xy 440.872793 -166.554696) (xy 440.905277 -166.627661) (xy 440.929957 -166.703622)
			(xy 440.946561 -166.781747) (xy 440.954908 -166.861179) (xy 440.95543 -166.901114) (xy 440.954978 -166.938222)
			(xy 440.947774 -167.012088) (xy 440.933426 -167.084904) (xy 440.923172 -167.12057) (xy 440.920805 -167.129476)
			(xy 440.921971 -167.147854) (xy 440.929605 -167.164612) (xy 440.935872 -167.17137) (xy 442.869828 -169.105326)
			(xy 442.90615 -169.108628) (xy 442.92139 -169.098214) (xy 442.95319 -169.076981) (xy 443.020249 -169.040232)
			(xy 443.090649 -169.010379) (xy 443.163683 -168.987722) (xy 443.238618 -168.972487) (xy 443.314702 -168.964828)
			(xy 443.352936 -168.964356) (xy 443.392869 -168.964881) (xy 443.472298 -168.973232) (xy 443.550419 -168.98984)
			(xy 443.626377 -169.014522) (xy 443.699338 -169.047009) (xy 443.768504 -169.086943) (xy 443.833117 -169.133889)
			(xy 443.89247 -169.18733) (xy 443.945911 -169.246683) (xy 443.992857 -169.311296) (xy 444.032791 -169.380462)
			(xy 444.065278 -169.453423) (xy 444.08996 -169.529381) (xy 444.106568 -169.607502) (xy 444.114919 -169.686931)
			(xy 444.115444 -169.726864) (xy 444.114956 -169.765078) (xy 444.107306 -169.841123) (xy 444.092078 -169.91602)
			(xy 444.069427 -169.989014) (xy 444.039579 -170.059374) (xy 444.002835 -170.12639) (xy 443.981586 -170.158156)
			(xy 443.975399 -170.168268) (xy 443.972136 -170.191719) (xy 443.979712 -170.214151) (xy 443.987682 -170.222926)
			(xy 456.158854 -182.394352) (xy 456.165659 -182.40178) (xy 456.173401 -182.420358) (xy 456.17384 -182.43042)
			(xy 456.17384 -195.108068) (xy 456.173496 -195.118116) (xy 456.165891 -195.136713) (xy 456.159108 -195.144136)
			(xy 456.036172 -195.266818) (xy 456.029227 -195.274497) (xy 456.021562 -195.293705) (xy 456.022115 -195.314378)
			(xy 456.026012 -195.323968) (xy 456.042163 -195.360657) (xy 456.067438 -195.436736) (xy 456.084461 -195.515074)
			(xy 456.093039 -195.594781) (xy 456.093576 -195.634864) (xy 456.093576 -195.635118) (xy 456.093129 -195.674389)
			(xy 456.084917 -195.752501) (xy 456.068585 -195.829327) (xy 456.044312 -195.904024) (xy 456.012364 -195.975775)
			(xy 455.973091 -196.043794) (xy 455.926923 -196.107334) (xy 455.874366 -196.165701) (xy 455.815995 -196.218254)
			(xy 455.752452 -196.264418) (xy 455.684431 -196.303687) (xy 455.612677 -196.33563) (xy 455.537978 -196.359898)
			(xy 455.461152 -196.376225) (xy 455.383039 -196.384431) (xy 455.343768 -196.384926) (xy 455.304393 -196.384472)
			(xy 455.226077 -196.376212) (xy 455.149059 -196.359787) (xy 455.074187 -196.335379) (xy 455.002287 -196.303255)
			(xy 454.934151 -196.26377) (xy 454.87053 -196.217359) (xy 454.812125 -196.164534) (xy 454.75958 -196.105877)
			(xy 454.713475 -196.042034) (xy 454.674317 -195.97371) (xy 454.657968 -195.937886) (xy 454.653624 -195.929078)
			(xy 454.6395 -195.915449) (xy 454.6213 -195.908103) (xy 454.611486 -195.90766) (xy 448.53225 -195.90766)
			(xy 448.522437 -195.90808) (xy 448.504242 -195.915437) (xy 448.490146 -195.929092) (xy 448.485768 -195.937886)
			(xy 448.469409 -195.973698) (xy 448.430235 -196.041999) (xy 448.384117 -196.105817) (xy 448.331565 -196.16445)
			(xy 448.273157 -196.217252) (xy 448.209536 -196.263641) (xy 448.141404 -196.303107) (xy 448.06951 -196.335214)
			(xy 447.994648 -196.359609) (xy 447.91764 -196.376024) (xy 447.839337 -196.384276) (xy 447.760599 -196.384276)
			(xy 447.682296 -196.376024) (xy 447.605288 -196.359609) (xy 447.530426 -196.335214) (xy 447.458532 -196.303107)
			(xy 447.3904 -196.263641) (xy 447.326779 -196.217252) (xy 447.268371 -196.16445) (xy 447.215819 -196.105817)
			(xy 447.169701 -196.041999) (xy 447.130527 -195.973698) (xy 447.114168 -195.937886) (xy 447.109824 -195.929078)
			(xy 447.0957 -195.915449) (xy 447.0775 -195.908103) (xy 447.067686 -195.90766) (xy 446.276222 -195.90766)
			(xy 446.24752 -195.93306) (xy 446.245234 -195.952364) (xy 446.239987 -195.991517) (xy 446.222428 -196.068542)
			(xy 446.196998 -196.143337) (xy 446.16397 -196.215103) (xy 446.123698 -196.283068) (xy 446.076615 -196.346505)
			(xy 446.023224 -196.404733) (xy 445.964099 -196.457128) (xy 445.899873 -196.503129) (xy 445.831234 -196.542241)
			(xy 445.758919 -196.574047) (xy 445.683702 -196.598204) (xy 445.606391 -196.614455) (xy 445.527814 -196.622624)
			(xy 445.448814 -196.622624) (xy 445.370237 -196.614455) (xy 445.292926 -196.598204) (xy 445.217709 -196.574047)
			(xy 445.145394 -196.542241) (xy 445.076755 -196.503129) (xy 445.012529 -196.457128) (xy 444.953404 -196.404733)
			(xy 444.900013 -196.346505) (xy 444.85293 -196.283068) (xy 444.812658 -196.215103) (xy 444.77963 -196.143337)
			(xy 444.7542 -196.068542) (xy 444.736641 -195.991517) (xy 444.731394 -195.952364) (xy 444.729108 -195.93306)
			(xy 444.700406 -195.90766) (xy 440.988196 -195.90766) (xy 440.978386 -195.908113) (xy 440.960193 -195.915454)
			(xy 440.946094 -195.929097) (xy 440.941714 -195.937886) (xy 440.925355 -195.973698) (xy 440.886181 -196.041999)
			(xy 440.840063 -196.105817) (xy 440.787511 -196.16445) (xy 440.729103 -196.217252) (xy 440.665482 -196.263641)
			(xy 440.59735 -196.303107) (xy 440.525456 -196.335214) (xy 440.450594 -196.359609) (xy 440.373586 -196.376024)
			(xy 440.295283 -196.384276) (xy 440.216545 -196.384276) (xy 440.138242 -196.376024) (xy 440.061234 -196.359609)
			(xy 439.986372 -196.335214) (xy 439.914478 -196.303107) (xy 439.846346 -196.263641) (xy 439.782725 -196.217252)
			(xy 439.724317 -196.16445) (xy 439.671765 -196.105817) (xy 439.625647 -196.041999) (xy 439.586473 -195.973698)
			(xy 439.570114 -195.937886) (xy 439.565737 -195.929097) (xy 439.551627 -195.915467) (xy 439.533441 -195.908111)
			(xy 439.523632 -195.90766) (xy 438.751726 -195.90766) (xy 438.742506 -195.908053) (xy 438.72525 -195.914556)
			(xy 438.711401 -195.926733) (xy 438.702745 -195.943015) (xy 438.70118 -195.95211) (xy 438.70118 -195.952364)
			(xy 438.695876 -195.991458) (xy 438.678218 -196.068355) (xy 438.652712 -196.143017) (xy 438.619632 -196.214645)
			(xy 438.579331 -196.282473) (xy 438.532239 -196.345777) (xy 438.478862 -196.403878) (xy 438.419768 -196.456155)
			(xy 438.355592 -196.502049) (xy 438.287019 -196.54107) (xy 438.214782 -196.572799) (xy 438.139654 -196.596898)
			(xy 438.062439 -196.613109) (xy 437.983963 -196.621258) (xy 437.905065 -196.621258) (xy 437.826589 -196.613109)
			(xy 437.749374 -196.596898) (xy 437.674246 -196.572799) (xy 437.602009 -196.54107) (xy 437.533436 -196.502049)
			(xy 437.46926 -196.456155) (xy 437.410166 -196.403878) (xy 437.356789 -196.345777) (xy 437.309697 -196.282473)
			(xy 437.269396 -196.214645) (xy 437.236316 -196.143017) (xy 437.21081 -196.068355) (xy 437.193152 -195.991458)
			(xy 437.187848 -195.952364) (xy 437.187848 -195.95211) (xy 437.186262 -195.943007) (xy 437.177664 -195.926678)
			(xy 437.163816 -195.914479) (xy 437.146532 -195.90801) (xy 437.137302 -195.90766) (xy 433.444142 -195.90766)
			(xy 433.434328 -195.908073) (xy 433.416133 -195.915434) (xy 433.402037 -195.929091) (xy 433.39766 -195.937886)
			(xy 433.381301 -195.973698) (xy 433.342127 -196.041999) (xy 433.296009 -196.105817) (xy 433.243457 -196.16445)
			(xy 433.185049 -196.217252) (xy 433.121428 -196.263641) (xy 433.053296 -196.303107) (xy 432.981402 -196.335214)
			(xy 432.90654 -196.359609) (xy 432.829532 -196.376024) (xy 432.751229 -196.384276) (xy 432.672491 -196.384276)
			(xy 432.594188 -196.376024) (xy 432.51718 -196.359609) (xy 432.442318 -196.335214) (xy 432.370424 -196.303107)
			(xy 432.302292 -196.263641) (xy 432.238671 -196.217252) (xy 432.180263 -196.16445) (xy 432.127711 -196.105817)
			(xy 432.081593 -196.041999) (xy 432.042419 -195.973698) (xy 432.02606 -195.937886) (xy 432.021651 -195.929116)
			(xy 432.007555 -195.915485) (xy 431.989382 -195.908119) (xy 431.979578 -195.90766) (xy 431.206402 -195.90766)
			(xy 431.197264 -195.908038) (xy 431.180158 -195.914479) (xy 431.166397 -195.926508) (xy 431.157726 -195.942599)
			(xy 431.15611 -195.951602) (xy 431.15611 -195.951856) (xy 431.150411 -195.990592) (xy 431.132104 -196.066722)
			(xy 431.106089 -196.140574) (xy 431.072643 -196.211371) (xy 431.032115 -196.278366) (xy 430.984935 -196.340856)
			(xy 430.931598 -196.39818) (xy 430.872667 -196.449735) (xy 430.808761 -196.494979) (xy 430.740555 -196.533434)
			(xy 430.668767 -196.564696) (xy 430.594152 -196.588435) (xy 430.517498 -196.604401) (xy 430.43961 -196.612427)
			(xy 430.36131 -196.612427) (xy 430.283422 -196.604401) (xy 430.206768 -196.588435) (xy 430.132153 -196.564696)
			(xy 430.060365 -196.533434) (xy 429.992159 -196.494979) (xy 429.928253 -196.449735) (xy 429.869322 -196.39818)
			(xy 429.815985 -196.340856) (xy 429.768805 -196.278366) (xy 429.728277 -196.211371) (xy 429.694831 -196.140574)
			(xy 429.668816 -196.066722) (xy 429.650509 -195.990592) (xy 429.64481 -195.951856) (xy 429.64481 -195.951602)
			(xy 429.643272 -195.942578) (xy 429.634596 -195.926467) (xy 429.620807 -195.914439) (xy 429.603668 -195.90803)
			(xy 429.594518 -195.90766) (xy 426.304456 -195.90766) (xy 426.294382 -195.908047) (xy 426.275784 -195.915793)
			(xy 426.268388 -195.922646) (xy 426.043598 -196.14769) (xy 426.02023 -196.168518) (xy 426.011453 -196.176064)
			(xy 426.001281 -196.196835) (xy 426.000672 -196.208396) (xy 426.000672 -266.372594) (xy 426.000281 -266.382637)
			(xy 425.992707 -266.401233) (xy 425.98594 -266.408662) (xy 425.925996 -266.468606) (xy 425.920154 -266.498578)
			(xy 425.925996 -266.512802) (xy 425.930358 -266.521808) (xy 425.944528 -266.535901) (xy 425.962994 -266.543544)
			(xy 425.972986 -266.544044) (xy 426.866304 -266.544044) (xy 426.876934 -266.543615) (xy 426.896397 -266.535078)
			(xy 426.903896 -266.527534) (xy 426.930499 -266.499313) (xy 426.988606 -266.447938) (xy 427.051706 -266.402838)
			(xy 427.119126 -266.364493) (xy 427.190144 -266.333315) (xy 427.264002 -266.309636) (xy 427.339911 -266.293709)
			(xy 427.417057 -266.285705) (xy 427.455838 -266.285218) (xy 427.456346 -266.285218) (xy 427.495126 -266.285715)
			(xy 427.57227 -266.293725) (xy 427.648176 -266.309656) (xy 427.722032 -266.333336) (xy 427.793049 -266.364514)
			(xy 427.860468 -266.402855) (xy 427.92357 -266.44795) (xy 427.98168 -266.499319) (xy 428.008288 -266.527534)
			(xy 428.015874 -266.534959) (xy 428.035281 -266.543496) (xy 428.04588 -266.544044) (xy 434.410358 -266.544044)
			(xy 434.420991 -266.543645) (xy 434.440454 -266.535087) (xy 434.44795 -266.527534) (xy 434.474576 -266.499335)
			(xy 434.532679 -266.447959) (xy 434.595776 -266.402857) (xy 434.663192 -266.36451) (xy 434.734207 -266.333329)
			(xy 434.808062 -266.309646) (xy 434.883968 -266.293715) (xy 434.961112 -266.285707) (xy 434.999892 -266.285218)
			(xy 435.0004 -266.285218) (xy 435.039181 -266.285678) (xy 435.116326 -266.293694) (xy 435.192233 -266.30963)
			(xy 435.266089 -266.333315) (xy 435.337106 -266.364498) (xy 435.404525 -266.402844) (xy 435.467626 -266.447944)
			(xy 435.525735 -266.499317) (xy 435.552342 -266.527534) (xy 435.559908 -266.534983) (xy 435.57933 -266.543506)
			(xy 435.589934 -266.544044) (xy 439.43397 -266.544044) (xy 439.444039 -266.544474) (xy 439.462638 -266.55219)
			(xy 439.470038 -266.55903) (xy 441.080906 -268.170152) (xy 441.087718 -268.177574) (xy 441.095454 -268.196156)
			(xy 441.095892 -268.20622) (xy 441.095892 -340.458552) (xy 441.095638 -340.45906) (xy 441.095638 -346.105734)
			(xy 441.09894 -346.11437) (xy 441.110088 -346.146508) (xy 441.122095 -346.213457) (xy 441.122816 -346.247466)
			(xy 441.122098 -346.281475) (xy 441.110085 -346.348423) (xy 441.09894 -346.380562) (xy 441.095638 -346.389198)
			(xy 441.095638 -346.740734) (xy 441.09894 -346.74937) (xy 441.110088 -346.781508) (xy 441.122095 -346.848457)
			(xy 441.122816 -346.882466) (xy 441.122098 -346.916475) (xy 441.110085 -346.983423) (xy 441.09894 -347.015562)
			(xy 441.095638 -347.024198) (xy 441.095638 -347.401134) (xy 441.09894 -347.40977) (xy 441.110088 -347.441908)
			(xy 441.122095 -347.508857) (xy 441.122816 -347.542866) (xy 441.122098 -347.576875) (xy 441.110085 -347.643823)
			(xy 441.09894 -347.675962) (xy 441.095638 -347.684598) (xy 441.095638 -355.03231) (xy 441.095106 -355.057273)
			(xy 441.085366 -355.106238) (xy 441.066245 -355.152357) (xy 441.03848 -355.193849) (xy 441.021216 -355.211888)
			(xy 439.853578 -356.379526) (xy 439.835543 -356.39679) (xy 439.794039 -356.424529) (xy 439.747921 -356.443636)
			(xy 439.69896 -356.453377) (xy 439.674 -356.453948) (xy 432.09464 -356.453948) (xy 432.085866 -356.454263)
			(xy 432.069327 -356.460115) (xy 432.055761 -356.47124) (xy 432.050952 -356.478586) (xy 432.036064 -356.502377)
			(xy 432.000406 -356.545715) (xy 431.958782 -356.58336) (xy 431.912092 -356.6145) (xy 431.861343 -356.638463)
			(xy 431.807631 -356.654731) (xy 431.752115 -356.662954) (xy 431.695993 -356.662954) (xy 431.640477 -356.654731)
			(xy 431.586765 -356.638463) (xy 431.536016 -356.6145) (xy 431.489326 -356.58336) (xy 431.447702 -356.545715)
			(xy 431.412044 -356.502377) (xy 431.397156 -356.478586) (xy 431.392272 -356.471308) (xy 431.378708 -356.460234)
			(xy 431.362222 -356.454329) (xy 431.353468 -356.453948) (xy 428.489364 -356.453948) (xy 428.481409 -356.454273)
			(xy 428.466277 -356.459193) (xy 428.459646 -356.4636) (xy 428.43777 -356.479008) (xy 428.390568 -356.504207)
			(xy 428.340309 -356.522568) (xy 428.287978 -356.53373) (xy 428.234602 -356.537476) (xy 428.181226 -356.53373)
			(xy 428.128895 -356.522568) (xy 428.078636 -356.504207) (xy 428.031434 -356.479008) (xy 428.009558 -356.4636)
			(xy 428.002952 -356.459143) (xy 427.987804 -356.45422) (xy 427.97984 -356.453948) (xy 423.751248 -356.453948)
			(xy 423.738987 -356.454639) (xy 423.717216 -356.465912) (xy 423.709592 -356.475538) (xy 423.693026 -356.498304)
			(xy 423.654289 -356.539163) (xy 423.609963 -356.573878) (xy 423.561012 -356.601695) (xy 423.508502 -356.622008)
			(xy 423.453575 -356.634375) (xy 423.397426 -356.638528) (xy 423.341277 -356.634375) (xy 423.28635 -356.622008)
			(xy 423.23384 -356.601695) (xy 423.184889 -356.573878) (xy 423.140563 -356.539163) (xy 423.101826 -356.498304)
			(xy 423.08526 -356.475538) (xy 423.077601 -356.465952) (xy 423.055852 -356.454673) (xy 423.043604 -356.453948)
			(xy 420.672514 -356.453948) (xy 420.659908 -356.454587) (xy 420.63766 -356.466448) (xy 420.630096 -356.476554)
			(xy 420.614873 -356.49863) (xy 420.579222 -356.538685) (xy 420.538309 -356.573349) (xy 420.492944 -356.601939)
			(xy 420.444019 -356.62389) (xy 420.392502 -356.63877) (xy 420.339408 -356.646283) (xy 420.285784 -356.646283)
			(xy 420.23269 -356.63877) (xy 420.181173 -356.62389) (xy 420.132248 -356.601939) (xy 420.086883 -356.573349)
			(xy 420.04597 -356.538685) (xy 420.010319 -356.49863) (xy 419.995096 -356.476554) (xy 419.987551 -356.466422)
			(xy 419.965295 -356.454551) (xy 419.952678 -356.453948) (xy 315.03112 -356.453948) (xy 315.023622 -356.454201)
			(xy 315.009286 -356.458602) (xy 315.002926 -356.462584) (xy 314.97153 -356.483033) (xy 314.905452 -356.518364)
			(xy 314.836228 -356.547045) (xy 314.764525 -356.568802) (xy 314.691035 -356.583424) (xy 314.616465 -356.590771)
			(xy 314.541535 -356.590771) (xy 314.466965 -356.583424) (xy 314.393475 -356.568802) (xy 314.321772 -356.547045)
			(xy 314.252548 -356.518364) (xy 314.18647 -356.483033) (xy 314.155074 -356.462584) (xy 314.148695 -356.458647)
			(xy 314.13437 -356.454256) (xy 314.12688 -356.453948) (xy 305.761898 -356.453948) (xy 305.750784 -356.454484)
			(xy 305.730624 -356.463843) (xy 305.723036 -356.471982) (xy 305.704814 -356.4929) (xy 305.663356 -356.529762)
			(xy 305.616996 -356.56023) (xy 305.566712 -356.583662) (xy 305.513564 -356.599563) (xy 305.458674 -356.607599)
			(xy 305.403198 -356.607599) (xy 305.348308 -356.599563) (xy 305.29516 -356.583662) (xy 305.244876 -356.56023)
			(xy 305.198516 -356.529762) (xy 305.157058 -356.4929) (xy 305.138836 -356.471982) (xy 305.131217 -356.463882)
			(xy 305.111078 -356.454518) (xy 305.099974 -356.453948) (xy 303.763934 -356.453948) (xy 303.755743 -356.454282)
			(xy 303.740197 -356.459448) (xy 303.733454 -356.464108) (xy 303.702975 -356.486378) (xy 303.63839 -356.525463)
			(xy 303.57026 -356.557977) (xy 303.499252 -356.583601) (xy 303.426059 -356.602086) (xy 303.351398 -356.613249)
			(xy 303.276 -356.616983) (xy 303.200602 -356.613249) (xy 303.125941 -356.602086) (xy 303.052748 -356.583601)
			(xy 302.98174 -356.557977) (xy 302.91361 -356.525463) (xy 302.849025 -356.486378) (xy 302.818546 -356.464108)
			(xy 302.811817 -356.459421) (xy 302.796262 -356.454251) (xy 302.788066 -356.453948) (xy 289.90671 -356.453948)
			(xy 289.896529 -356.45446) (xy 289.87779 -356.462435) (xy 289.870388 -356.469442) (xy 289.812476 -356.528878)
			(xy 289.80511 -356.548182) (xy 289.805364 -356.558596) (xy 289.805872 -356.584758) (xy 289.805362 -356.625872)
			(xy 289.797778 -356.707749) (xy 289.782672 -356.788578) (xy 289.760173 -356.867667) (xy 289.730472 -356.944344)
			(xy 289.693822 -357.017952) (xy 289.650537 -357.087865) (xy 289.600986 -357.153486) (xy 289.545592 -357.214255)
			(xy 289.484826 -357.269653) (xy 289.419208 -357.319208) (xy 289.349298 -357.362497) (xy 289.275691 -357.399151)
			(xy 289.199017 -357.428856) (xy 289.119928 -357.45136) (xy 289.039101 -357.466471) (xy 288.957224 -357.474059)
			(xy 288.91611 -357.47452) (xy 288.87782 -357.474114) (xy 288.801526 -357.467506) (xy 288.726084 -357.454357)
			(xy 288.652053 -357.434764) (xy 288.615882 -357.422196) (xy 288.607445 -357.419545) (xy 288.589775 -357.419545)
			(xy 288.581338 -357.422196) (xy 288.54516 -357.434739) (xy 288.471127 -357.454312) (xy 288.395688 -357.46746)
			(xy 288.319398 -357.474084) (xy 288.28111 -357.47452) (xy 288.24282 -357.474114) (xy 288.166526 -357.467506)
			(xy 288.091084 -357.454357) (xy 288.017053 -357.434764) (xy 287.980882 -357.422196) (xy 287.972445 -357.419545)
			(xy 287.954775 -357.419545) (xy 287.946338 -357.422196) (xy 287.91016 -357.434739) (xy 287.836127 -357.454312)
			(xy 287.760688 -357.46746) (xy 287.684398 -357.474084) (xy 287.64611 -357.47452) (xy 287.60782 -357.474114)
			(xy 287.531526 -357.467506) (xy 287.456084 -357.454357) (xy 287.382053 -357.434764) (xy 287.345882 -357.422196)
			(xy 287.337445 -357.419545) (xy 287.319775 -357.419545) (xy 287.311338 -357.422196) (xy 287.27516 -357.434739)
			(xy 287.201127 -357.454312) (xy 287.125688 -357.46746) (xy 287.049398 -357.474084) (xy 287.01111 -357.47452)
			(xy 286.97282 -357.474114) (xy 286.896526 -357.467506) (xy 286.821084 -357.454357) (xy 286.747053 -357.434764)
			(xy 286.710882 -357.422196) (xy 286.702445 -357.419545) (xy 286.684775 -357.419545) (xy 286.676338 -357.422196)
			(xy 286.64016 -357.434739) (xy 286.566127 -357.454312) (xy 286.490688 -357.46746) (xy 286.414398 -357.474084)
			(xy 286.37611 -357.47452) (xy 286.334994 -357.474092) (xy 286.253113 -357.466505) (xy 286.172281 -357.451395)
			(xy 286.093188 -357.428892) (xy 286.016509 -357.399186) (xy 285.942899 -357.362532) (xy 285.872984 -357.319241)
			(xy 285.807362 -357.269685) (xy 285.746593 -357.214284) (xy 285.691195 -357.153513) (xy 285.641641 -357.08789)
			(xy 285.598353 -357.017973) (xy 285.561701 -356.944361) (xy 285.531998 -356.867681) (xy 285.509497 -356.788588)
			(xy 285.49439 -356.707755) (xy 285.486807 -356.625874) (xy 285.486348 -356.584758) (xy 285.486856 -356.558596)
			(xy 285.48711 -356.548182) (xy 285.479744 -356.528878) (xy 285.421832 -356.469442) (xy 285.414422 -356.462444)
			(xy 285.39569 -356.454454) (xy 285.38551 -356.453948) (xy 273.05 -356.453948) (xy 273.025038 -356.453407)
			(xy 272.976073 -356.44367) (xy 272.929955 -356.424551) (xy 272.888462 -356.396788) (xy 272.870422 -356.379526)
			(xy 270.915384 -354.424488) (xy 270.898141 -354.406437) (xy 270.870412 -354.364935) (xy 270.851312 -354.318821)
			(xy 270.841574 -354.269867) (xy 270.840962 -354.24491) (xy 270.840962 -335.792318) (xy 270.840565 -335.782293)
			(xy 270.832894 -335.763769) (xy 270.818714 -335.749595) (xy 270.800187 -335.741931) (xy 270.790162 -335.741518)
			(xy 264.10031 -335.741518) (xy 264.075348 -335.740979) (xy 264.026382 -335.731243) (xy 263.980263 -335.712124)
			(xy 263.938771 -335.684359) (xy 263.920732 -335.667096) (xy 263.651238 -335.397602) (xy 263.633979 -335.379563)
			(xy 263.606241 -335.33806) (xy 263.587133 -335.291942) (xy 263.57739 -335.242983) (xy 263.576816 -335.218024)
			(xy 263.576816 -325.421498) (xy 263.576291 -325.410572) (xy 263.567203 -325.390697) (xy 263.55929 -325.383144)
			(xy 263.528689 -325.356003) (xy 263.47288 -325.296199) (xy 263.423794 -325.230763) (xy 263.381996 -325.160449)
			(xy 263.347966 -325.086064) (xy 263.322095 -325.008464) (xy 263.30468 -324.928539) (xy 263.295922 -324.84721)
			(xy 263.295384 -324.80631) (xy 263.295923 -324.766346) (xy 263.304306 -324.686859) (xy 263.320951 -324.608683)
			(xy 263.345675 -324.532675) (xy 263.378207 -324.459668) (xy 263.397746 -324.424802) (xy 263.402005 -324.416656)
			(xy 263.404999 -324.398531) (xy 263.401468 -324.380504) (xy 263.396984 -324.372478) (xy 263.375107 -324.336189)
			(xy 263.338643 -324.259696) (xy 263.310888 -324.17963) (xy 263.292185 -324.09698) (xy 263.282764 -324.012766)
			(xy 263.282176 -323.970396) (xy 263.282659 -323.933144) (xy 263.289937 -323.858996) (xy 263.304413 -323.785911)
			(xy 263.32595 -323.714587) (xy 263.354341 -323.645705) (xy 263.389317 -323.57992) (xy 263.430542 -323.517861)
			(xy 263.477625 -323.460119) (xy 263.530116 -323.407246) (xy 263.558528 -323.383148) (xy 263.566762 -323.375534)
			(xy 263.57624 -323.355234) (xy 263.576816 -323.344032) (xy 263.576816 -318.673226) (xy 263.551416 -318.644524)
			(xy 263.532112 -318.642238) (xy 263.493028 -318.636874) (xy 263.416145 -318.619172) (xy 263.341501 -318.593627)
			(xy 263.269893 -318.560513) (xy 263.202086 -318.520182) (xy 263.138806 -318.473067) (xy 263.080727 -318.419671)
			(xy 263.028471 -318.360565) (xy 262.982596 -318.296379) (xy 262.943593 -318.2278) (xy 262.911879 -318.155561)
			(xy 262.887791 -318.080434) (xy 262.871588 -318.003222) (xy 262.863443 -317.924749) (xy 207.391 -317.924749)
			(xy 207.391 -326.23252) (xy 207.390423 -326.257481) (xy 207.3807 -326.306445) (xy 207.361592 -326.352563)
			(xy 207.333837 -326.394057) (xy 207.316578 -326.412098) (xy 206.704438 -327.024238) (xy 206.68638 -327.041476)
			(xy 206.644884 -327.069219) (xy 206.598772 -327.088333) (xy 206.549818 -327.098083) (xy 206.52486 -327.09866)
			(xy 196.599048 -327.09866) (xy 196.589035 -327.099158) (xy 196.570526 -327.106805) (xy 196.556354 -327.120953)
			(xy 196.548675 -327.139448) (xy 196.548248 -327.14946) (xy 196.548248 -339.82406) (xy 196.547815 -339.834129)
			(xy 196.540101 -339.852727) (xy 196.533262 -339.860128) (xy 194.367404 -342.02624) (xy 194.362679 -342.031188)
			(xy 194.355857 -342.04304) (xy 194.353942 -342.049608) (xy 194.353942 -342.050116) (xy 194.344064 -342.087717)
			(xy 194.317574 -342.160813) (xy 194.283784 -342.230834) (xy 194.243045 -342.297054) (xy 194.195779 -342.358785)
			(xy 194.142477 -342.415386) (xy 194.083693 -342.46627) (xy 194.020036 -342.510909) (xy 193.952168 -342.548838)
			(xy 193.880793 -342.579665) (xy 193.806651 -342.60307) (xy 193.730513 -342.618809) (xy 193.653168 -342.62672)
			(xy 193.614294 -342.627204) (xy 193.613786 -342.627204) (xy 193.576493 -342.626694) (xy 193.502267 -342.619368)
			(xy 193.42911 -342.604835) (xy 193.357719 -342.583235) (xy 193.288777 -342.554772) (xy 193.22294 -342.51972)
			(xy 193.191638 -342.499442) (xy 193.185252 -342.495547) (xy 193.170921 -342.491286) (xy 193.163444 -342.49106)
			(xy 132.131054 -342.49106) (xy 132.130546 -342.490552) (xy 116.090446 -342.490552) (xy 116.080378 -342.490988)
			(xy 116.061779 -342.4987) (xy 116.054378 -342.505538) (xy 111.976916 -346.583) (xy 200.85558 -346.583)
			(xy 200.856207 -346.536598) (xy 200.865897 -346.444301) (xy 200.88515 -346.353515) (xy 200.913758 -346.26523)
			(xy 200.932034 -346.222574) (xy 200.935843 -346.212632) (xy 200.935843 -346.191368) (xy 200.932034 -346.181426)
			(xy 200.913772 -346.138765) (xy 200.885179 -346.050477) (xy 200.865922 -345.959694) (xy 200.856209 -345.867401)
			(xy 200.85558 -345.821) (xy 200.856064 -345.779859) (xy 200.863695 -345.69793) (xy 200.878855 -345.617056)
			(xy 200.901414 -345.537926) (xy 200.931179 -345.461215) (xy 200.967897 -345.38758) (xy 200.989184 -345.35237)
			(xy 200.993752 -345.344157) (xy 200.997195 -345.3257) (xy 200.993752 -345.307243) (xy 200.989184 -345.29903)
			(xy 200.967885 -345.263826) (xy 200.931155 -345.190194) (xy 200.901383 -345.113484) (xy 200.878824 -345.034352)
			(xy 200.86367 -344.953474) (xy 200.856051 -344.871542) (xy 200.85558 -344.8304) (xy 200.856207 -344.783998)
			(xy 200.865897 -344.691701) (xy 200.88515 -344.600915) (xy 200.913758 -344.51263) (xy 200.932034 -344.469974)
			(xy 200.935843 -344.460032) (xy 200.935843 -344.438768) (xy 200.932034 -344.428826) (xy 200.913772 -344.386165)
			(xy 200.885179 -344.297877) (xy 200.865922 -344.207094) (xy 200.856209 -344.114801) (xy 200.85558 -344.0684)
			(xy 200.856084 -344.026039) (xy 200.864137 -343.941702) (xy 200.880171 -343.858512) (xy 200.904039 -343.777222)
			(xy 200.935527 -343.69857) (xy 200.974349 -343.623267) (xy 201.020152 -343.551995) (xy 201.072523 -343.485399)
			(xy 201.130988 -343.424084) (xy 201.195016 -343.368603) (xy 201.264028 -343.31946) (xy 201.337398 -343.2771)
			(xy 201.414463 -343.241905) (xy 201.494525 -343.214196) (xy 201.576858 -343.194222) (xy 201.660717 -343.182165)
			(xy 201.745342 -343.178134) (xy 201.829967 -343.182165) (xy 201.913826 -343.194222) (xy 201.996159 -343.214196)
			(xy 202.076221 -343.241905) (xy 202.153286 -343.2771) (xy 202.226656 -343.31946) (xy 202.295668 -343.368603)
			(xy 202.359696 -343.424084) (xy 202.418161 -343.485399) (xy 202.470532 -343.551995) (xy 202.516335 -343.623267)
			(xy 202.555157 -343.69857) (xy 202.586645 -343.777222) (xy 202.610513 -343.858512) (xy 202.626547 -343.941702)
			(xy 202.6346 -344.026039) (xy 202.635104 -344.0684) (xy 202.634479 -344.114802) (xy 202.624789 -344.2071)
			(xy 202.605534 -344.297885) (xy 202.576926 -344.38617) (xy 202.55865 -344.428826) (xy 202.554842 -344.438768)
			(xy 202.554842 -344.460032) (xy 202.55865 -344.469974) (xy 202.576911 -344.512635) (xy 202.605505 -344.600923)
			(xy 202.624762 -344.691706) (xy 202.634475 -344.783999) (xy 202.635104 -344.8304) (xy 202.634622 -344.871541)
			(xy 202.626991 -344.95347) (xy 202.611831 -345.034344) (xy 202.589272 -345.113474) (xy 202.559506 -345.190185)
			(xy 202.522787 -345.263821) (xy 202.5015 -345.29903) (xy 202.496933 -345.307243) (xy 202.493491 -345.3257)
			(xy 202.496933 -345.344157) (xy 202.5015 -345.35237) (xy 202.522797 -345.387575) (xy 202.559528 -345.461207)
			(xy 202.5893 -345.537917) (xy 202.61186 -345.617049) (xy 202.627014 -345.697926) (xy 202.634633 -345.779858)
			(xy 202.635104 -345.821) (xy 202.634479 -345.867402) (xy 202.624789 -345.9597) (xy 202.605534 -346.050485)
			(xy 202.576926 -346.13877) (xy 202.55865 -346.181426) (xy 202.554842 -346.191368) (xy 202.554842 -346.212632)
			(xy 202.55865 -346.222574) (xy 202.576911 -346.265235) (xy 202.605505 -346.353523) (xy 202.624762 -346.444306)
			(xy 202.634475 -346.536599) (xy 202.635104 -346.583) (xy 202.6346 -346.625361) (xy 202.626547 -346.709698)
			(xy 202.610513 -346.792888) (xy 202.586645 -346.874178) (xy 202.555157 -346.95283) (xy 202.516335 -347.028133)
			(xy 202.470532 -347.099405) (xy 202.418161 -347.166001) (xy 202.359696 -347.227316) (xy 202.295668 -347.282797)
			(xy 202.226656 -347.33194) (xy 202.153286 -347.3743) (xy 202.076221 -347.409495) (xy 201.996159 -347.437204)
			(xy 201.913826 -347.457178) (xy 201.829967 -347.469235) (xy 201.745342 -347.473267) (xy 201.660717 -347.469235)
			(xy 201.576858 -347.457178) (xy 201.494525 -347.437204) (xy 201.414463 -347.409495) (xy 201.337398 -347.3743)
			(xy 201.264028 -347.33194) (xy 201.195016 -347.282797) (xy 201.130988 -347.227316) (xy 201.072523 -347.166001)
			(xy 201.020152 -347.099405) (xy 200.974349 -347.028133) (xy 200.935527 -346.95283) (xy 200.904039 -346.874178)
			(xy 200.880171 -346.792888) (xy 200.864137 -346.709698) (xy 200.856084 -346.625361) (xy 200.85558 -346.583)
			(xy 111.976916 -346.583) (xy 108.568236 -349.99168) (xy 108.550159 -350.008895) (xy 108.508666 -350.03663)
			(xy 108.46256 -350.055738) (xy 108.413612 -350.065485) (xy 108.388658 -350.066102) (xy 103.505254 -350.066102)
			(xy 103.4796 -350.083628) (xy 103.473758 -350.09836) (xy 103.463544 -350.123259) (xy 103.437125 -350.170146)
			(xy 103.404379 -350.212854) (xy 103.365954 -350.250535) (xy 103.322615 -350.282441) (xy 103.275221 -350.307939)
			(xy 103.224713 -350.326522) (xy 103.172096 -350.337821) (xy 103.118412 -350.341613) (xy 103.064728 -350.337821)
			(xy 103.012111 -350.326522) (xy 102.961603 -350.307939) (xy 102.914209 -350.282441) (xy 102.87087 -350.250535)
			(xy 102.832445 -350.212854) (xy 102.799699 -350.170146) (xy 102.77328 -350.123259) (xy 102.763066 -350.09836)
			(xy 102.758987 -350.089023) (xy 102.744774 -350.07444) (xy 102.726004 -350.066541) (xy 102.715822 -350.066102)
			(xy 87.169752 -350.066102) (xy 87.159682 -350.066527) (xy 87.141083 -350.074245) (xy 87.133684 -350.081088)
			(xy 85.26399 -351.950782) (xy 85.245933 -351.968019) (xy 85.204433 -351.99575) (xy 85.158321 -352.014852)
			(xy 85.109368 -352.024591) (xy 85.084412 -352.025204) (xy 81.938368 -352.025204) (xy 81.928293 -352.025585)
			(xy 81.909694 -352.033334) (xy 81.9023 -352.04019) (xy 80.65869 -353.2838) (xy 182.729656 -353.2838)
			(xy 182.733646 -353.200045) (xy 182.745579 -353.117047) (xy 182.765347 -353.035561) (xy 182.792771 -352.956321)
			(xy 182.827603 -352.880048) (xy 182.869527 -352.807431) (xy 182.918163 -352.739127) (xy 182.973072 -352.675756)
			(xy 183.033756 -352.617891) (xy 183.099666 -352.566056) (xy 183.170204 -352.520721) (xy 183.244732 -352.482296)
			(xy 183.322575 -352.451129) (xy 183.403028 -352.427503) (xy 183.485362 -352.411631) (xy 183.568833 -352.403656)
			(xy 183.610758 -352.403156) (xy 183.611774 -352.403156) (xy 183.648831 -352.403571) (xy 183.72268 -352.409833)
			(xy 183.795742 -352.422272) (xy 183.867502 -352.440802) (xy 183.902604 -352.452686) (xy 183.910801 -352.4552)
			(xy 183.927935 -352.4552) (xy 183.936132 -352.452686) (xy 183.964337 -352.443048) (xy 184.021791 -352.42716)
			(xy 184.05094 -352.420936) (xy 184.060579 -352.41851) (xy 184.077071 -352.407448) (xy 184.088123 -352.390948)
			(xy 184.090564 -352.381312) (xy 184.100088 -352.337416) (xy 184.126813 -352.251655) (xy 184.143904 -352.210116)
			(xy 184.147468 -352.200525) (xy 184.147469 -352.180082) (xy 184.143904 -352.170492) (xy 184.126892 -352.12911)
			(xy 184.100271 -352.043685) (xy 184.082363 -351.956018) (xy 184.073351 -351.866996) (xy 184.072784 -351.822258)
			(xy 184.072784 -351.822004) (xy 184.073288 -351.779656) (xy 184.081339 -351.695342) (xy 184.097368 -351.612176)
			(xy 184.121229 -351.530909) (xy 184.152708 -351.452279) (xy 184.191519 -351.376998) (xy 184.237309 -351.305746)
			(xy 184.289665 -351.23917) (xy 184.348113 -351.177872) (xy 184.412123 -351.122407) (xy 184.481115 -351.073278)
			(xy 184.554465 -351.030929) (xy 184.631508 -350.995745) (xy 184.711547 -350.968043) (xy 184.793856 -350.948075)
			(xy 184.877691 -350.936022) (xy 184.962292 -350.931992) (xy 185.046893 -350.936022) (xy 185.130728 -350.948075)
			(xy 185.213037 -350.968043) (xy 185.293076 -350.995745) (xy 185.370119 -351.030929) (xy 185.443469 -351.073278)
			(xy 185.512461 -351.122407) (xy 185.576471 -351.177872) (xy 185.634919 -351.23917) (xy 185.687275 -351.305746)
			(xy 185.733065 -351.376998) (xy 185.771876 -351.452279) (xy 185.803355 -351.530909) (xy 185.827216 -351.612176)
			(xy 185.843245 -351.695342) (xy 185.851296 -351.779656) (xy 185.8518 -351.822004) (xy 185.8518 -351.822258)
			(xy 185.851234 -351.866996) (xy 185.842218 -351.956018) (xy 185.824312 -352.043685) (xy 185.797698 -352.129113)
			(xy 185.78068 -352.170492) (xy 185.777112 -352.180082) (xy 185.777113 -352.200525) (xy 185.78068 -352.210116)
			(xy 185.797704 -352.251527) (xy 185.824339 -352.337015) (xy 185.842246 -352.424746) (xy 185.851245 -352.513834)
			(xy 185.8518 -352.558604) (xy 185.85116 -352.609084) (xy 185.839825 -352.709404) (xy 185.829194 -352.758756)
			(xy 185.826997 -352.771225) (xy 185.833664 -352.795617) (xy 185.841894 -352.805238) (xy 185.882534 -352.847656)
			(xy 185.889646 -352.846132) (xy 185.898412 -352.843862) (xy 185.913646 -352.834103) (xy 185.919364 -352.827082)
			(xy 185.944527 -352.794419) (xy 185.999939 -352.733355) (xy 186.060764 -352.67768) (xy 186.126478 -352.627872)
			(xy 186.196519 -352.584357) (xy 186.270286 -352.547509) (xy 186.347146 -352.517645) (xy 186.426439 -352.49502)
			(xy 186.507485 -352.479828) (xy 186.589589 -352.472201) (xy 186.630818 -352.471736) (xy 186.671925 -352.472195)
			(xy 186.753788 -352.479781) (xy 186.834603 -352.494887) (xy 186.913679 -352.517383) (xy 186.990343 -352.547078)
			(xy 187.06394 -352.583719) (xy 187.133844 -352.626993) (xy 187.199457 -352.676531) (xy 187.260221 -352.73191)
			(xy 187.315617 -352.792659) (xy 187.365173 -352.85826) (xy 187.408465 -352.928152) (xy 187.445126 -353.001739)
			(xy 187.474841 -353.078395) (xy 187.497359 -353.157466) (xy 187.512486 -353.238276) (xy 187.519078 -353.3092)
			(xy 191.056256 -353.3092) (xy 191.060246 -353.225443) (xy 191.07218 -353.142444) (xy 191.091948 -353.060956)
			(xy 191.119373 -352.981715) (xy 191.154206 -352.90544) (xy 191.196132 -352.832822) (xy 191.244771 -352.764518)
			(xy 191.299682 -352.701146) (xy 191.360368 -352.643281) (xy 191.42628 -352.591447) (xy 191.49682 -352.546112)
			(xy 191.57135 -352.507688) (xy 191.649196 -352.476522) (xy 191.729651 -352.452897) (xy 191.811988 -352.437027)
			(xy 191.89546 -352.429055) (xy 191.937386 -352.428556) (xy 191.938402 -352.428556) (xy 191.975459 -352.428963)
			(xy 192.049308 -352.435227) (xy 192.12237 -352.447669) (xy 192.194131 -352.466201) (xy 192.229232 -352.478086)
			(xy 192.237429 -352.4806) (xy 192.254563 -352.4806) (xy 192.26276 -352.478086) (xy 192.290041 -352.468747)
			(xy 192.345585 -352.453243) (xy 192.373758 -352.447098) (xy 192.383527 -352.444576) (xy 192.400163 -352.433196)
			(xy 192.411142 -352.416293) (xy 192.413382 -352.406458) (xy 192.422838 -352.357349) (xy 192.451357 -352.261489)
			(xy 192.470278 -352.215196) (xy 192.473919 -352.205632) (xy 192.474045 -352.185185) (xy 192.470532 -352.175572)
			(xy 192.453515 -352.134192) (xy 192.426895 -352.048766) (xy 192.408989 -351.961099) (xy 192.399978 -351.872077)
			(xy 192.399412 -351.827338) (xy 192.399412 -351.827084) (xy 192.399916 -351.784736) (xy 192.407967 -351.700422)
			(xy 192.423996 -351.617256) (xy 192.447857 -351.535989) (xy 192.479336 -351.457359) (xy 192.518147 -351.382078)
			(xy 192.563937 -351.310826) (xy 192.616293 -351.24425) (xy 192.674741 -351.182952) (xy 192.738751 -351.127487)
			(xy 192.807743 -351.078358) (xy 192.881093 -351.036009) (xy 192.958136 -351.000825) (xy 193.038175 -350.973123)
			(xy 193.120484 -350.953155) (xy 193.204319 -350.941102) (xy 193.28892 -350.937072) (xy 193.373521 -350.941102)
			(xy 193.457356 -350.953155) (xy 193.539665 -350.973123) (xy 193.619704 -351.000825) (xy 193.696747 -351.036009)
			(xy 193.770097 -351.078358) (xy 193.839089 -351.127487) (xy 193.903099 -351.182952) (xy 193.961547 -351.24425)
			(xy 194.013903 -351.310826) (xy 194.059693 -351.382078) (xy 194.098504 -351.457359) (xy 194.129983 -351.535989)
			(xy 194.153844 -351.617256) (xy 194.169873 -351.700422) (xy 194.177924 -351.784736) (xy 194.178428 -351.827084)
			(xy 194.178428 -351.827338) (xy 194.177853 -351.872076) (xy 194.168839 -351.961098) (xy 194.150936 -352.048765)
			(xy 194.124325 -352.134193) (xy 194.107308 -352.175572) (xy 194.10375 -352.185165) (xy 194.103744 -352.205606)
			(xy 194.107308 -352.215196) (xy 194.12436 -352.256596) (xy 194.150986 -352.342088) (xy 194.168886 -352.429823)
			(xy 194.177877 -352.518913) (xy 194.178428 -352.563684) (xy 194.178055 -352.600778) (xy 194.171875 -352.674709)
			(xy 194.159556 -352.747868) (xy 194.150742 -352.783902) (xy 194.149 -352.792252) (xy 194.15051 -352.809229)
			(xy 194.157543 -352.824754) (xy 194.163188 -352.831146) (xy 194.203574 -352.874326) (xy 194.216274 -352.871532)
			(xy 194.225043 -352.869274) (xy 194.240276 -352.859506) (xy 194.245992 -352.852482) (xy 194.271138 -352.819805)
			(xy 194.326552 -352.758742) (xy 194.387379 -352.703068) (xy 194.453095 -352.65326) (xy 194.523138 -352.609746)
			(xy 194.596907 -352.5729) (xy 194.673768 -352.543037) (xy 194.753063 -352.520414) (xy 194.834111 -352.505225)
			(xy 194.916217 -352.4976) (xy 194.957446 -352.497136) (xy 194.998553 -352.497569) (xy 195.080417 -352.505157)
			(xy 195.161232 -352.520265) (xy 195.240309 -352.542764) (xy 195.316973 -352.572461) (xy 195.354442 -352.591116)
			(xy 205.807056 -352.591116) (xy 205.807462 -352.564732) (xy 205.814752 -352.51247) (xy 205.829168 -352.461709)
			(xy 205.850436 -352.413416) (xy 205.878149 -352.368511) (xy 205.911782 -352.327849) (xy 205.950692 -352.292205)
			(xy 205.994139 -352.262257) (xy 206.041295 -352.238577) (xy 206.066136 -352.229674) (xy 206.077432 -352.225019)
			(xy 206.094294 -352.207398) (xy 206.098394 -352.195892) (xy 206.108643 -352.162345) (xy 206.134476 -352.097123)
			(xy 206.166181 -352.034545) (xy 206.1845 -352.00463) (xy 206.19024 -351.994335) (xy 206.192624 -351.970911)
			(xy 206.189072 -351.959672) (xy 206.169845 -351.928882) (xy 206.136611 -351.864342) (xy 206.109656 -351.796937)
			(xy 206.089223 -351.727278) (xy 206.075496 -351.655993) (xy 206.0686 -351.583727) (xy 206.068168 -351.54743)
			(xy 206.068657 -351.508759) (xy 206.076482 -351.431814) (xy 206.092051 -351.356055) (xy 206.115204 -351.28226)
			(xy 206.145704 -351.211186) (xy 206.183239 -351.143563) (xy 206.227422 -351.080083) (xy 206.2778 -351.021399)
			(xy 206.333857 -350.968113) (xy 206.395017 -350.920772) (xy 206.460653 -350.879861) (xy 206.530091 -350.8458)
			(xy 206.602618 -350.818938) (xy 206.677491 -350.799553) (xy 206.753941 -350.787841) (xy 206.831184 -350.783924)
			(xy 206.908427 -350.787841) (xy 206.984877 -350.799553) (xy 207.05975 -350.818938) (xy 207.132277 -350.8458)
			(xy 207.201715 -350.879861) (xy 207.267351 -350.920772) (xy 207.328511 -350.968113) (xy 207.384568 -351.021399)
			(xy 207.434946 -351.080083) (xy 207.479129 -351.143563) (xy 207.516664 -351.211186) (xy 207.547164 -351.28226)
			(xy 207.570317 -351.356055) (xy 207.585886 -351.431814) (xy 207.593711 -351.508759) (xy 207.5942 -351.54743)
			(xy 207.593778 -351.583728) (xy 207.586882 -351.655995) (xy 207.573156 -351.727281) (xy 207.552724 -351.796943)
			(xy 207.525771 -351.864349) (xy 207.492539 -351.928892) (xy 207.473296 -351.959672) (xy 207.469691 -351.970907)
			(xy 207.472073 -351.994352) (xy 207.477868 -352.00463) (xy 207.500205 -352.041221) (xy 207.537401 -352.118464)
			(xy 207.565714 -352.199386) (xy 207.584789 -352.28297) (xy 207.594385 -352.368164) (xy 207.594962 -352.41103)
			(xy 207.594483 -352.451032) (xy 207.586117 -352.530596) (xy 207.569481 -352.60885) (xy 207.544756 -352.684937)
			(xy 207.512213 -352.758022) (xy 207.472209 -352.827306) (xy 207.425182 -352.892028) (xy 207.371648 -352.951481)
			(xy 207.312193 -353.005011) (xy 207.247467 -353.052034) (xy 207.178181 -353.092034) (xy 207.105094 -353.124572)
			(xy 207.029006 -353.149293) (xy 206.950751 -353.165925) (xy 206.871186 -353.174285) (xy 206.831184 -353.174808)
			(xy 206.790883 -353.174276) (xy 206.710731 -353.165788) (xy 206.631919 -353.148898) (xy 206.555327 -353.123794)
			(xy 206.481808 -353.090756) (xy 206.412182 -353.050153) (xy 206.347223 -353.002435) (xy 206.317088 -352.975672)
			(xy 206.307595 -352.967943) (xy 206.283954 -352.961723) (xy 206.271876 -352.963734) (xy 206.251504 -352.96799)
			(xy 206.210136 -352.972573) (xy 206.189326 -352.972878) (xy 206.188818 -352.972878) (xy 206.161548 -352.972382)
			(xy 206.107563 -352.964623) (xy 206.055232 -352.949259) (xy 206.00562 -352.926605) (xy 205.959737 -352.897121)
			(xy 205.918517 -352.861407) (xy 205.8828 -352.82019) (xy 205.853311 -352.77431) (xy 205.830653 -352.7247)
			(xy 205.815285 -352.67237) (xy 205.807521 -352.618386) (xy 205.807056 -352.591116) (xy 195.354442 -352.591116)
			(xy 195.390571 -352.609104) (xy 195.460474 -352.652379) (xy 195.526087 -352.701919) (xy 195.586851 -352.757301)
			(xy 195.642247 -352.818051) (xy 195.691802 -352.883653) (xy 195.735094 -352.953546) (xy 195.771754 -353.027135)
			(xy 195.80147 -353.103792) (xy 195.823987 -353.182863) (xy 195.839114 -353.263674) (xy 195.846722 -353.345537)
			(xy 195.847208 -353.386644) (xy 195.846646 -353.431414) (xy 195.837635 -353.520499) (xy 195.81973 -353.60823)
			(xy 195.793111 -353.693721) (xy 195.776088 -353.735132) (xy 195.772497 -353.744715) (xy 195.772513 -353.765165)
			(xy 195.776088 -353.774756) (xy 195.793114 -353.816166) (xy 195.81975 -353.901654) (xy 195.837657 -353.989386)
			(xy 195.846654 -354.078474) (xy 195.847208 -354.123244) (xy 195.846646 -354.168014) (xy 195.837635 -354.257099)
			(xy 195.81973 -354.34483) (xy 195.793111 -354.430321) (xy 195.776088 -354.471732) (xy 195.772497 -354.481315)
			(xy 195.772513 -354.501765) (xy 195.776088 -354.511356) (xy 195.793114 -354.552766) (xy 195.81975 -354.638254)
			(xy 195.837657 -354.725986) (xy 195.846654 -354.815074) (xy 195.847208 -354.859844) (xy 195.84679 -354.900955)
			(xy 195.839198 -354.982827) (xy 195.824083 -355.063648) (xy 195.801575 -355.14273) (xy 195.771864 -355.219398)
			(xy 195.735206 -355.292996) (xy 195.691912 -355.362897) (xy 195.642352 -355.428505) (xy 195.586949 -355.48926)
			(xy 195.526176 -355.544642) (xy 195.460551 -355.59418) (xy 195.390636 -355.637451) (xy 195.317025 -355.674085)
			(xy 195.240348 -355.703769) (xy 195.161258 -355.726251) (xy 195.080432 -355.741339) (xy 194.998557 -355.748903)
			(xy 194.957446 -355.749352) (xy 194.915842 -355.74888) (xy 194.832994 -355.741147) (xy 194.75123 -355.725716)
			(xy 194.671262 -355.702722) (xy 194.593789 -355.672366) (xy 194.519488 -355.634911) (xy 194.48399 -355.613208)
			(xy 194.474858 -355.608031) (xy 194.454138 -355.60482) (xy 194.433861 -355.61016) (xy 194.425316 -355.616256)
			(xy 194.391667 -355.642178) (xy 194.320293 -355.688236) (xy 194.244854 -355.727283) (xy 194.166037 -355.758962)
			(xy 194.08456 -355.782986) (xy 194.001164 -355.799135) (xy 193.916608 -355.807262) (xy 193.874136 -355.807772)
			(xy 193.873882 -355.807772) (xy 193.832775 -355.807305) (xy 193.750912 -355.799719) (xy 193.670098 -355.784614)
			(xy 193.591023 -355.762118) (xy 193.514359 -355.732423) (xy 193.440762 -355.695782) (xy 193.370859 -355.652509)
			(xy 193.305245 -355.602971) (xy 193.244482 -355.547592) (xy 193.189086 -355.486844) (xy 193.13953 -355.421244)
			(xy 193.096237 -355.351353) (xy 193.059577 -355.277766) (xy 193.029861 -355.201111) (xy 193.007343 -355.122041)
			(xy 192.992215 -355.041231) (xy 192.984607 -354.959371) (xy 192.98412 -354.918264) (xy 192.984683 -354.873494)
			(xy 192.993693 -354.784409) (xy 193.011598 -354.696678) (xy 193.038217 -354.611187) (xy 193.05524 -354.569776)
			(xy 193.058825 -354.560191) (xy 193.058812 -354.539743) (xy 193.05524 -354.530152) (xy 193.03824 -354.4888)
			(xy 193.011628 -354.403438) (xy 192.99372 -354.315836) (xy 192.984697 -354.226879) (xy 192.98412 -354.182172)
			(xy 192.98412 -354.181156) (xy 192.984374 -354.169726) (xy 192.957895 -354.163781) (xy 192.90566 -354.149038)
			(xy 192.87998 -354.140262) (xy 192.871783 -354.137748) (xy 192.854649 -354.137748) (xy 192.846452 -354.140262)
			(xy 192.811236 -354.152209) (xy 192.739226 -354.170796) (xy 192.665903 -354.183236) (xy 192.591792 -354.18944)
			(xy 192.554606 -354.189792) (xy 192.517422 -354.189422) (xy 192.443314 -354.1832) (xy 192.369994 -354.170758)
			(xy 192.297983 -354.152184) (xy 192.26276 -354.140262) (xy 192.254563 -354.137748) (xy 192.237429 -354.137748)
			(xy 192.229232 -354.140262) (xy 192.19413 -354.15215) (xy 192.122374 -354.1707) (xy 192.049311 -354.183146)
			(xy 191.97546 -354.189399) (xy 191.938402 -354.189792) (xy 191.937386 -354.189792) (xy 191.89546 -354.189345)
			(xy 191.811988 -354.181373) (xy 191.729651 -354.165503) (xy 191.649196 -354.141878) (xy 191.57135 -354.110712)
			(xy 191.49682 -354.072288) (xy 191.42628 -354.026953) (xy 191.360368 -353.975119) (xy 191.299682 -353.917254)
			(xy 191.244771 -353.853882) (xy 191.196132 -353.785578) (xy 191.154206 -353.71296) (xy 191.119373 -353.636685)
			(xy 191.091948 -353.557444) (xy 191.07218 -353.475956) (xy 191.060246 -353.392957) (xy 191.056256 -353.3092)
			(xy 187.519078 -353.3092) (xy 187.520094 -353.320137) (xy 187.52058 -353.361244) (xy 187.52002 -353.406014)
			(xy 187.511009 -353.495099) (xy 187.493104 -353.58283) (xy 187.466484 -353.668321) (xy 187.44946 -353.709732)
			(xy 187.44587 -353.719315) (xy 187.445886 -353.739765) (xy 187.44946 -353.749356) (xy 187.466484 -353.790767)
			(xy 187.493121 -353.876254) (xy 187.511029 -353.963986) (xy 187.520026 -354.053074) (xy 187.52058 -354.097844)
			(xy 187.52002 -354.142614) (xy 187.511009 -354.231699) (xy 187.493104 -354.31943) (xy 187.466484 -354.404921)
			(xy 187.44946 -354.446332) (xy 187.44587 -354.455915) (xy 187.445886 -354.476365) (xy 187.44946 -354.485956)
			(xy 187.466484 -354.527367) (xy 187.493121 -354.612854) (xy 187.511029 -354.700586) (xy 187.520026 -354.789674)
			(xy 187.52058 -354.834444) (xy 187.520189 -354.875556) (xy 187.512597 -354.957429) (xy 187.497482 -355.038252)
			(xy 187.474973 -355.117336) (xy 187.445261 -355.194004) (xy 187.408601 -355.267604) (xy 187.365306 -355.337506)
			(xy 187.315744 -355.403115) (xy 187.260339 -355.46387) (xy 187.199564 -355.519252) (xy 187.133937 -355.56879)
			(xy 187.064019 -355.61206) (xy 186.990406 -355.648693) (xy 186.913727 -355.678376) (xy 186.834635 -355.700857)
			(xy 186.753806 -355.715942) (xy 186.67193 -355.723505) (xy 186.630818 -355.723952) (xy 186.589214 -355.723494)
			(xy 186.506365 -355.715758) (xy 186.424601 -355.700325) (xy 186.344633 -355.677328) (xy 186.267161 -355.646969)
			(xy 186.192859 -355.609513) (xy 186.157362 -355.587808) (xy 186.148243 -355.582606) (xy 186.127514 -355.579404)
			(xy 186.107233 -355.584754) (xy 186.098688 -355.590856) (xy 186.065049 -355.616791) (xy 185.993673 -355.662848)
			(xy 185.918232 -355.701893) (xy 185.839413 -355.73357) (xy 185.757935 -355.757592) (xy 185.674537 -355.773739)
			(xy 185.589981 -355.781864) (xy 185.547508 -355.782372) (xy 185.547254 -355.782372) (xy 185.506147 -355.781931)
			(xy 185.424283 -355.774343) (xy 185.343469 -355.759235) (xy 185.264393 -355.736737) (xy 185.187729 -355.70704)
			(xy 185.114132 -355.670398) (xy 185.044229 -355.627122) (xy 184.978615 -355.577583) (xy 184.917852 -355.522202)
			(xy 184.862456 -355.461452) (xy 184.812901 -355.395851) (xy 184.769609 -355.325959) (xy 184.732948 -355.252371)
			(xy 184.703232 -355.175714) (xy 184.680715 -355.096644) (xy 184.665587 -355.015833) (xy 184.657979 -354.933971)
			(xy 184.657492 -354.892864) (xy 184.658057 -354.848094) (xy 184.667066 -354.759009) (xy 184.684971 -354.671278)
			(xy 184.711589 -354.585787) (xy 184.728612 -354.544376) (xy 184.732199 -354.534792) (xy 184.732185 -354.514343)
			(xy 184.728612 -354.504752) (xy 184.711616 -354.463398) (xy 184.685002 -354.378037) (xy 184.667093 -354.290435)
			(xy 184.658069 -354.201478) (xy 184.657492 -354.156772) (xy 184.657492 -354.155756) (xy 184.657746 -354.144326)
			(xy 184.631266 -354.138384) (xy 184.579032 -354.123639) (xy 184.553352 -354.114862) (xy 184.545155 -354.112348)
			(xy 184.528021 -354.112348) (xy 184.519824 -354.114862) (xy 184.484602 -354.126789) (xy 184.412594 -354.145381)
			(xy 184.339273 -354.157827) (xy 184.265163 -354.164037) (xy 184.227978 -354.164392) (xy 184.190794 -354.16403)
			(xy 184.116686 -354.157806) (xy 184.043366 -354.145361) (xy 183.971355 -354.126785) (xy 183.936132 -354.114862)
			(xy 183.927935 -354.112348) (xy 183.910801 -354.112348) (xy 183.902604 -354.114862) (xy 183.867505 -354.126757)
			(xy 183.795747 -354.145305) (xy 183.722684 -354.157749) (xy 183.648832 -354.164001) (xy 183.611774 -354.164392)
			(xy 183.610758 -354.164392) (xy 183.568833 -354.163944) (xy 183.485362 -354.155969) (xy 183.403028 -354.140097)
			(xy 183.322575 -354.11647) (xy 183.244732 -354.085304) (xy 183.170204 -354.046879) (xy 183.099666 -354.001544)
			(xy 183.033756 -353.949709) (xy 182.973072 -353.891844) (xy 182.918163 -353.828473) (xy 182.869527 -353.760169)
			(xy 182.827603 -353.687552) (xy 182.792771 -353.611278) (xy 182.765347 -353.532039) (xy 182.745579 -353.450553)
			(xy 182.733646 -353.367555) (xy 182.729656 -353.2838) (xy 80.65869 -353.2838) (xy 79.204312 -354.738178)
			(xy 79.186245 -354.755404) (xy 79.144749 -354.783137) (xy 79.09864 -354.802242) (xy 79.049689 -354.811985)
			(xy 79.024734 -354.8126) (xy 27.187652 -354.8126) (xy 27.162691 -354.81204) (xy 27.113726 -354.802311)
			(xy 27.067607 -354.783198) (xy 27.026114 -354.755439) (xy 27.008074 -354.738178) (xy 25.037288 -352.767392)
			(xy 25.030685 -352.761223) (xy 25.014289 -352.753654) (xy 24.996282 -352.752289) (xy 24.987504 -352.754438)
			(xy 24.986996 -352.754438) (xy 24.952747 -352.763874) (xy 24.882939 -352.777074) (xy 24.812206 -352.783726)
			(xy 24.776684 -352.784156) (xy 24.736749 -352.783649) (xy 24.657317 -352.775301) (xy 24.579192 -352.758696)
			(xy 24.503232 -352.734015) (xy 24.430267 -352.701529) (xy 24.361097 -352.661594) (xy 24.296481 -352.614648)
			(xy 24.237126 -352.561205) (xy 24.183683 -352.50185) (xy 24.136737 -352.437234) (xy 24.096802 -352.368065)
			(xy 24.064316 -352.2951) (xy 24.039635 -352.21914) (xy 24.023029 -352.141015) (xy 24.014681 -352.061583)
			(xy 24.014176 -352.021648) (xy 24.014605 -351.986084) (xy 24.021246 -351.915265) (xy 24.034456 -351.845374)
			(xy 24.043894 -351.811082) (xy 24.043894 -351.810828) (xy 24.046001 -351.802051) (xy 24.044595 -351.784068)
			(xy 24.037057 -351.767681) (xy 24.03094 -351.761044) (xy 23.696422 -351.426526) (xy 23.679203 -351.408453)
			(xy 23.651469 -351.366959) (xy 23.632362 -351.320852) (xy 23.622616 -351.271903) (xy 23.622 -351.246948)
			(xy 23.622 -346.293186) (xy 23.621608 -346.283112) (xy 23.613867 -346.264513) (xy 23.607014 -346.257118)
			(xy 22.974808 -345.624912) (xy 22.95758 -345.606847) (xy 22.929848 -345.56535) (xy 22.910743 -345.51924)
			(xy 22.901001 -345.470289) (xy 22.900386 -345.445334) (xy 22.900386 -343.306908) (xy 22.899754 -343.295491)
			(xy 22.889854 -343.274914) (xy 22.881336 -343.267284) (xy 22.859903 -343.249489) (xy 22.822053 -343.20862)
			(xy 22.790708 -343.162572) (xy 22.766567 -343.112371) (xy 22.750168 -343.059135) (xy 22.741876 -343.004052)
			(xy 22.741876 -342.948348) (xy 22.750168 -342.893265) (xy 22.766567 -342.840029) (xy 22.790708 -342.789828)
			(xy 22.822053 -342.74378) (xy 22.859903 -342.702911) (xy 22.881336 -342.685116) (xy 22.889855 -342.677487)
			(xy 22.899754 -342.656909) (xy 22.900386 -342.645492) (xy 22.900386 -340.487254) (xy 22.881336 -340.460838)
			(xy 22.865842 -340.455504) (xy 22.839463 -340.446111) (xy 22.789557 -340.42072) (xy 22.743898 -340.388307)
			(xy 22.703467 -340.349568) (xy 22.669132 -340.305336) (xy 22.64163 -340.256561) (xy 22.621553 -340.20429)
			(xy 22.609332 -340.149646) (xy 22.605228 -340.093803) (xy 22.609331 -340.037959) (xy 22.621552 -339.983315)
			(xy 22.641628 -339.931043) (xy 22.669129 -339.882268) (xy 22.703463 -339.838036) (xy 22.743894 -339.799297)
			(xy 22.789552 -339.766883) (xy 22.839458 -339.741491) (xy 22.865842 -339.732112) (xy 22.875698 -339.728252)
			(xy 22.891334 -339.714022) (xy 22.899863 -339.694678) (xy 22.900386 -339.684106) (xy 22.900386 -335.047082)
			(xy 22.900132 -335.046574) (xy 22.900132 -244.844062) (xy 22.899631 -244.833451) (xy 22.891128 -244.814012)
			(xy 22.875473 -244.799691) (xy 22.865588 -244.795802) (xy 22.865334 -244.795802) (xy 22.828623 -244.782881)
			(xy 22.757856 -244.750488) (xy 22.690824 -244.710938) (xy 22.62825 -244.664657) (xy 22.570807 -244.612144)
			(xy 22.519113 -244.553962) (xy 22.473723 -244.490739) (xy 22.435128 -244.423153) (xy 22.40374 -244.351934)
			(xy 22.3799 -244.277846) (xy 22.363862 -244.201687) (xy 22.355799 -244.124276) (xy 22.355799 -244.046447)
			(xy 22.363861 -243.969036) (xy 22.379899 -243.892877) (xy 22.403739 -243.818789) (xy 22.435126 -243.747569)
			(xy 22.473722 -243.679984) (xy 22.519111 -243.61676) (xy 22.570805 -243.558578) (xy 22.628248 -243.506064)
			(xy 22.690822 -243.459783) (xy 22.757853 -243.420233) (xy 22.828621 -243.38784) (xy 22.865334 -243.374926)
			(xy 22.865588 -243.374926) (xy 22.875455 -243.371022) (xy 22.891058 -243.356671) (xy 22.899591 -243.337265)
			(xy 22.900132 -243.326666) (xy 22.900132 -227.059236) (xy 22.900568 -227.049168) (xy 22.90828 -227.030569)
			(xy 22.915118 -227.023168) (xy 23.51532 -226.422966) (xy 23.522715 -226.41612) (xy 23.541318 -226.408405)
			(xy 23.551388 -226.40798) (xy 28.919932 -226.40798) (xy 28.925372 -226.407844) (xy 28.936006 -226.405538)
			(xy 28.941014 -226.403408) (xy 28.977724 -226.387208) (xy 29.053857 -226.36185) (xy 29.132262 -226.344762)
			(xy 29.212042 -226.336141) (xy 29.252164 -226.33559) (xy 29.292287 -226.336138) (xy 29.372069 -226.34475)
			(xy 29.450474 -226.361838) (xy 29.526604 -226.387206) (xy 29.563314 -226.403408) (xy 29.568322 -226.405537)
			(xy 29.578956 -226.40784) (xy 29.584396 -226.40798) (xy 36.463732 -226.40798) (xy 36.469172 -226.407844)
			(xy 36.479806 -226.405538) (xy 36.484814 -226.403408) (xy 36.521524 -226.387208) (xy 36.597657 -226.36185)
			(xy 36.676062 -226.344762) (xy 36.755842 -226.336141) (xy 36.795964 -226.33559) (xy 36.836087 -226.336138)
			(xy 36.915869 -226.34475) (xy 36.994274 -226.361838) (xy 37.070404 -226.387206) (xy 37.107114 -226.403408)
			(xy 37.112122 -226.405537) (xy 37.122756 -226.40784) (xy 37.128196 -226.40798) (xy 40.502332 -226.40798)
			(xy 40.512344 -226.407538) (xy 40.530841 -226.399864) (xy 40.544993 -226.385697) (xy 40.552648 -226.367193)
			(xy 40.553132 -226.35718) (xy 40.553132 -195.9356) (xy 40.552613 -195.925596) (xy 40.544959 -195.907111)
			(xy 40.530816 -195.892959) (xy 40.512335 -195.885294) (xy 40.502332 -195.8848) (xy 38.693852 -195.8848)
			(xy 38.683784 -195.885262) (xy 38.665217 -195.893065) (xy 38.651054 -195.907384) (xy 38.646862 -195.91655)
			(xy 38.631906 -195.952239) (xy 38.595655 -196.02061) (xy 38.552557 -196.084885) (xy 38.503068 -196.144379)
			(xy 38.447715 -196.198459) (xy 38.387086 -196.246552) (xy 38.321828 -196.288145) (xy 38.252632 -196.322796)
			(xy 38.180236 -196.350137) (xy 38.10541 -196.369876) (xy 38.028948 -196.381804) (xy 37.951664 -196.385795)
			(xy 37.87438 -196.381804) (xy 37.797918 -196.369876) (xy 37.723092 -196.350137) (xy 37.650696 -196.322796)
			(xy 37.5815 -196.288145) (xy 37.516242 -196.246552) (xy 37.455613 -196.198459) (xy 37.40026 -196.144379)
			(xy 37.350771 -196.084885) (xy 37.307673 -196.02061) (xy 37.271422 -195.952239) (xy 37.256466 -195.91655)
			(xy 37.252331 -195.907343) (xy 37.238175 -195.892979) (xy 37.219561 -195.885217) (xy 37.209476 -195.8848)
			(xy 31.150052 -195.8848) (xy 31.139984 -195.885262) (xy 31.121417 -195.893065) (xy 31.107254 -195.907384)
			(xy 31.103062 -195.91655) (xy 31.088106 -195.952239) (xy 31.051855 -196.02061) (xy 31.008757 -196.084885)
			(xy 30.959268 -196.144379) (xy 30.903915 -196.198459) (xy 30.843286 -196.246552) (xy 30.778028 -196.288145)
			(xy 30.708832 -196.322796) (xy 30.636436 -196.350137) (xy 30.56161 -196.369876) (xy 30.485148 -196.381804)
			(xy 30.407864 -196.385795) (xy 30.33058 -196.381804) (xy 30.254118 -196.369876) (xy 30.179292 -196.350137)
			(xy 30.106896 -196.322796) (xy 30.0377 -196.288145) (xy 29.972442 -196.246552) (xy 29.911813 -196.198459)
			(xy 29.85646 -196.144379) (xy 29.806971 -196.084885) (xy 29.763873 -196.02061) (xy 29.727622 -195.952239)
			(xy 29.712666 -195.91655) (xy 29.708531 -195.907343) (xy 29.694375 -195.892979) (xy 29.675761 -195.885217)
			(xy 29.665676 -195.8848) (xy 23.605998 -195.8848) (xy 23.595934 -195.885296) (xy 23.577368 -195.893083)
			(xy 23.563202 -195.907389) (xy 23.559008 -195.91655) (xy 23.544052 -195.952239) (xy 23.507801 -196.02061)
			(xy 23.464703 -196.084885) (xy 23.415214 -196.144379) (xy 23.359861 -196.198459) (xy 23.299232 -196.246552)
			(xy 23.233974 -196.288145) (xy 23.164778 -196.322796) (xy 23.092382 -196.350137) (xy 23.017556 -196.369876)
			(xy 22.941094 -196.381804) (xy 22.86381 -196.385795) (xy 22.786526 -196.381804) (xy 22.710064 -196.369876)
			(xy 22.635238 -196.350137) (xy 22.562842 -196.322796) (xy 22.493646 -196.288145) (xy 22.428388 -196.246552)
			(xy 22.367759 -196.198459) (xy 22.312406 -196.144379) (xy 22.262917 -196.084885) (xy 22.219819 -196.02061)
			(xy 22.183568 -195.952239) (xy 22.168612 -195.91655) (xy 22.164443 -195.907362) (xy 22.150301 -195.892997)
			(xy 22.131702 -195.885225) (xy 22.121622 -195.8848) (xy 19.194526 -195.8848) (xy 19.187568 -195.885)
			(xy 19.174165 -195.888733) (xy 19.16811 -195.892166) (xy 19.136077 -195.91109) (xy 19.068969 -195.943229)
			(xy 18.999007 -195.968559) (xy 18.92688 -195.986833) (xy 18.853297 -195.99787) (xy 18.778982 -196.001561)
			(xy 18.704667 -195.99787) (xy 18.631084 -195.986833) (xy 18.558957 -195.968559) (xy 18.488995 -195.943229)
			(xy 18.421887 -195.91109) (xy 18.389854 -195.892166) (xy 18.383787 -195.888763) (xy 18.370391 -195.885035)
			(xy 18.363438 -195.8848) (xy 16.001492 -195.8848) (xy 15.995847 -195.884931) (xy 15.984823 -195.887366)
			(xy 15.979648 -195.889626) (xy 15.941117 -195.907386) (xy 15.860963 -195.935206) (xy 15.778217 -195.953967)
			(xy 15.693902 -195.963439) (xy 15.65148 -195.964048) (xy 15.609056 -195.963471) (xy 15.524735 -195.954015)
			(xy 15.441988 -195.935246) (xy 15.361841 -195.907395) (xy 15.323312 -195.889626) (xy 15.318134 -195.887373)
			(xy 15.307113 -195.884929) (xy 15.301468 -195.8848) (xy 14.588744 -195.8848) (xy 14.578674 -195.884378)
			(xy 14.560074 -195.876658) (xy 14.552676 -195.869814) (xy 13.950442 -195.267834) (xy 13.945108 -195.264532)
			(xy 13.912921 -195.244801) (xy 13.852225 -195.199899) (xy 13.796263 -195.149218) (xy 13.745584 -195.093254)
			(xy 13.700684 -195.032556) (xy 13.680948 -195.000372) (xy 13.677646 -194.995038) (xy 13.300202 -194.617594)
			(xy 13.293367 -194.61019) (xy 13.285644 -194.591594) (xy 13.285216 -194.581526) (xy 3.523996 -194.581526)
			(xy 3.523996 -358.071674) (xy 14.058646 -358.071674) (xy 14.05923 -358.028982) (xy 14.068776 -357.944134)
			(xy 14.087733 -357.860882) (xy 14.115866 -357.780266) (xy 14.152822 -357.703295) (xy 14.174978 -357.666798)
			(xy 14.179717 -357.658553) (xy 14.18324 -357.639878) (xy 14.179701 -357.621205) (xy 14.174978 -357.61295)
			(xy 14.152819 -357.576453) (xy 14.115833 -357.499493) (xy 14.087689 -357.418878) (xy 14.06874 -357.335621)
			(xy 14.059225 -357.250767) (xy 14.058646 -357.208074) (xy 14.059135 -357.169455) (xy 14.066949 -357.092612)
			(xy 14.082497 -357.016954) (xy 14.10562 -356.943257) (xy 14.136079 -356.872278) (xy 14.173564 -356.804744)
			(xy 14.217688 -356.74135) (xy 14.267999 -356.682744) (xy 14.323981 -356.629529) (xy 14.38506 -356.58225)
			(xy 14.450608 -356.541394) (xy 14.519954 -356.507378) (xy 14.592385 -356.480553) (xy 14.667158 -356.461193)
			(xy 14.743506 -356.449497) (xy 14.820646 -356.445585) (xy 14.897786 -356.449497) (xy 14.974134 -356.461193)
			(xy 15.048907 -356.480553) (xy 15.121338 -356.507378) (xy 15.190684 -356.541394) (xy 15.256232 -356.58225)
			(xy 15.317311 -356.629529) (xy 15.373293 -356.682744) (xy 15.423604 -356.74135) (xy 15.467728 -356.804744)
			(xy 15.505213 -356.872278) (xy 15.535672 -356.943257) (xy 15.558795 -357.016954) (xy 15.574343 -357.092612)
			(xy 15.582157 -357.169455) (xy 15.582646 -357.208074) (xy 15.582038 -357.250765) (xy 15.572498 -357.335612)
			(xy 15.553546 -357.418864) (xy 15.525419 -357.49948) (xy 15.488468 -357.576452) (xy 15.466314 -357.61295)
			(xy 15.461618 -357.621216) (xy 15.458081 -357.639878) (xy 15.461602 -357.658543) (xy 15.466314 -357.666798)
			(xy 15.488492 -357.703284) (xy 15.525474 -357.780247) (xy 15.553615 -357.860865) (xy 15.572559 -357.944124)
			(xy 15.58207 -358.02898) (xy 15.582646 -358.071674) (xy 15.582157 -358.110293) (xy 15.574343 -358.187136)
			(xy 15.558795 -358.262794) (xy 15.535672 -358.336491) (xy 15.505213 -358.40747) (xy 15.467728 -358.475004)
			(xy 15.423604 -358.538398) (xy 15.414336 -358.549194) (xy 40.47998 -358.549194) (xy 40.480352 -358.511134)
			(xy 40.486825 -358.435291) (xy 40.499758 -358.360279) (xy 40.519056 -358.286646) (xy 40.544577 -358.214933)
			(xy 40.55999 -358.180132) (xy 40.563435 -358.171803) (xy 40.56487 -358.153848) (xy 40.562784 -358.14508)
			(xy 40.551663 -358.104882) (xy 40.536092 -358.022938) (xy 40.528245 -357.939897) (xy 40.527732 -357.898192)
			(xy 40.528135 -357.859902) (xy 40.534744 -357.783608) (xy 40.547894 -357.708165) (xy 40.567488 -357.634135)
			(xy 40.580056 -357.597964) (xy 40.58271 -357.589528) (xy 40.582708 -357.571857) (xy 40.580056 -357.56342)
			(xy 40.567506 -357.527245) (xy 40.547935 -357.453211) (xy 40.53479 -357.37777) (xy 40.528167 -357.30148)
			(xy 40.527732 -357.263192) (xy 40.528236 -357.220831) (xy 40.536289 -357.136494) (xy 40.552323 -357.053304)
			(xy 40.576191 -356.972014) (xy 40.607679 -356.893362) (xy 40.646501 -356.818059) (xy 40.692304 -356.746787)
			(xy 40.744675 -356.680191) (xy 40.80314 -356.618876) (xy 40.867168 -356.563395) (xy 40.93618 -356.514252)
			(xy 41.00955 -356.471892) (xy 41.086615 -356.436697) (xy 41.166677 -356.408988) (xy 41.24901 -356.389014)
			(xy 41.332869 -356.376957) (xy 41.417494 -356.372926) (xy 41.502119 -356.376957) (xy 41.585978 -356.389014)
			(xy 41.668311 -356.408988) (xy 41.748373 -356.436697) (xy 41.825438 -356.471892) (xy 41.898808 -356.514252)
			(xy 41.96782 -356.563395) (xy 42.031848 -356.618876) (xy 42.090313 -356.680191) (xy 42.142684 -356.746787)
			(xy 42.188487 -356.818059) (xy 42.227309 -356.893362) (xy 42.258797 -356.972014) (xy 42.282665 -357.053304)
			(xy 42.298699 -357.136494) (xy 42.306752 -357.220831) (xy 42.307256 -357.263192) (xy 42.306849 -357.301482)
			(xy 42.300241 -357.377776) (xy 42.287093 -357.453218) (xy 42.2675 -357.527249) (xy 42.254932 -357.56342)
			(xy 42.252286 -357.571858) (xy 42.252283 -357.589527) (xy 42.254932 -357.597964) (xy 42.267477 -357.634141)
			(xy 42.28705 -357.708174) (xy 42.300196 -357.783614) (xy 42.30682 -357.859904) (xy 42.307256 -357.898192)
			(xy 42.306876 -357.936251) (xy 42.300404 -358.012094) (xy 42.287473 -358.087107) (xy 42.268177 -358.160739)
			(xy 42.242658 -358.232452) (xy 42.227246 -358.267254) (xy 42.223809 -358.275586) (xy 42.222368 -358.293538)
			(xy 42.224452 -358.302306) (xy 42.23557 -358.342505) (xy 42.251142 -358.424449) (xy 42.258991 -358.507489)
			(xy 42.259032 -358.51084) (xy 43.046396 -358.51084) (xy 43.046759 -358.47278) (xy 43.053225 -358.396935)
			(xy 43.066156 -358.321921) (xy 43.085458 -358.248289) (xy 43.110988 -358.176577) (xy 43.126406 -358.141778)
			(xy 43.129746 -358.133421) (xy 43.131033 -358.115482) (xy 43.128946 -358.106726) (xy 43.117873 -358.066521)
			(xy 43.102375 -357.984574) (xy 43.094614 -357.901538) (xy 43.094148 -357.859838) (xy 43.094524 -357.821522)
			(xy 43.101053 -357.745169) (xy 43.114136 -357.669662) (xy 43.133673 -357.595562) (xy 43.146218 -357.559356)
			(xy 43.148787 -357.551035) (xy 43.148799 -357.533636) (xy 43.146218 -357.52532) (xy 43.13374 -357.489193)
			(xy 43.114246 -357.415282) (xy 43.101158 -357.339973) (xy 43.094573 -357.263819) (xy 43.094148 -357.2256)
			(xy 43.094148 -357.224838) (xy 43.094652 -357.18249) (xy 43.102703 -357.098176) (xy 43.118732 -357.01501)
			(xy 43.142593 -356.933743) (xy 43.174072 -356.855113) (xy 43.212883 -356.779832) (xy 43.258673 -356.70858)
			(xy 43.311029 -356.642004) (xy 43.369477 -356.580706) (xy 43.433487 -356.525241) (xy 43.502479 -356.476112)
			(xy 43.575829 -356.433763) (xy 43.652872 -356.398579) (xy 43.732911 -356.370877) (xy 43.81522 -356.350909)
			(xy 43.899055 -356.338856) (xy 43.983656 -356.334826) (xy 44.068257 -356.338856) (xy 44.152092 -356.350909)
			(xy 44.234401 -356.370877) (xy 44.31444 -356.398579) (xy 44.391483 -356.433763) (xy 44.464833 -356.476112)
			(xy 44.533825 -356.525241) (xy 44.597835 -356.580706) (xy 44.656283 -356.642004) (xy 44.708639 -356.70858)
			(xy 44.754429 -356.779832) (xy 44.79324 -356.855113) (xy 44.824719 -356.933743) (xy 44.84858 -357.01501)
			(xy 44.864609 -357.098176) (xy 44.87266 -357.18249) (xy 44.873164 -357.224838) (xy 44.873164 -357.2256)
			(xy 44.87277 -357.263821) (xy 44.866201 -357.339979) (xy 44.853113 -357.415292) (xy 44.833602 -357.489202)
			(xy 44.821094 -357.52532) (xy 44.818487 -357.533631) (xy 44.818499 -357.55104) (xy 44.821094 -357.559356)
			(xy 44.833623 -357.595567) (xy 44.853143 -357.669669) (xy 44.866225 -357.745173) (xy 44.872771 -357.821523)
			(xy 44.873164 -357.859838) (xy 44.872788 -357.897898) (xy 44.866324 -357.973742) (xy 44.853395 -358.048756)
			(xy 44.837736 -358.108504) (xy 46.991016 -358.108504) (xy 46.991397 -358.070445) (xy 46.997869 -357.994602)
			(xy 47.0108 -357.919589) (xy 47.030096 -357.845957) (xy 47.055615 -357.774244) (xy 47.071026 -357.739442)
			(xy 47.074466 -357.731111) (xy 47.075906 -357.713158) (xy 47.07382 -357.70439) (xy 47.0627 -357.664192)
			(xy 47.047129 -357.582247) (xy 47.039281 -357.499207) (xy 47.038768 -357.457502) (xy 47.039173 -357.419212)
			(xy 47.045781 -357.342918) (xy 47.05893 -357.267476) (xy 47.078524 -357.193445) (xy 47.091092 -357.157274)
			(xy 47.09374 -357.148837) (xy 47.093741 -357.131167) (xy 47.091092 -357.12273) (xy 47.078546 -357.086553)
			(xy 47.058974 -357.01252) (xy 47.045827 -356.93708) (xy 47.039204 -356.86079) (xy 47.038768 -356.822502)
			(xy 47.0392 -356.781386) (xy 47.046788 -356.699506) (xy 47.061898 -356.618674) (xy 47.084402 -356.539582)
			(xy 47.114108 -356.462904) (xy 47.150762 -356.389293) (xy 47.194052 -356.319379) (xy 47.243609 -356.253758)
			(xy 47.299008 -356.192989) (xy 47.359779 -356.137591) (xy 47.425402 -356.088036) (xy 47.495318 -356.044749)
			(xy 47.568929 -356.008097) (xy 47.645609 -355.978393) (xy 47.724702 -355.955891) (xy 47.805533 -355.940784)
			(xy 47.887414 -355.933199) (xy 47.92853 -355.93274) (xy 47.969637 -355.933252) (xy 48.051499 -355.940877)
			(xy 48.132307 -355.956023) (xy 48.211373 -355.97856) (xy 48.288023 -356.008296) (xy 48.325024 -356.026212)
			(xy 48.335846 -356.030917) (xy 48.359414 -356.030917) (xy 48.370236 -356.026212) (xy 48.407247 -356.008316)
			(xy 48.483894 -355.978575) (xy 48.562957 -355.956031) (xy 48.643763 -355.940876) (xy 48.725623 -355.93324)
			(xy 48.76673 -355.93274) (xy 48.80502 -355.933136) (xy 48.881314 -355.939747) (xy 48.956757 -355.952899)
			(xy 49.030787 -355.972495) (xy 49.066958 -355.985064) (xy 49.075395 -355.987715) (xy 49.093065 -355.987715)
			(xy 49.101502 -355.985064) (xy 49.137675 -355.972508) (xy 49.21171 -355.952938) (xy 49.287151 -355.939795)
			(xy 49.363442 -355.933174) (xy 49.40173 -355.93274) (xy 49.44002 -355.933136) (xy 49.516314 -355.939747)
			(xy 49.591757 -355.952899) (xy 49.665787 -355.972495) (xy 49.701958 -355.985064) (xy 49.710395 -355.987715)
			(xy 49.728065 -355.987715) (xy 49.736502 -355.985064) (xy 49.772675 -355.972508) (xy 49.84671 -355.952938)
			(xy 49.922151 -355.939795) (xy 49.998442 -355.933174) (xy 50.03673 -355.93274) (xy 50.07502 -355.933136)
			(xy 50.151314 -355.939747) (xy 50.226757 -355.952899) (xy 50.300787 -355.972495) (xy 50.336958 -355.985064)
			(xy 50.345395 -355.987715) (xy 50.363065 -355.987715) (xy 50.371502 -355.985064) (xy 50.407675 -355.972508)
			(xy 50.48171 -355.952938) (xy 50.557151 -355.939795) (xy 50.633442 -355.933174) (xy 50.67173 -355.93274)
			(xy 50.712845 -355.933184) (xy 50.794723 -355.940774) (xy 50.875552 -355.955886) (xy 50.954642 -355.978392)
			(xy 51.031318 -356.008098) (xy 51.104926 -356.044753) (xy 51.174838 -356.088043) (xy 51.240458 -356.137599)
			(xy 51.301225 -356.192997) (xy 51.356622 -356.253767) (xy 51.406175 -356.319388) (xy 51.449463 -356.389302)
			(xy 51.486115 -356.462911) (xy 51.515819 -356.539588) (xy 51.538321 -356.618679) (xy 51.55343 -356.699508)
			(xy 51.561017 -356.781387) (xy 51.561492 -356.822502) (xy 51.561091 -356.860792) (xy 51.554482 -356.937086)
			(xy 51.541332 -357.012529) (xy 51.521737 -357.086559) (xy 51.509168 -357.12273) (xy 51.506515 -357.131166)
			(xy 51.506516 -357.148837) (xy 51.509168 -357.157274) (xy 51.521713 -357.193451) (xy 51.541286 -357.267484)
			(xy 51.554433 -357.342924) (xy 51.561057 -357.419214) (xy 51.561492 -357.457502) (xy 51.561112 -357.495561)
			(xy 51.55464 -357.571404) (xy 51.541708 -357.646417) (xy 51.522413 -357.720049) (xy 51.496894 -357.791762)
			(xy 51.481482 -357.826564) (xy 51.478039 -357.834894) (xy 51.476603 -357.852848) (xy 51.478688 -357.861616)
			(xy 51.48981 -357.901814) (xy 51.50538 -357.983758) (xy 51.513227 -358.066799) (xy 51.51374 -358.108504)
			(xy 51.513251 -358.149614) (xy 51.505664 -358.231482) (xy 51.490553 -358.312301) (xy 51.468049 -358.391381)
			(xy 51.438343 -358.468047) (xy 51.401689 -358.541644) (xy 51.3584 -358.611544) (xy 51.308844 -358.677152)
			(xy 51.253446 -358.737906) (xy 51.192678 -358.793289) (xy 51.127058 -358.842827) (xy 51.057146 -358.886099)
			(xy 50.98354 -358.922734) (xy 50.906867 -358.952421) (xy 50.827781 -358.974905) (xy 50.746958 -358.989995)
			(xy 50.665088 -358.997562) (xy 50.623978 -358.998012) (xy 50.585661 -358.99765) (xy 50.509308 -358.991116)
			(xy 50.433801 -358.97803) (xy 50.359702 -358.958488) (xy 50.323496 -358.945942) (xy 50.31518 -358.943356)
			(xy 50.297776 -358.943356) (xy 50.28946 -358.945942) (xy 50.253248 -358.958468) (xy 50.179147 -358.977989)
			(xy 50.103642 -358.991071) (xy 50.027293 -358.997619) (xy 49.988978 -358.998012) (xy 49.950661 -358.99765)
			(xy 49.874308 -358.991116) (xy 49.798801 -358.97803) (xy 49.724702 -358.958488) (xy 49.688496 -358.945942)
			(xy 49.68018 -358.943356) (xy 49.662776 -358.943356) (xy 49.65446 -358.945942) (xy 49.618248 -358.958468)
			(xy 49.544147 -358.977989) (xy 49.468642 -358.991071) (xy 49.392293 -358.997619) (xy 49.353978 -358.998012)
			(xy 49.315661 -358.99765) (xy 49.239308 -358.991116) (xy 49.163801 -358.97803) (xy 49.089702 -358.958488)
			(xy 49.053496 -358.945942) (xy 49.04518 -358.943356) (xy 49.027776 -358.943356) (xy 49.01946 -358.945942)
			(xy 48.983339 -358.95844) (xy 48.909426 -358.977928) (xy 48.834115 -358.99101) (xy 48.757959 -358.99759)
			(xy 48.71974 -358.998012) (xy 48.718978 -358.998012) (xy 48.677876 -358.99753) (xy 48.596022 -358.989953)
			(xy 48.515216 -358.974857) (xy 48.436148 -358.95237) (xy 48.359491 -358.922685) (xy 48.322484 -358.904794)
			(xy 48.311662 -358.900089) (xy 48.288094 -358.900089) (xy 48.277272 -358.904794) (xy 48.240271 -358.922698)
			(xy 48.163612 -358.952379) (xy 48.084542 -358.974864) (xy 48.003735 -358.98996) (xy 47.92188 -358.997539)
			(xy 47.880778 -358.998012) (xy 47.839669 -358.997608) (xy 47.757803 -358.990022) (xy 47.676986 -358.974915)
			(xy 47.597907 -358.952416) (xy 47.52124 -358.922719) (xy 47.447641 -358.886075) (xy 47.377735 -358.842798)
			(xy 47.312121 -358.793256) (xy 47.251356 -358.737873) (xy 47.19596 -358.677119) (xy 47.146405 -358.611515)
			(xy 47.103114 -358.541618) (xy 47.066455 -358.468026) (xy 47.036742 -358.391366) (xy 47.014227 -358.312292)
			(xy 46.999104 -358.231477) (xy 46.9915 -358.149612) (xy 46.991016 -358.108504) (xy 44.837736 -358.108504)
			(xy 44.834097 -358.122388) (xy 44.808571 -358.1941) (xy 44.793154 -358.2289) (xy 44.789778 -358.237249)
			(xy 44.788481 -358.255202) (xy 44.790614 -358.263952) (xy 44.801704 -358.304153) (xy 44.817195 -358.386101)
			(xy 44.82495 -358.46914) (xy 44.825412 -358.51084) (xy 44.824852 -358.556303) (xy 44.815599 -358.646758)
			(xy 44.797171 -358.735798) (xy 44.78401 -358.779318) (xy 44.78146 -358.788893) (xy 44.783017 -358.808626)
			(xy 44.787058 -358.817672) (xy 44.805431 -358.855048) (xy 44.835897 -358.932566) (xy 44.858991 -359.012591)
			(xy 44.87451 -359.094423) (xy 44.882318 -359.177347) (xy 44.882816 -359.218992) (xy 44.882816 -359.219246)
			(xy 44.882312 -359.261594) (xy 44.874261 -359.345908) (xy 44.858232 -359.429074) (xy 44.834371 -359.510341)
			(xy 44.802892 -359.588971) (xy 44.764081 -359.664252) (xy 44.718291 -359.735504) (xy 44.665935 -359.80208)
			(xy 44.607487 -359.863378) (xy 44.543477 -359.918843) (xy 44.474485 -359.967972) (xy 44.401135 -360.010321)
			(xy 44.324092 -360.045505) (xy 44.244053 -360.073207) (xy 44.161744 -360.093175) (xy 44.077909 -360.105228)
			(xy 43.993308 -360.109259) (xy 43.908707 -360.105228) (xy 43.824872 -360.093175) (xy 43.742563 -360.073207)
			(xy 43.662524 -360.045505) (xy 43.585481 -360.010321) (xy 43.512131 -359.967972) (xy 43.443139 -359.918843)
			(xy 43.379129 -359.863378) (xy 43.320681 -359.80208) (xy 43.268325 -359.735504) (xy 43.222535 -359.664252)
			(xy 43.183724 -359.588971) (xy 43.152245 -359.510341) (xy 43.128384 -359.429074) (xy 43.112355 -359.345908)
			(xy 43.104304 -359.261594) (xy 43.1038 -359.219246) (xy 43.104356 -359.173782) (xy 43.113611 -359.083328)
			(xy 43.13204 -358.994288) (xy 43.145202 -358.950768) (xy 43.147759 -358.941194) (xy 43.146197 -358.921461)
			(xy 43.142154 -358.912414) (xy 43.123767 -358.875016) (xy 43.093286 -358.797449) (xy 43.070189 -358.717372)
			(xy 43.054676 -358.635487) (xy 43.046883 -358.552511) (xy 43.046396 -358.51084) (xy 42.259032 -358.51084)
			(xy 42.259504 -358.549194) (xy 42.258889 -358.594663) (xy 42.249552 -358.685121) (xy 42.231047 -358.774157)
			(xy 42.217848 -358.817672) (xy 42.215273 -358.827242) (xy 42.216849 -358.846979) (xy 42.220896 -358.856026)
			(xy 42.239309 -358.893418) (xy 42.269845 -358.970977) (xy 42.292996 -359.051051) (xy 42.308559 -359.132939)
			(xy 42.316398 -359.215923) (xy 42.316908 -359.2576) (xy 42.316404 -359.299961) (xy 42.308351 -359.384298)
			(xy 42.292317 -359.467488) (xy 42.268449 -359.548778) (xy 42.236961 -359.62743) (xy 42.198139 -359.702733)
			(xy 42.152336 -359.774005) (xy 42.099965 -359.840601) (xy 42.0415 -359.901916) (xy 41.977472 -359.957397)
			(xy 41.90846 -360.00654) (xy 41.83509 -360.0489) (xy 41.758025 -360.084095) (xy 41.677963 -360.111804)
			(xy 41.59563 -360.131778) (xy 41.511771 -360.143835) (xy 41.427146 -360.147867) (xy 41.342521 -360.143835)
			(xy 41.258662 -360.131778) (xy 41.176329 -360.111804) (xy 41.096267 -360.084095) (xy 41.019202 -360.0489)
			(xy 40.945832 -360.00654) (xy 40.87682 -359.957397) (xy 40.812792 -359.901916) (xy 40.754327 -359.840601)
			(xy 40.701956 -359.774005) (xy 40.656153 -359.702733) (xy 40.617331 -359.62743) (xy 40.585843 -359.548778)
			(xy 40.561975 -359.467488) (xy 40.545941 -359.384298) (xy 40.537888 -359.299961) (xy 40.537384 -359.2576)
			(xy 40.537998 -359.212131) (xy 40.547335 -359.121673) (xy 40.565841 -359.032637) (xy 40.57904 -358.989122)
			(xy 40.581619 -358.979553) (xy 40.580041 -358.959815) (xy 40.575992 -358.950768) (xy 40.557613 -358.91336)
			(xy 40.527071 -358.835806) (xy 40.503913 -358.755736) (xy 40.488342 -358.673851) (xy 40.480494 -358.59087)
			(xy 40.47998 -358.549194) (xy 15.414336 -358.549194) (xy 15.373293 -358.597004) (xy 15.317311 -358.650219)
			(xy 15.256232 -358.697498) (xy 15.190684 -358.738354) (xy 15.121338 -358.77237) (xy 15.048907 -358.799195)
			(xy 14.974134 -358.818555) (xy 14.897786 -358.830251) (xy 14.820646 -358.834164) (xy 14.743506 -358.830251)
			(xy 14.667158 -358.818555) (xy 14.592385 -358.799195) (xy 14.519954 -358.77237) (xy 14.450608 -358.738354)
			(xy 14.38506 -358.697498) (xy 14.323981 -358.650219) (xy 14.267999 -358.597004) (xy 14.217688 -358.538398)
			(xy 14.173564 -358.475004) (xy 14.136079 -358.40747) (xy 14.10562 -358.336491) (xy 14.082497 -358.262794)
			(xy 14.066949 -358.187136) (xy 14.059135 -358.110293) (xy 14.058646 -358.071674) (xy 3.523996 -358.071674)
			(xy 3.523996 -361.825848) (xy 5.986007 -361.825848) (xy 5.986007 -361.696708) (xy 5.993957 -361.567813)
			(xy 6.009827 -361.439653) (xy 6.033556 -361.312712) (xy 6.065055 -361.187473) (xy 6.104204 -361.06441)
			(xy 6.150855 -360.943991) (xy 6.20483 -360.826672) (xy 6.265925 -360.712898) (xy 6.333908 -360.603101)
			(xy 6.408522 -360.497698) (xy 6.489483 -360.397088) (xy 6.576483 -360.301653) (xy 6.669194 -360.211754)
			(xy 6.767264 -360.127733) (xy 6.870319 -360.049909) (xy 6.97797 -359.978577) (xy 7.089809 -359.914007)
			(xy 7.20541 -359.856445) (xy 7.324335 -359.806108) (xy 7.446134 -359.763188) (xy 7.570344 -359.727847)
			(xy 7.696493 -359.70022) (xy 7.824105 -359.680411) (xy 7.952694 -359.668495) (xy 8.081772 -359.664519)
			(xy 8.21085 -359.668495) (xy 8.339439 -359.680411) (xy 8.467051 -359.70022) (xy 8.5932 -359.727847)
			(xy 8.71741 -359.763188) (xy 8.839209 -359.806108) (xy 8.958134 -359.856445) (xy 9.073735 -359.914007)
			(xy 9.185574 -359.978577) (xy 9.293225 -360.049909) (xy 9.39628 -360.127733) (xy 9.49435 -360.211754)
			(xy 9.587061 -360.301653) (xy 9.674061 -360.397088) (xy 9.689764 -360.416602) (xy 12.16152 -360.416602)
			(xy 12.162106 -360.37391) (xy 12.17165 -360.289062) (xy 12.190606 -360.205809) (xy 12.218739 -360.125194)
			(xy 12.255695 -360.048223) (xy 12.277852 -360.011726) (xy 12.282563 -360.003469) (xy 12.286088 -359.984802)
			(xy 12.282564 -359.966135) (xy 12.277852 -359.957878) (xy 12.25566 -359.9214) (xy 12.218681 -359.844434)
			(xy 12.190544 -359.763815) (xy 12.171603 -359.680554) (xy 12.162095 -359.595696) (xy 12.16152 -359.553002)
			(xy 12.162009 -359.514383) (xy 12.169823 -359.43754) (xy 12.185371 -359.361882) (xy 12.208494 -359.288185)
			(xy 12.238953 -359.217206) (xy 12.276438 -359.149672) (xy 12.320562 -359.086278) (xy 12.370873 -359.027672)
			(xy 12.426855 -358.974457) (xy 12.487934 -358.927178) (xy 12.553482 -358.886322) (xy 12.622828 -358.852306)
			(xy 12.695259 -358.825481) (xy 12.770032 -358.806121) (xy 12.84638 -358.794425) (xy 12.92352 -358.790513)
			(xy 13.00066 -358.794425) (xy 13.077008 -358.806121) (xy 13.151781 -358.825481) (xy 13.224212 -358.852306)
			(xy 13.293558 -358.886322) (xy 13.359106 -358.927178) (xy 13.420185 -358.974457) (xy 13.476167 -359.027672)
			(xy 13.526478 -359.086278) (xy 13.570602 -359.149672) (xy 13.608087 -359.217206) (xy 13.638546 -359.288185)
			(xy 13.661669 -359.361882) (xy 13.677217 -359.43754) (xy 13.685031 -359.514383) (xy 13.68552 -359.553002)
			(xy 13.68493 -359.595693) (xy 13.675386 -359.680542) (xy 13.65643 -359.763794) (xy 13.628299 -359.84441)
			(xy 13.591344 -359.921381) (xy 13.569188 -359.957878) (xy 13.564471 -359.966133) (xy 13.560944 -359.984802)
			(xy 13.564473 -360.00347) (xy 13.569188 -360.011726) (xy 13.591375 -360.048207) (xy 13.628356 -360.125171)
			(xy 13.656495 -360.20579) (xy 13.675437 -360.289051) (xy 13.684946 -360.373908) (xy 13.68552 -360.416602)
			(xy 13.685031 -360.455221) (xy 13.677217 -360.532064) (xy 13.661669 -360.607722) (xy 13.638546 -360.681419)
			(xy 13.608087 -360.752398) (xy 13.570602 -360.819932) (xy 13.526478 -360.883326) (xy 13.476167 -360.941932)
			(xy 13.420185 -360.995147) (xy 13.408614 -361.004104) (xy 165.274244 -361.004104) (xy 165.274705 -360.976833)
			(xy 165.282467 -360.922846) (xy 165.297833 -360.870512) (xy 165.320491 -360.820899) (xy 165.349978 -360.775015)
			(xy 165.385696 -360.733795) (xy 165.426917 -360.698077) (xy 165.472801 -360.66859) (xy 165.522414 -360.645932)
			(xy 165.574748 -360.630567) (xy 165.628735 -360.622805) (xy 165.656006 -360.622342) (xy 165.684126 -360.622865)
			(xy 165.73976 -360.631099) (xy 165.793585 -360.647402) (xy 165.844437 -360.671422) (xy 165.891217 -360.702641)
			(xy 165.932913 -360.740382) (xy 165.951154 -360.761788) (xy 165.958392 -360.769809) (xy 165.977727 -360.779407)
			(xy 165.988492 -360.78033) (xy 166.02007 -360.775345) (xy 166.083779 -360.77) (xy 166.115746 -360.769662)
			(xy 166.155707 -360.770163) (xy 166.23519 -360.778522) (xy 166.313364 -360.795142) (xy 166.389373 -360.819842)
			(xy 166.462383 -360.852352) (xy 166.531596 -360.892315) (xy 166.596253 -360.939293) (xy 166.655645 -360.992772)
			(xy 166.709122 -361.052166) (xy 166.756098 -361.116824) (xy 166.796059 -361.186038) (xy 166.828566 -361.25905)
			(xy 166.853264 -361.335059) (xy 166.869882 -361.413234) (xy 166.878238 -361.492717) (xy 166.878762 -361.532678)
			(xy 166.87832 -361.568975) (xy 166.871429 -361.641242) (xy 166.857707 -361.712528) (xy 166.837279 -361.782189)
			(xy 166.810328 -361.849596) (xy 166.777099 -361.914139) (xy 166.757858 -361.94492) (xy 166.754213 -361.956147)
			(xy 166.756619 -361.979602) (xy 166.76243 -361.989878) (xy 166.784742 -362.026484) (xy 166.821943 -362.103722)
			(xy 166.850262 -362.184641) (xy 166.861755 -362.234988) (xy 185.144664 -362.234988) (xy 185.144664 -362.23448)
			(xy 185.145268 -362.188148) (xy 185.154941 -362.09599) (xy 185.174137 -362.005336) (xy 185.202649 -361.917167)
			(xy 185.220864 -361.874562) (xy 185.224678 -361.864622) (xy 185.224673 -361.843356) (xy 185.220864 -361.833414)
			(xy 185.202614 -361.790754) (xy 185.174071 -361.702461) (xy 185.15488 -361.611675) (xy 185.145248 -361.519384)
			(xy 185.144664 -361.472988) (xy 185.145245 -361.426592) (xy 185.154891 -361.334304) (xy 185.174088 -361.24352)
			(xy 185.202626 -361.155227) (xy 185.220864 -361.112562) (xy 185.224678 -361.102622) (xy 185.224673 -361.081356)
			(xy 185.220864 -361.071414) (xy 185.202636 -361.028813) (xy 185.17412 -360.940645) (xy 185.154929 -360.849989)
			(xy 185.145271 -360.757828) (xy 185.144664 -360.711496) (xy 185.144664 -360.710988) (xy 185.145155 -360.669886)
			(xy 185.152741 -360.588033) (xy 185.167846 -360.507229) (xy 185.190343 -360.428164) (xy 185.220039 -360.351511)
			(xy 185.25668 -360.277925) (xy 185.299955 -360.208034) (xy 185.349493 -360.142434) (xy 185.404873 -360.081684)
			(xy 185.465622 -360.026303) (xy 185.531221 -359.976764) (xy 185.601111 -359.933488) (xy 185.674696 -359.896845)
			(xy 185.751348 -359.867148) (xy 185.830414 -359.84465) (xy 185.911217 -359.829543) (xy 185.99307 -359.821956)
			(xy 186.034172 -359.82148) (xy 186.03468 -359.82148) (xy 186.081011 -359.822097) (xy 186.173169 -359.831765)
			(xy 186.263823 -359.850958) (xy 186.351992 -359.879466) (xy 186.394598 -359.89768) (xy 186.40454 -359.901486)
			(xy 186.425804 -359.901486) (xy 186.435746 -359.89768) (xy 186.478352 -359.879466) (xy 186.566519 -359.850947)
			(xy 186.657173 -359.831752) (xy 186.749332 -359.822089) (xy 186.795664 -359.82148) (xy 186.796172 -359.82148)
			(xy 186.837274 -359.821979) (xy 186.919129 -359.829561) (xy 186.999934 -359.844664) (xy 187.079001 -359.867158)
			(xy 187.155656 -359.896852) (xy 187.229243 -359.933492) (xy 187.299136 -359.976765) (xy 187.364738 -360.026303)
			(xy 187.425489 -360.081682) (xy 187.480872 -360.142431) (xy 187.530412 -360.208031) (xy 187.573689 -360.277922)
			(xy 187.610332 -360.351508) (xy 187.640029 -360.428161) (xy 187.662527 -360.507227) (xy 187.677633 -360.588032)
			(xy 187.685219 -360.669886) (xy 187.68568 -360.710988) (xy 187.68568 -360.711496) (xy 187.685072 -360.757828)
			(xy 187.675402 -360.849986) (xy 187.673919 -360.856991) (xy 209.35746 -360.856991) (xy 209.35746 -360.671157)
			(xy 209.365455 -360.485494) (xy 209.38143 -360.300348) (xy 209.405356 -360.11606) (xy 209.437188 -359.932972)
			(xy 209.476868 -359.751423) (xy 209.524321 -359.571749) (xy 209.579461 -359.394283) (xy 209.642184 -359.219354)
			(xy 209.712375 -359.047285) (xy 209.789904 -358.878396) (xy 209.874627 -358.712998) (xy 209.966388 -358.551398)
			(xy 210.065016 -358.393896) (xy 210.170329 -358.240782) (xy 210.282131 -358.092342) (xy 210.400216 -357.948848)
			(xy 210.524366 -357.810568) (xy 210.654349 -357.677757) (xy 210.789926 -357.550661) (xy 210.930846 -357.429516)
			(xy 211.076846 -357.314545) (xy 211.227658 -357.205962) (xy 211.383002 -357.103969) (xy 211.54259 -357.008752)
			(xy 211.706127 -356.92049) (xy 211.873309 -356.839345) (xy 212.043828 -356.765468) (xy 212.217367 -356.698995)
			(xy 212.393606 -356.64005) (xy 212.572217 -356.588742) (xy 212.75287 -356.545165) (xy 212.935231 -356.509401)
			(xy 213.118961 -356.481515) (xy 213.303721 -356.46156) (xy 213.489168 -356.449572) (xy 213.67496 -356.445574)
			(xy 213.860752 -356.449572) (xy 214.046199 -356.46156) (xy 214.230959 -356.481515) (xy 214.414689 -356.509401)
			(xy 214.59705 -356.545165) (xy 214.777703 -356.588742) (xy 214.956314 -356.64005) (xy 215.132553 -356.698995)
			(xy 215.306092 -356.765468) (xy 215.476611 -356.839345) (xy 215.643793 -356.92049) (xy 215.80733 -357.008752)
			(xy 215.966918 -357.103969) (xy 216.122262 -357.205962) (xy 216.273074 -357.314545) (xy 216.419074 -357.429516)
			(xy 216.559994 -357.550661) (xy 216.695571 -357.677757) (xy 216.825554 -357.810568) (xy 216.949704 -357.948848)
			(xy 217.067789 -358.092342) (xy 217.179591 -358.240782) (xy 217.284904 -358.393896) (xy 217.383532 -358.551398)
			(xy 217.475293 -358.712998) (xy 217.560016 -358.878396) (xy 217.637545 -359.047285) (xy 217.707736 -359.219354)
			(xy 217.770459 -359.394283) (xy 217.825599 -359.571749) (xy 217.873052 -359.751423) (xy 217.912732 -359.932972)
			(xy 217.944564 -360.11606) (xy 217.96849 -360.300348) (xy 217.984465 -360.485494) (xy 217.99246 -360.671157)
			(xy 217.99296 -360.764074) (xy 217.99246 -360.856991) (xy 253.80746 -360.856991) (xy 253.80746 -360.671157)
			(xy 253.815455 -360.485494) (xy 253.83143 -360.300348) (xy 253.855356 -360.11606) (xy 253.887188 -359.932972)
			(xy 253.926868 -359.751423) (xy 253.974321 -359.571749) (xy 254.029461 -359.394283) (xy 254.092184 -359.219354)
			(xy 254.162375 -359.047285) (xy 254.239904 -358.878396) (xy 254.324627 -358.712998) (xy 254.416388 -358.551398)
			(xy 254.515016 -358.393896) (xy 254.620329 -358.240782) (xy 254.732131 -358.092342) (xy 254.850216 -357.948848)
			(xy 254.974366 -357.810568) (xy 255.104349 -357.677757) (xy 255.239926 -357.550661) (xy 255.380846 -357.429516)
			(xy 255.526846 -357.314545) (xy 255.677658 -357.205962) (xy 255.833002 -357.103969) (xy 255.99259 -357.008752)
			(xy 256.156127 -356.92049) (xy 256.323309 -356.839345) (xy 256.493828 -356.765468) (xy 256.667367 -356.698995)
			(xy 256.843606 -356.64005) (xy 257.022217 -356.588742) (xy 257.20287 -356.545165) (xy 257.385231 -356.509401)
			(xy 257.568961 -356.481515) (xy 257.753721 -356.46156) (xy 257.939168 -356.449572) (xy 258.12496 -356.445574)
			(xy 258.310752 -356.449572) (xy 258.496199 -356.46156) (xy 258.680959 -356.481515) (xy 258.864689 -356.509401)
			(xy 259.04705 -356.545165) (xy 259.227703 -356.588742) (xy 259.406314 -356.64005) (xy 259.582553 -356.698995)
			(xy 259.756092 -356.765468) (xy 259.926611 -356.839345) (xy 260.093793 -356.92049) (xy 260.25733 -357.008752)
			(xy 260.416918 -357.103969) (xy 260.572262 -357.205962) (xy 260.723074 -357.314545) (xy 260.869074 -357.429516)
			(xy 261.009994 -357.550661) (xy 261.145571 -357.677757) (xy 261.275554 -357.810568) (xy 261.399704 -357.948848)
			(xy 261.517789 -358.092342) (xy 261.629591 -358.240782) (xy 261.734904 -358.393896) (xy 261.833532 -358.551398)
			(xy 261.925293 -358.712998) (xy 261.95432 -358.769666) (xy 294.901627 -358.769666) (xy 294.905632 -358.663917)
			(xy 294.917622 -358.558774) (xy 294.937531 -358.454839) (xy 294.965242 -358.352707) (xy 295.000599 -358.252963)
			(xy 295.043397 -358.156179) (xy 295.093393 -358.062909) (xy 295.1503 -357.973688) (xy 295.213791 -357.889025)
			(xy 295.283503 -357.809407) (xy 295.359037 -357.735289) (xy 295.43996 -357.667096) (xy 295.525809 -357.605218)
			(xy 295.616092 -357.550011) (xy 295.710291 -357.501789) (xy 295.807868 -357.460829) (xy 295.908263 -357.427367)
			(xy 296.010901 -357.401593) (xy 296.115194 -357.383655) (xy 296.220545 -357.373656) (xy 296.326351 -357.371653)
			(xy 296.432005 -357.377658) (xy 296.536902 -357.391637) (xy 296.640442 -357.413508) (xy 296.742031 -357.443148)
			(xy 296.841088 -357.480386) (xy 296.937045 -357.525008) (xy 297.029352 -357.57676) (xy 297.117481 -357.635345)
			(xy 297.200927 -357.700427) (xy 297.279211 -357.771633) (xy 297.351886 -357.848556) (xy 297.418536 -357.930756)
			(xy 297.478778 -358.01776) (xy 297.532267 -358.109071) (xy 297.578698 -358.204166) (xy 297.617803 -358.3025)
			(xy 297.64936 -358.403511) (xy 297.673187 -358.506618) (xy 297.689148 -358.611232) (xy 297.697152 -358.716754)
			(xy 297.697652 -358.769666) (xy 297.697152 -358.822578) (xy 297.689148 -358.9281) (xy 297.673187 -359.032714)
			(xy 297.64936 -359.135821) (xy 297.617803 -359.236832) (xy 297.578698 -359.335166) (xy 297.532267 -359.430261)
			(xy 297.478778 -359.521572) (xy 297.418536 -359.608576) (xy 297.351886 -359.690776) (xy 297.279211 -359.767699)
			(xy 297.200927 -359.838905) (xy 297.117481 -359.903987) (xy 297.029352 -359.962572) (xy 296.937045 -360.014324)
			(xy 296.841088 -360.058946) (xy 296.742031 -360.096184) (xy 296.640442 -360.125824) (xy 296.536902 -360.147695)
			(xy 296.432005 -360.161674) (xy 296.326351 -360.167679) (xy 296.220545 -360.165676) (xy 296.115194 -360.155677)
			(xy 296.010901 -360.137739) (xy 295.908263 -360.111965) (xy 295.807868 -360.078503) (xy 295.710291 -360.037543)
			(xy 295.616092 -359.989321) (xy 295.525809 -359.934114) (xy 295.43996 -359.872236) (xy 295.359037 -359.804043)
			(xy 295.283503 -359.729925) (xy 295.213791 -359.650307) (xy 295.1503 -359.565644) (xy 295.093393 -359.476423)
			(xy 295.043397 -359.383153) (xy 295.000599 -359.286369) (xy 294.965242 -359.186625) (xy 294.937531 -359.084493)
			(xy 294.917622 -358.980558) (xy 294.905632 -358.875415) (xy 294.901627 -358.769666) (xy 261.95432 -358.769666)
			(xy 262.010016 -358.878396) (xy 262.087545 -359.047285) (xy 262.157736 -359.219354) (xy 262.220459 -359.394283)
			(xy 262.275599 -359.571749) (xy 262.323052 -359.751423) (xy 262.362732 -359.932972) (xy 262.394564 -360.11606)
			(xy 262.41849 -360.300348) (xy 262.434465 -360.485494) (xy 262.44246 -360.671157) (xy 262.44296 -360.764074)
			(xy 262.44246 -360.856991) (xy 262.434465 -361.042654) (xy 262.41849 -361.2278) (xy 262.394564 -361.412088)
			(xy 262.362732 -361.595176) (xy 262.323052 -361.776725) (xy 262.309556 -361.827826) (xy 430.615097 -361.827826)
			(xy 430.619102 -361.722077) (xy 430.631092 -361.616934) (xy 430.651001 -361.512999) (xy 430.678712 -361.410867)
			(xy 430.714069 -361.311123) (xy 430.756867 -361.214339) (xy 430.806863 -361.121069) (xy 430.86377 -361.031848)
			(xy 430.927261 -360.947185) (xy 430.996973 -360.867567) (xy 431.072507 -360.793449) (xy 431.15343 -360.725256)
			(xy 431.239279 -360.663378) (xy 431.329562 -360.608171) (xy 431.423761 -360.559949) (xy 431.521338 -360.518989)
			(xy 431.621733 -360.485527) (xy 431.724371 -360.459753) (xy 431.828664 -360.441815) (xy 431.934015 -360.431816)
			(xy 432.039821 -360.429813) (xy 432.145475 -360.435818) (xy 432.250372 -360.449797) (xy 432.353912 -360.471668)
			(xy 432.455501 -360.501308) (xy 432.554558 -360.538546) (xy 432.650515 -360.583168) (xy 432.742822 -360.63492)
			(xy 432.830951 -360.693505) (xy 432.914397 -360.758587) (xy 432.992681 -360.829793) (xy 433.065356 -360.906716)
			(xy 433.132006 -360.988916) (xy 433.192248 -361.07592) (xy 433.245737 -361.167231) (xy 433.292168 -361.262326)
			(xy 433.331273 -361.36066) (xy 433.36283 -361.461671) (xy 433.370787 -361.496102) (xy 434.579776 -361.496102)
			(xy 434.580404 -361.4497) (xy 434.590093 -361.357403) (xy 434.609347 -361.266617) (xy 434.637954 -361.178332)
			(xy 434.65623 -361.135676) (xy 434.660038 -361.125734) (xy 434.660039 -361.10447) (xy 434.65623 -361.094528)
			(xy 434.637968 -361.051867) (xy 434.609375 -360.963579) (xy 434.590118 -360.872796) (xy 434.580405 -360.780503)
			(xy 434.579776 -360.734102) (xy 434.580404 -360.6877) (xy 434.590093 -360.595403) (xy 434.609347 -360.504617)
			(xy 434.637954 -360.416332) (xy 434.65623 -360.373676) (xy 434.660038 -360.363734) (xy 434.660039 -360.34247)
			(xy 434.65623 -360.332528) (xy 434.637968 -360.289867) (xy 434.609375 -360.201579) (xy 434.590118 -360.110796)
			(xy 434.580405 -360.018503) (xy 434.579776 -359.972102) (xy 434.5802 -359.930986) (xy 434.587788 -359.849105)
			(xy 434.602898 -359.768273) (xy 434.625402 -359.68918) (xy 434.655109 -359.612502) (xy 434.691763 -359.538891)
			(xy 434.735054 -359.468977) (xy 434.784611 -359.403355) (xy 434.840011 -359.342586) (xy 434.900783 -359.287188)
			(xy 434.966406 -359.237634) (xy 435.036323 -359.194346) (xy 435.109935 -359.157694) (xy 435.186615 -359.127991)
			(xy 435.265708 -359.10549) (xy 435.346541 -359.090383) (xy 435.428422 -359.082799) (xy 435.469538 -359.08234)
			(xy 435.51594 -359.082957) (xy 435.608238 -359.09265) (xy 435.699023 -359.111907) (xy 435.787308 -359.140517)
			(xy 435.829964 -359.158794) (xy 435.839906 -359.1626) (xy 435.86117 -359.1626) (xy 435.871112 -359.158794)
			(xy 435.913767 -359.140517) (xy 436.002057 -359.111928) (xy 436.092842 -359.092675) (xy 436.185137 -359.082967)
			(xy 436.231538 -359.08234) (xy 436.272653 -359.082777) (xy 436.354532 -359.090367) (xy 436.435361 -359.10548)
			(xy 436.514451 -359.127986) (xy 436.591127 -359.157693) (xy 436.664735 -359.194349) (xy 436.734647 -359.237639)
			(xy 436.800266 -359.287195) (xy 436.861034 -359.342595) (xy 436.91643 -359.403364) (xy 436.965984 -359.468986)
			(xy 437.009271 -359.5389) (xy 437.045923 -359.61251) (xy 437.075627 -359.689187) (xy 437.098129 -359.768278)
			(xy 437.113238 -359.849108) (xy 437.120825 -359.930987) (xy 437.1213 -359.972102) (xy 437.120676 -360.018504)
			(xy 437.110985 -360.110802) (xy 437.091731 -360.201587) (xy 437.063122 -360.289872) (xy 437.044846 -360.332528)
			(xy 437.041037 -360.34247) (xy 437.041038 -360.363734) (xy 437.044846 -360.373676) (xy 437.063108 -360.416337)
			(xy 437.091701 -360.504625) (xy 437.110959 -360.595408) (xy 437.120671 -360.687701) (xy 437.1213 -360.734102)
			(xy 437.120676 -360.780504) (xy 437.110985 -360.872802) (xy 437.091731 -360.963587) (xy 437.063122 -361.051872)
			(xy 437.044846 -361.094528) (xy 437.041037 -361.10447) (xy 437.041038 -361.125734) (xy 437.044846 -361.135676)
			(xy 437.063108 -361.178337) (xy 437.091701 -361.266625) (xy 437.110959 -361.357408) (xy 437.120671 -361.449701)
			(xy 437.1213 -361.496102) (xy 437.120789 -361.537215) (xy 437.113202 -361.619091) (xy 437.098093 -361.699917)
			(xy 437.075592 -361.779004) (xy 437.045889 -361.855678) (xy 437.009238 -361.929285) (xy 436.965952 -361.999196)
			(xy 436.916401 -362.064814) (xy 436.861007 -362.125581) (xy 436.800242 -362.180978) (xy 436.734625 -362.230532)
			(xy 436.664716 -362.273821) (xy 436.591111 -362.310474) (xy 436.514439 -362.34018) (xy 436.435352 -362.362685)
			(xy 436.354526 -362.377797) (xy 436.272651 -362.385387) (xy 436.231538 -362.385864) (xy 436.185135 -362.385256)
			(xy 436.092838 -362.37556) (xy 436.002052 -362.356301) (xy 435.913768 -362.327688) (xy 435.871112 -362.30941)
			(xy 435.86117 -362.305604) (xy 435.839906 -362.305604) (xy 435.829964 -362.30941) (xy 435.787299 -362.327662)
			(xy 435.699012 -362.356257) (xy 435.608231 -362.375517) (xy 435.515939 -362.385233) (xy 435.469538 -362.385864)
			(xy 435.428424 -362.385365) (xy 435.346546 -362.377782) (xy 435.265717 -362.362675) (xy 435.186627 -362.340175)
			(xy 435.10995 -362.310473) (xy 435.036341 -362.273823) (xy 434.966428 -362.230538) (xy 434.900807 -362.180986)
			(xy 434.840038 -362.12559) (xy 434.78464 -362.064824) (xy 434.735085 -361.999205) (xy 434.691796 -361.929294)
			(xy 434.655143 -361.855686) (xy 434.625438 -361.779011) (xy 434.602934 -361.699922) (xy 434.587824 -361.619094)
			(xy 434.580237 -361.537216) (xy 434.579776 -361.496102) (xy 433.370787 -361.496102) (xy 433.386657 -361.564778)
			(xy 433.402618 -361.669392) (xy 433.410622 -361.774914) (xy 433.411122 -361.827826) (xy 433.410622 -361.880738)
			(xy 433.402618 -361.98626) (xy 433.386657 -362.090874) (xy 433.36283 -362.193981) (xy 433.331273 -362.294992)
			(xy 433.292168 -362.393326) (xy 433.245737 -362.488421) (xy 433.192248 -362.579732) (xy 433.132006 -362.666736)
			(xy 433.065356 -362.748936) (xy 432.992681 -362.825859) (xy 432.914397 -362.897065) (xy 432.830951 -362.962147)
			(xy 432.742822 -363.020732) (xy 432.650515 -363.072484) (xy 432.554558 -363.117106) (xy 432.455501 -363.154344)
			(xy 432.353912 -363.183984) (xy 432.250372 -363.205855) (xy 432.145475 -363.219834) (xy 432.039821 -363.225839)
			(xy 431.934015 -363.223836) (xy 431.828664 -363.213837) (xy 431.724371 -363.195899) (xy 431.621733 -363.170125)
			(xy 431.521338 -363.136663) (xy 431.423761 -363.095703) (xy 431.329562 -363.047481) (xy 431.239279 -362.992274)
			(xy 431.15343 -362.930396) (xy 431.072507 -362.862203) (xy 430.996973 -362.788085) (xy 430.927261 -362.708467)
			(xy 430.86377 -362.623804) (xy 430.806863 -362.534583) (xy 430.756867 -362.441313) (xy 430.714069 -362.344529)
			(xy 430.678712 -362.244785) (xy 430.651001 -362.142653) (xy 430.631092 -362.038718) (xy 430.619102 -361.933575)
			(xy 430.615097 -361.827826) (xy 262.309556 -361.827826) (xy 262.275599 -361.956399) (xy 262.220459 -362.133865)
			(xy 262.157736 -362.308794) (xy 262.087545 -362.480863) (xy 262.010016 -362.649752) (xy 261.925293 -362.81515)
			(xy 261.833532 -362.97675) (xy 261.734904 -363.134252) (xy 261.629591 -363.287366) (xy 261.517789 -363.435806)
			(xy 261.399704 -363.5793) (xy 261.275554 -363.71758) (xy 261.145571 -363.850391) (xy 261.009994 -363.977487)
			(xy 260.869074 -364.098632) (xy 260.723074 -364.213603) (xy 260.572262 -364.322186) (xy 260.416918 -364.424179)
			(xy 260.25733 -364.519396) (xy 260.093793 -364.607658) (xy 259.926611 -364.688803) (xy 259.756092 -364.76268)
			(xy 259.582553 -364.829153) (xy 259.406314 -364.888098) (xy 259.227703 -364.939406) (xy 259.04705 -364.982983)
			(xy 258.864689 -365.018747) (xy 258.680959 -365.046633) (xy 258.496199 -365.066588) (xy 258.310752 -365.078576)
			(xy 258.12496 -365.082574) (xy 257.939168 -365.078576) (xy 257.753721 -365.066588) (xy 257.568961 -365.046633)
			(xy 257.385231 -365.018747) (xy 257.20287 -364.982983) (xy 257.022217 -364.939406) (xy 256.843606 -364.888098)
			(xy 256.667367 -364.829153) (xy 256.493828 -364.76268) (xy 256.323309 -364.688803) (xy 256.156127 -364.607658)
			(xy 255.99259 -364.519396) (xy 255.833002 -364.424179) (xy 255.677658 -364.322186) (xy 255.526846 -364.213603)
			(xy 255.380846 -364.098632) (xy 255.239926 -363.977487) (xy 255.104349 -363.850391) (xy 254.974366 -363.71758)
			(xy 254.850216 -363.5793) (xy 254.732131 -363.435806) (xy 254.620329 -363.287366) (xy 254.515016 -363.134252)
			(xy 254.416388 -362.97675) (xy 254.324627 -362.81515) (xy 254.239904 -362.649752) (xy 254.162375 -362.480863)
			(xy 254.092184 -362.308794) (xy 254.029461 -362.133865) (xy 253.974321 -361.956399) (xy 253.926868 -361.776725)
			(xy 253.887188 -361.595176) (xy 253.855356 -361.412088) (xy 253.83143 -361.2278) (xy 253.815455 -361.042654)
			(xy 253.80746 -360.856991) (xy 217.99246 -360.856991) (xy 217.984465 -361.042654) (xy 217.96849 -361.2278)
			(xy 217.944564 -361.412088) (xy 217.912732 -361.595176) (xy 217.873052 -361.776725) (xy 217.825599 -361.956399)
			(xy 217.770459 -362.133865) (xy 217.707736 -362.308794) (xy 217.637545 -362.480863) (xy 217.560016 -362.649752)
			(xy 217.475293 -362.81515) (xy 217.383532 -362.97675) (xy 217.284904 -363.134252) (xy 217.179591 -363.287366)
			(xy 217.067789 -363.435806) (xy 216.949704 -363.5793) (xy 216.825554 -363.71758) (xy 216.695571 -363.850391)
			(xy 216.559994 -363.977487) (xy 216.419074 -364.098632) (xy 216.273074 -364.213603) (xy 216.122262 -364.322186)
			(xy 215.966918 -364.424179) (xy 215.80733 -364.519396) (xy 215.643793 -364.607658) (xy 215.476611 -364.688803)
			(xy 215.306092 -364.76268) (xy 215.132553 -364.829153) (xy 214.956314 -364.888098) (xy 214.777703 -364.939406)
			(xy 214.59705 -364.982983) (xy 214.414689 -365.018747) (xy 214.230959 -365.046633) (xy 214.046199 -365.066588)
			(xy 213.860752 -365.078576) (xy 213.67496 -365.082574) (xy 213.489168 -365.078576) (xy 213.303721 -365.066588)
			(xy 213.118961 -365.046633) (xy 212.935231 -365.018747) (xy 212.75287 -364.982983) (xy 212.572217 -364.939406)
			(xy 212.393606 -364.888098) (xy 212.217367 -364.829153) (xy 212.043828 -364.76268) (xy 211.873309 -364.688803)
			(xy 211.706127 -364.607658) (xy 211.54259 -364.519396) (xy 211.383002 -364.424179) (xy 211.227658 -364.322186)
			(xy 211.076846 -364.213603) (xy 210.930846 -364.098632) (xy 210.789926 -363.977487) (xy 210.654349 -363.850391)
			(xy 210.524366 -363.71758) (xy 210.400216 -363.5793) (xy 210.282131 -363.435806) (xy 210.170329 -363.287366)
			(xy 210.065016 -363.134252) (xy 209.966388 -362.97675) (xy 209.874627 -362.81515) (xy 209.789904 -362.649752)
			(xy 209.712375 -362.480863) (xy 209.642184 -362.308794) (xy 209.579461 -362.133865) (xy 209.524321 -361.956399)
			(xy 209.476868 -361.776725) (xy 209.437188 -361.595176) (xy 209.405356 -361.412088) (xy 209.38143 -361.2278)
			(xy 209.365455 -361.042654) (xy 209.35746 -360.856991) (xy 187.673919 -360.856991) (xy 187.656207 -360.94064)
			(xy 187.627695 -361.028809) (xy 187.60948 -361.071414) (xy 187.605683 -361.081359) (xy 187.605679 -361.10262)
			(xy 187.60948 -361.112562) (xy 187.627719 -361.155227) (xy 187.656265 -361.243518) (xy 187.67546 -361.334302)
			(xy 187.685094 -361.426592) (xy 187.68568 -361.472988) (xy 187.685095 -361.519384) (xy 187.675451 -361.611672)
			(xy 187.656256 -361.702456) (xy 187.627718 -361.790749) (xy 187.60948 -361.833414) (xy 187.605683 -361.843359)
			(xy 187.605679 -361.86462) (xy 187.60948 -361.874562) (xy 187.627696 -361.917167) (xy 187.656216 -362.005334)
			(xy 187.67541 -362.095988) (xy 187.685071 -362.188148) (xy 187.68568 -362.23448) (xy 187.68568 -362.234988)
			(xy 187.685236 -362.276092) (xy 187.677652 -362.357949) (xy 187.664078 -362.430568) (xy 190.281567 -362.430568)
			(xy 190.285572 -362.324819) (xy 190.297562 -362.219676) (xy 190.317471 -362.115741) (xy 190.345182 -362.013609)
			(xy 190.380539 -361.913865) (xy 190.423337 -361.817081) (xy 190.473333 -361.723811) (xy 190.53024 -361.63459)
			(xy 190.593731 -361.549927) (xy 190.663443 -361.470309) (xy 190.738977 -361.396191) (xy 190.8199 -361.327998)
			(xy 190.905749 -361.26612) (xy 190.996032 -361.210913) (xy 191.090231 -361.162691) (xy 191.187808 -361.121731)
			(xy 191.288203 -361.088269) (xy 191.390841 -361.062495) (xy 191.495134 -361.044557) (xy 191.600485 -361.034558)
			(xy 191.706291 -361.032555) (xy 191.811945 -361.03856) (xy 191.916842 -361.052539) (xy 192.020382 -361.07441)
			(xy 192.121971 -361.10405) (xy 192.221028 -361.141288) (xy 192.316985 -361.18591) (xy 192.409292 -361.237662)
			(xy 192.497421 -361.296247) (xy 192.580867 -361.361329) (xy 192.659151 -361.432535) (xy 192.731826 -361.509458)
			(xy 192.798476 -361.591658) (xy 192.858718 -361.678662) (xy 192.912207 -361.769973) (xy 192.958638 -361.865068)
			(xy 192.997743 -361.963402) (xy 193.0293 -362.064413) (xy 193.053127 -362.16752) (xy 193.069088 -362.272134)
			(xy 193.077092 -362.377656) (xy 193.077592 -362.430568) (xy 193.077092 -362.48348) (xy 193.069088 -362.589002)
			(xy 193.053127 -362.693616) (xy 193.0293 -362.796723) (xy 192.997743 -362.897734) (xy 192.958638 -362.996068)
			(xy 192.912207 -363.091163) (xy 192.858718 -363.182474) (xy 192.798476 -363.269478) (xy 192.731826 -363.351678)
			(xy 192.659151 -363.428601) (xy 192.580867 -363.499807) (xy 192.497421 -363.564889) (xy 192.409292 -363.623474)
			(xy 192.316985 -363.675226) (xy 192.221028 -363.719848) (xy 192.121971 -363.757086) (xy 192.020382 -363.786726)
			(xy 191.916842 -363.808597) (xy 191.811945 -363.822576) (xy 191.706291 -363.828581) (xy 191.600485 -363.826578)
			(xy 191.495134 -363.816579) (xy 191.390841 -363.798641) (xy 191.288203 -363.772867) (xy 191.187808 -363.739405)
			(xy 191.090231 -363.698445) (xy 190.996032 -363.650223) (xy 190.905749 -363.595016) (xy 190.8199 -363.533138)
			(xy 190.738977 -363.464945) (xy 190.663443 -363.390827) (xy 190.593731 -363.311209) (xy 190.53024 -363.226546)
			(xy 190.473333 -363.137325) (xy 190.423337 -363.044055) (xy 190.380539 -362.947271) (xy 190.345182 -362.847527)
			(xy 190.317471 -362.745395) (xy 190.297562 -362.64146) (xy 190.285572 -362.536317) (xy 190.281567 -362.430568)
			(xy 187.664078 -362.430568) (xy 187.662547 -362.438757) (xy 187.64005 -362.517826) (xy 187.610354 -362.594483)
			(xy 187.573711 -362.668072) (xy 187.530434 -362.737966) (xy 187.480892 -362.803569) (xy 187.425509 -362.86432)
			(xy 187.364756 -362.919703) (xy 187.299153 -362.969243) (xy 187.229258 -363.012519) (xy 187.155668 -363.04916)
			(xy 187.079011 -363.078856) (xy 186.999941 -363.101351) (xy 186.919133 -363.116454) (xy 186.837276 -363.124037)
			(xy 186.796172 -363.124496) (xy 186.795664 -363.124496) (xy 186.749333 -363.123866) (xy 186.657176 -363.114202)
			(xy 186.566521 -363.095013) (xy 186.478352 -363.066508) (xy 186.435746 -363.048296) (xy 186.425804 -363.04449)
			(xy 186.40454 -363.04449) (xy 186.394598 -363.048296) (xy 186.351999 -363.066527) (xy 186.26383 -363.095042)
			(xy 186.173173 -363.114232) (xy 186.081013 -363.123889) (xy 186.03468 -363.124496) (xy 186.034172 -363.124496)
			(xy 185.993069 -363.12406) (xy 185.911213 -363.116473) (xy 185.830407 -363.101365) (xy 185.751339 -363.078866)
			(xy 185.674684 -363.049167) (xy 185.601097 -363.012522) (xy 185.531204 -362.969244) (xy 185.465603 -362.919702)
			(xy 185.404853 -362.864319) (xy 185.349472 -362.803566) (xy 185.299933 -362.737963) (xy 185.256658 -362.668068)
			(xy 185.220017 -362.594479) (xy 185.190322 -362.517823) (xy 185.167826 -362.438755) (xy 185.152722 -362.357947)
			(xy 185.145138 -362.276091) (xy 185.144664 -362.234988) (xy 166.861755 -362.234988) (xy 166.869342 -362.268221)
			(xy 166.878944 -362.353413) (xy 166.879524 -362.396278) (xy 166.879524 -362.396532) (xy 166.879105 -362.432139)
			(xy 166.87247 -362.503043) (xy 166.859253 -362.573019) (xy 166.849806 -362.607352) (xy 166.84764 -362.616108)
			(xy 166.848933 -362.634087) (xy 166.856407 -362.650491) (xy 166.862506 -362.657136) (xy 166.883163 -362.678752)
			(xy 166.918174 -362.727215) (xy 166.945209 -362.780541) (xy 166.963608 -362.837426) (xy 166.972924 -362.896483)
			(xy 166.973504 -362.926376) (xy 166.972953 -362.953643) (xy 166.965196 -363.007622) (xy 166.949836 -363.059948)
			(xy 166.927186 -363.109555) (xy 166.897706 -363.155434) (xy 166.861998 -363.196651) (xy 166.820787 -363.232366)
			(xy 166.774913 -363.261854) (xy 166.72531 -363.284513) (xy 166.672987 -363.299882) (xy 166.619009 -363.307649)
			(xy 166.591742 -363.308138) (xy 166.563429 -363.307673) (xy 166.507424 -363.2993) (xy 166.453275 -363.282732)
			(xy 166.402174 -363.258333) (xy 166.355246 -363.226642) (xy 166.313525 -363.188354) (xy 166.295324 -363.16666)
			(xy 166.289383 -363.159834) (xy 166.273827 -363.150609) (xy 166.25603 -363.147392) (xy 166.247064 -363.148626)
			(xy 166.214498 -363.153977) (xy 166.148746 -363.159698) (xy 166.115746 -363.160056) (xy 166.075745 -363.159529)
			(xy 165.99618 -363.151171) (xy 165.917925 -363.134541) (xy 165.841837 -363.109822) (xy 165.76875 -363.077285)
			(xy 165.699464 -363.037286) (xy 165.63474 -362.990263) (xy 165.575285 -362.936732) (xy 165.521752 -362.877279)
			(xy 165.474727 -362.812556) (xy 165.434726 -362.743272) (xy 165.402187 -362.670186) (xy 165.377465 -362.594098)
			(xy 165.360833 -362.515844) (xy 165.352472 -362.436279) (xy 165.351968 -362.396278) (xy 165.352527 -362.353412)
			(xy 165.36213 -362.268219) (xy 165.381213 -362.184637) (xy 165.409535 -362.103718) (xy 165.446741 -362.026479)
			(xy 165.469062 -361.989878) (xy 165.474834 -361.979597) (xy 165.477199 -361.95616) (xy 165.473634 -361.94492)
			(xy 165.45438 -361.914147) (xy 165.421151 -361.849602) (xy 165.3942 -361.782194) (xy 165.373772 -361.712532)
			(xy 165.36005 -361.641244) (xy 165.353159 -361.568976) (xy 165.35273 -361.532678) (xy 165.353223 -361.493666)
			(xy 165.361175 -361.416048) (xy 165.376995 -361.339644) (xy 165.38829 -361.3023) (xy 165.388907 -361.291485)
			(xy 165.382069 -361.270953) (xy 165.375082 -361.262676) (xy 165.356243 -361.241395) (xy 165.324384 -361.19433)
			(xy 165.299852 -361.143063) (xy 165.28319 -361.088727) (xy 165.274766 -361.032521) (xy 165.274244 -361.004104)
			(xy 13.408614 -361.004104) (xy 13.359106 -361.042426) (xy 13.293558 -361.083282) (xy 13.224212 -361.117298)
			(xy 13.151781 -361.144123) (xy 13.077008 -361.163483) (xy 13.00066 -361.175179) (xy 12.92352 -361.179092)
			(xy 12.84638 -361.175179) (xy 12.770032 -361.163483) (xy 12.695259 -361.144123) (xy 12.622828 -361.117298)
			(xy 12.553482 -361.083282) (xy 12.487934 -361.042426) (xy 12.426855 -360.995147) (xy 12.370873 -360.941932)
			(xy 12.320562 -360.883326) (xy 12.276438 -360.819932) (xy 12.238953 -360.752398) (xy 12.208494 -360.681419)
			(xy 12.185371 -360.607722) (xy 12.169823 -360.532064) (xy 12.162009 -360.455221) (xy 12.16152 -360.416602)
			(xy 9.689764 -360.416602) (xy 9.755022 -360.497698) (xy 9.829636 -360.603101) (xy 9.897619 -360.712898)
			(xy 9.958714 -360.826672) (xy 10.012689 -360.943991) (xy 10.05934 -361.06441) (xy 10.098489 -361.187473)
			(xy 10.129988 -361.312712) (xy 10.153717 -361.439653) (xy 10.169587 -361.567813) (xy 10.177537 -361.696708)
			(xy 10.178034 -361.761278) (xy 10.177537 -361.825848) (xy 10.169587 -361.954743) (xy 10.153717 -362.082903)
			(xy 10.129988 -362.209844) (xy 10.098489 -362.335083) (xy 10.05934 -362.458146) (xy 10.012689 -362.578565)
			(xy 9.958714 -362.695884) (xy 9.897619 -362.809658) (xy 9.829636 -362.919455) (xy 9.755022 -363.024858)
			(xy 9.674061 -363.125468) (xy 9.587061 -363.220903) (xy 9.49435 -363.310802) (xy 9.39628 -363.394823)
			(xy 9.293225 -363.472647) (xy 9.185574 -363.543979) (xy 9.073735 -363.608549) (xy 8.958134 -363.666111)
			(xy 8.839209 -363.716448) (xy 8.71741 -363.759368) (xy 8.5932 -363.794709) (xy 8.467051 -363.822336)
			(xy 8.339439 -363.842145) (xy 8.21085 -363.854061) (xy 8.081772 -363.858038) (xy 7.952694 -363.854061)
			(xy 7.824105 -363.842145) (xy 7.696493 -363.822336) (xy 7.570344 -363.794709) (xy 7.446134 -363.759368)
			(xy 7.324335 -363.716448) (xy 7.20541 -363.666111) (xy 7.089809 -363.608549) (xy 6.97797 -363.543979)
			(xy 6.870319 -363.472647) (xy 6.767264 -363.394823) (xy 6.669194 -363.310802) (xy 6.576483 -363.220903)
			(xy 6.489483 -363.125468) (xy 6.408522 -363.024858) (xy 6.333908 -362.919455) (xy 6.265925 -362.809658)
			(xy 6.20483 -362.695884) (xy 6.150855 -362.578565) (xy 6.104204 -362.458146) (xy 6.065055 -362.335083)
			(xy 6.033556 -362.209844) (xy 6.009827 -362.082903) (xy 5.993957 -361.954743) (xy 5.986007 -361.825848)
			(xy 3.523996 -361.825848) (xy 3.523996 -369.035302) (xy 43.674419 -369.035302) (xy 43.678313 -368.980888)
			(xy 43.689914 -368.927582) (xy 43.708986 -368.876471) (xy 43.735142 -368.828596) (xy 43.767847 -368.784933)
			(xy 43.806436 -368.746371) (xy 43.850122 -368.713696) (xy 43.898016 -368.687575) (xy 43.94914 -368.668538)
			(xy 44.002454 -368.656974) (xy 44.02963 -368.654584) (xy 44.041631 -368.653099) (xy 44.062306 -368.640609)
			(xy 44.069254 -368.630708) (xy 44.089152 -368.599589) (xy 44.134063 -368.54094) (xy 44.158916 -368.513614)
			(xy 44.164471 -368.507276) (xy 44.171361 -368.491905) (xy 44.172845 -368.475125) (xy 44.171108 -368.466878)
			(xy 44.165861 -368.444255) (xy 44.160259 -368.398151) (xy 44.159932 -368.37493) (xy 44.160429 -368.34766)
			(xy 44.168187 -368.293675) (xy 44.183549 -368.241343) (xy 44.206203 -368.19173) (xy 44.235687 -368.145847)
			(xy 44.271401 -368.104626) (xy 44.312618 -368.068909) (xy 44.358499 -368.03942) (xy 44.408109 -368.016762)
			(xy 44.460439 -368.001395) (xy 44.514424 -367.993632) (xy 44.541694 -367.993168) (xy 44.569174 -367.993593)
			(xy 44.623562 -368.001499) (xy 44.676256 -368.01712) (xy 44.726166 -368.040133) (xy 44.772262 -368.070063)
			(xy 44.813591 -368.106292) (xy 44.8493 -368.148071) (xy 44.878651 -368.194538) (xy 44.901038 -368.244732)
			(xy 44.908978 -368.271044) (xy 44.911606 -368.279121) (xy 44.921273 -368.29307) (xy 44.934988 -368.303067)
			(xy 44.943014 -368.305842) (xy 44.974313 -368.31594) (xy 45.035215 -368.340776) (xy 45.093763 -368.370743)
			(xy 45.12183 -368.387884) (xy 45.130091 -368.39258) (xy 45.148754 -368.396088) (xy 45.167417 -368.39258)
			(xy 45.175678 -368.387884) (xy 45.203735 -368.370723) (xy 45.262276 -368.340739) (xy 45.323185 -368.315914)
			(xy 45.354494 -368.305842) (xy 45.362508 -368.303037) (xy 45.37622 -368.293044) (xy 45.385917 -368.279121)
			(xy 45.38853 -368.271044) (xy 45.396474 -368.244733) (xy 45.418848 -368.194533) (xy 45.448192 -368.148062)
			(xy 45.483898 -368.106281) (xy 45.525229 -368.070055) (xy 45.571328 -368.040131) (xy 45.621244 -368.01713)
			(xy 45.673942 -368.001528) (xy 45.728334 -367.993646) (xy 45.755814 -367.993168) (xy 45.783087 -367.993589)
			(xy 45.837077 -368.001353) (xy 45.889412 -368.016723) (xy 45.939027 -368.039384) (xy 45.984912 -368.068876)
			(xy 46.026133 -368.104598) (xy 46.06185 -368.145823) (xy 46.091337 -368.191711) (xy 46.113992 -368.241329)
			(xy 46.129356 -368.293666) (xy 46.137115 -368.347657) (xy 46.137576 -368.37493) (xy 46.137244 -368.398151)
			(xy 46.131643 -368.444254) (xy 46.1264 -368.466878) (xy 46.124068 -368.47935) (xy 46.130464 -368.503871)
			(xy 46.138592 -368.513614) (xy 46.163456 -368.540931) (xy 46.208369 -368.59958) (xy 46.228254 -368.630708)
			(xy 46.235214 -368.640596) (xy 46.255883 -368.653071) (xy 46.267878 -368.654584) (xy 46.295067 -368.656909)
			(xy 46.348399 -368.668465) (xy 46.399543 -368.687497) (xy 46.447455 -368.713618) (xy 46.491159 -368.746296)
			(xy 46.529764 -368.784865) (xy 46.562484 -368.828537) (xy 46.588651 -368.876424) (xy 46.607732 -368.92755)
			(xy 46.619339 -368.980871) (xy 46.623234 -369.035302) (xy 50.481619 -369.035302) (xy 50.485513 -368.980888)
			(xy 50.497114 -368.927582) (xy 50.516186 -368.876471) (xy 50.542342 -368.828596) (xy 50.575047 -368.784933)
			(xy 50.613636 -368.746371) (xy 50.657322 -368.713696) (xy 50.705216 -368.687575) (xy 50.75634 -368.668538)
			(xy 50.809654 -368.656974) (xy 50.83683 -368.654584) (xy 50.848831 -368.653099) (xy 50.869506 -368.640609)
			(xy 50.876454 -368.630708) (xy 50.896352 -368.599589) (xy 50.941263 -368.54094) (xy 50.966116 -368.513614)
			(xy 50.971671 -368.507276) (xy 50.978561 -368.491905) (xy 50.980045 -368.475125) (xy 50.978308 -368.466878)
			(xy 50.973061 -368.444255) (xy 50.967459 -368.398151) (xy 50.967132 -368.37493) (xy 50.967629 -368.34766)
			(xy 50.975387 -368.293675) (xy 50.990749 -368.241343) (xy 51.013403 -368.19173) (xy 51.042887 -368.145847)
			(xy 51.078601 -368.104626) (xy 51.119818 -368.068909) (xy 51.165699 -368.03942) (xy 51.215309 -368.016762)
			(xy 51.267639 -368.001395) (xy 51.321624 -367.993632) (xy 51.348894 -367.993168) (xy 51.376374 -367.993593)
			(xy 51.430762 -368.001499) (xy 51.483456 -368.01712) (xy 51.533366 -368.040133) (xy 51.579462 -368.070063)
			(xy 51.620791 -368.106292) (xy 51.6565 -368.148071) (xy 51.685851 -368.194538) (xy 51.708238 -368.244732)
			(xy 51.716178 -368.271044) (xy 51.718806 -368.279121) (xy 51.728473 -368.29307) (xy 51.742188 -368.303067)
			(xy 51.750214 -368.305842) (xy 51.781513 -368.31594) (xy 51.842415 -368.340776) (xy 51.900963 -368.370743)
			(xy 51.92903 -368.387884) (xy 51.937291 -368.39258) (xy 51.955954 -368.396088) (xy 51.974617 -368.39258)
			(xy 51.982878 -368.387884) (xy 52.010935 -368.370723) (xy 52.069476 -368.340739) (xy 52.130385 -368.315914)
			(xy 52.161694 -368.305842) (xy 52.169708 -368.303037) (xy 52.18342 -368.293044) (xy 52.193117 -368.279121)
			(xy 52.19573 -368.271044) (xy 52.203674 -368.244733) (xy 52.226048 -368.194533) (xy 52.255392 -368.148062)
			(xy 52.291098 -368.106281) (xy 52.332429 -368.070055) (xy 52.378528 -368.040131) (xy 52.428444 -368.01713)
			(xy 52.481142 -368.001528) (xy 52.535534 -367.993646) (xy 52.563014 -367.993168) (xy 52.590287 -367.993589)
			(xy 52.644277 -368.001353) (xy 52.696612 -368.016723) (xy 52.746227 -368.039384) (xy 52.792112 -368.068876)
			(xy 52.833333 -368.104598) (xy 52.86905 -368.145823) (xy 52.898537 -368.191711) (xy 52.921192 -368.241329)
			(xy 52.936556 -368.293666) (xy 52.944315 -368.347657) (xy 52.944776 -368.37493) (xy 52.944444 -368.398151)
			(xy 52.938843 -368.444254) (xy 52.9336 -368.466878) (xy 52.931268 -368.47935) (xy 52.937664 -368.503871)
			(xy 52.945792 -368.513614) (xy 52.970656 -368.540931) (xy 53.015569 -368.59958) (xy 53.035454 -368.630708)
			(xy 53.042414 -368.640596) (xy 53.063083 -368.653071) (xy 53.075078 -368.654584) (xy 53.102267 -368.656909)
			(xy 53.155599 -368.668465) (xy 53.206743 -368.687497) (xy 53.254655 -368.713618) (xy 53.298359 -368.746296)
			(xy 53.336964 -368.784865) (xy 53.369684 -368.828537) (xy 53.395851 -368.876424) (xy 53.414932 -368.92755)
			(xy 53.426539 -368.980871) (xy 53.430434 -369.035302) (xy 57.288819 -369.035302) (xy 57.292713 -368.980888)
			(xy 57.304314 -368.927582) (xy 57.323386 -368.876471) (xy 57.349542 -368.828596) (xy 57.382247 -368.784933)
			(xy 57.420836 -368.746371) (xy 57.464522 -368.713696) (xy 57.512416 -368.687575) (xy 57.56354 -368.668538)
			(xy 57.616854 -368.656974) (xy 57.64403 -368.654584) (xy 57.656031 -368.653099) (xy 57.676706 -368.640609)
			(xy 57.683654 -368.630708) (xy 57.703552 -368.599589) (xy 57.748463 -368.54094) (xy 57.773316 -368.513614)
			(xy 57.778871 -368.507276) (xy 57.785761 -368.491905) (xy 57.787245 -368.475125) (xy 57.785508 -368.466878)
			(xy 57.780261 -368.444255) (xy 57.774659 -368.398151) (xy 57.774332 -368.37493) (xy 57.774829 -368.34766)
			(xy 57.782587 -368.293675) (xy 57.797949 -368.241343) (xy 57.820603 -368.19173) (xy 57.850087 -368.145847)
			(xy 57.885801 -368.104626) (xy 57.927018 -368.068909) (xy 57.972899 -368.03942) (xy 58.022509 -368.016762)
			(xy 58.074839 -368.001395) (xy 58.128824 -367.993632) (xy 58.156094 -367.993168) (xy 58.183574 -367.993593)
			(xy 58.237962 -368.001499) (xy 58.290656 -368.01712) (xy 58.340566 -368.040133) (xy 58.386662 -368.070063)
			(xy 58.427991 -368.106292) (xy 58.4637 -368.148071) (xy 58.493051 -368.194538) (xy 58.515438 -368.244732)
			(xy 58.523378 -368.271044) (xy 58.526006 -368.279121) (xy 58.535673 -368.29307) (xy 58.549388 -368.303067)
			(xy 58.557414 -368.305842) (xy 58.588713 -368.31594) (xy 58.649615 -368.340776) (xy 58.708163 -368.370743)
			(xy 58.73623 -368.387884) (xy 58.744491 -368.39258) (xy 58.763154 -368.396088) (xy 58.781817 -368.39258)
			(xy 58.790078 -368.387884) (xy 58.818135 -368.370723) (xy 58.876676 -368.340739) (xy 58.937585 -368.315914)
			(xy 58.968894 -368.305842) (xy 58.976908 -368.303037) (xy 58.99062 -368.293044) (xy 59.000317 -368.279121)
			(xy 59.00293 -368.271044) (xy 59.010874 -368.244733) (xy 59.033248 -368.194533) (xy 59.062592 -368.148062)
			(xy 59.098298 -368.106281) (xy 59.139629 -368.070055) (xy 59.185728 -368.040131) (xy 59.235644 -368.01713)
			(xy 59.288342 -368.001528) (xy 59.342734 -367.993646) (xy 59.370214 -367.993168) (xy 59.397487 -367.993589)
			(xy 59.451477 -368.001353) (xy 59.503812 -368.016723) (xy 59.553427 -368.039384) (xy 59.599312 -368.068876)
			(xy 59.640533 -368.104598) (xy 59.67625 -368.145823) (xy 59.705737 -368.191711) (xy 59.728392 -368.241329)
			(xy 59.743756 -368.293666) (xy 59.751515 -368.347657) (xy 59.751976 -368.37493) (xy 59.751644 -368.398151)
			(xy 59.746043 -368.444254) (xy 59.7408 -368.466878) (xy 59.738468 -368.47935) (xy 59.744864 -368.503871)
			(xy 59.752992 -368.513614) (xy 59.777856 -368.540931) (xy 59.822769 -368.59958) (xy 59.842654 -368.630708)
			(xy 59.849614 -368.640596) (xy 59.870283 -368.653071) (xy 59.882278 -368.654584) (xy 59.909467 -368.656909)
			(xy 59.962799 -368.668465) (xy 60.013943 -368.687497) (xy 60.061855 -368.713618) (xy 60.105559 -368.746296)
			(xy 60.144164 -368.784865) (xy 60.176884 -368.828537) (xy 60.203051 -368.876424) (xy 60.222132 -368.92755)
			(xy 60.233739 -368.980871) (xy 60.237634 -369.035302) (xy 64.096019 -369.035302) (xy 64.099913 -368.980888)
			(xy 64.111514 -368.927582) (xy 64.130586 -368.876471) (xy 64.156742 -368.828596) (xy 64.189447 -368.784933)
			(xy 64.228036 -368.746371) (xy 64.271722 -368.713696) (xy 64.319616 -368.687575) (xy 64.37074 -368.668538)
			(xy 64.424054 -368.656974) (xy 64.45123 -368.654584) (xy 64.463231 -368.653099) (xy 64.483906 -368.640609)
			(xy 64.490854 -368.630708) (xy 64.510752 -368.599589) (xy 64.555663 -368.54094) (xy 64.580516 -368.513614)
			(xy 64.586071 -368.507276) (xy 64.592961 -368.491905) (xy 64.594445 -368.475125) (xy 64.592708 -368.466878)
			(xy 64.587461 -368.444255) (xy 64.581859 -368.398151) (xy 64.581532 -368.37493) (xy 64.582029 -368.34766)
			(xy 64.589787 -368.293675) (xy 64.605149 -368.241343) (xy 64.627803 -368.19173) (xy 64.657287 -368.145847)
			(xy 64.693001 -368.104626) (xy 64.734218 -368.068909) (xy 64.780099 -368.03942) (xy 64.829709 -368.016762)
			(xy 64.882039 -368.001395) (xy 64.936024 -367.993632) (xy 64.963294 -367.993168) (xy 64.990774 -367.993593)
			(xy 65.045162 -368.001499) (xy 65.097856 -368.01712) (xy 65.147766 -368.040133) (xy 65.193862 -368.070063)
			(xy 65.235191 -368.106292) (xy 65.2709 -368.148071) (xy 65.300251 -368.194538) (xy 65.322638 -368.244732)
			(xy 65.330578 -368.271044) (xy 65.333206 -368.279121) (xy 65.342873 -368.29307) (xy 65.356588 -368.303067)
			(xy 65.364614 -368.305842) (xy 65.395913 -368.31594) (xy 65.456815 -368.340776) (xy 65.515363 -368.370743)
			(xy 65.54343 -368.387884) (xy 65.551691 -368.39258) (xy 65.570354 -368.396088) (xy 65.589017 -368.39258)
			(xy 65.597278 -368.387884) (xy 65.625335 -368.370723) (xy 65.683876 -368.340739) (xy 65.744785 -368.315914)
			(xy 65.776094 -368.305842) (xy 65.784108 -368.303037) (xy 65.79782 -368.293044) (xy 65.807517 -368.279121)
			(xy 65.81013 -368.271044) (xy 65.818074 -368.244733) (xy 65.840448 -368.194533) (xy 65.869792 -368.148062)
			(xy 65.905498 -368.106281) (xy 65.946829 -368.070055) (xy 65.992928 -368.040131) (xy 66.042844 -368.01713)
			(xy 66.095542 -368.001528) (xy 66.149934 -367.993646) (xy 66.177414 -367.993168) (xy 66.204687 -367.993589)
			(xy 66.258677 -368.001353) (xy 66.311012 -368.016723) (xy 66.360627 -368.039384) (xy 66.406512 -368.068876)
			(xy 66.447733 -368.104598) (xy 66.48345 -368.145823) (xy 66.512937 -368.191711) (xy 66.535592 -368.241329)
			(xy 66.550956 -368.293666) (xy 66.558715 -368.347657) (xy 66.559176 -368.37493) (xy 66.558844 -368.398151)
			(xy 66.553243 -368.444254) (xy 66.548 -368.466878) (xy 66.545668 -368.47935) (xy 66.552064 -368.503871)
			(xy 66.560192 -368.513614) (xy 66.585056 -368.540931) (xy 66.629969 -368.59958) (xy 66.649854 -368.630708)
			(xy 66.656814 -368.640596) (xy 66.677483 -368.653071) (xy 66.689478 -368.654584) (xy 66.716667 -368.656909)
			(xy 66.769999 -368.668465) (xy 66.821143 -368.687497) (xy 66.869055 -368.713618) (xy 66.912759 -368.746296)
			(xy 66.951364 -368.784865) (xy 66.984084 -368.828537) (xy 67.010251 -368.876424) (xy 67.029332 -368.92755)
			(xy 67.040939 -368.980871) (xy 67.044834 -369.035302) (xy 67.040938 -369.089733) (xy 67.029331 -369.143054)
			(xy 67.010249 -369.194179) (xy 66.984082 -369.242066) (xy 66.951362 -369.285739) (xy 66.912756 -369.324307)
			(xy 66.869051 -369.356984) (xy 66.821139 -369.383105) (xy 66.769995 -369.402137) (xy 66.716663 -369.413691)
			(xy 66.689478 -369.416076) (xy 66.677482 -369.417582) (xy 66.656806 -369.430058) (xy 66.649854 -369.439952)
			(xy 66.629951 -369.471069) (xy 66.585043 -369.529719) (xy 66.560192 -369.557046) (xy 66.554664 -369.563404)
			(xy 66.547766 -369.578765) (xy 66.54627 -369.595537) (xy 66.548 -369.603782) (xy 66.55324 -369.626407)
			(xy 66.558846 -369.672509) (xy 66.559176 -369.69573) (xy 66.558703 -369.722999) (xy 66.550938 -369.776983)
			(xy 66.53557 -369.829312) (xy 66.512911 -369.878921) (xy 66.483423 -369.924801) (xy 66.447707 -369.966018)
			(xy 66.406488 -370.001733) (xy 66.360607 -370.031219) (xy 66.310997 -370.053875) (xy 66.258667 -370.069242)
			(xy 66.204683 -370.077005) (xy 66.177414 -370.077492) (xy 66.149936 -370.077017) (xy 66.095552 -370.069113)
			(xy 66.042862 -370.053496) (xy 65.992954 -370.030488) (xy 65.94686 -370.000564) (xy 65.905531 -369.964342)
			(xy 65.86982 -369.922571) (xy 65.840466 -369.876112) (xy 65.818073 -369.825925) (xy 65.81013 -369.799616)
			(xy 65.807575 -369.791511) (xy 65.797878 -369.777563) (xy 65.784133 -369.76758) (xy 65.776094 -369.764818)
			(xy 65.744797 -369.754713) (xy 65.683895 -369.72988) (xy 65.625346 -369.699916) (xy 65.597278 -369.682776)
			(xy 65.589017 -369.67808) (xy 65.570354 -369.674572) (xy 65.551691 -369.67808) (xy 65.54343 -369.682776)
			(xy 65.515371 -369.699933) (xy 65.45683 -369.729919) (xy 65.395922 -369.754746) (xy 65.364614 -369.764818)
			(xy 65.356587 -369.767592) (xy 65.342874 -369.777596) (xy 65.333184 -369.791533) (xy 65.330578 -369.799616)
			(xy 65.322691 -369.825947) (xy 65.300315 -369.876152) (xy 65.270967 -369.922627) (xy 65.235254 -369.96441)
			(xy 65.193916 -370.000637) (xy 65.147808 -370.030558) (xy 65.097884 -370.053554) (xy 65.045176 -370.069149)
			(xy 64.990777 -370.07702) (xy 64.963294 -370.077492) (xy 64.936026 -370.076981) (xy 64.882045 -370.06922)
			(xy 64.829717 -370.053855) (xy 64.780109 -370.0312) (xy 64.73423 -370.001717) (xy 64.693013 -369.966004)
			(xy 64.657298 -369.924789) (xy 64.627811 -369.878912) (xy 64.605153 -369.829305) (xy 64.589786 -369.776979)
			(xy 64.58202 -369.722998) (xy 64.581532 -369.69573) (xy 64.581857 -369.672509) (xy 64.587463 -369.626406)
			(xy 64.592708 -369.603782) (xy 64.595065 -369.591312) (xy 64.588652 -369.566788) (xy 64.580516 -369.557046)
			(xy 64.555643 -369.529738) (xy 64.510736 -369.471083) (xy 64.490854 -369.439952) (xy 64.4839 -369.43006)
			(xy 64.463226 -369.417589) (xy 64.45123 -369.416076) (xy 64.424058 -369.413626) (xy 64.370744 -369.402063)
			(xy 64.319619 -369.383027) (xy 64.271726 -369.356906) (xy 64.228039 -369.324232) (xy 64.18945 -369.285671)
			(xy 64.156744 -369.242008) (xy 64.130588 -369.194133) (xy 64.111515 -369.143022) (xy 64.099913 -369.089717)
			(xy 64.096019 -369.035302) (xy 60.237634 -369.035302) (xy 60.233738 -369.089733) (xy 60.222131 -369.143054)
			(xy 60.203049 -369.194179) (xy 60.176882 -369.242066) (xy 60.144162 -369.285739) (xy 60.105556 -369.324307)
			(xy 60.061851 -369.356984) (xy 60.013939 -369.383105) (xy 59.962795 -369.402137) (xy 59.909463 -369.413691)
			(xy 59.882278 -369.416076) (xy 59.870282 -369.417582) (xy 59.849606 -369.430058) (xy 59.842654 -369.439952)
			(xy 59.822751 -369.471069) (xy 59.777843 -369.529719) (xy 59.752992 -369.557046) (xy 59.747464 -369.563404)
			(xy 59.740566 -369.578765) (xy 59.73907 -369.595537) (xy 59.7408 -369.603782) (xy 59.74604 -369.626407)
			(xy 59.751646 -369.672509) (xy 59.751976 -369.69573) (xy 59.751503 -369.722999) (xy 59.743738 -369.776983)
			(xy 59.72837 -369.829312) (xy 59.705711 -369.878921) (xy 59.676223 -369.924801) (xy 59.640507 -369.966018)
			(xy 59.599288 -370.001733) (xy 59.553407 -370.031219) (xy 59.503797 -370.053875) (xy 59.451467 -370.069242)
			(xy 59.397483 -370.077005) (xy 59.370214 -370.077492) (xy 59.342736 -370.077017) (xy 59.288352 -370.069113)
			(xy 59.235662 -370.053496) (xy 59.185754 -370.030488) (xy 59.13966 -370.000564) (xy 59.098331 -369.964342)
			(xy 59.06262 -369.922571) (xy 59.033266 -369.876112) (xy 59.010873 -369.825925) (xy 59.00293 -369.799616)
			(xy 59.000375 -369.791511) (xy 58.990678 -369.777563) (xy 58.976933 -369.76758) (xy 58.968894 -369.764818)
			(xy 58.937597 -369.754713) (xy 58.876695 -369.72988) (xy 58.818146 -369.699916) (xy 58.790078 -369.682776)
			(xy 58.781817 -369.67808) (xy 58.763154 -369.674572) (xy 58.744491 -369.67808) (xy 58.73623 -369.682776)
			(xy 58.708171 -369.699933) (xy 58.64963 -369.729919) (xy 58.588722 -369.754746) (xy 58.557414 -369.764818)
			(xy 58.549387 -369.767592) (xy 58.535674 -369.777596) (xy 58.525984 -369.791533) (xy 58.523378 -369.799616)
			(xy 58.515491 -369.825947) (xy 58.493115 -369.876152) (xy 58.463767 -369.922627) (xy 58.428054 -369.96441)
			(xy 58.386716 -370.000637) (xy 58.340608 -370.030558) (xy 58.290684 -370.053554) (xy 58.237976 -370.069149)
			(xy 58.183577 -370.07702) (xy 58.156094 -370.077492) (xy 58.128826 -370.076981) (xy 58.074845 -370.06922)
			(xy 58.022517 -370.053855) (xy 57.972909 -370.0312) (xy 57.92703 -370.001717) (xy 57.885813 -369.966004)
			(xy 57.850098 -369.924789) (xy 57.820611 -369.878912) (xy 57.797953 -369.829305) (xy 57.782586 -369.776979)
			(xy 57.77482 -369.722998) (xy 57.774332 -369.69573) (xy 57.774657 -369.672509) (xy 57.780263 -369.626406)
			(xy 57.785508 -369.603782) (xy 57.787865 -369.591312) (xy 57.781452 -369.566788) (xy 57.773316 -369.557046)
			(xy 57.748443 -369.529738) (xy 57.703536 -369.471083) (xy 57.683654 -369.439952) (xy 57.6767 -369.43006)
			(xy 57.656026 -369.417589) (xy 57.64403 -369.416076) (xy 57.616858 -369.413626) (xy 57.563544 -369.402063)
			(xy 57.512419 -369.383027) (xy 57.464526 -369.356906) (xy 57.420839 -369.324232) (xy 57.38225 -369.285671)
			(xy 57.349544 -369.242008) (xy 57.323388 -369.194133) (xy 57.304315 -369.143022) (xy 57.292713 -369.089717)
			(xy 57.288819 -369.035302) (xy 53.430434 -369.035302) (xy 53.426538 -369.089733) (xy 53.414931 -369.143054)
			(xy 53.395849 -369.194179) (xy 53.369682 -369.242066) (xy 53.336962 -369.285739) (xy 53.298356 -369.324307)
			(xy 53.254651 -369.356984) (xy 53.206739 -369.383105) (xy 53.155595 -369.402137) (xy 53.102263 -369.413691)
			(xy 53.075078 -369.416076) (xy 53.063082 -369.417582) (xy 53.042406 -369.430058) (xy 53.035454 -369.439952)
			(xy 53.015551 -369.471069) (xy 52.970643 -369.529719) (xy 52.945792 -369.557046) (xy 52.940264 -369.563404)
			(xy 52.933366 -369.578765) (xy 52.93187 -369.595537) (xy 52.9336 -369.603782) (xy 52.93884 -369.626407)
			(xy 52.944446 -369.672509) (xy 52.944776 -369.69573) (xy 52.944303 -369.722999) (xy 52.936538 -369.776983)
			(xy 52.92117 -369.829312) (xy 52.898511 -369.878921) (xy 52.869023 -369.924801) (xy 52.833307 -369.966018)
			(xy 52.792088 -370.001733) (xy 52.746207 -370.031219) (xy 52.696597 -370.053875) (xy 52.644267 -370.069242)
			(xy 52.590283 -370.077005) (xy 52.563014 -370.077492) (xy 52.535536 -370.077017) (xy 52.481152 -370.069113)
			(xy 52.428462 -370.053496) (xy 52.378554 -370.030488) (xy 52.33246 -370.000564) (xy 52.291131 -369.964342)
			(xy 52.25542 -369.922571) (xy 52.226066 -369.876112) (xy 52.203673 -369.825925) (xy 52.19573 -369.799616)
			(xy 52.193175 -369.791511) (xy 52.183478 -369.777563) (xy 52.169733 -369.76758) (xy 52.161694 -369.764818)
			(xy 52.130397 -369.754713) (xy 52.069495 -369.72988) (xy 52.010946 -369.699916) (xy 51.982878 -369.682776)
			(xy 51.974617 -369.67808) (xy 51.955954 -369.674572) (xy 51.937291 -369.67808) (xy 51.92903 -369.682776)
			(xy 51.900971 -369.699933) (xy 51.84243 -369.729919) (xy 51.781522 -369.754746) (xy 51.750214 -369.764818)
			(xy 51.742187 -369.767592) (xy 51.728474 -369.777596) (xy 51.718784 -369.791533) (xy 51.716178 -369.799616)
			(xy 51.708291 -369.825947) (xy 51.685915 -369.876152) (xy 51.656567 -369.922627) (xy 51.620854 -369.96441)
			(xy 51.579516 -370.000637) (xy 51.533408 -370.030558) (xy 51.483484 -370.053554) (xy 51.430776 -370.069149)
			(xy 51.376377 -370.07702) (xy 51.348894 -370.077492) (xy 51.321626 -370.076981) (xy 51.267645 -370.06922)
			(xy 51.215317 -370.053855) (xy 51.165709 -370.0312) (xy 51.11983 -370.001717) (xy 51.078613 -369.966004)
			(xy 51.042898 -369.924789) (xy 51.013411 -369.878912) (xy 50.990753 -369.829305) (xy 50.975386 -369.776979)
			(xy 50.96762 -369.722998) (xy 50.967132 -369.69573) (xy 50.967457 -369.672509) (xy 50.973063 -369.626406)
			(xy 50.978308 -369.603782) (xy 50.980665 -369.591312) (xy 50.974252 -369.566788) (xy 50.966116 -369.557046)
			(xy 50.941243 -369.529738) (xy 50.896336 -369.471083) (xy 50.876454 -369.439952) (xy 50.8695 -369.43006)
			(xy 50.848826 -369.417589) (xy 50.83683 -369.416076) (xy 50.809658 -369.413626) (xy 50.756344 -369.402063)
			(xy 50.705219 -369.383027) (xy 50.657326 -369.356906) (xy 50.613639 -369.324232) (xy 50.57505 -369.285671)
			(xy 50.542344 -369.242008) (xy 50.516188 -369.194133) (xy 50.497115 -369.143022) (xy 50.485513 -369.089717)
			(xy 50.481619 -369.035302) (xy 46.623234 -369.035302) (xy 46.619338 -369.089733) (xy 46.607731 -369.143054)
			(xy 46.588649 -369.194179) (xy 46.562482 -369.242066) (xy 46.529762 -369.285739) (xy 46.491156 -369.324307)
			(xy 46.447451 -369.356984) (xy 46.399539 -369.383105) (xy 46.348395 -369.402137) (xy 46.295063 -369.413691)
			(xy 46.267878 -369.416076) (xy 46.255882 -369.417582) (xy 46.235206 -369.430058) (xy 46.228254 -369.439952)
			(xy 46.208351 -369.471069) (xy 46.163443 -369.529719) (xy 46.138592 -369.557046) (xy 46.133064 -369.563404)
			(xy 46.126166 -369.578765) (xy 46.12467 -369.595537) (xy 46.1264 -369.603782) (xy 46.13164 -369.626407)
			(xy 46.137246 -369.672509) (xy 46.137576 -369.69573) (xy 46.137103 -369.722999) (xy 46.129338 -369.776983)
			(xy 46.11397 -369.829312) (xy 46.091311 -369.878921) (xy 46.061823 -369.924801) (xy 46.026107 -369.966018)
			(xy 45.984888 -370.001733) (xy 45.939007 -370.031219) (xy 45.889397 -370.053875) (xy 45.837067 -370.069242)
			(xy 45.783083 -370.077005) (xy 45.755814 -370.077492) (xy 45.728336 -370.077017) (xy 45.673952 -370.069113)
			(xy 45.621262 -370.053496) (xy 45.571354 -370.030488) (xy 45.52526 -370.000564) (xy 45.483931 -369.964342)
			(xy 45.44822 -369.922571) (xy 45.418866 -369.876112) (xy 45.396473 -369.825925) (xy 45.38853 -369.799616)
			(xy 45.385975 -369.791511) (xy 45.376278 -369.777563) (xy 45.362533 -369.76758) (xy 45.354494 -369.764818)
			(xy 45.323197 -369.754713) (xy 45.262295 -369.72988) (xy 45.203746 -369.699916) (xy 45.175678 -369.682776)
			(xy 45.167417 -369.67808) (xy 45.148754 -369.674572) (xy 45.130091 -369.67808) (xy 45.12183 -369.682776)
			(xy 45.093771 -369.699933) (xy 45.03523 -369.729919) (xy 44.974322 -369.754746) (xy 44.943014 -369.764818)
			(xy 44.934987 -369.767592) (xy 44.921274 -369.777596) (xy 44.911584 -369.791533) (xy 44.908978 -369.799616)
			(xy 44.901091 -369.825947) (xy 44.878715 -369.876152) (xy 44.849367 -369.922627) (xy 44.813654 -369.96441)
			(xy 44.772316 -370.000637) (xy 44.726208 -370.030558) (xy 44.676284 -370.053554) (xy 44.623576 -370.069149)
			(xy 44.569177 -370.07702) (xy 44.541694 -370.077492) (xy 44.514426 -370.076981) (xy 44.460445 -370.06922)
			(xy 44.408117 -370.053855) (xy 44.358509 -370.0312) (xy 44.31263 -370.001717) (xy 44.271413 -369.966004)
			(xy 44.235698 -369.924789) (xy 44.206211 -369.878912) (xy 44.183553 -369.829305) (xy 44.168186 -369.776979)
			(xy 44.16042 -369.722998) (xy 44.159932 -369.69573) (xy 44.160257 -369.672509) (xy 44.165863 -369.626406)
			(xy 44.171108 -369.603782) (xy 44.173465 -369.591312) (xy 44.167052 -369.566788) (xy 44.158916 -369.557046)
			(xy 44.134043 -369.529738) (xy 44.089136 -369.471083) (xy 44.069254 -369.439952) (xy 44.0623 -369.43006)
			(xy 44.041626 -369.417589) (xy 44.02963 -369.416076) (xy 44.002458 -369.413626) (xy 43.949144 -369.402063)
			(xy 43.898019 -369.383027) (xy 43.850126 -369.356906) (xy 43.806439 -369.324232) (xy 43.76785 -369.285671)
			(xy 43.735144 -369.242008) (xy 43.708988 -369.194133) (xy 43.689915 -369.143022) (xy 43.678313 -369.089717)
			(xy 43.674419 -369.035302) (xy 3.523996 -369.035302) (xy 3.523996 -371.499102) (xy 41.972619 -371.499102)
			(xy 41.976513 -371.444688) (xy 41.988114 -371.391382) (xy 42.007186 -371.340271) (xy 42.033342 -371.292396)
			(xy 42.066047 -371.248733) (xy 42.104636 -371.210171) (xy 42.148322 -371.177496) (xy 42.196216 -371.151375)
			(xy 42.24734 -371.132338) (xy 42.300654 -371.120774) (xy 42.32783 -371.118384) (xy 42.339831 -371.116899)
			(xy 42.360506 -371.104409) (xy 42.367454 -371.094508) (xy 42.387352 -371.063389) (xy 42.432263 -371.00474)
			(xy 42.457116 -370.977414) (xy 42.462671 -370.971076) (xy 42.469561 -370.955705) (xy 42.471045 -370.938925)
			(xy 42.469308 -370.930678) (xy 42.464061 -370.908055) (xy 42.458459 -370.861951) (xy 42.458132 -370.83873)
			(xy 42.458629 -370.81146) (xy 42.466387 -370.757475) (xy 42.481749 -370.705143) (xy 42.504403 -370.65553)
			(xy 42.533887 -370.609647) (xy 42.569601 -370.568426) (xy 42.610818 -370.532709) (xy 42.656699 -370.50322)
			(xy 42.706309 -370.480562) (xy 42.758639 -370.465195) (xy 42.812624 -370.457432) (xy 42.839894 -370.456968)
			(xy 42.867374 -370.457393) (xy 42.921762 -370.465299) (xy 42.974456 -370.48092) (xy 43.024366 -370.503933)
			(xy 43.070462 -370.533863) (xy 43.111791 -370.570092) (xy 43.1475 -370.611871) (xy 43.176851 -370.658338)
			(xy 43.199238 -370.708532) (xy 43.207178 -370.734844) (xy 43.209806 -370.742921) (xy 43.219473 -370.75687)
			(xy 43.233188 -370.766867) (xy 43.241214 -370.769642) (xy 43.272513 -370.77974) (xy 43.333415 -370.804576)
			(xy 43.391963 -370.834543) (xy 43.42003 -370.851684) (xy 43.428291 -370.85638) (xy 43.446954 -370.859888)
			(xy 43.465617 -370.85638) (xy 43.473878 -370.851684) (xy 43.501935 -370.834523) (xy 43.560476 -370.804539)
			(xy 43.621385 -370.779714) (xy 43.652694 -370.769642) (xy 43.660708 -370.766837) (xy 43.67442 -370.756844)
			(xy 43.684117 -370.742921) (xy 43.68673 -370.734844) (xy 43.694674 -370.708533) (xy 43.717048 -370.658333)
			(xy 43.746392 -370.611862) (xy 43.782098 -370.570081) (xy 43.823429 -370.533855) (xy 43.869528 -370.503931)
			(xy 43.919444 -370.48093) (xy 43.972142 -370.465328) (xy 44.026534 -370.457446) (xy 44.054014 -370.456968)
			(xy 44.081287 -370.457389) (xy 44.135277 -370.465153) (xy 44.187612 -370.480523) (xy 44.237227 -370.503184)
			(xy 44.283112 -370.532676) (xy 44.324333 -370.568398) (xy 44.36005 -370.609623) (xy 44.389537 -370.655511)
			(xy 44.412192 -370.705129) (xy 44.427556 -370.757466) (xy 44.435315 -370.811457) (xy 44.435776 -370.83873)
			(xy 44.435444 -370.861951) (xy 44.429843 -370.908054) (xy 44.4246 -370.930678) (xy 44.422268 -370.94315)
			(xy 44.428664 -370.967671) (xy 44.436792 -370.977414) (xy 44.461656 -371.004731) (xy 44.506569 -371.06338)
			(xy 44.526454 -371.094508) (xy 44.533414 -371.104396) (xy 44.554083 -371.116871) (xy 44.566078 -371.118384)
			(xy 44.593267 -371.120709) (xy 44.646599 -371.132265) (xy 44.697743 -371.151297) (xy 44.745655 -371.177418)
			(xy 44.789359 -371.210096) (xy 44.827964 -371.248665) (xy 44.860684 -371.292337) (xy 44.886851 -371.340224)
			(xy 44.905932 -371.39135) (xy 44.917539 -371.444671) (xy 44.921434 -371.499102) (xy 48.779819 -371.499102)
			(xy 48.783713 -371.444688) (xy 48.795314 -371.391382) (xy 48.814386 -371.340271) (xy 48.840542 -371.292396)
			(xy 48.873247 -371.248733) (xy 48.911836 -371.210171) (xy 48.955522 -371.177496) (xy 49.003416 -371.151375)
			(xy 49.05454 -371.132338) (xy 49.107854 -371.120774) (xy 49.13503 -371.118384) (xy 49.147031 -371.116899)
			(xy 49.167706 -371.104409) (xy 49.174654 -371.094508) (xy 49.194552 -371.063389) (xy 49.239463 -371.00474)
			(xy 49.264316 -370.977414) (xy 49.269871 -370.971076) (xy 49.276761 -370.955705) (xy 49.278245 -370.938925)
			(xy 49.276508 -370.930678) (xy 49.271261 -370.908055) (xy 49.265659 -370.861951) (xy 49.265332 -370.83873)
			(xy 49.265829 -370.81146) (xy 49.273587 -370.757475) (xy 49.288949 -370.705143) (xy 49.311603 -370.65553)
			(xy 49.341087 -370.609647) (xy 49.376801 -370.568426) (xy 49.418018 -370.532709) (xy 49.463899 -370.50322)
			(xy 49.513509 -370.480562) (xy 49.565839 -370.465195) (xy 49.619824 -370.457432) (xy 49.647094 -370.456968)
			(xy 49.674574 -370.457393) (xy 49.728962 -370.465299) (xy 49.781656 -370.48092) (xy 49.831566 -370.503933)
			(xy 49.877662 -370.533863) (xy 49.918991 -370.570092) (xy 49.9547 -370.611871) (xy 49.984051 -370.658338)
			(xy 50.006438 -370.708532) (xy 50.014378 -370.734844) (xy 50.017006 -370.742921) (xy 50.026673 -370.75687)
			(xy 50.040388 -370.766867) (xy 50.048414 -370.769642) (xy 50.079713 -370.77974) (xy 50.140615 -370.804576)
			(xy 50.199163 -370.834543) (xy 50.22723 -370.851684) (xy 50.235491 -370.85638) (xy 50.254154 -370.859888)
			(xy 50.272817 -370.85638) (xy 50.281078 -370.851684) (xy 50.309135 -370.834523) (xy 50.367676 -370.804539)
			(xy 50.428585 -370.779714) (xy 50.459894 -370.769642) (xy 50.467908 -370.766837) (xy 50.48162 -370.756844)
			(xy 50.491317 -370.742921) (xy 50.49393 -370.734844) (xy 50.501874 -370.708533) (xy 50.524248 -370.658333)
			(xy 50.553592 -370.611862) (xy 50.589298 -370.570081) (xy 50.630629 -370.533855) (xy 50.676728 -370.503931)
			(xy 50.726644 -370.48093) (xy 50.779342 -370.465328) (xy 50.833734 -370.457446) (xy 50.861214 -370.456968)
			(xy 50.888487 -370.457389) (xy 50.942477 -370.465153) (xy 50.994812 -370.480523) (xy 51.044427 -370.503184)
			(xy 51.090312 -370.532676) (xy 51.131533 -370.568398) (xy 51.16725 -370.609623) (xy 51.196737 -370.655511)
			(xy 51.219392 -370.705129) (xy 51.234756 -370.757466) (xy 51.242515 -370.811457) (xy 51.242976 -370.83873)
			(xy 51.242644 -370.861951) (xy 51.237043 -370.908054) (xy 51.2318 -370.930678) (xy 51.229468 -370.94315)
			(xy 51.235864 -370.967671) (xy 51.243992 -370.977414) (xy 51.268856 -371.004731) (xy 51.313769 -371.06338)
			(xy 51.333654 -371.094508) (xy 51.340614 -371.104396) (xy 51.361283 -371.116871) (xy 51.373278 -371.118384)
			(xy 51.400467 -371.120709) (xy 51.453799 -371.132265) (xy 51.504943 -371.151297) (xy 51.552855 -371.177418)
			(xy 51.596559 -371.210096) (xy 51.635164 -371.248665) (xy 51.667884 -371.292337) (xy 51.694051 -371.340224)
			(xy 51.713132 -371.39135) (xy 51.724739 -371.444671) (xy 51.728634 -371.499102) (xy 55.587019 -371.499102)
			(xy 55.590913 -371.444688) (xy 55.602514 -371.391382) (xy 55.621586 -371.340271) (xy 55.647742 -371.292396)
			(xy 55.680447 -371.248733) (xy 55.719036 -371.210171) (xy 55.762722 -371.177496) (xy 55.810616 -371.151375)
			(xy 55.86174 -371.132338) (xy 55.915054 -371.120774) (xy 55.94223 -371.118384) (xy 55.954231 -371.116899)
			(xy 55.974906 -371.104409) (xy 55.981854 -371.094508) (xy 56.001752 -371.063389) (xy 56.046663 -371.00474)
			(xy 56.071516 -370.977414) (xy 56.077071 -370.971076) (xy 56.083961 -370.955705) (xy 56.085445 -370.938925)
			(xy 56.083708 -370.930678) (xy 56.078461 -370.908055) (xy 56.072859 -370.861951) (xy 56.072532 -370.83873)
			(xy 56.073029 -370.81146) (xy 56.080787 -370.757475) (xy 56.096149 -370.705143) (xy 56.118803 -370.65553)
			(xy 56.148287 -370.609647) (xy 56.184001 -370.568426) (xy 56.225218 -370.532709) (xy 56.271099 -370.50322)
			(xy 56.320709 -370.480562) (xy 56.373039 -370.465195) (xy 56.427024 -370.457432) (xy 56.454294 -370.456968)
			(xy 56.481774 -370.457393) (xy 56.536162 -370.465299) (xy 56.588856 -370.48092) (xy 56.638766 -370.503933)
			(xy 56.684862 -370.533863) (xy 56.726191 -370.570092) (xy 56.7619 -370.611871) (xy 56.791251 -370.658338)
			(xy 56.813638 -370.708532) (xy 56.821578 -370.734844) (xy 56.824206 -370.742921) (xy 56.833873 -370.75687)
			(xy 56.847588 -370.766867) (xy 56.855614 -370.769642) (xy 56.886913 -370.77974) (xy 56.947815 -370.804576)
			(xy 57.006363 -370.834543) (xy 57.03443 -370.851684) (xy 57.042691 -370.85638) (xy 57.061354 -370.859888)
			(xy 57.080017 -370.85638) (xy 57.088278 -370.851684) (xy 57.116335 -370.834523) (xy 57.174876 -370.804539)
			(xy 57.235785 -370.779714) (xy 57.267094 -370.769642) (xy 57.275108 -370.766837) (xy 57.28882 -370.756844)
			(xy 57.298517 -370.742921) (xy 57.30113 -370.734844) (xy 57.309074 -370.708533) (xy 57.331448 -370.658333)
			(xy 57.360792 -370.611862) (xy 57.396498 -370.570081) (xy 57.437829 -370.533855) (xy 57.483928 -370.503931)
			(xy 57.533844 -370.48093) (xy 57.586542 -370.465328) (xy 57.640934 -370.457446) (xy 57.668414 -370.456968)
			(xy 57.695687 -370.457389) (xy 57.749677 -370.465153) (xy 57.802012 -370.480523) (xy 57.851627 -370.503184)
			(xy 57.897512 -370.532676) (xy 57.938733 -370.568398) (xy 57.97445 -370.609623) (xy 58.003937 -370.655511)
			(xy 58.026592 -370.705129) (xy 58.041956 -370.757466) (xy 58.049715 -370.811457) (xy 58.050176 -370.83873)
			(xy 58.049844 -370.861951) (xy 58.044243 -370.908054) (xy 58.039 -370.930678) (xy 58.036668 -370.94315)
			(xy 58.043064 -370.967671) (xy 58.051192 -370.977414) (xy 58.076056 -371.004731) (xy 58.120969 -371.06338)
			(xy 58.140854 -371.094508) (xy 58.147814 -371.104396) (xy 58.168483 -371.116871) (xy 58.180478 -371.118384)
			(xy 58.207667 -371.120709) (xy 58.260999 -371.132265) (xy 58.312143 -371.151297) (xy 58.360055 -371.177418)
			(xy 58.403759 -371.210096) (xy 58.442364 -371.248665) (xy 58.475084 -371.292337) (xy 58.501251 -371.340224)
			(xy 58.520332 -371.39135) (xy 58.531939 -371.444671) (xy 58.535834 -371.499102) (xy 62.394219 -371.499102)
			(xy 62.398113 -371.444688) (xy 62.409714 -371.391382) (xy 62.428786 -371.340271) (xy 62.454942 -371.292396)
			(xy 62.487647 -371.248733) (xy 62.526236 -371.210171) (xy 62.569922 -371.177496) (xy 62.617816 -371.151375)
			(xy 62.66894 -371.132338) (xy 62.722254 -371.120774) (xy 62.74943 -371.118384) (xy 62.761431 -371.116899)
			(xy 62.782106 -371.104409) (xy 62.789054 -371.094508) (xy 62.808952 -371.063389) (xy 62.853863 -371.00474)
			(xy 62.878716 -370.977414) (xy 62.884271 -370.971076) (xy 62.891161 -370.955705) (xy 62.892645 -370.938925)
			(xy 62.890908 -370.930678) (xy 62.885661 -370.908055) (xy 62.880059 -370.861951) (xy 62.879732 -370.83873)
			(xy 62.880229 -370.81146) (xy 62.887987 -370.757475) (xy 62.903349 -370.705143) (xy 62.926003 -370.65553)
			(xy 62.955487 -370.609647) (xy 62.991201 -370.568426) (xy 63.032418 -370.532709) (xy 63.078299 -370.50322)
			(xy 63.127909 -370.480562) (xy 63.180239 -370.465195) (xy 63.234224 -370.457432) (xy 63.261494 -370.456968)
			(xy 63.288974 -370.457393) (xy 63.343362 -370.465299) (xy 63.396056 -370.48092) (xy 63.445966 -370.503933)
			(xy 63.492062 -370.533863) (xy 63.533391 -370.570092) (xy 63.5691 -370.611871) (xy 63.598451 -370.658338)
			(xy 63.620838 -370.708532) (xy 63.628778 -370.734844) (xy 63.631406 -370.742921) (xy 63.641073 -370.75687)
			(xy 63.654788 -370.766867) (xy 63.662814 -370.769642) (xy 63.694113 -370.77974) (xy 63.755015 -370.804576)
			(xy 63.813563 -370.834543) (xy 63.84163 -370.851684) (xy 63.849891 -370.85638) (xy 63.868554 -370.859888)
			(xy 63.887217 -370.85638) (xy 63.895478 -370.851684) (xy 63.923535 -370.834523) (xy 63.982076 -370.804539)
			(xy 64.042985 -370.779714) (xy 64.074294 -370.769642) (xy 64.082308 -370.766837) (xy 64.09602 -370.756844)
			(xy 64.105717 -370.742921) (xy 64.10833 -370.734844) (xy 64.116274 -370.708533) (xy 64.138648 -370.658333)
			(xy 64.167992 -370.611862) (xy 64.203698 -370.570081) (xy 64.245029 -370.533855) (xy 64.291128 -370.503931)
			(xy 64.341044 -370.48093) (xy 64.393742 -370.465328) (xy 64.448134 -370.457446) (xy 64.475614 -370.456968)
			(xy 64.502887 -370.457389) (xy 64.556877 -370.465153) (xy 64.609212 -370.480523) (xy 64.658827 -370.503184)
			(xy 64.704712 -370.532676) (xy 64.745933 -370.568398) (xy 64.78165 -370.609623) (xy 64.811137 -370.655511)
			(xy 64.833792 -370.705129) (xy 64.849156 -370.757466) (xy 64.856915 -370.811457) (xy 64.857376 -370.83873)
			(xy 64.857044 -370.861951) (xy 64.851443 -370.908054) (xy 64.8462 -370.930678) (xy 64.843868 -370.94315)
			(xy 64.850264 -370.967671) (xy 64.858392 -370.977414) (xy 64.883256 -371.004731) (xy 64.928169 -371.06338)
			(xy 64.948054 -371.094508) (xy 64.955014 -371.104396) (xy 64.975683 -371.116871) (xy 64.987678 -371.118384)
			(xy 65.014867 -371.120709) (xy 65.068199 -371.132265) (xy 65.119343 -371.151297) (xy 65.167255 -371.177418)
			(xy 65.210959 -371.210096) (xy 65.249564 -371.248665) (xy 65.282284 -371.292337) (xy 65.308451 -371.340224)
			(xy 65.327532 -371.39135) (xy 65.339139 -371.444671) (xy 65.343034 -371.499102) (xy 65.339138 -371.553533)
			(xy 65.327531 -371.606854) (xy 65.308449 -371.657979) (xy 65.282282 -371.705866) (xy 65.249562 -371.749539)
			(xy 65.210956 -371.788107) (xy 65.167251 -371.820784) (xy 65.119339 -371.846905) (xy 65.068195 -371.865937)
			(xy 65.014863 -371.877491) (xy 64.987678 -371.879876) (xy 64.975682 -371.881382) (xy 64.955006 -371.893858)
			(xy 64.948054 -371.903752) (xy 64.928151 -371.934869) (xy 64.883243 -371.993519) (xy 64.858392 -372.020846)
			(xy 64.852864 -372.027204) (xy 64.845966 -372.042565) (xy 64.84447 -372.059337) (xy 64.8462 -372.067582)
			(xy 64.85144 -372.090207) (xy 64.857046 -372.136309) (xy 64.857376 -372.15953) (xy 64.856903 -372.186799)
			(xy 64.849138 -372.240783) (xy 64.83377 -372.293112) (xy 64.811111 -372.342721) (xy 64.781623 -372.388601)
			(xy 64.745907 -372.429818) (xy 64.704688 -372.465533) (xy 64.658807 -372.495019) (xy 64.609197 -372.517675)
			(xy 64.556867 -372.533042) (xy 64.502883 -372.540805) (xy 64.475614 -372.541292) (xy 64.448136 -372.540817)
			(xy 64.393752 -372.532913) (xy 64.341062 -372.517296) (xy 64.291154 -372.494288) (xy 64.24506 -372.464364)
			(xy 64.203731 -372.428142) (xy 64.16802 -372.386371) (xy 64.138666 -372.339912) (xy 64.116273 -372.289725)
			(xy 64.10833 -372.263416) (xy 64.105775 -372.255311) (xy 64.096078 -372.241363) (xy 64.082333 -372.23138)
			(xy 64.074294 -372.228618) (xy 64.042997 -372.218513) (xy 63.982095 -372.19368) (xy 63.923546 -372.163716)
			(xy 63.895478 -372.146576) (xy 63.887217 -372.14188) (xy 63.868554 -372.138372) (xy 63.849891 -372.14188)
			(xy 63.84163 -372.146576) (xy 63.813571 -372.163733) (xy 63.75503 -372.193719) (xy 63.694122 -372.218546)
			(xy 63.662814 -372.228618) (xy 63.654787 -372.231392) (xy 63.641074 -372.241396) (xy 63.631384 -372.255333)
			(xy 63.628778 -372.263416) (xy 63.620891 -372.289747) (xy 63.598515 -372.339952) (xy 63.569167 -372.386427)
			(xy 63.533454 -372.42821) (xy 63.492116 -372.464437) (xy 63.446008 -372.494358) (xy 63.396084 -372.517354)
			(xy 63.343376 -372.532949) (xy 63.288977 -372.54082) (xy 63.261494 -372.541292) (xy 63.234226 -372.540781)
			(xy 63.180245 -372.53302) (xy 63.127917 -372.517655) (xy 63.078309 -372.495) (xy 63.03243 -372.465517)
			(xy 62.991213 -372.429804) (xy 62.955498 -372.388589) (xy 62.926011 -372.342712) (xy 62.903353 -372.293105)
			(xy 62.887986 -372.240779) (xy 62.88022 -372.186798) (xy 62.879732 -372.15953) (xy 62.880057 -372.136309)
			(xy 62.885663 -372.090206) (xy 62.890908 -372.067582) (xy 62.893265 -372.055112) (xy 62.886852 -372.030588)
			(xy 62.878716 -372.020846) (xy 62.853843 -371.993538) (xy 62.808936 -371.934883) (xy 62.789054 -371.903752)
			(xy 62.7821 -371.89386) (xy 62.761426 -371.881389) (xy 62.74943 -371.879876) (xy 62.722258 -371.877426)
			(xy 62.668944 -371.865863) (xy 62.617819 -371.846827) (xy 62.569926 -371.820706) (xy 62.526239 -371.788032)
			(xy 62.48765 -371.749471) (xy 62.454944 -371.705808) (xy 62.428788 -371.657933) (xy 62.409715 -371.606822)
			(xy 62.398113 -371.553517) (xy 62.394219 -371.499102) (xy 58.535834 -371.499102) (xy 58.531938 -371.553533)
			(xy 58.520331 -371.606854) (xy 58.501249 -371.657979) (xy 58.475082 -371.705866) (xy 58.442362 -371.749539)
			(xy 58.403756 -371.788107) (xy 58.360051 -371.820784) (xy 58.312139 -371.846905) (xy 58.260995 -371.865937)
			(xy 58.207663 -371.877491) (xy 58.180478 -371.879876) (xy 58.168482 -371.881382) (xy 58.147806 -371.893858)
			(xy 58.140854 -371.903752) (xy 58.120951 -371.934869) (xy 58.076043 -371.993519) (xy 58.051192 -372.020846)
			(xy 58.045664 -372.027204) (xy 58.038766 -372.042565) (xy 58.03727 -372.059337) (xy 58.039 -372.067582)
			(xy 58.04424 -372.090207) (xy 58.049846 -372.136309) (xy 58.050176 -372.15953) (xy 58.049703 -372.186799)
			(xy 58.041938 -372.240783) (xy 58.02657 -372.293112) (xy 58.003911 -372.342721) (xy 57.974423 -372.388601)
			(xy 57.938707 -372.429818) (xy 57.897488 -372.465533) (xy 57.851607 -372.495019) (xy 57.801997 -372.517675)
			(xy 57.749667 -372.533042) (xy 57.695683 -372.540805) (xy 57.668414 -372.541292) (xy 57.640936 -372.540817)
			(xy 57.586552 -372.532913) (xy 57.533862 -372.517296) (xy 57.483954 -372.494288) (xy 57.43786 -372.464364)
			(xy 57.396531 -372.428142) (xy 57.36082 -372.386371) (xy 57.331466 -372.339912) (xy 57.309073 -372.289725)
			(xy 57.30113 -372.263416) (xy 57.298575 -372.255311) (xy 57.288878 -372.241363) (xy 57.275133 -372.23138)
			(xy 57.267094 -372.228618) (xy 57.235797 -372.218513) (xy 57.174895 -372.19368) (xy 57.116346 -372.163716)
			(xy 57.088278 -372.146576) (xy 57.080017 -372.14188) (xy 57.061354 -372.138372) (xy 57.042691 -372.14188)
			(xy 57.03443 -372.146576) (xy 57.006371 -372.163733) (xy 56.94783 -372.193719) (xy 56.886922 -372.218546)
			(xy 56.855614 -372.228618) (xy 56.847587 -372.231392) (xy 56.833874 -372.241396) (xy 56.824184 -372.255333)
			(xy 56.821578 -372.263416) (xy 56.813691 -372.289747) (xy 56.791315 -372.339952) (xy 56.761967 -372.386427)
			(xy 56.726254 -372.42821) (xy 56.684916 -372.464437) (xy 56.638808 -372.494358) (xy 56.588884 -372.517354)
			(xy 56.536176 -372.532949) (xy 56.481777 -372.54082) (xy 56.454294 -372.541292) (xy 56.427026 -372.540781)
			(xy 56.373045 -372.53302) (xy 56.320717 -372.517655) (xy 56.271109 -372.495) (xy 56.22523 -372.465517)
			(xy 56.184013 -372.429804) (xy 56.148298 -372.388589) (xy 56.118811 -372.342712) (xy 56.096153 -372.293105)
			(xy 56.080786 -372.240779) (xy 56.07302 -372.186798) (xy 56.072532 -372.15953) (xy 56.072857 -372.136309)
			(xy 56.078463 -372.090206) (xy 56.083708 -372.067582) (xy 56.086065 -372.055112) (xy 56.079652 -372.030588)
			(xy 56.071516 -372.020846) (xy 56.046643 -371.993538) (xy 56.001736 -371.934883) (xy 55.981854 -371.903752)
			(xy 55.9749 -371.89386) (xy 55.954226 -371.881389) (xy 55.94223 -371.879876) (xy 55.915058 -371.877426)
			(xy 55.861744 -371.865863) (xy 55.810619 -371.846827) (xy 55.762726 -371.820706) (xy 55.719039 -371.788032)
			(xy 55.68045 -371.749471) (xy 55.647744 -371.705808) (xy 55.621588 -371.657933) (xy 55.602515 -371.606822)
			(xy 55.590913 -371.553517) (xy 55.587019 -371.499102) (xy 51.728634 -371.499102) (xy 51.724738 -371.553533)
			(xy 51.713131 -371.606854) (xy 51.694049 -371.657979) (xy 51.667882 -371.705866) (xy 51.635162 -371.749539)
			(xy 51.596556 -371.788107) (xy 51.552851 -371.820784) (xy 51.504939 -371.846905) (xy 51.453795 -371.865937)
			(xy 51.400463 -371.877491) (xy 51.373278 -371.879876) (xy 51.361282 -371.881382) (xy 51.340606 -371.893858)
			(xy 51.333654 -371.903752) (xy 51.313751 -371.934869) (xy 51.268843 -371.993519) (xy 51.243992 -372.020846)
			(xy 51.238464 -372.027204) (xy 51.231566 -372.042565) (xy 51.23007 -372.059337) (xy 51.2318 -372.067582)
			(xy 51.23704 -372.090207) (xy 51.242646 -372.136309) (xy 51.242976 -372.15953) (xy 51.242503 -372.186799)
			(xy 51.234738 -372.240783) (xy 51.21937 -372.293112) (xy 51.196711 -372.342721) (xy 51.167223 -372.388601)
			(xy 51.131507 -372.429818) (xy 51.090288 -372.465533) (xy 51.044407 -372.495019) (xy 50.994797 -372.517675)
			(xy 50.942467 -372.533042) (xy 50.888483 -372.540805) (xy 50.861214 -372.541292) (xy 50.833736 -372.540817)
			(xy 50.779352 -372.532913) (xy 50.726662 -372.517296) (xy 50.676754 -372.494288) (xy 50.63066 -372.464364)
			(xy 50.589331 -372.428142) (xy 50.55362 -372.386371) (xy 50.524266 -372.339912) (xy 50.501873 -372.289725)
			(xy 50.49393 -372.263416) (xy 50.491375 -372.255311) (xy 50.481678 -372.241363) (xy 50.467933 -372.23138)
			(xy 50.459894 -372.228618) (xy 50.428597 -372.218513) (xy 50.367695 -372.19368) (xy 50.309146 -372.163716)
			(xy 50.281078 -372.146576) (xy 50.272817 -372.14188) (xy 50.254154 -372.138372) (xy 50.235491 -372.14188)
			(xy 50.22723 -372.146576) (xy 50.199171 -372.163733) (xy 50.14063 -372.193719) (xy 50.079722 -372.218546)
			(xy 50.048414 -372.228618) (xy 50.040387 -372.231392) (xy 50.026674 -372.241396) (xy 50.016984 -372.255333)
			(xy 50.014378 -372.263416) (xy 50.006491 -372.289747) (xy 49.984115 -372.339952) (xy 49.954767 -372.386427)
			(xy 49.919054 -372.42821) (xy 49.877716 -372.464437) (xy 49.831608 -372.494358) (xy 49.781684 -372.517354)
			(xy 49.728976 -372.532949) (xy 49.674577 -372.54082) (xy 49.647094 -372.541292) (xy 49.619826 -372.540781)
			(xy 49.565845 -372.53302) (xy 49.513517 -372.517655) (xy 49.463909 -372.495) (xy 49.41803 -372.465517)
			(xy 49.376813 -372.429804) (xy 49.341098 -372.388589) (xy 49.311611 -372.342712) (xy 49.288953 -372.293105)
			(xy 49.273586 -372.240779) (xy 49.26582 -372.186798) (xy 49.265332 -372.15953) (xy 49.265657 -372.136309)
			(xy 49.271263 -372.090206) (xy 49.276508 -372.067582) (xy 49.278865 -372.055112) (xy 49.272452 -372.030588)
			(xy 49.264316 -372.020846) (xy 49.239443 -371.993538) (xy 49.194536 -371.934883) (xy 49.174654 -371.903752)
			(xy 49.1677 -371.89386) (xy 49.147026 -371.881389) (xy 49.13503 -371.879876) (xy 49.107858 -371.877426)
			(xy 49.054544 -371.865863) (xy 49.003419 -371.846827) (xy 48.955526 -371.820706) (xy 48.911839 -371.788032)
			(xy 48.87325 -371.749471) (xy 48.840544 -371.705808) (xy 48.814388 -371.657933) (xy 48.795315 -371.606822)
			(xy 48.783713 -371.553517) (xy 48.779819 -371.499102) (xy 44.921434 -371.499102) (xy 44.917538 -371.553533)
			(xy 44.905931 -371.606854) (xy 44.886849 -371.657979) (xy 44.860682 -371.705866) (xy 44.827962 -371.749539)
			(xy 44.789356 -371.788107) (xy 44.745651 -371.820784) (xy 44.697739 -371.846905) (xy 44.646595 -371.865937)
			(xy 44.593263 -371.877491) (xy 44.566078 -371.879876) (xy 44.554082 -371.881382) (xy 44.533406 -371.893858)
			(xy 44.526454 -371.903752) (xy 44.506551 -371.934869) (xy 44.461643 -371.993519) (xy 44.436792 -372.020846)
			(xy 44.431264 -372.027204) (xy 44.424366 -372.042565) (xy 44.42287 -372.059337) (xy 44.4246 -372.067582)
			(xy 44.42984 -372.090207) (xy 44.435446 -372.136309) (xy 44.435776 -372.15953) (xy 44.435303 -372.186799)
			(xy 44.427538 -372.240783) (xy 44.41217 -372.293112) (xy 44.389511 -372.342721) (xy 44.360023 -372.388601)
			(xy 44.324307 -372.429818) (xy 44.283088 -372.465533) (xy 44.237207 -372.495019) (xy 44.187597 -372.517675)
			(xy 44.135267 -372.533042) (xy 44.081283 -372.540805) (xy 44.054014 -372.541292) (xy 44.026536 -372.540817)
			(xy 43.972152 -372.532913) (xy 43.919462 -372.517296) (xy 43.869554 -372.494288) (xy 43.82346 -372.464364)
			(xy 43.782131 -372.428142) (xy 43.74642 -372.386371) (xy 43.717066 -372.339912) (xy 43.694673 -372.289725)
			(xy 43.68673 -372.263416) (xy 43.684175 -372.255311) (xy 43.674478 -372.241363) (xy 43.660733 -372.23138)
			(xy 43.652694 -372.228618) (xy 43.621397 -372.218513) (xy 43.560495 -372.19368) (xy 43.501946 -372.163716)
			(xy 43.473878 -372.146576) (xy 43.465617 -372.14188) (xy 43.446954 -372.138372) (xy 43.428291 -372.14188)
			(xy 43.42003 -372.146576) (xy 43.391971 -372.163733) (xy 43.33343 -372.193719) (xy 43.272522 -372.218546)
			(xy 43.241214 -372.228618) (xy 43.233187 -372.231392) (xy 43.219474 -372.241396) (xy 43.209784 -372.255333)
			(xy 43.207178 -372.263416) (xy 43.199291 -372.289747) (xy 43.176915 -372.339952) (xy 43.147567 -372.386427)
			(xy 43.111854 -372.42821) (xy 43.070516 -372.464437) (xy 43.024408 -372.494358) (xy 42.974484 -372.517354)
			(xy 42.921776 -372.532949) (xy 42.867377 -372.54082) (xy 42.839894 -372.541292) (xy 42.812626 -372.540781)
			(xy 42.758645 -372.53302) (xy 42.706317 -372.517655) (xy 42.656709 -372.495) (xy 42.61083 -372.465517)
			(xy 42.569613 -372.429804) (xy 42.533898 -372.388589) (xy 42.504411 -372.342712) (xy 42.481753 -372.293105)
			(xy 42.466386 -372.240779) (xy 42.45862 -372.186798) (xy 42.458132 -372.15953) (xy 42.458457 -372.136309)
			(xy 42.464063 -372.090206) (xy 42.469308 -372.067582) (xy 42.471665 -372.055112) (xy 42.465252 -372.030588)
			(xy 42.457116 -372.020846) (xy 42.432243 -371.993538) (xy 42.387336 -371.934883) (xy 42.367454 -371.903752)
			(xy 42.3605 -371.89386) (xy 42.339826 -371.881389) (xy 42.32783 -371.879876) (xy 42.300658 -371.877426)
			(xy 42.247344 -371.865863) (xy 42.196219 -371.846827) (xy 42.148326 -371.820706) (xy 42.104639 -371.788032)
			(xy 42.06605 -371.749471) (xy 42.033344 -371.705808) (xy 42.007188 -371.657933) (xy 41.988115 -371.606822)
			(xy 41.976513 -371.553517) (xy 41.972619 -371.499102) (xy 3.523996 -371.499102) (xy 3.523996 -379.448822)
			(xy 6.884924 -379.448822) (xy 6.884924 -374.65) (xy 6.885343 -374.63993) (xy 6.893068 -374.621332)
			(xy 6.89991 -374.613932) (xy 8.250428 -373.263414) (xy 8.257826 -373.256571) (xy 8.276427 -373.248852)
			(xy 8.286496 -373.248428) (xy 32.203898 -373.248428) (xy 32.213 -373.248047) (xy 32.230051 -373.241665)
			(xy 32.237172 -373.235982) (xy 32.308143 -373.175037) (xy 32.454602 -373.058616) (xy 32.605967 -372.948649)
			(xy 32.761952 -372.845341) (xy 32.922267 -372.748888) (xy 33.086609 -372.659469) (xy 33.25467 -372.577253)
			(xy 33.426135 -372.502395) (xy 33.600681 -372.435033) (xy 33.777982 -372.375296) (xy 33.957703 -372.323295)
			(xy 34.139509 -372.279128) (xy 34.323057 -372.242878) (xy 34.508003 -372.214613) (xy 34.694 -372.194385)
			(xy 34.880698 -372.182233) (xy 35.067748 -372.17818) (xy 35.254798 -372.182233) (xy 35.441496 -372.194385)
			(xy 35.627493 -372.214613) (xy 35.812439 -372.242878) (xy 35.995987 -372.279128) (xy 36.177793 -372.323295)
			(xy 36.357514 -372.375296) (xy 36.534815 -372.435033) (xy 36.709361 -372.502395) (xy 36.880826 -372.577253)
			(xy 37.048887 -372.659469) (xy 37.213229 -372.748888) (xy 37.373544 -372.845341) (xy 37.529529 -372.948649)
			(xy 37.680894 -373.058616) (xy 37.827353 -373.175037) (xy 37.898324 -373.235982) (xy 37.905448 -373.241662)
			(xy 37.922496 -373.248048) (xy 37.931598 -373.248428) (xy 47.52594 -373.248428) (xy 47.537205 -373.247864)
			(xy 47.557581 -373.238254) (xy 47.57189 -373.220853) (xy 47.575216 -373.210074) (xy 47.575216 -373.20982)
			(xy 47.582562 -373.182688) (xy 47.604069 -373.130759) (xy 47.632962 -373.082547) (xy 47.668618 -373.039097)
			(xy 47.710263 -373.00135) (xy 47.756996 -372.970121) (xy 47.807806 -372.946088) (xy 47.861592 -372.929771)
			(xy 47.917191 -372.921523) (xy 47.945294 -372.921022) (xy 47.972834 -372.921509) (xy 48.027345 -372.929403)
			(xy 48.080153 -372.945057) (xy 48.13016 -372.968146) (xy 48.176325 -372.998188) (xy 48.217689 -373.034559)
			(xy 48.253389 -373.076502) (xy 48.282684 -373.123145) (xy 48.304964 -373.173517) (xy 48.312832 -373.199914)
			(xy 48.315347 -373.208) (xy 48.324954 -373.221936) (xy 48.338614 -373.231932) (xy 48.346614 -373.234712)
			(xy 48.378364 -373.24538) (xy 48.391318 -373.247666) (xy 48.400208 -373.248428) (xy 48.717962 -373.248428)
			(xy 48.726344 -373.24538) (xy 48.758094 -373.234712) (xy 48.770032 -373.230247) (xy 48.787756 -373.211976)
			(xy 48.791876 -373.199914) (xy 48.799798 -373.173538) (xy 48.822095 -373.123184) (xy 48.851397 -373.076557)
			(xy 48.887096 -373.034626) (xy 48.92845 -372.99826) (xy 48.974601 -372.968214) (xy 49.024592 -372.945114)
			(xy 49.077383 -372.929438) (xy 49.131879 -372.921511) (xy 49.159414 -372.921022) (xy 49.18752 -372.921481)
			(xy 49.243124 -372.929731) (xy 49.296915 -372.946051) (xy 49.347729 -372.970087) (xy 49.394467 -373.001319)
			(xy 49.436116 -373.039071) (xy 49.471774 -373.082526) (xy 49.50067 -373.130743) (xy 49.522179 -373.182677)
			(xy 49.529492 -373.20982) (xy 49.529492 -373.210074) (xy 49.532858 -373.220832) (xy 49.547162 -373.238212)
			(xy 49.567514 -373.247829) (xy 49.578768 -373.248428) (xy 52.17414 -373.248428) (xy 52.184213 -373.248825)
			(xy 52.202811 -373.256565) (xy 52.210208 -373.263414) (xy 52.909696 -373.962902) (xy 53.885219 -373.962902)
			(xy 53.889113 -373.908488) (xy 53.900714 -373.855182) (xy 53.919786 -373.804071) (xy 53.945942 -373.756196)
			(xy 53.978647 -373.712533) (xy 54.017236 -373.673971) (xy 54.060922 -373.641296) (xy 54.108816 -373.615175)
			(xy 54.15994 -373.596138) (xy 54.213254 -373.584574) (xy 54.24043 -373.582184) (xy 54.252431 -373.580699)
			(xy 54.273106 -373.568209) (xy 54.280054 -373.558308) (xy 54.299952 -373.527189) (xy 54.344863 -373.46854)
			(xy 54.369716 -373.441214) (xy 54.375271 -373.434876) (xy 54.382161 -373.419505) (xy 54.383645 -373.402725)
			(xy 54.381908 -373.394478) (xy 54.376661 -373.371855) (xy 54.371059 -373.325751) (xy 54.370732 -373.30253)
			(xy 54.371229 -373.27526) (xy 54.378987 -373.221275) (xy 54.394349 -373.168943) (xy 54.417003 -373.11933)
			(xy 54.446487 -373.073447) (xy 54.482201 -373.032226) (xy 54.523418 -372.996509) (xy 54.569299 -372.96702)
			(xy 54.618909 -372.944362) (xy 54.671239 -372.928995) (xy 54.725224 -372.921232) (xy 54.752494 -372.920768)
			(xy 54.779974 -372.921193) (xy 54.834362 -372.929099) (xy 54.887056 -372.94472) (xy 54.936966 -372.967733)
			(xy 54.983062 -372.997663) (xy 55.024391 -373.033892) (xy 55.0601 -373.075671) (xy 55.089451 -373.122138)
			(xy 55.111838 -373.172332) (xy 55.119778 -373.198644) (xy 55.122406 -373.206721) (xy 55.132073 -373.22067)
			(xy 55.145788 -373.230667) (xy 55.153814 -373.233442) (xy 55.185113 -373.24354) (xy 55.246015 -373.268376)
			(xy 55.304563 -373.298343) (xy 55.33263 -373.315484) (xy 55.340891 -373.32018) (xy 55.359554 -373.323688)
			(xy 55.378217 -373.32018) (xy 55.386478 -373.315484) (xy 55.414535 -373.298323) (xy 55.473076 -373.268339)
			(xy 55.533985 -373.243514) (xy 55.565294 -373.233442) (xy 55.573308 -373.230637) (xy 55.58702 -373.220644)
			(xy 55.596717 -373.206721) (xy 55.59933 -373.198644) (xy 55.607274 -373.172333) (xy 55.629648 -373.122133)
			(xy 55.658992 -373.075662) (xy 55.694698 -373.033881) (xy 55.736029 -372.997655) (xy 55.782128 -372.967731)
			(xy 55.832044 -372.94473) (xy 55.884742 -372.929128) (xy 55.939134 -372.921246) (xy 55.966614 -372.920768)
			(xy 55.993887 -372.921189) (xy 56.047877 -372.928953) (xy 56.100212 -372.944323) (xy 56.149827 -372.966984)
			(xy 56.195712 -372.996476) (xy 56.236933 -373.032198) (xy 56.27265 -373.073423) (xy 56.302137 -373.119311)
			(xy 56.324792 -373.168929) (xy 56.340156 -373.221266) (xy 56.347915 -373.275257) (xy 56.348376 -373.30253)
			(xy 56.348044 -373.325751) (xy 56.342443 -373.371854) (xy 56.3372 -373.394478) (xy 56.334868 -373.40695)
			(xy 56.341264 -373.431471) (xy 56.349392 -373.441214) (xy 56.374256 -373.468531) (xy 56.419169 -373.52718)
			(xy 56.439054 -373.558308) (xy 56.446014 -373.568196) (xy 56.466683 -373.580671) (xy 56.478678 -373.582184)
			(xy 56.505867 -373.584509) (xy 56.559199 -373.596065) (xy 56.610343 -373.615097) (xy 56.658255 -373.641218)
			(xy 56.701959 -373.673896) (xy 56.740564 -373.712465) (xy 56.773284 -373.756137) (xy 56.799451 -373.804024)
			(xy 56.818532 -373.85515) (xy 56.830139 -373.908471) (xy 56.834034 -373.962902) (xy 60.692419 -373.962902)
			(xy 60.696313 -373.908488) (xy 60.707914 -373.855182) (xy 60.726986 -373.804071) (xy 60.753142 -373.756196)
			(xy 60.785847 -373.712533) (xy 60.824436 -373.673971) (xy 60.868122 -373.641296) (xy 60.916016 -373.615175)
			(xy 60.96714 -373.596138) (xy 61.020454 -373.584574) (xy 61.04763 -373.582184) (xy 61.059631 -373.580699)
			(xy 61.080306 -373.568209) (xy 61.087254 -373.558308) (xy 61.107152 -373.527189) (xy 61.152063 -373.46854)
			(xy 61.176916 -373.441214) (xy 61.182471 -373.434876) (xy 61.189361 -373.419505) (xy 61.190845 -373.402725)
			(xy 61.189108 -373.394478) (xy 61.183861 -373.371855) (xy 61.178259 -373.325751) (xy 61.177932 -373.30253)
			(xy 61.178429 -373.27526) (xy 61.186187 -373.221275) (xy 61.201549 -373.168943) (xy 61.224203 -373.11933)
			(xy 61.253687 -373.073447) (xy 61.289401 -373.032226) (xy 61.330618 -372.996509) (xy 61.376499 -372.96702)
			(xy 61.426109 -372.944362) (xy 61.478439 -372.928995) (xy 61.532424 -372.921232) (xy 61.559694 -372.920768)
			(xy 61.587174 -372.921193) (xy 61.641562 -372.929099) (xy 61.694256 -372.94472) (xy 61.744166 -372.967733)
			(xy 61.790262 -372.997663) (xy 61.831591 -373.033892) (xy 61.8673 -373.075671) (xy 61.896651 -373.122138)
			(xy 61.919038 -373.172332) (xy 61.926978 -373.198644) (xy 61.929606 -373.206721) (xy 61.939273 -373.22067)
			(xy 61.952988 -373.230667) (xy 61.961014 -373.233442) (xy 61.992313 -373.24354) (xy 62.053215 -373.268376)
			(xy 62.111763 -373.298343) (xy 62.13983 -373.315484) (xy 62.148091 -373.32018) (xy 62.166754 -373.323688)
			(xy 62.185417 -373.32018) (xy 62.193678 -373.315484) (xy 62.221735 -373.298323) (xy 62.280276 -373.268339)
			(xy 62.341185 -373.243514) (xy 62.372494 -373.233442) (xy 62.380508 -373.230637) (xy 62.39422 -373.220644)
			(xy 62.403917 -373.206721) (xy 62.40653 -373.198644) (xy 62.414474 -373.172333) (xy 62.436848 -373.122133)
			(xy 62.466192 -373.075662) (xy 62.501898 -373.033881) (xy 62.543229 -372.997655) (xy 62.589328 -372.967731)
			(xy 62.639244 -372.94473) (xy 62.691942 -372.929128) (xy 62.746334 -372.921246) (xy 62.773814 -372.920768)
			(xy 62.801087 -372.921189) (xy 62.855077 -372.928953) (xy 62.907412 -372.944323) (xy 62.957027 -372.966984)
			(xy 63.002912 -372.996476) (xy 63.044133 -373.032198) (xy 63.07985 -373.073423) (xy 63.109337 -373.119311)
			(xy 63.131992 -373.168929) (xy 63.147356 -373.221266) (xy 63.155115 -373.275257) (xy 63.155576 -373.30253)
			(xy 63.155244 -373.325751) (xy 63.149643 -373.371854) (xy 63.1444 -373.394478) (xy 63.142068 -373.40695)
			(xy 63.148464 -373.431471) (xy 63.156592 -373.441214) (xy 63.181456 -373.468531) (xy 63.226369 -373.52718)
			(xy 63.246254 -373.558308) (xy 63.253214 -373.568196) (xy 63.273883 -373.580671) (xy 63.285878 -373.582184)
			(xy 63.313067 -373.584509) (xy 63.366399 -373.596065) (xy 63.417543 -373.615097) (xy 63.465455 -373.641218)
			(xy 63.509159 -373.673896) (xy 63.547764 -373.712465) (xy 63.580484 -373.756137) (xy 63.606651 -373.804024)
			(xy 63.625732 -373.85515) (xy 63.637339 -373.908471) (xy 63.641234 -373.962902) (xy 63.637338 -374.017333)
			(xy 63.625731 -374.070654) (xy 63.606649 -374.121779) (xy 63.580482 -374.169666) (xy 63.547762 -374.213339)
			(xy 63.509156 -374.251907) (xy 63.465451 -374.284584) (xy 63.417539 -374.310705) (xy 63.366395 -374.329737)
			(xy 63.313063 -374.341291) (xy 63.285878 -374.343676) (xy 63.273882 -374.345182) (xy 63.253206 -374.357658)
			(xy 63.246254 -374.367552) (xy 63.226351 -374.398669) (xy 63.181443 -374.457319) (xy 63.156592 -374.484646)
			(xy 63.151064 -374.491004) (xy 63.144166 -374.506365) (xy 63.14267 -374.523137) (xy 63.1444 -374.531382)
			(xy 63.14964 -374.554007) (xy 63.155246 -374.600109) (xy 63.155576 -374.62333) (xy 63.155103 -374.650599)
			(xy 63.147338 -374.704583) (xy 63.13197 -374.756912) (xy 63.109311 -374.806521) (xy 63.079823 -374.852401)
			(xy 63.044107 -374.893618) (xy 63.002888 -374.929333) (xy 62.957007 -374.958819) (xy 62.907397 -374.981475)
			(xy 62.855067 -374.996842) (xy 62.801083 -375.004605) (xy 62.773814 -375.005092) (xy 62.746336 -375.004617)
			(xy 62.691952 -374.996713) (xy 62.639262 -374.981096) (xy 62.589354 -374.958088) (xy 62.54326 -374.928164)
			(xy 62.501931 -374.891942) (xy 62.46622 -374.850171) (xy 62.436866 -374.803712) (xy 62.414473 -374.753525)
			(xy 62.40653 -374.727216) (xy 62.403975 -374.719111) (xy 62.394278 -374.705163) (xy 62.380533 -374.69518)
			(xy 62.372494 -374.692418) (xy 62.341197 -374.682313) (xy 62.280295 -374.65748) (xy 62.221746 -374.627516)
			(xy 62.193678 -374.610376) (xy 62.185417 -374.60568) (xy 62.166754 -374.602172) (xy 62.148091 -374.60568)
			(xy 62.13983 -374.610376) (xy 62.111771 -374.627533) (xy 62.05323 -374.657519) (xy 61.992322 -374.682346)
			(xy 61.961014 -374.692418) (xy 61.952987 -374.695192) (xy 61.939274 -374.705196) (xy 61.929584 -374.719133)
			(xy 61.926978 -374.727216) (xy 61.919091 -374.753547) (xy 61.896715 -374.803752) (xy 61.867367 -374.850227)
			(xy 61.831654 -374.89201) (xy 61.790316 -374.928237) (xy 61.744208 -374.958158) (xy 61.694284 -374.981154)
			(xy 61.641576 -374.996749) (xy 61.587177 -375.00462) (xy 61.559694 -375.005092) (xy 61.532426 -375.004581)
			(xy 61.478445 -374.99682) (xy 61.426117 -374.981455) (xy 61.376509 -374.9588) (xy 61.33063 -374.929317)
			(xy 61.289413 -374.893604) (xy 61.253698 -374.852389) (xy 61.224211 -374.806512) (xy 61.201553 -374.756905)
			(xy 61.186186 -374.704579) (xy 61.17842 -374.650598) (xy 61.177932 -374.62333) (xy 61.178257 -374.600109)
			(xy 61.183863 -374.554006) (xy 61.189108 -374.531382) (xy 61.191465 -374.518912) (xy 61.185052 -374.494388)
			(xy 61.176916 -374.484646) (xy 61.152043 -374.457338) (xy 61.107136 -374.398683) (xy 61.087254 -374.367552)
			(xy 61.0803 -374.35766) (xy 61.059626 -374.345189) (xy 61.04763 -374.343676) (xy 61.020458 -374.341226)
			(xy 60.967144 -374.329663) (xy 60.916019 -374.310627) (xy 60.868126 -374.284506) (xy 60.824439 -374.251832)
			(xy 60.78585 -374.213271) (xy 60.753144 -374.169608) (xy 60.726988 -374.121733) (xy 60.707915 -374.070622)
			(xy 60.696313 -374.017317) (xy 60.692419 -373.962902) (xy 56.834034 -373.962902) (xy 56.830138 -374.017333)
			(xy 56.818531 -374.070654) (xy 56.799449 -374.121779) (xy 56.773282 -374.169666) (xy 56.740562 -374.213339)
			(xy 56.701956 -374.251907) (xy 56.658251 -374.284584) (xy 56.610339 -374.310705) (xy 56.559195 -374.329737)
			(xy 56.505863 -374.341291) (xy 56.478678 -374.343676) (xy 56.466682 -374.345182) (xy 56.446006 -374.357658)
			(xy 56.439054 -374.367552) (xy 56.419151 -374.398669) (xy 56.374243 -374.457319) (xy 56.349392 -374.484646)
			(xy 56.343864 -374.491004) (xy 56.336966 -374.506365) (xy 56.33547 -374.523137) (xy 56.3372 -374.531382)
			(xy 56.34244 -374.554007) (xy 56.348046 -374.600109) (xy 56.348376 -374.62333) (xy 56.347903 -374.650599)
			(xy 56.340138 -374.704583) (xy 56.32477 -374.756912) (xy 56.302111 -374.806521) (xy 56.272623 -374.852401)
			(xy 56.236907 -374.893618) (xy 56.195688 -374.929333) (xy 56.149807 -374.958819) (xy 56.100197 -374.981475)
			(xy 56.047867 -374.996842) (xy 55.993883 -375.004605) (xy 55.966614 -375.005092) (xy 55.939136 -375.004617)
			(xy 55.884752 -374.996713) (xy 55.832062 -374.981096) (xy 55.782154 -374.958088) (xy 55.73606 -374.928164)
			(xy 55.694731 -374.891942) (xy 55.65902 -374.850171) (xy 55.629666 -374.803712) (xy 55.607273 -374.753525)
			(xy 55.59933 -374.727216) (xy 55.596775 -374.719111) (xy 55.587078 -374.705163) (xy 55.573333 -374.69518)
			(xy 55.565294 -374.692418) (xy 55.533997 -374.682313) (xy 55.473095 -374.65748) (xy 55.414546 -374.627516)
			(xy 55.386478 -374.610376) (xy 55.378217 -374.60568) (xy 55.359554 -374.602172) (xy 55.340891 -374.60568)
			(xy 55.33263 -374.610376) (xy 55.304571 -374.627533) (xy 55.24603 -374.657519) (xy 55.185122 -374.682346)
			(xy 55.153814 -374.692418) (xy 55.145787 -374.695192) (xy 55.132074 -374.705196) (xy 55.122384 -374.719133)
			(xy 55.119778 -374.727216) (xy 55.111891 -374.753547) (xy 55.089515 -374.803752) (xy 55.060167 -374.850227)
			(xy 55.024454 -374.89201) (xy 54.983116 -374.928237) (xy 54.937008 -374.958158) (xy 54.887084 -374.981154)
			(xy 54.834376 -374.996749) (xy 54.779977 -375.00462) (xy 54.752494 -375.005092) (xy 54.725226 -375.004581)
			(xy 54.671245 -374.99682) (xy 54.618917 -374.981455) (xy 54.569309 -374.9588) (xy 54.52343 -374.929317)
			(xy 54.482213 -374.893604) (xy 54.446498 -374.852389) (xy 54.417011 -374.806512) (xy 54.394353 -374.756905)
			(xy 54.378986 -374.704579) (xy 54.37122 -374.650598) (xy 54.370732 -374.62333) (xy 54.371057 -374.600109)
			(xy 54.376663 -374.554006) (xy 54.381908 -374.531382) (xy 54.384265 -374.518912) (xy 54.377852 -374.494388)
			(xy 54.369716 -374.484646) (xy 54.344843 -374.457338) (xy 54.299936 -374.398683) (xy 54.280054 -374.367552)
			(xy 54.2731 -374.35766) (xy 54.252426 -374.345189) (xy 54.24043 -374.343676) (xy 54.213258 -374.341226)
			(xy 54.159944 -374.329663) (xy 54.108819 -374.310627) (xy 54.060926 -374.284506) (xy 54.017239 -374.251832)
			(xy 53.97865 -374.213271) (xy 53.945944 -374.169608) (xy 53.919788 -374.121733) (xy 53.900715 -374.070622)
			(xy 53.889113 -374.017317) (xy 53.885219 -373.962902) (xy 52.909696 -373.962902) (xy 54.678834 -375.73204)
			(xy 54.685689 -375.739428) (xy 54.693399 -375.758037) (xy 54.69382 -375.768108) (xy 54.69382 -383.172208)
			(xy 54.694214 -383.182232) (xy 54.70189 -383.200753) (xy 54.71607 -383.214926) (xy 54.734595 -383.222592)
			(xy 54.74462 -383.223008) (xy 69.284088 -383.223008) (xy 69.294108 -383.222571) (xy 69.312623 -383.214906)
			(xy 69.326795 -383.20074) (xy 69.334467 -383.182227) (xy 69.334888 -383.172208) (xy 69.334888 -370.009928)
			(xy 69.334393 -369.99956) (xy 69.326121 -369.980543) (xy 69.318886 -369.973098) (xy 69.30042 -369.955027)
			(xy 69.268013 -369.914786) (xy 69.241324 -369.870545) (xy 69.22084 -369.823112) (xy 69.213476 -369.798346)
			(xy 69.210926 -369.790273) (xy 69.201336 -369.776334) (xy 69.187689 -369.766332) (xy 69.179694 -369.763548)
			(xy 69.148486 -369.753477) (xy 69.087756 -369.728723) (xy 69.029374 -369.698849) (xy 69.001386 -369.68176)
			(xy 68.993122 -369.677055) (xy 68.974428 -369.673625) (xy 68.955772 -369.677253) (xy 68.947538 -369.682014)
			(xy 68.919442 -369.699185) (xy 68.860816 -369.729176) (xy 68.79982 -369.753994) (xy 68.768468 -369.764056)
			(xy 68.760428 -369.766809) (xy 68.746689 -369.776797) (xy 68.737013 -369.790756) (xy 68.734432 -369.798854)
			(xy 68.726523 -369.825223) (xy 68.704199 -369.875544) (xy 68.674878 -369.922136) (xy 68.639168 -369.964033)
			(xy 68.597809 -370.000365) (xy 68.55166 -370.030378) (xy 68.501677 -370.05345) (xy 68.448899 -370.069103)
			(xy 68.394419 -370.07701) (xy 68.366894 -370.077492) (xy 68.339626 -370.076981) (xy 68.285645 -370.06922)
			(xy 68.233317 -370.053855) (xy 68.183709 -370.0312) (xy 68.13783 -370.001717) (xy 68.096613 -369.966004)
			(xy 68.060898 -369.924789) (xy 68.031411 -369.878912) (xy 68.008753 -369.829305) (xy 67.993386 -369.776979)
			(xy 67.98562 -369.722998) (xy 67.985132 -369.69573) (xy 67.985132 -369.695222) (xy 67.985499 -369.671866)
			(xy 67.991231 -369.625508) (xy 67.996562 -369.602766) (xy 67.998873 -369.590291) (xy 67.992493 -369.565773)
			(xy 67.98437 -369.55603) (xy 67.959679 -369.528936) (xy 67.915022 -369.470798) (xy 67.895216 -369.439952)
			(xy 67.88828 -369.430044) (xy 67.867593 -369.417582) (xy 67.855592 -369.416076) (xy 67.828383 -369.413676)
			(xy 67.774985 -369.402195) (xy 67.723769 -369.383219) (xy 67.675782 -369.357135) (xy 67.632003 -369.324476)
			(xy 67.593328 -369.28591) (xy 67.560546 -369.242223) (xy 67.534327 -369.194309) (xy 67.515207 -369.143147)
			(xy 67.503576 -369.089781) (xy 67.499673 -369.035302) (xy 67.503576 -368.980823) (xy 67.515206 -368.927457)
			(xy 67.534325 -368.876295) (xy 67.560543 -368.828381) (xy 67.593325 -368.784694) (xy 67.632 -368.746126)
			(xy 67.675778 -368.713467) (xy 67.723765 -368.687383) (xy 67.774981 -368.668406) (xy 67.828379 -368.656925)
			(xy 67.855592 -368.654584) (xy 67.867589 -368.653078) (xy 67.888265 -368.640603) (xy 67.895216 -368.630708)
			(xy 67.915021 -368.599862) (xy 67.959675 -368.541721) (xy 67.98437 -368.51463) (xy 67.989921 -368.50829)
			(xy 67.996807 -368.492919) (xy 67.998295 -368.476141) (xy 67.996562 -368.467894) (xy 67.99123 -368.445152)
			(xy 67.985499 -368.398794) (xy 67.985132 -368.375438) (xy 67.985132 -368.37493) (xy 67.985629 -368.34766)
			(xy 67.993387 -368.293675) (xy 68.008749 -368.241343) (xy 68.031403 -368.19173) (xy 68.060887 -368.145847)
			(xy 68.096601 -368.104626) (xy 68.137818 -368.068909) (xy 68.183699 -368.03942) (xy 68.233309 -368.016762)
			(xy 68.285639 -368.001395) (xy 68.339624 -367.993632) (xy 68.366894 -367.993168) (xy 68.394418 -367.993648)
			(xy 68.448895 -368.001566) (xy 68.501669 -368.017225) (xy 68.551648 -368.040301) (xy 68.597796 -368.070314)
			(xy 68.639155 -368.106643) (xy 68.674868 -368.148535) (xy 68.704196 -368.195121) (xy 68.72653 -368.245436)
			(xy 68.734432 -368.271806) (xy 68.737072 -368.279866) (xy 68.746788 -368.293758) (xy 68.760476 -368.303759)
			(xy 68.768468 -368.306604) (xy 68.79982 -368.316667) (xy 68.86081 -368.341497) (xy 68.919439 -368.371481)
			(xy 68.947538 -368.388646) (xy 68.955793 -368.393347) (xy 68.974428 -368.396946) (xy 68.993101 -368.393544)
			(xy 69.001386 -368.3889) (xy 69.029368 -368.371799) (xy 69.087746 -368.341915) (xy 69.148478 -368.31716)
			(xy 69.179694 -368.307112) (xy 69.191632 -368.302647) (xy 69.209356 -368.284376) (xy 69.213476 -368.272314)
			(xy 69.220822 -368.247541) (xy 69.241289 -368.200095) (xy 69.267978 -368.15585) (xy 69.300401 -368.115617)
			(xy 69.318886 -368.097562) (xy 69.326077 -368.090088) (xy 69.334342 -368.071088) (xy 69.334888 -368.060732)
			(xy 69.334888 -367.864898) (xy 69.335289 -367.854826) (xy 69.343024 -367.836227) (xy 69.349874 -367.82883)
			(xy 70.42404 -366.754918) (xy 70.431434 -366.74807) (xy 70.450038 -366.740354) (xy 70.460108 -366.739932)
			(xy 182.040276 -366.739932) (xy 182.050345 -366.740362) (xy 182.068943 -366.748079) (xy 182.076344 -366.754918)
			(xy 184.63133 -369.30965) (xy 184.638145 -369.31707) (xy 184.645878 -369.335654) (xy 184.646316 -369.345718)
			(xy 184.646316 -373.956834) (xy 282.471114 -373.956834) (xy 282.471739 -373.914145) (xy 282.481298 -373.829303)
			(xy 282.500255 -373.746055) (xy 282.528374 -373.66544) (xy 282.565305 -373.588462) (xy 282.587446 -373.551958)
			(xy 282.592117 -373.543684) (xy 282.595637 -373.525029) (xy 282.592138 -373.50637) (xy 282.587446 -373.49811)
			(xy 282.565303 -373.461607) (xy 282.528357 -373.384633) (xy 282.500229 -373.304019) (xy 282.481271 -373.220769)
			(xy 282.471719 -373.135924) (xy 282.471114 -373.093234) (xy 282.47166 -373.053233) (xy 282.480019 -372.97367)
			(xy 282.496649 -372.895417) (xy 282.521368 -372.81933) (xy 282.553904 -372.746245) (xy 282.593902 -372.676961)
			(xy 282.640924 -372.612237) (xy 282.694453 -372.552783) (xy 282.753904 -372.49925) (xy 282.818625 -372.452225)
			(xy 282.887907 -372.412223) (xy 282.960991 -372.379683) (xy 283.037076 -372.35496) (xy 283.115329 -372.338325)
			(xy 283.194892 -372.329962) (xy 283.234892 -372.329456) (xy 283.275327 -372.329955) (xy 283.355745 -372.338503)
			(xy 283.43481 -372.355493) (xy 283.51164 -372.380736) (xy 283.585376 -372.413949) (xy 283.655193 -372.454761)
			(xy 283.720311 -372.502716) (xy 283.750512 -372.529608) (xy 283.758153 -372.536152) (xy 283.777034 -372.543063)
			(xy 283.797118 -372.542149) (xy 283.806392 -372.538244) (xy 283.830255 -372.527496) (xy 283.880344 -372.512327)
			(xy 283.932116 -372.504666) (xy 283.958284 -372.504208) (xy 283.986285 -372.504802) (xy 284.041598 -372.51356)
			(xy 284.094861 -372.530863) (xy 284.14476 -372.556284) (xy 284.190069 -372.589199) (xy 284.229671 -372.628796)
			(xy 284.262592 -372.6741) (xy 284.28802 -372.723997) (xy 284.305329 -372.777257) (xy 284.314095 -372.832569)
			(xy 284.314646 -372.86057) (xy 284.314081 -372.88807) (xy 284.305629 -372.942415) (xy 284.288921 -372.994816)
			(xy 284.264356 -373.044024) (xy 284.232516 -373.08887) (xy 284.19416 -373.128287) (xy 284.1502 -373.161338)
			(xy 284.10168 -373.187237) (xy 284.049755 -373.205367) (xy 284.0228 -373.210836) (xy 284.012957 -373.21306)
			(xy 283.996044 -373.224043) (xy 283.984646 -373.240679) (xy 283.98216 -373.25046) (xy 283.972326 -373.294116)
			(xy 283.94378 -373.378932) (xy 283.905521 -373.459833) (xy 283.882338 -373.49811) (xy 283.877613 -373.506358)
			(xy 283.874112 -373.525029) (xy 283.877634 -373.543697) (xy 283.882338 -373.551958) (xy 283.904004 -373.587611)
			(xy 283.940308 -373.662731) (xy 283.968217 -373.741357) (xy 283.97835 -373.781828) (xy 283.98087 -373.790807)
			(xy 283.991268 -373.806266) (xy 284.006504 -373.816988) (xy 284.015434 -373.819674) (xy 284.04073 -373.826572)
			(xy 284.089147 -373.846691) (xy 284.134091 -373.873689) (xy 284.174594 -373.906983) (xy 284.209779 -373.945853)
			(xy 284.238888 -373.98946) (xy 284.261292 -374.036863) (xy 284.276506 -374.087037) (xy 284.284203 -374.138899)
			(xy 284.284674 -374.165114) (xy 284.284126 -374.193117) (xy 284.275363 -374.248433) (xy 284.258055 -374.301697)
			(xy 284.232628 -374.351598) (xy 284.199708 -374.396907) (xy 284.160106 -374.436509) (xy 284.114796 -374.469429)
			(xy 284.064895 -374.494855) (xy 284.011631 -374.512163) (xy 283.956315 -374.520926) (xy 283.928312 -374.521476)
			(xy 283.928058 -374.521476) (xy 283.898074 -374.520826) (xy 283.838958 -374.510742) (xy 283.810456 -374.50141)
			(xy 283.801553 -374.498768) (xy 283.78301 -374.499329) (xy 283.765892 -374.506484) (xy 283.758894 -374.512586)
			(xy 283.728487 -374.540473) (xy 283.662696 -374.590269) (xy 283.591922 -374.632684) (xy 283.51699 -374.667224)
			(xy 283.438771 -374.693487) (xy 283.358177 -374.711168) (xy 283.276147 -374.720059) (xy 283.234892 -374.720612)
			(xy 283.194893 -374.720062) (xy 283.115332 -374.711699) (xy 283.037081 -374.695067) (xy 282.960997 -374.670346)
			(xy 282.887915 -374.637807) (xy 282.818633 -374.597808) (xy 282.753912 -374.550787) (xy 282.69446 -374.497258)
			(xy 282.64093 -374.437808) (xy 282.593906 -374.373089) (xy 282.553905 -374.303809) (xy 282.521364 -374.230727)
			(xy 282.49664 -374.154644) (xy 282.480005 -374.076394) (xy 282.471639 -373.996833) (xy 282.471114 -373.956834)
			(xy 184.646316 -373.956834) (xy 184.646316 -377.678385) (xy 193.900548 -377.678385) (xy 193.900548 -377.593663)
			(xy 193.908601 -377.509326) (xy 193.924635 -377.426136) (xy 193.948503 -377.344846) (xy 193.979991 -377.266194)
			(xy 194.018813 -377.190891) (xy 194.064616 -377.119619) (xy 194.116987 -377.053023) (xy 194.175452 -376.991708)
			(xy 194.23948 -376.936227) (xy 194.308492 -376.887084) (xy 194.381862 -376.844724) (xy 194.458927 -376.809529)
			(xy 194.538989 -376.78182) (xy 194.621322 -376.761846) (xy 194.705181 -376.749789) (xy 194.789806 -376.745758)
			(xy 194.874431 -376.749789) (xy 194.95829 -376.761846) (xy 195.040623 -376.78182) (xy 195.120685 -376.809529)
			(xy 195.19775 -376.844724) (xy 195.27112 -376.887084) (xy 195.340132 -376.936227) (xy 195.40416 -376.991708)
			(xy 195.462625 -377.053023) (xy 195.514996 -377.119619) (xy 195.560799 -377.190891) (xy 195.599621 -377.266194)
			(xy 195.631109 -377.344846) (xy 195.654977 -377.426136) (xy 195.671011 -377.509326) (xy 195.679064 -377.593663)
			(xy 195.679568 -377.636024) (xy 195.679064 -377.678385) (xy 195.671011 -377.762722) (xy 195.654977 -377.845912)
			(xy 195.631109 -377.927202) (xy 195.599621 -378.005854) (xy 195.560799 -378.081157) (xy 195.514996 -378.152429)
			(xy 195.47531 -378.202895) (xy 199.443082 -378.202895) (xy 199.443082 -378.118173) (xy 199.451135 -378.033836)
			(xy 199.467169 -377.950646) (xy 199.491037 -377.869356) (xy 199.522525 -377.790704) (xy 199.561347 -377.715401)
			(xy 199.60715 -377.644129) (xy 199.659521 -377.577533) (xy 199.717986 -377.516218) (xy 199.782014 -377.460737)
			(xy 199.851026 -377.411594) (xy 199.924396 -377.369234) (xy 200.001461 -377.334039) (xy 200.081523 -377.30633)
			(xy 200.163856 -377.286356) (xy 200.247715 -377.274299) (xy 200.33234 -377.270268) (xy 200.416965 -377.274299)
			(xy 200.500824 -377.286356) (xy 200.583157 -377.30633) (xy 200.663219 -377.334039) (xy 200.740284 -377.369234)
			(xy 200.813654 -377.411594) (xy 200.882666 -377.460737) (xy 200.946694 -377.516218) (xy 201.005159 -377.577533)
			(xy 201.05753 -377.644129) (xy 201.103333 -377.715401) (xy 201.142155 -377.790704) (xy 201.173643 -377.869356)
			(xy 201.197511 -377.950646) (xy 201.213545 -378.033836) (xy 201.221598 -378.118173) (xy 201.222102 -378.160534)
			(xy 201.221598 -378.202895) (xy 201.213545 -378.287232) (xy 201.197511 -378.370422) (xy 201.173643 -378.451712)
			(xy 201.142155 -378.530364) (xy 201.103333 -378.605667) (xy 201.05753 -378.676939) (xy 201.005159 -378.743535)
			(xy 200.946694 -378.80485) (xy 200.882666 -378.860331) (xy 200.813654 -378.909474) (xy 200.740284 -378.951834)
			(xy 200.663219 -378.987029) (xy 200.583157 -379.014738) (xy 200.500824 -379.034712) (xy 200.416965 -379.046769)
			(xy 200.33234 -379.050801) (xy 200.247715 -379.046769) (xy 200.163856 -379.034712) (xy 200.081523 -379.014738)
			(xy 200.001461 -378.987029) (xy 199.924396 -378.951834) (xy 199.851026 -378.909474) (xy 199.782014 -378.860331)
			(xy 199.717986 -378.80485) (xy 199.659521 -378.743535) (xy 199.60715 -378.676939) (xy 199.561347 -378.605667)
			(xy 199.522525 -378.530364) (xy 199.491037 -378.451712) (xy 199.467169 -378.370422) (xy 199.451135 -378.287232)
			(xy 199.443082 -378.202895) (xy 195.47531 -378.202895) (xy 195.462625 -378.219025) (xy 195.40416 -378.28034)
			(xy 195.340132 -378.335821) (xy 195.27112 -378.384964) (xy 195.19775 -378.427324) (xy 195.120685 -378.462519)
			(xy 195.040623 -378.490228) (xy 194.95829 -378.510202) (xy 194.874431 -378.522259) (xy 194.789806 -378.526291)
			(xy 194.705181 -378.522259) (xy 194.621322 -378.510202) (xy 194.538989 -378.490228) (xy 194.458927 -378.462519)
			(xy 194.381862 -378.427324) (xy 194.308492 -378.384964) (xy 194.23948 -378.335821) (xy 194.175452 -378.28034)
			(xy 194.116987 -378.219025) (xy 194.064616 -378.152429) (xy 194.018813 -378.081157) (xy 193.979991 -378.005854)
			(xy 193.948503 -377.927202) (xy 193.924635 -377.845912) (xy 193.908601 -377.762722) (xy 193.900548 -377.678385)
			(xy 184.646316 -377.678385) (xy 184.646316 -386.496052) (xy 184.645888 -386.506121) (xy 184.638171 -386.52472)
			(xy 184.63133 -386.53212) (xy 182.435816 -388.727385) (xy 193.900548 -388.727385) (xy 193.900548 -388.642663)
			(xy 193.908601 -388.558326) (xy 193.924635 -388.475136) (xy 193.948503 -388.393846) (xy 193.979991 -388.315194)
			(xy 194.018813 -388.239891) (xy 194.064616 -388.168619) (xy 194.116987 -388.102023) (xy 194.175452 -388.040708)
			(xy 194.23948 -387.985227) (xy 194.308492 -387.936084) (xy 194.381862 -387.893724) (xy 194.458927 -387.858529)
			(xy 194.538989 -387.83082) (xy 194.621322 -387.810846) (xy 194.705181 -387.798789) (xy 194.789806 -387.794758)
			(xy 194.874431 -387.798789) (xy 194.95829 -387.810846) (xy 195.040623 -387.83082) (xy 195.120685 -387.858529)
			(xy 195.19775 -387.893724) (xy 195.27112 -387.936084) (xy 195.340132 -387.985227) (xy 195.40416 -388.040708)
			(xy 195.462625 -388.102023) (xy 195.514996 -388.168619) (xy 195.560799 -388.239891) (xy 195.599621 -388.315194)
			(xy 195.631109 -388.393846) (xy 195.654977 -388.475136) (xy 195.671011 -388.558326) (xy 195.679064 -388.642663)
			(xy 195.679568 -388.685024) (xy 195.679064 -388.727385) (xy 195.671011 -388.811722) (xy 195.654977 -388.894912)
			(xy 195.631109 -388.976202) (xy 195.599621 -389.054854) (xy 195.560799 -389.130157) (xy 195.514996 -389.201429)
			(xy 195.462625 -389.268025) (xy 195.40416 -389.32934) (xy 195.340132 -389.384821) (xy 195.27112 -389.433964)
			(xy 195.19775 -389.476324) (xy 195.120685 -389.511519) (xy 195.040623 -389.539228) (xy 194.95829 -389.559202)
			(xy 194.874431 -389.571259) (xy 194.789806 -389.575291) (xy 194.705181 -389.571259) (xy 194.621322 -389.559202)
			(xy 194.538989 -389.539228) (xy 194.458927 -389.511519) (xy 194.381862 -389.476324) (xy 194.308492 -389.433964)
			(xy 194.23948 -389.384821) (xy 194.175452 -389.32934) (xy 194.116987 -389.268025) (xy 194.064616 -389.201429)
			(xy 194.018813 -389.130157) (xy 193.979991 -389.054854) (xy 193.948503 -388.976202) (xy 193.924635 -388.894912)
			(xy 193.908601 -388.811722) (xy 193.900548 -388.727385) (xy 182.435816 -388.727385) (xy 182.395622 -388.767574)
			(xy 182.390796 -388.80034) (xy 182.398416 -388.815072) (xy 182.411846 -388.842316) (xy 182.430869 -388.899996)
			(xy 182.4405 -388.959964) (xy 182.441088 -388.990332) (xy 182.441088 -388.990586) (xy 182.440613 -389.018022)
			(xy 182.43278 -389.07233) (xy 182.417244 -389.124955) (xy 182.394328 -389.174811) (xy 182.364502 -389.220868)
			(xy 182.328384 -389.262175) (xy 182.286719 -389.29788) (xy 182.240368 -389.327244) (xy 182.190286 -389.349663)
			(xy 182.137509 -389.364674) (xy 182.11038 -389.368792) (xy 182.101236 -389.370062) (xy 182.08498 -389.378952)
			(xy 182.028338 -389.44423) (xy 182.022242 -389.461756) (xy 182.022496 -389.471154) (xy 182.022496 -389.478012)
			(xy 182.022033 -389.505264) (xy 182.014275 -389.559213) (xy 181.998918 -389.611509) (xy 181.976274 -389.661087)
			(xy 181.946806 -389.706938) (xy 181.911112 -389.748129) (xy 181.869919 -389.78382) (xy 181.824066 -389.813286)
			(xy 181.774487 -389.835926) (xy 181.72219 -389.85128) (xy 181.66824 -389.859035) (xy 181.640988 -389.85952)
			(xy 181.612444 -389.858973) (xy 181.555994 -389.850464) (xy 181.501441 -389.833639) (xy 181.450005 -389.808873)
			(xy 181.402834 -389.776718) (xy 181.36098 -389.737894) (xy 181.325379 -389.693266) (xy 181.296826 -389.643832)
			(xy 181.285896 -389.617458) (xy 181.280308 -389.60298) (xy 181.2544 -389.5852) (xy 180.156866 -389.5852)
			(xy 180.147008 -389.585579) (xy 180.128711 -389.592904) (xy 180.121306 -389.599424) (xy 180.094678 -389.624638)
			(xy 180.037347 -389.670374) (xy 179.975891 -389.710395) (xy 179.910877 -389.744331) (xy 179.842905 -389.77187)
			(xy 179.772603 -389.792755) (xy 179.700621 -389.806795) (xy 179.627623 -389.81386) (xy 179.590954 -389.814308)
			(xy 179.590446 -389.814308) (xy 179.553776 -389.813898) (xy 179.480777 -389.806832) (xy 179.408793 -389.792788)
			(xy 179.338491 -389.771897) (xy 179.27052 -389.744352) (xy 179.205508 -389.710407) (xy 179.144056 -389.670377)
			(xy 179.086731 -389.62463) (xy 179.060094 -389.599424) (xy 179.052659 -389.59295) (xy 179.034382 -389.585618)
			(xy 179.024534 -389.5852) (xy 170.472608 -389.5852) (xy 170.462536 -389.584797) (xy 170.443936 -389.577064)
			(xy 170.43654 -389.570214) (xy 169.67327 -388.806944) (xy 169.665858 -388.80026) (xy 169.647425 -388.792663)
			(xy 169.627487 -388.792663) (xy 169.609054 -388.80026) (xy 169.601642 -388.806944) (xy 169.429684 -388.978902)
			(xy 169.427144 -388.982712) (xy 169.413777 -389.00151) (xy 169.383186 -389.036035) (xy 169.348655 -389.06662)
			(xy 169.329862 -389.079994) (xy 169.326052 -389.082788) (xy 168.884854 -389.523986) (xy 168.877428 -389.530793)
			(xy 168.858849 -389.538533) (xy 168.848786 -389.538972) (xy 167.995854 -389.538972) (xy 167.986393 -389.539399)
			(xy 167.968773 -389.546294) (xy 167.961564 -389.552434) (xy 167.933335 -389.577968) (xy 167.872341 -389.623514)
			(xy 167.806835 -389.662292) (xy 167.737567 -389.69386) (xy 167.665325 -389.717856) (xy 167.590936 -389.734007)
			(xy 167.515247 -389.742129) (xy 167.439125 -389.742129) (xy 167.363436 -389.734007) (xy 167.289047 -389.717856)
			(xy 167.216805 -389.69386) (xy 167.147537 -389.662292) (xy 167.082031 -389.623514) (xy 167.021037 -389.577968)
			(xy 166.992808 -389.552434) (xy 166.985565 -389.54635) (xy 166.967966 -389.539456) (xy 166.958518 -389.538972)
			(xy 166.137336 -389.538972) (xy 166.111428 -389.557006) (xy 166.10584 -389.572246) (xy 166.097401 -389.593961)
			(xy 166.074924 -389.634766) (xy 166.046512 -389.671685) (xy 166.012823 -389.703861) (xy 165.974639 -389.730548)
			(xy 165.932845 -389.751128) (xy 165.888411 -389.765123) (xy 165.842367 -389.772208) (xy 165.819074 -389.772652)
			(xy 165.795665 -389.772204) (xy 165.749396 -389.765054) (xy 165.704761 -389.750924) (xy 165.662806 -389.730146)
			(xy 165.624515 -389.703208) (xy 165.590784 -389.670739) (xy 165.562405 -389.633503) (xy 165.55085 -389.61314)
			(xy 165.549834 -389.611108) (xy 165.549326 -389.610346) (xy 165.151562 -388.922006) (xy 165.139686 -388.899329)
			(xy 165.122835 -388.850996) (xy 165.114262 -388.800533) (xy 165.113716 -388.77494) (xy 165.113716 -388.774432)
			(xy 165.113819 -388.763151) (xy 165.115471 -388.740649) (xy 165.117018 -388.729474) (xy 165.117901 -388.720759)
			(xy 165.1144 -388.703611) (xy 165.11016 -388.695946) (xy 165.071298 -388.631938) (xy 165.057582 -388.620762)
			(xy 165.048946 -388.617968) (xy 165.025655 -388.60965) (xy 164.981925 -388.586551) (xy 164.942485 -388.556713)
			(xy 164.908365 -388.520913) (xy 164.880455 -388.480086) (xy 164.859483 -388.435298) (xy 164.845996 -388.387717)
			(xy 164.842698 -388.363206) (xy 164.840633 -388.350912) (xy 164.826526 -388.330396) (xy 164.815774 -388.32409)
			(xy 164.776047 -388.302446) (xy 164.701904 -388.250604) (xy 164.667946 -388.220712) (xy 164.661088 -388.214362)
			(xy 164.643308 -388.207504) (xy 164.449252 -388.207504) (xy 164.431472 -388.214362) (xy 164.424614 -388.220712)
			(xy 164.390491 -388.250711) (xy 164.315964 -388.302685) (xy 164.276024 -388.324344) (xy 164.267346 -388.32932)
			(xy 164.254516 -388.344648) (xy 164.251132 -388.354062) (xy 164.247068 -388.384796) (xy 164.249862 -388.400036)
			(xy 164.288978 -388.463282) (xy 164.293902 -388.470694) (xy 164.307821 -388.481757) (xy 164.316156 -388.484872)
			(xy 164.338391 -388.492825) (xy 164.380288 -388.514606) (xy 164.418348 -388.542558) (xy 164.451669 -388.576017)
			(xy 164.479462 -388.614192) (xy 164.490654 -388.634986) (xy 164.491162 -388.636256) (xy 164.883592 -389.314944)
			(xy 164.896306 -389.338272) (xy 164.914407 -389.388215) (xy 164.923631 -389.44053) (xy 164.924232 -389.46709)
			(xy 164.924232 -389.467344) (xy 164.923778 -389.491335) (xy 164.916266 -389.538726) (xy 164.901434 -389.584359)
			(xy 164.879647 -389.62711) (xy 164.851442 -389.665927) (xy 164.817512 -389.699855) (xy 164.778693 -389.728058)
			(xy 164.73594 -389.749842) (xy 164.690307 -389.764671) (xy 164.642915 -389.77218) (xy 164.618924 -389.772652)
			(xy 164.595515 -389.772222) (xy 164.549248 -389.765064) (xy 164.504615 -389.750928) (xy 164.462663 -389.730146)
			(xy 164.424375 -389.703203) (xy 164.390648 -389.670732) (xy 164.362273 -389.633493) (xy 164.3507 -389.61314)
			(xy 164.349684 -389.611108) (xy 164.349176 -389.610346) (xy 163.951412 -388.922006) (xy 163.939498 -388.899337)
			(xy 163.92256 -388.851012) (xy 163.9139 -388.800542) (xy 163.913312 -388.77494) (xy 163.913312 -388.774432)
			(xy 163.913453 -388.763019) (xy 163.915235 -388.740262) (xy 163.916868 -388.728966) (xy 163.916868 -388.728712)
			(xy 163.917775 -388.719998) (xy 163.914256 -388.702848) (xy 163.91001 -388.695184) (xy 163.871148 -388.63143)
			(xy 163.859464 -388.621778) (xy 163.834569 -388.613852) (xy 163.787731 -388.590714) (xy 163.745506 -388.559952)
			(xy 163.709124 -388.522461) (xy 163.679644 -388.479332) (xy 163.657922 -388.43182) (xy 163.644592 -388.381307)
			(xy 163.641786 -388.355332) (xy 163.638448 -388.345535) (xy 163.625335 -388.329545) (xy 163.616386 -388.324344)
			(xy 163.57651 -388.302677) (xy 163.502116 -388.250697) (xy 163.46805 -388.220712) (xy 163.461192 -388.214362)
			(xy 163.443412 -388.207504) (xy 163.249102 -388.207504) (xy 163.231322 -388.214362) (xy 163.224464 -388.220712)
			(xy 163.190555 -388.250525) (xy 163.116541 -388.302239) (xy 163.07689 -388.323836) (xy 163.066115 -388.330117)
			(xy 163.052001 -388.350646) (xy 163.049966 -388.362952) (xy 163.048442 -388.374636) (xy 163.047357 -388.383603)
			(xy 163.050875 -388.401306) (xy 163.0553 -388.40918) (xy 163.088828 -388.463282) (xy 163.093734 -388.470707)
			(xy 163.107666 -388.481764) (xy 163.116006 -388.484872) (xy 163.138275 -388.492796) (xy 163.180241 -388.514544)
			(xy 163.218363 -388.542487) (xy 163.251734 -388.575962) (xy 163.279558 -388.61417) (xy 163.290758 -388.634986)
			(xy 163.291266 -388.636256) (xy 163.683696 -389.314944) (xy 163.69641 -389.338271) (xy 163.714511 -389.388215)
			(xy 163.723735 -389.44053) (xy 163.724336 -389.46709) (xy 163.724336 -389.467344) (xy 163.723878 -389.491335)
			(xy 163.716366 -389.538726) (xy 163.701535 -389.584358) (xy 163.679748 -389.627109) (xy 163.651543 -389.665926)
			(xy 163.617613 -389.699853) (xy 163.578795 -389.728056) (xy 163.536043 -389.749841) (xy 163.49041 -389.76467)
			(xy 163.443019 -389.772179) (xy 163.419028 -389.772652) (xy 163.395619 -389.772219) (xy 163.349352 -389.765062)
			(xy 163.30472 -389.750926) (xy 163.262768 -389.730144) (xy 163.22448 -389.703202) (xy 163.190753 -389.670731)
			(xy 163.162377 -389.633493) (xy 163.150804 -389.61314) (xy 163.149788 -389.611108) (xy 163.14928 -389.610346)
			(xy 162.751516 -388.922006) (xy 162.739602 -388.899337) (xy 162.722664 -388.851012) (xy 162.714004 -388.800542)
			(xy 162.713416 -388.77494) (xy 162.713416 -388.774432) (xy 162.713496 -388.763023) (xy 162.715153 -388.740267)
			(xy 162.716718 -388.728966) (xy 162.717636 -388.720126) (xy 162.71414 -388.702718) (xy 162.70986 -388.69493)
			(xy 162.677094 -388.640828) (xy 162.672135 -388.63333) (xy 162.658078 -388.622143) (xy 162.649662 -388.618984)
			(xy 162.62621 -388.610675) (xy 162.582158 -388.587556) (xy 162.542428 -388.557612) (xy 162.508067 -388.521634)
			(xy 162.479982 -388.480569) (xy 162.458912 -388.4355) (xy 162.445414 -388.387616) (xy 162.442144 -388.362952)
			(xy 162.440132 -388.350643) (xy 162.425989 -388.330132) (xy 162.41522 -388.323836) (xy 162.375631 -388.302235)
			(xy 162.301746 -388.250517) (xy 162.2679 -388.220712) (xy 162.261042 -388.214362) (xy 162.243262 -388.207504)
			(xy 162.049206 -388.207504) (xy 162.031426 -388.214362) (xy 162.024568 -388.220712) (xy 161.990439 -388.250705)
			(xy 161.915917 -388.302682) (xy 161.875978 -388.324344) (xy 161.86731 -388.329335) (xy 161.854473 -388.344652)
			(xy 161.851086 -388.354062) (xy 161.847022 -388.384796) (xy 161.849816 -388.400036) (xy 161.888932 -388.463282)
			(xy 161.893871 -388.470682) (xy 161.90778 -388.481752) (xy 161.91611 -388.484872) (xy 161.938337 -388.492846)
			(xy 161.980235 -388.514622) (xy 162.018297 -388.542568) (xy 162.05162 -388.576022) (xy 162.079415 -388.614194)
			(xy 162.090608 -388.634986) (xy 162.091116 -388.636256) (xy 162.483546 -389.314944) (xy 162.496353 -389.338286)
			(xy 162.51458 -389.388304) (xy 162.523847 -389.440727) (xy 162.52444 -389.467344) (xy 162.523979 -389.491322)
			(xy 162.516475 -389.538688) (xy 162.501659 -389.584298) (xy 162.479895 -389.627032) (xy 162.451718 -389.665837)
			(xy 162.417822 -389.699761) (xy 162.379038 -389.727969) (xy 162.336322 -389.749767) (xy 162.290724 -389.764619)
			(xy 162.243364 -389.77216) (xy 162.219386 -389.772652) (xy 162.218878 -389.772652) (xy 162.195469 -389.772201)
			(xy 162.1492 -389.765051) (xy 162.104566 -389.750922) (xy 162.062611 -389.730145) (xy 162.024319 -389.703207)
			(xy 161.990588 -389.670739) (xy 161.962209 -389.633503) (xy 161.950654 -389.61314) (xy 161.949638 -389.611108)
			(xy 161.94913 -389.610346) (xy 161.551366 -388.922006) (xy 161.539491 -388.899329) (xy 161.522639 -388.850996)
			(xy 161.514066 -388.800533) (xy 161.51352 -388.77494) (xy 161.51352 -388.774432) (xy 161.513601 -388.76296)
			(xy 161.515252 -388.740076) (xy 161.516822 -388.728712) (xy 161.518092 -388.719822) (xy 161.51479 -388.702296)
			(xy 161.471102 -388.63143) (xy 161.459418 -388.621778) (xy 161.434514 -388.613879) (xy 161.387677 -388.590734)
			(xy 161.345454 -388.559967) (xy 161.309074 -388.522471) (xy 161.279595 -388.479338) (xy 161.257875 -388.431823)
			(xy 161.244545 -388.381308) (xy 161.24174 -388.355332) (xy 161.238464 -388.345555) (xy 161.22549 -388.329556)
			(xy 161.216594 -388.324344) (xy 161.202439 -388.316827) (xy 161.174742 -388.300693) (xy 161.161222 -388.292086)
			(xy 161.153378 -388.287464) (xy 161.13561 -388.283553) (xy 161.117591 -388.286066) (xy 161.109406 -388.290054)
			(xy 161.03092 -388.33298) (xy 161.023114 -388.337631) (xy 161.0112 -388.351334) (xy 161.004861 -388.36835)
			(xy 161.004504 -388.37743) (xy 161.004504 -388.818374) (xy 161.004738 -388.825035) (xy 161.008216 -388.837897)
			(xy 161.011362 -388.843774) (xy 161.28365 -389.314944) (xy 161.296457 -389.338285) (xy 161.314684 -389.388304)
			(xy 161.323951 -389.440726) (xy 161.324544 -389.467344) (xy 161.324107 -389.492284) (xy 161.316008 -389.5415)
			(xy 161.300016 -389.588746) (xy 161.276557 -389.632764) (xy 161.246255 -389.672383) (xy 161.209915 -389.706549)
			(xy 161.168505 -389.734354) (xy 161.123126 -389.755057) (xy 161.074985 -389.768109) (xy 161.050224 -389.771128)
			(xy 161.04997 -389.771128) (xy 161.040726 -389.772505) (xy 161.024099 -389.781009) (xy 161.011614 -389.794899)
			(xy 161.004924 -389.812336) (xy 161.004504 -389.821674) (xy 161.004504 -392.303) (xy 161.007044 -392.310874)
			(xy 161.01579 -392.339616) (xy 161.025228 -392.398946) (xy 161.02584 -392.428984) (xy 161.02584 -393.292838)
			(xy 161.46272 -393.292838) (xy 161.46272 -392.429238) (xy 161.463206 -392.401987) (xy 161.470962 -392.348039)
			(xy 161.486317 -392.295744) (xy 161.508959 -392.246167) (xy 161.538425 -392.200317) (xy 161.574116 -392.159126)
			(xy 161.615307 -392.123435) (xy 161.661157 -392.093969) (xy 161.710734 -392.071327) (xy 161.763029 -392.055972)
			(xy 161.816977 -392.048216) (xy 161.871479 -392.048216) (xy 161.925427 -392.055972) (xy 161.977722 -392.071327)
			(xy 162.027299 -392.093969) (xy 162.073149 -392.123435) (xy 162.11434 -392.159126) (xy 162.150031 -392.200317)
			(xy 162.179497 -392.246167) (xy 162.202139 -392.295744) (xy 162.217494 -392.348039) (xy 162.22525 -392.401987)
			(xy 162.225736 -392.429238) (xy 162.225736 -393.292838) (xy 162.662616 -393.292838) (xy 162.662616 -392.429238)
			(xy 162.663102 -392.401987) (xy 162.670858 -392.348039) (xy 162.686213 -392.295744) (xy 162.708855 -392.246167)
			(xy 162.738321 -392.200317) (xy 162.774012 -392.159126) (xy 162.815203 -392.123435) (xy 162.861053 -392.093969)
			(xy 162.91063 -392.071327) (xy 162.962925 -392.055972) (xy 163.016873 -392.048216) (xy 163.071375 -392.048216)
			(xy 163.125323 -392.055972) (xy 163.177618 -392.071327) (xy 163.227195 -392.093969) (xy 163.273045 -392.123435)
			(xy 163.314236 -392.159126) (xy 163.349927 -392.200317) (xy 163.379393 -392.246167) (xy 163.402035 -392.295744)
			(xy 163.41739 -392.348039) (xy 163.425146 -392.401987) (xy 163.425632 -392.429238) (xy 163.425632 -393.292838)
			(xy 163.862512 -393.292838) (xy 163.862512 -392.429238) (xy 163.862998 -392.401969) (xy 163.87076 -392.347985)
			(xy 163.886125 -392.295655) (xy 163.908782 -392.246045) (xy 163.938268 -392.200164) (xy 163.973983 -392.158947)
			(xy 164.0152 -392.123232) (xy 164.061081 -392.093746) (xy 164.110691 -392.071089) (xy 164.163021 -392.055724)
			(xy 164.217005 -392.047962) (xy 164.271543 -392.047962) (xy 164.325527 -392.055724) (xy 164.377857 -392.071089)
			(xy 164.427467 -392.093746) (xy 164.473348 -392.123232) (xy 164.514565 -392.158947) (xy 164.55028 -392.200164)
			(xy 164.579766 -392.246045) (xy 164.602423 -392.295655) (xy 164.617788 -392.347985) (xy 164.62555 -392.401969)
			(xy 164.626036 -392.429238) (xy 164.626036 -393.292838) (xy 165.062408 -393.292838) (xy 165.062408 -392.429238)
			(xy 165.062894 -392.401969) (xy 165.070656 -392.347985) (xy 165.086021 -392.295655) (xy 165.108678 -392.246045)
			(xy 165.138164 -392.200164) (xy 165.173879 -392.158947) (xy 165.215096 -392.123232) (xy 165.260977 -392.093746)
			(xy 165.310587 -392.071089) (xy 165.362917 -392.055724) (xy 165.416901 -392.047962) (xy 165.471439 -392.047962)
			(xy 165.525423 -392.055724) (xy 165.577753 -392.071089) (xy 165.627363 -392.093746) (xy 165.673244 -392.123232)
			(xy 165.714461 -392.158947) (xy 165.750176 -392.200164) (xy 165.779662 -392.246045) (xy 165.802319 -392.295655)
			(xy 165.817684 -392.347985) (xy 165.825446 -392.401969) (xy 165.825932 -392.429238) (xy 165.825932 -393.292838)
			(xy 165.825446 -393.320107) (xy 165.817684 -393.374091) (xy 165.802319 -393.426421) (xy 165.779662 -393.476031)
			(xy 165.750176 -393.521912) (xy 165.714461 -393.563129) (xy 165.673244 -393.598844) (xy 165.627363 -393.62833)
			(xy 165.577753 -393.650987) (xy 165.525423 -393.666352) (xy 165.471439 -393.674114) (xy 165.416901 -393.674114)
			(xy 165.362917 -393.666352) (xy 165.310587 -393.650987) (xy 165.260977 -393.62833) (xy 165.215096 -393.598844)
			(xy 165.173879 -393.563129) (xy 165.138164 -393.521912) (xy 165.108678 -393.476031) (xy 165.086021 -393.426421)
			(xy 165.070656 -393.374091) (xy 165.062894 -393.320107) (xy 165.062408 -393.292838) (xy 164.626036 -393.292838)
			(xy 164.62555 -393.320107) (xy 164.617788 -393.374091) (xy 164.602423 -393.426421) (xy 164.579766 -393.476031)
			(xy 164.55028 -393.521912) (xy 164.514565 -393.563129) (xy 164.473348 -393.598844) (xy 164.427467 -393.62833)
			(xy 164.377857 -393.650987) (xy 164.325527 -393.666352) (xy 164.271543 -393.674114) (xy 164.217005 -393.674114)
			(xy 164.163021 -393.666352) (xy 164.110691 -393.650987) (xy 164.061081 -393.62833) (xy 164.0152 -393.598844)
			(xy 163.973983 -393.563129) (xy 163.938268 -393.521912) (xy 163.908782 -393.476031) (xy 163.886125 -393.426421)
			(xy 163.87076 -393.374091) (xy 163.862998 -393.320107) (xy 163.862512 -393.292838) (xy 163.425632 -393.292838)
			(xy 163.425146 -393.320089) (xy 163.41739 -393.374037) (xy 163.402035 -393.426332) (xy 163.379393 -393.475909)
			(xy 163.349927 -393.521759) (xy 163.314236 -393.56295) (xy 163.273045 -393.598641) (xy 163.227195 -393.628107)
			(xy 163.177618 -393.650749) (xy 163.125323 -393.666104) (xy 163.071375 -393.67386) (xy 163.016873 -393.67386)
			(xy 162.962925 -393.666104) (xy 162.91063 -393.650749) (xy 162.861053 -393.628107) (xy 162.815203 -393.598641)
			(xy 162.774012 -393.56295) (xy 162.738321 -393.521759) (xy 162.708855 -393.475909) (xy 162.686213 -393.426332)
			(xy 162.670858 -393.374037) (xy 162.663102 -393.320089) (xy 162.662616 -393.292838) (xy 162.225736 -393.292838)
			(xy 162.22525 -393.320089) (xy 162.217494 -393.374037) (xy 162.202139 -393.426332) (xy 162.179497 -393.475909)
			(xy 162.150031 -393.521759) (xy 162.11434 -393.56295) (xy 162.073149 -393.598641) (xy 162.027299 -393.628107)
			(xy 161.977722 -393.650749) (xy 161.925427 -393.666104) (xy 161.871479 -393.67386) (xy 161.816977 -393.67386)
			(xy 161.763029 -393.666104) (xy 161.710734 -393.650749) (xy 161.661157 -393.628107) (xy 161.615307 -393.598641)
			(xy 161.574116 -393.56295) (xy 161.538425 -393.521759) (xy 161.508959 -393.475909) (xy 161.486317 -393.426332)
			(xy 161.470962 -393.374037) (xy 161.463206 -393.320089) (xy 161.46272 -393.292838) (xy 161.02584 -393.292838)
			(xy 161.02584 -393.293092) (xy 161.025273 -393.323133) (xy 161.015831 -393.382469) (xy 161.007044 -393.411202)
			(xy 161.004504 -393.419076) (xy 161.004504 -397.747236) (xy 161.004883 -397.757311) (xy 161.012633 -397.77591)
			(xy 161.01949 -397.783304) (xy 161.736278 -398.499838) (xy 161.744744 -398.507519) (xy 161.766262 -398.515154)
			(xy 161.77768 -398.51457) (xy 161.868104 -398.504664) (xy 161.887662 -398.492726) (xy 161.893758 -398.48282)
			(xy 161.914719 -398.450841) (xy 161.962093 -398.390818) (xy 162.015238 -398.335839) (xy 162.073621 -398.286458)
			(xy 162.136655 -398.24317) (xy 162.203706 -398.206411) (xy 162.2741 -398.17655) (xy 162.347131 -398.153887)
			(xy 162.422063 -398.13865) (xy 162.498145 -398.130992) (xy 162.536378 -398.130522) (xy 162.576287 -398.131025)
			(xy 162.655667 -398.139367) (xy 162.73374 -398.15596) (xy 162.809651 -398.180623) (xy 162.882568 -398.213087)
			(xy 162.951692 -398.252995) (xy 163.016266 -398.29991) (xy 163.075582 -398.353318) (xy 163.12899 -398.412634)
			(xy 163.175905 -398.477208) (xy 163.215813 -398.546332) (xy 163.248277 -398.619249) (xy 163.27294 -398.69516)
			(xy 163.289533 -398.773233) (xy 163.297875 -398.852613) (xy 163.298378 -398.892522) (xy 163.297844 -398.932367)
			(xy 163.289537 -399.011624) (xy 163.273005 -399.089581) (xy 163.248429 -399.165387) (xy 163.216078 -399.238215)
			(xy 163.176303 -399.30727) (xy 163.12954 -399.371798) (xy 163.103306 -399.401792) (xy 163.095912 -399.410721)
			(xy 163.089434 -399.432958) (xy 163.09086 -399.444464) (xy 163.096084 -399.476658) (xy 163.101681 -399.541645)
			(xy 163.102036 -399.574258) (xy 163.101566 -399.611548) (xy 163.094226 -399.685768) (xy 163.07966 -399.758913)
			(xy 163.06927 -399.79473) (xy 163.06927 -399.795238) (xy 163.067031 -399.804067) (xy 163.068306 -399.822227)
			(xy 163.075823 -399.838807) (xy 163.08197 -399.84553) (xy 165.362382 -402.125942) (xy 165.369231 -402.133336)
			(xy 165.376946 -402.15194) (xy 165.377368 -402.16201) (xy 165.377368 -404.885605) (xy 166.678094 -404.885605)
			(xy 166.678094 -404.699771) (xy 166.686089 -404.514108) (xy 166.702064 -404.328962) (xy 166.72599 -404.144674)
			(xy 166.757822 -403.961586) (xy 166.797502 -403.780037) (xy 166.844955 -403.600363) (xy 166.900095 -403.422897)
			(xy 166.962818 -403.247968) (xy 167.033009 -403.075899) (xy 167.110538 -402.90701) (xy 167.195261 -402.741612)
			(xy 167.287022 -402.580012) (xy 167.38565 -402.42251) (xy 167.490963 -402.269396) (xy 167.602765 -402.120956)
			(xy 167.72085 -401.977462) (xy 167.845 -401.839182) (xy 167.974983 -401.706371) (xy 168.11056 -401.579275)
			(xy 168.25148 -401.45813) (xy 168.39748 -401.343159) (xy 168.548292 -401.234576) (xy 168.703636 -401.132583)
			(xy 168.863224 -401.037366) (xy 169.026761 -400.949104) (xy 169.193943 -400.867959) (xy 169.364462 -400.794082)
			(xy 169.538001 -400.727609) (xy 169.71424 -400.668664) (xy 169.892851 -400.617356) (xy 170.073504 -400.573779)
			(xy 170.255865 -400.538015) (xy 170.439595 -400.510129) (xy 170.624355 -400.490174) (xy 170.809802 -400.478186)
			(xy 170.995594 -400.474188) (xy 171.181386 -400.478186) (xy 171.366833 -400.490174) (xy 171.551593 -400.510129)
			(xy 171.735323 -400.538015) (xy 171.917684 -400.573779) (xy 172.098337 -400.617356) (xy 172.276948 -400.668664)
			(xy 172.453187 -400.727609) (xy 172.626726 -400.794082) (xy 172.797245 -400.867959) (xy 172.964427 -400.949104)
			(xy 173.127964 -401.037366) (xy 173.287552 -401.132583) (xy 173.442896 -401.234576) (xy 173.593708 -401.343159)
			(xy 173.739708 -401.45813) (xy 173.880628 -401.579275) (xy 174.016205 -401.706371) (xy 174.146188 -401.839182)
			(xy 174.270338 -401.977462) (xy 174.388423 -402.120956) (xy 174.500225 -402.269396) (xy 174.605538 -402.42251)
			(xy 174.704166 -402.580012) (xy 174.795927 -402.741612) (xy 174.88065 -402.90701) (xy 174.958179 -403.075899)
			(xy 175.02837 -403.247968) (xy 175.091093 -403.422897) (xy 175.146233 -403.600363) (xy 175.193686 -403.780037)
			(xy 175.233366 -403.961586) (xy 175.265198 -404.144674) (xy 175.289124 -404.328962) (xy 175.305099 -404.514108)
			(xy 175.313094 -404.699771) (xy 175.313594 -404.792688) (xy 175.313094 -404.885605) (xy 175.305099 -405.071268)
			(xy 175.289124 -405.256414) (xy 175.265198 -405.440702) (xy 175.233366 -405.62379) (xy 175.193686 -405.805339)
			(xy 175.146233 -405.985013) (xy 175.091093 -406.162479) (xy 175.02837 -406.337408) (xy 174.958179 -406.509477)
			(xy 174.88065 -406.678366) (xy 174.795927 -406.843764) (xy 174.704166 -407.005364) (xy 174.605538 -407.162866)
			(xy 174.500225 -407.31598) (xy 174.388423 -407.46442) (xy 174.270338 -407.607914) (xy 174.146188 -407.746194)
			(xy 174.016205 -407.879005) (xy 173.880628 -408.006101) (xy 173.739708 -408.127246) (xy 173.593708 -408.242217)
			(xy 173.442896 -408.3508) (xy 173.287552 -408.452793) (xy 173.127964 -408.54801) (xy 172.964427 -408.636272)
			(xy 172.797245 -408.717417) (xy 172.626726 -408.791294) (xy 172.453187 -408.857767) (xy 172.276948 -408.916712)
			(xy 172.098337 -408.96802) (xy 171.917684 -409.011597) (xy 171.735323 -409.047361) (xy 171.551593 -409.075247)
			(xy 171.366833 -409.095202) (xy 171.181386 -409.10719) (xy 170.995594 -409.111188) (xy 170.809802 -409.10719)
			(xy 170.624355 -409.095202) (xy 170.439595 -409.075247) (xy 170.255865 -409.047361) (xy 170.073504 -409.011597)
			(xy 169.892851 -408.96802) (xy 169.71424 -408.916712) (xy 169.538001 -408.857767) (xy 169.364462 -408.791294)
			(xy 169.193943 -408.717417) (xy 169.026761 -408.636272) (xy 168.863224 -408.54801) (xy 168.703636 -408.452793)
			(xy 168.548292 -408.3508) (xy 168.39748 -408.242217) (xy 168.25148 -408.127246) (xy 168.11056 -408.006101)
			(xy 167.974983 -407.879005) (xy 167.845 -407.746194) (xy 167.72085 -407.607914) (xy 167.602765 -407.46442)
			(xy 167.490963 -407.31598) (xy 167.38565 -407.162866) (xy 167.287022 -407.005364) (xy 167.195261 -406.843764)
			(xy 167.110538 -406.678366) (xy 167.033009 -406.509477) (xy 166.962818 -406.337408) (xy 166.900095 -406.162479)
			(xy 166.844955 -405.985013) (xy 166.797502 -405.805339) (xy 166.757822 -405.62379) (xy 166.72599 -405.440702)
			(xy 166.702064 -405.256414) (xy 166.686089 -405.071268) (xy 166.678094 -404.885605) (xy 165.377368 -404.885605)
			(xy 165.377368 -409.640024) (xy 165.377739 -409.648939) (xy 165.383856 -409.665688) (xy 165.395342 -409.679327)
			(xy 165.410806 -409.688205) (xy 165.419532 -409.690062) (xy 165.45709 -409.696951) (xy 165.530706 -409.717246)
			(xy 165.601924 -409.7448) (xy 165.670031 -409.779336) (xy 165.734344 -409.820507) (xy 165.794218 -409.867902)
			(xy 165.849054 -409.921045) (xy 165.898303 -409.979405) (xy 165.94147 -410.042395) (xy 165.978124 -410.109386)
			(xy 166.007896 -410.179706) (xy 166.030489 -410.252649) (xy 166.045677 -410.327486) (xy 166.053306 -410.403467)
			(xy 166.05377 -410.441648) (xy 166.05377 -410.441902) (xy 166.053256 -410.482152) (xy 166.044743 -410.562202)
			(xy 166.027844 -410.64091) (xy 166.005717 -410.708348) (xy 183.940958 -410.708348) (xy 183.940958 -400.09572)
			(xy 183.941483 -400.070772) (xy 183.94929 -400.021491) (xy 183.964701 -399.974034) (xy 183.987336 -399.929568)
			(xy 184.01664 -399.889183) (xy 184.033922 -399.871184) (xy 184.239408 -399.665698) (xy 184.257395 -399.648399)
			(xy 184.297773 -399.619076) (xy 184.342241 -399.59643) (xy 184.389704 -399.581018) (xy 184.438993 -399.57322)
			(xy 184.463944 -399.572734) (xy 188.119004 -399.572734) (xy 188.143952 -399.57325) (xy 188.193234 -399.581061)
			(xy 188.24069 -399.596474) (xy 188.285156 -399.619111) (xy 188.32554 -399.648416) (xy 188.34354 -399.665698)
			(xy 188.362082 -399.684494) (xy 188.369495 -399.691318) (xy 188.388084 -399.699047) (xy 188.39815 -399.69948)
			(xy 188.444124 -399.69948) (xy 188.454131 -399.699968) (xy 188.472619 -399.707632) (xy 188.486771 -399.721784)
			(xy 188.494433 -399.740273) (xy 188.494924 -399.75028) (xy 188.494924 -399.796) (xy 188.495459 -399.805899)
			(xy 188.503018 -399.8242) (xy 188.509656 -399.83156) (xy 188.528452 -399.85061) (xy 188.545762 -399.868588)
			(xy 188.575091 -399.908966) (xy 188.597741 -399.953436) (xy 188.613156 -400.000901) (xy 188.620956 -400.050193)
			(xy 188.621416 -400.075146) (xy 188.621416 -402.753322) (xy 188.621826 -402.763393) (xy 188.629557 -402.781991)
			(xy 188.636402 -402.78939) (xy 191.190372 -405.34336) (xy 191.197792 -405.350175) (xy 191.216376 -405.35791)
			(xy 191.22644 -405.358346) (xy 195.26631 -405.358346) (xy 195.276382 -405.35794) (xy 195.29498 -405.350207)
			(xy 195.302378 -405.34336) (xy 197.179184 -403.466554) (xy 197.185991 -403.459128) (xy 197.193731 -403.440549)
			(xy 197.19417 -403.430486) (xy 197.19417 -400.104356) (xy 197.194651 -400.079406) (xy 197.202469 -400.030123)
			(xy 197.217889 -399.982665) (xy 197.240534 -399.9382) (xy 197.269848 -399.897818) (xy 197.287134 -399.87982)
			(xy 197.53961 -399.627344) (xy 197.557604 -399.610052) (xy 197.597979 -399.580727) (xy 197.642445 -399.558078)
			(xy 197.689907 -399.542665) (xy 197.739195 -399.534866) (xy 197.764146 -399.53438) (xy 201.33818 -399.53438)
			(xy 201.363128 -399.534898) (xy 201.41241 -399.542706) (xy 201.459867 -399.558118) (xy 201.504334 -399.580755)
			(xy 201.544717 -399.610061) (xy 201.562716 -399.627344) (xy 201.823066 -399.887694) (xy 201.840352 -399.905693)
			(xy 201.869678 -399.946068) (xy 201.892327 -399.990532) (xy 201.907742 -400.037992) (xy 201.915543 -400.08728)
			(xy 201.91603 -400.11223) (xy 201.91603 -403.422612) (xy 201.916441 -403.432683) (xy 201.924171 -403.451281)
			(xy 201.931016 -403.45868) (xy 202.036172 -403.563836) (xy 202.053479 -403.581816) (xy 202.082802 -403.622195)
			(xy 202.105447 -403.666665) (xy 202.120857 -403.714129) (xy 202.128652 -403.76342) (xy 202.129136 -403.788372)
			(xy 202.129136 -406.516078) (xy 202.129564 -406.526147) (xy 202.137282 -406.544745) (xy 202.144122 -406.552146)
			(xy 203.1365 -407.544524) (xy 203.14386 -407.551203) (xy 203.162204 -407.558804) (xy 203.18206 -407.55887)
			(xy 203.200455 -407.551392) (xy 203.207874 -407.544778) (xy 203.208128 -407.544524) (xy 203.234897 -407.518495)
			(xy 203.292695 -407.47122) (xy 203.354838 -407.429822) (xy 203.420731 -407.3947) (xy 203.489743 -407.366189)
			(xy 203.561212 -407.344564) (xy 203.634454 -407.33003) (xy 203.708765 -407.322729) (xy 203.7461 -407.322274)
			(xy 203.784342 -407.322756) (xy 203.860439 -407.330431) (xy 203.935385 -407.345686) (xy 204.008428 -407.368366)
			(xy 204.078834 -407.398244) (xy 204.145896 -407.435019) (xy 204.20894 -407.478323) (xy 204.267332 -407.527719)
			(xy 204.320487 -407.582713) (xy 204.367869 -407.642751) (xy 204.409004 -407.70723) (xy 204.443479 -407.775504)
			(xy 204.470945 -407.846885) (xy 204.491129 -407.920657) (xy 204.49794 -407.95829) (xy 204.499688 -407.967077)
			(xy 204.508531 -407.982651) (xy 204.522201 -407.994222) (xy 204.539023 -408.000371) (xy 204.547978 -408.000708)
			(xy 205.795372 -408.000708) (xy 205.805443 -408.000292) (xy 205.824042 -407.992567) (xy 205.83144 -407.985722)
			(xy 207.658716 -406.158446) (xy 207.66553 -406.151026) (xy 207.673264 -406.132442) (xy 207.673702 -406.122378)
			(xy 207.673702 -403.722586) (xy 207.674193 -403.697637) (xy 207.682006 -403.648353) (xy 207.697424 -403.600896)
			(xy 207.720068 -403.55643) (xy 207.74938 -403.516048) (xy 207.766666 -403.49805) (xy 207.847184 -403.417532)
			(xy 207.854 -403.410113) (xy 207.861735 -403.391528) (xy 207.86217 -403.381464) (xy 207.86217 -400.079464)
			(xy 207.862656 -400.054515) (xy 207.870472 -400.005231) (xy 207.885892 -399.957774) (xy 207.908536 -399.913308)
			(xy 207.937848 -399.872926) (xy 207.955134 -399.854928) (xy 208.201514 -399.608548) (xy 208.21949 -399.591236)
			(xy 208.259869 -399.561908) (xy 208.304339 -399.539258) (xy 208.351805 -399.523843) (xy 208.401097 -399.516044)
			(xy 208.42605 -399.515584) (xy 211.971128 -399.515584) (xy 211.996077 -399.516071) (xy 212.045361 -399.523886)
			(xy 212.092818 -399.539306) (xy 212.137284 -399.561949) (xy 212.177666 -399.591262) (xy 212.195664 -399.608548)
			(xy 212.507576 -399.92046) (xy 212.524847 -399.938473) (xy 212.554175 -399.978843) (xy 212.576826 -400.023305)
			(xy 212.592245 -400.070762) (xy 212.600051 -400.120047) (xy 212.60054 -400.144996) (xy 212.60054 -403.480016)
			(xy 212.600947 -403.490088) (xy 212.608679 -403.508686) (xy 212.615526 -403.516084) (xy 212.638894 -403.539452)
			(xy 212.656213 -403.557421) (xy 212.685533 -403.597804) (xy 212.708176 -403.642276) (xy 212.723583 -403.689743)
			(xy 212.731376 -403.739036) (xy 212.731858 -403.763988) (xy 212.731858 -406.258014) (xy 212.732261 -406.268086)
			(xy 212.739995 -406.286685) (xy 212.746844 -406.294082) (xy 213.909148 -407.456386) (xy 213.918075 -407.464228)
			(xy 213.940643 -407.471552) (xy 213.964107 -407.468029) (xy 213.974172 -407.46172) (xy 214.00639 -407.439635)
			(xy 214.074493 -407.401378) (xy 214.146148 -407.370278) (xy 214.220606 -407.346659) (xy 214.297086 -407.330769)
			(xy 214.374789 -407.322775) (xy 214.413846 -407.322274) (xy 214.4141 -407.322274) (xy 214.453201 -407.322745)
			(xy 214.530992 -407.330766) (xy 214.607553 -407.346704) (xy 214.682083 -407.370392) (xy 214.753797 -407.40158)
			(xy 214.821945 -407.439942) (xy 214.88581 -407.485074) (xy 214.944722 -407.536504) (xy 214.998064 -407.593691)
			(xy 215.045275 -407.656036) (xy 215.085859 -407.722884) (xy 215.119392 -407.793533) (xy 215.14552 -407.867242)
			(xy 215.16397 -407.943237) (xy 215.16975 -407.981912) (xy 215.17229 -408.000962) (xy 215.200738 -408.025854)
			(xy 216.38895 -408.025854) (xy 216.399018 -408.025415) (xy 216.417617 -408.017705) (xy 216.425018 -408.010868)
			(xy 218.335098 -406.100788) (xy 218.341936 -406.093386) (xy 218.349657 -406.074788) (xy 218.350084 -406.06472)
			(xy 218.350084 -403.755606) (xy 218.350592 -403.730657) (xy 218.358403 -403.681375) (xy 218.373817 -403.633918)
			(xy 218.396456 -403.589452) (xy 218.425764 -403.549069) (xy 218.443048 -403.53107) (xy 218.50731 -403.466808)
			(xy 218.51414 -403.4594) (xy 218.521865 -403.440807) (xy 218.522296 -403.43074) (xy 218.522296 -400.095974)
			(xy 218.522781 -400.071024) (xy 218.530596 -400.021741) (xy 218.546016 -399.974283) (xy 218.56866 -399.929817)
			(xy 218.597974 -399.889436) (xy 218.61526 -399.871438) (xy 218.820746 -399.665952) (xy 218.838709 -399.648625)
			(xy 218.879091 -399.619299) (xy 218.923564 -399.596652) (xy 218.971033 -399.581241) (xy 219.020328 -399.573446)
			(xy 219.045282 -399.572988) (xy 222.709232 -399.572988) (xy 222.734182 -399.573471) (xy 222.783465 -399.581288)
			(xy 222.830923 -399.596707) (xy 222.875388 -399.619352) (xy 222.91577 -399.648666) (xy 222.933768 -399.665952)
			(xy 223.130618 -399.862802) (xy 223.147917 -399.880789) (xy 223.177239 -399.921168) (xy 223.199885 -399.965636)
			(xy 223.215297 -400.013098) (xy 223.223096 -400.062387) (xy 223.223582 -400.087338) (xy 223.223582 -403.455124)
			(xy 223.223973 -403.465198) (xy 223.231716 -403.483796) (xy 223.238568 -403.491192) (xy 223.323658 -403.576282)
			(xy 223.340937 -403.594288) (xy 223.370264 -403.63466) (xy 223.392915 -403.679123) (xy 223.408331 -403.726582)
			(xy 223.416134 -403.775868) (xy 223.416622 -403.800818) (xy 223.416622 -406.262078) (xy 223.417053 -406.272147)
			(xy 223.424769 -406.290745) (xy 223.431608 -406.298146) (xy 224.597722 -407.46426) (xy 224.634044 -407.467308)
			(xy 224.649284 -407.456894) (xy 224.681129 -407.435538) (xy 224.748312 -407.398577) (xy 224.818867 -407.368551)
			(xy 224.892082 -407.345763) (xy 224.967215 -407.330443) (xy 225.043506 -407.322747) (xy 225.081846 -407.322274)
			(xy 225.0821 -407.322274) (xy 225.119934 -407.322682) (xy 225.19523 -407.330193) (xy 225.269411 -407.345122)
			(xy 225.34175 -407.367321) (xy 225.411536 -407.396574) (xy 225.478083 -407.432592) (xy 225.540737 -407.475021)
			(xy 225.598883 -407.523445) (xy 225.651949 -407.577387) (xy 225.699414 -407.636318) (xy 225.740811 -407.699659)
			(xy 225.775734 -407.766787) (xy 225.803839 -407.837043) (xy 225.824851 -407.909736) (xy 225.832162 -407.94686)
			(xy 225.835464 -407.965148) (xy 225.863658 -407.988516) (xy 227.066094 -407.988516) (xy 227.076166 -407.98811)
			(xy 227.094765 -407.980378) (xy 227.102162 -407.97353) (xy 228.999288 -406.076404) (xy 229.006117 -406.068995)
			(xy 229.013844 -406.050403) (xy 229.014274 -406.040336) (xy 229.014274 -403.768052) (xy 229.014751 -403.743102)
			(xy 229.02257 -403.693818) (xy 229.037991 -403.646361) (xy 229.060637 -403.601896) (xy 229.089951 -403.561514)
			(xy 229.107238 -403.543516) (xy 229.183692 -403.467062) (xy 229.19054 -403.459668) (xy 229.198255 -403.441064)
			(xy 229.198678 -403.430994) (xy 229.198678 -400.11223) (xy 229.199203 -400.087282) (xy 229.20701 -400.038)
			(xy 229.22242 -399.990544) (xy 229.245055 -399.946077) (xy 229.27436 -399.905693) (xy 229.291642 -399.887694)
			(xy 229.521766 -399.65757) (xy 229.539767 -399.640284) (xy 229.580139 -399.610952) (xy 229.624602 -399.588297)
			(xy 229.672062 -399.572876) (xy 229.721351 -399.56507) (xy 229.746302 -399.564606) (xy 233.352594 -399.564606)
			(xy 233.377543 -399.565108) (xy 233.426826 -399.572919) (xy 233.474284 -399.588334) (xy 233.51875 -399.610975)
			(xy 233.559132 -399.640285) (xy 233.57713 -399.65757) (xy 233.798872 -399.879312) (xy 233.816168 -399.897302)
			(xy 233.845492 -399.937679) (xy 233.868139 -399.982146) (xy 233.883552 -400.029608) (xy 233.89135 -400.078897)
			(xy 233.891836 -400.103848) (xy 233.891836 -403.52091) (xy 233.892247 -403.530981) (xy 233.899977 -403.549579)
			(xy 233.906822 -403.556978) (xy 234.044998 -403.695154) (xy 234.062318 -403.713122) (xy 234.091638 -403.753505)
			(xy 234.114281 -403.797978) (xy 234.129687 -403.845445) (xy 234.13748 -403.894737) (xy 234.137962 -403.91969)
			(xy 234.137962 -404.702518) (xy 234.138361 -404.712591) (xy 234.146098 -404.731189) (xy 234.152948 -404.738586)
			(xy 234.63885 -405.224488) (xy 234.646275 -405.231297) (xy 234.664855 -405.239035) (xy 234.674918 -405.239474)
			(xy 238.514382 -405.239474) (xy 238.524405 -405.239065) (xy 238.542927 -405.231396) (xy 238.557101 -405.21722)
			(xy 238.564767 -405.198697) (xy 238.565182 -405.188674) (xy 238.565182 -394.210794) (xy 238.565684 -394.185845)
			(xy 238.57349 -394.136563) (xy 238.588909 -394.089108) (xy 238.611562 -394.044649) (xy 238.64089 -394.004281)
			(xy 238.676172 -393.968998) (xy 238.716539 -393.939668) (xy 238.760997 -393.917014) (xy 238.808451 -393.901593)
			(xy 238.857733 -393.893785) (xy 238.882682 -393.893294) (xy 238.88319 -393.893294) (xy 238.893211 -393.892872)
			(xy 238.911729 -393.885204) (xy 238.925902 -393.871033) (xy 238.933571 -393.852515) (xy 238.93399 -393.842494)
			(xy 238.93399 -393.82954) (xy 238.921798 -393.807188) (xy 238.91113 -393.800076) (xy 238.882225 -393.780498)
			(xy 238.828145 -393.736342) (xy 238.80318 -393.711938) (xy 238.579914 -393.488672) (xy 238.553014 -393.461125)
			(xy 238.504928 -393.400988) (xy 238.463885 -393.33584) (xy 238.430403 -393.266502) (xy 238.404904 -393.193848)
			(xy 238.387709 -393.118794) (xy 238.379036 -393.042285) (xy 238.378492 -393.003786) (xy 238.378492 -384.337306)
			(xy 238.379215 -384.306679) (xy 238.390978 -384.246564) (xy 238.40186 -384.217926) (xy 238.457994 -384.079496)
			(xy 238.466633 -384.059188) (xy 238.488684 -384.020961) (xy 238.515818 -383.986157) (xy 238.5314 -383.97053)
			(xy 238.583216 -383.920746) (xy 238.583724 -383.920238) (xy 239.05718 -383.446782) (xy 239.084743 -383.419899)
			(xy 239.144878 -383.371812) (xy 239.210023 -383.330768) (xy 239.279359 -383.297284) (xy 239.35201 -383.271782)
			(xy 239.427061 -383.254584) (xy 239.503568 -383.245906) (xy 239.542066 -383.24536) (xy 273.481546 -383.24536)
			(xy 273.512174 -383.24607) (xy 273.572289 -383.257841) (xy 273.600926 -383.268728) (xy 273.739356 -383.324862)
			(xy 273.759667 -383.333494) (xy 273.797892 -383.355549) (xy 273.832695 -383.382685) (xy 273.848322 -383.398268)
			(xy 273.898106 -383.450084) (xy 273.898614 -383.450592) (xy 274.11807 -383.670048) (xy 274.141946 -383.69494)
			(xy 274.148804 -383.70256) (xy 274.167854 -383.71145) (xy 274.251674 -383.713482) (xy 274.262067 -383.713236)
			(xy 274.281342 -383.705512) (xy 274.289012 -383.698496) (xy 274.649184 -383.338324) (xy 274.667186 -383.321041)
			(xy 274.70756 -383.291715) (xy 274.752024 -383.269066) (xy 274.799483 -383.25365) (xy 274.84877 -383.245848)
			(xy 274.87372 -383.24536) (xy 280.202132 -383.24536) (xy 280.227081 -383.245851) (xy 280.276364 -383.253667)
			(xy 280.323821 -383.269085) (xy 280.368287 -383.291728) (xy 280.40867 -383.321039) (xy 280.426668 -383.338324)
			(xy 281.135836 -384.047492) (xy 281.153135 -384.065481) (xy 281.182465 -384.105856) (xy 281.205118 -384.150322)
			(xy 281.220536 -384.197785) (xy 281.228338 -384.247076) (xy 281.2288 -384.272028) (xy 281.2288 -384.878585)
			(xy 286.749043 -384.878585) (xy 286.75295 -384.694958) (xy 286.764661 -384.511664) (xy 286.784157 -384.329034)
			(xy 286.811401 -384.147398) (xy 286.846345 -383.967085) (xy 286.888924 -383.788421) (xy 286.939063 -383.611729)
			(xy 286.99667 -383.437329) (xy 287.061641 -383.265536) (xy 287.133858 -383.096662) (xy 287.213192 -382.931012)
			(xy 287.299498 -382.768885) (xy 287.39262 -382.610574) (xy 287.49239 -382.456367) (xy 287.598627 -382.306542)
			(xy 287.711139 -382.16137) (xy 287.770062 -382.09093) (xy 287.775496 -382.083846) (xy 287.781604 -382.067084)
			(xy 287.782 -382.058164) (xy 287.782 -377.650756) (xy 287.781617 -377.64116) (xy 287.774628 -377.623291)
			(xy 287.761538 -377.609261) (xy 287.753044 -377.604782) (xy 287.718141 -377.587458) (xy 287.651661 -377.546806)
			(xy 287.589675 -377.499584) (xy 287.532829 -377.446285) (xy 287.481716 -377.387466) (xy 287.43687 -377.323741)
			(xy 287.398758 -377.255772) (xy 287.367778 -377.184271) (xy 287.344253 -377.109983) (xy 287.328428 -377.033683)
			(xy 287.320469 -376.956166) (xy 287.319974 -376.917204) (xy 287.320518 -376.877271) (xy 287.328866 -376.797842)
			(xy 287.345471 -376.71972) (xy 287.37015 -376.643762) (xy 287.402634 -376.5708) (xy 287.442567 -376.501633)
			(xy 287.48951 -376.437019) (xy 287.542951 -376.377666) (xy 287.602302 -376.324224) (xy 287.666915 -376.277279)
			(xy 287.736081 -376.237344) (xy 287.809042 -376.204858) (xy 287.884999 -376.180177) (xy 287.96312 -376.16357)
			(xy 288.042549 -376.15522) (xy 288.082482 -376.154696) (xy 288.11708 -376.155097) (xy 288.185987 -376.161407)
			(xy 288.254038 -376.17394) (xy 288.28746 -376.18289) (xy 288.287714 -376.18289) (xy 288.296419 -376.184877)
			(xy 288.314202 -376.183425) (xy 288.330412 -376.175971) (xy 288.33699 -376.169936) (xy 289.570922 -374.93575)
			(xy 289.578326 -374.928915) (xy 289.596922 -374.921191) (xy 289.60699 -374.920764) (xy 392.42111 -374.920764)
			(xy 392.430968 -374.920382) (xy 392.449266 -374.91306) (xy 392.45667 -374.90654) (xy 392.483305 -374.8813)
			(xy 392.540649 -374.835509) (xy 392.602127 -374.795439) (xy 392.66717 -374.761461) (xy 392.735177 -374.733889)
			(xy 392.805518 -374.712978) (xy 392.877542 -374.698922) (xy 392.950584 -374.69185) (xy 392.987276 -374.691402)
			(xy 392.987784 -374.691402) (xy 393.024476 -374.691824) (xy 393.097518 -374.698901) (xy 393.169542 -374.712963)
			(xy 393.239882 -374.733879) (xy 393.307888 -374.761456) (xy 393.372929 -374.795439) (xy 393.434405 -374.835513)
			(xy 393.491747 -374.881308) (xy 393.51839 -374.90654) (xy 393.525791 -374.913059) (xy 393.544094 -374.920362)
			(xy 393.55395 -374.920764) (xy 426.282104 -374.920764) (xy 426.292176 -374.921171) (xy 426.310774 -374.928903)
			(xy 426.318172 -374.93575) (xy 432.13401 -380.751588) (xy 432.140841 -380.757895) (xy 432.157799 -380.76548)
			(xy 432.17635 -380.766489) (xy 432.185318 -380.764034) (xy 432.27603 -380.735716) (xy 432.459492 -380.68609)
			(xy 432.64496 -380.644583) (xy 432.832074 -380.611275) (xy 433.020472 -380.58623) (xy 433.20979 -380.569498)
			(xy 433.39966 -380.56111) (xy 433.494688 -380.56058) (xy 433.49545 -380.56058) (xy 433.594886 -380.561146)
			(xy 433.793547 -380.570306) (xy 433.991576 -380.588604) (xy 434.188552 -380.616001) (xy 434.384058 -380.65244)
			(xy 434.577678 -380.697842) (xy 434.769002 -380.752113) (xy 434.863494 -380.783084) (xy 434.871368 -380.785624)
			(xy 435.902354 -380.785624) (xy 435.902354 -380.785116) (xy 464.46948 -380.785116) (xy 464.479549 -380.785548)
			(xy 464.498147 -380.793263) (xy 464.505548 -380.800102) (xy 465.018374 -381.313182) (xy 465.025195 -381.320597)
			(xy 465.032926 -381.339185) (xy 465.03336 -381.34925) (xy 465.03336 -392.832336) (xy 465.032964 -392.842409)
			(xy 465.025224 -392.861007) (xy 465.018374 -392.868404) (xy 458.197458 -399.689574) (xy 458.191314 -399.696175)
			(xy 458.183797 -399.712559) (xy 458.18242 -399.730532) (xy 458.187352 -399.74787) (xy 458.192378 -399.75536)
			(xy 458.215489 -399.787951) (xy 458.255468 -399.857132) (xy 458.28799 -399.930115) (xy 458.312698 -400.006101)
			(xy 458.329319 -400.084255) (xy 458.337672 -400.163719) (xy 458.338174 -400.20367) (xy 458.337675 -400.243605)
			(xy 458.329329 -400.323039) (xy 458.312725 -400.401165) (xy 458.288045 -400.477127) (xy 458.25556 -400.550094)
			(xy 458.215625 -400.619264) (xy 458.168679 -400.683882) (xy 458.115234 -400.743237) (xy 458.055879 -400.796681)
			(xy 457.991261 -400.843627) (xy 457.92209 -400.883562) (xy 457.849124 -400.916046) (xy 457.773161 -400.940726)
			(xy 457.695035 -400.957329) (xy 457.615601 -400.965675) (xy 457.575666 -400.966178) (xy 457.538489 -400.965719)
			(xy 457.464488 -400.958473) (xy 457.391546 -400.944054) (xy 457.320355 -400.922598) (xy 457.251592 -400.894309)
			(xy 457.218542 -400.877278) (xy 457.207186 -400.871969) (xy 457.182146 -400.871969) (xy 457.17079 -400.877278)
			(xy 457.135292 -400.89555) (xy 457.06124 -400.925405) (xy 456.984472 -400.947352) (xy 456.945238 -400.954748)
			(xy 456.937595 -400.956376) (xy 456.92376 -400.963626) (xy 456.91806 -400.968972) (xy 449.886832 -407.999946)
			(xy 449.878958 -408.020012) (xy 449.879466 -408.03068) (xy 449.880228 -408.063446) (xy 449.879729 -408.10338)
			(xy 449.871376 -408.18281) (xy 449.854767 -408.260933) (xy 449.830083 -408.336891) (xy 449.797595 -408.409853)
			(xy 449.757658 -408.47902) (xy 449.710711 -408.543633) (xy 449.657268 -408.602986) (xy 449.597913 -408.656428)
			(xy 449.533298 -408.703373) (xy 449.46413 -408.743306) (xy 449.391167 -408.775792) (xy 449.315208 -408.800473)
			(xy 449.237085 -408.81708) (xy 449.157654 -408.82543) (xy 449.11772 -408.825954) (xy 449.084954 -408.825192)
			(xy 449.074286 -408.824684) (xy 449.05422 -408.832558) (xy 447.757042 -410.12999) (xy 447.749583 -410.138369)
			(xy 447.742064 -410.159475) (xy 447.744214 -410.181777) (xy 447.749422 -410.191712) (xy 447.769526 -410.226967)
			(xy 447.803042 -410.300884) (xy 447.828518 -410.377943) (xy 447.845666 -410.457272) (xy 447.854291 -410.537974)
			(xy 447.854832 -410.578554) (xy 447.85426 -410.618487) (xy 447.845916 -410.697917) (xy 447.829315 -410.776039)
			(xy 447.804639 -410.851998) (xy 447.772159 -410.924961) (xy 447.732229 -410.994129) (xy 447.685288 -411.058745)
			(xy 447.631849 -411.1181) (xy 447.572499 -411.171544) (xy 447.507888 -411.218491) (xy 447.438723 -411.258427)
			(xy 447.365763 -411.290914) (xy 447.289806 -411.315597) (xy 447.211686 -411.332205) (xy 447.132257 -411.340556)
			(xy 447.092324 -411.341062) (xy 447.051743 -411.340522) (xy 446.971039 -411.331904) (xy 446.891708 -411.314761)
			(xy 446.814646 -411.289289) (xy 446.740726 -411.255776) (xy 446.705482 -411.235652) (xy 446.695533 -411.230464)
			(xy 446.673233 -411.228283) (xy 446.652124 -411.235796) (xy 446.64376 -411.243272) (xy 444.98514 -412.901892)
			(xy 444.978969 -412.908575) (xy 444.971334 -412.925068) (xy 444.969939 -412.943189) (xy 444.974958 -412.960657)
			(xy 444.98006 -412.968186) (xy 444.997584 -412.992916) (xy 445.025382 -413.046774) (xy 445.044313 -413.10435)
			(xy 445.053899 -413.164196) (xy 445.054482 -413.1945) (xy 445.054045 -413.221754) (xy 445.046287 -413.275707)
			(xy 445.03093 -413.328007) (xy 445.008285 -413.377589) (xy 444.978815 -413.423443) (xy 444.943118 -413.464637)
			(xy 444.901923 -413.50033) (xy 444.856066 -413.529798) (xy 444.806483 -413.552439) (xy 444.754182 -413.567792)
			(xy 444.700228 -413.575546) (xy 444.672974 -413.576008) (xy 444.64267 -413.575426) (xy 444.582823 -413.565845)
			(xy 444.525247 -413.546912) (xy 444.471394 -413.519105) (xy 444.44666 -413.501586) (xy 444.439156 -413.49644)
			(xy 444.421672 -413.491431) (xy 444.403539 -413.492833) (xy 444.387033 -413.500471) (xy 444.380366 -413.506666)
			(xy 439.235342 -418.65169) (xy 439.229246 -418.66185) (xy 439.227214 -418.667438) (xy 439.227214 -418.667946)
			(xy 439.214448 -418.706263) (xy 439.181866 -418.780169) (xy 439.141659 -418.85022) (xy 439.094275 -418.91563)
			(xy 439.040246 -418.975668) (xy 438.980175 -419.029661) (xy 438.914737 -419.077006) (xy 438.844663 -419.117172)
			(xy 438.770737 -419.149709) (xy 438.732422 -419.162484) (xy 438.726722 -419.164447) (xy 438.716451 -419.170754)
			(xy 438.712102 -419.17493) (xy 435.525418 -422.361614) (xy 435.518007 -422.36844) (xy 435.499416 -422.376168)
			(xy 435.48935 -422.3766) (xy 420.619174 -422.3766) (xy 420.610325 -422.37689) (xy 420.593673 -422.382876)
			(xy 420.586662 -422.388284) (xy 420.557288 -422.412161) (xy 420.494622 -422.454633) (xy 420.428055 -422.490684)
			(xy 420.358242 -422.519961) (xy 420.285871 -422.542173) (xy 420.211656 -422.557103) (xy 420.136325 -422.564604)
			(xy 420.098474 -422.565068) (xy 420.097966 -422.565068) (xy 420.060115 -422.564597) (xy 419.984786 -422.557093)
			(xy 419.910571 -422.542161) (xy 419.838202 -422.519948) (xy 419.768389 -422.490674) (xy 419.701821 -422.454627)
			(xy 419.639152 -422.41216) (xy 419.609778 -422.388284) (xy 419.602729 -422.382948) (xy 419.5861 -422.376976)
			(xy 419.577266 -422.3766) (xy 370.363496 -422.3766) (xy 370.353488 -422.377085) (xy 370.334996 -422.384746)
			(xy 370.320844 -422.3989) (xy 370.313184 -422.417392) (xy 370.312696 -422.4274) (xy 370.312696 -422.692576)
			(xy 370.312264 -422.702697) (xy 370.304523 -422.721401) (xy 370.290211 -422.735717) (xy 370.271509 -422.743462)
			(xy 370.261388 -422.743884) (xy 365.362744 -422.743884) (xy 365.352622 -422.743447) (xy 365.333917 -422.735711)
			(xy 365.3196 -422.7214) (xy 365.311856 -422.702697) (xy 365.311436 -422.692576) (xy 365.311436 -422.4274)
			(xy 365.310913 -422.417397) (xy 365.30326 -422.398912) (xy 365.289118 -422.38476) (xy 365.270639 -422.377094)
			(xy 365.260636 -422.3766) (xy 303.062386 -422.3766) (xy 303.053086 -422.377017) (xy 303.035689 -422.383588)
			(xy 303.021806 -422.395959) (xy 303.017174 -422.404032) (xy 302.998483 -422.439092) (xy 302.954867 -422.505506)
			(xy 302.904581 -422.567025) (xy 302.848171 -422.62298) (xy 302.786247 -422.672766) (xy 302.719482 -422.715843)
			(xy 302.648599 -422.751743) (xy 302.574367 -422.780077) (xy 302.497591 -422.800538) (xy 302.419104 -422.812904)
			(xy 302.339756 -422.817041) (xy 302.260408 -422.812904) (xy 302.181921 -422.800538) (xy 302.105145 -422.780077)
			(xy 302.030913 -422.751743) (xy 301.96003 -422.715843) (xy 301.893265 -422.672766) (xy 301.831341 -422.62298)
			(xy 301.774931 -422.567025) (xy 301.724645 -422.505506) (xy 301.681029 -422.439092) (xy 301.662338 -422.404032)
			(xy 301.657645 -422.396004) (xy 301.643768 -422.383653) (xy 301.626414 -422.377024) (xy 301.617126 -422.3766)
			(xy 299.341794 -422.3766) (xy 299.331721 -422.376204) (xy 299.313122 -422.368466) (xy 299.305726 -422.361614)
			(xy 295.79443 -418.850064) (xy 295.787586 -418.842667) (xy 295.779868 -418.824066) (xy 295.779444 -418.813996)
			(xy 295.779444 -417.137342) (xy 295.778962 -417.127707) (xy 295.771787 -417.109817) (xy 295.75854 -417.095815)
			(xy 295.74998 -417.091368) (xy 295.666202 -417.05197) (xy 295.501746 -416.966901) (xy 295.341088 -416.87486)
			(xy 295.184523 -416.776016) (xy 295.032339 -416.670553) (xy 294.884815 -416.558662) (xy 294.742223 -416.440551)
			(xy 294.604826 -416.316436) (xy 294.472875 -416.186545) (xy 294.346613 -416.051118) (xy 294.226273 -415.910403)
			(xy 294.112075 -415.764658) (xy 294.004229 -415.614152) (xy 293.902935 -415.459162) (xy 293.808377 -415.299972)
			(xy 293.72073 -415.136875) (xy 293.640155 -414.97017) (xy 293.5668 -414.800165) (xy 293.5008 -414.627172)
			(xy 293.442276 -414.451509) (xy 293.391336 -414.273498) (xy 293.348074 -414.093468) (xy 293.312568 -413.911748)
			(xy 293.284885 -413.728674) (xy 293.265075 -413.544581) (xy 293.253174 -413.359808) (xy 293.249205 -413.174695)
			(xy 293.253174 -412.989582) (xy 293.265075 -412.804809) (xy 293.284886 -412.620716) (xy 293.31257 -412.437642)
			(xy 293.348076 -412.255922) (xy 293.391339 -412.075892) (xy 293.442279 -411.897881) (xy 293.500804 -411.722218)
			(xy 293.566804 -411.549225) (xy 293.640159 -411.37922) (xy 293.720735 -411.212516) (xy 293.808382 -411.04942)
			(xy 293.90294 -410.89023) (xy 294.004235 -410.73524) (xy 294.112081 -410.584734) (xy 294.226279 -410.43899)
			(xy 294.34662 -410.298275) (xy 294.472882 -410.162847) (xy 294.604833 -410.032957) (xy 294.742231 -409.908842)
			(xy 294.884823 -409.790731) (xy 295.032347 -409.678841) (xy 295.184531 -409.573378) (xy 295.341097 -409.474535)
			(xy 295.501755 -409.382495) (xy 295.666211 -409.297425) (xy 295.74998 -409.258008) (xy 295.758565 -409.25358)
			(xy 295.771873 -409.239606) (xy 295.779028 -409.221683) (xy 295.779444 -409.212034) (xy 295.779444 -400.138392)
			(xy 295.778919 -400.128389) (xy 295.771265 -400.109906) (xy 295.757124 -400.095755) (xy 295.738646 -400.088088)
			(xy 295.728644 -400.087592) (xy 289.122866 -400.087592) (xy 289.112795 -400.087186) (xy 289.094197 -400.079452)
			(xy 289.086798 -400.072606) (xy 288.254948 -399.240756) (xy 288.227008 -399.234152) (xy 288.213546 -399.23847)
			(xy 288.175164 -399.250488) (xy 288.096513 -399.267328) (xy 288.016527 -399.275796) (xy 287.97631 -399.276316)
			(xy 287.936376 -399.275794) (xy 287.856944 -399.267446) (xy 287.77882 -399.250842) (xy 287.70286 -399.226162)
			(xy 287.629896 -399.193677) (xy 287.560727 -399.153743) (xy 287.496111 -399.106798) (xy 287.436756 -399.053356)
			(xy 287.383313 -398.994003) (xy 287.336366 -398.929388) (xy 287.296431 -398.86022) (xy 287.263945 -398.787257)
			(xy 287.239263 -398.711297) (xy 287.222657 -398.633174) (xy 287.214307 -398.553742) (xy 287.213802 -398.513808)
			(xy 287.214348 -398.473606) (xy 287.222788 -398.393648) (xy 287.239596 -398.315021) (xy 287.264587 -398.2386)
			(xy 287.297481 -398.165234) (xy 287.337914 -398.095737) (xy 287.385437 -398.030882) (xy 287.439521 -397.971388)
			(xy 287.499566 -397.917916) (xy 287.564906 -397.871062) (xy 287.634814 -397.831343) (xy 287.708514 -397.799203)
			(xy 287.746694 -397.786606) (xy 287.762442 -397.781526) (xy 287.782 -397.754856) (xy 287.782 -395.835378)
			(xy 287.781518 -395.825193) (xy 287.773524 -395.806454) (xy 287.766506 -395.799056) (xy 287.739572 -395.77211)
			(xy 287.690535 -395.713796) (xy 287.647557 -395.650884) (xy 287.611066 -395.584) (xy 287.581426 -395.51381)
			(xy 287.558933 -395.441015) (xy 287.543811 -395.36634) (xy 287.53621 -395.290529) (xy 287.536207 -395.214338)
			(xy 287.543801 -395.138526) (xy 287.558917 -395.06385) (xy 287.581403 -394.991053) (xy 287.611037 -394.92086)
			(xy 287.647522 -394.853973) (xy 287.690494 -394.791057) (xy 287.739526 -394.73274) (xy 287.766506 -394.70584)
			(xy 287.773493 -394.698421) (xy 287.781491 -394.679696) (xy 287.782 -394.669518) (xy 287.782 -387.698996)
			(xy 287.781685 -387.690062) (xy 287.775561 -387.673278) (xy 287.770062 -387.66623) (xy 287.71112 -387.595806)
			(xy 287.598609 -387.450633) (xy 287.492373 -387.300808) (xy 287.392604 -387.1466) (xy 287.299483 -386.988289)
			(xy 287.213178 -386.826161) (xy 287.133846 -386.66051) (xy 287.061629 -386.491635) (xy 286.996659 -386.319842)
			(xy 286.939054 -386.145442) (xy 286.888916 -385.96875) (xy 286.846338 -385.790085) (xy 286.811396 -385.609772)
			(xy 286.784153 -385.428136) (xy 286.764659 -385.245505) (xy 286.752948 -385.062211) (xy 286.749043 -384.878585)
			(xy 281.2288 -384.878585) (xy 281.2288 -386.978652) (xy 281.250898 -387.006084) (xy 281.268424 -387.010148)
			(xy 281.306983 -387.019259) (xy 281.382098 -387.044474) (xy 281.454194 -387.077345) (xy 281.522491 -387.117516)
			(xy 281.586253 -387.164555) (xy 281.644791 -387.217953) (xy 281.697476 -387.277135) (xy 281.743737 -387.341463)
			(xy 281.783077 -387.410243) (xy 281.81507 -387.482731) (xy 281.839372 -387.558148) (xy 281.85572 -387.635678)
			(xy 281.863939 -387.714486) (xy 281.863938 -387.793721) (xy 281.855719 -387.872528) (xy 281.839371 -387.950058)
			(xy 281.815068 -388.025474) (xy 281.783074 -388.097963) (xy 281.743734 -388.166742) (xy 281.697472 -388.231069)
			(xy 281.644787 -388.290251) (xy 281.586248 -388.343649) (xy 281.522486 -388.390687) (xy 281.454188 -388.430858)
			(xy 281.382093 -388.463728) (xy 281.306977 -388.488942) (xy 281.268424 -388.49808) (xy 281.250898 -388.502144)
			(xy 281.2288 -388.529576) (xy 281.2288 -393.283694) (xy 281.228296 -393.308643) (xy 281.220486 -393.357926)
			(xy 281.205071 -393.405383) (xy 281.18243 -393.449849) (xy 281.153121 -393.490232) (xy 281.135836 -393.50823)
			(xy 280.360882 -394.283184) (xy 280.354195 -394.290595) (xy 280.34659 -394.309028) (xy 280.346589 -394.328969)
			(xy 280.354193 -394.347403) (xy 280.360882 -394.354812) (xy 280.483818 -394.478002) (xy 280.510712 -394.505555)
			(xy 280.558798 -394.565692) (xy 280.599841 -394.630839) (xy 280.633323 -394.700176) (xy 280.658823 -394.772829)
			(xy 280.67602 -394.847882) (xy 280.684696 -394.924389) (xy 280.68524 -394.962888) (xy 280.68524 -402.161756)
			(xy 289.53714 -402.161756) (xy 289.537635 -402.121005) (xy 289.546327 -402.039968) (xy 289.563597 -401.960317)
			(xy 289.589248 -401.882958) (xy 289.62299 -401.808769) (xy 289.664438 -401.738593) (xy 289.713122 -401.67323)
			(xy 289.768488 -401.61342) (xy 289.829906 -401.559845) (xy 289.89668 -401.513113) (xy 289.93211 -401.492974)
			(xy 289.94059 -401.487733) (xy 289.953086 -401.472227) (xy 289.958781 -401.453145) (xy 289.958272 -401.44319)
			(xy 289.95624 -401.405344) (xy 289.95624 -401.404836) (xy 289.956726 -401.377567) (xy 289.964488 -401.323583)
			(xy 289.979853 -401.271253) (xy 290.00251 -401.221643) (xy 290.031996 -401.175762) (xy 290.067711 -401.134545)
			(xy 290.108928 -401.09883) (xy 290.154809 -401.069344) (xy 290.204419 -401.046687) (xy 290.256749 -401.031322)
			(xy 290.310733 -401.02356) (xy 290.365271 -401.02356) (xy 290.419255 -401.031322) (xy 290.471585 -401.046687)
			(xy 290.521195 -401.069344) (xy 290.567076 -401.09883) (xy 290.608293 -401.134545) (xy 290.644008 -401.175762)
			(xy 290.673494 -401.221643) (xy 290.696151 -401.271253) (xy 290.711516 -401.323583) (xy 290.719278 -401.377567)
			(xy 290.719764 -401.404836) (xy 290.719505 -401.423826) (xy 290.715691 -401.461616) (xy 290.712144 -401.480274)
			(xy 290.71068 -401.490086) (xy 290.714439 -401.509542) (xy 290.725314 -401.526107) (xy 290.733226 -401.53209)
			(xy 290.766806 -401.555851) (xy 290.829228 -401.609432) (xy 290.885531 -401.66941) (xy 290.935062 -401.735092)
			(xy 290.977248 -401.805716) (xy 291.011599 -401.880465) (xy 291.037717 -401.958473) (xy 291.055301 -402.038836)
			(xy 291.064147 -402.120624) (xy 291.064696 -402.161756) (xy 291.064111 -402.204622) (xy 291.054515 -402.289814)
			(xy 291.035439 -402.373396) (xy 291.007122 -402.454315) (xy 290.96992 -402.531554) (xy 290.947602 -402.568156)
			(xy 290.941871 -402.578455) (xy 290.939482 -402.601875) (xy 290.94303 -402.613114) (xy 290.962251 -402.643907)
			(xy 290.995486 -402.708447) (xy 291.022442 -402.775851) (xy 291.042876 -402.845509) (xy 291.056604 -402.916793)
			(xy 291.063501 -402.989059) (xy 291.063934 -403.025356) (xy 291.063445 -403.064027) (xy 291.05562 -403.140972)
			(xy 291.040051 -403.216731) (xy 291.016898 -403.290526) (xy 290.986398 -403.3616) (xy 290.948863 -403.429223)
			(xy 290.90468 -403.492703) (xy 290.854302 -403.551387) (xy 290.798245 -403.604673) (xy 290.737085 -403.652014)
			(xy 290.671449 -403.692925) (xy 290.602011 -403.726986) (xy 290.529484 -403.753848) (xy 290.454611 -403.773233)
			(xy 290.378161 -403.784945) (xy 290.300918 -403.788863) (xy 290.223675 -403.784945) (xy 290.147225 -403.773233)
			(xy 290.072352 -403.753848) (xy 289.999825 -403.726986) (xy 289.930387 -403.692925) (xy 289.864751 -403.652014)
			(xy 289.803591 -403.604673) (xy 289.747534 -403.551387) (xy 289.697156 -403.492703) (xy 289.652973 -403.429223)
			(xy 289.615438 -403.3616) (xy 289.584938 -403.290526) (xy 289.561785 -403.216731) (xy 289.546216 -403.140972)
			(xy 289.538391 -403.064027) (xy 289.537902 -403.025356) (xy 289.538317 -402.989058) (xy 289.545214 -402.91679)
			(xy 289.558941 -402.845504) (xy 289.579374 -402.775843) (xy 289.606329 -402.708437) (xy 289.639562 -402.643894)
			(xy 289.658806 -402.613114) (xy 289.662419 -402.601881) (xy 289.660032 -402.578434) (xy 289.654234 -402.568156)
			(xy 289.631952 -402.531534) (xy 289.594751 -402.454299) (xy 289.566431 -402.373384) (xy 289.547348 -402.289807)
			(xy 289.537744 -402.20462) (xy 289.53714 -402.161756) (xy 280.68524 -402.161756) (xy 280.68524 -404.215092)
			(xy 283.243782 -404.215092) (xy 283.244369 -404.1724) (xy 283.253913 -404.087552) (xy 283.27287 -404.0043)
			(xy 283.301002 -403.923684) (xy 283.337958 -403.846713) (xy 283.360114 -403.810216) (xy 283.364836 -403.801963)
			(xy 283.368362 -403.783293) (xy 283.364831 -403.764624) (xy 283.360114 -403.756368) (xy 283.337925 -403.719888)
			(xy 283.300944 -403.642924) (xy 283.272806 -403.562305) (xy 283.253864 -403.479044) (xy 283.244356 -403.394186)
			(xy 283.243782 -403.351492) (xy 283.244271 -403.312873) (xy 283.252085 -403.23603) (xy 283.267633 -403.160372)
			(xy 283.290756 -403.086675) (xy 283.321215 -403.015696) (xy 283.3587 -402.948162) (xy 283.402824 -402.884768)
			(xy 283.453135 -402.826162) (xy 283.509117 -402.772947) (xy 283.570196 -402.725668) (xy 283.635744 -402.684812)
			(xy 283.70509 -402.650796) (xy 283.777521 -402.623971) (xy 283.852294 -402.604611) (xy 283.928642 -402.592915)
			(xy 284.005782 -402.589003) (xy 284.082922 -402.592915) (xy 284.15927 -402.604611) (xy 284.234043 -402.623971)
			(xy 284.306474 -402.650796) (xy 284.37582 -402.684812) (xy 284.441368 -402.725668) (xy 284.502447 -402.772947)
			(xy 284.558429 -402.826162) (xy 284.60874 -402.884768) (xy 284.652864 -402.948162) (xy 284.690349 -403.015696)
			(xy 284.720808 -403.086675) (xy 284.743931 -403.160372) (xy 284.759479 -403.23603) (xy 284.767293 -403.312873)
			(xy 284.767782 -403.351492) (xy 284.767193 -403.394184) (xy 284.75765 -403.479032) (xy 284.738694 -403.562284)
			(xy 284.710562 -403.6429) (xy 284.673606 -403.719871) (xy 284.65145 -403.756368) (xy 284.646744 -403.764628)
			(xy 284.643216 -403.783293) (xy 284.646739 -403.801959) (xy 284.65145 -403.810216) (xy 284.673639 -403.846695)
			(xy 284.710619 -403.923661) (xy 284.738756 -404.00428) (xy 284.757698 -404.08754) (xy 284.767207 -404.172398)
			(xy 284.767782 -404.215092) (xy 284.767251 -404.254852) (xy 284.758988 -404.333943) (xy 284.742531 -404.411742)
			(xy 284.718059 -404.487403) (xy 284.685837 -404.560103) (xy 284.646217 -404.629051) (xy 284.59963 -404.693496)
			(xy 284.546582 -404.752737) (xy 284.487652 -404.806129) (xy 284.45587 -404.830026) (xy 284.449103 -404.835398)
			(xy 284.439368 -404.84966) (xy 284.434943 -404.866351) (xy 284.435296 -404.874984) (xy 284.436566 -404.905464)
			(xy 284.436566 -404.905972) (xy 284.43608 -404.933241) (xy 284.428318 -404.987225) (xy 284.412953 -405.039555)
			(xy 284.390296 -405.089165) (xy 284.36081 -405.135046) (xy 284.325095 -405.176263) (xy 284.283878 -405.211978)
			(xy 284.237997 -405.241464) (xy 284.188387 -405.264121) (xy 284.136057 -405.279486) (xy 284.082073 -405.287248)
			(xy 284.027535 -405.287248) (xy 283.973551 -405.279486) (xy 283.921221 -405.264121) (xy 283.871611 -405.241464)
			(xy 283.82573 -405.211978) (xy 283.784513 -405.176263) (xy 283.748798 -405.135046) (xy 283.719312 -405.089165)
			(xy 283.696655 -405.039555) (xy 283.68129 -404.987225) (xy 283.673528 -404.933241) (xy 283.673042 -404.905972)
			(xy 283.673042 -404.900638) (xy 283.63836 -404.883314) (xy 283.572413 -404.842543) (xy 283.510947 -404.795287)
			(xy 283.454597 -404.742035) (xy 283.403945 -404.683336) (xy 283.359514 -404.619798) (xy 283.321764 -404.552077)
			(xy 283.291085 -404.480873) (xy 283.267795 -404.406923) (xy 283.252133 -404.330989) (xy 283.244262 -404.253858)
			(xy 283.243782 -404.215092) (xy 280.68524 -404.215092) (xy 280.68524 -406.550622) (xy 286.72028 -406.550622)
			(xy 286.720799 -406.511177) (xy 286.728937 -406.432708) (xy 286.745129 -406.355498) (xy 286.769201 -406.280371)
			(xy 286.800897 -406.208128) (xy 286.839877 -406.139542) (xy 286.885727 -406.075344) (xy 286.937957 -406.01622)
			(xy 286.996008 -405.962801) (xy 287.059262 -405.915657) (xy 287.092898 -405.895048) (xy 287.092898 -405.887936)
			(xy 287.093458 -405.860669) (xy 287.101213 -405.80669) (xy 287.116572 -405.754365) (xy 287.139221 -405.704757)
			(xy 287.1687 -405.658878) (xy 287.204407 -405.617661) (xy 287.245617 -405.581945) (xy 287.291491 -405.552458)
			(xy 287.341093 -405.529799) (xy 287.393416 -405.51443) (xy 287.447393 -405.506663) (xy 287.47466 -405.506174)
			(xy 287.503262 -405.50668) (xy 287.559825 -405.515209) (xy 287.614483 -405.532084) (xy 287.666011 -405.556925)
			(xy 287.713256 -405.589176) (xy 287.755159 -405.628117) (xy 287.790783 -405.672873) (xy 287.819329 -405.722445)
			(xy 287.840159 -405.775721) (xy 287.852807 -405.831508) (xy 287.855406 -405.859996) (xy 287.856475 -405.869547)
			(xy 287.864689 -405.886907) (xy 287.871408 -405.893778) (xy 287.905205 -405.914371) (xy 287.968819 -405.961461)
			(xy 288.027216 -406.014884) (xy 288.079767 -406.074066) (xy 288.12591 -406.138371) (xy 288.165146 -406.207107)
			(xy 288.197055 -406.279536) (xy 288.221295 -406.35488) (xy 288.237603 -406.432328) (xy 288.245805 -406.511049)
			(xy 288.246312 -406.550622) (xy 288.245911 -406.587018) (xy 288.239012 -406.659483) (xy 288.22524 -406.730961)
			(xy 288.204721 -406.800801) (xy 288.177641 -406.868369) (xy 288.144247 -406.933049) (xy 288.1249 -406.96388)
			(xy 288.121134 -406.975188) (xy 288.123239 -406.998894) (xy 288.128964 -407.009346) (xy 288.151103 -407.045826)
			(xy 288.188074 -407.122736) (xy 288.216214 -407.203297) (xy 288.23517 -407.2865) (xy 288.244704 -407.371301)
			(xy 288.245296 -407.413968) (xy 288.245296 -407.414222) (xy 288.244807 -407.452841) (xy 288.236993 -407.529684)
			(xy 288.221445 -407.605342) (xy 288.198322 -407.679039) (xy 288.167863 -407.750018) (xy 288.130378 -407.817552)
			(xy 288.086254 -407.880946) (xy 288.035943 -407.939552) (xy 287.979961 -407.992767) (xy 287.918882 -408.040046)
			(xy 287.853334 -408.080902) (xy 287.783988 -408.114918) (xy 287.711557 -408.141743) (xy 287.636784 -408.161103)
			(xy 287.560436 -408.172799) (xy 287.483296 -408.176712) (xy 287.406156 -408.172799) (xy 287.329808 -408.161103)
			(xy 287.255035 -408.141743) (xy 287.182604 -408.114918) (xy 287.113258 -408.080902) (xy 287.04771 -408.040046)
			(xy 286.986631 -407.992767) (xy 286.930649 -407.939552) (xy 286.880338 -407.880946) (xy 286.836214 -407.817552)
			(xy 286.798729 -407.750018) (xy 286.76827 -407.679039) (xy 286.745147 -407.605342) (xy 286.729599 -407.529684)
			(xy 286.721785 -407.452841) (xy 286.721296 -407.414222) (xy 286.721296 -407.413968) (xy 286.721908 -407.371302)
			(xy 286.731466 -407.286508) (xy 286.750425 -407.203309) (xy 286.778548 -407.122744) (xy 286.815485 -407.045821)
			(xy 286.837628 -407.009346) (xy 286.843386 -406.9989) (xy 286.845515 -406.975178) (xy 286.841692 -406.96388)
			(xy 286.822364 -406.933038) (xy 286.78898 -406.868356) (xy 286.761905 -406.800789) (xy 286.741384 -406.730951)
			(xy 286.727606 -406.659478) (xy 286.720693 -406.587017) (xy 286.72028 -406.550622) (xy 280.68524 -406.550622)
			(xy 280.68524 -407.5567) (xy 282.15461 -407.5567) (xy 282.158522 -407.479558) (xy 282.170219 -407.403207)
			(xy 282.189581 -407.328432) (xy 282.216408 -407.255999) (xy 282.250425 -407.186651) (xy 282.291284 -407.121102)
			(xy 282.338566 -407.060022) (xy 282.391784 -407.004039) (xy 282.450393 -406.953728) (xy 282.513791 -406.909604)
			(xy 282.581328 -406.872121) (xy 282.652311 -406.841663) (xy 282.726011 -406.818543) (xy 282.801672 -406.802998)
			(xy 282.878517 -406.795187) (xy 282.917138 -406.794716) (xy 282.959829 -406.795331) (xy 283.044676 -406.804868)
			(xy 283.127928 -406.823818) (xy 283.208544 -406.851944) (xy 283.285516 -406.888894) (xy 283.322014 -406.911048)
			(xy 283.33027 -406.915762) (xy 283.348938 -406.919289) (xy 283.367606 -406.915762) (xy 283.375862 -406.911048)
			(xy 283.412355 -406.888881) (xy 283.489316 -406.851897) (xy 283.569932 -406.823755) (xy 283.65319 -406.804808)
			(xy 283.738044 -406.795294) (xy 283.780738 -406.794716) (xy 283.819357 -406.795175) (xy 283.896198 -406.802993)
			(xy 283.971855 -406.818544) (xy 284.04555 -406.841669) (xy 284.116527 -406.872131) (xy 284.184059 -406.909617)
			(xy 284.247452 -406.953743) (xy 284.306055 -407.004055) (xy 284.359268 -407.060038) (xy 284.406545 -407.121117)
			(xy 284.4474 -407.186665) (xy 284.481414 -407.256011) (xy 284.508239 -407.328441) (xy 284.527598 -407.403214)
			(xy 284.539294 -407.479561) (xy 284.543206 -407.5567) (xy 284.539294 -407.633839) (xy 284.527598 -407.710186)
			(xy 284.508239 -407.784959) (xy 284.481414 -407.857389) (xy 284.4474 -407.926735) (xy 284.406545 -407.992283)
			(xy 284.359268 -408.053362) (xy 284.306055 -408.109345) (xy 284.247452 -408.159657) (xy 284.184059 -408.203783)
			(xy 284.116527 -408.241269) (xy 284.04555 -408.271731) (xy 283.971855 -408.294856) (xy 283.896198 -408.310407)
			(xy 283.819357 -408.318225) (xy 283.780738 -408.318716) (xy 283.738047 -408.318107) (xy 283.6532 -408.308568)
			(xy 283.569947 -408.289617) (xy 283.489332 -408.261489) (xy 283.41236 -408.224538) (xy 283.375862 -408.202384)
			(xy 283.367606 -408.19767) (xy 283.348938 -408.194143) (xy 283.33027 -408.19767) (xy 283.322014 -408.202384)
			(xy 283.285523 -408.224554) (xy 283.208562 -408.261538) (xy 283.127945 -408.289681) (xy 283.044687 -408.308627)
			(xy 282.959832 -408.318139) (xy 282.917138 -408.318716) (xy 282.878517 -408.318213) (xy 282.801672 -408.310402)
			(xy 282.726011 -408.294857) (xy 282.652311 -408.271737) (xy 282.581328 -408.241279) (xy 282.513791 -408.203796)
			(xy 282.450393 -408.159672) (xy 282.391784 -408.109361) (xy 282.338566 -408.053378) (xy 282.291284 -407.992298)
			(xy 282.250425 -407.926749) (xy 282.216408 -407.857401) (xy 282.189581 -407.784968) (xy 282.170219 -407.710193)
			(xy 282.158522 -407.633842) (xy 282.15461 -407.5567) (xy 280.68524 -407.5567) (xy 280.68524 -409.10256)
			(xy 280.684766 -409.12751) (xy 280.676946 -409.176794) (xy 280.661524 -409.224251) (xy 280.638877 -409.268716)
			(xy 280.609563 -409.309098) (xy 280.592276 -409.327096) (xy 272.414746 -417.504626) (xy 272.396783 -417.521953)
			(xy 272.356401 -417.55128) (xy 272.311928 -417.573928) (xy 272.264459 -417.589339) (xy 272.215164 -417.597133)
			(xy 272.19021 -417.59759) (xy 235.05033 -417.59759) (xy 235.040259 -417.598007) (xy 235.02166 -417.605731)
			(xy 235.014262 -417.612576) (xy 233.545126 -419.081712) (xy 276.341332 -419.081712) (xy 276.341921 -419.03902)
			(xy 276.351464 -418.954172) (xy 276.370419 -418.87092) (xy 276.398551 -418.790304) (xy 276.435508 -418.713333)
			(xy 276.457664 -418.676836) (xy 276.462366 -418.668574) (xy 276.465893 -418.64991) (xy 276.462373 -418.631245)
			(xy 276.457664 -418.622988) (xy 276.435478 -418.586507) (xy 276.398497 -418.509542) (xy 276.370359 -418.428923)
			(xy 276.351416 -418.345663) (xy 276.341907 -418.260806) (xy 276.341332 -418.218112) (xy 276.341821 -418.179493)
			(xy 276.349635 -418.10265) (xy 276.365183 -418.026992) (xy 276.388306 -417.953295) (xy 276.418765 -417.882316)
			(xy 276.45625 -417.814782) (xy 276.500374 -417.751388) (xy 276.550685 -417.692782) (xy 276.606667 -417.639567)
			(xy 276.667746 -417.592288) (xy 276.733294 -417.551432) (xy 276.80264 -417.517416) (xy 276.875071 -417.490591)
			(xy 276.949844 -417.471231) (xy 277.026192 -417.459535) (xy 277.103332 -417.455623) (xy 277.180472 -417.459535)
			(xy 277.25682 -417.471231) (xy 277.331593 -417.490591) (xy 277.404024 -417.517416) (xy 277.47337 -417.551432)
			(xy 277.538918 -417.592288) (xy 277.599997 -417.639567) (xy 277.655979 -417.692782) (xy 277.70629 -417.751388)
			(xy 277.750414 -417.814782) (xy 277.787899 -417.882316) (xy 277.818358 -417.953295) (xy 277.841481 -418.026992)
			(xy 277.857029 -418.10265) (xy 277.864843 -418.179493) (xy 277.865332 -418.218112) (xy 277.864828 -418.254688)
			(xy 289.073336 -418.254688) (xy 289.073913 -418.211996) (xy 289.083458 -418.127147) (xy 289.102417 -418.043895)
			(xy 289.130551 -417.963279) (xy 289.16751 -417.886308) (xy 289.189668 -417.849812) (xy 289.194389 -417.84156)
			(xy 289.19791 -417.82289) (xy 289.194382 -417.804221) (xy 289.189668 -417.795964) (xy 289.167472 -417.759488)
			(xy 289.130493 -417.682522) (xy 289.102357 -417.601902) (xy 289.083417 -417.518641) (xy 289.07391 -417.433783)
			(xy 289.073336 -417.391088) (xy 289.073825 -417.352469) (xy 289.081639 -417.275626) (xy 289.097187 -417.199968)
			(xy 289.12031 -417.126271) (xy 289.150769 -417.055292) (xy 289.188254 -416.987758) (xy 289.232378 -416.924364)
			(xy 289.282689 -416.865758) (xy 289.338671 -416.812543) (xy 289.39975 -416.765264) (xy 289.465298 -416.724408)
			(xy 289.534644 -416.690392) (xy 289.607075 -416.663567) (xy 289.681848 -416.644207) (xy 289.758196 -416.632511)
			(xy 289.835336 -416.628599) (xy 289.912476 -416.632511) (xy 289.988824 -416.644207) (xy 290.063597 -416.663567)
			(xy 290.136028 -416.690392) (xy 290.205374 -416.724408) (xy 290.270922 -416.765264) (xy 290.332001 -416.812543)
			(xy 290.387983 -416.865758) (xy 290.438294 -416.924364) (xy 290.482418 -416.987758) (xy 290.519903 -417.055292)
			(xy 290.550362 -417.126271) (xy 290.573485 -417.199968) (xy 290.589033 -417.275626) (xy 290.596847 -417.352469)
			(xy 290.597336 -417.391088) (xy 290.596736 -417.433779) (xy 290.587195 -417.518627) (xy 290.568241 -417.601879)
			(xy 290.540112 -417.682495) (xy 290.503159 -417.759467) (xy 290.481004 -417.795964) (xy 290.476297 -417.804224)
			(xy 290.472765 -417.82289) (xy 290.47629 -417.841557) (xy 290.481004 -417.849812) (xy 290.503187 -417.886295)
			(xy 290.540169 -417.963259) (xy 290.568308 -418.043877) (xy 290.587251 -418.127137) (xy 290.596761 -418.211994)
			(xy 290.597336 -418.254688) (xy 290.596847 -418.293307) (xy 290.589033 -418.37015) (xy 290.573485 -418.445808)
			(xy 290.550362 -418.519505) (xy 290.519903 -418.590484) (xy 290.482418 -418.658018) (xy 290.438294 -418.721412)
			(xy 290.387983 -418.780018) (xy 290.332001 -418.833233) (xy 290.270922 -418.880512) (xy 290.205374 -418.921368)
			(xy 290.136028 -418.955384) (xy 290.063597 -418.982209) (xy 289.988824 -419.001569) (xy 289.912476 -419.013265)
			(xy 289.835336 -419.017178) (xy 289.758196 -419.013265) (xy 289.681848 -419.001569) (xy 289.607075 -418.982209)
			(xy 289.534644 -418.955384) (xy 289.465298 -418.921368) (xy 289.39975 -418.880512) (xy 289.338671 -418.833233)
			(xy 289.282689 -418.780018) (xy 289.232378 -418.721412) (xy 289.188254 -418.658018) (xy 289.150769 -418.590484)
			(xy 289.12031 -418.519505) (xy 289.097187 -418.445808) (xy 289.081639 -418.37015) (xy 289.073825 -418.293307)
			(xy 289.073336 -418.254688) (xy 277.864828 -418.254688) (xy 277.864744 -418.260804) (xy 277.8552 -418.345652)
			(xy 277.836244 -418.428904) (xy 277.808112 -418.50952) (xy 277.771156 -418.586491) (xy 277.749 -418.622988)
			(xy 277.744274 -418.631239) (xy 277.740749 -418.64991) (xy 277.744282 -418.66858) (xy 277.749 -418.676836)
			(xy 277.771192 -418.713314) (xy 277.808173 -418.790279) (xy 277.83631 -418.870899) (xy 277.855251 -418.95416)
			(xy 277.864758 -419.039017) (xy 277.865332 -419.081712) (xy 277.864843 -419.120331) (xy 277.857029 -419.197174)
			(xy 277.841481 -419.272832) (xy 277.818358 -419.346529) (xy 277.787899 -419.417508) (xy 277.750414 -419.485042)
			(xy 277.70629 -419.548436) (xy 277.655979 -419.607042) (xy 277.599997 -419.660257) (xy 277.599254 -419.660832)
			(xy 290.447476 -419.660832) (xy 290.44798 -419.620714) (xy 290.456404 -419.540922) (xy 290.47315 -419.462453)
			(xy 290.498035 -419.386174) (xy 290.530783 -419.312926) (xy 290.571034 -419.243517) (xy 290.618344 -419.178713)
			(xy 290.67219 -419.119229) (xy 290.731978 -419.065721) (xy 290.764214 -419.041834) (xy 290.771273 -419.036255)
			(xy 290.781256 -419.021298) (xy 290.785472 -419.003816) (xy 290.784788 -418.994844) (xy 290.783712 -418.984464)
			(xy 290.78257 -418.963624) (xy 290.782502 -418.953188) (xy 290.782988 -418.925919) (xy 290.79075 -418.871935)
			(xy 290.806115 -418.819605) (xy 290.828772 -418.769995) (xy 290.858258 -418.724114) (xy 290.893973 -418.682897)
			(xy 290.93519 -418.647182) (xy 290.981071 -418.617696) (xy 291.030681 -418.595039) (xy 291.083011 -418.579674)
			(xy 291.136995 -418.571912) (xy 291.191533 -418.571912) (xy 291.245517 -418.579674) (xy 291.297847 -418.595039)
			(xy 291.347457 -418.617696) (xy 291.393338 -418.647182) (xy 291.434555 -418.682897) (xy 291.47027 -418.724114)
			(xy 291.499756 -418.769995) (xy 291.522413 -418.819605) (xy 291.537778 -418.871935) (xy 291.54554 -418.925919)
			(xy 291.546026 -418.953188) (xy 291.545518 -418.974016) (xy 291.580194 -418.99147) (xy 291.646189 -419.032359)
			(xy 291.707697 -419.07973) (xy 291.764083 -419.133096) (xy 291.814765 -419.191905) (xy 291.859221 -419.255552)
			(xy 291.896992 -419.32338) (xy 291.927688 -419.394689) (xy 291.950994 -419.468744) (xy 291.966668 -419.54478)
			(xy 291.974549 -419.622014) (xy 291.975032 -419.660832) (xy 291.974478 -419.703698) (xy 291.964874 -419.788892)
			(xy 291.94579 -419.872474) (xy 291.917466 -419.953393) (xy 291.880259 -420.030631) (xy 291.857938 -420.067232)
			(xy 291.852222 -420.077538) (xy 291.849822 -420.100953) (xy 291.853366 -420.11219) (xy 291.872624 -420.142961)
			(xy 291.905853 -420.207506) (xy 291.932803 -420.274915) (xy 291.953231 -420.344577) (xy 291.966951 -420.415865)
			(xy 291.973841 -420.488134) (xy 291.97427 -420.524432) (xy 291.973792 -420.563822) (xy 291.965665 -420.642181)
			(xy 291.949511 -420.719287) (xy 291.925502 -420.794319) (xy 291.893893 -420.86648) (xy 291.855021 -420.935001)
			(xy 291.809298 -420.999155) (xy 291.757211 -421.058258) (xy 291.699314 -421.111683) (xy 291.636223 -421.158861)
			(xy 291.602668 -421.179498) (xy 291.594677 -421.187636) (xy 291.586098 -421.208734) (xy 291.586158 -421.220138)
			(xy 291.58692 -421.244014) (xy 291.586434 -421.271283) (xy 291.578672 -421.325267) (xy 291.563307 -421.377597)
			(xy 291.54065 -421.427207) (xy 291.511164 -421.473088) (xy 291.475449 -421.514305) (xy 291.434232 -421.55002)
			(xy 291.388351 -421.579506) (xy 291.338741 -421.602163) (xy 291.286411 -421.617528) (xy 291.232427 -421.62529)
			(xy 291.177889 -421.62529) (xy 291.123905 -421.617528) (xy 291.071575 -421.602163) (xy 291.021965 -421.579506)
			(xy 290.976084 -421.55002) (xy 290.934867 -421.514305) (xy 290.899152 -421.473088) (xy 290.869666 -421.427207)
			(xy 290.847009 -421.377597) (xy 290.831644 -421.325267) (xy 290.823882 -421.271283) (xy 290.823396 -421.244014)
			(xy 290.823396 -421.243506) (xy 290.824666 -421.213788) (xy 290.824895 -421.2024) (xy 290.816743 -421.181168)
			(xy 290.808918 -421.172894) (xy 290.776263 -421.152023) (xy 290.714898 -421.104683) (xy 290.658646 -421.051368)
			(xy 290.608088 -420.992626) (xy 290.563742 -420.929063) (xy 290.526067 -420.861333) (xy 290.49545 -420.790134)
			(xy 290.472206 -420.716198) (xy 290.456575 -420.640288) (xy 290.448717 -420.563184) (xy 290.448238 -420.524432)
			(xy 290.448685 -420.488135) (xy 290.455575 -420.415868) (xy 290.469296 -420.344582) (xy 290.489723 -420.274921)
			(xy 290.516673 -420.207514) (xy 290.549901 -420.142971) (xy 290.569142 -420.11219) (xy 290.57278 -420.100962)
			(xy 290.570379 -420.077508) (xy 290.56457 -420.067232) (xy 290.542263 -420.030624) (xy 290.50506 -419.953386)
			(xy 290.476741 -419.872468) (xy 290.457659 -419.788888) (xy 290.448057 -419.703697) (xy 290.447476 -419.660832)
			(xy 277.599254 -419.660832) (xy 277.538918 -419.707536) (xy 277.47337 -419.748392) (xy 277.404024 -419.782408)
			(xy 277.331593 -419.809233) (xy 277.25682 -419.828593) (xy 277.180472 -419.840289) (xy 277.103332 -419.844202)
			(xy 277.026192 -419.840289) (xy 276.949844 -419.828593) (xy 276.875071 -419.809233) (xy 276.80264 -419.782408)
			(xy 276.733294 -419.748392) (xy 276.667746 -419.707536) (xy 276.606667 -419.660257) (xy 276.550685 -419.607042)
			(xy 276.500374 -419.548436) (xy 276.45625 -419.485042) (xy 276.418765 -419.417508) (xy 276.388306 -419.346529)
			(xy 276.365183 -419.272832) (xy 276.349635 -419.197174) (xy 276.341821 -419.120331) (xy 276.341332 -419.081712)
			(xy 233.545126 -419.081712) (xy 230.329486 -422.297352) (xy 230.322673 -422.304773) (xy 230.314938 -422.323356)
			(xy 230.314775 -422.3271) (xy 285.186564 -422.3271) (xy 285.190477 -422.249953) (xy 285.202174 -422.173598)
			(xy 285.221537 -422.098818) (xy 285.248365 -422.026381) (xy 285.282385 -421.95703) (xy 285.323246 -421.891476)
			(xy 285.37053 -421.830393) (xy 285.423751 -421.774407) (xy 285.482364 -421.724092) (xy 285.545766 -421.679966)
			(xy 285.613307 -421.64248) (xy 285.684293 -421.612021) (xy 285.757998 -421.588899) (xy 285.833663 -421.573352)
			(xy 285.910513 -421.565541) (xy 285.949136 -421.56507) (xy 285.991827 -421.565693) (xy 286.076673 -421.575229)
			(xy 286.159925 -421.594178) (xy 286.240541 -421.622302) (xy 286.317514 -421.65925) (xy 286.354012 -421.681402)
			(xy 286.362268 -421.686116) (xy 286.380936 -421.689643) (xy 286.399604 -421.686116) (xy 286.40786 -421.681402)
			(xy 286.444356 -421.659242) (xy 286.521316 -421.622256) (xy 286.601931 -421.594112) (xy 286.685188 -421.575163)
			(xy 286.770043 -421.565648) (xy 286.812736 -421.56507) (xy 286.851353 -421.565621) (xy 286.92819 -421.573438)
			(xy 287.003842 -421.588988) (xy 287.077532 -421.612112) (xy 287.148506 -421.642572) (xy 287.216033 -421.680055)
			(xy 287.279423 -421.724178) (xy 287.338023 -421.774488) (xy 287.391233 -421.830467) (xy 287.438507 -421.891543)
			(xy 287.47936 -421.957087) (xy 287.513372 -422.026428) (xy 287.540195 -422.098854) (xy 287.559553 -422.173623)
			(xy 287.571248 -422.249966) (xy 287.57516 -422.3271) (xy 287.571248 -422.404234) (xy 287.559553 -422.480577)
			(xy 287.540195 -422.555346) (xy 287.513372 -422.627772) (xy 287.47936 -422.697113) (xy 287.438507 -422.762657)
			(xy 287.391233 -422.823733) (xy 287.338023 -422.879712) (xy 287.279423 -422.930022) (xy 287.216033 -422.974145)
			(xy 287.148506 -423.011628) (xy 287.077532 -423.042088) (xy 287.003842 -423.065212) (xy 286.92819 -423.080762)
			(xy 286.851353 -423.088579) (xy 286.812736 -423.08907) (xy 286.770045 -423.088469) (xy 286.685197 -423.078929)
			(xy 286.601944 -423.059976) (xy 286.521329 -423.031847) (xy 286.444357 -422.994893) (xy 286.40786 -422.972738)
			(xy 286.399604 -422.968024) (xy 286.380936 -422.964497) (xy 286.362268 -422.968024) (xy 286.354012 -422.972738)
			(xy 286.317525 -422.994914) (xy 286.240562 -423.031897) (xy 286.159945 -423.060037) (xy 286.076686 -423.078982)
			(xy 285.99183 -423.088494) (xy 285.949136 -423.08907) (xy 285.910513 -423.088659) (xy 285.833663 -423.080848)
			(xy 285.757998 -423.065301) (xy 285.684293 -423.042179) (xy 285.613307 -423.01172) (xy 285.545766 -422.974234)
			(xy 285.482364 -422.930108) (xy 285.423751 -422.879793) (xy 285.37053 -422.823807) (xy 285.323246 -422.762724)
			(xy 285.282385 -422.69717) (xy 285.248365 -422.627819) (xy 285.221537 -422.555382) (xy 285.202174 -422.480602)
			(xy 285.190477 -422.404247) (xy 285.186564 -422.3271) (xy 230.314775 -422.3271) (xy 230.3145 -422.33342)
			(xy 230.3145 -424.74007) (xy 357.551238 -424.74007) (xy 357.555218 -424.60708) (xy 357.567145 -424.474566)
			(xy 357.586975 -424.343002) (xy 357.614637 -424.21286) (xy 357.650033 -424.084605) (xy 357.693036 -423.958697)
			(xy 357.743492 -423.835585) (xy 357.80122 -423.715712) (xy 357.866014 -423.599505) (xy 357.937641 -423.487381)
			(xy 358.015846 -423.379742) (xy 358.100348 -423.276972) (xy 358.190845 -423.17944) (xy 358.287012 -423.087494)
			(xy 358.388506 -423.001464) (xy 358.494964 -422.921658) (xy 358.606003 -422.848362) (xy 358.721228 -422.781837)
			(xy 358.840224 -422.722322) (xy 358.962567 -422.67003) (xy 359.087818 -422.625149) (xy 359.215529 -422.587838)
			(xy 359.345243 -422.558231) (xy 359.476495 -422.536436) (xy 359.608816 -422.522528) (xy 359.741732 -422.516559)
			(xy 359.874767 -422.518549) (xy 360.007444 -422.528492) (xy 360.13929 -422.546352) (xy 360.269831 -422.572064)
			(xy 360.398601 -422.605538) (xy 360.525139 -422.646652) (xy 360.648991 -422.695261) (xy 360.769715 -422.751189)
			(xy 360.886878 -422.814237) (xy 361.000061 -422.884179) (xy 361.108858 -422.960765) (xy 361.21288 -423.04372)
			(xy 361.311755 -423.132748) (xy 361.405129 -423.227529) (xy 361.492668 -423.327725) (xy 361.574058 -423.432977)
			(xy 361.649007 -423.542907) (xy 361.657271 -423.556738) (xy 456.285335 -423.556738) (xy 456.285335 -423.427598)
			(xy 456.293285 -423.298703) (xy 456.309155 -423.170543) (xy 456.332884 -423.043602) (xy 456.364383 -422.918363)
			(xy 456.403532 -422.7953) (xy 456.450183 -422.674881) (xy 456.504158 -422.557562) (xy 456.565253 -422.443788)
			(xy 456.633236 -422.333991) (xy 456.70785 -422.228588) (xy 456.788811 -422.127978) (xy 456.875811 -422.032543)
			(xy 456.968522 -421.942644) (xy 457.066592 -421.858623) (xy 457.169647 -421.780799) (xy 457.277298 -421.709467)
			(xy 457.389137 -421.644897) (xy 457.504738 -421.587335) (xy 457.623663 -421.536998) (xy 457.745462 -421.494078)
			(xy 457.869672 -421.458737) (xy 457.995821 -421.43111) (xy 458.123433 -421.411301) (xy 458.252022 -421.399385)
			(xy 458.3811 -421.395409) (xy 458.510178 -421.399385) (xy 458.638767 -421.411301) (xy 458.766379 -421.43111)
			(xy 458.892528 -421.458737) (xy 459.016738 -421.494078) (xy 459.138537 -421.536998) (xy 459.257462 -421.587335)
			(xy 459.373063 -421.644897) (xy 459.484902 -421.709467) (xy 459.592553 -421.780799) (xy 459.695608 -421.858623)
			(xy 459.793678 -421.942644) (xy 459.886389 -422.032543) (xy 459.973389 -422.127978) (xy 460.05435 -422.228588)
			(xy 460.128964 -422.333991) (xy 460.196947 -422.443788) (xy 460.258042 -422.557562) (xy 460.312017 -422.674881)
			(xy 460.358668 -422.7953) (xy 460.397817 -422.918363) (xy 460.429316 -423.043602) (xy 460.453045 -423.170543)
			(xy 460.468915 -423.298703) (xy 460.476865 -423.427598) (xy 460.477362 -423.492168) (xy 460.476865 -423.556738)
			(xy 460.468915 -423.685633) (xy 460.453045 -423.813793) (xy 460.429316 -423.940734) (xy 460.397817 -424.065973)
			(xy 460.358668 -424.189036) (xy 460.312017 -424.309455) (xy 460.258042 -424.426774) (xy 460.196947 -424.540548)
			(xy 460.128964 -424.650345) (xy 460.05435 -424.755748) (xy 459.973389 -424.856358) (xy 459.886389 -424.951793)
			(xy 459.793678 -425.041692) (xy 459.695608 -425.125713) (xy 459.592553 -425.203537) (xy 459.484902 -425.274869)
			(xy 459.373063 -425.339439) (xy 459.257462 -425.397001) (xy 459.138537 -425.447338) (xy 459.016738 -425.490258)
			(xy 458.892528 -425.525599) (xy 458.766379 -425.553226) (xy 458.638767 -425.573035) (xy 458.510178 -425.584951)
			(xy 458.3811 -425.588928) (xy 458.252022 -425.584951) (xy 458.123433 -425.573035) (xy 457.995821 -425.553226)
			(xy 457.869672 -425.525599) (xy 457.745462 -425.490258) (xy 457.623663 -425.447338) (xy 457.504738 -425.397001)
			(xy 457.389137 -425.339439) (xy 457.277298 -425.274869) (xy 457.169647 -425.203537) (xy 457.066592 -425.125713)
			(xy 456.968522 -425.041692) (xy 456.875811 -424.951793) (xy 456.788811 -424.856358) (xy 456.70785 -424.755748)
			(xy 456.633236 -424.650345) (xy 456.565253 -424.540548) (xy 456.504158 -424.426774) (xy 456.450183 -424.309455)
			(xy 456.403532 -424.189036) (xy 456.364383 -424.065973) (xy 456.332884 -423.940734) (xy 456.309155 -423.813793)
			(xy 456.293285 -423.685633) (xy 456.285335 -423.556738) (xy 361.657271 -423.556738) (xy 361.717248 -423.657124)
			(xy 361.778537 -423.775217) (xy 361.832653 -423.896764) (xy 361.879403 -424.021329) (xy 361.91862 -424.148468)
			(xy 361.950164 -424.277724) (xy 361.97392 -424.408636) (xy 361.989806 -424.540734) (xy 361.997763 -424.673545)
			(xy 361.99826 -424.74007) (xy 361.997763 -424.806595) (xy 361.989806 -424.939406) (xy 361.97392 -425.071504)
			(xy 361.950164 -425.202416) (xy 361.91862 -425.331672) (xy 361.879403 -425.458811) (xy 361.832653 -425.583376)
			(xy 361.778537 -425.704923) (xy 361.717248 -425.823016) (xy 361.649007 -425.937233) (xy 361.574058 -426.047163)
			(xy 361.492668 -426.152415) (xy 361.405129 -426.252611) (xy 361.311755 -426.347392) (xy 361.21288 -426.43642)
			(xy 361.108858 -426.519375) (xy 361.000061 -426.595961) (xy 360.886878 -426.665903) (xy 360.769715 -426.728951)
			(xy 360.648991 -426.784879) (xy 360.525139 -426.833488) (xy 360.398601 -426.874602) (xy 360.269831 -426.908076)
			(xy 360.13929 -426.933788) (xy 360.007444 -426.951648) (xy 359.874767 -426.961591) (xy 359.741732 -426.963581)
			(xy 359.608816 -426.957612) (xy 359.476495 -426.943704) (xy 359.345243 -426.921909) (xy 359.215529 -426.892302)
			(xy 359.087818 -426.854991) (xy 358.962567 -426.81011) (xy 358.840224 -426.757818) (xy 358.721228 -426.698303)
			(xy 358.606003 -426.631778) (xy 358.494964 -426.558482) (xy 358.388506 -426.478676) (xy 358.287012 -426.392646)
			(xy 358.190845 -426.3007) (xy 358.100348 -426.203168) (xy 358.015846 -426.100398) (xy 357.937641 -425.992759)
			(xy 357.866014 -425.880635) (xy 357.80122 -425.764428) (xy 357.743492 -425.644555) (xy 357.693036 -425.521443)
			(xy 357.650033 -425.395535) (xy 357.614637 -425.26728) (xy 357.586975 -425.137138) (xy 357.567145 -425.005574)
			(xy 357.555218 -424.87306) (xy 357.551238 -424.74007) (xy 230.3145 -424.74007) (xy 230.3145 -427.960536)
			(xy 314.141104 -427.960536) (xy 314.141104 -425.419012) (xy 314.14157 -425.406962) (xy 314.149 -425.384036)
			(xy 314.163139 -425.36452) (xy 314.182609 -425.350316) (xy 314.20551 -425.342811) (xy 314.217558 -425.342304)
			(xy 315.157866 -425.342304) (xy 315.16995 -425.342836) (xy 315.192944 -425.350279) (xy 315.212521 -425.36445)
			(xy 315.226774 -425.383968) (xy 315.234313 -425.40693) (xy 315.234828 -425.419012) (xy 315.234828 -427.960536)
			(xy 315.234371 -427.972585) (xy 315.226932 -427.995507) (xy 315.21279 -428.01502) (xy 315.193321 -428.029223)
			(xy 315.170422 -428.036734) (xy 315.158374 -428.037244) (xy 314.218066 -428.037244) (xy 314.205973 -428.036821)
			(xy 314.182969 -428.029353) (xy 314.163388 -428.015156) (xy 314.149139 -427.995612) (xy 314.141611 -427.972628)
			(xy 314.141104 -427.960536) (xy 230.3145 -427.960536) (xy 230.3145 -433.134051) (xy 266.619222 -433.134051)
			(xy 266.619222 -432.950069) (xy 266.627247 -432.766261) (xy 266.643282 -432.582979) (xy 266.667296 -432.400571)
			(xy 266.699245 -432.219383) (xy 266.739066 -432.039762) (xy 266.786684 -431.862048) (xy 266.842008 -431.686581)
			(xy 266.904934 -431.513694) (xy 266.975341 -431.343717) (xy 267.053096 -431.176972) (xy 267.138049 -431.013777)
			(xy 267.23004 -430.854444) (xy 267.328894 -430.699275) (xy 267.434422 -430.548565) (xy 267.546424 -430.402602)
			(xy 267.664685 -430.261663) (xy 267.788982 -430.126017) (xy 267.919077 -429.995922) (xy 268.054723 -429.871625)
			(xy 268.195662 -429.753364) (xy 268.341625 -429.641362) (xy 268.492335 -429.535834) (xy 268.647504 -429.43698)
			(xy 268.806837 -429.344989) (xy 268.970032 -429.260036) (xy 269.136777 -429.182281) (xy 269.306754 -429.111874)
			(xy 269.479641 -429.048948) (xy 269.655108 -428.993624) (xy 269.832822 -428.946006) (xy 270.012443 -428.906185)
			(xy 270.193631 -428.874236) (xy 270.376039 -428.850222) (xy 270.559321 -428.834187) (xy 270.743129 -428.826162)
			(xy 270.927111 -428.826162) (xy 271.110919 -428.834187) (xy 271.294201 -428.850222) (xy 271.476609 -428.874236)
			(xy 271.657797 -428.906185) (xy 271.837418 -428.946006) (xy 272.015132 -428.993624) (xy 272.190599 -429.048948)
			(xy 272.363486 -429.111874) (xy 272.533463 -429.182281) (xy 272.700208 -429.260036) (xy 272.863403 -429.344989)
			(xy 273.022736 -429.43698) (xy 273.177905 -429.535834) (xy 273.328615 -429.641362) (xy 273.474578 -429.753364)
			(xy 273.615517 -429.871625) (xy 273.751163 -429.995922) (xy 273.881258 -430.126017) (xy 274.005555 -430.261663)
			(xy 274.123816 -430.402602) (xy 274.235818 -430.548565) (xy 274.341346 -430.699275) (xy 274.4402 -430.854444)
			(xy 274.532191 -431.013777) (xy 274.617144 -431.176972) (xy 274.694899 -431.343717) (xy 274.765306 -431.513694)
			(xy 274.828232 -431.686581) (xy 274.883556 -431.862048) (xy 274.931174 -432.039762) (xy 274.970995 -432.219383)
			(xy 275.002944 -432.400571) (xy 275.026958 -432.582979) (xy 275.042993 -432.766261) (xy 275.051018 -432.950069)
			(xy 275.05152 -433.04206) (xy 275.051018 -433.134051) (xy 275.042993 -433.317859) (xy 275.026958 -433.501141)
			(xy 275.002944 -433.683549) (xy 274.970995 -433.864737) (xy 274.931174 -434.044358) (xy 274.883556 -434.222072)
			(xy 274.828232 -434.397539) (xy 274.765306 -434.570426) (xy 274.694899 -434.740403) (xy 274.617144 -434.907148)
			(xy 274.532191 -435.070343) (xy 274.4402 -435.229676) (xy 274.341346 -435.384845) (xy 274.235818 -435.535555)
			(xy 274.123816 -435.681518) (xy 274.005555 -435.822457) (xy 273.881258 -435.958103) (xy 273.751163 -436.088198)
			(xy 273.615517 -436.212495) (xy 273.474578 -436.330756) (xy 273.328615 -436.442758) (xy 273.177905 -436.548286)
			(xy 273.022736 -436.64714) (xy 272.863403 -436.739131) (xy 272.700208 -436.824084) (xy 272.533463 -436.901839)
			(xy 272.363486 -436.972246) (xy 272.190599 -437.035172) (xy 272.015132 -437.090496) (xy 271.837418 -437.138114)
			(xy 271.657797 -437.177935) (xy 271.476609 -437.209884) (xy 271.294201 -437.233898) (xy 271.110919 -437.249933)
			(xy 270.927111 -437.257958) (xy 270.743129 -437.257958) (xy 270.559321 -437.249933) (xy 270.376039 -437.233898)
			(xy 270.193631 -437.209884) (xy 270.012443 -437.177935) (xy 269.832822 -437.138114) (xy 269.655108 -437.090496)
			(xy 269.479641 -437.035172) (xy 269.306754 -436.972246) (xy 269.136777 -436.901839) (xy 268.970032 -436.824084)
			(xy 268.806837 -436.739131) (xy 268.647504 -436.64714) (xy 268.492335 -436.548286) (xy 268.341625 -436.442758)
			(xy 268.195662 -436.330756) (xy 268.054723 -436.212495) (xy 267.919077 -436.088198) (xy 267.788982 -435.958103)
			(xy 267.664685 -435.822457) (xy 267.546424 -435.681518) (xy 267.434422 -435.535555) (xy 267.328894 -435.384845)
			(xy 267.23004 -435.229676) (xy 267.138049 -435.070343) (xy 267.053096 -434.907148) (xy 266.975341 -434.740403)
			(xy 266.904934 -434.570426) (xy 266.842008 -434.397539) (xy 266.786684 -434.222072) (xy 266.739066 -434.044358)
			(xy 266.699245 -433.864737) (xy 266.667296 -433.683549) (xy 266.643282 -433.501141) (xy 266.627247 -433.317859)
			(xy 266.619222 -433.134051) (xy 230.3145 -433.134051) (xy 230.3145 -435.873652) (xy 230.314033 -435.898602)
			(xy 230.306213 -435.947887) (xy 230.29079 -435.995345) (xy 230.268141 -436.03981) (xy 230.238824 -436.080191)
			(xy 230.221536 -436.098188) (xy 229.299008 -437.020716) (xy 229.281016 -437.03801) (xy 229.240639 -437.067332)
			(xy 229.196172 -437.089979) (xy 229.148711 -437.105393) (xy 229.099423 -437.113193) (xy 229.074472 -437.11368)
			(xy 207.302608 -437.11368) (xy 207.27766 -437.113152) (xy 207.22838 -437.105344) (xy 207.180923 -437.089933)
			(xy 207.136457 -437.067299) (xy 207.096072 -437.037997) (xy 207.078072 -437.020716) (xy 205.512924 -435.455568)
			(xy 205.495618 -435.437587) (xy 205.466295 -435.397208) (xy 205.44365 -435.352738) (xy 205.42824 -435.305274)
			(xy 205.420444 -435.255984) (xy 205.41996 -435.231032) (xy 205.41996 -431.16881) (xy 205.41954 -431.15874)
			(xy 205.411817 -431.140141) (xy 205.404974 -431.132742) (xy 196.207888 -421.935656) (xy 196.19057 -421.917686)
			(xy 196.16125 -421.877303) (xy 196.138608 -421.832831) (xy 196.1232 -421.785364) (xy 196.115407 -421.736072)
			(xy 196.114924 -421.71112) (xy 196.114924 -413.329374) (xy 196.114532 -413.319301) (xy 196.10679 -413.300702)
			(xy 196.099938 -413.293306) (xy 195.154296 -412.347664) (xy 195.146896 -412.340825) (xy 195.128296 -412.333106)
			(xy 195.118228 -412.332678) (xy 188.720222 -412.332678) (xy 188.695275 -412.332142) (xy 188.645994 -412.324336)
			(xy 188.598538 -412.308927) (xy 188.554072 -412.286295) (xy 188.513686 -412.256994) (xy 188.495686 -412.239714)
			(xy 187.848748 -411.592776) (xy 187.841328 -411.585961) (xy 187.822744 -411.578227) (xy 187.81268 -411.57779)
			(xy 184.8104 -411.57779) (xy 184.785451 -411.577293) (xy 184.736167 -411.569481) (xy 184.68871 -411.554065)
			(xy 184.644244 -411.531423) (xy 184.603862 -411.502111) (xy 184.585864 -411.484826) (xy 184.033922 -410.932884)
			(xy 184.016624 -410.914896) (xy 183.9873 -410.874519) (xy 183.964653 -410.830051) (xy 183.949241 -410.782588)
			(xy 183.941443 -410.733299) (xy 183.940958 -410.708348) (xy 166.005717 -410.708348) (xy 166.002747 -410.717399)
			(xy 165.986714 -410.754322) (xy 165.982115 -410.766115) (xy 165.984005 -410.791327) (xy 165.99027 -410.802328)
			(xy 166.012694 -410.838944) (xy 166.050052 -410.916258) (xy 166.07849 -410.997278) (xy 166.09765 -411.080979)
			(xy 166.107289 -411.166303) (xy 166.107872 -411.209236) (xy 166.107389 -411.248809) (xy 166.09919 -411.32753)
			(xy 166.082884 -411.404978) (xy 166.058646 -411.480321) (xy 166.026736 -411.55275) (xy 165.987498 -411.621485)
			(xy 165.941354 -411.685788) (xy 165.888799 -411.744966) (xy 165.830399 -411.798385) (xy 165.766781 -411.84547)
			(xy 165.69863 -411.885713) (xy 165.662864 -411.902656) (xy 165.65372 -411.90672) (xy 165.640258 -411.920944)
			(xy 165.621716 -411.967934) (xy 165.62197 -411.987746) (xy 165.62578 -411.996636) (xy 165.639748 -412.031452)
			(xy 165.661538 -412.103238) (xy 165.676173 -412.176818) (xy 165.683512 -412.251479) (xy 165.683946 -412.28899)
			(xy 165.683946 -412.289244) (xy 165.683539 -412.324647) (xy 165.676948 -412.395147) (xy 165.663855 -412.464733)
			(xy 165.644373 -412.532808) (xy 165.618668 -412.598784) (xy 165.603174 -412.63062) (xy 165.598942 -412.640112)
			(xy 165.597765 -412.660839) (xy 165.600888 -412.670752) (xy 165.615779 -412.71305) (xy 165.63668 -412.800257)
			(xy 165.647218 -412.889312) (xy 165.647878 -412.93415) (xy 165.647878 -412.934404) (xy 165.647415 -412.974367)
			(xy 165.63906 -413.053855) (xy 165.622441 -413.132034) (xy 165.597742 -413.208047) (xy 165.565232 -413.281062)
			(xy 165.525268 -413.350279) (xy 165.478287 -413.414939) (xy 165.424805 -413.474334) (xy 165.365407 -413.527813)
			(xy 165.300744 -413.57479) (xy 165.231525 -413.614751) (xy 165.158508 -413.647257) (xy 165.082493 -413.671952)
			(xy 165.004313 -413.688566) (xy 164.924825 -413.696917) (xy 164.884862 -413.69742) (xy 164.847791 -413.696948)
			(xy 164.773997 -413.689766) (xy 164.701247 -413.675466) (xy 164.630226 -413.65418) (xy 164.561602 -413.62611)
			(xy 164.496023 -413.59152) (xy 164.434106 -413.550736) (xy 164.376434 -413.504141) (xy 164.349684 -413.478472)
			(xy 164.342572 -413.47136) (xy 164.32403 -413.46374) (xy 164.242242 -413.464248) (xy 164.232339 -413.464747)
			(xy 164.214038 -413.472331) (xy 164.206682 -413.47898) (xy 163.666424 -414.019238) (xy 163.659014 -414.026065)
			(xy 163.640422 -414.033791) (xy 163.630356 -414.034224) (xy 116.511832 -414.034224) (xy 116.487194 -414.049464)
			(xy 116.480844 -414.062418) (xy 116.467834 -414.087519) (xy 116.435532 -414.133917) (xy 116.396737 -414.17504)
			(xy 116.352299 -414.209989) (xy 116.30319 -414.237999) (xy 116.250486 -414.258455) (xy 116.19534 -414.270911)
			(xy 116.13896 -414.275094) (xy 116.08258 -414.270911) (xy 116.027434 -414.258455) (xy 115.97473 -414.237999)
			(xy 115.925621 -414.209989) (xy 115.881183 -414.17504) (xy 115.842388 -414.133917) (xy 115.810086 -414.087519)
			(xy 115.797076 -414.062418) (xy 115.790726 -414.049464) (xy 115.766088 -414.034224) (xy 107.362752 -414.034224)
			(xy 107.354556 -414.034507) (xy 107.33901 -414.039707) (xy 107.332272 -414.044384) (xy 107.3194 -414.053884)
			(xy 107.292975 -414.071924) (xy 107.27944 -414.080452) (xy 107.271948 -414.085582) (xy 107.26092 -414.099991)
			(xy 107.255632 -414.117348) (xy 107.255818 -414.126426) (xy 107.256326 -414.14573) (xy 107.255839 -414.173018)
			(xy 107.248073 -414.227037) (xy 107.232697 -414.279401) (xy 107.210026 -414.329045) (xy 107.18052 -414.374956)
			(xy 107.144781 -414.416201) (xy 107.103536 -414.45194) (xy 107.057625 -414.481446) (xy 107.007981 -414.504117)
			(xy 106.955617 -414.519493) (xy 106.901598 -414.527259) (xy 106.847022 -414.527259) (xy 106.793003 -414.519493)
			(xy 106.740639 -414.504117) (xy 106.690995 -414.481446) (xy 106.645084 -414.45194) (xy 106.603839 -414.416201)
			(xy 106.5681 -414.374956) (xy 106.538594 -414.329045) (xy 106.515923 -414.279401) (xy 106.500547 -414.227037)
			(xy 106.492781 -414.173018) (xy 106.492294 -414.14573) (xy 106.492366 -414.134592) (xy 106.493635 -414.112353)
			(xy 106.494834 -414.10128) (xy 106.495088 -414.096708) (xy 106.469434 -414.080706) (xy 106.461178 -414.075992)
			(xy 106.44251 -414.072465) (xy 106.423842 -414.075992) (xy 106.415586 -414.080706) (xy 106.389932 -414.096708)
			(xy 106.390186 -414.10128) (xy 106.39139 -414.112353) (xy 106.392661 -414.134592) (xy 106.392726 -414.14573)
			(xy 106.392239 -414.173018) (xy 106.384473 -414.227037) (xy 106.369097 -414.279401) (xy 106.346426 -414.329045)
			(xy 106.31692 -414.374956) (xy 106.281181 -414.416201) (xy 106.239936 -414.45194) (xy 106.194025 -414.481446)
			(xy 106.144381 -414.504117) (xy 106.092017 -414.519493) (xy 106.037998 -414.527259) (xy 105.983422 -414.527259)
			(xy 105.929403 -414.519493) (xy 105.877039 -414.504117) (xy 105.827395 -414.481446) (xy 105.781484 -414.45194)
			(xy 105.740239 -414.416201) (xy 105.7045 -414.374956) (xy 105.674994 -414.329045) (xy 105.652323 -414.279401)
			(xy 105.636947 -414.227037) (xy 105.629181 -414.173018) (xy 105.628694 -414.14573) (xy 105.629202 -414.126426)
			(xy 105.629365 -414.117356) (xy 105.624038 -414.100027) (xy 105.613041 -414.085614) (xy 105.60558 -414.080452)
			(xy 105.592045 -414.071924) (xy 105.56562 -414.053884) (xy 105.552748 -414.044384) (xy 105.546014 -414.039705)
			(xy 105.530463 -414.034529) (xy 105.522268 -414.034224) (xy 103.654606 -414.034224) (xy 103.645886 -414.034602)
			(xy 103.629476 -414.040521) (xy 103.615984 -414.051579) (xy 103.611172 -414.058862) (xy 103.59054 -414.092351)
			(xy 103.543387 -414.155315) (xy 103.490004 -414.213091) (xy 103.430957 -414.265066) (xy 103.366875 -414.310687)
			(xy 103.298436 -414.349469) (xy 103.22637 -414.381001) (xy 103.151441 -414.404948) (xy 103.074445 -414.421056)
			(xy 102.996199 -414.429152) (xy 102.917537 -414.429152) (xy 102.839291 -414.421056) (xy 102.762295 -414.404948)
			(xy 102.687366 -414.381001) (xy 102.6153 -414.349469) (xy 102.546861 -414.310687) (xy 102.482779 -414.265066)
			(xy 102.423732 -414.213091) (xy 102.370349 -414.155315) (xy 102.323196 -414.092351) (xy 102.302564 -414.058862)
			(xy 102.29778 -414.051551) (xy 102.284299 -414.040458) (xy 102.26786 -414.034577) (xy 102.25913 -414.034224)
			(xy 102.172516 -414.034224) (xy 102.16168 -414.034807) (xy 102.14195 -414.043784) (xy 102.127649 -414.060074)
			(xy 102.124002 -414.070292) (xy 102.124002 -414.070546) (xy 102.117725 -414.090731) (xy 102.101303 -414.129683)
			(xy 102.091236 -414.14827) (xy 102.08641 -414.156906) (xy 102.08387 -414.17621) (xy 102.10419 -414.254188)
			(xy 102.107077 -414.263519) (xy 102.118706 -414.279193) (xy 102.126796 -414.284668) (xy 102.134008 -414.289532)
			(xy 102.144943 -414.303043) (xy 102.150791 -414.319413) (xy 102.15118 -414.328102) (xy 102.15118 -421.122094)
			(xy 102.150662 -421.132249) (xy 102.142893 -421.151015) (xy 102.128535 -421.16538) (xy 102.109773 -421.173157)
			(xy 102.099618 -421.173656) (xy 97.200974 -421.173656) (xy 97.190814 -421.173188) (xy 97.172043 -421.165404)
			(xy 97.157678 -421.15103) (xy 97.149906 -421.132255) (xy 97.149412 -421.122094) (xy 97.149412 -414.440624)
			(xy 97.149097 -414.432284) (xy 97.143781 -414.416475) (xy 97.138998 -414.409636) (xy 97.117072 -414.380183)
			(xy 97.078336 -414.317801) (xy 97.045781 -414.251981) (xy 97.019709 -414.183334) (xy 97.000363 -414.112498)
			(xy 96.99371 -414.076388) (xy 96.991887 -414.067648) (xy 96.983009 -414.052169) (xy 96.969359 -414.040675)
			(xy 96.952594 -414.034562) (xy 96.943672 -414.034224) (xy 42.362882 -414.034224) (xy 42.35431 -414.034572)
			(xy 42.338137 -414.040264) (xy 42.324768 -414.050997) (xy 42.319956 -414.0581) (xy 42.267378 -414.142936)
			(xy 42.266108 -414.169098) (xy 42.272204 -414.181036) (xy 42.291182 -414.220667) (xy 42.320937 -414.303348)
			(xy 42.340995 -414.3889) (xy 42.351089 -414.47619) (xy 42.351706 -414.520126) (xy 42.351131 -414.562727)
			(xy 42.341628 -414.647397) (xy 42.322754 -414.730482) (xy 42.294744 -414.810948) (xy 42.257947 -414.887794)
			(xy 42.235882 -414.92424) (xy 42.231196 -414.93251) (xy 42.227659 -414.951169) (xy 42.231174 -414.969832)
			(xy 42.235882 -414.978088) (xy 42.258115 -415.014607) (xy 42.295158 -415.091667) (xy 42.32335 -415.172387)
			(xy 42.342337 -415.255754) (xy 42.35188 -415.340721) (xy 42.352468 -415.383472) (xy 42.352468 -415.383726)
			(xy 42.351979 -415.423727) (xy 42.343614 -415.503291) (xy 42.326978 -415.581545) (xy 42.302254 -415.657631)
			(xy 42.269712 -415.730717) (xy 42.229708 -415.8) (xy 42.182682 -415.864722) (xy 42.129149 -415.924174)
			(xy 42.069694 -415.977705) (xy 42.00497 -416.024728) (xy 41.935684 -416.064728) (xy 41.862598 -416.097267)
			(xy 41.78651 -416.121987) (xy 41.708256 -416.13862) (xy 41.628691 -416.146981) (xy 41.58869 -416.147504)
			(xy 41.547848 -416.14698) (xy 41.46663 -416.138265) (xy 41.386807 -416.120925) (xy 41.309294 -416.095158)
			(xy 41.234975 -416.06126) (xy 41.164703 -416.019617) (xy 41.099281 -415.970707) (xy 41.069006 -415.943288)
			(xy 41.059662 -415.935672) (xy 41.03649 -415.929163) (xy 41.024556 -415.930842) (xy 41.007398 -415.934034)
			(xy 40.972665 -415.937473) (xy 40.955214 -415.9377) (xy 40.954706 -415.9377) (xy 40.926705 -415.937107)
			(xy 40.871392 -415.928348) (xy 40.818131 -415.911044) (xy 40.768231 -415.885622) (xy 40.722923 -415.852707)
			(xy 40.683321 -415.813111) (xy 40.650401 -415.767806) (xy 40.624972 -415.71791) (xy 40.607662 -415.664651)
			(xy 40.598896 -415.609339) (xy 40.598344 -415.581338) (xy 40.598844 -415.55542) (xy 40.606362 -415.504132)
			(xy 40.621229 -415.454473) (xy 40.643134 -415.407493) (xy 40.671612 -415.36418) (xy 40.706065 -415.32545)
			(xy 40.745764 -415.292119) (xy 40.789873 -415.26489) (xy 40.813482 -415.254186) (xy 40.824266 -415.248777)
			(xy 40.83964 -415.230228) (xy 40.842946 -415.218626) (xy 40.852954 -415.176239) (xy 40.881331 -415.093895)
			(xy 40.918893 -415.015315) (xy 40.941498 -414.978088) (xy 40.946244 -414.969847) (xy 40.949763 -414.951169)
			(xy 40.946221 -414.932496) (xy 40.941498 -414.92424) (xy 40.919094 -414.887273) (xy 40.881857 -414.809262)
			(xy 40.853676 -414.727541) (xy 40.843708 -414.68548) (xy 40.840423 -414.673861) (xy 40.825056 -414.65529)
			(xy 40.814244 -414.64992) (xy 40.790553 -414.639275) (xy 40.746293 -414.612097) (xy 40.70645 -414.57878)
			(xy 40.671866 -414.54003) (xy 40.643276 -414.49667) (xy 40.621284 -414.449617) (xy 40.606359 -414.39987)
			(xy 40.598815 -414.348483) (xy 40.598344 -414.322514) (xy 40.598899 -414.294524) (xy 40.607651 -414.239231)
			(xy 40.62494 -414.185988) (xy 40.650343 -414.136103) (xy 40.683234 -414.090803) (xy 40.722804 -414.051205)
			(xy 40.768079 -414.01828) (xy 40.817945 -413.992841) (xy 40.871176 -413.975512) (xy 40.926462 -413.96672)
			(xy 40.954452 -413.966152) (xy 40.954706 -413.966152) (xy 40.972482 -413.96637) (xy 41.007855 -413.969937)
			(xy 41.025318 -413.973264) (xy 41.037263 -413.974994) (xy 41.060471 -413.968511) (xy 41.069768 -413.960818)
			(xy 41.087926 -413.944258) (xy 41.126057 -413.913247) (xy 41.145968 -413.898842) (xy 41.15476 -413.891948)
			(xy 41.165837 -413.872579) (xy 41.167304 -413.861504) (xy 41.173654 -413.784288) (xy 41.173981 -413.773199)
			(xy 41.166353 -413.752393) (xy 41.158922 -413.744156) (xy 40.235886 -412.82112) (xy 40.229712 -412.815342)
			(xy 40.214512 -412.807949) (xy 40.197731 -412.805926) (xy 40.189404 -412.807404) (xy 40.105838 -412.82493)
			(xy 40.093527 -412.828346) (xy 40.074201 -412.845007) (xy 40.069008 -412.85668) (xy 40.055409 -412.891106)
			(xy 40.022462 -412.957393) (xy 40.003222 -412.989014) (xy 39.998473 -412.997254) (xy 39.994954 -413.015933)
			(xy 39.998497 -413.034607) (xy 40.003222 -413.042862) (xy 40.025438 -413.079391) (xy 40.062485 -413.156448)
			(xy 40.090681 -413.237166) (xy 40.109672 -413.32053) (xy 40.119219 -413.405496) (xy 40.119808 -413.448246)
			(xy 40.119808 -413.4485) (xy 40.119255 -413.488499) (xy 40.110893 -413.56806) (xy 40.09426 -413.646311)
			(xy 40.06954 -413.722395) (xy 40.037002 -413.795478) (xy 39.997004 -413.864759) (xy 39.949982 -413.929481)
			(xy 39.896454 -413.988933) (xy 39.837004 -414.042464) (xy 39.772285 -414.089487) (xy 39.703005 -414.129489)
			(xy 39.629923 -414.162029) (xy 39.55384 -414.186753) (xy 39.47559 -414.203388) (xy 39.396029 -414.211753)
			(xy 39.35603 -414.212278) (xy 39.315189 -414.21171) (xy 39.233974 -414.203) (xy 39.154153 -414.185665)
			(xy 39.07664 -414.159905) (xy 39.002321 -414.126014) (xy 38.932047 -414.084379) (xy 38.866622 -414.035477)
			(xy 38.836346 -414.008062) (xy 38.827027 -414.00041) (xy 38.803835 -413.993923) (xy 38.791896 -413.995616)
			(xy 38.774739 -413.998817) (xy 38.740005 -414.00225) (xy 38.722554 -414.002474) (xy 38.722046 -414.002474)
			(xy 38.694043 -414.001899) (xy 38.638724 -413.993144) (xy 38.585457 -413.975843) (xy 38.535552 -413.950421)
			(xy 38.490238 -413.917505) (xy 38.450632 -413.877906) (xy 38.417709 -413.832598) (xy 38.392279 -413.782697)
			(xy 38.37497 -413.729432) (xy 38.366206 -413.674115) (xy 38.365684 -413.646112) (xy 38.366138 -413.620192)
			(xy 38.37366 -413.568901) (xy 38.388534 -413.51924) (xy 38.410444 -413.472258) (xy 38.438929 -413.428945)
			(xy 38.473388 -413.390216) (xy 38.513094 -413.356887) (xy 38.55721 -413.329662) (xy 38.580822 -413.31896)
			(xy 38.591591 -413.313528) (xy 38.60697 -413.294994) (xy 38.610286 -413.2834) (xy 38.620308 -413.241017)
			(xy 38.64868 -413.158672) (xy 38.686236 -413.08009) (xy 38.708838 -413.042862) (xy 38.71352 -413.03459)
			(xy 38.717057 -413.015932) (xy 38.713544 -412.99727) (xy 38.708838 -412.989014) (xy 38.686431 -412.952049)
			(xy 38.649195 -412.874037) (xy 38.621015 -412.792315) (xy 38.611048 -412.750254) (xy 38.607804 -412.73862)
			(xy 38.592409 -412.720054) (xy 38.581584 -412.714694) (xy 38.557908 -412.704019) (xy 38.513652 -412.676841)
			(xy 38.473812 -412.643527) (xy 38.439229 -412.604781) (xy 38.410638 -412.561426) (xy 38.388644 -412.514379)
			(xy 38.373712 -412.464637) (xy 38.36616 -412.413255) (xy 38.365684 -412.387288) (xy 38.366175 -412.359295)
			(xy 38.374932 -412.303998) (xy 38.392228 -412.25075) (xy 38.417637 -412.200863) (xy 38.450535 -412.155562)
			(xy 38.490113 -412.115963) (xy 38.535395 -412.08304) (xy 38.585269 -412.057603) (xy 38.638507 -412.040278)
			(xy 38.693799 -412.031491) (xy 38.721792 -412.030926) (xy 38.722046 -412.030926) (xy 38.739822 -412.031153)
			(xy 38.775194 -412.034714) (xy 38.792658 -412.038038) (xy 38.804601 -412.039801) (xy 38.827814 -412.033297)
			(xy 38.837108 -412.025592) (xy 38.86427 -412.001003) (xy 38.922522 -411.956556) (xy 38.984764 -411.917893)
			(xy 39.050422 -411.885369) (xy 39.084504 -411.871922) (xy 39.092286 -411.868625) (xy 39.10523 -411.857767)
			(xy 39.113937 -411.843289) (xy 39.116 -411.835092) (xy 39.13378 -411.751526) (xy 39.135253 -411.743202)
			(xy 39.133213 -411.72643) (xy 39.125816 -411.711239) (xy 39.120064 -411.705044) (xy 28.41371 -400.998944)
			(xy 28.404765 -400.990934) (xy 28.381967 -400.983507) (xy 28.370022 -400.98472) (xy 28.288742 -400.997166)
			(xy 28.276975 -400.999656) (xy 28.257497 -401.013718) (xy 28.251404 -401.02409) (xy 28.251404 -401.024344)
			(xy 28.233593 -401.057923) (xy 28.192279 -401.121729) (xy 28.144824 -401.18111) (xy 28.091699 -401.235477)
			(xy 28.033431 -401.284293) (xy 27.970598 -401.327071) (xy 27.903822 -401.36339) (xy 27.833765 -401.392888)
			(xy 27.761122 -401.415273) (xy 27.686613 -401.430323) (xy 27.610977 -401.437889) (xy 27.57297 -401.438364)
			(xy 27.533008 -401.437861) (xy 27.453523 -401.429507) (xy 27.375346 -401.41289) (xy 27.299335 -401.388192)
			(xy 27.226322 -401.355684) (xy 27.157106 -401.315723) (xy 27.092447 -401.268745) (xy 27.033053 -401.215266)
			(xy 26.979574 -401.155871) (xy 26.932596 -401.091212) (xy 26.892635 -401.021997) (xy 26.860127 -400.948983)
			(xy 26.83543 -400.872972) (xy 26.818813 -400.794795) (xy 26.810459 -400.71531) (xy 26.809954 -400.675348)
			(xy 26.809954 -400.675094) (xy 26.810579 -400.631828) (xy 26.820372 -400.545853) (xy 26.839842 -400.461541)
			(xy 26.868739 -400.379978) (xy 26.88717 -400.34083) (xy 26.89183 -400.330144) (xy 26.89197 -400.30686)
			(xy 26.887424 -400.296126) (xy 26.869087 -400.257082) (xy 26.840301 -400.175763) (xy 26.820885 -400.091714)
			(xy 26.811087 -400.006009) (xy 26.810462 -399.962878) (xy 26.810462 -399.962624) (xy 26.81103 -399.920618)
			(xy 26.820281 -399.837117) (xy 26.83865 -399.755138) (xy 26.865915 -399.675674) (xy 26.901747 -399.599687)
			(xy 26.923238 -399.56359) (xy 26.932636 -399.548604) (xy 26.928572 -399.513806) (xy 22.46757 -395.052804)
			(xy 22.450552 -395.045184) (xy 22.441154 -395.044676) (xy 22.402504 -395.04209) (xy 22.325964 -395.030148)
			(xy 22.251029 -395.010508) (xy 22.178472 -394.98337) (xy 22.109041 -394.949016) (xy 22.043451 -394.907798)
			(xy 21.982378 -394.860143) (xy 21.926452 -394.80654) (xy 21.876249 -394.747543) (xy 21.832287 -394.68376)
			(xy 21.795019 -394.615848) (xy 21.779484 -394.580364) (xy 21.747734 -394.581634) (xy 21.720483 -394.581113)
			(xy 21.666536 -394.573361) (xy 21.61424 -394.558011) (xy 21.564662 -394.535374) (xy 21.51881 -394.505912)
			(xy 21.477618 -394.470225) (xy 21.441924 -394.429038) (xy 21.412454 -394.383191) (xy 21.38981 -394.333616)
			(xy 21.374451 -394.281323) (xy 21.366691 -394.227377) (xy 21.366226 -394.200126) (xy 21.366776 -394.171928)
			(xy 21.375148 -394.116157) (xy 21.391641 -394.062226) (xy 21.40331 -394.03655) (xy 21.40331 -394.036042)
			(xy 21.407282 -394.026435) (xy 21.407967 -394.00568) (xy 21.40037 -393.986353) (xy 21.393404 -393.978638)
			(xy 19.967194 -392.552428) (xy 19.958686 -392.544702) (xy 19.937003 -392.537159) (xy 19.925538 -392.53795)
			(xy 19.92503 -392.53795) (xy 19.902951 -392.540416) (xy 19.8586 -392.543087) (xy 19.836384 -392.543284)
			(xy 19.83613 -392.543284) (xy 19.800898 -392.542839) (xy 19.730737 -392.536319) (xy 19.661475 -392.523358)
			(xy 19.593703 -392.504068) (xy 19.527998 -392.478613) (xy 19.496278 -392.463274) (xy 19.486138 -392.458785)
			(xy 19.463998 -392.458133) (xy 19.453606 -392.462004) (xy 19.417719 -392.477014) (xy 19.343547 -392.500475)
			(xy 19.267374 -392.516269) (xy 19.189989 -392.524232) (xy 19.151092 -392.524742) (xy 19.150584 -392.524742)
			(xy 19.110624 -392.524208) (xy 19.031142 -392.515853) (xy 18.952969 -392.499236) (xy 18.87696 -392.474538)
			(xy 18.80395 -392.442031) (xy 18.734737 -392.402071) (xy 18.670081 -392.355095) (xy 18.610688 -392.301619)
			(xy 18.557211 -392.242227) (xy 18.510234 -392.177571) (xy 18.470273 -392.108359) (xy 18.437765 -392.035349)
			(xy 18.413067 -391.959341) (xy 18.396449 -391.881168) (xy 18.388092 -391.801686) (xy 18.387568 -391.761726)
			(xy 18.387568 -391.760964) (xy 18.387653 -391.745516) (xy 18.388924 -391.714645) (xy 18.390108 -391.699242)
			(xy 18.390448 -391.689678) (xy 18.384848 -391.671396) (xy 18.379186 -391.663682) (xy 18.36039 -391.639806)
			(xy 18.354123 -391.632571) (xy 18.337538 -391.623042) (xy 18.328132 -391.621264) (xy 18.281967 -391.613663)
			(xy 18.191905 -391.588316) (xy 18.148554 -391.570718) (xy 18.138963 -391.567153) (xy 18.118521 -391.567153)
			(xy 18.10893 -391.570718) (xy 18.074528 -391.584887) (xy 18.003498 -391.607043) (xy 17.9306 -391.621942)
			(xy 17.856573 -391.629434) (xy 17.81937 -391.6299) (xy 17.819116 -391.6299) (xy 17.782015 -391.629431)
			(xy 17.70819 -391.621961) (xy 17.635487 -391.607126) (xy 17.564637 -391.585074) (xy 17.530318 -391.570972)
			(xy 17.520727 -391.567407) (xy 17.500285 -391.567407) (xy 17.490694 -391.570972) (xy 17.456459 -391.585013)
			(xy 17.385792 -391.606971) (xy 17.313282 -391.621743) (xy 17.239658 -391.629179) (xy 17.202658 -391.629646)
			(xy 17.20215 -391.629646) (xy 17.163533 -391.629133) (xy 17.086723 -391.62106) (xy 17.011177 -391.605002)
			(xy 16.937723 -391.581135) (xy 16.867167 -391.549722) (xy 16.80028 -391.511105) (xy 16.737797 -391.465708)
			(xy 16.680401 -391.414029) (xy 16.628722 -391.356633) (xy 16.583325 -391.29415) (xy 16.544708 -391.227263)
			(xy 16.513295 -391.156707) (xy 16.489428 -391.083253) (xy 16.47337 -391.007707) (xy 16.465297 -390.930897)
			(xy 16.465297 -390.853663) (xy 16.47337 -390.776853) (xy 16.489428 -390.701307) (xy 16.513295 -390.627853)
			(xy 16.544708 -390.557297) (xy 16.583325 -390.49041) (xy 16.628722 -390.427927) (xy 16.680401 -390.370531)
			(xy 16.737797 -390.318852) (xy 16.80028 -390.273455) (xy 16.867167 -390.234838) (xy 16.937723 -390.203425)
			(xy 17.011177 -390.179558) (xy 17.086723 -390.1635) (xy 17.163533 -390.155427) (xy 17.20215 -390.154922)
			(xy 17.231553 -390.155222) (xy 17.29017 -390.159925) (xy 17.319244 -390.16432) (xy 17.3355 -390.16686)
			(xy 17.36471 -390.152128) (xy 17.416526 -390.05129) (xy 17.420985 -390.041507) (xy 17.422133 -390.020059)
			(xy 17.414409 -390.000017) (xy 17.407128 -389.992108) (xy 16.211042 -388.796022) (xy 16.20436 -388.789783)
			(xy 16.187729 -388.782215) (xy 16.169499 -388.780975) (xy 16.151997 -388.786223) (xy 16.144494 -388.79145)
			(xy 16.120149 -388.808953) (xy 16.067024 -388.836749) (xy 16.010137 -388.855686) (xy 15.950952 -388.865276)
			(xy 15.920974 -388.865872) (xy 15.894353 -388.86549) (xy 15.841655 -388.857909) (xy 15.790571 -388.842905)
			(xy 15.742143 -388.820784) (xy 15.697357 -388.791995) (xy 15.657123 -388.757126) (xy 15.622261 -388.716886)
			(xy 15.593482 -388.672093) (xy 15.57137 -388.623661) (xy 15.556376 -388.572575) (xy 15.548805 -388.519875)
			(xy 15.548356 -388.493254) (xy 15.548925 -388.463275) (xy 15.558527 -388.404091) (xy 15.577475 -388.347206)
			(xy 15.605283 -388.294086) (xy 15.622778 -388.269734) (xy 15.627936 -388.262209) (xy 15.633102 -388.244727)
			(xy 15.631856 -388.22654) (xy 15.624353 -388.209926) (xy 15.618206 -388.203186) (xy 15.440406 -388.025386)
			(xy 15.406878 -388.020814) (xy 15.391892 -388.029196) (xy 15.363894 -388.044148) (xy 15.304061 -388.065319)
			(xy 15.241508 -388.076058) (xy 15.209774 -388.076694) (xy 15.183156 -388.076267) (xy 15.130462 -388.068688)
			(xy 15.079384 -388.053686) (xy 15.03096 -388.031567) (xy 14.986177 -388.002783) (xy 14.945947 -387.967918)
			(xy 14.911087 -387.927683) (xy 14.882309 -387.882896) (xy 14.860197 -387.834469) (xy 14.845202 -387.783389)
			(xy 14.837629 -387.730694) (xy 14.837156 -387.704076) (xy 14.837779 -387.672342) (xy 14.848527 -387.60979)
			(xy 14.869709 -387.54996) (xy 14.884654 -387.521958) (xy 14.893036 -387.506972) (xy 14.888464 -387.473444)
			(xy 14.701012 -387.286246) (xy 14.694401 -387.280088) (xy 14.678008 -387.27252) (xy 14.660005 -387.271149)
			(xy 14.651228 -387.273292) (xy 14.626291 -387.279943) (xy 14.575179 -387.28708) (xy 14.549374 -387.287516)
			(xy 14.522757 -387.287068) (xy 14.470065 -387.279488) (xy 14.418989 -387.264487) (xy 14.370566 -387.242371)
			(xy 14.325785 -387.213588) (xy 14.285554 -387.178726) (xy 14.250695 -387.138493) (xy 14.221916 -387.093709)
			(xy 14.199803 -387.045285) (xy 14.184806 -386.994207) (xy 14.17723 -386.941515) (xy 14.176756 -386.914898)
			(xy 14.177221 -386.889096) (xy 14.184353 -386.837985) (xy 14.19098 -386.813044) (xy 14.193078 -386.804266)
			(xy 14.191677 -386.786284) (xy 14.184142 -386.769897) (xy 14.178026 -386.76326) (xy 12.572238 -385.157472)
			(xy 12.55395 -385.149598) (xy 12.544044 -385.149598) (xy 12.517235 -385.148841) (xy 12.464231 -385.140656)
			(xy 12.412895 -385.125128) (xy 12.364239 -385.102565) (xy 12.319222 -385.073411) (xy 12.278731 -385.03824)
			(xy 12.243565 -384.997746) (xy 12.214415 -384.952726) (xy 12.191857 -384.904068) (xy 12.176335 -384.85273)
			(xy 12.168155 -384.799725) (xy 12.167362 -384.772916) (xy 12.167362 -384.76301) (xy 12.159488 -384.744722)
			(xy 12.107926 -384.69316) (xy 12.082018 -384.686302) (xy 12.069064 -384.689604) (xy 12.04566 -384.695277)
			(xy 11.997892 -384.701394) (xy 11.973814 -384.701796) (xy 11.973052 -384.701796) (xy 11.945799 -384.701367)
			(xy 11.891849 -384.693603) (xy 11.839552 -384.678242) (xy 11.789974 -384.655594) (xy 11.744123 -384.626122)
			(xy 11.702933 -384.590424) (xy 11.667242 -384.549229) (xy 11.637777 -384.503373) (xy 11.615137 -384.453792)
			(xy 11.599784 -384.401493) (xy 11.592029 -384.347541) (xy 11.591544 -384.320288) (xy 11.591544 -384.319526)
			(xy 11.591931 -384.295446) (xy 11.598046 -384.247677) (xy 11.603736 -384.224276) (xy 11.607038 -384.211322)
			(xy 11.60018 -384.185414) (xy 6.89991 -379.48489) (xy 6.893074 -379.477486) (xy 6.885352 -379.45889)
			(xy 6.884924 -379.448822) (xy 3.523996 -379.448822) (xy 3.523996 -403.371812) (xy 3.524481 -403.402978)
			(xy 3.532614 -403.464777) (xy 3.548748 -403.524985) (xy 3.572608 -403.58257) (xy 3.603784 -403.636545)
			(xy 3.641742 -403.685987) (xy 3.663442 -403.708362) (xy 6.991604 -407.036524) (xy 7.052397 -407.098056)
			(xy 7.168585 -407.226226) (xy 7.278345 -407.359941) (xy 7.381412 -407.49888) (xy 7.477539 -407.642708)
			(xy 7.566493 -407.79108) (xy 7.648061 -407.943637) (xy 7.722046 -408.100012) (xy 7.78827 -408.259829)
			(xy 7.846574 -408.422702) (xy 7.896816 -408.588239) (xy 7.938876 -408.756043) (xy 7.972653 -408.925707)
			(xy 7.998065 -409.096825) (xy 8.015052 -409.268983) (xy 8.023571 -409.441767) (xy 8.024114 -409.528264)
			(xy 8.024114 -416.06089) (xy 35.400488 -416.06089) (xy 35.40095 -416.032882) (xy 35.409715 -415.977556)
			(xy 35.427027 -415.924282) (xy 35.452461 -415.874373) (xy 35.48539 -415.829057) (xy 35.525003 -415.789451)
			(xy 35.570324 -415.75653) (xy 35.620238 -415.731104) (xy 35.673514 -415.713801) (xy 35.728842 -415.705045)
			(xy 35.75685 -415.704528) (xy 35.782851 -415.70503) (xy 35.8343 -415.712593) (xy 35.884104 -415.727553)
			(xy 35.931206 -415.74959) (xy 35.974605 -415.778238) (xy 36.013381 -415.812888) (xy 36.030408 -415.832544)
			(xy 36.036446 -415.839144) (xy 36.051945 -415.848048) (xy 36.06956 -415.85108) (xy 36.078414 -415.849816)
			(xy 36.112097 -415.844111) (xy 36.180144 -415.838004) (xy 36.214304 -415.837624) (xy 36.254305 -415.838142)
			(xy 36.333868 -415.846504) (xy 36.41212 -415.863138) (xy 36.488206 -415.88786) (xy 36.561291 -415.9204)
			(xy 36.630574 -415.960401) (xy 36.695296 -416.007425) (xy 36.754748 -416.060956) (xy 36.808279 -416.120409)
			(xy 36.855302 -416.185131) (xy 36.895303 -416.254415) (xy 36.927842 -416.3275) (xy 36.952564 -416.403585)
			(xy 36.969196 -416.481838) (xy 36.977559 -416.561401) (xy 36.977713 -416.573208) (xy 48.430688 -416.573208)
			(xy 48.431253 -416.533209) (xy 48.439614 -416.453649) (xy 48.456245 -416.375398) (xy 48.480965 -416.299315)
			(xy 48.513502 -416.226232) (xy 48.5535 -416.15695) (xy 48.60052 -416.092229) (xy 48.654048 -416.032777)
			(xy 48.713497 -415.979246) (xy 48.778215 -415.932222) (xy 48.847494 -415.892221) (xy 48.920575 -415.85968)
			(xy 48.996657 -415.834956) (xy 49.074907 -415.818321) (xy 49.154467 -415.809955) (xy 49.194466 -415.80943)
			(xy 49.234412 -415.809963) (xy 49.313868 -415.818288) (xy 49.392022 -415.83486) (xy 49.468019 -415.8595)
			(xy 49.541029 -415.891937) (xy 49.610254 -415.931817) (xy 49.674939 -415.978705) (xy 49.705006 -416.00501)
			(xy 49.713821 -416.01207) (xy 49.735423 -416.018545) (xy 49.746662 -416.017456) (xy 49.761048 -416.015347)
			(xy 49.790035 -416.013059) (xy 49.804574 -416.012884) (xy 49.831846 -416.013326) (xy 49.885837 -416.021086)
			(xy 49.938172 -416.036451) (xy 49.987789 -416.059109) (xy 50.033675 -416.088598) (xy 50.074896 -416.124318)
			(xy 50.110614 -416.165541) (xy 50.140101 -416.211429) (xy 50.162756 -416.261046) (xy 50.178119 -416.313383)
			(xy 50.185876 -416.367374) (xy 50.186336 -416.394646) (xy 50.185862 -416.422206) (xy 50.177922 -416.476751)
			(xy 50.162228 -416.52959) (xy 50.139105 -416.579626) (xy 50.109034 -416.625821) (xy 50.072638 -416.667216)
			(xy 50.030673 -416.702953) (xy 49.984008 -416.73229) (xy 49.959006 -416.743896) (xy 49.948984 -416.748983)
			(xy 49.934342 -416.765992) (xy 49.930812 -416.776662) (xy 49.92048 -416.812315) (xy 49.893815 -416.881596)
			(xy 49.860551 -416.947961) (xy 49.84115 -416.979608) (xy 49.835387 -416.989893) (xy 49.833015 -417.013326)
			(xy 49.836578 -417.024566) (xy 49.855827 -417.055342) (xy 49.889057 -417.119886) (xy 49.916008 -417.187294)
			(xy 49.936438 -417.256955) (xy 49.95016 -417.328242) (xy 49.957052 -417.40051) (xy 49.957482 -417.436808)
			(xy 49.957121 -417.469866) (xy 49.951385 -417.535732) (xy 49.939982 -417.600857) (xy 49.931828 -417.632896)
			(xy 49.931839 -417.642681) (xy 49.93837 -417.661106) (xy 49.944528 -417.66871) (xy 49.962373 -417.68976)
			(xy 49.99249 -417.735999) (xy 50.015644 -417.786088) (xy 50.031354 -417.838987) (xy 50.039292 -417.893595)
			(xy 50.039778 -417.921186) (xy 50.039263 -417.948454) (xy 50.031503 -418.002436) (xy 50.016141 -418.054764)
			(xy 49.993487 -418.104373) (xy 49.964004 -418.150253) (xy 49.928292 -418.191471) (xy 49.887077 -418.227186)
			(xy 49.841199 -418.256673) (xy 49.791592 -418.27933) (xy 49.739265 -418.294697) (xy 49.733111 -418.295582)
			(xy 51.383438 -418.295582) (xy 51.383438 -418.295328) (xy 51.383928 -418.268058) (xy 51.391686 -418.214072)
			(xy 51.407049 -418.16174) (xy 51.429703 -418.112126) (xy 51.459188 -418.066243) (xy 51.494902 -418.025022)
			(xy 51.53612 -417.989304) (xy 51.582002 -417.959816) (xy 51.631613 -417.937158) (xy 51.683944 -417.921792)
			(xy 51.73793 -417.91403) (xy 51.7652 -417.913566) (xy 51.793253 -417.91404) (xy 51.848752 -417.922275)
			(xy 51.902445 -417.938552) (xy 51.953174 -417.962521) (xy 51.999843 -417.993664) (xy 52.020978 -418.012118)
			(xy 52.029919 -418.019497) (xy 52.052146 -418.025986) (xy 52.06365 -418.024564) (xy 52.09541 -418.019477)
			(xy 52.159503 -418.014008) (xy 52.191666 -418.013642) (xy 52.231667 -418.01416) (xy 52.311232 -418.022519)
			(xy 52.389488 -418.03915) (xy 52.465576 -418.06387) (xy 52.538663 -418.096408) (xy 52.607948 -418.136408)
			(xy 52.672673 -418.183432) (xy 52.732127 -418.236963) (xy 52.78566 -418.296417) (xy 52.832684 -418.36114)
			(xy 52.872686 -418.430425) (xy 52.905225 -418.503511) (xy 52.929946 -418.579599) (xy 52.946579 -418.657854)
			(xy 52.95494 -418.737419) (xy 52.955444 -418.77742) (xy 52.954883 -418.820286) (xy 52.94528 -418.905479)
			(xy 52.926198 -418.989061) (xy 52.897876 -419.06998) (xy 52.86067 -419.147219) (xy 52.83835 -419.18382)
			(xy 52.832579 -419.194102) (xy 52.830212 -419.217538) (xy 52.833778 -419.228778) (xy 52.854216 -419.261522)
			(xy 52.889154 -419.330354) (xy 52.916973 -419.402358) (xy 52.937389 -419.476801) (xy 52.944268 -419.514782)
			(xy 52.948396 -419.524058) (xy 52.962537 -419.538604) (xy 52.9717 -419.542976) (xy 52.997318 -419.554307)
			(xy 53.045233 -419.583321) (xy 53.088397 -419.619023) (xy 53.125883 -419.660646) (xy 53.156887 -419.707298)
			(xy 53.180744 -419.757979) (xy 53.196943 -419.8116) (xy 53.205137 -419.867013) (xy 53.205634 -419.89502)
			(xy 53.205217 -419.922293) (xy 53.197451 -419.976283) (xy 53.182081 -420.028618) (xy 53.159419 -420.078233)
			(xy 53.129927 -420.124118) (xy 53.094205 -420.165339) (xy 53.05298 -420.201056) (xy 53.007091 -420.230542)
			(xy 52.957473 -420.253198) (xy 52.905136 -420.268562) (xy 52.851145 -420.27632) (xy 52.823872 -420.276782)
			(xy 52.80057 -420.276404) (xy 52.754317 -420.270693) (xy 52.7091 -420.259406) (xy 52.68722 -420.251382)
			(xy 52.677575 -420.248178) (xy 52.657275 -420.248845) (xy 52.64785 -420.252652) (xy 52.614874 -420.276613)
			(xy 52.544705 -420.318102) (xy 52.470513 -420.351875) (xy 52.393143 -420.377546) (xy 52.313478 -420.394823)
			(xy 52.232425 -420.40351) (xy 52.191666 -420.404036) (xy 52.151705 -420.403525) (xy 52.072223 -420.395168)
			(xy 51.994048 -420.378549) (xy 51.91804 -420.35385) (xy 51.845029 -420.321341) (xy 51.775816 -420.281379)
			(xy 51.711159 -420.234401) (xy 51.651767 -420.180923) (xy 51.59829 -420.12153) (xy 51.551313 -420.056872)
			(xy 51.511353 -419.987659) (xy 51.478845 -419.914647) (xy 51.454147 -419.838638) (xy 51.43753 -419.760464)
			(xy 51.429174 -419.680981) (xy 51.42865 -419.64102) (xy 51.42909 -419.604723) (xy 51.435981 -419.532456)
			(xy 51.449703 -419.461169) (xy 51.470132 -419.391508) (xy 51.497083 -419.324102) (xy 51.530312 -419.259559)
			(xy 51.549554 -419.228778) (xy 51.553199 -419.217551) (xy 51.550793 -419.194096) (xy 51.544982 -419.18382)
			(xy 51.522671 -419.147214) (xy 51.485469 -419.069976) (xy 51.45715 -418.989057) (xy 51.43807 -418.905477)
			(xy 51.428468 -418.820285) (xy 51.427888 -418.77742) (xy 51.428339 -418.740446) (xy 51.435503 -418.666846)
			(xy 51.449735 -418.59428) (xy 51.459892 -418.558726) (xy 51.462623 -418.547522) (xy 51.45894 -418.524784)
			(xy 51.45278 -418.515038) (xy 51.436446 -418.490783) (xy 51.410539 -418.438363) (xy 51.39292 -418.382607)
			(xy 51.384 -418.324818) (xy 51.383438 -418.295582) (xy 49.733111 -418.295582) (xy 49.685284 -418.30246)
			(xy 49.658016 -418.302948) (xy 49.628757 -418.302359) (xy 49.570927 -418.29342) (xy 49.515137 -418.275764)
			(xy 49.462693 -418.249804) (xy 49.414823 -418.216148) (xy 49.393348 -418.196268) (xy 49.385811 -418.18975)
			(xy 49.367242 -418.18257) (xy 49.35728 -418.182298) (xy 49.317078 -418.190506) (xy 49.235494 -418.199293)
			(xy 49.194466 -418.199824) (xy 49.154505 -418.199325) (xy 49.075021 -418.190968) (xy 48.996847 -418.174348)
			(xy 48.920837 -418.149649) (xy 48.847826 -418.117139) (xy 48.778612 -418.077176) (xy 48.713955 -418.030198)
			(xy 48.654563 -417.976719) (xy 48.601086 -417.917324) (xy 48.554109 -417.852666) (xy 48.514149 -417.783451)
			(xy 48.481642 -417.710439) (xy 48.456945 -417.634428) (xy 48.440328 -417.556253) (xy 48.431973 -417.476769)
			(xy 48.43145 -417.436808) (xy 48.431884 -417.40051) (xy 48.438776 -417.328243) (xy 48.452499 -417.256957)
			(xy 48.472929 -417.187296) (xy 48.499881 -417.119889) (xy 48.533112 -417.055346) (xy 48.552354 -417.024566)
			(xy 48.55594 -417.013326) (xy 48.553573 -416.989885) (xy 48.547782 -416.979608) (xy 48.525466 -416.943005)
			(xy 48.488265 -416.865766) (xy 48.459947 -416.784846) (xy 48.440868 -416.701265) (xy 48.431267 -416.616074)
			(xy 48.430688 -416.573208) (xy 36.977713 -416.573208) (xy 36.978082 -416.601402) (xy 36.977506 -416.644268)
			(xy 36.967906 -416.72946) (xy 36.948827 -416.813041) (xy 36.920508 -416.893961) (xy 36.883306 -416.9712)
			(xy 36.860988 -417.007802) (xy 36.855229 -417.018088) (xy 36.852857 -417.04152) (xy 36.856416 -417.05276)
			(xy 36.875655 -417.083542) (xy 36.908887 -417.148084) (xy 36.935841 -417.21549) (xy 36.956272 -417.285151)
			(xy 36.969996 -417.356437) (xy 36.976889 -417.428704) (xy 36.97732 -417.465002) (xy 36.976831 -417.503673)
			(xy 36.969006 -417.580618) (xy 36.953437 -417.656377) (xy 36.930284 -417.730172) (xy 36.899784 -417.801246)
			(xy 36.862249 -417.868869) (xy 36.818066 -417.932349) (xy 36.767688 -417.991033) (xy 36.711631 -418.044319)
			(xy 36.650471 -418.09166) (xy 36.584835 -418.132571) (xy 36.515397 -418.166632) (xy 36.44287 -418.193494)
			(xy 36.367997 -418.212879) (xy 36.291547 -418.224591) (xy 36.214304 -418.228509) (xy 36.137061 -418.224591)
			(xy 36.060611 -418.212879) (xy 35.985738 -418.193494) (xy 35.913211 -418.166632) (xy 35.843773 -418.132571)
			(xy 35.778137 -418.09166) (xy 35.716977 -418.044319) (xy 35.66092 -417.991033) (xy 35.610542 -417.932349)
			(xy 35.566359 -417.868869) (xy 35.528824 -417.801246) (xy 35.498324 -417.730172) (xy 35.475171 -417.656377)
			(xy 35.459602 -417.580618) (xy 35.451777 -417.503673) (xy 35.451288 -417.465002) (xy 35.451728 -417.428705)
			(xy 35.45862 -417.356438) (xy 35.472343 -417.285152) (xy 35.492772 -417.215491) (xy 35.519722 -417.148084)
			(xy 35.552951 -417.083541) (xy 35.572192 -417.05276) (xy 35.575777 -417.04152) (xy 35.573409 -417.01808)
			(xy 35.56762 -417.007802) (xy 35.545305 -416.971198) (xy 35.508104 -416.893959) (xy 35.479785 -416.81304)
			(xy 35.460705 -416.729459) (xy 35.451105 -416.644268) (xy 35.450526 -416.601402) (xy 35.450526 -416.600894)
			(xy 35.451159 -416.557049) (xy 35.461255 -416.46994) (xy 35.481245 -416.384558) (xy 35.495484 -416.343084)
			(xy 35.49823 -416.334547) (xy 35.498153 -416.316624) (xy 35.491903 -416.299827) (xy 35.48634 -416.292792)
			(xy 35.470221 -416.273331) (xy 35.443068 -416.230716) (xy 35.422211 -416.184691) (xy 35.40807 -416.136179)
			(xy 35.400929 -416.086155) (xy 35.400488 -416.06089) (xy 8.024114 -416.06089) (xy 8.024114 -421.400986)
			(xy 9.378442 -421.400986) (xy 9.378963 -421.372228) (xy 9.387572 -421.315362) (xy 9.404624 -421.260433)
			(xy 9.42973 -421.208688) (xy 9.462323 -421.161299) (xy 9.501662 -421.119343) (xy 9.546856 -421.08377)
			(xy 9.59688 -421.055387) (xy 9.623552 -421.044624) (xy 9.634657 -421.039609) (xy 9.650835 -421.021434)
			(xy 9.65454 -421.009826) (xy 9.66475 -420.972143) (xy 9.691826 -420.898912) (xy 9.726223 -420.82882)
			(xy 9.746488 -420.79545) (xy 9.751184 -420.787184) (xy 9.754721 -420.768522) (xy 9.7512 -420.749857)
			(xy 9.746488 -420.741602) (xy 9.726214 -420.708236) (xy 9.691806 -420.638149) (xy 9.664739 -420.564913)
			(xy 9.65454 -420.527226) (xy 9.65085 -420.515611) (xy 9.63466 -420.497442) (xy 9.623552 -420.492428)
			(xy 9.596899 -420.481626) (xy 9.546893 -420.453229) (xy 9.501713 -420.417652) (xy 9.462382 -420.375699)
			(xy 9.42979 -420.32832) (xy 9.404675 -420.276588) (xy 9.387606 -420.221673) (xy 9.378969 -420.164819)
			(xy 9.378442 -420.136066) (xy 9.378893 -420.108796) (xy 9.386659 -420.054811) (xy 9.402029 -420.00248)
			(xy 9.42469 -419.95287) (xy 9.454179 -419.906989) (xy 9.489898 -419.865771) (xy 9.531119 -419.830057)
			(xy 9.577003 -419.800571) (xy 9.626616 -419.777916) (xy 9.678948 -419.762551) (xy 9.732934 -419.75479)
			(xy 9.760204 -419.754304) (xy 9.783751 -419.754628) (xy 9.830495 -419.760356) (xy 9.853422 -419.765734)
			(xy 9.865391 -419.768069) (xy 9.889128 -419.762631) (xy 9.898888 -419.75532) (xy 9.928501 -419.730736)
			(xy 9.991813 -419.686968) (xy 10.059207 -419.649789) (xy 10.129998 -419.619578) (xy 10.203469 -419.59664)
			(xy 10.278875 -419.581208) (xy 10.35545 -419.57344) (xy 10.393934 -419.572948) (xy 10.394188 -419.572948)
			(xy 10.43419 -419.573449) (xy 10.513754 -419.581812) (xy 10.592009 -419.598445) (xy 10.668097 -419.623168)
			(xy 10.741183 -419.655708) (xy 10.810468 -419.695709) (xy 10.875192 -419.742734) (xy 10.934646 -419.796267)
			(xy 10.988178 -419.855721) (xy 11.035203 -419.920445) (xy 11.075204 -419.98973) (xy 11.107744 -420.062817)
			(xy 11.132466 -420.138904) (xy 11.149099 -420.217159) (xy 11.157461 -420.296724) (xy 11.157966 -420.336726)
			(xy 11.157373 -420.379416) (xy 11.147807 -420.464259) (xy 11.128843 -420.547507) (xy 11.100716 -420.628122)
			(xy 11.063778 -420.705099) (xy 11.041634 -420.741602) (xy 11.036916 -420.749853) (xy 11.033413 -420.768522)
			(xy 11.036932 -420.787189) (xy 11.041634 -420.79545) (xy 11.0638 -420.83194) (xy 11.100743 -420.908917)
			(xy 11.128866 -420.989535) (xy 11.147818 -421.072788) (xy 11.157364 -421.157635) (xy 11.157966 -421.200326)
			(xy 11.157479 -421.240327) (xy 11.149114 -421.319892) (xy 11.132478 -421.398146) (xy 11.10894 -421.470582)
			(xy 20.786598 -421.470582) (xy 20.787144 -421.441826) (xy 20.795753 -421.384962) (xy 20.812802 -421.330035)
			(xy 20.837906 -421.278291) (xy 20.870495 -421.230903) (xy 20.90983 -421.188946) (xy 20.955019 -421.153371)
			(xy 21.005038 -421.124985) (xy 21.031708 -421.11422) (xy 21.042805 -421.109191) (xy 21.058988 -421.091027)
			(xy 21.062696 -421.079422) (xy 21.072899 -421.041737) (xy 21.099978 -420.968506) (xy 21.134378 -420.898416)
			(xy 21.154644 -420.865046) (xy 21.159339 -420.856781) (xy 21.162871 -420.838119) (xy 21.159353 -420.819454)
			(xy 21.154644 -420.811198) (xy 21.134374 -420.77783) (xy 21.099964 -420.707744) (xy 21.072895 -420.634508)
			(xy 21.062696 -420.596822) (xy 21.058981 -420.585218) (xy 21.042808 -420.567045) (xy 21.031708 -420.562024)
			(xy 21.005044 -420.551249) (xy 20.955039 -420.522846) (xy 20.909861 -420.487264) (xy 20.870531 -420.445307)
			(xy 20.837941 -420.397924) (xy 20.812828 -420.346189) (xy 20.79576 -420.291272) (xy 20.787124 -420.234416)
			(xy 20.786598 -420.205662) (xy 20.787089 -420.178394) (xy 20.794855 -420.124412) (xy 20.810223 -420.072085)
			(xy 20.832881 -420.022478) (xy 20.862367 -419.976599) (xy 20.898081 -419.935383) (xy 20.939297 -419.899668)
			(xy 20.985176 -419.870182) (xy 21.034783 -419.847524) (xy 21.08711 -419.832155) (xy 21.141092 -419.824389)
			(xy 21.16836 -419.8239) (xy 21.191908 -419.824211) (xy 21.238651 -419.829948) (xy 21.261578 -419.83533)
			(xy 21.273551 -419.837637) (xy 21.297283 -419.832218) (xy 21.307044 -419.824916) (xy 21.336635 -419.800305)
			(xy 21.399951 -419.756539) (xy 21.467349 -419.719364) (xy 21.538144 -419.689156) (xy 21.611618 -419.666223)
			(xy 21.687027 -419.650796) (xy 21.763605 -419.643033) (xy 21.80209 -419.642544) (xy 21.802344 -419.642544)
			(xy 21.842346 -419.643004) (xy 21.921911 -419.651371) (xy 22.000166 -419.668009) (xy 22.076253 -419.692735)
			(xy 22.149339 -419.72528) (xy 22.218623 -419.765285) (xy 22.283345 -419.812313) (xy 22.342798 -419.865849)
			(xy 22.396328 -419.925306) (xy 22.443351 -419.990033) (xy 22.48335 -420.05932) (xy 22.515888 -420.132408)
			(xy 22.540608 -420.208498) (xy 22.557239 -420.286754) (xy 22.5656 -420.36632) (xy 22.566122 -420.406322)
			(xy 22.565518 -420.449012) (xy 22.555954 -420.533854) (xy 22.536991 -420.617102) (xy 22.508867 -420.697717)
			(xy 22.471932 -420.774695) (xy 22.44979 -420.811198) (xy 22.445078 -420.819451) (xy 22.441578 -420.838119)
			(xy 22.445092 -420.856784) (xy 22.44979 -420.865046) (xy 22.47195 -420.90154) (xy 22.508894 -420.978515)
			(xy 22.537019 -421.059132) (xy 22.555973 -421.142384) (xy 22.56552 -421.227231) (xy 22.566122 -421.269922)
			(xy 22.565575 -421.309921) (xy 22.557211 -421.389482) (xy 22.540577 -421.467732) (xy 22.515856 -421.543815)
			(xy 22.483317 -421.616898) (xy 22.443317 -421.686179) (xy 22.396295 -421.7509) (xy 22.342766 -421.810351)
			(xy 22.283317 -421.863882) (xy 22.218597 -421.910905) (xy 22.149317 -421.950907) (xy 22.076236 -421.983448)
			(xy 22.000154 -422.008172) (xy 21.921904 -422.024808) (xy 21.842343 -422.033174) (xy 21.802344 -422.0337)
			(xy 21.80209 -422.0337) (xy 21.763607 -422.033176) (xy 21.687032 -422.025413) (xy 21.611626 -422.009988)
			(xy 21.538154 -421.987057) (xy 21.467361 -421.956852) (xy 21.399966 -421.91968) (xy 21.336651 -421.875918)
			(xy 21.307044 -421.851328) (xy 21.297306 -421.843971) (xy 21.27355 -421.838537) (xy 21.261578 -421.840914)
			(xy 21.238652 -421.8463) (xy 21.191908 -421.852028) (xy 21.16836 -421.852344) (xy 21.141089 -421.851913)
			(xy 21.087102 -421.844145) (xy 21.034771 -421.828774) (xy 20.985159 -421.806112) (xy 20.939278 -421.77662)
			(xy 20.89806 -421.740899) (xy 20.862345 -421.699676) (xy 20.832861 -421.65379) (xy 20.810206 -421.604175)
			(xy 20.794843 -421.551841) (xy 20.787083 -421.497853) (xy 20.786598 -421.470582) (xy 11.10894 -421.470582)
			(xy 11.107754 -421.474232) (xy 11.075211 -421.547317) (xy 11.035208 -421.6166) (xy 10.988182 -421.681323)
			(xy 10.934648 -421.740775) (xy 10.875193 -421.794306) (xy 10.810468 -421.841329) (xy 10.741183 -421.881329)
			(xy 10.668096 -421.913867) (xy 10.592009 -421.938588) (xy 10.513754 -421.95522) (xy 10.434189 -421.963581)
			(xy 10.394188 -421.964104) (xy 10.393934 -421.964104) (xy 10.35545 -421.963612) (xy 10.278874 -421.955844)
			(xy 10.203468 -421.940414) (xy 10.129996 -421.917477) (xy 10.059203 -421.887268) (xy 9.991808 -421.850091)
			(xy 9.928494 -421.806324) (xy 9.898888 -421.781732) (xy 9.889133 -421.774402) (xy 9.865391 -421.768952)
			(xy 9.853422 -421.771318) (xy 9.830495 -421.776696) (xy 9.783751 -421.78243) (xy 9.760204 -421.782748)
			(xy 9.732932 -421.782295) (xy 9.678944 -421.774533) (xy 9.626611 -421.759166) (xy 9.576997 -421.736508)
			(xy 9.531112 -421.70702) (xy 9.489892 -421.671301) (xy 9.454174 -421.63008) (xy 9.424687 -421.584195)
			(xy 9.40203 -421.53458) (xy 9.386665 -421.482246) (xy 9.378905 -421.428258) (xy 9.378442 -421.400986)
			(xy 8.024114 -421.400986) (xy 8.024114 -422.130474) (xy 24.494744 -422.130474) (xy 24.495304 -422.087608)
			(xy 24.504908 -422.002415) (xy 24.52399 -421.918833) (xy 24.552312 -421.837914) (xy 24.589518 -421.760675)
			(xy 24.611838 -421.724074) (xy 24.617612 -421.713794) (xy 24.619977 -421.690356) (xy 24.61641 -421.679116)
			(xy 24.597152 -421.648345) (xy 24.563923 -421.5838) (xy 24.536974 -421.516391) (xy 24.516546 -421.446728)
			(xy 24.502825 -421.375441) (xy 24.495935 -421.303172) (xy 24.495506 -421.266874) (xy 24.495982 -421.226912)
			(xy 24.504339 -421.147427) (xy 24.520959 -421.06925) (xy 24.545659 -420.993239) (xy 24.578169 -420.920226)
			(xy 24.618133 -420.851012) (xy 24.665113 -420.786354) (xy 24.718595 -420.726961) (xy 24.777991 -420.673483)
			(xy 24.842652 -420.626507) (xy 24.911869 -420.586548) (xy 24.984884 -420.554042) (xy 25.060897 -420.529346)
			(xy 25.139074 -420.512732) (xy 25.21856 -420.50438) (xy 25.258522 -420.503858) (xy 25.297603 -420.504357)
			(xy 25.375356 -420.512337) (xy 25.451886 -420.528221) (xy 25.526393 -420.551842) (xy 25.598095 -420.582954)
			(xy 25.666243 -420.62123) (xy 25.730123 -420.66627) (xy 25.759918 -420.691564) (xy 25.768627 -420.69597)
			(xy 25.787949 -420.698598) (xy 25.79751 -420.696644) (xy 25.820737 -420.691085) (xy 25.868119 -420.685094)
			(xy 25.891998 -420.684706) (xy 25.892506 -420.684706) (xy 25.919774 -420.685219) (xy 25.973755 -420.69298)
			(xy 26.026082 -420.708345) (xy 26.07569 -420.730999) (xy 26.121438 -420.760398) (xy 58.141108 -420.760398)
			(xy 58.141108 -418.218874) (xy 58.141589 -418.206761) (xy 58.14908 -418.183722) (xy 58.16332 -418.164123)
			(xy 58.182918 -418.149882) (xy 58.205957 -418.14239) (xy 58.21807 -418.141912) (xy 59.15787 -418.141912)
			(xy 59.169989 -418.142385) (xy 59.193042 -418.149866) (xy 59.212655 -418.164105) (xy 59.226908 -418.183708)
			(xy 59.234406 -418.206756) (xy 59.234832 -418.218874) (xy 59.234832 -420.760398) (xy 59.234438 -420.772524)
			(xy 59.226942 -420.795587) (xy 59.212685 -420.815205) (xy 59.193062 -420.829455) (xy 59.169996 -420.836942)
			(xy 59.15787 -420.83736) (xy 58.21807 -420.83736) (xy 58.205954 -420.836914) (xy 58.182909 -420.829418)
			(xy 58.163308 -420.81517) (xy 58.149067 -420.795562) (xy 58.141581 -420.772515) (xy 58.141108 -420.760398)
			(xy 26.121438 -420.760398) (xy 26.12157 -420.760483) (xy 26.162786 -420.796195) (xy 26.198501 -420.83741)
			(xy 26.227988 -420.883287) (xy 26.250646 -420.932893) (xy 26.266014 -420.98522) (xy 26.273779 -421.0392)
			(xy 26.274268 -421.066468) (xy 26.273775 -421.095347) (xy 26.265065 -421.152444) (xy 26.247855 -421.207578)
			(xy 26.222537 -421.259491) (xy 26.189688 -421.306998) (xy 26.150059 -421.349015) (xy 26.104554 -421.384585)
			(xy 26.05421 -421.412894) (xy 26.02738 -421.423592) (xy 26.018391 -421.427514) (xy 26.004016 -421.440827)
			(xy 25.99944 -421.4495) (xy 25.988848 -421.490002) (xy 25.960015 -421.568602) (xy 25.922767 -421.643581)
			(xy 25.900634 -421.679116) (xy 25.896995 -421.690344) (xy 25.899397 -421.713797) (xy 25.905206 -421.724074)
			(xy 25.907079 -421.727138) (xy 26.688369 -421.727138) (xy 26.688369 -421.67226) (xy 26.69623 -421.617948)
			(xy 26.71179 -421.565322) (xy 26.734728 -421.515468) (xy 26.76457 -421.469414) (xy 26.800702 -421.42811)
			(xy 26.842378 -421.392407) (xy 26.888738 -421.363042) (xy 26.938827 -421.340621) (xy 26.99161 -421.325605)
			(xy 27.018742 -421.321484) (xy 27.029854 -421.319379) (xy 27.04883 -421.307125) (xy 27.055318 -421.297862)
			(xy 27.076126 -421.265078) (xy 27.123449 -421.203511) (xy 27.17678 -421.147067) (xy 27.235567 -421.096331)
			(xy 27.299202 -421.051826) (xy 27.367028 -421.014015) (xy 27.438343 -420.983286) (xy 27.51241 -420.959958)
			(xy 27.588463 -420.944272) (xy 27.665715 -420.936391) (xy 27.704542 -420.935912) (xy 27.747231 -420.936549)
			(xy 27.832072 -420.946105) (xy 27.91532 -420.965059) (xy 27.995935 -420.993176) (xy 28.072914 -421.030105)
			(xy 28.109418 -421.052244) (xy 28.117679 -421.05694) (xy 28.136342 -421.060448) (xy 28.155005 -421.05694)
			(xy 28.163266 -421.052244) (xy 28.199751 -421.030069) (xy 28.276729 -420.993129) (xy 28.357349 -420.965007)
			(xy 28.440602 -420.946057) (xy 28.525451 -420.936513) (xy 28.568142 -420.935912) (xy 28.606968 -420.936389)
			(xy 28.684218 -420.944277) (xy 28.760268 -420.959968) (xy 28.834332 -420.9833) (xy 28.905644 -421.014031)
			(xy 28.973467 -421.051844) (xy 29.037101 -421.096348) (xy 29.095887 -421.147083) (xy 29.149218 -421.203525)
			(xy 29.196542 -421.265089) (xy 29.217366 -421.297862) (xy 29.223827 -421.307157) (xy 29.242811 -421.319429)
			(xy 29.253942 -421.321484) (xy 29.281066 -421.32563) (xy 29.333837 -421.340653) (xy 29.383913 -421.363079)
			(xy 29.43026 -421.392446) (xy 29.471924 -421.428148) (xy 29.508045 -421.469449) (xy 29.537879 -421.515498)
			(xy 29.560809 -421.565345) (xy 29.576364 -421.617962) (xy 29.584222 -421.672265) (xy 29.584223 -421.727133)
			(xy 29.576364 -421.781435) (xy 29.56081 -421.834053) (xy 29.53788 -421.8839) (xy 29.508047 -421.929949)
			(xy 29.471926 -421.97125) (xy 29.430263 -422.006953) (xy 29.383915 -422.03632) (xy 29.33384 -422.058746)
			(xy 29.281068 -422.073769) (xy 29.253942 -422.077896) (xy 29.24283 -422.080001) (xy 29.223855 -422.092256)
			(xy 29.217366 -422.101518) (xy 29.196562 -422.134304) (xy 29.149239 -422.195873) (xy 29.095908 -422.252317)
			(xy 29.037121 -422.303054) (xy 28.973485 -422.347558) (xy 28.905659 -422.38537) (xy 28.834343 -422.416098)
			(xy 28.760276 -422.439425) (xy 28.684222 -422.45511) (xy 28.606969 -422.46299) (xy 28.568142 -422.463468)
			(xy 28.525453 -422.462842) (xy 28.440611 -422.453284) (xy 28.357363 -422.434327) (xy 28.276748 -422.406208)
			(xy 28.19977 -422.369277) (xy 28.163266 -422.347136) (xy 28.155005 -422.34244) (xy 28.136342 -422.338932)
			(xy 28.117679 -422.34244) (xy 28.109418 -422.347136) (xy 28.072911 -422.369274) (xy 27.995939 -422.406222)
			(xy 27.915325 -422.43435) (xy 27.832076 -422.45331) (xy 27.747232 -422.462862) (xy 27.704542 -422.463468)
			(xy 27.665717 -422.462966) (xy 27.588469 -422.455077) (xy 27.512421 -422.439386) (xy 27.438358 -422.416056)
			(xy 27.367048 -422.385327) (xy 27.299225 -422.347516) (xy 27.235591 -422.303016) (xy 27.176804 -422.252285)
			(xy 27.123471 -422.195848) (xy 27.076144 -422.134288) (xy 27.055318 -422.101518) (xy 27.048869 -422.092213)
			(xy 27.029876 -422.079948) (xy 27.018742 -422.077896) (xy 26.991608 -422.073794) (xy 26.938824 -422.058779)
			(xy 26.888736 -422.036357) (xy 26.842376 -422.006992) (xy 26.8007 -421.971289) (xy 26.764569 -421.929984)
			(xy 26.734727 -421.883929) (xy 26.711789 -421.834075) (xy 26.69623 -421.781449) (xy 26.688369 -421.727138)
			(xy 25.907079 -421.727138) (xy 25.925889 -421.757909) (xy 25.960911 -421.829061) (xy 25.98838 -421.903457)
			(xy 25.998678 -421.941752) (xy 26.002309 -421.953334) (xy 26.018376 -421.97149) (xy 26.029412 -421.97655)
			(xy 26.056064 -421.987324) (xy 26.106029 -422.015754) (xy 26.151166 -422.051355) (xy 26.190455 -422.09332)
			(xy 26.223008 -422.140702) (xy 26.248089 -422.192429) (xy 26.265131 -422.247331) (xy 26.273748 -422.304169)
			(xy 26.274268 -422.332912) (xy 26.273787 -422.360181) (xy 26.266024 -422.414165) (xy 26.250657 -422.466494)
			(xy 26.228 -422.516104) (xy 26.198513 -422.561984) (xy 26.162798 -422.603202) (xy 26.12158 -422.638917)
			(xy 26.078761 -422.666435) (xy 38.128055 -422.666435) (xy 38.128055 -422.61156) (xy 38.135915 -422.557251)
			(xy 38.151473 -422.504628) (xy 38.174408 -422.454775) (xy 38.204247 -422.408722) (xy 38.240374 -422.367417)
			(xy 38.282045 -422.331713) (xy 38.328401 -422.302346) (xy 38.378485 -422.279921) (xy 38.431264 -422.2649)
			(xy 38.458394 -422.260776) (xy 38.4695 -422.25865) (xy 38.488479 -422.246411) (xy 38.49497 -422.237154)
			(xy 38.515808 -422.20439) (xy 38.563128 -422.142823) (xy 38.616456 -422.086379) (xy 38.675239 -422.035642)
			(xy 38.738871 -421.991137) (xy 38.806693 -421.953323) (xy 38.878005 -421.922592) (xy 38.952068 -421.899261)
			(xy 39.028118 -421.883571) (xy 39.105368 -421.875685) (xy 39.144194 -421.875204) (xy 39.186883 -421.875817)
			(xy 39.271726 -421.885379) (xy 39.354974 -421.904339) (xy 39.435589 -421.932461) (xy 39.512566 -421.969394)
			(xy 39.54907 -421.991536) (xy 39.557331 -421.996232) (xy 39.575994 -421.99974) (xy 39.594657 -421.996232)
			(xy 39.602918 -421.991536) (xy 39.63942 -421.969391) (xy 39.716393 -421.932443) (xy 39.797008 -421.904315)
			(xy 39.880258 -421.885358) (xy 39.965104 -421.875808) (xy 40.007794 -421.875204) (xy 40.046621 -421.875643)
			(xy 40.123872 -421.883536) (xy 40.199923 -421.899233) (xy 40.273987 -421.922569) (xy 40.345299 -421.953305)
			(xy 40.410676 -421.989758) (xy 41.018968 -421.989758) (xy 41.019385 -421.962486) (xy 41.027154 -421.908499)
			(xy 41.042526 -421.856166) (xy 41.065189 -421.806554) (xy 41.094682 -421.760672) (xy 41.130405 -421.719454)
			(xy 41.171629 -421.683739) (xy 41.217517 -421.654255) (xy 41.267134 -421.631601) (xy 41.319469 -421.616238)
			(xy 41.373458 -421.60848) (xy 41.40073 -421.607996) (xy 41.425071 -421.608402) (xy 41.473352 -421.614642)
			(xy 41.496996 -421.620442) (xy 41.508967 -421.622758) (xy 41.532701 -421.617333) (xy 41.542462 -421.610028)
			(xy 41.571991 -421.5858) (xy 41.635035 -421.542669) (xy 41.70207 -421.506047) (xy 41.772426 -421.476299)
			(xy 41.8454 -421.453724) (xy 41.920263 -421.438545) (xy 41.996267 -421.430916) (xy 42.03446 -421.43045)
			(xy 42.034714 -421.43045) (xy 42.074717 -421.430914) (xy 42.154283 -421.439279) (xy 42.23254 -421.455914)
			(xy 42.308629 -421.480639) (xy 42.381717 -421.513182) (xy 42.451002 -421.553186) (xy 42.515727 -421.600214)
			(xy 42.575181 -421.653749) (xy 42.628713 -421.713206) (xy 42.675737 -421.777933) (xy 42.715737 -421.847221)
			(xy 42.748276 -421.92031) (xy 42.772997 -421.996401) (xy 42.789628 -422.074658) (xy 42.797988 -422.154225)
			(xy 42.798492 -422.194228) (xy 42.797896 -422.236918) (xy 42.78833 -422.321761) (xy 42.769366 -422.405009)
			(xy 42.741241 -422.485624) (xy 42.704303 -422.562601) (xy 42.68216 -422.599104) (xy 42.677438 -422.607353)
			(xy 42.673934 -422.626024) (xy 42.677456 -422.644691) (xy 42.68216 -422.652952) (xy 42.704319 -422.689446)
			(xy 42.741264 -422.766422) (xy 42.76939 -422.847038) (xy 42.788344 -422.93029) (xy 42.79789 -423.015137)
			(xy 42.798492 -423.057828) (xy 42.797981 -423.097829) (xy 42.789616 -423.177391) (xy 42.772981 -423.255643)
			(xy 42.748257 -423.331728) (xy 42.715716 -423.404812) (xy 42.675714 -423.474095) (xy 42.62869 -423.538816)
			(xy 42.575158 -423.598268) (xy 42.515705 -423.651799) (xy 42.450983 -423.698822) (xy 42.3817 -423.738822)
			(xy 42.308615 -423.771362) (xy 42.23253 -423.796084) (xy 42.154277 -423.812718) (xy 42.074715 -423.821082)
			(xy 42.034714 -423.821606) (xy 41.998052 -423.821162) (xy 41.925065 -423.814143) (xy 41.853086 -423.800168)
			(xy 41.782775 -423.779366) (xy 41.714779 -423.751927) (xy 41.649722 -423.718104) (xy 41.588203 -423.678207)
			(xy 41.559226 -423.655744) (xy 41.549213 -423.648507) (xy 41.52498 -423.643844) (xy 41.512998 -423.646854)
			(xy 41.486074 -423.65445) (xy 41.430732 -423.662617) (xy 41.402762 -423.66311) (xy 41.375494 -423.662611)
			(xy 41.321513 -423.654845) (xy 41.269187 -423.639478) (xy 41.21958 -423.616821) (xy 41.173701 -423.587335)
			(xy 41.132485 -423.551622) (xy 41.096771 -423.510407) (xy 41.067284 -423.464529) (xy 41.044626 -423.414922)
			(xy 41.029257 -423.362597) (xy 41.02149 -423.308616) (xy 41.021 -423.281348) (xy 41.021529 -423.253075)
			(xy 41.029879 -423.197147) (xy 41.046374 -423.143059) (xy 41.070655 -423.09199) (xy 41.102192 -423.045054)
			(xy 41.140297 -423.003273) (xy 41.18414 -422.96756) (xy 41.232764 -422.938693) (xy 41.258744 -422.927526)
			(xy 41.269839 -422.922217) (xy 41.285757 -422.903513) (xy 41.289224 -422.891712) (xy 41.299209 -422.849656)
			(xy 41.327398 -422.767941) (xy 41.364626 -422.689927) (xy 41.387014 -422.652952) (xy 41.391706 -422.644685)
			(xy 41.395242 -422.626024) (xy 41.391724 -422.60736) (xy 41.387014 -422.599104) (xy 41.366403 -422.565173)
			(xy 41.331531 -422.493846) (xy 41.304245 -422.419287) (xy 41.29405 -422.380918) (xy 41.290432 -422.369218)
			(xy 41.274225 -422.350907) (xy 41.263062 -422.345866) (xy 41.236502 -422.334999) (xy 41.186681 -422.306526)
			(xy 41.141682 -422.270917) (xy 41.102519 -422.228977) (xy 41.070072 -422.181648) (xy 41.045072 -422.129996)
			(xy 41.028084 -422.075185) (xy 41.019488 -422.01845) (xy 41.018968 -421.989758) (xy 40.410676 -421.989758)
			(xy 40.413122 -421.991122) (xy 40.476755 -422.035629) (xy 40.535541 -422.086368) (xy 40.588871 -422.142812)
			(xy 40.636195 -422.20438) (xy 40.657018 -422.237154) (xy 40.663458 -422.246467) (xy 40.682457 -422.25873)
			(xy 40.693594 -422.260776) (xy 40.720717 -422.264935) (xy 40.773493 -422.279952) (xy 40.823574 -422.302374)
			(xy 40.869926 -422.331738) (xy 40.911595 -422.367439) (xy 40.94772 -422.40874) (xy 40.977557 -422.454789)
			(xy 41.000491 -422.504638) (xy 41.016048 -422.557257) (xy 41.023908 -422.611562) (xy 41.023908 -422.666433)
			(xy 41.016049 -422.720738) (xy 41.000493 -422.773358) (xy 40.97756 -422.823206) (xy 40.947723 -422.869256)
			(xy 40.911598 -422.910558) (xy 40.86993 -422.946259) (xy 40.823578 -422.975624) (xy 40.773498 -422.998046)
			(xy 40.720722 -423.013064) (xy 40.693594 -423.017188) (xy 40.68249 -423.019322) (xy 40.663511 -423.031556)
			(xy 40.657018 -423.04081) (xy 40.636175 -423.073571) (xy 40.588857 -423.13514) (xy 40.535531 -423.191585)
			(xy 40.476748 -423.242322) (xy 40.413117 -423.286829) (xy 40.345295 -423.324643) (xy 40.273983 -423.355374)
			(xy 40.19992 -423.378705) (xy 40.12387 -423.394394) (xy 40.04662 -423.402279) (xy 40.007794 -423.40276)
			(xy 39.965104 -423.402158) (xy 39.880261 -423.392595) (xy 39.797013 -423.373632) (xy 39.716398 -423.345508)
			(xy 39.639421 -423.308571) (xy 39.602918 -423.286428) (xy 39.594657 -423.281732) (xy 39.575994 -423.278224)
			(xy 39.557331 -423.281732) (xy 39.54907 -423.286428) (xy 39.512575 -423.308585) (xy 39.435599 -423.345529)
			(xy 39.354983 -423.373654) (xy 39.271731 -423.392609) (xy 39.186885 -423.402157) (xy 39.144194 -423.40276)
			(xy 39.105368 -423.402301) (xy 39.028118 -423.394407) (xy 38.952069 -423.378711) (xy 38.878006 -423.355376)
			(xy 38.806695 -423.324642) (xy 38.738872 -423.286827) (xy 38.675239 -423.242322) (xy 38.616452 -423.191587)
			(xy 38.563121 -423.135146) (xy 38.515794 -423.073583) (xy 38.49497 -423.04081) (xy 38.488544 -423.031486)
			(xy 38.469534 -423.01923) (xy 38.458394 -423.017188) (xy 38.431259 -423.013099) (xy 38.37848 -422.998078)
			(xy 38.328397 -422.975652) (xy 38.282042 -422.946284) (xy 38.240371 -422.91058) (xy 38.204244 -422.869274)
			(xy 38.174406 -422.823221) (xy 38.151471 -422.773368) (xy 38.135914 -422.720744) (xy 38.128055 -422.666435)
			(xy 26.078761 -422.666435) (xy 26.075699 -422.668403) (xy 26.026088 -422.691059) (xy 25.973759 -422.706425)
			(xy 25.919775 -422.714187) (xy 25.892506 -422.714674) (xy 25.868562 -422.714312) (xy 25.821051 -422.708319)
			(xy 25.797764 -422.702736) (xy 25.785797 -422.700376) (xy 25.762055 -422.705828) (xy 25.752298 -422.71315)
			(xy 25.722753 -422.737622) (xy 25.659542 -422.781107) (xy 25.592289 -422.818034) (xy 25.521673 -422.848031)
			(xy 25.448404 -422.870795) (xy 25.373222 -422.886097) (xy 25.296884 -422.893783) (xy 25.258522 -422.894252)
			(xy 25.21852 -422.893752) (xy 25.138954 -422.885391) (xy 25.060699 -422.868759) (xy 24.98461 -422.844038)
			(xy 24.911523 -422.811498) (xy 24.842237 -422.771497) (xy 24.777513 -422.724472) (xy 24.718058 -422.670939)
			(xy 24.664526 -422.611484) (xy 24.617501 -422.546759) (xy 24.5775 -422.477474) (xy 24.544961 -422.404386)
			(xy 24.52024 -422.328297) (xy 24.503608 -422.250042) (xy 24.495248 -422.170476) (xy 24.494744 -422.130474)
			(xy 8.024114 -422.130474) (xy 8.024114 -425.887642) (xy 9.824466 -425.887642) (xy 9.825079 -425.844951)
			(xy 9.834618 -425.760104) (xy 9.853568 -425.676852) (xy 9.881695 -425.596236) (xy 9.918645 -425.519264)
			(xy 9.940798 -425.482766) (xy 9.94548 -425.474494) (xy 9.949021 -425.455836) (xy 9.945507 -425.437173)
			(xy 9.940798 -425.428918) (xy 9.918628 -425.392427) (xy 9.881644 -425.315466) (xy 9.853502 -425.234849)
			(xy 9.834556 -425.151591) (xy 9.825043 -425.066736) (xy 9.824466 -425.024042) (xy 9.824955 -424.985423)
			(xy 9.832769 -424.90858) (xy 9.848317 -424.832922) (xy 9.87144 -424.759225) (xy 9.901899 -424.688246)
			(xy 9.939384 -424.620712) (xy 9.983508 -424.557318) (xy 10.033819 -424.498712) (xy 10.089801 -424.445497)
			(xy 10.15088 -424.398218) (xy 10.216428 -424.357362) (xy 10.285774 -424.323346) (xy 10.358205 -424.296521)
			(xy 10.432978 -424.277161) (xy 10.509326 -424.265465) (xy 10.586466 -424.261553) (xy 10.663606 -424.265465)
			(xy 10.739954 -424.277161) (xy 10.814727 -424.296521) (xy 10.887158 -424.323346) (xy 10.956504 -424.357362)
			(xy 11.022052 -424.398218) (xy 11.083131 -424.445497) (xy 11.139113 -424.498712) (xy 11.189424 -424.557318)
			(xy 11.233548 -424.620712) (xy 11.271033 -424.688246) (xy 11.301492 -424.759225) (xy 11.324615 -424.832922)
			(xy 11.340163 -424.90858) (xy 11.347977 -424.985423) (xy 11.348466 -425.024042) (xy 11.347855 -425.066733)
			(xy 11.338318 -425.151581) (xy 11.319367 -425.234833) (xy 11.29124 -425.315449) (xy 11.254288 -425.392421)
			(xy 11.232134 -425.428918) (xy 11.227388 -425.437158) (xy 11.223876 -425.455836) (xy 11.227415 -425.474509)
			(xy 11.232134 -425.482766) (xy 11.254301 -425.519259) (xy 11.258979 -425.528994) (xy 21.308568 -425.528994)
			(xy 21.309143 -425.500239) (xy 21.317749 -425.443377) (xy 21.334796 -425.388452) (xy 21.359896 -425.336709)
			(xy 21.392481 -425.289322) (xy 21.431811 -425.247364) (xy 21.476996 -425.211788) (xy 21.52701 -425.183399)
			(xy 21.553678 -425.172632) (xy 21.564786 -425.167622) (xy 21.580961 -425.149443) (xy 21.584666 -425.137834)
			(xy 21.594875 -425.100151) (xy 21.621952 -425.02692) (xy 21.656349 -424.956828) (xy 21.676614 -424.923458)
			(xy 21.681302 -424.915189) (xy 21.684839 -424.896529) (xy 21.681323 -424.877866) (xy 21.676614 -424.86961)
			(xy 21.656344 -424.836242) (xy 21.621934 -424.766156) (xy 21.594865 -424.69292) (xy 21.584666 -424.655234)
			(xy 21.58096 -424.643626) (xy 21.564781 -424.625454) (xy 21.553678 -424.620436) (xy 21.527012 -424.609666)
			(xy 21.477008 -424.581262) (xy 21.431831 -424.545677) (xy 21.392503 -424.503719) (xy 21.359914 -424.456336)
			(xy 21.334801 -424.404601) (xy 21.317732 -424.349684) (xy 21.309095 -424.292828) (xy 21.308568 -424.264074)
			(xy 21.308977 -424.236801) (xy 21.316744 -424.182811) (xy 21.332115 -424.130475) (xy 21.354778 -424.08086)
			(xy 21.384271 -424.034975) (xy 21.419994 -423.993754) (xy 21.46122 -423.958037) (xy 21.507109 -423.928551)
			(xy 21.556728 -423.905895) (xy 21.609065 -423.890532) (xy 21.663057 -423.882773) (xy 21.69033 -423.882312)
			(xy 21.713877 -423.882631) (xy 21.760621 -423.888363) (xy 21.783548 -423.893742) (xy 21.795515 -423.896092)
			(xy 21.819254 -423.890644) (xy 21.829014 -423.883328) (xy 21.858618 -423.858733) (xy 21.921932 -423.814965)
			(xy 21.989327 -423.777788) (xy 22.06012 -423.747578) (xy 22.133592 -423.724642) (xy 22.208999 -423.709213)
			(xy 22.285576 -423.701447) (xy 22.32406 -423.700956) (xy 22.324314 -423.700956) (xy 22.364317 -423.701414)
			(xy 22.443884 -423.709779) (xy 22.522141 -423.726415) (xy 22.59823 -423.751139) (xy 22.671318 -423.783683)
			(xy 22.740604 -423.823687) (xy 22.805329 -423.870715) (xy 22.864783 -423.924251) (xy 22.918315 -423.983709)
			(xy 22.965339 -424.048436) (xy 23.005339 -424.117725) (xy 23.037878 -424.190815) (xy 23.062598 -424.266905)
			(xy 23.079229 -424.345163) (xy 23.08085 -424.360594) (xy 58.141108 -424.360594) (xy 58.141108 -421.81907)
			(xy 58.141586 -421.806957) (xy 58.149077 -421.783918) (xy 58.163319 -421.764319) (xy 58.182918 -421.750077)
			(xy 58.205957 -421.742586) (xy 58.21807 -421.742108) (xy 59.15787 -421.742108) (xy 59.16998 -421.742637)
			(xy 59.193017 -421.750112) (xy 59.207184 -421.760396) (xy 60.141104 -421.760396) (xy 60.141104 -419.218872)
			(xy 60.141536 -419.20682) (xy 60.148977 -419.183893) (xy 60.163125 -419.164377) (xy 60.182601 -419.150175)
			(xy 60.205507 -419.14267) (xy 60.217558 -419.142164) (xy 61.157866 -419.142164) (xy 61.169956 -419.142637)
			(xy 61.19296 -419.150087) (xy 61.212542 -419.164271) (xy 61.226793 -419.183805) (xy 61.234322 -419.206783)
			(xy 61.234828 -419.218872) (xy 61.234828 -421.760396) (xy 61.234337 -421.772443) (xy 61.226909 -421.795364)
			(xy 61.212775 -421.814877) (xy 61.193313 -421.829082) (xy 61.170419 -421.836593) (xy 61.158374 -421.837104)
			(xy 60.218066 -421.837104) (xy 60.205979 -421.836623) (xy 60.182985 -421.829162) (xy 60.163409 -421.814977)
			(xy 60.149158 -421.79545) (xy 60.141619 -421.772481) (xy 60.141104 -421.760396) (xy 59.207184 -421.760396)
			(xy 59.212617 -421.76434) (xy 59.22686 -421.783929) (xy 59.234354 -421.80696) (xy 59.234832 -421.81907)
			(xy 59.234832 -424.360594) (xy 62.1411 -424.360594) (xy 62.1411 -421.81907) (xy 62.141585 -421.806958)
			(xy 62.149076 -421.78392) (xy 62.163316 -421.764322) (xy 62.182913 -421.75008) (xy 62.20595 -421.742587)
			(xy 62.218062 -421.742108) (xy 63.157862 -421.742108) (xy 63.16998 -421.742592) (xy 63.193032 -421.75007)
			(xy 63.207258 -421.760396) (xy 68.141088 -421.760396) (xy 68.141088 -419.218872) (xy 68.141536 -419.206822)
			(xy 68.148975 -419.183897) (xy 68.163119 -419.164383) (xy 68.182591 -419.15018) (xy 68.205493 -419.142672)
			(xy 68.217542 -419.142164) (xy 69.15785 -419.142164) (xy 69.169939 -419.14265) (xy 69.192942 -419.150096)
			(xy 69.212525 -419.164277) (xy 69.226777 -419.183808) (xy 69.234306 -419.206784) (xy 69.234812 -419.218872)
			(xy 69.234812 -420.760398) (xy 70.141084 -420.760398) (xy 70.141084 -418.218874) (xy 70.141438 -418.206745)
			(xy 70.148943 -418.183678) (xy 70.16321 -418.164059) (xy 70.182842 -418.14981) (xy 70.205917 -418.142327)
			(xy 70.218046 -418.141912) (xy 71.157846 -418.141912) (xy 71.16996 -418.142372) (xy 71.193001 -418.149869)
			(xy 71.212599 -418.164115) (xy 71.22684 -418.183717) (xy 71.234331 -418.20676) (xy 71.234808 -418.218874)
			(xy 71.234808 -418.3761) (xy 77.278992 -418.3761) (xy 77.279604 -418.333411) (xy 77.289166 -418.248568)
			(xy 77.308127 -418.165321) (xy 77.336249 -418.084705) (xy 77.373182 -418.007728) (xy 77.395324 -417.971224)
			(xy 77.400017 -417.962962) (xy 77.403523 -417.9443) (xy 77.400017 -417.925638) (xy 77.395324 -417.917376)
			(xy 77.373175 -417.880876) (xy 77.336228 -417.803902) (xy 77.308101 -417.723287) (xy 77.289144 -417.640036)
			(xy 77.279595 -417.555191) (xy 77.278992 -417.5125) (xy 77.279467 -417.473829) (xy 77.287277 -417.396883)
			(xy 77.302828 -417.321121) (xy 77.32596 -417.247319) (xy 77.356435 -417.176235) (xy 77.393942 -417.108596)
			(xy 77.438096 -417.045097) (xy 77.488445 -416.986388) (xy 77.544472 -416.933071) (xy 77.605603 -416.885692)
			(xy 77.638148 -416.8648) (xy 77.648062 -416.857872) (xy 77.660522 -416.837179) (xy 77.662024 -416.825176)
			(xy 77.664412 -416.797996) (xy 77.675971 -416.744672) (xy 77.695005 -416.693538) (xy 77.721126 -416.645635)
			(xy 77.753802 -416.60194) (xy 77.792367 -416.563343) (xy 77.836035 -416.53063) (xy 77.883916 -416.504469)
			(xy 77.935034 -416.485391) (xy 77.988347 -416.473787) (xy 78.04277 -416.469893) (xy 78.097193 -416.473787)
			(xy 78.150506 -416.485391) (xy 78.201624 -416.504469) (xy 78.249505 -416.53063) (xy 78.293173 -416.563343)
			(xy 78.331738 -416.60194) (xy 78.364414 -416.645635) (xy 78.390535 -416.693538) (xy 78.409569 -416.744672)
			(xy 78.421128 -416.797996) (xy 78.423516 -416.825176) (xy 78.425031 -416.837171) (xy 78.437499 -416.857848)
			(xy 78.447392 -416.8648) (xy 78.479943 -416.885682) (xy 78.541064 -416.933069) (xy 78.597083 -416.986393)
			(xy 78.647425 -417.045106) (xy 78.691574 -417.108606) (xy 78.729078 -417.176245) (xy 78.759553 -417.247327)
			(xy 78.782686 -417.321127) (xy 78.798242 -417.396886) (xy 78.806059 -417.47383) (xy 78.806548 -417.5125)
			(xy 78.805945 -417.55519) (xy 78.796382 -417.640033) (xy 78.77742 -417.723281) (xy 78.749296 -417.803896)
			(xy 78.712359 -417.880873) (xy 78.690216 -417.917376) (xy 78.68552 -417.925637) (xy 78.682012 -417.9443)
			(xy 78.68552 -417.962963) (xy 78.690216 -417.971224) (xy 78.712369 -418.007722) (xy 78.749315 -418.084696)
			(xy 78.77744 -418.165312) (xy 78.796396 -418.248563) (xy 78.805945 -418.333409) (xy 78.806548 -418.3761)
			(xy 78.806054 -418.41477) (xy 78.798244 -418.491715) (xy 78.782695 -418.567476) (xy 78.759564 -418.641277)
			(xy 78.72909 -418.712361) (xy 78.691585 -418.779999) (xy 78.647434 -418.843498) (xy 78.597088 -418.902208)
			(xy 78.541064 -418.955526) (xy 78.479936 -419.002907) (xy 78.447392 -419.0238) (xy 78.437485 -419.030738)
			(xy 78.425021 -419.051424) (xy 78.423516 -419.063424) (xy 78.421128 -419.090604) (xy 78.409569 -419.143928)
			(xy 78.390535 -419.195062) (xy 78.364414 -419.242965) (xy 78.331738 -419.28666) (xy 78.293173 -419.325257)
			(xy 78.249505 -419.35797) (xy 78.201624 -419.384131) (xy 78.150506 -419.403209) (xy 78.097193 -419.414813)
			(xy 78.04277 -419.418707) (xy 77.988347 -419.414813) (xy 77.935034 -419.403209) (xy 77.883916 -419.384131)
			(xy 77.836035 -419.35797) (xy 77.792367 -419.325257) (xy 77.753802 -419.28666) (xy 77.721126 -419.242965)
			(xy 77.695005 -419.195062) (xy 77.675971 -419.143928) (xy 77.664412 -419.090604) (xy 77.662024 -419.063424)
			(xy 77.660493 -419.051433) (xy 77.648035 -419.030756) (xy 77.638148 -419.0238) (xy 77.605583 -419.00294)
			(xy 77.544464 -418.955548) (xy 77.488447 -418.902221) (xy 77.438107 -418.843505) (xy 77.39396 -418.780001)
			(xy 77.356458 -418.712361) (xy 77.325985 -418.641277) (xy 77.302852 -418.567476) (xy 77.287298 -418.491715)
			(xy 77.279481 -418.414771) (xy 77.278992 -418.3761) (xy 71.234808 -418.3761) (xy 71.234808 -420.760398)
			(xy 71.234287 -420.772508) (xy 71.226806 -420.795543) (xy 71.212575 -420.815141) (xy 71.192986 -420.829384)
			(xy 71.169956 -420.83688) (xy 71.157846 -420.83736) (xy 70.218046 -420.83736) (xy 70.205925 -420.836901)
			(xy 70.182868 -420.829421) (xy 70.163252 -420.81518) (xy 70.148999 -420.795572) (xy 70.141506 -420.772518)
			(xy 70.141084 -420.760398) (xy 69.234812 -420.760398) (xy 69.234812 -421.760396) (xy 69.234337 -421.772445)
			(xy 69.226907 -421.795368) (xy 69.212769 -421.814883) (xy 69.193303 -421.829087) (xy 69.170405 -421.836595)
			(xy 69.158358 -421.837104) (xy 68.21805 -421.837104) (xy 68.205967 -421.836551) (xy 68.182976 -421.829113)
			(xy 68.163399 -421.814947) (xy 68.149145 -421.795434) (xy 68.141604 -421.772476) (xy 68.141088 -421.760396)
			(xy 63.207258 -421.760396) (xy 63.212645 -421.764306) (xy 63.226899 -421.783907) (xy 63.234398 -421.806953)
			(xy 63.234824 -421.81907) (xy 63.234824 -424.360594) (xy 63.234434 -424.37272) (xy 63.226939 -424.395785)
			(xy 63.212681 -424.415404) (xy 63.193057 -424.429654) (xy 63.169988 -424.437139) (xy 63.157862 -424.437556)
			(xy 62.218062 -424.437556) (xy 62.205945 -424.437121) (xy 62.182899 -424.429622) (xy 62.163298 -424.415371)
			(xy 62.149058 -424.395761) (xy 62.141572 -424.372711) (xy 62.1411 -424.360594) (xy 59.234832 -424.360594)
			(xy 59.234434 -424.372719) (xy 59.22694 -424.395783) (xy 59.212684 -424.415401) (xy 59.193062 -424.429651)
			(xy 59.169996 -424.437138) (xy 59.15787 -424.437556) (xy 58.21807 -424.437556) (xy 58.205953 -424.437114)
			(xy 58.182908 -424.429618) (xy 58.163306 -424.415368) (xy 58.149066 -424.39576) (xy 58.14158 -424.372711)
			(xy 58.141108 -424.360594) (xy 23.08085 -424.360594) (xy 23.087588 -424.424731) (xy 23.088092 -424.464734)
			(xy 23.087498 -424.507424) (xy 23.077932 -424.592267) (xy 23.058968 -424.675515) (xy 23.030841 -424.75613)
			(xy 22.993904 -424.833107) (xy 22.97176 -424.86961) (xy 22.967034 -424.877857) (xy 22.963531 -424.896529)
			(xy 22.967055 -424.915197) (xy 22.97176 -424.923458) (xy 22.993922 -424.959951) (xy 23.030866 -425.036926)
			(xy 23.058991 -425.117544) (xy 23.077945 -425.200796) (xy 23.087491 -425.285643) (xy 23.088092 -425.328334)
			(xy 23.087587 -425.368335) (xy 23.079221 -425.447897) (xy 23.062585 -425.52615) (xy 23.037861 -425.602235)
			(xy 23.005319 -425.675319) (xy 22.965317 -425.744601) (xy 22.918292 -425.809322) (xy 22.86476 -425.868774)
			(xy 22.805307 -425.922305) (xy 22.784478 -425.937438) (xy 38.102373 -425.937438) (xy 38.102373 -425.882561)
			(xy 38.110234 -425.82825) (xy 38.125793 -425.775625) (xy 38.148731 -425.725771) (xy 38.178573 -425.679717)
			(xy 38.214704 -425.638413) (xy 38.256379 -425.602711) (xy 38.302738 -425.573346) (xy 38.352826 -425.550925)
			(xy 38.405609 -425.535909) (xy 38.43274 -425.531788) (xy 38.443851 -425.52968) (xy 38.462827 -425.517428)
			(xy 38.469316 -425.508166) (xy 38.490126 -425.475384) (xy 38.537449 -425.413816) (xy 38.59078 -425.357372)
			(xy 38.649566 -425.306636) (xy 38.713201 -425.262132) (xy 38.781027 -425.22432) (xy 38.852342 -425.193591)
			(xy 38.926408 -425.170263) (xy 39.002461 -425.154577) (xy 39.079713 -425.146695) (xy 39.11854 -425.146216)
			(xy 39.16123 -425.146805) (xy 39.246073 -425.156372) (xy 39.329321 -425.175338) (xy 39.409936 -425.203465)
			(xy 39.486913 -425.240404) (xy 39.523416 -425.262548) (xy 39.531677 -425.267244) (xy 39.55034 -425.270752)
			(xy 39.569003 -425.267244) (xy 39.577264 -425.262548) (xy 39.61375 -425.240374) (xy 39.690728 -425.203433)
			(xy 39.771347 -425.175312) (xy 39.854601 -425.156361) (xy 39.939449 -425.146817) (xy 39.98214 -425.146216)
			(xy 40.020966 -425.146692) (xy 40.098216 -425.154581) (xy 40.174266 -425.170272) (xy 40.24833 -425.193604)
			(xy 40.319642 -425.224335) (xy 40.387466 -425.262148) (xy 40.39167 -425.265088) (xy 40.979598 -425.265088)
			(xy 40.980113 -425.23782) (xy 40.987875 -425.18384) (xy 41.00324 -425.131513) (xy 41.025895 -425.081906)
			(xy 41.055378 -425.036027) (xy 41.09109 -424.99481) (xy 41.132304 -424.959095) (xy 41.178181 -424.929608)
			(xy 41.227787 -424.90695) (xy 41.280112 -424.891581) (xy 41.334092 -424.883815) (xy 41.36136 -424.883326)
			(xy 41.385701 -424.883728) (xy 41.433983 -424.889971) (xy 41.457626 -424.895772) (xy 41.469594 -424.898123)
			(xy 41.493334 -424.892677) (xy 41.503092 -424.885358) (xy 41.532614 -424.861121) (xy 41.595659 -424.81799)
			(xy 41.662695 -424.781369) (xy 41.733052 -424.751622) (xy 41.806027 -424.729048) (xy 41.880891 -424.713872)
			(xy 41.956897 -424.706245) (xy 41.99509 -424.70578) (xy 41.995344 -424.70578) (xy 42.035344 -424.706304)
			(xy 42.114905 -424.71467) (xy 42.193156 -424.731306) (xy 42.269239 -424.75603) (xy 42.342322 -424.788571)
			(xy 42.411603 -424.828572) (xy 42.476324 -424.875596) (xy 42.535775 -424.929126) (xy 42.589305 -424.988578)
			(xy 42.636329 -425.053299) (xy 42.67633 -425.12258) (xy 42.708871 -425.195662) (xy 42.733594 -425.271746)
			(xy 42.75023 -425.349997) (xy 42.758596 -425.429558) (xy 42.759122 -425.469558) (xy 42.758488 -425.512247)
			(xy 42.748931 -425.597088) (xy 42.729975 -425.680336) (xy 42.701858 -425.760951) (xy 42.664929 -425.83793)
			(xy 42.64279 -425.874434) (xy 42.63813 -425.882713) (xy 42.634612 -425.901364) (xy 42.638104 -425.92002)
			(xy 42.64279 -425.928282) (xy 42.664923 -425.964791) (xy 42.701872 -426.041763) (xy 42.730003 -426.122376)
			(xy 42.748963 -426.205624) (xy 42.758516 -426.290468) (xy 42.759122 -426.333158) (xy 42.758515 -426.373156)
			(xy 42.750157 -426.452715) (xy 42.733529 -426.530964) (xy 42.708813 -426.607047) (xy 42.67628 -426.680129)
			(xy 42.636286 -426.74941) (xy 42.589269 -426.814131) (xy 42.535744 -426.873583) (xy 42.476298 -426.927114)
			(xy 42.411582 -426.974139) (xy 42.342305 -427.014141) (xy 42.269227 -427.046683) (xy 42.193147 -427.071407)
			(xy 42.1149 -427.088044) (xy 42.035342 -427.09641) (xy 41.995344 -427.096936) (xy 41.958683 -427.096468)
			(xy 41.885697 -427.089452) (xy 41.813718 -427.075481) (xy 41.743407 -427.054682) (xy 41.675411 -427.027247)
			(xy 41.610354 -426.993428) (xy 41.548834 -426.953535) (xy 41.519856 -426.931074) (xy 41.50983 -426.923858)
			(xy 41.485608 -426.919181) (xy 41.473628 -426.922184) (xy 41.446708 -426.929795) (xy 41.391363 -426.937952)
			(xy 41.363392 -426.93844) (xy 41.33612 -426.938006) (xy 41.282131 -426.930242) (xy 41.229796 -426.914874)
			(xy 41.180182 -426.892214) (xy 41.134297 -426.862723) (xy 41.093076 -426.827003) (xy 41.057359 -426.785779)
			(xy 41.027872 -426.739892) (xy 41.005216 -426.690276) (xy 40.989852 -426.63794) (xy 40.982092 -426.58395)
			(xy 40.98163 -426.556678) (xy 40.982166 -426.528404) (xy 40.990513 -426.472476) (xy 41.007005 -426.418388)
			(xy 41.031284 -426.367318) (xy 41.06282 -426.320381) (xy 41.100926 -426.2786) (xy 41.144769 -426.242888)
			(xy 41.193394 -426.214022) (xy 41.219374 -426.202856) (xy 41.230466 -426.197542) (xy 41.246384 -426.178841)
			(xy 41.249854 -426.167042) (xy 41.259843 -426.124987) (xy 41.288031 -426.043271) (xy 41.325256 -425.965257)
			(xy 41.347644 -425.928282) (xy 41.352391 -425.920042) (xy 41.355905 -425.901364) (xy 41.352365 -425.882691)
			(xy 41.347644 -425.874434) (xy 41.327042 -425.840498) (xy 41.292166 -425.769173) (xy 41.264877 -425.694617)
			(xy 41.25468 -425.656248) (xy 41.251034 -425.64456) (xy 41.234847 -425.626243) (xy 41.223692 -425.621196)
			(xy 41.197113 -425.610371) (xy 41.147289 -425.581895) (xy 41.102288 -425.546282) (xy 41.063124 -425.504335)
			(xy 41.030678 -425.457) (xy 41.005683 -425.405341) (xy 40.9887 -425.350524) (xy 40.980113 -425.293782)
			(xy 40.979598 -425.265088) (xy 40.39167 -425.265088) (xy 40.451099 -425.306652) (xy 40.509885 -425.357387)
			(xy 40.563216 -425.413828) (xy 40.61054 -425.475393) (xy 40.631364 -425.508166) (xy 40.637825 -425.517461)
			(xy 40.656809 -425.529733) (xy 40.66794 -425.531788) (xy 40.695065 -425.535926) (xy 40.747837 -425.550949)
			(xy 40.797914 -425.573375) (xy 40.844262 -425.602742) (xy 40.885927 -425.638445) (xy 40.922048 -425.679747)
			(xy 40.951882 -425.725796) (xy 40.974812 -425.775644) (xy 40.990368 -425.828262) (xy 40.998226 -425.882565)
			(xy 40.998226 -425.937434) (xy 40.990368 -425.991737) (xy 40.974813 -426.044355) (xy 40.951882 -426.094202)
			(xy 40.922049 -426.140252) (xy 40.885928 -426.181554) (xy 40.844263 -426.217257) (xy 40.797915 -426.246624)
			(xy 40.747839 -426.26905) (xy 40.695067 -426.284074) (xy 40.66794 -426.2882) (xy 40.656828 -426.290303)
			(xy 40.637852 -426.302559) (xy 40.631364 -426.311822) (xy 40.610563 -426.34461) (xy 40.563239 -426.406178)
			(xy 40.509908 -426.462623) (xy 40.451121 -426.513359) (xy 40.387484 -426.557863) (xy 40.319658 -426.595675)
			(xy 40.248342 -426.626403) (xy 40.174274 -426.649729) (xy 40.09822 -426.665414) (xy 40.020967 -426.673294)
			(xy 39.98214 -426.673772) (xy 39.939451 -426.673146) (xy 39.854609 -426.663588) (xy 39.771361 -426.644631)
			(xy 39.690746 -426.616512) (xy 39.613768 -426.579581) (xy 39.577264 -426.55744) (xy 39.569003 -426.552744)
			(xy 39.55034 -426.549236) (xy 39.531677 -426.552744) (xy 39.523416 -426.55744) (xy 39.48691 -426.579579)
			(xy 39.409938 -426.616526) (xy 39.329324 -426.644655) (xy 39.246075 -426.663614) (xy 39.16123 -426.673167)
			(xy 39.11854 -426.673772) (xy 39.079715 -426.67327) (xy 39.002467 -426.665381) (xy 38.926419 -426.64969)
			(xy 38.852357 -426.626359) (xy 38.781046 -426.59563) (xy 38.713223 -426.55782) (xy 38.64959 -426.51332)
			(xy 38.590802 -426.462589) (xy 38.537469 -426.406152) (xy 38.490142 -426.344592) (xy 38.469316 -426.311822)
			(xy 38.462867 -426.302517) (xy 38.443874 -426.290251) (xy 38.43274 -426.2882) (xy 38.405607 -426.28409)
			(xy 38.352824 -426.269075) (xy 38.302737 -426.246653) (xy 38.256377 -426.217288) (xy 38.214703 -426.181586)
			(xy 38.178572 -426.140281) (xy 38.14873 -426.094227) (xy 38.125793 -426.044374) (xy 38.110233 -425.991749)
			(xy 38.102373 -425.937438) (xy 22.784478 -425.937438) (xy 22.740584 -425.969328) (xy 22.671301 -426.009329)
			(xy 22.598216 -426.041868) (xy 22.522131 -426.06659) (xy 22.443878 -426.083224) (xy 22.364315 -426.091588)
			(xy 22.324314 -426.092112) (xy 22.32406 -426.092112) (xy 22.285576 -426.091603) (xy 22.209001 -426.083838)
			(xy 22.133595 -426.06841) (xy 22.060123 -426.045476) (xy 21.989331 -426.015269) (xy 21.921935 -425.978095)
			(xy 21.85862 -425.934331) (xy 21.829014 -425.90974) (xy 21.819249 -425.902426) (xy 21.795515 -425.896966)
			(xy 21.783548 -425.899326) (xy 21.76062 -425.9047) (xy 21.713877 -425.910436) (xy 21.69033 -425.910756)
			(xy 21.663059 -425.910271) (xy 21.609073 -425.902512) (xy 21.55674 -425.88715) (xy 21.507127 -425.864495)
			(xy 21.461243 -425.83501) (xy 21.420022 -425.799295) (xy 21.384304 -425.758076) (xy 21.354816 -425.712194)
			(xy 21.332159 -425.662582) (xy 21.316793 -425.61025) (xy 21.309031 -425.556265) (xy 21.308568 -425.528994)
			(xy 11.258979 -425.528994) (xy 11.291285 -425.59622) (xy 11.319427 -425.676836) (xy 11.338374 -425.760094)
			(xy 11.347888 -425.844948) (xy 11.348466 -425.887642) (xy 11.347977 -425.926261) (xy 11.340163 -426.003104)
			(xy 11.324615 -426.078762) (xy 11.301492 -426.152459) (xy 11.271033 -426.223438) (xy 11.233548 -426.290972)
			(xy 11.189424 -426.354366) (xy 11.139113 -426.412972) (xy 11.083131 -426.466187) (xy 11.022052 -426.513466)
			(xy 10.956504 -426.554322) (xy 10.887158 -426.588338) (xy 10.814727 -426.615163) (xy 10.739954 -426.634523)
			(xy 10.663606 -426.646219) (xy 10.586466 -426.650132) (xy 10.509326 -426.646219) (xy 10.432978 -426.634523)
			(xy 10.358205 -426.615163) (xy 10.285774 -426.588338) (xy 10.216428 -426.554322) (xy 10.15088 -426.513466)
			(xy 10.089801 -426.466187) (xy 10.033819 -426.412972) (xy 9.983508 -426.354366) (xy 9.939384 -426.290972)
			(xy 9.901899 -426.223438) (xy 9.87144 -426.152459) (xy 9.848317 -426.078762) (xy 9.832769 -426.003104)
			(xy 9.824955 -425.926261) (xy 9.824466 -425.887642) (xy 8.024114 -425.887642) (xy 8.024114 -428.615602)
			(xy 24.748744 -428.615602) (xy 24.749349 -428.572912) (xy 24.758912 -428.488069) (xy 24.777873 -428.404821)
			(xy 24.805997 -428.324206) (xy 24.842933 -428.247229) (xy 24.865076 -428.210726) (xy 24.869771 -428.202464)
			(xy 24.87328 -428.183802) (xy 24.869772 -428.165139) (xy 24.865076 -428.156878) (xy 24.842922 -428.12038)
			(xy 24.805978 -428.043406) (xy 24.777852 -427.96279) (xy 24.758896 -427.879539) (xy 24.749347 -427.794693)
			(xy 24.748744 -427.752002) (xy 24.749229 -427.712) (xy 24.757592 -427.632434) (xy 24.774226 -427.554178)
			(xy 24.798949 -427.47809) (xy 24.83149 -427.405002) (xy 24.871493 -427.335717) (xy 24.918519 -427.270993)
			(xy 24.972053 -427.211538) (xy 25.031508 -427.158006) (xy 25.096234 -427.110982) (xy 25.16552 -427.070981)
			(xy 25.238608 -427.038442) (xy 25.314697 -427.013721) (xy 25.392954 -426.997089) (xy 25.47252 -426.988728)
			(xy 25.512522 -426.988224) (xy 25.556227 -426.988868) (xy 25.643056 -426.998922) (xy 25.68575 -427.00829)
			(xy 25.697261 -427.010415) (xy 25.720035 -427.005104) (xy 25.729438 -426.99813) (xy 25.749907 -426.982092)
			(xy 25.794389 -426.955159) (xy 25.842115 -426.934511) (xy 25.892201 -426.920531) (xy 25.943722 -426.913478)
			(xy 25.969722 -426.91304) (xy 25.996992 -426.913504) (xy 26.050977 -426.921269) (xy 26.103307 -426.936637)
			(xy 26.152917 -426.959296) (xy 26.198798 -426.988784) (xy 26.240015 -427.024502) (xy 26.27573 -427.065721)
			(xy 26.305216 -427.111604) (xy 26.327871 -427.161216) (xy 26.343236 -427.213547) (xy 26.350998 -427.267532)
			(xy 26.351484 -427.294802) (xy 26.351074 -427.320803) (xy 26.344014 -427.372323) (xy 26.330025 -427.422408)
			(xy 26.309366 -427.470131) (xy 26.28242 -427.514606) (xy 26.266394 -427.535086) (xy 26.259441 -427.544493)
			(xy 26.254165 -427.567259) (xy 26.256234 -427.578774) (xy 26.265599 -427.621468) (xy 26.275654 -427.708298)
			(xy 26.2763 -427.752002) (xy 26.27569 -427.794692) (xy 26.266128 -427.879534) (xy 26.247167 -427.962782)
			(xy 26.219044 -428.043397) (xy 26.18211 -428.120375) (xy 26.159968 -428.156878) (xy 26.155267 -428.165138)
			(xy 26.151755 -428.183802) (xy 26.155268 -428.202466) (xy 26.159968 -428.210726) (xy 26.160279 -428.211238)
			(xy 26.306379 -428.211238) (xy 26.306379 -428.156363) (xy 26.314239 -428.102054) (xy 26.329797 -428.049431)
			(xy 26.352733 -427.999579) (xy 26.382573 -427.953527) (xy 26.418702 -427.912224) (xy 26.460374 -427.876522)
			(xy 26.506731 -427.847157) (xy 26.556816 -427.824735) (xy 26.609596 -427.809718) (xy 26.636726 -427.805596)
			(xy 26.647834 -427.803478) (xy 26.666811 -427.791233) (xy 26.673302 -427.781974) (xy 26.694125 -427.7492)
			(xy 26.741446 -427.687632) (xy 26.794775 -427.631188) (xy 26.85356 -427.580451) (xy 26.917194 -427.535946)
			(xy 26.985018 -427.498133) (xy 27.056331 -427.467403) (xy 27.130397 -427.444074) (xy 27.206448 -427.428387)
			(xy 27.2837 -427.420504) (xy 27.322526 -427.420024) (xy 27.365216 -427.420619) (xy 27.450059 -427.430184)
			(xy 27.533307 -427.449148) (xy 27.613922 -427.477275) (xy 27.690899 -427.514212) (xy 27.727402 -427.536356)
			(xy 27.735663 -427.541052) (xy 27.754326 -427.54456) (xy 27.772989 -427.541052) (xy 27.78125 -427.536356)
			(xy 27.817739 -427.514189) (xy 27.894717 -427.477247) (xy 27.975335 -427.449124) (xy 28.058587 -427.430171)
			(xy 28.143435 -427.420626) (xy 28.186126 -427.420024) (xy 28.22495 -427.420555) (xy 28.302197 -427.428441)
			(xy 28.378245 -427.444128) (xy 28.452306 -427.467456) (xy 28.523617 -427.498182) (xy 28.59144 -427.535989)
			(xy 28.655074 -427.580486) (xy 28.713861 -427.631214) (xy 28.767195 -427.687648) (xy 28.814524 -427.749205)
			(xy 28.83535 -427.781974) (xy 28.841816 -427.791265) (xy 28.860796 -427.803538) (xy 28.871926 -427.805596)
			(xy 28.899054 -427.809718) (xy 28.951829 -427.82474) (xy 29.001908 -427.847165) (xy 29.048259 -427.876533)
			(xy 29.089926 -427.912236) (xy 29.12605 -427.953539) (xy 29.130583 -427.960536) (xy 58.141108 -427.960536)
			(xy 58.141108 -425.419012) (xy 58.14157 -425.406962) (xy 58.149001 -425.384035) (xy 58.163141 -425.364518)
			(xy 58.182611 -425.350315) (xy 58.205513 -425.34281) (xy 58.217562 -425.342304) (xy 59.15787 -425.342304)
			(xy 59.169954 -425.342832) (xy 59.192948 -425.350276) (xy 59.212525 -425.364448) (xy 59.226778 -425.383967)
			(xy 59.234317 -425.40693) (xy 59.234832 -425.419012) (xy 59.234832 -427.960536) (xy 59.234372 -427.972585)
			(xy 59.226933 -427.995506) (xy 59.212791 -428.015019) (xy 59.193323 -428.029222) (xy 59.170425 -428.036733)
			(xy 59.158378 -428.037244) (xy 58.21807 -428.037244) (xy 58.205977 -428.036818) (xy 58.182973 -428.029351)
			(xy 58.163392 -428.015154) (xy 58.149143 -427.995612) (xy 58.141615 -427.972627) (xy 58.141108 -427.960536)
			(xy 29.130583 -427.960536) (xy 29.155885 -427.99959) (xy 29.178817 -428.049439) (xy 29.194373 -428.102059)
			(xy 29.202232 -428.156365) (xy 29.202232 -428.211236) (xy 29.194373 -428.265541) (xy 29.178817 -428.318161)
			(xy 29.155885 -428.368011) (xy 29.126049 -428.414061) (xy 29.089926 -428.455364) (xy 29.048259 -428.491068)
			(xy 29.001908 -428.520435) (xy 28.951829 -428.542861) (xy 28.899054 -428.557882) (xy 28.871926 -428.562008)
			(xy 28.860811 -428.564101) (xy 28.841837 -428.576364) (xy 28.83535 -428.58563) (xy 28.814493 -428.618381)
			(xy 28.767175 -428.679949) (xy 28.71385 -428.736394) (xy 28.655069 -428.787131) (xy 28.591439 -428.831638)
			(xy 28.523619 -428.869453) (xy 28.45231 -428.900186) (xy 28.378248 -428.923519) (xy 28.3022 -428.93921)
			(xy 28.224951 -428.947098) (xy 28.186126 -428.94758) (xy 28.143437 -428.94696) (xy 28.058595 -428.9374)
			(xy 27.975347 -428.918442) (xy 27.894732 -428.890321) (xy 27.817754 -428.853389) (xy 27.78125 -428.831248)
			(xy 27.772989 -428.826552) (xy 27.754326 -428.823044) (xy 27.735663 -428.826552) (xy 27.727402 -428.831248)
			(xy 27.6909 -428.853394) (xy 27.613926 -428.89034) (xy 27.533311 -428.918467) (xy 27.450062 -428.937424)
			(xy 27.365216 -428.946975) (xy 27.322526 -428.94758) (xy 27.283699 -428.947133) (xy 27.206448 -428.939241)
			(xy 27.130397 -428.923546) (xy 27.056333 -428.900211) (xy 26.98502 -428.869477) (xy 26.917197 -428.831661)
			(xy 26.853564 -428.787154) (xy 26.794779 -428.736416) (xy 26.741449 -428.679971) (xy 26.694125 -428.618404)
			(xy 26.673302 -428.58563) (xy 26.666857 -428.576321) (xy 26.647861 -428.564057) (xy 26.636726 -428.562008)
			(xy 26.609596 -428.557882) (xy 26.556816 -428.542865) (xy 26.506731 -428.520443) (xy 26.460375 -428.491079)
			(xy 26.418702 -428.455377) (xy 26.382573 -428.414073) (xy 26.352733 -428.368021) (xy 26.329798 -428.318169)
			(xy 26.314239 -428.265547) (xy 26.306379 -428.211238) (xy 26.160279 -428.211238) (xy 26.182117 -428.247226)
			(xy 26.219064 -428.3242) (xy 26.247191 -428.404815) (xy 26.266148 -428.488066) (xy 26.275697 -428.572911)
			(xy 26.2763 -428.615602) (xy 26.275669 -428.659307) (xy 26.265606 -428.746137) (xy 26.256234 -428.78883)
			(xy 26.254138 -428.800343) (xy 26.259432 -428.823111) (xy 26.266394 -428.832518) (xy 26.282426 -428.852991)
			(xy 26.30936 -428.897473) (xy 26.330008 -428.945197) (xy 26.343989 -428.995283) (xy 26.351045 -429.046802)
			(xy 26.351484 -429.072802) (xy 26.350978 -429.10007) (xy 26.343216 -429.154052) (xy 26.327852 -429.20638)
			(xy 26.305197 -429.255989) (xy 26.275713 -429.301869) (xy 26.24 -429.343086) (xy 26.198785 -429.378801)
			(xy 26.152906 -429.408287) (xy 26.103299 -429.430945) (xy 26.050972 -429.446312) (xy 25.99699 -429.454076)
			(xy 25.969722 -429.454564) (xy 25.943721 -429.454145) (xy 25.892201 -429.447088) (xy 25.842116 -429.433101)
			(xy 25.794394 -429.412444) (xy 25.749918 -429.385499) (xy 25.729438 -429.369474) (xy 25.720024 -429.362533)
			(xy 25.697263 -429.357251) (xy 25.68575 -429.359314) (xy 25.643055 -429.368675) (xy 25.556226 -429.378732)
			(xy 25.512522 -429.37938) (xy 25.472521 -429.378852) (xy 25.392957 -429.370491) (xy 25.314703 -429.35386)
			(xy 25.238616 -429.32914) (xy 25.16553 -429.296602) (xy 25.096246 -429.256602) (xy 25.031522 -429.20958)
			(xy 24.972068 -429.156049) (xy 24.918536 -429.096597) (xy 24.871511 -429.031874) (xy 24.831509 -428.962591)
			(xy 24.798969 -428.889506) (xy 24.774246 -428.81342) (xy 24.757612 -428.735167) (xy 24.74925 -428.655603)
			(xy 24.748744 -428.615602) (xy 8.024114 -428.615602) (xy 8.024114 -433.34051) (xy 8.024709 -433.351981)
			(xy 8.034584 -433.372684) (xy 8.052463 -433.387052) (xy 8.063484 -433.390294) (xy 8.063992 -433.390294)
			(xy 8.160766 -433.41163) (xy 8.172161 -433.413576) (xy 8.194629 -433.408236) (xy 8.212553 -433.393674)
			(xy 8.217916 -433.383436) (xy 8.217916 -433.383182) (xy 8.261878 -433.289572) (xy 8.356178 -433.105483)
			(xy 8.457626 -432.925236) (xy 8.566067 -432.749106) (xy 8.681333 -432.577366) (xy 8.803248 -432.41028)
			(xy 8.931623 -432.248105) (xy 9.066262 -432.091091) (xy 9.206956 -431.939479) (xy 9.353489 -431.793502)
			(xy 9.505635 -431.653387) (xy 9.663161 -431.519347) (xy 9.825823 -431.39159) (xy 9.993372 -431.270312)
			(xy 10.16555 -431.1557) (xy 10.342091 -431.04793) (xy 10.522723 -430.947169) (xy 10.70717 -430.853571)
			(xy 10.895145 -430.76728) (xy 11.086362 -430.68843) (xy 11.280524 -430.617141) (xy 11.477333 -430.553524)
			(xy 11.676486 -430.497676) (xy 11.877677 -430.449683) (xy 12.080595 -430.40962) (xy 12.284929 -430.377547)
			(xy 12.490364 -430.353514) (xy 12.696583 -430.337559) (xy 12.90327 -430.329706) (xy 13.110105 -430.329966)
			(xy 13.316771 -430.33834) (xy 13.52295 -430.354814) (xy 13.728323 -430.379364) (xy 13.932576 -430.411951)
			(xy 14.135393 -430.452525) (xy 14.336462 -430.501024) (xy 14.535474 -430.557373) (xy 14.732122 -430.621486)
			(xy 14.926104 -430.693263) (xy 15.117121 -430.772595) (xy 15.304879 -430.859358) (xy 15.489089 -430.95342)
			(xy 15.669468 -431.054636) (xy 15.845737 -431.16285) (xy 16.017625 -431.277895) (xy 16.184868 -431.399594)
			(xy 16.347209 -431.52776) (xy 16.385464 -431.560478) (xy 58.141108 -431.560478) (xy 58.141108 -429.018954)
			(xy 58.141572 -429.00684) (xy 58.149068 -428.9838) (xy 58.163313 -428.964202) (xy 58.182915 -428.949961)
			(xy 58.205956 -428.94247) (xy 58.21807 -428.941992) (xy 59.15787 -428.941992) (xy 59.169978 -428.942537)
			(xy 59.193013 -428.95001) (xy 59.207512 -428.960534) (xy 60.141104 -428.960534) (xy 60.141104 -426.41901)
			(xy 60.14162 -426.406899) (xy 60.1491 -426.383862) (xy 60.163332 -426.364263) (xy 60.182923 -426.35002)
			(xy 60.205956 -426.342527) (xy 60.218066 -426.342048) (xy 61.157866 -426.342048) (xy 61.169988 -426.342489)
			(xy 61.193047 -426.349973) (xy 61.212664 -426.364219) (xy 61.226916 -426.383831) (xy 61.234407 -426.406888)
			(xy 61.234828 -426.41901) (xy 61.234828 -427.960536) (xy 62.1411 -427.960536) (xy 62.1411 -425.419012)
			(xy 62.14157 -425.406962) (xy 62.149 -425.384037) (xy 62.163138 -425.364521) (xy 62.182606 -425.350318)
			(xy 62.205506 -425.342811) (xy 62.217554 -425.342304) (xy 63.157862 -425.342304) (xy 63.169946 -425.342839)
			(xy 63.192939 -425.350281) (xy 63.207185 -425.360592) (xy 64.141096 -425.360592) (xy 64.141096 -422.819068)
			(xy 64.141532 -422.807017) (xy 64.148973 -422.784091) (xy 64.16312 -422.764576) (xy 64.182595 -422.750373)
			(xy 64.2055 -422.742867) (xy 64.21755 -422.74236) (xy 65.157858 -422.74236) (xy 65.169947 -422.742843)
			(xy 65.19295 -422.750291) (xy 65.212532 -422.764473) (xy 65.226784 -422.784004) (xy 65.234313 -422.80698)
			(xy 65.23482 -422.819068) (xy 65.23482 -425.360592) (xy 65.234334 -425.37264) (xy 65.226905 -425.395562)
			(xy 65.212771 -425.415076) (xy 65.193307 -425.42928) (xy 65.170412 -425.43679) (xy 65.158366 -425.4373)
			(xy 64.218058 -425.4373) (xy 64.20597 -425.436829) (xy 64.182975 -425.429366) (xy 64.163399 -425.415179)
			(xy 64.149149 -425.395649) (xy 64.141611 -425.372678) (xy 64.141096 -425.360592) (xy 63.207185 -425.360592)
			(xy 63.212517 -425.364451) (xy 63.22677 -425.383968) (xy 63.234309 -425.40693) (xy 63.234824 -425.419012)
			(xy 63.234824 -427.960536) (xy 63.234371 -427.972586) (xy 63.226932 -427.995508) (xy 63.212788 -428.015022)
			(xy 63.193318 -428.029225) (xy 63.170418 -428.036734) (xy 63.15837 -428.037244) (xy 62.218062 -428.037244)
			(xy 62.205969 -428.036825) (xy 62.182964 -428.029356) (xy 62.163384 -428.015157) (xy 62.149135 -427.995613)
			(xy 62.141607 -427.972628) (xy 62.1411 -427.960536) (xy 61.234828 -427.960536) (xy 61.234828 -428.960534)
			(xy 61.234417 -428.972654) (xy 61.226916 -428.995704) (xy 61.21266 -429.015308) (xy 61.193043 -429.029547)
			(xy 61.169986 -429.037027) (xy 61.157866 -429.037496) (xy 60.218066 -429.037496) (xy 60.205953 -429.037018)
			(xy 60.182914 -429.029525) (xy 60.163316 -429.015284) (xy 60.149075 -428.995686) (xy 60.141582 -428.972647)
			(xy 60.141104 -428.960534) (xy 59.207512 -428.960534) (xy 59.212611 -428.964235) (xy 59.226855 -428.983819)
			(xy 59.234351 -429.006846) (xy 59.234832 -429.018954) (xy 59.234832 -431.560478) (xy 59.234421 -431.572603)
			(xy 59.226931 -431.595666) (xy 59.212678 -431.615284) (xy 59.193059 -431.629535) (xy 59.169995 -431.637022)
			(xy 59.15787 -431.63744) (xy 58.21807 -431.63744) (xy 58.205952 -431.637014) (xy 58.182904 -431.629515)
			(xy 58.163301 -431.615262) (xy 58.149061 -431.59565) (xy 58.141578 -431.572597) (xy 58.141108 -431.560478)
			(xy 16.385464 -431.560478) (xy 16.504397 -431.662196) (xy 16.65619 -431.802694) (xy 16.802355 -431.949039)
			(xy 16.942667 -432.101005) (xy 17.076909 -432.258358) (xy 17.204876 -432.420855) (xy 17.32637 -432.588248)
			(xy 17.441203 -432.760278) (xy 17.5492 -432.936679) (xy 17.650195 -433.117182) (xy 17.74403 -433.301507)
			(xy 17.830563 -433.489372) (xy 17.90966 -433.680486) (xy 17.981199 -433.874556) (xy 18.04507 -434.071283)
			(xy 18.101175 -434.270364) (xy 18.149427 -434.471493) (xy 18.189752 -434.674359) (xy 18.222088 -434.878652)
			(xy 18.246385 -435.084055) (xy 18.252392 -435.16042) (xy 58.141108 -435.16042) (xy 58.141108 -432.618896)
			(xy 58.141557 -432.606845) (xy 58.148992 -432.583918) (xy 58.163135 -432.564401) (xy 58.182608 -432.550199)
			(xy 58.205512 -432.542694) (xy 58.217562 -432.542188) (xy 59.15787 -432.542188) (xy 59.169963 -432.542634)
			(xy 59.19297 -432.550088) (xy 59.207307 -432.560476) (xy 60.141104 -432.560476) (xy 60.141104 -430.018952)
			(xy 60.141519 -430.006899) (xy 60.148965 -429.983971) (xy 60.163118 -429.964456) (xy 60.182597 -429.950254)
			(xy 60.205506 -429.94275) (xy 60.217558 -429.942244) (xy 61.157866 -429.942244) (xy 61.169954 -429.942736)
			(xy 61.192954 -429.950184) (xy 61.212535 -429.964364) (xy 61.226787 -429.983893) (xy 61.234319 -430.006866)
			(xy 61.234828 -430.018952) (xy 61.234828 -431.560478) (xy 62.1411 -431.560478) (xy 62.1411 -429.018954)
			(xy 62.141572 -429.006841) (xy 62.149067 -428.983803) (xy 62.163311 -428.964205) (xy 62.18291 -428.949964)
			(xy 62.205949 -428.942471) (xy 62.218062 -428.941992) (xy 63.157862 -428.941992) (xy 63.16997 -428.942543)
			(xy 63.193004 -428.950015) (xy 63.207499 -428.960534) (xy 64.141096 -428.960534) (xy 64.141096 -426.41901)
			(xy 64.14162 -426.4069) (xy 64.149099 -426.383864) (xy 64.163329 -426.364266) (xy 64.182918 -426.350023)
			(xy 64.205948 -426.342528) (xy 64.218058 -426.342048) (xy 65.157858 -426.342048) (xy 65.16998 -426.342496)
			(xy 65.193039 -426.349978) (xy 65.212655 -426.364222) (xy 65.226908 -426.383833) (xy 65.234399 -426.406889)
			(xy 65.23482 -426.41901) (xy 65.23482 -427.960536) (xy 66.141092 -427.960536) (xy 66.141092 -425.419012)
			(xy 66.14157 -425.406963) (xy 66.148998 -425.384039) (xy 66.163135 -425.364524) (xy 66.182601 -425.35032)
			(xy 66.205499 -425.342812) (xy 66.217546 -425.342304) (xy 67.157854 -425.342304) (xy 67.169938 -425.342846)
			(xy 67.192931 -425.350286) (xy 67.207172 -425.360592) (xy 68.141088 -425.360592) (xy 68.141088 -422.819068)
			(xy 68.141532 -422.807017) (xy 68.148972 -422.784093) (xy 68.163118 -422.764578) (xy 68.18259 -422.750376)
			(xy 68.205493 -422.742868) (xy 68.217542 -422.74236) (xy 69.15785 -422.74236) (xy 69.169939 -422.74285)
			(xy 69.192941 -422.750296) (xy 69.212524 -422.764475) (xy 69.226775 -422.784006) (xy 69.234305 -422.806981)
			(xy 69.234812 -422.819068) (xy 69.234812 -424.360594) (xy 70.141084 -424.360594) (xy 70.141084 -421.81907)
			(xy 70.141435 -421.806941) (xy 70.148941 -421.783873) (xy 70.163209 -421.764255) (xy 70.182842 -421.750006)
			(xy 70.205917 -421.742523) (xy 70.218046 -421.742108) (xy 71.157846 -421.742108) (xy 71.16996 -421.742572)
			(xy 71.193 -421.750068) (xy 71.207209 -421.760396) (xy 72.14108 -421.760396) (xy 72.14108 -419.218872)
			(xy 72.141535 -419.206822) (xy 72.148973 -419.183899) (xy 72.163116 -419.164386) (xy 72.182586 -419.150182)
			(xy 72.205486 -419.142673) (xy 72.217534 -419.142164) (xy 73.157842 -419.142164) (xy 73.169936 -419.142572)
			(xy 73.192942 -419.150043) (xy 73.212524 -419.164244) (xy 73.226772 -419.183791) (xy 73.234298 -419.206779)
			(xy 73.234804 -419.218872) (xy 73.234804 -420.921688) (xy 74.756264 -420.921688) (xy 74.75686 -420.878998)
			(xy 74.766424 -420.794155) (xy 74.785387 -420.710907) (xy 74.813514 -420.630292) (xy 74.850452 -420.553315)
			(xy 74.872596 -420.516812) (xy 74.8773 -420.508555) (xy 74.880805 -420.48989) (xy 74.877293 -420.471226)
			(xy 74.872596 -420.462964) (xy 74.850439 -420.426469) (xy 74.813494 -420.349493) (xy 74.785369 -420.268877)
			(xy 74.766414 -420.185625) (xy 74.756867 -420.100779) (xy 74.756264 -420.058088) (xy 74.756742 -420.019417)
			(xy 74.764554 -419.942472) (xy 74.780105 -419.86671) (xy 74.803237 -419.792909) (xy 74.833712 -419.721825)
			(xy 74.871219 -419.654187) (xy 74.915372 -419.590688) (xy 74.96572 -419.531978) (xy 75.021746 -419.47866)
			(xy 75.082875 -419.431281) (xy 75.11542 -419.410388) (xy 75.125334 -419.403459) (xy 75.137795 -419.382767)
			(xy 75.139296 -419.370764) (xy 75.141684 -419.343584) (xy 75.153243 -419.29026) (xy 75.172277 -419.239126)
			(xy 75.198398 -419.191223) (xy 75.231074 -419.147528) (xy 75.269639 -419.108931) (xy 75.313307 -419.076218)
			(xy 75.361188 -419.050057) (xy 75.412306 -419.030979) (xy 75.465619 -419.019375) (xy 75.520042 -419.015481)
			(xy 75.574465 -419.019375) (xy 75.627778 -419.030979) (xy 75.678896 -419.050057) (xy 75.726777 -419.076218)
			(xy 75.770445 -419.108931) (xy 75.80901 -419.147528) (xy 75.841686 -419.191223) (xy 75.867807 -419.239126)
			(xy 75.886841 -419.29026) (xy 75.8984 -419.343584) (xy 75.900788 -419.370764) (xy 75.902321 -419.382755)
			(xy 75.914778 -419.403432) (xy 75.924664 -419.410388) (xy 75.957226 -419.431252) (xy 76.018345 -419.478644)
			(xy 76.074362 -419.531971) (xy 76.124701 -419.590686) (xy 76.168848 -419.654189) (xy 76.20635 -419.721829)
			(xy 76.236824 -419.792913) (xy 76.259957 -419.866713) (xy 76.275513 -419.942473) (xy 76.283331 -420.019418)
			(xy 76.28382 -420.058088) (xy 76.2832 -420.100777) (xy 76.27364 -420.185619) (xy 76.254681 -420.268867)
			(xy 76.226561 -420.349482) (xy 76.189629 -420.42646) (xy 76.167488 -420.462964) (xy 76.162804 -420.471231)
			(xy 76.159294 -420.48989) (xy 76.162797 -420.50855) (xy 76.167488 -420.516812) (xy 76.189634 -420.553314)
			(xy 76.226581 -420.630287) (xy 76.254708 -420.710902) (xy 76.273666 -420.794152) (xy 76.283216 -420.878998)
			(xy 76.28382 -420.921688) (xy 76.28333 -420.960358) (xy 76.275521 -421.037304) (xy 76.259972 -421.113066)
			(xy 76.236841 -421.186867) (xy 76.206367 -421.257951) (xy 76.168862 -421.325589) (xy 76.12471 -421.389089)
			(xy 76.074363 -421.447798) (xy 76.018338 -421.501116) (xy 75.957208 -421.548495) (xy 75.924664 -421.569388)
			(xy 75.914757 -421.576325) (xy 75.902294 -421.597012) (xy 75.900788 -421.609012) (xy 75.8984 -421.636192)
			(xy 75.886841 -421.689516) (xy 75.867807 -421.74065) (xy 75.841686 -421.788553) (xy 75.80901 -421.832248)
			(xy 75.770445 -421.870845) (xy 75.726777 -421.903558) (xy 75.678896 -421.929719) (xy 75.627778 -421.948797)
			(xy 75.574465 -421.960401) (xy 75.520042 -421.964295) (xy 75.465619 -421.960401) (xy 75.412306 -421.948797)
			(xy 75.361188 -421.929719) (xy 75.313307 -421.903558) (xy 75.269639 -421.870845) (xy 75.231074 -421.832248)
			(xy 75.198398 -421.788553) (xy 75.172277 -421.74065) (xy 75.153243 -421.689516) (xy 75.141684 -421.636192)
			(xy 75.139296 -421.609012) (xy 75.137783 -421.597017) (xy 75.125313 -421.57634) (xy 75.11542 -421.569388)
			(xy 75.082912 -421.548442) (xy 75.02179 -421.501062) (xy 74.96577 -421.447746) (xy 74.915426 -421.389041)
			(xy 74.871274 -421.325547) (xy 74.833766 -421.257917) (xy 74.803285 -421.186841) (xy 74.780145 -421.113048)
			(xy 74.764583 -421.037294) (xy 74.756757 -420.960356) (xy 74.756264 -420.921688) (xy 73.234804 -420.921688)
			(xy 73.234804 -421.760396) (xy 73.234337 -421.772446) (xy 73.226906 -421.79537) (xy 73.212766 -421.814886)
			(xy 73.193298 -421.829089) (xy 73.170398 -421.836596) (xy 73.15835 -421.837104) (xy 72.218042 -421.837104)
			(xy 72.205959 -421.836558) (xy 72.182967 -421.829118) (xy 72.16339 -421.81495) (xy 72.149137 -421.795436)
			(xy 72.141596 -421.772477) (xy 72.14108 -421.760396) (xy 71.207209 -421.760396) (xy 71.212598 -421.764313)
			(xy 71.226839 -421.783915) (xy 71.23433 -421.806956) (xy 71.234808 -421.81907) (xy 71.234808 -424.360594)
			(xy 71.234284 -424.372704) (xy 71.226804 -424.395739) (xy 71.212574 -424.415337) (xy 71.192985 -424.42958)
			(xy 71.169955 -424.437076) (xy 71.157846 -424.437556) (xy 70.218046 -424.437556) (xy 70.205925 -424.437101)
			(xy 70.182867 -424.429621) (xy 70.16325 -424.415378) (xy 70.148998 -424.395769) (xy 70.141505 -424.372715)
			(xy 70.141084 -424.360594) (xy 69.234812 -424.360594) (xy 69.234812 -425.360592) (xy 69.234333 -425.372641)
			(xy 69.226904 -425.395564) (xy 69.212768 -425.415079) (xy 69.193302 -425.429283) (xy 69.170405 -425.436791)
			(xy 69.158358 -425.4373) (xy 68.21805 -425.4373) (xy 68.205967 -425.436751) (xy 68.182975 -425.429313)
			(xy 68.163397 -425.415146) (xy 68.149144 -425.395632) (xy 68.141603 -425.372673) (xy 68.141088 -425.360592)
			(xy 67.207172 -425.360592) (xy 67.212508 -425.364454) (xy 67.226762 -425.38397) (xy 67.234301 -425.40693)
			(xy 67.234816 -425.419012) (xy 67.234816 -427.960536) (xy 67.234371 -427.972587) (xy 67.226931 -427.995511)
			(xy 67.212785 -428.015024) (xy 67.193313 -428.029227) (xy 67.170411 -428.036735) (xy 67.158362 -428.037244)
			(xy 66.218054 -428.037244) (xy 66.20596 -428.036832) (xy 66.182956 -428.02936) (xy 66.163375 -428.01516)
			(xy 66.149127 -427.995615) (xy 66.141599 -427.972628) (xy 66.141092 -427.960536) (xy 65.23482 -427.960536)
			(xy 65.23482 -428.960534) (xy 65.234469 -428.972663) (xy 65.226962 -428.99573) (xy 65.212694 -429.015348)
			(xy 65.193062 -429.029597) (xy 65.169987 -429.03708) (xy 65.157858 -429.037496) (xy 64.218058 -429.037496)
			(xy 64.205945 -429.037025) (xy 64.182906 -429.02953) (xy 64.163308 -429.015287) (xy 64.149066 -428.995687)
			(xy 64.141574 -428.972647) (xy 64.141096 -428.960534) (xy 63.207499 -428.960534) (xy 63.212603 -428.964238)
			(xy 63.226847 -428.98382) (xy 63.234343 -429.006847) (xy 63.234824 -429.018954) (xy 63.234824 -431.560478)
			(xy 63.234421 -431.572603) (xy 63.22693 -431.595668) (xy 63.212675 -431.615287) (xy 63.193054 -431.629537)
			(xy 63.169987 -431.637023) (xy 63.157862 -431.63744) (xy 62.218062 -431.63744) (xy 62.205943 -431.63702)
			(xy 62.182895 -431.62952) (xy 62.163292 -431.615265) (xy 62.149053 -431.595651) (xy 62.14157 -431.572597)
			(xy 62.1411 -431.560478) (xy 61.234828 -431.560478) (xy 61.234828 -432.560476) (xy 61.23432 -432.572522)
			(xy 61.226897 -432.595442) (xy 61.212768 -432.614956) (xy 61.193309 -432.629161) (xy 61.170418 -432.636673)
			(xy 61.158374 -432.637184) (xy 60.218066 -432.637184) (xy 60.205977 -432.636722) (xy 60.182979 -432.629259)
			(xy 60.163402 -432.61507) (xy 60.149152 -432.595538) (xy 60.141616 -432.572563) (xy 60.141104 -432.560476)
			(xy 59.207307 -432.560476) (xy 59.212555 -432.564278) (xy 59.226805 -432.58382) (xy 59.234329 -432.606805)
			(xy 59.234832 -432.618896) (xy 59.234832 -435.16042) (xy 59.234358 -435.172468) (xy 59.226923 -435.195389)
			(xy 59.212785 -435.214901) (xy 59.19332 -435.229105) (xy 59.170424 -435.236616) (xy 59.158378 -435.237128)
			(xy 58.21807 -435.237128) (xy 58.205976 -435.236718) (xy 58.182969 -435.229249) (xy 58.163386 -435.215049)
			(xy 58.149138 -435.195502) (xy 58.141612 -435.172513) (xy 58.141108 -435.16042) (xy 18.252392 -435.16042)
			(xy 18.262606 -435.290254) (xy 18.270726 -435.49693) (xy 18.271236 -435.600348) (xy 18.270733 -435.702967)
			(xy 18.262731 -435.908049) (xy 18.246752 -436.112665) (xy 18.222822 -436.316503) (xy 18.190975 -436.519256)
			(xy 18.15126 -436.720615) (xy 18.103738 -436.920276) (xy 18.04848 -437.117936) (xy 17.98557 -437.313295)
			(xy 17.915104 -437.506057) (xy 17.837188 -437.69593) (xy 17.751941 -437.882627) (xy 17.659491 -438.065864)
			(xy 17.559979 -438.245364) (xy 17.453556 -438.420854) (xy 17.340382 -438.592069) (xy 17.22063 -438.758749)
			(xy 17.219175 -438.760616) (xy 58.141108 -438.760616) (xy 58.141108 -436.219092) (xy 58.141553 -436.207041)
			(xy 58.148989 -436.184113) (xy 58.163134 -436.164597) (xy 58.182607 -436.150394) (xy 58.205512 -436.14289)
			(xy 58.217562 -436.142384) (xy 59.15787 -436.142384) (xy 59.169962 -436.142834) (xy 59.192969 -436.150288)
			(xy 59.206951 -436.160418) (xy 60.141104 -436.160418) (xy 60.141104 -433.618894) (xy 60.141606 -433.606783)
			(xy 60.149091 -433.583745) (xy 60.163326 -433.564146) (xy 60.18292 -433.549904) (xy 60.205955 -433.542411)
			(xy 60.218066 -433.541932) (xy 61.157866 -433.541932) (xy 61.169986 -433.542389) (xy 61.193043 -433.549871)
			(xy 61.212658 -433.564113) (xy 61.226911 -433.583721) (xy 61.234405 -433.606774) (xy 61.234828 -433.618894)
			(xy 61.234828 -435.16042) (xy 62.1411 -435.16042) (xy 62.1411 -432.618896) (xy 62.141557 -432.606846)
			(xy 62.14899 -432.58392) (xy 62.163132 -432.564404) (xy 62.182603 -432.550201) (xy 62.205505 -432.542695)
			(xy 62.217554 -432.542188) (xy 63.157862 -432.542188) (xy 63.169954 -432.542641) (xy 63.192962 -432.550093)
			(xy 63.207295 -432.560476) (xy 64.141096 -432.560476) (xy 64.141096 -430.018952) (xy 64.141519 -430.0069)
			(xy 64.148964 -429.983973) (xy 64.163115 -429.964459) (xy 64.182592 -429.950257) (xy 64.205499 -429.942751)
			(xy 64.21755 -429.942244) (xy 65.157858 -429.942244) (xy 65.169946 -429.942743) (xy 65.192946 -429.950189)
			(xy 65.212527 -429.964367) (xy 65.226779 -429.983894) (xy 65.234311 -430.006866) (xy 65.23482 -430.018952)
			(xy 65.23482 -431.560478) (xy 66.141092 -431.560478) (xy 66.141092 -429.018954) (xy 66.141572 -429.006842)
			(xy 66.149066 -428.983805) (xy 66.163308 -428.964208) (xy 66.182905 -428.949966) (xy 66.205942 -428.942472)
			(xy 66.218054 -428.941992) (xy 67.157854 -428.941992) (xy 67.169962 -428.94255) (xy 67.192996 -428.950019)
			(xy 67.207487 -428.960534) (xy 68.141088 -428.960534) (xy 68.141088 -426.41901) (xy 68.14162 -426.406901)
			(xy 68.149098 -426.383867) (xy 68.163326 -426.364269) (xy 68.182913 -426.350025) (xy 68.205941 -426.342529)
			(xy 68.21805 -426.342048) (xy 69.15785 -426.342048) (xy 69.169968 -426.342469) (xy 69.193015 -426.349972)
			(xy 69.212616 -426.364226) (xy 69.226856 -426.383839) (xy 69.23434 -426.406891) (xy 69.234812 -426.41901)
			(xy 69.234812 -427.960536) (xy 70.141084 -427.960536) (xy 70.141084 -425.419012) (xy 70.14157 -425.406964)
			(xy 70.148997 -425.384042) (xy 70.163132 -425.364527) (xy 70.182596 -425.350323) (xy 70.205492 -425.342813)
			(xy 70.217538 -425.342304) (xy 71.157846 -425.342304) (xy 71.169934 -425.342767) (xy 71.19293 -425.350232)
			(xy 71.207224 -425.360592) (xy 72.14108 -425.360592) (xy 72.14108 -422.819068) (xy 72.141532 -422.807018)
			(xy 72.148971 -422.784095) (xy 72.163115 -422.764581) (xy 72.182585 -422.750378) (xy 72.205486 -422.742869)
			(xy 72.217534 -422.74236) (xy 73.157842 -422.74236) (xy 73.169936 -422.742772) (xy 73.192941 -422.750243)
			(xy 73.212522 -422.764443) (xy 73.226771 -422.783989) (xy 73.234298 -422.806975) (xy 73.234804 -422.819068)
			(xy 73.234804 -424.74007) (xy 109.801162 -424.74007) (xy 109.805142 -424.60708) (xy 109.817069 -424.474566)
			(xy 109.836899 -424.343002) (xy 109.864561 -424.21286) (xy 109.899957 -424.084605) (xy 109.94296 -423.958697)
			(xy 109.993416 -423.835585) (xy 110.051144 -423.715712) (xy 110.115938 -423.599505) (xy 110.187565 -423.487381)
			(xy 110.26577 -423.379742) (xy 110.350272 -423.276972) (xy 110.440769 -423.17944) (xy 110.536936 -423.087494)
			(xy 110.63843 -423.001464) (xy 110.744888 -422.921658) (xy 110.855927 -422.848362) (xy 110.971152 -422.781837)
			(xy 111.090148 -422.722322) (xy 111.212491 -422.67003) (xy 111.337742 -422.625149) (xy 111.465453 -422.587838)
			(xy 111.595167 -422.558231) (xy 111.726419 -422.536436) (xy 111.85874 -422.522528) (xy 111.991656 -422.516559)
			(xy 112.124691 -422.518549) (xy 112.257368 -422.528492) (xy 112.389214 -422.546352) (xy 112.519755 -422.572064)
			(xy 112.648525 -422.605538) (xy 112.775063 -422.646652) (xy 112.898915 -422.695261) (xy 113.019639 -422.751189)
			(xy 113.136802 -422.814237) (xy 113.249985 -422.884179) (xy 113.358782 -422.960765) (xy 113.462804 -423.04372)
			(xy 113.561679 -423.132748) (xy 113.655053 -423.227529) (xy 113.742592 -423.327725) (xy 113.823982 -423.432977)
			(xy 113.898931 -423.542907) (xy 113.967172 -423.657124) (xy 114.028461 -423.775217) (xy 114.082577 -423.896764)
			(xy 114.129327 -424.021329) (xy 114.168544 -424.148468) (xy 114.200088 -424.277724) (xy 114.223844 -424.408636)
			(xy 114.23973 -424.540734) (xy 114.247687 -424.673545) (xy 114.248184 -424.74007) (xy 114.247687 -424.806595)
			(xy 114.23973 -424.939406) (xy 114.223844 -425.071504) (xy 114.200088 -425.202416) (xy 114.168544 -425.331672)
			(xy 114.129327 -425.458811) (xy 114.082577 -425.583376) (xy 114.028461 -425.704923) (xy 113.967172 -425.823016)
			(xy 113.898931 -425.937233) (xy 113.823982 -426.047163) (xy 113.742592 -426.152415) (xy 113.655053 -426.252611)
			(xy 113.561679 -426.347392) (xy 113.462804 -426.43642) (xy 113.358782 -426.519375) (xy 113.249985 -426.595961)
			(xy 113.136802 -426.665903) (xy 113.019639 -426.728951) (xy 112.898915 -426.784879) (xy 112.775063 -426.833488)
			(xy 112.648525 -426.874602) (xy 112.519755 -426.908076) (xy 112.389214 -426.933788) (xy 112.257368 -426.951648)
			(xy 112.124691 -426.961591) (xy 111.991656 -426.963581) (xy 111.85874 -426.957612) (xy 111.726419 -426.943704)
			(xy 111.595167 -426.921909) (xy 111.465453 -426.892302) (xy 111.337742 -426.854991) (xy 111.212491 -426.81011)
			(xy 111.090148 -426.757818) (xy 110.971152 -426.698303) (xy 110.855927 -426.631778) (xy 110.744888 -426.558482)
			(xy 110.63843 -426.478676) (xy 110.536936 -426.392646) (xy 110.440769 -426.3007) (xy 110.350272 -426.203168)
			(xy 110.26577 -426.100398) (xy 110.187565 -425.992759) (xy 110.115938 -425.880635) (xy 110.051144 -425.764428)
			(xy 109.993416 -425.644555) (xy 109.94296 -425.521443) (xy 109.899957 -425.395535) (xy 109.864561 -425.26728)
			(xy 109.836899 -425.137138) (xy 109.817069 -425.005574) (xy 109.805142 -424.87306) (xy 109.801162 -424.74007)
			(xy 73.234804 -424.74007) (xy 73.234804 -425.360592) (xy 73.234333 -425.372641) (xy 73.226903 -425.395566)
			(xy 73.212765 -425.415082) (xy 73.193297 -425.429285) (xy 73.170398 -425.436792) (xy 73.15835 -425.4373)
			(xy 72.218042 -425.4373) (xy 72.205959 -425.436758) (xy 72.182966 -425.429317) (xy 72.163389 -425.415149)
			(xy 72.149135 -425.395633) (xy 72.141595 -425.372673) (xy 72.14108 -425.360592) (xy 71.207224 -425.360592)
			(xy 71.212507 -425.364421) (xy 71.226757 -425.383953) (xy 71.234294 -425.406925) (xy 71.234808 -425.419012)
			(xy 71.234808 -427.960536) (xy 71.234371 -427.972587) (xy 71.226929 -427.995513) (xy 71.212782 -428.015027)
			(xy 71.193308 -428.02923) (xy 71.170404 -428.036736) (xy 71.158354 -428.037244) (xy 70.218046 -428.037244)
			(xy 70.205957 -428.036753) (xy 70.182955 -428.029307) (xy 70.163373 -428.015127) (xy 70.149122 -427.995597)
			(xy 70.141591 -427.972623) (xy 70.141084 -427.960536) (xy 69.234812 -427.960536) (xy 69.234812 -428.960534)
			(xy 69.234318 -428.972645) (xy 69.226828 -428.995681) (xy 69.21259 -429.015278) (xy 69.192996 -429.02952)
			(xy 69.169961 -429.037016) (xy 69.15785 -429.037496) (xy 68.21805 -429.037496) (xy 68.205936 -429.037031)
			(xy 68.182897 -429.029535) (xy 68.163299 -429.015289) (xy 68.149058 -428.995689) (xy 68.141566 -428.972648)
			(xy 68.141088 -428.960534) (xy 67.207487 -428.960534) (xy 67.212594 -428.96424) (xy 67.226839 -428.983822)
			(xy 67.234335 -429.006847) (xy 67.234816 -429.018954) (xy 67.234816 -431.560478) (xy 67.234421 -431.572604)
			(xy 67.226929 -431.59567) (xy 67.212672 -431.61529) (xy 67.193049 -431.62954) (xy 67.16998 -431.637024)
			(xy 67.157854 -431.63744) (xy 66.218054 -431.63744) (xy 66.205935 -431.637027) (xy 66.182886 -431.629525)
			(xy 66.163284 -431.615268) (xy 66.149044 -431.595653) (xy 66.141562 -431.572598) (xy 66.141092 -431.560478)
			(xy 65.23482 -431.560478) (xy 65.23482 -432.560476) (xy 65.23432 -432.572523) (xy 65.226896 -432.595444)
			(xy 65.212765 -432.614959) (xy 65.193304 -432.629164) (xy 65.170411 -432.636674) (xy 65.158366 -432.637184)
			(xy 64.218058 -432.637184) (xy 64.205969 -432.636729) (xy 64.182971 -432.629264) (xy 64.163393 -432.615073)
			(xy 64.149143 -432.595539) (xy 64.141608 -432.572564) (xy 64.141096 -432.560476) (xy 63.207295 -432.560476)
			(xy 63.212547 -432.564281) (xy 63.226797 -432.583821) (xy 63.234321 -432.606805) (xy 63.234824 -432.618896)
			(xy 63.234824 -435.16042) (xy 63.234357 -435.172469) (xy 63.226922 -435.195391) (xy 63.212782 -435.214904)
			(xy 63.193315 -435.229108) (xy 63.170417 -435.236618) (xy 63.15837 -435.237128) (xy 62.218062 -435.237128)
			(xy 62.205967 -435.236724) (xy 62.18296 -435.229253) (xy 62.163378 -435.215052) (xy 62.14913 -435.195503)
			(xy 62.141604 -435.172514) (xy 62.1411 -435.16042) (xy 61.234828 -435.16042) (xy 61.234828 -436.160418)
			(xy 61.234455 -436.172545) (xy 61.226953 -436.19561) (xy 61.212691 -436.215228) (xy 61.193064 -436.229477)
			(xy 61.169993 -436.236963) (xy 61.157866 -436.23738) (xy 60.218066 -436.23738) (xy 60.205951 -436.236918)
			(xy 60.18291 -436.229423) (xy 60.16331 -436.215178) (xy 60.149069 -436.195576) (xy 60.14158 -436.172533)
			(xy 60.141104 -436.160418) (xy 59.206951 -436.160418) (xy 59.212554 -436.164477) (xy 59.226804 -436.184017)
			(xy 59.234329 -436.207001) (xy 59.234832 -436.219092) (xy 59.234832 -438.760616) (xy 59.234354 -438.772664)
			(xy 59.226921 -438.795584) (xy 59.212784 -438.815097) (xy 59.193319 -438.829301) (xy 59.170424 -438.836812)
			(xy 59.158378 -438.837324) (xy 58.21807 -438.837324) (xy 58.205975 -438.836918) (xy 58.182968 -438.829448)
			(xy 58.163385 -438.815247) (xy 58.149137 -438.795699) (xy 58.141612 -438.77271) (xy 58.141108 -438.760616)
			(xy 17.219175 -438.760616) (xy 17.094481 -438.920641) (xy 16.962125 -439.077501) (xy 16.823765 -439.229089)
			(xy 16.679609 -439.375178) (xy 16.529876 -439.515544) (xy 16.374792 -439.649976) (xy 16.236641 -439.760614)
			(xy 60.141104 -439.760614) (xy 60.141104 -437.21909) (xy 60.141603 -437.206978) (xy 60.149089 -437.183941)
			(xy 60.163325 -437.164342) (xy 60.182919 -437.1501) (xy 60.205954 -437.142607) (xy 60.218066 -437.142128)
			(xy 61.157866 -437.142128) (xy 61.169986 -437.142589) (xy 61.193042 -437.15007) (xy 61.212657 -437.164312)
			(xy 61.22691 -437.183918) (xy 61.234404 -437.20697) (xy 61.234828 -437.21909) (xy 61.234828 -438.760616)
			(xy 62.1411 -438.760616) (xy 62.1411 -436.219092) (xy 62.141553 -436.207041) (xy 62.148988 -436.184116)
			(xy 62.163131 -436.1646) (xy 62.182602 -436.150397) (xy 62.205505 -436.142891) (xy 62.217554 -436.142384)
			(xy 63.157862 -436.142384) (xy 63.169954 -436.142841) (xy 63.192961 -436.150292) (xy 63.206938 -436.160418)
			(xy 64.141096 -436.160418) (xy 64.141096 -433.618894) (xy 64.141606 -433.606783) (xy 64.14909 -433.583747)
			(xy 64.163324 -433.564149) (xy 64.182915 -433.549906) (xy 64.205948 -433.542412) (xy 64.218058 -433.541932)
			(xy 65.157858 -433.541932) (xy 65.169978 -433.542396) (xy 65.193034 -433.549876) (xy 65.21265 -433.564116)
			(xy 65.226903 -433.583722) (xy 65.234397 -433.606774) (xy 65.23482 -433.618894) (xy 65.23482 -435.16042)
			(xy 66.141092 -435.16042) (xy 66.141092 -432.618896) (xy 66.141556 -432.606846) (xy 66.148989 -432.583922)
			(xy 66.163129 -432.564407) (xy 66.182598 -432.550204) (xy 66.205498 -432.542696) (xy 66.217546 -432.542188)
			(xy 67.157854 -432.542188) (xy 67.169946 -432.542647) (xy 67.192953 -432.550097) (xy 67.207281 -432.560476)
			(xy 68.141088 -432.560476) (xy 68.141088 -430.018952) (xy 68.141519 -430.0069) (xy 68.148963 -429.983975)
			(xy 68.163112 -429.964461) (xy 68.182587 -429.950259) (xy 68.205492 -429.942752) (xy 68.217542 -429.942244)
			(xy 69.15785 -429.942244) (xy 69.169937 -429.94275) (xy 69.192937 -429.950193) (xy 69.212518 -429.96437)
			(xy 69.22677 -429.983896) (xy 69.234303 -430.006866) (xy 69.234812 -430.018952) (xy 69.234812 -431.560478)
			(xy 70.141084 -431.560478) (xy 70.141084 -429.018954) (xy 70.141473 -429.006832) (xy 70.148979 -428.98378)
			(xy 70.16324 -428.964175) (xy 70.182862 -428.949937) (xy 70.205924 -428.942459) (xy 70.218046 -428.941992)
			(xy 71.157846 -428.941992) (xy 71.169958 -428.942472) (xy 71.192995 -428.949966) (xy 71.207537 -428.960534)
			(xy 72.14108 -428.960534) (xy 72.14108 -426.41901) (xy 72.141469 -426.406884) (xy 72.148964 -426.383818)
			(xy 72.163222 -426.364199) (xy 72.182847 -426.349949) (xy 72.205915 -426.342464) (xy 72.218042 -426.342048)
			(xy 73.157842 -426.342048) (xy 73.16996 -426.342476) (xy 73.193006 -426.349976) (xy 73.212608 -426.364229)
			(xy 73.226848 -426.383841) (xy 73.234332 -426.406892) (xy 73.234804 -426.41901) (xy 73.234804 -427.960536)
			(xy 75.141328 -427.960536) (xy 75.141328 -425.419012) (xy 75.141724 -425.406926) (xy 75.149192 -425.383938)
			(xy 75.163402 -425.364384) (xy 75.18296 -425.350181) (xy 75.20595 -425.34272) (xy 75.218036 -425.342304)
			(xy 76.157836 -425.342304) (xy 76.169914 -425.342734) (xy 76.192884 -425.350207) (xy 76.212422 -425.364413)
			(xy 76.226615 -425.383959) (xy 76.234074 -425.406934) (xy 76.234544 -425.419012) (xy 76.234544 -427.960536)
			(xy 76.234067 -427.972609) (xy 76.226599 -427.995571) (xy 76.212405 -428.015105) (xy 76.192871 -428.029299)
			(xy 76.169909 -428.036767) (xy 76.157836 -428.037244) (xy 75.218036 -428.037244) (xy 75.205967 -428.036706)
			(xy 75.183007 -428.029258) (xy 75.163472 -428.015079) (xy 75.149275 -427.995558) (xy 75.141806 -427.972605)
			(xy 75.141328 -427.960536) (xy 73.234804 -427.960536) (xy 73.234804 -428.960534) (xy 73.234318 -428.972646)
			(xy 73.226827 -428.995683) (xy 73.212587 -429.015281) (xy 73.192991 -429.029523) (xy 73.169954 -429.037017)
			(xy 73.157842 -429.037496) (xy 72.218042 -429.037496) (xy 72.205925 -429.037005) (xy 72.182873 -429.029528)
			(xy 72.16326 -429.015294) (xy 72.149006 -428.995695) (xy 72.141507 -428.972651) (xy 72.14108 -428.960534)
			(xy 71.207537 -428.960534) (xy 71.212592 -428.964208) (xy 71.226834 -428.983805) (xy 71.234328 -429.006842)
			(xy 71.234808 -429.018954) (xy 71.234808 -431.560478) (xy 71.23427 -431.572587) (xy 71.226795 -431.595622)
			(xy 71.212568 -431.61522) (xy 71.192983 -431.629464) (xy 71.169954 -431.636959) (xy 71.157846 -431.63744)
			(xy 70.218046 -431.63744) (xy 70.205923 -431.637001) (xy 70.182862 -431.629518) (xy 70.163245 -431.615273)
			(xy 70.148993 -431.595659) (xy 70.141503 -431.5726) (xy 70.141084 -431.560478) (xy 69.234812 -431.560478)
			(xy 69.234812 -432.560476) (xy 69.23432 -432.572524) (xy 69.226895 -432.595447) (xy 69.212762 -432.614962)
			(xy 69.193299 -432.629166) (xy 69.170404 -432.636675) (xy 69.158358 -432.637184) (xy 68.21805 -432.637184)
			(xy 68.205965 -432.636651) (xy 68.18297 -432.62921) (xy 68.163392 -432.61504) (xy 68.149139 -432.595522)
			(xy 68.141601 -432.572559) (xy 68.141088 -432.560476) (xy 67.207281 -432.560476) (xy 67.212538 -432.564284)
			(xy 67.226788 -432.583823) (xy 67.234313 -432.606806) (xy 67.234816 -432.618896) (xy 67.234816 -435.16042)
			(xy 67.234357 -435.17247) (xy 67.226921 -435.195393) (xy 67.212779 -435.214907) (xy 67.19331 -435.22911)
			(xy 67.17041 -435.236619) (xy 67.158362 -435.237128) (xy 66.218054 -435.237128) (xy 66.205959 -435.236731)
			(xy 66.182951 -435.229258) (xy 66.163369 -435.215054) (xy 66.149122 -435.195505) (xy 66.141596 -435.172514)
			(xy 66.141092 -435.16042) (xy 65.23482 -435.16042) (xy 65.23482 -436.160418) (xy 65.234454 -436.172546)
			(xy 65.226952 -436.195612) (xy 65.212688 -436.215231) (xy 65.193058 -436.22948) (xy 65.169986 -436.236964)
			(xy 65.157858 -436.23738) (xy 64.218058 -436.23738) (xy 64.205943 -436.236924) (xy 64.182901 -436.229428)
			(xy 64.163302 -436.215181) (xy 64.149061 -436.195577) (xy 64.141572 -436.172533) (xy 64.141096 -436.160418)
			(xy 63.206938 -436.160418) (xy 63.212545 -436.16448) (xy 63.226795 -436.184019) (xy 63.234321 -436.207002)
			(xy 63.234824 -436.219092) (xy 63.234824 -438.760616) (xy 63.234354 -438.772665) (xy 63.22692 -438.795587)
			(xy 63.212781 -438.8151) (xy 63.193314 -438.829304) (xy 63.170417 -438.836814) (xy 63.15837 -438.837324)
			(xy 62.218062 -438.837324) (xy 62.205967 -438.836924) (xy 62.182959 -438.829453) (xy 62.163377 -438.81525)
			(xy 62.149129 -438.795701) (xy 62.141604 -438.77271) (xy 62.1411 -438.760616) (xy 61.234828 -438.760616)
			(xy 61.234828 -439.760614) (xy 64.141096 -439.760614) (xy 64.141096 -437.21909) (xy 64.141603 -437.206979)
			(xy 64.149088 -437.183943) (xy 64.163322 -437.164345) (xy 64.182914 -437.150102) (xy 64.205947 -437.142608)
			(xy 64.218058 -437.142128) (xy 65.157858 -437.142128) (xy 65.169978 -437.142595) (xy 65.193033 -437.150075)
			(xy 65.212648 -437.164315) (xy 65.226901 -437.18392) (xy 65.234396 -437.206971) (xy 65.23482 -437.21909)
			(xy 65.23482 -438.760616) (xy 66.141092 -438.760616) (xy 66.141092 -436.219092) (xy 66.141553 -436.207042)
			(xy 66.148987 -436.184118) (xy 66.163128 -436.164603) (xy 66.182597 -436.1504) (xy 66.205498 -436.142892)
			(xy 66.217546 -436.142384) (xy 67.157854 -436.142384) (xy 67.169946 -436.142847) (xy 67.192952 -436.150297)
			(xy 67.206925 -436.160418) (xy 68.141088 -436.160418) (xy 68.141088 -433.618894) (xy 68.141606 -433.606784)
			(xy 68.149089 -433.583749) (xy 68.163321 -433.564152) (xy 68.18291 -433.549909) (xy 68.20594 -433.542413)
			(xy 68.21805 -433.541932) (xy 69.15785 -433.541932) (xy 69.169967 -433.542369) (xy 69.19301 -433.549869)
			(xy 69.212611 -433.564121) (xy 69.226851 -433.583729) (xy 69.234338 -433.606777) (xy 69.234812 -433.618894)
			(xy 69.234812 -435.16042) (xy 70.141084 -435.16042) (xy 70.141084 -432.618896) (xy 70.141556 -432.606847)
			(xy 70.148988 -432.583924) (xy 70.163126 -432.56441) (xy 70.182593 -432.550206) (xy 70.205491 -432.542697)
			(xy 70.217538 -432.542188) (xy 71.157846 -432.542188) (xy 71.169943 -432.542569) (xy 71.192953 -432.550044)
			(xy 71.207333 -432.560476) (xy 72.14108 -432.560476) (xy 72.14108 -430.018952) (xy 72.141519 -430.006901)
			(xy 72.148962 -429.983977) (xy 72.163109 -429.964464) (xy 72.182582 -429.950262) (xy 72.205485 -429.942753)
			(xy 72.217534 -429.942244) (xy 73.157842 -429.942244) (xy 73.169934 -429.942672) (xy 73.192937 -429.95014)
			(xy 73.212516 -429.964337) (xy 73.226765 -429.983879) (xy 73.234296 -430.006861) (xy 73.234804 -430.018952)
			(xy 73.234804 -431.560478) (xy 75.141328 -431.560478) (xy 75.141328 -429.018954) (xy 75.141768 -429.006863)
			(xy 75.149236 -428.983863) (xy 75.16343 -428.964285) (xy 75.182968 -428.950036) (xy 75.205947 -428.942503)
			(xy 75.218036 -428.941992) (xy 76.157836 -428.941992) (xy 76.169946 -428.942386) (xy 76.192973 -428.949894)
			(xy 76.207568 -428.960534) (xy 77.141324 -428.960534) (xy 77.141324 -426.41901) (xy 77.141816 -426.406923)
			(xy 77.149268 -426.383925) (xy 77.163449 -426.364346) (xy 77.182976 -426.350095) (xy 77.205946 -426.34256)
			(xy 77.218032 -426.342048) (xy 78.157832 -426.342048) (xy 78.169937 -426.342488) (xy 78.192957 -426.34999)
			(xy 78.212525 -426.364248) (xy 78.22672 -426.38386) (xy 78.234149 -426.406903) (xy 78.23454 -426.41901)
			(xy 78.23454 -427.960536) (xy 79.14132 -427.960536) (xy 79.14132 -425.419012) (xy 79.141724 -425.406927)
			(xy 79.149191 -425.38394) (xy 79.163399 -425.364387) (xy 79.182954 -425.350184) (xy 79.205943 -425.342721)
			(xy 79.218028 -425.342304) (xy 80.157828 -425.342304) (xy 80.169905 -425.34274) (xy 80.192875 -425.350212)
			(xy 80.212413 -425.364415) (xy 80.226606 -425.38396) (xy 80.234066 -425.406935) (xy 80.234536 -425.419012)
			(xy 80.234536 -427.960536) (xy 80.234067 -427.97261) (xy 80.226598 -427.995573) (xy 80.212402 -428.015107)
			(xy 80.192866 -428.029302) (xy 80.169902 -428.036768) (xy 80.157828 -428.037244) (xy 79.218028 -428.037244)
			(xy 79.205958 -428.036713) (xy 79.182998 -428.029262) (xy 79.163464 -428.015082) (xy 79.149267 -427.995559)
			(xy 79.141797 -427.972605) (xy 79.14132 -427.960536) (xy 78.23454 -427.960536) (xy 78.23454 -428.960534)
			(xy 78.234121 -428.972627) (xy 78.226653 -428.995632) (xy 78.212454 -429.015214) (xy 78.19291 -429.029462)
			(xy 78.169924 -429.03699) (xy 78.157832 -429.037496) (xy 77.218032 -429.037496) (xy 77.205924 -429.037056)
			(xy 77.182898 -429.029565) (xy 77.163324 -429.01531) (xy 77.149128 -428.995692) (xy 77.141707 -428.972643)
			(xy 77.141324 -428.960534) (xy 76.207568 -428.960534) (xy 76.212545 -428.964162) (xy 76.226738 -428.983787)
			(xy 76.23416 -429.006843) (xy 76.234544 -429.018954) (xy 76.234544 -431.560478) (xy 76.234074 -431.572568)
			(xy 76.226621 -431.595571) (xy 76.212436 -431.615152) (xy 76.192902 -431.629403) (xy 76.169924 -431.636933)
			(xy 76.157836 -431.63744) (xy 75.218036 -431.63744) (xy 75.205933 -431.636953) (xy 75.182914 -431.629469)
			(xy 75.163344 -431.615224) (xy 75.149146 -431.595619) (xy 75.141718 -431.572582) (xy 75.141328 -431.560478)
			(xy 73.234804 -431.560478) (xy 73.234804 -432.560476) (xy 73.23432 -432.572525) (xy 73.226894 -432.595449)
			(xy 73.212759 -432.614964) (xy 73.193294 -432.629169) (xy 73.170397 -432.636676) (xy 73.15835 -432.637184)
			(xy 72.218042 -432.637184) (xy 72.205957 -432.636657) (xy 72.182962 -432.629215) (xy 72.163383 -432.615043)
			(xy 72.14913 -432.595523) (xy 72.141593 -432.572559) (xy 72.14108 -432.560476) (xy 71.207333 -432.560476)
			(xy 71.212536 -432.564251) (xy 71.226784 -432.583805) (xy 71.234306 -432.6068) (xy 71.234808 -432.618896)
			(xy 71.234808 -435.16042) (xy 71.234357 -435.17247) (xy 71.22692 -435.195395) (xy 71.212776 -435.21491)
			(xy 71.193305 -435.229113) (xy 71.170403 -435.23662) (xy 71.158354 -435.237128) (xy 70.218046 -435.237128)
			(xy 70.205956 -435.236653) (xy 70.182951 -435.229205) (xy 70.163368 -435.215022) (xy 70.149117 -435.195487)
			(xy 70.141589 -435.172509) (xy 70.141084 -435.16042) (xy 69.234812 -435.16042) (xy 69.234812 -436.160418)
			(xy 69.234305 -436.172529) (xy 69.226818 -436.195564) (xy 69.212584 -436.215161) (xy 69.192993 -436.229404)
			(xy 69.16996 -436.2369) (xy 69.15785 -436.23738) (xy 68.21805 -436.23738) (xy 68.205935 -436.236931)
			(xy 68.182893 -436.229432) (xy 68.163293 -436.215184) (xy 68.149053 -436.195578) (xy 68.141564 -436.172534)
			(xy 68.141088 -436.160418) (xy 67.206925 -436.160418) (xy 67.212537 -436.164483) (xy 67.226787 -436.18402)
			(xy 67.234312 -436.207002) (xy 67.234816 -436.219092) (xy 67.234816 -438.760616) (xy 67.234354 -438.772665)
			(xy 67.226919 -438.795589) (xy 67.212778 -438.815103) (xy 67.193309 -438.829306) (xy 67.17041 -438.836815)
			(xy 67.158362 -438.837324) (xy 66.218054 -438.837324) (xy 66.205958 -438.836931) (xy 66.18295 -438.829457)
			(xy 66.163368 -438.815253) (xy 66.14912 -438.795702) (xy 66.141596 -438.77271) (xy 66.141092 -438.760616)
			(xy 65.23482 -438.760616) (xy 65.23482 -439.760614) (xy 68.141088 -439.760614) (xy 68.141088 -437.21909)
			(xy 68.141603 -437.20698) (xy 68.149087 -437.183945) (xy 68.163319 -437.164348) (xy 68.182909 -437.150105)
			(xy 68.20594 -437.142609) (xy 68.21805 -437.142128) (xy 69.15785 -437.142128) (xy 69.169966 -437.142569)
			(xy 69.193009 -437.150069) (xy 69.212609 -437.164319) (xy 69.22685 -437.183927) (xy 69.234337 -437.206974)
			(xy 69.234812 -437.21909) (xy 69.234812 -438.760616) (xy 70.141084 -438.760616) (xy 70.141084 -436.219092)
			(xy 70.141553 -436.207043) (xy 70.148986 -436.18412) (xy 70.163125 -436.164606) (xy 70.182592 -436.150402)
			(xy 70.205491 -436.142893) (xy 70.217538 -436.142384) (xy 71.157846 -436.142384) (xy 71.169942 -436.142769)
			(xy 71.192952 -436.150244) (xy 71.206977 -436.160418) (xy 72.14108 -436.160418) (xy 72.14108 -433.618894)
			(xy 72.141456 -433.606767) (xy 72.148955 -433.583701) (xy 72.163216 -433.564082) (xy 72.182844 -433.549833)
			(xy 72.205915 -433.542348) (xy 72.218042 -433.541932) (xy 73.157842 -433.541932) (xy 73.169958 -433.542376)
			(xy 73.193002 -433.549874) (xy 73.212602 -433.564123) (xy 73.226843 -433.583731) (xy 73.23433 -433.606778)
			(xy 73.234804 -433.618894) (xy 73.234804 -435.16042) (xy 75.141328 -435.16042) (xy 75.141328 -432.618896)
			(xy 75.14171 -432.606809) (xy 75.149183 -432.58382) (xy 75.163396 -432.564267) (xy 75.182956 -432.550064)
			(xy 75.205949 -432.542603) (xy 75.218036 -432.542188) (xy 76.157836 -432.542188) (xy 76.169912 -432.542633)
			(xy 76.19288 -432.550105) (xy 76.207146 -432.560476) (xy 77.141324 -432.560476) (xy 77.141324 -430.018952)
			(xy 77.141724 -430.006872) (xy 77.149203 -429.983898) (xy 77.163415 -429.964358) (xy 77.182969 -429.950167)
			(xy 77.205951 -429.942711) (xy 77.218032 -429.942244) (xy 78.157832 -429.942244) (xy 78.169903 -429.942736)
			(xy 78.192864 -429.950201) (xy 78.212396 -429.964393) (xy 78.226591 -429.983922) (xy 78.234062 -430.006881)
			(xy 78.23454 -430.018952) (xy 78.23454 -431.560478) (xy 79.14132 -431.560478) (xy 79.14132 -429.018954)
			(xy 79.141768 -429.006864) (xy 79.149235 -428.983865) (xy 79.163427 -428.964288) (xy 79.182963 -428.950038)
			(xy 79.205939 -428.942504) (xy 79.218028 -428.941992) (xy 80.157828 -428.941992) (xy 80.169938 -428.942392)
			(xy 80.192964 -428.949899) (xy 80.207555 -428.960534) (xy 81.141316 -428.960534) (xy 81.141316 -426.41901)
			(xy 81.141816 -426.406923) (xy 81.149267 -426.383927) (xy 81.163446 -426.364349) (xy 81.182971 -426.350097)
			(xy 81.205939 -426.342561) (xy 81.218024 -426.342048) (xy 82.157824 -426.342048) (xy 82.169929 -426.342495)
			(xy 82.192948 -426.349995) (xy 82.212516 -426.36425) (xy 82.226712 -426.383862) (xy 82.234141 -426.406904)
			(xy 82.234532 -426.41901) (xy 82.234532 -427.960536) (xy 83.141312 -427.960536) (xy 83.141312 -425.419012)
			(xy 83.141723 -425.406928) (xy 83.14919 -425.383942) (xy 83.163396 -425.36439) (xy 83.182949 -425.350186)
			(xy 83.205936 -425.342722) (xy 83.21802 -425.342304) (xy 84.15782 -425.342304) (xy 84.169897 -425.342748)
			(xy 84.192867 -425.350217) (xy 84.212404 -425.364419) (xy 84.226598 -425.383962) (xy 84.234057 -425.406935)
			(xy 84.234528 -425.419012) (xy 84.234528 -427.960536) (xy 84.234067 -427.97261) (xy 84.226597 -427.995576)
			(xy 84.212399 -428.01511) (xy 84.192861 -428.029304) (xy 84.169895 -428.036769) (xy 84.15782 -428.037244)
			(xy 83.21802 -428.037244) (xy 83.20595 -428.036719) (xy 83.18299 -428.029267) (xy 83.163455 -428.015085)
			(xy 83.149259 -427.995561) (xy 83.141789 -427.972606) (xy 83.141312 -427.960536) (xy 82.234532 -427.960536)
			(xy 82.234532 -428.960534) (xy 82.234121 -428.972628) (xy 82.226652 -428.995635) (xy 82.212452 -429.015216)
			(xy 82.192905 -429.029465) (xy 82.169917 -429.036991) (xy 82.157824 -429.037496) (xy 81.218024 -429.037496)
			(xy 81.205916 -429.037063) (xy 81.182889 -429.02957) (xy 81.163315 -429.015313) (xy 81.14912 -428.995694)
			(xy 81.141699 -428.972643) (xy 81.141316 -428.960534) (xy 80.207555 -428.960534) (xy 80.212536 -428.964165)
			(xy 80.22673 -428.983789) (xy 80.234152 -429.006843) (xy 80.234536 -429.018954) (xy 80.234536 -431.560478)
			(xy 80.234073 -431.572569) (xy 80.22662 -431.595573) (xy 80.212433 -431.615155) (xy 80.192897 -431.629405)
			(xy 80.169917 -431.636934) (xy 80.157828 -431.63744) (xy 79.218028 -431.63744) (xy 79.205925 -431.63696)
			(xy 79.182905 -431.629473) (xy 79.163335 -431.615227) (xy 79.149138 -431.595621) (xy 79.141709 -431.572582)
			(xy 79.14132 -431.560478) (xy 78.23454 -431.560478) (xy 78.23454 -432.560476) (xy 78.234016 -432.572546)
			(xy 78.226564 -432.595507) (xy 78.212382 -432.615042) (xy 78.192857 -432.629238) (xy 78.169902 -432.636707)
			(xy 78.157832 -432.637184) (xy 77.218032 -432.637184) (xy 77.205949 -432.63676) (xy 77.182963 -432.629298)
			(xy 77.16341 -432.615096) (xy 77.149206 -432.595544) (xy 77.141742 -432.572559) (xy 77.141324 -432.560476)
			(xy 76.207146 -432.560476) (xy 76.212416 -432.564307) (xy 76.226609 -432.583849) (xy 76.234072 -432.60682)
			(xy 76.234544 -432.618896) (xy 76.234544 -435.16042) (xy 76.234053 -435.172492) (xy 76.22659 -435.195454)
			(xy 76.212399 -435.214987) (xy 76.192868 -435.229182) (xy 76.169908 -435.236651) (xy 76.157836 -435.237128)
			(xy 75.218036 -435.237128) (xy 75.205957 -435.236657) (xy 75.182979 -435.229202) (xy 75.16343 -435.21501)
			(xy 75.149224 -435.195471) (xy 75.141752 -435.172499) (xy 75.141328 -435.16042) (xy 73.234804 -435.16042)
			(xy 73.234804 -436.160418) (xy 73.234304 -436.172529) (xy 73.226817 -436.195566) (xy 73.212581 -436.215164)
			(xy 73.192988 -436.229406) (xy 73.169953 -436.236901) (xy 73.157842 -436.23738) (xy 72.218042 -436.23738)
			(xy 72.205923 -436.236905) (xy 72.182869 -436.229426) (xy 72.163255 -436.215188) (xy 72.149001 -436.195585)
			(xy 72.141505 -436.172536) (xy 72.14108 -436.160418) (xy 71.206977 -436.160418) (xy 71.212535 -436.16445)
			(xy 71.226782 -436.184003) (xy 71.234305 -436.206997) (xy 71.234808 -436.219092) (xy 71.234808 -438.760616)
			(xy 71.234354 -438.772666) (xy 71.226918 -438.795591) (xy 71.212775 -438.815106) (xy 71.193304 -438.829309)
			(xy 71.170403 -438.836816) (xy 71.158354 -438.837324) (xy 70.218046 -438.837324) (xy 70.205955 -438.836853)
			(xy 70.18295 -438.829404) (xy 70.163366 -438.81522) (xy 70.149115 -438.795685) (xy 70.141589 -438.772705)
			(xy 70.141084 -438.760616) (xy 69.234812 -438.760616) (xy 69.234812 -439.760614) (xy 72.14108 -439.760614)
			(xy 72.14108 -437.21909) (xy 72.141452 -437.206963) (xy 72.148952 -437.183896) (xy 72.163215 -437.164278)
			(xy 72.182843 -437.150029) (xy 72.205914 -437.142544) (xy 72.218042 -437.142128) (xy 73.157842 -437.142128)
			(xy 73.169958 -437.142576) (xy 73.193001 -437.150073) (xy 73.212601 -437.164322) (xy 73.226841 -437.183928)
			(xy 73.234329 -437.206974) (xy 73.234804 -437.21909) (xy 73.234804 -438.760616) (xy 75.141328 -438.760616)
			(xy 75.141328 -436.219092) (xy 75.141706 -436.207005) (xy 75.14918 -436.184016) (xy 75.163394 -436.164463)
			(xy 75.182956 -436.15026) (xy 75.205949 -436.142799) (xy 75.218036 -436.142384) (xy 76.157836 -436.142384)
			(xy 76.169912 -436.142833) (xy 76.192879 -436.150305) (xy 76.206792 -436.160418) (xy 77.141324 -436.160418)
			(xy 77.141324 -433.618894) (xy 77.141802 -433.606806) (xy 77.149259 -433.583808) (xy 77.163443 -433.564229)
			(xy 77.182973 -433.549978) (xy 77.205945 -433.542444) (xy 77.218032 -433.541932) (xy 78.157832 -433.541932)
			(xy 78.169946 -433.542289) (xy 78.19298 -433.549802) (xy 78.212555 -433.564077) (xy 78.226747 -433.583713)
			(xy 78.234161 -433.606779) (xy 78.23454 -433.618894) (xy 78.23454 -435.16042) (xy 79.14132 -435.16042)
			(xy 79.14132 -432.618896) (xy 79.141709 -432.60681) (xy 79.149182 -432.583823) (xy 79.163393 -432.56427)
			(xy 79.182951 -432.550067) (xy 79.205942 -432.542604) (xy 79.218028 -432.542188) (xy 80.157828 -432.542188)
			(xy 80.169904 -432.54264) (xy 80.192871 -432.55011) (xy 80.207132 -432.560476) (xy 81.141316 -432.560476)
			(xy 81.141316 -430.018952) (xy 81.141724 -430.006873) (xy 81.149202 -429.9839) (xy 81.163413 -429.964361)
			(xy 81.182964 -429.950169) (xy 81.205944 -429.942712) (xy 81.218024 -429.942244) (xy 82.157824 -429.942244)
			(xy 82.169895 -429.942743) (xy 82.192855 -429.950206) (xy 82.212387 -429.964396) (xy 82.226583 -429.983924)
			(xy 82.234053 -430.006881) (xy 82.234532 -430.018952) (xy 82.234532 -431.560478) (xy 83.141312 -431.560478)
			(xy 83.141312 -429.018954) (xy 83.141768 -429.006865) (xy 83.149234 -428.983867) (xy 83.163424 -428.964291)
			(xy 83.182958 -428.950041) (xy 83.205932 -428.942505) (xy 83.21802 -428.941992) (xy 84.15782 -428.941992)
			(xy 84.169929 -428.942399) (xy 84.192956 -428.949903) (xy 84.207543 -428.960534) (xy 85.141308 -428.960534)
			(xy 85.141308 -426.41901) (xy 85.141815 -426.406924) (xy 85.149265 -426.383929) (xy 85.163443 -426.364352)
			(xy 85.182966 -426.3501) (xy 85.205932 -426.342562) (xy 85.218016 -426.342048) (xy 86.157816 -426.342048)
			(xy 86.169921 -426.342502) (xy 86.192939 -426.349999) (xy 86.212508 -426.364253) (xy 86.226704 -426.383863)
			(xy 86.234133 -426.406904) (xy 86.234524 -426.41901) (xy 86.234524 -427.960536) (xy 87.141304 -427.960536)
			(xy 87.141304 -425.419012) (xy 87.141723 -425.406929) (xy 87.149189 -425.383944) (xy 87.163393 -425.364393)
			(xy 87.182944 -425.350189) (xy 87.205929 -425.342723) (xy 87.218012 -425.342304) (xy 88.157812 -425.342304)
			(xy 88.169888 -425.342754) (xy 88.192858 -425.350222) (xy 88.212396 -425.364421) (xy 88.226589 -425.383964)
			(xy 88.234049 -425.406935) (xy 88.23452 -425.419012) (xy 88.23452 -427.960536) (xy 88.234067 -427.972611)
			(xy 88.226596 -427.995578) (xy 88.212396 -428.015113) (xy 88.192856 -428.029307) (xy 88.169887 -428.036771)
			(xy 88.157812 -428.037244) (xy 87.218012 -428.037244) (xy 87.205942 -428.036726) (xy 87.182981 -428.029271)
			(xy 87.163447 -428.015087) (xy 87.149251 -427.995562) (xy 87.141781 -427.972606) (xy 87.141304 -427.960536)
			(xy 86.234524 -427.960536) (xy 86.234524 -428.960534) (xy 86.234121 -428.972629) (xy 86.226651 -428.995637)
			(xy 86.212449 -429.015219) (xy 86.1929 -429.029467) (xy 86.16991 -429.036992) (xy 86.157816 -429.037496)
			(xy 85.218016 -429.037496) (xy 85.205908 -429.03707) (xy 85.18288 -429.029574) (xy 85.163307 -429.015315)
			(xy 85.149112 -428.995695) (xy 85.141691 -428.972644) (xy 85.141308 -428.960534) (xy 84.207543 -428.960534)
			(xy 84.212528 -428.964167) (xy 84.226722 -428.98379) (xy 84.234144 -429.006843) (xy 84.234528 -429.018954)
			(xy 84.234528 -431.560478) (xy 84.234073 -431.57257) (xy 84.226619 -431.595575) (xy 84.21243 -431.615158)
			(xy 84.192892 -431.629408) (xy 84.16991 -431.636935) (xy 84.15782 -431.63744) (xy 83.21802 -431.63744)
			(xy 83.205916 -431.636967) (xy 83.182896 -431.629478) (xy 83.163327 -431.61523) (xy 83.14913 -431.595622)
			(xy 83.141701 -431.572583) (xy 83.141312 -431.560478) (xy 82.234532 -431.560478) (xy 82.234532 -432.560476)
			(xy 82.234016 -432.572547) (xy 82.226563 -432.595509) (xy 82.212379 -432.615045) (xy 82.192852 -432.629241)
			(xy 82.169895 -432.636708) (xy 82.157824 -432.637184) (xy 81.218024 -432.637184) (xy 81.20594 -432.636766)
			(xy 81.182954 -432.629303) (xy 81.163401 -432.615099) (xy 81.149197 -432.595546) (xy 81.141734 -432.57256)
			(xy 81.141316 -432.560476) (xy 80.207132 -432.560476) (xy 80.212407 -432.56431) (xy 80.226601 -432.58385)
			(xy 80.234064 -432.60682) (xy 80.234536 -432.618896) (xy 80.234536 -435.16042) (xy 80.234053 -435.172493)
			(xy 80.226588 -435.195456) (xy 80.212396 -435.21499) (xy 80.192863 -435.229185) (xy 80.169901 -435.236652)
			(xy 80.157828 -435.237128) (xy 79.218028 -435.237128) (xy 79.205949 -435.236664) (xy 79.18297 -435.229206)
			(xy 79.163421 -435.215013) (xy 79.149216 -435.195473) (xy 79.141744 -435.172499) (xy 79.14132 -435.16042)
			(xy 78.23454 -435.16042) (xy 78.23454 -436.160418) (xy 78.234108 -436.172511) (xy 78.226644 -436.195515)
			(xy 78.212449 -436.215097) (xy 78.192907 -436.229346) (xy 78.169923 -436.236874) (xy 78.157832 -436.23738)
			(xy 77.218032 -436.23738) (xy 77.205923 -436.236956) (xy 77.182893 -436.229463) (xy 77.163318 -436.215204)
			(xy 77.149123 -436.195582) (xy 77.141705 -436.172528) (xy 77.141324 -436.160418) (xy 76.206792 -436.160418)
			(xy 76.212415 -436.164505) (xy 76.226608 -436.184046) (xy 76.234071 -436.207016) (xy 76.234544 -436.219092)
			(xy 76.234544 -438.760616) (xy 76.23405 -438.772688) (xy 76.226587 -438.795649) (xy 76.212397 -438.815183)
			(xy 76.192867 -438.829378) (xy 76.169908 -438.836847) (xy 76.157836 -438.837324) (xy 75.218036 -438.837324)
			(xy 75.205957 -438.836857) (xy 75.182978 -438.829401) (xy 75.163428 -438.815209) (xy 75.149223 -438.795669)
			(xy 75.141751 -438.772695) (xy 75.141328 -438.760616) (xy 73.234804 -438.760616) (xy 73.234804 -439.760614)
			(xy 77.141324 -439.760614) (xy 77.141324 -437.21909) (xy 77.141799 -437.207002) (xy 77.149256 -437.184003)
			(xy 77.163441 -437.164425) (xy 77.182972 -437.150174) (xy 77.205945 -437.14264) (xy 77.218032 -437.142128)
			(xy 78.157832 -437.142128) (xy 78.169945 -437.142489) (xy 78.192978 -437.150001) (xy 78.212553 -437.164276)
			(xy 78.226746 -437.183911) (xy 78.234161 -437.206975) (xy 78.23454 -437.21909) (xy 78.23454 -438.760616)
			(xy 79.14132 -438.760616) (xy 79.14132 -436.219092) (xy 79.141706 -436.207006) (xy 79.149179 -436.184018)
			(xy 79.163391 -436.164466) (xy 79.182951 -436.150263) (xy 79.205942 -436.1428) (xy 79.218028 -436.142384)
			(xy 80.157828 -436.142384) (xy 80.169903 -436.14284) (xy 80.19287 -436.150309) (xy 80.206779 -436.160418)
			(xy 81.141316 -436.160418) (xy 81.141316 -433.618894) (xy 81.141802 -433.606807) (xy 81.149257 -433.58381)
			(xy 81.16344 -433.564232) (xy 81.182968 -433.549981) (xy 81.205938 -433.542445) (xy 81.218024 -433.541932)
			(xy 82.157824 -433.541932) (xy 82.169937 -433.542296) (xy 82.192971 -433.549806) (xy 82.212546 -433.56408)
			(xy 82.226739 -433.583715) (xy 82.234153 -433.606779) (xy 82.234532 -433.618894) (xy 82.234532 -435.16042)
			(xy 83.141312 -435.16042) (xy 83.141312 -432.618896) (xy 83.141709 -432.606811) (xy 83.14918 -432.583825)
			(xy 83.16339 -432.564273) (xy 83.182946 -432.550069) (xy 83.205935 -432.542606) (xy 83.21802 -432.542188)
			(xy 84.15782 -432.542188) (xy 84.169895 -432.542647) (xy 84.192862 -432.550115) (xy 84.207119 -432.560476)
			(xy 85.141308 -432.560476) (xy 85.141308 -430.018952) (xy 85.141723 -430.006873) (xy 85.149201 -429.983902)
			(xy 85.16341 -429.964364) (xy 85.182959 -429.950172) (xy 85.205937 -429.942713) (xy 85.218016 -429.942244)
			(xy 86.157816 -429.942244) (xy 86.169887 -429.94275) (xy 86.192846 -429.950211) (xy 86.212379 -429.964399)
			(xy 86.226574 -429.983925) (xy 86.234045 -430.006882) (xy 86.234524 -430.018952) (xy 86.234524 -431.560478)
			(xy 87.141304 -431.560478) (xy 87.141304 -429.018954) (xy 87.141767 -429.006866) (xy 87.149232 -428.98387)
			(xy 87.163421 -428.964293) (xy 87.182953 -428.950043) (xy 87.205925 -428.942506) (xy 87.218012 -428.941992)
			(xy 88.157812 -428.941992) (xy 88.169921 -428.942406) (xy 88.192947 -428.949908) (xy 88.207529 -428.960534)
			(xy 89.1413 -428.960534) (xy 89.1413 -426.41901) (xy 89.141815 -426.406925) (xy 89.149264 -426.383931)
			(xy 89.16344 -426.364355) (xy 89.182961 -426.350103) (xy 89.205925 -426.342563) (xy 89.218008 -426.342048)
			(xy 90.157808 -426.342048) (xy 90.169912 -426.342509) (xy 90.192931 -426.350004) (xy 90.212499 -426.364256)
			(xy 90.226696 -426.383865) (xy 90.234125 -426.406905) (xy 90.234516 -426.41901) (xy 90.234516 -428.960534)
			(xy 90.234121 -428.97263) (xy 90.226649 -428.995639) (xy 90.212446 -429.015222) (xy 90.192895 -429.02947)
			(xy 90.169903 -429.036993) (xy 90.157808 -429.037496) (xy 89.218008 -429.037496) (xy 89.205899 -429.037077)
			(xy 89.182871 -429.029579) (xy 89.163298 -429.015319) (xy 89.149103 -428.995697) (xy 89.141683 -428.972644)
			(xy 89.1413 -428.960534) (xy 88.207529 -428.960534) (xy 88.212519 -428.96417) (xy 88.226714 -428.983792)
			(xy 88.234136 -429.006844) (xy 88.23452 -429.018954) (xy 88.23452 -431.560478) (xy 88.234073 -431.57257)
			(xy 88.226618 -431.595577) (xy 88.212427 -431.615161) (xy 88.192887 -431.629411) (xy 88.169903 -431.636936)
			(xy 88.157812 -431.63744) (xy 87.218012 -431.63744) (xy 87.205908 -431.636974) (xy 87.182888 -431.629483)
			(xy 87.163318 -431.615232) (xy 87.149122 -431.595624) (xy 87.141693 -431.572583) (xy 87.141304 -431.560478)
			(xy 86.234524 -431.560478) (xy 86.234524 -432.560476) (xy 86.234067 -432.572556) (xy 86.226608 -432.595535)
			(xy 86.212413 -432.615084) (xy 86.192871 -432.62929) (xy 86.169896 -432.636761) (xy 86.157816 -432.637184)
			(xy 85.218016 -432.637184) (xy 85.205932 -432.636773) (xy 85.182946 -432.629307) (xy 85.163393 -432.615101)
			(xy 85.149189 -432.595547) (xy 85.141726 -432.57256) (xy 85.141308 -432.560476) (xy 84.207119 -432.560476)
			(xy 84.212399 -432.564313) (xy 84.226593 -432.583852) (xy 84.234055 -432.606821) (xy 84.234528 -432.618896)
			(xy 84.234528 -435.16042) (xy 84.234053 -435.172494) (xy 84.226587 -435.195458) (xy 84.212393 -435.214993)
			(xy 84.192858 -435.229187) (xy 84.169894 -435.236653) (xy 84.15782 -435.237128) (xy 83.21802 -435.237128)
			(xy 83.205948 -435.236619) (xy 83.182985 -435.229165) (xy 83.16345 -435.214979) (xy 83.149254 -435.195451)
			(xy 83.141787 -435.172491) (xy 83.141312 -435.16042) (xy 82.234532 -435.16042) (xy 82.234532 -436.160418)
			(xy 82.234108 -436.172511) (xy 82.226643 -436.195517) (xy 82.212446 -436.215099) (xy 82.192902 -436.229348)
			(xy 82.169916 -436.236875) (xy 82.157824 -436.23738) (xy 81.218024 -436.23738) (xy 81.205914 -436.236963)
			(xy 81.182885 -436.229468) (xy 81.163309 -436.215207) (xy 81.149115 -436.195584) (xy 81.141697 -436.172529)
			(xy 81.141316 -436.160418) (xy 80.206779 -436.160418) (xy 80.212406 -436.164508) (xy 80.2266 -436.184048)
			(xy 80.234063 -436.207017) (xy 80.234536 -436.219092) (xy 80.234536 -438.760616) (xy 80.23405 -438.772689)
			(xy 80.226586 -438.795651) (xy 80.212394 -438.815186) (xy 80.192862 -438.829381) (xy 80.169901 -438.836848)
			(xy 80.157828 -438.837324) (xy 79.218028 -438.837324) (xy 79.205948 -438.836864) (xy 79.182969 -438.829406)
			(xy 79.16342 -438.815211) (xy 79.149214 -438.79567) (xy 79.141743 -438.772695) (xy 79.14132 -438.760616)
			(xy 78.23454 -438.760616) (xy 78.23454 -439.760614) (xy 81.141316 -439.760614) (xy 81.141316 -437.21909)
			(xy 81.141799 -437.207002) (xy 81.149255 -437.184006) (xy 81.163439 -437.164428) (xy 81.182967 -437.150177)
			(xy 81.205938 -437.142641) (xy 81.218024 -437.142128) (xy 82.157824 -437.142128) (xy 82.169937 -437.142496)
			(xy 82.19297 -437.150006) (xy 82.212545 -437.164279) (xy 82.226738 -437.183912) (xy 82.234153 -437.206975)
			(xy 82.234532 -437.21909) (xy 82.234532 -438.760616) (xy 83.141312 -438.760616) (xy 83.141312 -436.219092)
			(xy 83.141706 -436.207007) (xy 83.149178 -436.18402) (xy 83.163388 -436.164469) (xy 83.182946 -436.150265)
			(xy 83.205935 -436.142802) (xy 83.21802 -436.142384) (xy 84.15782 -436.142384) (xy 84.169895 -436.142847)
			(xy 84.192861 -436.150314) (xy 84.206765 -436.160418) (xy 85.141308 -436.160418) (xy 85.141308 -433.618894)
			(xy 85.141802 -433.606807) (xy 85.149256 -433.583812) (xy 85.163437 -433.564235) (xy 85.182963 -433.549984)
			(xy 85.205931 -433.542446) (xy 85.218016 -433.541932) (xy 86.157816 -433.541932) (xy 86.169929 -433.542303)
			(xy 86.192962 -433.549811) (xy 86.212538 -433.564083) (xy 86.226731 -433.583716) (xy 86.234145 -433.606779)
			(xy 86.234524 -433.618894) (xy 86.234524 -435.16042) (xy 87.141304 -435.16042) (xy 87.141304 -432.618896)
			(xy 87.141709 -432.606812) (xy 87.149179 -432.583827) (xy 87.163387 -432.564276) (xy 87.182941 -432.550072)
			(xy 87.205928 -432.542607) (xy 87.218012 -432.542188) (xy 88.157812 -432.542188) (xy 88.169887 -432.542654)
			(xy 88.192854 -432.550119) (xy 88.207106 -432.560476) (xy 89.1413 -432.560476) (xy 89.1413 -430.018952)
			(xy 89.141723 -430.006874) (xy 89.1492 -429.983904) (xy 89.163407 -429.964367) (xy 89.182954 -429.950174)
			(xy 89.20593 -429.942714) (xy 89.218008 -429.942244) (xy 90.157808 -429.942244) (xy 90.169878 -429.942757)
			(xy 90.192837 -429.950216) (xy 90.21237 -429.964401) (xy 90.226566 -429.983927) (xy 90.234037 -430.006882)
			(xy 90.234516 -430.018952) (xy 90.234516 -432.560476) (xy 90.234067 -432.572557) (xy 90.226607 -432.595537)
			(xy 90.21241 -432.615087) (xy 90.192866 -432.629292) (xy 90.169888 -432.636762) (xy 90.157808 -432.637184)
			(xy 89.218008 -432.637184) (xy 89.205923 -432.63678) (xy 89.182937 -432.629312) (xy 89.163384 -432.615105)
			(xy 89.149181 -432.595549) (xy 89.141717 -432.572561) (xy 89.1413 -432.560476) (xy 88.207106 -432.560476)
			(xy 88.21239 -432.564316) (xy 88.226584 -432.583854) (xy 88.234047 -432.606821) (xy 88.23452 -432.618896)
			(xy 88.23452 -435.16042) (xy 88.234053 -435.172494) (xy 88.226586 -435.19546) (xy 88.21239 -435.214996)
			(xy 88.192853 -435.22919) (xy 88.169886 -435.236654) (xy 88.157812 -435.237128) (xy 87.218012 -435.237128)
			(xy 87.20594 -435.236626) (xy 87.182977 -435.229169) (xy 87.163441 -435.214982) (xy 87.149246 -435.195452)
			(xy 87.141779 -435.172492) (xy 87.141304 -435.16042) (xy 86.234524 -435.16042) (xy 86.234524 -436.160418)
			(xy 86.234107 -436.172512) (xy 86.226641 -436.195519) (xy 86.212443 -436.215102) (xy 86.192897 -436.229351)
			(xy 86.169909 -436.236876) (xy 86.157816 -436.23738) (xy 85.218016 -436.23738) (xy 85.205906 -436.23697)
			(xy 85.182876 -436.229472) (xy 85.163301 -436.21521) (xy 85.149106 -436.195585) (xy 85.141689 -436.172529)
			(xy 85.141308 -436.160418) (xy 84.206765 -436.160418) (xy 84.212397 -436.164511) (xy 84.226591 -436.18405)
			(xy 84.234055 -436.207017) (xy 84.234528 -436.219092) (xy 84.234528 -438.760616) (xy 84.23405 -438.772689)
			(xy 84.226585 -438.795654) (xy 84.212391 -438.815189) (xy 84.192857 -438.829383) (xy 84.169893 -438.836849)
			(xy 84.15782 -438.837324) (xy 83.21802 -438.837324) (xy 83.20594 -438.83687) (xy 83.182961 -438.82941)
			(xy 83.163411 -438.815214) (xy 83.149206 -438.795672) (xy 83.141735 -438.772696) (xy 83.141312 -438.760616)
			(xy 82.234532 -438.760616) (xy 82.234532 -439.760614) (xy 85.141308 -439.760614) (xy 85.141308 -437.21909)
			(xy 85.141798 -437.207003) (xy 85.149254 -437.184008) (xy 85.163436 -437.164431) (xy 85.182962 -437.150179)
			(xy 85.205931 -437.142642) (xy 85.218016 -437.142128) (xy 86.157816 -437.142128) (xy 86.169929 -437.142503)
			(xy 86.192961 -437.15001) (xy 86.212536 -437.164281) (xy 86.226729 -437.183914) (xy 86.234145 -437.206976)
			(xy 86.234524 -437.21909) (xy 86.234524 -438.760616) (xy 87.141304 -438.760616) (xy 87.141304 -436.219092)
			(xy 87.141706 -436.207008) (xy 87.149177 -436.184023) (xy 87.163386 -436.164471) (xy 87.182941 -436.150268)
			(xy 87.205928 -436.142803) (xy 87.218012 -436.142384) (xy 88.157812 -436.142384) (xy 88.169886 -436.142854)
			(xy 88.192853 -436.150319) (xy 88.206752 -436.160418) (xy 89.1413 -436.160418) (xy 89.1413 -433.618894)
			(xy 89.141802 -433.606808) (xy 89.149255 -433.583814) (xy 89.163434 -433.564238) (xy 89.182958 -433.549986)
			(xy 89.205924 -433.542447) (xy 89.218008 -433.541932) (xy 90.157808 -433.541932) (xy 90.169921 -433.54231)
			(xy 90.192954 -433.549815) (xy 90.212529 -433.564086) (xy 90.226723 -433.583717) (xy 90.234137 -433.60678)
			(xy 90.234516 -433.618894) (xy 90.234516 -436.160418) (xy 90.234107 -436.172513) (xy 90.22664 -436.195522)
			(xy 90.21244 -436.215105) (xy 90.192892 -436.229353) (xy 90.169902 -436.236877) (xy 90.157808 -436.23738)
			(xy 89.218008 -436.23738) (xy 89.205898 -436.236977) (xy 89.182867 -436.229477) (xy 89.163292 -436.215213)
			(xy 89.149098 -436.195587) (xy 89.14168 -436.17253) (xy 89.1413 -436.160418) (xy 88.206752 -436.160418)
			(xy 88.212389 -436.164514) (xy 88.226583 -436.184051) (xy 88.234047 -436.207018) (xy 88.23452 -436.219092)
			(xy 88.23452 -438.760616) (xy 88.234049 -438.77269) (xy 88.226584 -438.795656) (xy 88.212389 -438.815191)
			(xy 88.192852 -438.829386) (xy 88.169886 -438.83685) (xy 88.157812 -438.837324) (xy 87.218012 -438.837324)
			(xy 87.20594 -438.836826) (xy 87.182976 -438.829369) (xy 87.16344 -438.81518) (xy 87.149244 -438.79565)
			(xy 87.141779 -438.772688) (xy 87.141304 -438.760616) (xy 86.234524 -438.760616) (xy 86.234524 -439.760614)
			(xy 89.1413 -439.760614) (xy 89.1413 -437.21909) (xy 89.141798 -437.207004) (xy 89.149253 -437.18401)
			(xy 89.163433 -437.164434) (xy 89.182957 -437.150182) (xy 89.205924 -437.142643) (xy 89.218008 -437.142128)
			(xy 90.157808 -437.142128) (xy 90.16992 -437.14251) (xy 90.192952 -437.150015) (xy 90.212528 -437.164284)
			(xy 90.226721 -437.183915) (xy 90.234137 -437.206976) (xy 90.234516 -437.21909) (xy 90.234516 -439.760614)
			(xy 90.234104 -439.772709) (xy 90.226638 -439.795717) (xy 90.212439 -439.815301) (xy 90.192891 -439.829549)
			(xy 90.169901 -439.837073) (xy 90.157808 -439.837576) (xy 89.218008 -439.837576) (xy 89.205897 -439.837177)
			(xy 89.182866 -439.829677) (xy 89.163291 -439.815412) (xy 89.149096 -439.795785) (xy 89.14168 -439.772726)
			(xy 89.1413 -439.760614) (xy 86.234524 -439.760614) (xy 86.234104 -439.772708) (xy 86.226639 -439.795715)
			(xy 86.212442 -439.815298) (xy 86.192896 -439.829547) (xy 86.169909 -439.837072) (xy 86.157816 -439.837576)
			(xy 85.218016 -439.837576) (xy 85.205906 -439.83717) (xy 85.182875 -439.829672) (xy 85.163299 -439.815408)
			(xy 85.149105 -439.795783) (xy 85.141688 -439.772726) (xy 85.141308 -439.760614) (xy 82.234532 -439.760614)
			(xy 82.234104 -439.772707) (xy 82.22664 -439.795713) (xy 82.212445 -439.815295) (xy 82.192901 -439.829544)
			(xy 82.169916 -439.837071) (xy 82.157824 -439.837576) (xy 81.218024 -439.837576) (xy 81.205914 -439.837163)
			(xy 81.182883 -439.829667) (xy 81.163308 -439.815406) (xy 81.149113 -439.795781) (xy 81.141696 -439.772725)
			(xy 81.141316 -439.760614) (xy 78.23454 -439.760614) (xy 78.234104 -439.772706) (xy 78.226641 -439.795711)
			(xy 78.212447 -439.815292) (xy 78.192906 -439.829542) (xy 78.169923 -439.83707) (xy 78.157832 -439.837576)
			(xy 77.218032 -439.837576) (xy 77.205922 -439.837156) (xy 77.182892 -439.829663) (xy 77.163316 -439.815403)
			(xy 77.149122 -439.79578) (xy 77.141704 -439.772725) (xy 77.141324 -439.760614) (xy 73.234804 -439.760614)
			(xy 73.234301 -439.772725) (xy 73.226815 -439.795762) (xy 73.21258 -439.81536) (xy 73.192987 -439.829602)
			(xy 73.169953 -439.837097) (xy 73.157842 -439.837576) (xy 72.218042 -439.837576) (xy 72.205923 -439.837105)
			(xy 72.182868 -439.829626) (xy 72.163253 -439.815387) (xy 72.149 -439.795783) (xy 72.141504 -439.772733)
			(xy 72.14108 -439.760614) (xy 69.234812 -439.760614) (xy 69.234301 -439.772724) (xy 69.226816 -439.79576)
			(xy 69.212582 -439.815357) (xy 69.192992 -439.8296) (xy 69.16996 -439.837096) (xy 69.15785 -439.837576)
			(xy 68.21805 -439.837576) (xy 68.205934 -439.837131) (xy 68.182892 -439.829632) (xy 68.163292 -439.815382)
			(xy 68.149052 -439.795776) (xy 68.141563 -439.77273) (xy 68.141088 -439.760614) (xy 65.23482 -439.760614)
			(xy 65.234451 -439.772742) (xy 65.22695 -439.795808) (xy 65.212686 -439.815426) (xy 65.193058 -439.829675)
			(xy 65.169986 -439.83716) (xy 65.157858 -439.837576) (xy 64.218058 -439.837576) (xy 64.205943 -439.837124)
			(xy 64.1829 -439.829627) (xy 64.163301 -439.815379) (xy 64.14906 -439.795774) (xy 64.141571 -439.77273)
			(xy 64.141096 -439.760614) (xy 61.234828 -439.760614) (xy 61.234451 -439.772741) (xy 61.226951 -439.795806)
			(xy 61.212689 -439.815424) (xy 61.193063 -439.829673) (xy 61.169993 -439.837159) (xy 61.157866 -439.837576)
			(xy 60.218066 -439.837576) (xy 60.205951 -439.837118) (xy 60.182909 -439.829623) (xy 60.163309 -439.815377)
			(xy 60.149068 -439.795773) (xy 60.141579 -439.772729) (xy 60.141104 -439.760614) (xy 16.236641 -439.760614)
			(xy 16.214594 -439.77827) (xy 16.049523 -439.900231) (xy 15.87983 -440.015674) (xy 15.705772 -440.124424)
			(xy 15.527614 -440.226317) (xy 15.43685 -440.274202) (xy 15.436596 -440.274202) (xy 15.426876 -440.279997)
			(xy 15.41332 -440.29808) (xy 15.408836 -440.320231) (xy 15.410942 -440.331352) (xy 15.434564 -440.427364)
			(xy 15.437868 -440.438173) (xy 15.452161 -440.455646) (xy 15.472554 -440.465325) (xy 15.48384 -440.465972)
			(xy 58.119264 -440.465972)
		)
		(stroke
			(width 0)
			(type solid)
		)
		(fill yes)
		(layer "In9.Cu")
		(net "P12V_AUX")
	)
	(gr_line
		(start 1.414272 -79.914242)
		(end 0.585724 -79.085694)
		(stroke
			(width 3.048)
			(type default)
		)
		(layer "In9.Cu")
	)
	(gr_line
		(start 1.999996 -403.371558)
		(end 1.999996 -81.328514)
		(stroke
			(width 3.048)
			(type default)
		)
		(layer "In9.Cu")
	)
	(gr_arc
		(start 1.999996 -403.371558)
		(mid 2.152159 -404.136965)
		(end 2.58572 -404.78583)
		(stroke
			(width 3.048)
			(type default)
		)
		(layer "In9.Cu")
	)
	(gr_arc
		(start 1.999996 -81.328514)
		(mid 1.847755 -80.563149)
		(end 1.414272 -79.914242)
		(stroke
			(width 3.048)
			(type default)
		)
		(layer "In9.Cu")
	)
	(gr_arc
		(start 1.999996 -11.780012)
		(mid 0.585785 -12.365797)
		(end 0 -13.780008)
		(stroke
			(width 3.048)
			(type default)
		)
		(layer "In9.Cu")
	)
	(gr_line
		(start 1.999996 -11.780012)
		(end 11.102086 -11.780012)
		(stroke
			(width 3.048)
			(type default)
		)
		(layer "In9.Cu")
	)
	(gr_line
		(start 5.914136 -408.114246)
		(end 2.58572 -404.78583)
		(stroke
			(width 3.048)
			(type default)
		)
		(layer "In9.Cu")
	)
	(gr_line
		(start 6.500114 -439.989976)
		(end 6.500114 -409.528518)
		(stroke
			(width 3.048)
			(type default)
		)
		(layer "In9.Cu")
	)
	(gr_arc
		(start 6.500114 -439.989976)
		(mid 7.085891 -441.404199)
		(end 8.50011 -441.989972)
		(stroke
			(width 3.048)
			(type default)
		)
		(layer "In9.Cu")
	)
	(gr_arc
		(start 6.500114 -409.528518)
		(mid 6.347771 -408.763109)
		(end 5.914136 -408.114246)
		(stroke
			(width 3.048)
			(type default)
		)
		(layer "In9.Cu")
	)
	(gr_line
		(start 7.139178 -379.364494)
		(end 41.5544 -413.779716)
		(stroke
			(width 0.508)
			(type default)
		)
		(layer "In9.Cu")
	)
	(gr_line
		(start 7.139178 -374.734328)
		(end 7.139178 -379.364494)
		(stroke
			(width 0.508)
			(type default)
		)
		(layer "In9.Cu")
	)
	(gr_line
		(start 8.370824 -373.502682)
		(end 7.139178 -374.734328)
		(stroke
			(width 0.508)
			(type default)
		)
		(layer "In9.Cu")
	)
	(gr_arc
		(start 11.102086 -11.780012)
		(mid 12.516297 -11.194227)
		(end 13.102082 -9.780016)
		(stroke
			(width 3.048)
			(type default)
		)
		(layer "In9.Cu")
	)
	(gr_line
		(start 13.102082 -9.780016)
		(end 13.102082 -0.500126)
		(stroke
			(width 3.048)
			(type default)
		)
		(layer "In9.Cu")
	)
	(gr_line
		(start 13.539724 -194.497198)
		(end 13.539724 -185.935874)
		(stroke
			(width 0.508)
			(type default)
		)
		(layer "In9.Cu")
	)
	(gr_line
		(start 13.539724 -185.935874)
		(end 15.639034 -183.836564)
		(stroke
			(width 0.508)
			(type default)
		)
		(layer "In9.Cu")
	)
	(gr_arc
		(start 13.601954 0)
		(mid 13.24848 -0.146572)
		(end 13.102082 -0.500126)
		(stroke
			(width 3.048)
			(type default)
		)
		(layer "In9.Cu")
	)
	(gr_line
		(start 13.601954 0)
		(end 81.202022 0)
		(stroke
			(width 3.048)
			(type default)
		)
		(layer "In9.Cu")
	)
	(gr_line
		(start 14.673072 -195.630546)
		(end 13.539724 -194.497198)
		(stroke
			(width 0.508)
			(type default)
		)
		(layer "In9.Cu")
	)
	(gr_line
		(start 15.639034 -183.836564)
		(end 24.622252 -183.836564)
		(stroke
			(width 0.508)
			(type default)
		)
		(layer "In9.Cu")
	)
	(gr_line
		(start 23.154386 -345.445334)
		(end 23.876 -346.166948)
		(stroke
			(width 0.508)
			(type default)
		)
		(layer "In9.Cu")
	)
	(gr_line
		(start 23.154386 -334.941164)
		(end 23.154386 -345.445334)
		(stroke
			(width 0.508)
			(type default)
		)
		(layer "In9.Cu")
	)
	(gr_line
		(start 23.154386 -334.941164)
		(end 23.154386 -227.143564)
		(stroke
			(width 0.508)
			(type default)
		)
		(layer "In9.Cu")
	)
	(gr_line
		(start 23.154386 -227.143564)
		(end 23.635716 -226.662234)
		(stroke
			(width 0.508)
			(type default)
		)
		(layer "In9.Cu")
	)
	(gr_line
		(start 23.635716 -226.662234)
		(end 79.817976 -226.662234)
		(stroke
			(width 0.508)
			(type default)
		)
		(layer "In9.Cu")
	)
	(gr_line
		(start 23.700486 -335.487264)
		(end 23.154386 -334.941164)
		(stroke
			(width 0.508)
			(type default)
		)
		(layer "In9.Cu")
	)
	(gr_line
		(start 23.700486 -335.487264)
		(end 64.444626 -335.487264)
		(stroke
			(width 0.508)
			(type default)
		)
		(layer "In9.Cu")
	)
	(gr_line
		(start 23.876 -351.246948)
		(end 27.187652 -354.5586)
		(stroke
			(width 0.508)
			(type default)
		)
		(layer "In9.Cu")
	)
	(gr_line
		(start 23.876 -346.166948)
		(end 23.876 -351.246948)
		(stroke
			(width 0.508)
			(type default)
		)
		(layer "In9.Cu")
	)
	(gr_line
		(start 24.622252 -183.836564)
		(end 35.28441 -173.174406)
		(stroke
			(width 0.508)
			(type default)
		)
		(layer "In9.Cu")
	)
	(gr_circle
		(center 25.82545 -40.816276)
		(end 26.71445 -40.816276)
		(stroke
			(width 0.2)
			(type default)
		)
		(fill no)
		(layer "In9.Cu")
	)
	(gr_line
		(start 27.187652 -354.5586)
		(end 79.024734 -354.5586)
		(stroke
			(width 0.508)
			(type default)
		)
		(layer "In9.Cu")
	)
	(gr_circle
		(center 29.291534 -348.709488)
		(end 30.171644 -348.709488)
		(stroke
			(width 0.2)
			(type default)
		)
		(fill no)
		(layer "In9.Cu")
	)
	(gr_circle
		(center 29.908754 -348.709488)
		(end 30.788864 -348.709488)
		(stroke
			(width 0.2)
			(type default)
		)
		(fill no)
		(layer "In9.Cu")
	)
	(gr_circle
		(center 30.525974 -348.709488)
		(end 31.406084 -348.709488)
		(stroke
			(width 0.2)
			(type default)
		)
		(fill no)
		(layer "In9.Cu")
	)
	(gr_circle
		(center 30.795214 -347.966538)
		(end 31.684214 -347.966538)
		(stroke
			(width 0.2)
			(type default)
		)
		(fill no)
		(layer "In9.Cu")
	)
	(gr_circle
		(center 30.795214 -347.229938)
		(end 31.684214 -347.229938)
		(stroke
			(width 0.2)
			(type default)
		)
		(fill no)
		(layer "In9.Cu")
	)
	(gr_circle
		(center 31.22803 -350.318578)
		(end 32.11703 -350.318578)
		(stroke
			(width 0.2)
			(type default)
		)
		(fill no)
		(layer "In9.Cu")
	)
	(gr_circle
		(center 31.22803 -349.581978)
		(end 32.11703 -349.581978)
		(stroke
			(width 0.2)
			(type default)
		)
		(fill no)
		(layer "In9.Cu")
	)
	(gr_circle
		(center 31.752794 -349.142558)
		(end 32.641794 -349.142558)
		(stroke
			(width 0.2)
			(type default)
		)
		(fill no)
		(layer "In9.Cu")
	)
	(gr_circle
		(center 31.778194 -349.904558)
		(end 32.667194 -349.904558)
		(stroke
			(width 0.2)
			(type default)
		)
		(fill no)
		(layer "In9.Cu")
	)
	(gr_circle
		(center 32.311594 -350.260158)
		(end 33.200594 -350.260158)
		(stroke
			(width 0.2)
			(type default)
		)
		(fill no)
		(layer "In9.Cu")
	)
	(gr_circle
		(center 32.311594 -349.523558)
		(end 33.200594 -349.523558)
		(stroke
			(width 0.2)
			(type default)
		)
		(fill no)
		(layer "In9.Cu")
	)
	(gr_circle
		(center 32.311594 -348.786958)
		(end 33.200594 -348.786958)
		(stroke
			(width 0.2)
			(type default)
		)
		(fill no)
		(layer "In9.Cu")
	)
	(gr_circle
		(center 35.067748 -376.49658)
		(end 37.226748 -376.49658)
		(stroke
			(width 4.318)
			(type default)
		)
		(fill no)
		(layer "In9.Cu")
	)
	(gr_line
		(start 35.28441 -173.174406)
		(end 35.28441 -153.193242)
		(stroke
			(width 0.508)
			(type default)
		)
		(layer "In9.Cu")
	)
	(gr_line
		(start 35.28441 -153.193242)
		(end 42.401236 -146.076416)
		(stroke
			(width 0.508)
			(type default)
		)
		(layer "In9.Cu")
	)
	(gr_circle
		(center 37.571934 -348.709488)
		(end 38.452044 -348.709488)
		(stroke
			(width 0.2)
			(type default)
		)
		(fill no)
		(layer "In9.Cu")
	)
	(gr_circle
		(center 38.189154 -348.709488)
		(end 39.069264 -348.709488)
		(stroke
			(width 0.2)
			(type default)
		)
		(fill no)
		(layer "In9.Cu")
	)
	(gr_circle
		(center 38.806374 -348.709488)
		(end 39.686484 -348.709488)
		(stroke
			(width 0.2)
			(type default)
		)
		(fill no)
		(layer "In9.Cu")
	)
	(gr_circle
		(center 39.050214 -347.974158)
		(end 39.939214 -347.974158)
		(stroke
			(width 0.2)
			(type default)
		)
		(fill no)
		(layer "In9.Cu")
	)
	(gr_circle
		(center 39.050214 -347.237558)
		(end 39.939214 -347.237558)
		(stroke
			(width 0.2)
			(type default)
		)
		(fill no)
		(layer "In9.Cu")
	)
	(gr_circle
		(center 39.50843 -350.318578)
		(end 40.39743 -350.318578)
		(stroke
			(width 0.2)
			(type default)
		)
		(fill no)
		(layer "In9.Cu")
	)
	(gr_circle
		(center 39.50843 -349.581978)
		(end 40.39743 -349.581978)
		(stroke
			(width 0.2)
			(type default)
		)
		(fill no)
		(layer "In9.Cu")
	)
	(gr_circle
		(center 40.033194 -349.142558)
		(end 40.922194 -349.142558)
		(stroke
			(width 0.2)
			(type default)
		)
		(fill no)
		(layer "In9.Cu")
	)
	(gr_circle
		(center 40.058594 -349.904558)
		(end 40.947594 -349.904558)
		(stroke
			(width 0.2)
			(type default)
		)
		(fill no)
		(layer "In9.Cu")
	)
	(gr_circle
		(center 40.591994 -350.260158)
		(end 41.480994 -350.260158)
		(stroke
			(width 0.2)
			(type default)
		)
		(fill no)
		(layer "In9.Cu")
	)
	(gr_circle
		(center 40.591994 -349.523558)
		(end 41.480994 -349.523558)
		(stroke
			(width 0.2)
			(type default)
		)
		(fill no)
		(layer "In9.Cu")
	)
	(gr_circle
		(center 40.591994 -348.786958)
		(end 41.480994 -348.786958)
		(stroke
			(width 0.2)
			(type default)
		)
		(fill no)
		(layer "In9.Cu")
	)
	(gr_line
		(start 40.74033 -195.630546)
		(end 14.673072 -195.630546)
		(stroke
			(width 0.508)
			(type default)
		)
		(layer "In9.Cu")
	)
	(gr_line
		(start 40.807386 -226.662234)
		(end 40.807386 -180.71592)
		(stroke
			(width 0.508)
			(type default)
		)
		(layer "In9.Cu")
	)
	(gr_line
		(start 40.807386 -180.71592)
		(end 45.202094 -176.321212)
		(stroke
			(width 0.508)
			(type default)
		)
		(layer "In9.Cu")
	)
	(gr_circle
		(center 41.369742 -358.549194)
		(end 42.258742 -358.549194)
		(stroke
			(width 0.2)
			(type default)
		)
		(fill no)
		(layer "In9.Cu")
	)
	(gr_circle
		(center 41.417494 -357.898192)
		(end 42.306494 -357.898192)
		(stroke
			(width 0.2)
			(type default)
		)
		(fill no)
		(layer "In9.Cu")
	)
	(gr_circle
		(center 41.417494 -357.263192)
		(end 42.306494 -357.263192)
		(stroke
			(width 0.2)
			(type default)
		)
		(fill no)
		(layer "In9.Cu")
	)
	(gr_circle
		(center 41.427146 -359.2576)
		(end 42.316146 -359.2576)
		(stroke
			(width 0.2)
			(type default)
		)
		(fill no)
		(layer "In9.Cu")
	)
	(gr_line
		(start 41.5544 -413.779716)
		(end 163.546028 -413.779716)
		(stroke
			(width 0.508)
			(type default)
		)
		(layer "In9.Cu")
	)
	(gr_circle
		(center 41.567862 -404.792688)
		(end 43.726862 -404.792688)
		(stroke
			(width 4.318)
			(type default)
		)
		(fill no)
		(layer "In9.Cu")
	)
	(gr_line
		(start 42.401236 -146.076416)
		(end 59.946032 -146.076416)
		(stroke
			(width 0.508)
			(type default)
		)
		(layer "In9.Cu")
	)
	(gr_circle
		(center 43.935904 -358.51084)
		(end 44.824904 -358.51084)
		(stroke
			(width 0.2)
			(type default)
		)
		(fill no)
		(layer "In9.Cu")
	)
	(gr_circle
		(center 43.983656 -357.859838)
		(end 44.872656 -357.859838)
		(stroke
			(width 0.2)
			(type default)
		)
		(fill no)
		(layer "In9.Cu")
	)
	(gr_circle
		(center 43.983656 -357.224838)
		(end 44.872656 -357.224838)
		(stroke
			(width 0.2)
			(type default)
		)
		(fill no)
		(layer "In9.Cu")
	)
	(gr_circle
		(center 43.993308 -359.219246)
		(end 44.882308 -359.219246)
		(stroke
			(width 0.2)
			(type default)
		)
		(fill no)
		(layer "In9.Cu")
	)
	(gr_line
		(start 44.264834 -172.488352)
		(end 44.264834 -156.714952)
		(stroke
			(width 0.508)
			(type default)
		)
		(layer "In9.Cu")
	)
	(gr_line
		(start 44.264834 -156.714952)
		(end 47.576994 -153.402792)
		(stroke
			(width 0.508)
			(type default)
		)
		(layer "In9.Cu")
	)
	(gr_line
		(start 45.202094 -176.321212)
		(end 45.202094 -173.425612)
		(stroke
			(width 0.508)
			(type default)
		)
		(layer "In9.Cu")
	)
	(gr_line
		(start 45.202094 -173.425612)
		(end 44.264834 -172.488352)
		(stroke
			(width 0.508)
			(type default)
		)
		(layer "In9.Cu")
	)
	(gr_circle
		(center 45.877734 -348.709488)
		(end 46.757844 -348.709488)
		(stroke
			(width 0.2)
			(type default)
		)
		(fill no)
		(layer "In9.Cu")
	)
	(gr_circle
		(center 46.494954 -348.709488)
		(end 47.375064 -348.709488)
		(stroke
			(width 0.2)
			(type default)
		)
		(fill no)
		(layer "In9.Cu")
	)
	(gr_circle
		(center 47.112174 -348.709488)
		(end 47.992284 -348.709488)
		(stroke
			(width 0.2)
			(type default)
		)
		(fill no)
		(layer "In9.Cu")
	)
	(gr_circle
		(center 47.366174 -348.017338)
		(end 48.255174 -348.017338)
		(stroke
			(width 0.2)
			(type default)
		)
		(fill no)
		(layer "In9.Cu")
	)
	(gr_circle
		(center 47.366174 -347.280738)
		(end 48.255174 -347.280738)
		(stroke
			(width 0.2)
			(type default)
		)
		(fill no)
		(layer "In9.Cu")
	)
	(gr_line
		(start 47.576994 -153.402792)
		(end 58.940954 -153.402792)
		(stroke
			(width 0.508)
			(type default)
		)
		(layer "In9.Cu")
	)
	(gr_circle
		(center 47.81423 -350.318578)
		(end 48.70323 -350.318578)
		(stroke
			(width 0.2)
			(type default)
		)
		(fill no)
		(layer "In9.Cu")
	)
	(gr_circle
		(center 47.81423 -349.581978)
		(end 48.70323 -349.581978)
		(stroke
			(width 0.2)
			(type default)
		)
		(fill no)
		(layer "In9.Cu")
	)
	(gr_circle
		(center 47.880778 -358.108504)
		(end 48.769778 -358.108504)
		(stroke
			(width 0.2)
			(type default)
		)
		(fill no)
		(layer "In9.Cu")
	)
	(gr_circle
		(center 47.92853 -357.457502)
		(end 48.81753 -357.457502)
		(stroke
			(width 0.2)
			(type default)
		)
		(fill no)
		(layer "In9.Cu")
	)
	(gr_circle
		(center 47.92853 -356.822502)
		(end 48.81753 -356.822502)
		(stroke
			(width 0.2)
			(type default)
		)
		(fill no)
		(layer "In9.Cu")
	)
	(gr_circle
		(center 48.338994 -349.142558)
		(end 49.227994 -349.142558)
		(stroke
			(width 0.2)
			(type default)
		)
		(fill no)
		(layer "In9.Cu")
	)
	(gr_circle
		(center 48.364394 -349.904558)
		(end 49.253394 -349.904558)
		(stroke
			(width 0.2)
			(type default)
		)
		(fill no)
		(layer "In9.Cu")
	)
	(gr_circle
		(center 48.718978 -358.108504)
		(end 49.607978 -358.108504)
		(stroke
			(width 0.2)
			(type default)
		)
		(fill no)
		(layer "In9.Cu")
	)
	(gr_circle
		(center 48.76673 -357.457502)
		(end 49.65573 -357.457502)
		(stroke
			(width 0.2)
			(type default)
		)
		(fill no)
		(layer "In9.Cu")
	)
	(gr_circle
		(center 48.76673 -356.822502)
		(end 49.65573 -356.822502)
		(stroke
			(width 0.2)
			(type default)
		)
		(fill no)
		(layer "In9.Cu")
	)
	(gr_circle
		(center 48.897794 -350.260158)
		(end 49.786794 -350.260158)
		(stroke
			(width 0.2)
			(type default)
		)
		(fill no)
		(layer "In9.Cu")
	)
	(gr_circle
		(center 48.897794 -349.523558)
		(end 49.786794 -349.523558)
		(stroke
			(width 0.2)
			(type default)
		)
		(fill no)
		(layer "In9.Cu")
	)
	(gr_circle
		(center 48.897794 -348.786958)
		(end 49.786794 -348.786958)
		(stroke
			(width 0.2)
			(type default)
		)
		(fill no)
		(layer "In9.Cu")
	)
	(gr_circle
		(center 49.353978 -358.108504)
		(end 50.242978 -358.108504)
		(stroke
			(width 0.2)
			(type default)
		)
		(fill no)
		(layer "In9.Cu")
	)
	(gr_circle
		(center 49.40173 -357.457502)
		(end 50.29073 -357.457502)
		(stroke
			(width 0.2)
			(type default)
		)
		(fill no)
		(layer "In9.Cu")
	)
	(gr_circle
		(center 49.40173 -356.822502)
		(end 50.29073 -356.822502)
		(stroke
			(width 0.2)
			(type default)
		)
		(fill no)
		(layer "In9.Cu")
	)
	(gr_circle
		(center 49.988978 -358.108504)
		(end 50.877978 -358.108504)
		(stroke
			(width 0.2)
			(type default)
		)
		(fill no)
		(layer "In9.Cu")
	)
	(gr_circle
		(center 50.03673 -357.457502)
		(end 50.92573 -357.457502)
		(stroke
			(width 0.2)
			(type default)
		)
		(fill no)
		(layer "In9.Cu")
	)
	(gr_circle
		(center 50.03673 -356.822502)
		(end 50.92573 -356.822502)
		(stroke
			(width 0.2)
			(type default)
		)
		(fill no)
		(layer "In9.Cu")
	)
	(gr_circle
		(center 50.623978 -358.108504)
		(end 51.512978 -358.108504)
		(stroke
			(width 0.2)
			(type default)
		)
		(fill no)
		(layer "In9.Cu")
	)
	(gr_circle
		(center 50.67173 -357.457502)
		(end 51.56073 -357.457502)
		(stroke
			(width 0.2)
			(type default)
		)
		(fill no)
		(layer "In9.Cu")
	)
	(gr_circle
		(center 50.67173 -356.822502)
		(end 51.56073 -356.822502)
		(stroke
			(width 0.2)
			(type default)
		)
		(fill no)
		(layer "In9.Cu")
	)
	(gr_line
		(start 52.089812 -373.502682)
		(end 8.370824 -373.502682)
		(stroke
			(width 0.508)
			(type default)
		)
		(layer "In9.Cu")
	)
	(gr_line
		(start 54.101238 -387.902196)
		(end 54.101238 -384.033776)
		(stroke
			(width 0.508)
			(type default)
		)
		(layer "In9.Cu")
	)
	(gr_line
		(start 54.101238 -384.033776)
		(end 54.439566 -383.695448)
		(stroke
			(width 0.508)
			(type default)
		)
		(layer "In9.Cu")
	)
	(gr_circle
		(center 54.234334 -348.709488)
		(end 55.114444 -348.709488)
		(stroke
			(width 0.2)
			(type default)
		)
		(fill no)
		(layer "In9.Cu")
	)
	(gr_line
		(start 54.439566 -383.695448)
		(end 54.439566 -375.852436)
		(stroke
			(width 0.508)
			(type default)
		)
		(layer "In9.Cu")
	)
	(gr_line
		(start 54.439566 -375.852436)
		(end 52.089812 -373.502682)
		(stroke
			(width 0.508)
			(type default)
		)
		(layer "In9.Cu")
	)
	(gr_line
		(start 54.548024 -383.649728)
		(end 54.720236 -383.477516)
		(stroke
			(width 0.508)
			(type default)
		)
		(layer "In9.Cu")
	)
	(gr_line
		(start 54.548278 -388.349236)
		(end 54.101238 -387.902196)
		(stroke
			(width 0.508)
			(type default)
		)
		(layer "In9.Cu")
	)
	(gr_line
		(start 54.720236 -383.477516)
		(end 69.589396 -383.477516)
		(stroke
			(width 0.508)
			(type default)
		)
		(layer "In9.Cu")
	)
	(gr_circle
		(center 54.851554 -348.709488)
		(end 55.731664 -348.709488)
		(stroke
			(width 0.2)
			(type default)
		)
		(fill no)
		(layer "In9.Cu")
	)
	(gr_circle
		(center 55.468774 -348.709488)
		(end 56.348884 -348.709488)
		(stroke
			(width 0.2)
			(type default)
		)
		(fill no)
		(layer "In9.Cu")
	)
	(gr_circle
		(center 55.727854 -347.997018)
		(end 56.616854 -347.997018)
		(stroke
			(width 0.2)
			(type default)
		)
		(fill no)
		(layer "In9.Cu")
	)
	(gr_circle
		(center 55.727854 -347.260418)
		(end 56.616854 -347.260418)
		(stroke
			(width 0.2)
			(type default)
		)
		(fill no)
		(layer "In9.Cu")
	)
	(gr_circle
		(center 56.17083 -350.318578)
		(end 57.05983 -350.318578)
		(stroke
			(width 0.2)
			(type default)
		)
		(fill no)
		(layer "In9.Cu")
	)
	(gr_circle
		(center 56.17083 -349.581978)
		(end 57.05983 -349.581978)
		(stroke
			(width 0.2)
			(type default)
		)
		(fill no)
		(layer "In9.Cu")
	)
	(gr_line
		(start 56.230266 -335.487264)
		(end 56.809386 -334.908144)
		(stroke
			(width 0.508)
			(type default)
		)
		(layer "In9.Cu")
	)
	(gr_line
		(start 56.593486 -335.487264)
		(end 56.499506 -335.487264)
		(stroke
			(width 0.508)
			(type default)
		)
		(layer "In9.Cu")
	)
	(gr_circle
		(center 56.695594 -349.142558)
		(end 57.584594 -349.142558)
		(stroke
			(width 0.2)
			(type default)
		)
		(fill no)
		(layer "In9.Cu")
	)
	(gr_circle
		(center 56.720994 -349.904558)
		(end 57.609994 -349.904558)
		(stroke
			(width 0.2)
			(type default)
		)
		(fill no)
		(layer "In9.Cu")
	)
	(gr_line
		(start 56.809386 -334.908144)
		(end 56.809386 -308.169564)
		(stroke
			(width 0.508)
			(type default)
		)
		(layer "In9.Cu")
	)
	(gr_line
		(start 56.809386 -308.169564)
		(end 69.02069 -295.95826)
		(stroke
			(width 0.508)
			(type default)
		)
		(layer "In9.Cu")
	)
	(gr_line
		(start 57.237122 -388.349236)
		(end 54.548278 -388.349236)
		(stroke
			(width 0.508)
			(type default)
		)
		(layer "In9.Cu")
	)
	(gr_circle
		(center 57.254394 -350.260158)
		(end 58.143394 -350.260158)
		(stroke
			(width 0.2)
			(type default)
		)
		(fill no)
		(layer "In9.Cu")
	)
	(gr_circle
		(center 57.254394 -349.523558)
		(end 58.143394 -349.523558)
		(stroke
			(width 0.2)
			(type default)
		)
		(fill no)
		(layer "In9.Cu")
	)
	(gr_circle
		(center 57.254394 -348.786958)
		(end 58.143394 -348.786958)
		(stroke
			(width 0.2)
			(type default)
		)
		(fill no)
		(layer "In9.Cu")
	)
	(gr_line
		(start 57.388506 -335.487264)
		(end 56.809386 -334.908144)
		(stroke
			(width 0.508)
			(type default)
		)
		(layer "In9.Cu")
	)
	(gr_line
		(start 57.404 -90.769948)
		(end 62.738 -96.103948)
		(stroke
			(width 0.508)
			(type default)
		)
		(layer "In9.Cu")
	)
	(gr_line
		(start 57.404 -30.190948)
		(end 57.404 -90.769948)
		(stroke
			(width 0.508)
			(type default)
		)
		(layer "In9.Cu")
	)
	(gr_line
		(start 59.064144 -386.522214)
		(end 57.237122 -388.349236)
		(stroke
			(width 0.508)
			(type default)
		)
		(layer "In9.Cu")
	)
	(gr_line
		(start 59.76493 -386.522214)
		(end 59.064144 -386.522214)
		(stroke
			(width 0.508)
			(type default)
		)
		(layer "In9.Cu")
	)
	(gr_line
		(start 59.944 -27.650948)
		(end 57.404 -30.190948)
		(stroke
			(width 0.508)
			(type default)
		)
		(layer "In9.Cu")
	)
	(gr_line
		(start 59.946032 -146.076416)
		(end 66.872104 -153.002488)
		(stroke
			(width 0.508)
			(type default)
		)
		(layer "In9.Cu")
	)
	(gr_line
		(start 60.12688 -202.648058)
		(end 60.12688 -154.588718)
		(stroke
			(width 0.508)
			(type default)
		)
		(layer "In9.Cu")
	)
	(gr_line
		(start 60.12688 -154.588718)
		(end 58.940954 -153.402792)
		(stroke
			(width 0.508)
			(type default)
		)
		(layer "In9.Cu")
	)
	(gr_line
		(start 60.134246 -179.541424)
		(end 60.492386 -179.899564)
		(stroke
			(width 0.508)
			(type default)
		)
		(layer "In9.Cu")
	)
	(gr_line
		(start 60.492386 -179.899564)
		(end 60.129166 -180.262784)
		(stroke
			(width 0.508)
			(type default)
		)
		(layer "In9.Cu")
	)
	(gr_line
		(start 60.598558 -162.19551)
		(end 60.12688 -162.667188)
		(stroke
			(width 0.508)
			(type default)
		)
		(layer "In9.Cu")
	)
	(gr_line
		(start 60.598558 -162.19551)
		(end 60.598558 -162.092894)
		(stroke
			(width 0.508)
			(type default)
		)
		(layer "In9.Cu")
	)
	(gr_line
		(start 60.598558 -162.092894)
		(end 60.16498 -161.659316)
		(stroke
			(width 0.508)
			(type default)
		)
		(layer "In9.Cu")
	)
	(gr_line
		(start 61.12129 -387.878574)
		(end 59.76493 -386.522214)
		(stroke
			(width 0.508)
			(type default)
		)
		(layer "In9.Cu")
	)
	(gr_circle
		(center 61.93663 -166.86276)
		(end 62.82563 -166.86276)
		(stroke
			(width 0.2)
			(type default)
		)
		(fill no)
		(layer "In9.Cu")
	)
	(gr_circle
		(center 61.93663 -166.12616)
		(end 62.82563 -166.12616)
		(stroke
			(width 0.2)
			(type default)
		)
		(fill no)
		(layer "In9.Cu")
	)
	(gr_circle
		(center 61.93663 -165.38956)
		(end 62.82563 -165.38956)
		(stroke
			(width 0.2)
			(type default)
		)
		(fill no)
		(layer "In9.Cu")
	)
	(gr_circle
		(center 62.47003 -165.74516)
		(end 63.35903 -165.74516)
		(stroke
			(width 0.2)
			(type default)
		)
		(fill no)
		(layer "In9.Cu")
	)
	(gr_circle
		(center 62.49543 -166.50716)
		(end 63.38443 -166.50716)
		(stroke
			(width 0.2)
			(type default)
		)
		(fill no)
		(layer "In9.Cu")
	)
	(gr_circle
		(center 62.565534 -348.709488)
		(end 63.445644 -348.709488)
		(stroke
			(width 0.2)
			(type default)
		)
		(fill no)
		(layer "In9.Cu")
	)
	(gr_line
		(start 62.738 -96.103948)
		(end 103.886 -96.103948)
		(stroke
			(width 0.508)
			(type default)
		)
		(layer "In9.Cu")
	)
	(gr_circle
		(center 63.020194 -166.06774)
		(end 63.909194 -166.06774)
		(stroke
			(width 0.2)
			(type default)
		)
		(fill no)
		(layer "In9.Cu")
	)
	(gr_circle
		(center 63.020194 -165.33114)
		(end 63.909194 -165.33114)
		(stroke
			(width 0.2)
			(type default)
		)
		(fill no)
		(layer "In9.Cu")
	)
	(gr_circle
		(center 63.182754 -348.709488)
		(end 64.062864 -348.709488)
		(stroke
			(width 0.2)
			(type default)
		)
		(fill no)
		(layer "In9.Cu")
	)
	(gr_circle
		(center 63.199264 -12.43711)
		(end 64.088264 -12.43711)
		(stroke
			(width 0.2)
			(type default)
		)
		(fill no)
		(layer "In9.Cu")
	)
	(gr_circle
		(center 63.579248 -168.42232)
		(end 64.468248 -168.42232)
		(stroke
			(width 0.2)
			(type default)
		)
		(fill no)
		(layer "In9.Cu")
	)
	(gr_circle
		(center 63.579248 -167.68572)
		(end 64.468248 -167.68572)
		(stroke
			(width 0.2)
			(type default)
		)
		(fill no)
		(layer "In9.Cu")
	)
	(gr_circle
		(center 63.631064 -13.09751)
		(end 64.520064 -13.09751)
		(stroke
			(width 0.2)
			(type default)
		)
		(fill no)
		(layer "In9.Cu")
	)
	(gr_circle
		(center 63.72225 -166.94023)
		(end 64.60236 -166.94023)
		(stroke
			(width 0.2)
			(type default)
		)
		(fill no)
		(layer "In9.Cu")
	)
	(gr_circle
		(center 63.799974 -348.709488)
		(end 64.680084 -348.709488)
		(stroke
			(width 0.2)
			(type default)
		)
		(fill no)
		(layer "In9.Cu")
	)
	(gr_circle
		(center 64.061594 -348.038928)
		(end 64.941704 -348.038928)
		(stroke
			(width 0.2)
			(type default)
		)
		(fill no)
		(layer "In9.Cu")
	)
	(gr_circle
		(center 64.061594 -347.302328)
		(end 64.941704 -347.302328)
		(stroke
			(width 0.2)
			(type default)
		)
		(fill no)
		(layer "In9.Cu")
	)
	(gr_circle
		(center 64.088264 -12.43711)
		(end 64.977264 -12.43711)
		(stroke
			(width 0.2)
			(type default)
		)
		(fill no)
		(layer "In9.Cu")
	)
	(gr_line
		(start 64.135 -27.650948)
		(end 59.944 -27.650948)
		(stroke
			(width 0.508)
			(type default)
		)
		(layer "In9.Cu")
	)
	(gr_circle
		(center 64.33947 -166.94023)
		(end 65.21958 -166.94023)
		(stroke
			(width 0.2)
			(type default)
		)
		(fill no)
		(layer "In9.Cu")
	)
	(gr_line
		(start 64.444626 -335.487264)
		(end 64.937386 -334.994504)
		(stroke
			(width 0.508)
			(type default)
		)
		(layer "In9.Cu")
	)
	(gr_circle
		(center 64.50203 -350.318578)
		(end 65.39103 -350.318578)
		(stroke
			(width 0.2)
			(type default)
		)
		(fill no)
		(layer "In9.Cu")
	)
	(gr_circle
		(center 64.50203 -349.581978)
		(end 65.39103 -349.581978)
		(stroke
			(width 0.2)
			(type default)
		)
		(fill no)
		(layer "In9.Cu")
	)
	(gr_circle
		(center 64.520064 -13.09751)
		(end 65.409064 -13.09751)
		(stroke
			(width 0.2)
			(type default)
		)
		(fill no)
		(layer "In9.Cu")
	)
	(gr_line
		(start 64.937386 -330.394564)
		(end 64.937386 -334.994504)
		(stroke
			(width 0.508)
			(type default)
		)
		(layer "In9.Cu")
	)
	(gr_line
		(start 64.937386 -330.394564)
		(end 65.699386 -329.632564)
		(stroke
			(width 0.508)
			(type default)
		)
		(layer "In9.Cu")
	)
	(gr_circle
		(center 64.95669 -166.94023)
		(end 65.8368 -166.94023)
		(stroke
			(width 0.2)
			(type default)
		)
		(fill no)
		(layer "In9.Cu")
	)
	(gr_circle
		(center 64.977264 -12.43711)
		(end 65.866264 -12.43711)
		(stroke
			(width 0.2)
			(type default)
		)
		(fill no)
		(layer "In9.Cu")
	)
	(gr_circle
		(center 65.026794 -349.142558)
		(end 65.915794 -349.142558)
		(stroke
			(width 0.2)
			(type default)
		)
		(fill no)
		(layer "In9.Cu")
	)
	(gr_circle
		(center 65.052194 -349.904558)
		(end 65.941194 -349.904558)
		(stroke
			(width 0.2)
			(type default)
		)
		(fill no)
		(layer "In9.Cu")
	)
	(gr_circle
		(center 65.409064 -13.09751)
		(end 66.298064 -13.09751)
		(stroke
			(width 0.2)
			(type default)
		)
		(fill no)
		(layer "In9.Cu")
	)
	(gr_circle
		(center 65.585594 -350.260158)
		(end 66.474594 -350.260158)
		(stroke
			(width 0.2)
			(type default)
		)
		(fill no)
		(layer "In9.Cu")
	)
	(gr_circle
		(center 65.585594 -349.523558)
		(end 66.474594 -349.523558)
		(stroke
			(width 0.2)
			(type default)
		)
		(fill no)
		(layer "In9.Cu")
	)
	(gr_circle
		(center 65.585594 -348.786958)
		(end 66.474594 -348.786958)
		(stroke
			(width 0.2)
			(type default)
		)
		(fill no)
		(layer "In9.Cu")
	)
	(gr_line
		(start 65.699386 -329.632564)
		(end 70.779386 -329.632564)
		(stroke
			(width 0.508)
			(type default)
		)
		(layer "In9.Cu")
	)
	(gr_circle
		(center 65.866264 -12.43711)
		(end 66.755264 -12.43711)
		(stroke
			(width 0.2)
			(type default)
		)
		(fill no)
		(layer "In9.Cu")
	)
	(gr_circle
		(center 66.298064 -13.09751)
		(end 67.187064 -13.09751)
		(stroke
			(width 0.2)
			(type default)
		)
		(fill no)
		(layer "In9.Cu")
	)
	(gr_circle
		(center 66.399664 -25.56891)
		(end 67.288664 -25.56891)
		(stroke
			(width 0.2)
			(type default)
		)
		(fill no)
		(layer "In9.Cu")
	)
	(gr_line
		(start 66.421 -29.936948)
		(end 64.135 -27.650948)
		(stroke
			(width 0.508)
			(type default)
		)
		(layer "In9.Cu")
	)
	(gr_circle
		(center 66.501264 -12.43711)
		(end 67.390264 -12.43711)
		(stroke
			(width 0.2)
			(type default)
		)
		(fill no)
		(layer "In9.Cu")
	)
	(gr_circle
		(center 66.774822 -20.327366)
		(end 67.663822 -20.327366)
		(stroke
			(width 0.2)
			(type default)
		)
		(fill no)
		(layer "In9.Cu")
	)
	(gr_circle
		(center 66.774822 -19.692366)
		(end 67.663822 -19.692366)
		(stroke
			(width 0.2)
			(type default)
		)
		(fill no)
		(layer "In9.Cu")
	)
	(gr_circle
		(center 66.780664 -24.88311)
		(end 67.669664 -24.88311)
		(stroke
			(width 0.2)
			(type default)
		)
		(fill no)
		(layer "In9.Cu")
	)
	(gr_circle
		(center 66.848228 -18.642584)
		(end 67.737228 -18.642584)
		(stroke
			(width 0.2)
			(type default)
		)
		(fill no)
		(layer "In9.Cu")
	)
	(gr_line
		(start 66.872104 -153.002488)
		(end 76.484988 -153.002488)
		(stroke
			(width 0.508)
			(type default)
		)
		(layer "In9.Cu")
	)
	(gr_circle
		(center 66.882264 -22.26691)
		(end 67.771264 -22.26691)
		(stroke
			(width 0.2)
			(type default)
		)
		(fill no)
		(layer "In9.Cu")
	)
	(gr_circle
		(center 66.933064 -13.09751)
		(end 67.822064 -13.09751)
		(stroke
			(width 0.2)
			(type default)
		)
		(fill no)
		(layer "In9.Cu")
	)
	(gr_circle
		(center 67.288664 -25.56891)
		(end 68.177664 -25.56891)
		(stroke
			(width 0.2)
			(type default)
		)
		(fill no)
		(layer "In9.Cu")
	)
	(gr_circle
		(center 67.40271 -12.489434)
		(end 68.29171 -12.489434)
		(stroke
			(width 0.2)
			(type default)
		)
		(fill no)
		(layer "In9.Cu")
	)
	(gr_circle
		(center 67.669664 -24.88311)
		(end 68.558664 -24.88311)
		(stroke
			(width 0.2)
			(type default)
		)
		(fill no)
		(layer "In9.Cu")
	)
	(gr_line
		(start 67.985386 -179.899564)
		(end 60.492386 -179.899564)
		(stroke
			(width 0.508)
			(type default)
		)
		(layer "In9.Cu")
	)
	(gr_circle
		(center 68.177664 -25.56891)
		(end 69.066664 -25.56891)
		(stroke
			(width 0.2)
			(type default)
		)
		(fill no)
		(layer "In9.Cu")
	)
	(gr_circle
		(center 68.54444 -18.476214)
		(end 69.43344 -18.476214)
		(stroke
			(width 0.2)
			(type default)
		)
		(fill no)
		(layer "In9.Cu")
	)
	(gr_circle
		(center 68.558664 -24.88311)
		(end 69.447664 -24.88311)
		(stroke
			(width 0.2)
			(type default)
		)
		(fill no)
		(layer "In9.Cu")
	)
	(gr_line
		(start 69.02069 -295.95826)
		(end 79.177896 -295.95826)
		(stroke
			(width 0.508)
			(type default)
		)
		(layer "In9.Cu")
	)
	(gr_line
		(start 69.158358 -387.878574)
		(end 61.12129 -387.878574)
		(stroke
			(width 0.508)
			(type default)
		)
		(layer "In9.Cu")
	)
	(gr_circle
		(center 69.498464 -24.55291)
		(end 70.387464 -24.55291)
		(stroke
			(width 0.2)
			(type default)
		)
		(fill no)
		(layer "In9.Cu")
	)
	(gr_line
		(start 69.589396 -383.477516)
		(end 69.589396 -367.949226)
		(stroke
			(width 0.508)
			(type default)
		)
		(layer "In9.Cu")
	)
	(gr_line
		(start 69.589396 -383.477516)
		(end 69.93382 -383.82194)
		(stroke
			(width 0.508)
			(type default)
		)
		(layer "In9.Cu")
	)
	(gr_line
		(start 69.589396 -367.949226)
		(end 70.544436 -366.994186)
		(stroke
			(width 0.508)
			(type default)
		)
		(layer "In9.Cu")
	)
	(gr_line
		(start 69.636386 -183.985408)
		(end 69.636386 -181.550564)
		(stroke
			(width 0.508)
			(type default)
		)
		(layer "In9.Cu")
	)
	(gr_line
		(start 69.636386 -181.550564)
		(end 67.985386 -179.899564)
		(stroke
			(width 0.508)
			(type default)
		)
		(layer "In9.Cu")
	)
	(gr_line
		(start 69.75602 -387.280912)
		(end 69.158358 -387.878574)
		(stroke
			(width 0.508)
			(type default)
		)
		(layer "In9.Cu")
	)
	(gr_line
		(start 69.75602 -386.689346)
		(end 69.75602 -387.280912)
		(stroke
			(width 0.508)
			(type default)
		)
		(layer "In9.Cu")
	)
	(gr_line
		(start 69.75602 -386.320538)
		(end 69.75602 -386.689346)
		(stroke
			(width 0.254)
			(type default)
		)
		(layer "In9.Cu")
	)
	(gr_line
		(start 69.93382 -386.142738)
		(end 69.75602 -386.320538)
		(stroke
			(width 0.254)
			(type default)
		)
		(layer "In9.Cu")
	)
	(gr_line
		(start 69.93382 -384.62077)
		(end 69.93382 -386.142738)
		(stroke
			(width 0.254)
			(type default)
		)
		(layer "In9.Cu")
	)
	(gr_line
		(start 69.93382 -383.82194)
		(end 69.93382 -384.62077)
		(stroke
			(width 0.508)
			(type default)
		)
		(layer "In9.Cu")
	)
	(gr_circle
		(center 70.25005 -175.559974)
		(end 71.13905 -175.559974)
		(stroke
			(width 0.2)
			(type default)
		)
		(fill no)
		(layer "In9.Cu")
	)
	(gr_circle
		(center 70.25005 -174.823374)
		(end 71.13905 -174.823374)
		(stroke
			(width 0.2)
			(type default)
		)
		(fill no)
		(layer "In9.Cu")
	)
	(gr_circle
		(center 70.25005 -174.086774)
		(end 71.13905 -174.086774)
		(stroke
			(width 0.2)
			(type default)
		)
		(fill no)
		(layer "In9.Cu")
	)
	(gr_line
		(start 70.544436 -366.994186)
		(end 181.955948 -366.994186)
		(stroke
			(width 0.508)
			(type default)
		)
		(layer "In9.Cu")
	)
	(gr_line
		(start 70.779386 -329.632564)
		(end 74.462386 -325.949564)
		(stroke
			(width 0.508)
			(type default)
		)
		(layer "In9.Cu")
	)
	(gr_circle
		(center 70.78345 -174.442374)
		(end 71.67245 -174.442374)
		(stroke
			(width 0.2)
			(type default)
		)
		(fill no)
		(layer "In9.Cu")
	)
	(gr_circle
		(center 70.80885 -175.204374)
		(end 71.69785 -175.204374)
		(stroke
			(width 0.2)
			(type default)
		)
		(fill no)
		(layer "In9.Cu")
	)
	(gr_circle
		(center 71.099934 -336.988404)
		(end 71.980044 -336.988404)
		(stroke
			(width 0.2)
			(type default)
		)
		(fill no)
		(layer "In9.Cu")
	)
	(gr_circle
		(center 71.333614 -174.764954)
		(end 72.222614 -174.764954)
		(stroke
			(width 0.2)
			(type default)
		)
		(fill no)
		(layer "In9.Cu")
	)
	(gr_circle
		(center 71.333614 -174.028354)
		(end 72.222614 -174.028354)
		(stroke
			(width 0.2)
			(type default)
		)
		(fill no)
		(layer "In9.Cu")
	)
	(gr_line
		(start 71.70293 -387.280912)
		(end 69.75602 -387.280912)
		(stroke
			(width 0.508)
			(type default)
		)
		(layer "In9.Cu")
	)
	(gr_circle
		(center 71.717154 -336.988404)
		(end 72.597264 -336.988404)
		(stroke
			(width 0.2)
			(type default)
		)
		(fill no)
		(layer "In9.Cu")
	)
	(gr_line
		(start 71.830692 -186.179714)
		(end 69.636386 -183.985408)
		(stroke
			(width 0.508)
			(type default)
		)
		(layer "In9.Cu")
	)
	(gr_circle
		(center 71.892668 -177.10912)
		(end 72.781668 -177.10912)
		(stroke
			(width 0.2)
			(type default)
		)
		(fill no)
		(layer "In9.Cu")
	)
	(gr_circle
		(center 71.892668 -176.37252)
		(end 72.781668 -176.37252)
		(stroke
			(width 0.2)
			(type default)
		)
		(fill no)
		(layer "In9.Cu")
	)
	(gr_circle
		(center 72.03567 -175.639222)
		(end 72.91578 -175.639222)
		(stroke
			(width 0.2)
			(type default)
		)
		(fill no)
		(layer "In9.Cu")
	)
	(gr_circle
		(center 72.334374 -336.988404)
		(end 73.214484 -336.988404)
		(stroke
			(width 0.2)
			(type default)
		)
		(fill no)
		(layer "In9.Cu")
	)
	(gr_circle
		(center 72.616314 -336.255868)
		(end 73.496424 -336.255868)
		(stroke
			(width 0.2)
			(type default)
		)
		(fill no)
		(layer "In9.Cu")
	)
	(gr_circle
		(center 72.616314 -335.519268)
		(end 73.496424 -335.519268)
		(stroke
			(width 0.2)
			(type default)
		)
		(fill no)
		(layer "In9.Cu")
	)
	(gr_circle
		(center 72.65289 -175.639222)
		(end 73.533 -175.639222)
		(stroke
			(width 0.2)
			(type default)
		)
		(fill no)
		(layer "In9.Cu")
	)
	(gr_circle
		(center 73.03643 -338.597494)
		(end 73.92543 -338.597494)
		(stroke
			(width 0.2)
			(type default)
		)
		(fill no)
		(layer "In9.Cu")
	)
	(gr_circle
		(center 73.03643 -337.860894)
		(end 73.92543 -337.860894)
		(stroke
			(width 0.2)
			(type default)
		)
		(fill no)
		(layer "In9.Cu")
	)
	(gr_circle
		(center 73.27011 -175.639222)
		(end 74.15022 -175.639222)
		(stroke
			(width 0.2)
			(type default)
		)
		(fill no)
		(layer "In9.Cu")
	)
	(gr_line
		(start 73.278746 -385.705096)
		(end 71.70293 -387.280912)
		(stroke
			(width 0.508)
			(type default)
		)
		(layer "In9.Cu")
	)
	(gr_line
		(start 73.278746 -384.41249)
		(end 73.278746 -385.705096)
		(stroke
			(width 0.508)
			(type default)
		)
		(layer "In9.Cu")
	)
	(gr_circle
		(center 73.561194 -337.421474)
		(end 74.450194 -337.421474)
		(stroke
			(width 0.2)
			(type default)
		)
		(fill no)
		(layer "In9.Cu")
	)
	(gr_circle
		(center 73.586594 -338.183474)
		(end 74.475594 -338.183474)
		(stroke
			(width 0.2)
			(type default)
		)
		(fill no)
		(layer "In9.Cu")
	)
	(gr_line
		(start 73.753726 -186.179714)
		(end 71.830692 -186.179714)
		(stroke
			(width 0.508)
			(type default)
		)
		(layer "In9.Cu")
	)
	(gr_line
		(start 73.979278 -383.711958)
		(end 73.278746 -384.41249)
		(stroke
			(width 0.508)
			(type default)
		)
		(layer "In9.Cu")
	)
	(gr_circle
		(center 74.119994 -338.539074)
		(end 75.008994 -338.539074)
		(stroke
			(width 0.2)
			(type default)
		)
		(fill no)
		(layer "In9.Cu")
	)
	(gr_circle
		(center 74.119994 -337.802474)
		(end 75.008994 -337.802474)
		(stroke
			(width 0.2)
			(type default)
		)
		(fill no)
		(layer "In9.Cu")
	)
	(gr_circle
		(center 74.119994 -337.065874)
		(end 75.008994 -337.065874)
		(stroke
			(width 0.2)
			(type default)
		)
		(fill no)
		(layer "In9.Cu")
	)
	(gr_circle
		(center 74.811382 -351.637854)
		(end 75.700382 -351.637854)
		(stroke
			(width 0.2)
			(type default)
		)
		(fill no)
		(layer "In9.Cu")
	)
	(gr_circle
		(center 74.849482 -353.131374)
		(end 75.738482 -353.131374)
		(stroke
			(width 0.2)
			(type default)
		)
		(fill no)
		(layer "In9.Cu")
	)
	(gr_circle
		(center 74.849736 -352.30816)
		(end 75.738736 -352.30816)
		(stroke
			(width 0.2)
			(type default)
		)
		(fill no)
		(layer "In9.Cu")
	)
	(gr_circle
		(center 74.86015 -350.929448)
		(end 75.74915 -350.929448)
		(stroke
			(width 0.2)
			(type default)
		)
		(fill no)
		(layer "In9.Cu")
	)
	(gr_line
		(start 76.484988 -153.002488)
		(end 81.438496 -157.955996)
		(stroke
			(width 0.508)
			(type default)
		)
		(layer "In9.Cu")
	)
	(gr_line
		(start 76.748386 -219.269564)
		(end 60.12688 -202.648058)
		(stroke
			(width 0.508)
			(type default)
		)
		(layer "In9.Cu")
	)
	(gr_circle
		(center 77.178408 -16.520668)
		(end 78.067408 -16.520668)
		(stroke
			(width 0.2)
			(type default)
		)
		(fill no)
		(layer "In9.Cu")
	)
	(gr_circle
		(center 77.473048 -351.5995)
		(end 78.362048 -351.5995)
		(stroke
			(width 0.2)
			(type default)
		)
		(fill no)
		(layer "In9.Cu")
	)
	(gr_circle
		(center 77.511402 -352.978212)
		(end 78.400402 -352.978212)
		(stroke
			(width 0.2)
			(type default)
		)
		(fill no)
		(layer "In9.Cu")
	)
	(gr_circle
		(center 77.511402 -352.269806)
		(end 78.400402 -352.269806)
		(stroke
			(width 0.2)
			(type default)
		)
		(fill no)
		(layer "In9.Cu")
	)
	(gr_circle
		(center 77.521816 -350.891094)
		(end 78.410816 -350.891094)
		(stroke
			(width 0.2)
			(type default)
		)
		(fill no)
		(layer "In9.Cu")
	)
	(gr_circle
		(center 77.84338 -16.55064)
		(end 78.73238 -16.55064)
		(stroke
			(width 0.2)
			(type default)
		)
		(fill no)
		(layer "In9.Cu")
	)
	(gr_line
		(start 78.573884 -190.999872)
		(end 73.753726 -186.179714)
		(stroke
			(width 0.508)
			(type default)
		)
		(layer "In9.Cu")
	)
	(gr_circle
		(center 78.85303 -178.798474)
		(end 79.74203 -178.798474)
		(stroke
			(width 0.2)
			(type default)
		)
		(fill no)
		(layer "In9.Cu")
	)
	(gr_circle
		(center 78.85303 -178.036474)
		(end 79.74203 -178.036474)
		(stroke
			(width 0.2)
			(type default)
		)
		(fill no)
		(layer "In9.Cu")
	)
	(gr_line
		(start 79.024734 -354.5586)
		(end 81.81213 -351.771204)
		(stroke
			(width 0.508)
			(type default)
		)
		(layer "In9.Cu")
	)
	(gr_circle
		(center 79.10703 -179.560474)
		(end 79.99603 -179.560474)
		(stroke
			(width 0.2)
			(type default)
		)
		(fill no)
		(layer "In9.Cu")
	)
	(gr_circle
		(center 79.13243 -180.322474)
		(end 80.02143 -180.322474)
		(stroke
			(width 0.2)
			(type default)
		)
		(fill no)
		(layer "In9.Cu")
	)
	(gr_line
		(start 79.177896 -295.95826)
		(end 92.33789 -295.95826)
		(stroke
			(width 0.254)
			(type default)
		)
		(layer "In9.Cu")
	)
	(gr_circle
		(center 79.403194 -178.384454)
		(end 80.292194 -178.384454)
		(stroke
			(width 0.2)
			(type default)
		)
		(fill no)
		(layer "In9.Cu")
	)
	(gr_circle
		(center 79.455518 -336.981292)
		(end 80.335628 -336.981292)
		(stroke
			(width 0.2)
			(type default)
		)
		(fill no)
		(layer "In9.Cu")
	)
	(gr_circle
		(center 79.657194 -179.883054)
		(end 80.546194 -179.883054)
		(stroke
			(width 0.2)
			(type default)
		)
		(fill no)
		(layer "In9.Cu")
	)
	(gr_circle
		(center 79.657194 -179.146454)
		(end 80.546194 -179.146454)
		(stroke
			(width 0.2)
			(type default)
		)
		(fill no)
		(layer "In9.Cu")
	)
	(gr_line
		(start 79.817976 -226.662234)
		(end 86.946486 -226.662234)
		(stroke
			(width 0.254)
			(type default)
		)
		(layer "In9.Cu")
	)
	(gr_circle
		(center 79.921862 -18.238724)
		(end 80.810862 -18.238724)
		(stroke
			(width 0.2)
			(type default)
		)
		(fill no)
		(layer "In9.Cu")
	)
	(gr_circle
		(center 79.921862 -17.502124)
		(end 80.810862 -17.502124)
		(stroke
			(width 0.2)
			(type default)
		)
		(fill no)
		(layer "In9.Cu")
	)
	(gr_circle
		(center 80.072738 -336.981292)
		(end 80.952848 -336.981292)
		(stroke
			(width 0.2)
			(type default)
		)
		(fill no)
		(layer "In9.Cu")
	)
	(gr_circle
		(center 80.241648 -182.2196)
		(end 81.130648 -182.2196)
		(stroke
			(width 0.2)
			(type default)
		)
		(fill no)
		(layer "In9.Cu")
	)
	(gr_circle
		(center 80.241648 -181.483)
		(end 81.130648 -181.483)
		(stroke
			(width 0.2)
			(type default)
		)
		(fill no)
		(layer "In9.Cu")
	)
	(gr_circle
		(center 80.35925 -180.755544)
		(end 81.23936 -180.755544)
		(stroke
			(width 0.2)
			(type default)
		)
		(fill no)
		(layer "In9.Cu")
	)
	(gr_circle
		(center 80.689958 -336.981292)
		(end 81.570068 -336.981292)
		(stroke
			(width 0.2)
			(type default)
		)
		(fill no)
		(layer "In9.Cu")
	)
	(gr_circle
		(center 80.97647 -180.755544)
		(end 81.85658 -180.755544)
		(stroke
			(width 0.2)
			(type default)
		)
		(fill no)
		(layer "In9.Cu")
	)
	(gr_circle
		(center 80.977994 -336.245708)
		(end 81.858104 -336.245708)
		(stroke
			(width 0.2)
			(type default)
		)
		(fill no)
		(layer "In9.Cu")
	)
	(gr_circle
		(center 80.977994 -335.509108)
		(end 81.858104 -335.509108)
		(stroke
			(width 0.2)
			(type default)
		)
		(fill no)
		(layer "In9.Cu")
	)
	(gr_circle
		(center 81.392014 -338.590382)
		(end 82.281014 -338.590382)
		(stroke
			(width 0.2)
			(type default)
		)
		(fill no)
		(layer "In9.Cu")
	)
	(gr_circle
		(center 81.392014 -337.853782)
		(end 82.281014 -337.853782)
		(stroke
			(width 0.2)
			(type default)
		)
		(fill no)
		(layer "In9.Cu")
	)
	(gr_line
		(start 81.438496 -157.955996)
		(end 91.976956 -157.955996)
		(stroke
			(width 0.508)
			(type default)
		)
		(layer "In9.Cu")
	)
	(gr_circle
		(center 81.59369 -180.755544)
		(end 82.4738 -180.755544)
		(stroke
			(width 0.2)
			(type default)
		)
		(fill no)
		(layer "In9.Cu")
	)
	(gr_arc
		(start 81.701894 -9.780016)
		(mid 82.287679 -11.194227)
		(end 83.70189 -11.780012)
		(stroke
			(width 3.048)
			(type default)
		)
		(layer "In9.Cu")
	)
	(gr_arc
		(start 81.701894 -0.500126)
		(mid 81.555625 -0.146451)
		(end 81.202022 0)
		(stroke
			(width 3.048)
			(type default)
		)
		(layer "In9.Cu")
	)
	(gr_line
		(start 81.701894 -0.500126)
		(end 81.701894 -9.780016)
		(stroke
			(width 3.048)
			(type default)
		)
		(layer "In9.Cu")
	)
	(gr_line
		(start 81.81213 -351.771204)
		(end 85.084412 -351.771204)
		(stroke
			(width 0.508)
			(type default)
		)
		(layer "In9.Cu")
	)
	(gr_circle
		(center 81.916778 -337.414362)
		(end 82.805778 -337.414362)
		(stroke
			(width 0.2)
			(type default)
		)
		(fill no)
		(layer "In9.Cu")
	)
	(gr_circle
		(center 81.942178 -338.176362)
		(end 82.831178 -338.176362)
		(stroke
			(width 0.2)
			(type default)
		)
		(fill no)
		(layer "In9.Cu")
	)
	(gr_circle
		(center 82.183986 -348.89948)
		(end 83.072986 -348.89948)
		(stroke
			(width 0.2)
			(type default)
		)
		(fill no)
		(layer "In9.Cu")
	)
	(gr_circle
		(center 82.222086 -350.393)
		(end 83.111086 -350.393)
		(stroke
			(width 0.2)
			(type default)
		)
		(fill no)
		(layer "In9.Cu")
	)
	(gr_circle
		(center 82.22234 -349.569786)
		(end 83.11134 -349.569786)
		(stroke
			(width 0.2)
			(type default)
		)
		(fill no)
		(layer "In9.Cu")
	)
	(gr_circle
		(center 82.232754 -348.191074)
		(end 83.121754 -348.191074)
		(stroke
			(width 0.2)
			(type default)
		)
		(fill no)
		(layer "In9.Cu")
	)
	(gr_circle
		(center 82.475578 -338.531962)
		(end 83.364578 -338.531962)
		(stroke
			(width 0.2)
			(type default)
		)
		(fill no)
		(layer "In9.Cu")
	)
	(gr_circle
		(center 82.475578 -337.795362)
		(end 83.364578 -337.795362)
		(stroke
			(width 0.2)
			(type default)
		)
		(fill no)
		(layer "In9.Cu")
	)
	(gr_circle
		(center 82.475578 -337.058762)
		(end 83.364578 -337.058762)
		(stroke
			(width 0.2)
			(type default)
		)
		(fill no)
		(layer "In9.Cu")
	)
	(gr_circle
		(center 82.989674 -165.962076)
		(end 84.386674 -165.962076)
		(stroke
			(width 0.2)
			(type default)
		)
		(fill no)
		(layer "In9.Cu")
	)
	(gr_line
		(start 83.70189 -11.780012)
		(end 124.102114 -11.780012)
		(stroke
			(width 3.048)
			(type default)
		)
		(layer "In9.Cu")
	)
	(gr_line
		(start 84.622386 -219.269564)
		(end 76.748386 -219.269564)
		(stroke
			(width 0.508)
			(type default)
		)
		(layer "In9.Cu")
	)
	(gr_circle
		(center 84.845652 -348.861126)
		(end 85.734652 -348.861126)
		(stroke
			(width 0.2)
			(type default)
		)
		(fill no)
		(layer "In9.Cu")
	)
	(gr_circle
		(center 84.884006 -350.239838)
		(end 85.773006 -350.239838)
		(stroke
			(width 0.2)
			(type default)
		)
		(fill no)
		(layer "In9.Cu")
	)
	(gr_circle
		(center 84.884006 -349.531432)
		(end 85.773006 -349.531432)
		(stroke
			(width 0.2)
			(type default)
		)
		(fill no)
		(layer "In9.Cu")
	)
	(gr_circle
		(center 84.89442 -348.15272)
		(end 85.78342 -348.15272)
		(stroke
			(width 0.2)
			(type default)
		)
		(fill no)
		(layer "In9.Cu")
	)
	(gr_line
		(start 85.084412 -351.771204)
		(end 87.043514 -349.812102)
		(stroke
			(width 0.508)
			(type default)
		)
		(layer "In9.Cu")
	)
	(gr_line
		(start 86.228682 -383.711958)
		(end 73.979278 -383.711958)
		(stroke
			(width 0.508)
			(type default)
		)
		(layer "In9.Cu")
	)
	(gr_line
		(start 86.606126 -387.797802)
		(end 86.606126 -384.089402)
		(stroke
			(width 0.508)
			(type default)
		)
		(layer "In9.Cu")
	)
	(gr_line
		(start 86.606126 -384.089402)
		(end 86.228682 -383.711958)
		(stroke
			(width 0.508)
			(type default)
		)
		(layer "In9.Cu")
	)
	(gr_line
		(start 86.606126 -384.089402)
		(end 86.606126 -383.99466)
		(stroke
			(width 0.508)
			(type default)
		)
		(layer "In9.Cu")
	)
	(gr_line
		(start 86.606126 -383.99466)
		(end 87.065866 -383.53492)
		(stroke
			(width 0.508)
			(type default)
		)
		(layer "In9.Cu")
	)
	(gr_line
		(start 86.946486 -226.662234)
		(end 87.503762 -227.21951)
		(stroke
			(width 0.254)
			(type default)
		)
		(layer "In9.Cu")
	)
	(gr_circle
		(center 86.97087 -180.610002)
		(end 87.85987 -180.610002)
		(stroke
			(width 0.2)
			(type default)
		)
		(fill no)
		(layer "In9.Cu")
	)
	(gr_circle
		(center 86.97087 -179.873402)
		(end 87.85987 -179.873402)
		(stroke
			(width 0.2)
			(type default)
		)
		(fill no)
		(layer "In9.Cu")
	)
	(gr_circle
		(center 86.97087 -179.136802)
		(end 87.85987 -179.136802)
		(stroke
			(width 0.2)
			(type default)
		)
		(fill no)
		(layer "In9.Cu")
	)
	(gr_circle
		(center 87.01913 -164.097716)
		(end 87.90813 -164.097716)
		(stroke
			(width 0.2)
			(type default)
		)
		(fill no)
		(layer "In9.Cu")
	)
	(gr_circle
		(center 87.03945 -163.447476)
		(end 87.92845 -163.447476)
		(stroke
			(width 0.2)
			(type default)
		)
		(fill no)
		(layer "In9.Cu")
	)
	(gr_circle
		(center 87.03945 -162.812476)
		(end 87.92845 -162.812476)
		(stroke
			(width 0.2)
			(type default)
		)
		(fill no)
		(layer "In9.Cu")
	)
	(gr_line
		(start 87.042752 -388.234428)
		(end 86.606126 -387.797802)
		(stroke
			(width 0.508)
			(type default)
		)
		(layer "In9.Cu")
	)
	(gr_line
		(start 87.043514 -349.812102)
		(end 108.388658 -349.812102)
		(stroke
			(width 0.508)
			(type default)
		)
		(layer "In9.Cu")
	)
	(gr_line
		(start 87.065866 -383.53492)
		(end 102.181406 -383.53492)
		(stroke
			(width 0.508)
			(type default)
		)
		(layer "In9.Cu")
	)
	(gr_line
		(start 87.503762 -255.164082)
		(end 88.974422 -256.634742)
		(stroke
			(width 0.254)
			(type default)
		)
		(layer "In9.Cu")
	)
	(gr_line
		(start 87.503762 -227.21951)
		(end 87.503762 -255.164082)
		(stroke
			(width 0.254)
			(type default)
		)
		(layer "In9.Cu")
	)
	(gr_circle
		(center 87.50427 -179.492402)
		(end 88.39327 -179.492402)
		(stroke
			(width 0.2)
			(type default)
		)
		(fill no)
		(layer "In9.Cu")
	)
	(gr_circle
		(center 87.52967 -180.254402)
		(end 88.41867 -180.254402)
		(stroke
			(width 0.2)
			(type default)
		)
		(fill no)
		(layer "In9.Cu")
	)
	(gr_circle
		(center 87.65413 -164.097716)
		(end 88.54313 -164.097716)
		(stroke
			(width 0.2)
			(type default)
		)
		(fill no)
		(layer "In9.Cu")
	)
	(gr_circle
		(center 87.67445 -163.447476)
		(end 88.56345 -163.447476)
		(stroke
			(width 0.2)
			(type default)
		)
		(fill no)
		(layer "In9.Cu")
	)
	(gr_circle
		(center 87.67445 -162.812476)
		(end 88.56345 -162.812476)
		(stroke
			(width 0.2)
			(type default)
		)
		(fill no)
		(layer "In9.Cu")
	)
	(gr_circle
		(center 87.813134 -336.966814)
		(end 88.693244 -336.966814)
		(stroke
			(width 0.2)
			(type default)
		)
		(fill no)
		(layer "In9.Cu")
	)
	(gr_circle
		(center 88.054434 -179.814982)
		(end 88.943434 -179.814982)
		(stroke
			(width 0.2)
			(type default)
		)
		(fill no)
		(layer "In9.Cu")
	)
	(gr_circle
		(center 88.054434 -179.078382)
		(end 88.943434 -179.078382)
		(stroke
			(width 0.2)
			(type default)
		)
		(fill no)
		(layer "In9.Cu")
	)
	(gr_circle
		(center 88.28913 -164.097716)
		(end 89.17813 -164.097716)
		(stroke
			(width 0.2)
			(type default)
		)
		(fill no)
		(layer "In9.Cu")
	)
	(gr_circle
		(center 88.30945 -163.447476)
		(end 89.19845 -163.447476)
		(stroke
			(width 0.2)
			(type default)
		)
		(fill no)
		(layer "In9.Cu")
	)
	(gr_circle
		(center 88.30945 -162.812476)
		(end 89.19845 -162.812476)
		(stroke
			(width 0.2)
			(type default)
		)
		(fill no)
		(layer "In9.Cu")
	)
	(gr_circle
		(center 88.430354 -336.966814)
		(end 89.310464 -336.966814)
		(stroke
			(width 0.2)
			(type default)
		)
		(fill no)
		(layer "In9.Cu")
	)
	(gr_circle
		(center 88.49233 -182.13324)
		(end 89.38133 -182.13324)
		(stroke
			(width 0.2)
			(type default)
		)
		(fill no)
		(layer "In9.Cu")
	)
	(gr_circle
		(center 88.49233 -181.39664)
		(end 89.38133 -181.39664)
		(stroke
			(width 0.2)
			(type default)
		)
		(fill no)
		(layer "In9.Cu")
	)
	(gr_circle
		(center 88.75649 -180.687472)
		(end 89.6366 -180.687472)
		(stroke
			(width 0.2)
			(type default)
		)
		(fill no)
		(layer "In9.Cu")
	)
	(gr_circle
		(center 88.92413 -164.097716)
		(end 89.81313 -164.097716)
		(stroke
			(width 0.2)
			(type default)
		)
		(fill no)
		(layer "In9.Cu")
	)
	(gr_circle
		(center 88.94445 -163.447476)
		(end 89.83345 -163.447476)
		(stroke
			(width 0.2)
			(type default)
		)
		(fill no)
		(layer "In9.Cu")
	)
	(gr_circle
		(center 88.94445 -162.812476)
		(end 89.83345 -162.812476)
		(stroke
			(width 0.2)
			(type default)
		)
		(fill no)
		(layer "In9.Cu")
	)
	(gr_line
		(start 88.974422 -256.634742)
		(end 95.331026 -256.634488)
		(stroke
			(width 0.254)
			(type default)
		)
		(layer "In9.Cu")
	)
	(gr_circle
		(center 89.047574 -336.966814)
		(end 89.927684 -336.966814)
		(stroke
			(width 0.2)
			(type default)
		)
		(fill no)
		(layer "In9.Cu")
	)
	(gr_circle
		(center 89.314528 -345.237562)
		(end 90.203528 -345.237562)
		(stroke
			(width 0.2)
			(type default)
		)
		(fill no)
		(layer "In9.Cu")
	)
	(gr_circle
		(center 89.319354 -336.255868)
		(end 90.199464 -336.255868)
		(stroke
			(width 0.2)
			(type default)
		)
		(fill no)
		(layer "In9.Cu")
	)
	(gr_circle
		(center 89.319354 -335.519268)
		(end 90.199464 -335.519268)
		(stroke
			(width 0.2)
			(type default)
		)
		(fill no)
		(layer "In9.Cu")
	)
	(gr_circle
		(center 89.350088 -345.96959)
		(end 90.239088 -345.96959)
		(stroke
			(width 0.2)
			(type default)
		)
		(fill no)
		(layer "In9.Cu")
	)
	(gr_circle
		(center 89.37371 -180.687472)
		(end 90.25382 -180.687472)
		(stroke
			(width 0.2)
			(type default)
		)
		(fill no)
		(layer "In9.Cu")
	)
	(gr_circle
		(center 89.388442 -346.639896)
		(end 90.277442 -346.639896)
		(stroke
			(width 0.2)
			(type default)
		)
		(fill no)
		(layer "In9.Cu")
	)
	(gr_circle
		(center 89.55913 -164.097716)
		(end 90.44813 -164.097716)
		(stroke
			(width 0.2)
			(type default)
		)
		(fill no)
		(layer "In9.Cu")
	)
	(gr_circle
		(center 89.57945 -163.447476)
		(end 90.46845 -163.447476)
		(stroke
			(width 0.2)
			(type default)
		)
		(fill no)
		(layer "In9.Cu")
	)
	(gr_circle
		(center 89.57945 -162.812476)
		(end 90.46845 -162.812476)
		(stroke
			(width 0.2)
			(type default)
		)
		(fill no)
		(layer "In9.Cu")
	)
	(gr_circle
		(center 89.74963 -338.575904)
		(end 90.63863 -338.575904)
		(stroke
			(width 0.2)
			(type default)
		)
		(fill no)
		(layer "In9.Cu")
	)
	(gr_circle
		(center 89.74963 -337.839304)
		(end 90.63863 -337.839304)
		(stroke
			(width 0.2)
			(type default)
		)
		(fill no)
		(layer "In9.Cu")
	)
	(gr_circle
		(center 89.983056 -345.261184)
		(end 90.872056 -345.261184)
		(stroke
			(width 0.2)
			(type default)
		)
		(fill no)
		(layer "In9.Cu")
	)
	(gr_circle
		(center 89.985088 -345.96959)
		(end 90.874088 -345.96959)
		(stroke
			(width 0.2)
			(type default)
		)
		(fill no)
		(layer "In9.Cu")
	)
	(gr_circle
		(center 89.99093 -180.687472)
		(end 90.87104 -180.687472)
		(stroke
			(width 0.2)
			(type default)
		)
		(fill no)
		(layer "In9.Cu")
	)
	(gr_circle
		(center 90.023442 -346.639896)
		(end 90.912442 -346.639896)
		(stroke
			(width 0.2)
			(type default)
		)
		(fill no)
		(layer "In9.Cu")
	)
	(gr_line
		(start 90.030554 -388.234428)
		(end 87.042752 -388.234428)
		(stroke
			(width 0.508)
			(type default)
		)
		(layer "In9.Cu")
	)
	(gr_circle
		(center 90.21953 -164.107876)
		(end 91.10853 -164.107876)
		(stroke
			(width 0.2)
			(type default)
		)
		(fill no)
		(layer "In9.Cu")
	)
	(gr_circle
		(center 90.23985 -163.457636)
		(end 91.12885 -163.457636)
		(stroke
			(width 0.2)
			(type default)
		)
		(fill no)
		(layer "In9.Cu")
	)
	(gr_circle
		(center 90.23985 -162.822636)
		(end 91.12885 -162.822636)
		(stroke
			(width 0.2)
			(type default)
		)
		(fill no)
		(layer "In9.Cu")
	)
	(gr_circle
		(center 90.274394 -337.399884)
		(end 91.163394 -337.399884)
		(stroke
			(width 0.2)
			(type default)
		)
		(fill no)
		(layer "In9.Cu")
	)
	(gr_circle
		(center 90.299794 -338.161884)
		(end 91.188794 -338.161884)
		(stroke
			(width 0.2)
			(type default)
		)
		(fill no)
		(layer "In9.Cu")
	)
	(gr_circle
		(center 90.618056 -345.261184)
		(end 91.507056 -345.261184)
		(stroke
			(width 0.2)
			(type default)
		)
		(fill no)
		(layer "In9.Cu")
	)
	(gr_circle
		(center 90.620088 -345.96959)
		(end 91.509088 -345.96959)
		(stroke
			(width 0.2)
			(type default)
		)
		(fill no)
		(layer "In9.Cu")
	)
	(gr_circle
		(center 90.658442 -346.639896)
		(end 91.547442 -346.639896)
		(stroke
			(width 0.2)
			(type default)
		)
		(fill no)
		(layer "In9.Cu")
	)
	(gr_circle
		(center 90.833194 -338.517484)
		(end 91.722194 -338.517484)
		(stroke
			(width 0.2)
			(type default)
		)
		(fill no)
		(layer "In9.Cu")
	)
	(gr_circle
		(center 90.833194 -337.780884)
		(end 91.722194 -337.780884)
		(stroke
			(width 0.2)
			(type default)
		)
		(fill no)
		(layer "In9.Cu")
	)
	(gr_circle
		(center 90.833194 -337.044284)
		(end 91.722194 -337.044284)
		(stroke
			(width 0.2)
			(type default)
		)
		(fill no)
		(layer "In9.Cu")
	)
	(gr_circle
		(center 91.255088 -345.96959)
		(end 92.144088 -345.96959)
		(stroke
			(width 0.2)
			(type default)
		)
		(fill no)
		(layer "In9.Cu")
	)
	(gr_circle
		(center 91.293442 -346.639896)
		(end 92.182442 -346.639896)
		(stroke
			(width 0.2)
			(type default)
		)
		(fill no)
		(layer "In9.Cu")
	)
	(gr_circle
		(center 91.380056 -345.261184)
		(end 92.269056 -345.261184)
		(stroke
			(width 0.2)
			(type default)
		)
		(fill no)
		(layer "In9.Cu")
	)
	(gr_line
		(start 91.731084 -386.533898)
		(end 90.030554 -388.234428)
		(stroke
			(width 0.508)
			(type default)
		)
		(layer "In9.Cu")
	)
	(gr_circle
		(center 91.966288 -345.96959)
		(end 92.855288 -345.96959)
		(stroke
			(width 0.2)
			(type default)
		)
		(fill no)
		(layer "In9.Cu")
	)
	(gr_line
		(start 91.976956 -157.955996)
		(end 106.856276 -143.076676)
		(stroke
			(width 0.508)
			(type default)
		)
		(layer "In9.Cu")
	)
	(gr_circle
		(center 92.004642 -346.639896)
		(end 92.893642 -346.639896)
		(stroke
			(width 0.2)
			(type default)
		)
		(fill no)
		(layer "In9.Cu")
	)
	(gr_circle
		(center 92.015056 -345.261184)
		(end 92.904056 -345.261184)
		(stroke
			(width 0.2)
			(type default)
		)
		(fill no)
		(layer "In9.Cu")
	)
	(gr_line
		(start 92.33789 -295.95826)
		(end 92.808044 -295.148254)
		(stroke
			(width 0.254)
			(type default)
		)
		(layer "In9.Cu")
	)
	(gr_circle
		(center 92.387674 -165.962076)
		(end 93.784674 -165.962076)
		(stroke
			(width 0.2)
			(type default)
		)
		(fill no)
		(layer "In9.Cu")
	)
	(gr_line
		(start 92.420694 -386.533898)
		(end 91.731084 -386.533898)
		(stroke
			(width 0.508)
			(type default)
		)
		(layer "In9.Cu")
	)
	(gr_line
		(start 92.496386 -219.269564)
		(end 84.622386 -219.269564)
		(stroke
			(width 0.254)
			(type default)
		)
		(layer "In9.Cu")
	)
	(gr_circle
		(center 92.601288 -345.96959)
		(end 93.490288 -345.96959)
		(stroke
			(width 0.2)
			(type default)
		)
		(fill no)
		(layer "In9.Cu")
	)
	(gr_circle
		(center 92.639642 -346.639896)
		(end 93.528642 -346.639896)
		(stroke
			(width 0.2)
			(type default)
		)
		(fill no)
		(layer "In9.Cu")
	)
	(gr_circle
		(center 92.650056 -345.261184)
		(end 93.539056 -345.261184)
		(stroke
			(width 0.2)
			(type default)
		)
		(fill no)
		(layer "In9.Cu")
	)
	(gr_line
		(start 93.004386 -223.752156)
		(end 93.004386 -222.317564)
		(stroke
			(width 0.254)
			(type default)
		)
		(layer "In9.Cu")
	)
	(gr_line
		(start 93.004386 -222.317564)
		(end 93.131386 -222.190564)
		(stroke
			(width 0.254)
			(type default)
		)
		(layer "In9.Cu")
	)
	(gr_line
		(start 93.110812 -223.858582)
		(end 93.004386 -223.752156)
		(stroke
			(width 0.254)
			(type default)
		)
		(layer "In9.Cu")
	)
	(gr_line
		(start 93.131386 -222.190564)
		(end 93.131386 -219.904564)
		(stroke
			(width 0.254)
			(type default)
		)
		(layer "In9.Cu")
	)
	(gr_line
		(start 93.131386 -219.904564)
		(end 92.496386 -219.269564)
		(stroke
			(width 0.254)
			(type default)
		)
		(layer "In9.Cu")
	)
	(gr_line
		(start 93.747844 -293.528242)
		(end 92.808044 -295.148254)
		(stroke
			(width 0.254)
			(type default)
		)
		(layer "In9.Cu")
	)
	(gr_line
		(start 93.805248 -387.918452)
		(end 92.420694 -386.533898)
		(stroke
			(width 0.508)
			(type default)
		)
		(layer "In9.Cu")
	)
	(gr_line
		(start 94.687898 -293.528242)
		(end 93.747844 -293.528242)
		(stroke
			(width 0.254)
			(type default)
		)
		(layer "In9.Cu")
	)
	(gr_line
		(start 94.873826 -162.19551)
		(end 60.598558 -162.19551)
		(stroke
			(width 0.508)
			(type default)
		)
		(layer "In9.Cu")
	)
	(gr_line
		(start 95.157798 -292.718236)
		(end 94.687898 -293.528242)
		(stroke
			(width 0.254)
			(type default)
		)
		(layer "In9.Cu")
	)
	(gr_line
		(start 95.331026 -256.634488)
		(end 95.800926 -255.824482)
		(stroke
			(width 0.254)
			(type default)
		)
		(layer "In9.Cu")
	)
	(gr_circle
		(center 95.36303 -180.627274)
		(end 96.25203 -180.627274)
		(stroke
			(width 0.2)
			(type default)
		)
		(fill no)
		(layer "In9.Cu")
	)
	(gr_circle
		(center 95.36303 -179.890674)
		(end 96.25203 -179.890674)
		(stroke
			(width 0.2)
			(type default)
		)
		(fill no)
		(layer "In9.Cu")
	)
	(gr_circle
		(center 95.36303 -179.154074)
		(end 96.25203 -179.154074)
		(stroke
			(width 0.2)
			(type default)
		)
		(fill no)
		(layer "In9.Cu")
	)
	(gr_line
		(start 95.627952 -291.90823)
		(end 95.157798 -292.718236)
		(stroke
			(width 0.254)
			(type default)
		)
		(layer "In9.Cu")
	)
	(gr_line
		(start 95.800926 -255.824482)
		(end 97.211134 -256.634488)
		(stroke
			(width 0.254)
			(type default)
		)
		(layer "In9.Cu")
	)
	(gr_circle
		(center 95.89643 -179.509674)
		(end 96.78543 -179.509674)
		(stroke
			(width 0.2)
			(type default)
		)
		(fill no)
		(layer "In9.Cu")
	)
	(gr_circle
		(center 95.92183 -180.271674)
		(end 96.81083 -180.271674)
		(stroke
			(width 0.2)
			(type default)
		)
		(fill no)
		(layer "In9.Cu")
	)
	(gr_line
		(start 96.097852 -291.098224)
		(end 95.627952 -291.90823)
		(stroke
			(width 0.254)
			(type default)
		)
		(layer "In9.Cu")
	)
	(gr_circle
		(center 96.144334 -337.017614)
		(end 97.024444 -337.017614)
		(stroke
			(width 0.2)
			(type default)
		)
		(fill no)
		(layer "In9.Cu")
	)
	(gr_line
		(start 96.267778 -248.532396)
		(end 97.207832 -246.912384)
		(stroke
			(width 0.254)
			(type default)
		)
		(layer "In9.Cu")
	)
	(gr_line
		(start 96.267778 -245.292372)
		(end 97.207832 -243.67236)
		(stroke
			(width 0.254)
			(type default)
		)
		(layer "In9.Cu")
	)
	(gr_line
		(start 96.267778 -242.052348)
		(end 97.207832 -240.432336)
		(stroke
			(width 0.254)
			(type default)
		)
		(layer "In9.Cu")
	)
	(gr_line
		(start 96.267778 -238.812324)
		(end 97.677986 -238.002318)
		(stroke
			(width 0.254)
			(type default)
		)
		(layer "In9.Cu")
	)
	(gr_line
		(start 96.267778 -233.952288)
		(end 97.207832 -232.332276)
		(stroke
			(width 0.254)
			(type default)
		)
		(layer "In9.Cu")
	)
	(gr_line
		(start 96.306386 -325.949564)
		(end 74.462386 -325.949564)
		(stroke
			(width 0.508)
			(type default)
		)
		(layer "In9.Cu")
	)
	(gr_circle
		(center 96.446594 -179.832254)
		(end 97.335594 -179.832254)
		(stroke
			(width 0.2)
			(type default)
		)
		(fill no)
		(layer "In9.Cu")
	)
	(gr_circle
		(center 96.446594 -179.095654)
		(end 97.335594 -179.095654)
		(stroke
			(width 0.2)
			(type default)
		)
		(fill no)
		(layer "In9.Cu")
	)
	(gr_line
		(start 96.568006 -290.288472)
		(end 96.097852 -291.098224)
		(stroke
			(width 0.254)
			(type default)
		)
		(layer "In9.Cu")
	)
	(gr_line
		(start 96.568006 -287.048448)
		(end 97.507806 -288.66846)
		(stroke
			(width 0.254)
			(type default)
		)
		(layer "In9.Cu")
	)
	(gr_line
		(start 96.568006 -283.808424)
		(end 97.507806 -285.428436)
		(stroke
			(width 0.254)
			(type default)
		)
		(layer "In9.Cu")
	)
	(gr_line
		(start 96.568006 -278.948388)
		(end 97.97796 -279.758394)
		(stroke
			(width 0.254)
			(type default)
		)
		(layer "In9.Cu")
	)
	(gr_line
		(start 96.568006 -275.708364)
		(end 97.507806 -277.328376)
		(stroke
			(width 0.254)
			(type default)
		)
		(layer "In9.Cu")
	)
	(gr_line
		(start 96.568006 -272.46834)
		(end 97.507806 -274.088352)
		(stroke
			(width 0.254)
			(type default)
		)
		(layer "In9.Cu")
	)
	(gr_line
		(start 96.568006 -269.228316)
		(end 97.507806 -270.848328)
		(stroke
			(width 0.254)
			(type default)
		)
		(layer "In9.Cu")
	)
	(gr_line
		(start 96.737932 -236.382306)
		(end 97.207832 -235.5723)
		(stroke
			(width 0.254)
			(type default)
		)
		(layer "In9.Cu")
	)
	(gr_line
		(start 96.737932 -231.52227)
		(end 97.207832 -230.712264)
		(stroke
			(width 0.254)
			(type default)
		)
		(layer "In9.Cu")
	)
	(gr_line
		(start 96.737932 -229.902258)
		(end 97.207832 -229.092252)
		(stroke
			(width 0.254)
			(type default)
		)
		(layer "In9.Cu")
	)
	(gr_line
		(start 96.737932 -228.282246)
		(end 93.110812 -223.858582)
		(stroke
			(width 0.254)
			(type default)
		)
		(layer "In9.Cu")
	)
	(gr_circle
		(center 96.761554 -337.017614)
		(end 97.641664 -337.017614)
		(stroke
			(width 0.2)
			(type default)
		)
		(fill no)
		(layer "In9.Cu")
	)
	(gr_circle
		(center 96.980248 -182.13324)
		(end 97.869248 -182.13324)
		(stroke
			(width 0.2)
			(type default)
		)
		(fill no)
		(layer "In9.Cu")
	)
	(gr_circle
		(center 96.980248 -181.39664)
		(end 97.869248 -181.39664)
		(stroke
			(width 0.2)
			(type default)
		)
		(fill no)
		(layer "In9.Cu")
	)
	(gr_line
		(start 97.037906 -281.378406)
		(end 97.507806 -282.188412)
		(stroke
			(width 0.254)
			(type default)
		)
		(layer "In9.Cu")
	)
	(gr_circle
		(center 97.14865 -180.704744)
		(end 98.02876 -180.704744)
		(stroke
			(width 0.2)
			(type default)
		)
		(fill no)
		(layer "In9.Cu")
	)
	(gr_line
		(start 97.207832 -246.912384)
		(end 96.267778 -245.292372)
		(stroke
			(width 0.254)
			(type default)
		)
		(layer "In9.Cu")
	)
	(gr_line
		(start 97.207832 -243.67236)
		(end 96.267778 -242.052348)
		(stroke
			(width 0.254)
			(type default)
		)
		(layer "In9.Cu")
	)
	(gr_line
		(start 97.207832 -240.432336)
		(end 96.267778 -238.812324)
		(stroke
			(width 0.254)
			(type default)
		)
		(layer "In9.Cu")
	)
	(gr_line
		(start 97.207832 -235.5723)
		(end 96.267778 -233.952288)
		(stroke
			(width 0.254)
			(type default)
		)
		(layer "In9.Cu")
	)
	(gr_line
		(start 97.207832 -232.332276)
		(end 96.737932 -231.52227)
		(stroke
			(width 0.254)
			(type default)
		)
		(layer "In9.Cu")
	)
	(gr_line
		(start 97.207832 -230.712264)
		(end 96.737932 -229.902258)
		(stroke
			(width 0.254)
			(type default)
		)
		(layer "In9.Cu")
	)
	(gr_line
		(start 97.207832 -229.092252)
		(end 96.737932 -228.282246)
		(stroke
			(width 0.254)
			(type default)
		)
		(layer "In9.Cu")
	)
	(gr_line
		(start 97.211134 -256.634488)
		(end 97.681034 -255.824482)
		(stroke
			(width 0.254)
			(type default)
		)
		(layer "In9.Cu")
	)
	(gr_circle
		(center 97.378774 -337.017614)
		(end 98.258884 -337.017614)
		(stroke
			(width 0.2)
			(type default)
		)
		(fill no)
		(layer "In9.Cu")
	)
	(gr_line
		(start 97.507806 -288.66846)
		(end 96.568006 -290.288472)
		(stroke
			(width 0.254)
			(type default)
		)
		(layer "In9.Cu")
	)
	(gr_line
		(start 97.507806 -285.428436)
		(end 96.568006 -287.048448)
		(stroke
			(width 0.254)
			(type default)
		)
		(layer "In9.Cu")
	)
	(gr_line
		(start 97.507806 -282.188412)
		(end 96.568006 -283.808424)
		(stroke
			(width 0.254)
			(type default)
		)
		(layer "In9.Cu")
	)
	(gr_line
		(start 97.507806 -280.5684)
		(end 97.037906 -281.378406)
		(stroke
			(width 0.254)
			(type default)
		)
		(layer "In9.Cu")
	)
	(gr_line
		(start 97.507806 -277.328376)
		(end 96.568006 -278.948388)
		(stroke
			(width 0.254)
			(type default)
		)
		(layer "In9.Cu")
	)
	(gr_line
		(start 97.507806 -274.088352)
		(end 96.568006 -275.708364)
		(stroke
			(width 0.254)
			(type default)
		)
		(layer "In9.Cu")
	)
	(gr_line
		(start 97.507806 -270.848328)
		(end 96.568006 -272.46834)
		(stroke
			(width 0.254)
			(type default)
		)
		(layer "In9.Cu")
	)
	(gr_line
		(start 97.507806 -267.608304)
		(end 96.568006 -269.228316)
		(stroke
			(width 0.254)
			(type default)
		)
		(layer "In9.Cu")
	)
	(gr_circle
		(center 97.658174 -336.319368)
		(end 98.538284 -336.319368)
		(stroke
			(width 0.2)
			(type default)
		)
		(fill no)
		(layer "In9.Cu")
	)
	(gr_circle
		(center 97.658174 -335.582768)
		(end 98.538284 -335.582768)
		(stroke
			(width 0.2)
			(type default)
		)
		(fill no)
		(layer "In9.Cu")
	)
	(gr_line
		(start 97.677986 -249.342402)
		(end 96.267778 -248.532396)
		(stroke
			(width 0.254)
			(type default)
		)
		(layer "In9.Cu")
	)
	(gr_line
		(start 97.677986 -238.002318)
		(end 96.737932 -236.382306)
		(stroke
			(width 0.254)
			(type default)
		)
		(layer "In9.Cu")
	)
	(gr_line
		(start 97.681034 -255.824482)
		(end 99.090988 -256.634488)
		(stroke
			(width 0.254)
			(type default)
		)
		(layer "In9.Cu")
	)
	(gr_circle
		(center 97.76587 -180.704744)
		(end 98.64598 -180.704744)
		(stroke
			(width 0.2)
			(type default)
		)
		(fill no)
		(layer "In9.Cu")
	)
	(gr_line
		(start 97.97796 -279.758394)
		(end 97.507806 -280.5684)
		(stroke
			(width 0.254)
			(type default)
		)
		(layer "In9.Cu")
	)
	(gr_line
		(start 97.981008 -291.096192)
		(end 98.921062 -291.096192)
		(stroke
			(width 0.6096)
			(type default)
		)
		(layer "In9.Cu")
	)
	(gr_line
		(start 97.981008 -289.47618)
		(end 98.921062 -289.47618)
		(stroke
			(width 0.6096)
			(type default)
		)
		(layer "In9.Cu")
	)
	(gr_line
		(start 97.981008 -287.856422)
		(end 98.921062 -287.856422)
		(stroke
			(width 0.6096)
			(type default)
		)
		(layer "In9.Cu")
	)
	(gr_line
		(start 97.981008 -286.23641)
		(end 98.921062 -286.23641)
		(stroke
			(width 0.6096)
			(type default)
		)
		(layer "In9.Cu")
	)
	(gr_circle
		(center 98.08083 -338.626704)
		(end 98.96983 -338.626704)
		(stroke
			(width 0.2)
			(type default)
		)
		(fill no)
		(layer "In9.Cu")
	)
	(gr_circle
		(center 98.08083 -337.890104)
		(end 98.96983 -337.890104)
		(stroke
			(width 0.2)
			(type default)
		)
		(fill no)
		(layer "In9.Cu")
	)
	(gr_circle
		(center 98.199194 -339.358224)
		(end 99.088194 -339.358224)
		(stroke
			(width 0.2)
			(type default)
		)
		(fill no)
		(layer "In9.Cu")
	)
	(gr_circle
		(center 98.38309 -180.704744)
		(end 99.2632 -180.704744)
		(stroke
			(width 0.2)
			(type default)
		)
		(fill no)
		(layer "In9.Cu")
	)
	(gr_circle
		(center 98.605594 -337.450684)
		(end 99.494594 -337.450684)
		(stroke
			(width 0.2)
			(type default)
		)
		(fill no)
		(layer "In9.Cu")
	)
	(gr_line
		(start 98.621088 -247.724422)
		(end 97.681034 -247.724422)
		(stroke
			(width 0.6096)
			(type default)
		)
		(layer "In9.Cu")
	)
	(gr_line
		(start 98.621088 -246.10441)
		(end 97.681034 -246.10441)
		(stroke
			(width 0.6096)
			(type default)
		)
		(layer "In9.Cu")
	)
	(gr_line
		(start 98.621088 -244.484398)
		(end 97.681034 -244.484398)
		(stroke
			(width 0.6096)
			(type default)
		)
		(layer "In9.Cu")
	)
	(gr_circle
		(center 98.630994 -338.212684)
		(end 99.519994 -338.212684)
		(stroke
			(width 0.2)
			(type default)
		)
		(fill no)
		(layer "In9.Cu")
	)
	(gr_circle
		(center 98.747834 -339.736684)
		(end 99.636834 -339.736684)
		(stroke
			(width 0.2)
			(type default)
		)
		(fill no)
		(layer "In9.Cu")
	)
	(gr_circle
		(center 98.747834 -338.974684)
		(end 99.636834 -338.974684)
		(stroke
			(width 0.2)
			(type default)
		)
		(fill no)
		(layer "In9.Cu")
	)
	(gr_line
		(start 98.775774 -328.418952)
		(end 96.306386 -325.949564)
		(stroke
			(width 0.508)
			(type default)
		)
		(layer "In9.Cu")
	)
	(gr_line
		(start 98.921062 -284.616398)
		(end 97.981008 -284.616398)
		(stroke
			(width 0.6096)
			(type default)
		)
		(layer "In9.Cu")
	)
	(gr_line
		(start 98.921062 -282.996386)
		(end 97.981008 -282.996386)
		(stroke
			(width 0.6096)
			(type default)
		)
		(layer "In9.Cu")
	)
	(gr_line
		(start 98.921062 -281.376374)
		(end 97.981008 -281.376374)
		(stroke
			(width 0.6096)
			(type default)
		)
		(layer "In9.Cu")
	)
	(gr_line
		(start 99.08794 -248.532396)
		(end 97.677986 -249.342402)
		(stroke
			(width 0.254)
			(type default)
		)
		(layer "In9.Cu")
	)
	(gr_line
		(start 99.090988 -256.634488)
		(end 99.561142 -255.824482)
		(stroke
			(width 0.254)
			(type default)
		)
		(layer "In9.Cu")
	)
	(gr_line
		(start 99.387914 -267.608304)
		(end 97.507806 -267.608304)
		(stroke
			(width 0.254)
			(type default)
		)
		(layer "In9.Cu")
	)
	(gr_line
		(start 99.561142 -255.824482)
		(end 100.500942 -255.824482)
		(stroke
			(width 0.254)
			(type default)
		)
		(layer "In9.Cu")
	)
	(gr_line
		(start 99.857814 -266.798298)
		(end 99.387914 -267.608304)
		(stroke
			(width 0.254)
			(type default)
		)
		(layer "In9.Cu")
	)
	(gr_line
		(start 100.027994 -255.012444)
		(end 101.437948 -254.202438)
		(stroke
			(width 0.254)
			(type default)
		)
		(layer "In9.Cu")
	)
	(gr_line
		(start 100.027994 -253.392432)
		(end 101.437948 -252.582426)
		(stroke
			(width 0.254)
			(type default)
		)
		(layer "In9.Cu")
	)
	(gr_line
		(start 100.027994 -250.152408)
		(end 99.08794 -248.532396)
		(stroke
			(width 0.254)
			(type default)
		)
		(layer "In9.Cu")
	)
	(gr_line
		(start 100.327968 -265.988292)
		(end 99.857814 -266.798298)
		(stroke
			(width 0.254)
			(type default)
		)
		(layer "In9.Cu")
	)
	(gr_line
		(start 100.327968 -264.36828)
		(end 101.737922 -265.178286)
		(stroke
			(width 0.254)
			(type default)
		)
		(layer "In9.Cu")
	)
	(gr_line
		(start 100.47478 -190.999872)
		(end 78.573884 -190.999872)
		(stroke
			(width 0.508)
			(type default)
		)
		(layer "In9.Cu")
	)
	(gr_line
		(start 100.80117 -291.096192)
		(end 101.741224 -291.096192)
		(stroke
			(width 0.6096)
			(type default)
		)
		(layer "In9.Cu")
	)
	(gr_line
		(start 100.80117 -289.47618)
		(end 101.741224 -289.47618)
		(stroke
			(width 0.6096)
			(type default)
		)
		(layer "In9.Cu")
	)
	(gr_line
		(start 100.80117 -287.856422)
		(end 101.741224 -287.856422)
		(stroke
			(width 0.6096)
			(type default)
		)
		(layer "In9.Cu")
	)
	(gr_line
		(start 100.967794 -256.632456)
		(end 100.027994 -255.012444)
		(stroke
			(width 0.254)
			(type default)
		)
		(layer "In9.Cu")
	)
	(gr_line
		(start 100.967794 -256.632456)
		(end 102.855014 -257.930396)
		(stroke
			(width 0.254)
			(type default)
		)
		(layer "In9.Cu")
	)
	(gr_line
		(start 101.268022 -262.748268)
		(end 101.737922 -263.558274)
		(stroke
			(width 0.254)
			(type default)
		)
		(layer "In9.Cu")
	)
	(gr_line
		(start 101.268022 -261.128256)
		(end 101.737922 -261.938262)
		(stroke
			(width 0.254)
			(type default)
		)
		(layer "In9.Cu")
	)
	(gr_line
		(start 101.437948 -254.202438)
		(end 100.027994 -253.392432)
		(stroke
			(width 0.254)
			(type default)
		)
		(layer "In9.Cu")
	)
	(gr_line
		(start 101.437948 -252.582426)
		(end 101.907848 -251.77242)
		(stroke
			(width 0.254)
			(type default)
		)
		(layer "In9.Cu")
	)
	(gr_line
		(start 101.437948 -250.962414)
		(end 100.027994 -250.152408)
		(stroke
			(width 0.254)
			(type default)
		)
		(layer "In9.Cu")
	)
	(gr_line
		(start 101.440996 -247.724422)
		(end 100.500942 -247.724422)
		(stroke
			(width 0.6096)
			(type default)
		)
		(layer "In9.Cu")
	)
	(gr_line
		(start 101.440996 -246.10441)
		(end 100.500942 -246.10441)
		(stroke
			(width 0.6096)
			(type default)
		)
		(layer "In9.Cu")
	)
	(gr_line
		(start 101.440996 -244.484398)
		(end 100.500942 -244.484398)
		(stroke
			(width 0.6096)
			(type default)
		)
		(layer "In9.Cu")
	)
	(gr_line
		(start 101.737922 -266.798298)
		(end 100.327968 -265.988292)
		(stroke
			(width 0.254)
			(type default)
		)
		(layer "In9.Cu")
	)
	(gr_line
		(start 101.737922 -265.178286)
		(end 100.327968 -265.988292)
		(stroke
			(width 0.254)
			(type default)
		)
		(layer "In9.Cu")
	)
	(gr_line
		(start 101.737922 -263.558274)
		(end 100.327968 -264.36828)
		(stroke
			(width 0.254)
			(type default)
		)
		(layer "In9.Cu")
	)
	(gr_line
		(start 101.737922 -261.938262)
		(end 101.268022 -262.748268)
		(stroke
			(width 0.254)
			(type default)
		)
		(layer "In9.Cu")
	)
	(gr_line
		(start 101.741224 -286.23641)
		(end 100.80117 -286.23641)
		(stroke
			(width 0.6096)
			(type default)
		)
		(layer "In9.Cu")
	)
	(gr_line
		(start 101.741224 -284.616398)
		(end 100.80117 -284.616398)
		(stroke
			(width 0.6096)
			(type default)
		)
		(layer "In9.Cu")
	)
	(gr_line
		(start 101.741224 -282.996386)
		(end 100.80117 -282.996386)
		(stroke
			(width 0.6096)
			(type default)
		)
		(layer "In9.Cu")
	)
	(gr_line
		(start 101.741224 -281.376374)
		(end 100.80117 -281.376374)
		(stroke
			(width 0.6096)
			(type default)
		)
		(layer "In9.Cu")
	)
	(gr_line
		(start 101.907848 -251.77242)
		(end 101.437948 -250.962414)
		(stroke
			(width 0.254)
			(type default)
		)
		(layer "In9.Cu")
	)
	(gr_line
		(start 102.060756 -387.918452)
		(end 93.805248 -387.918452)
		(stroke
			(width 0.508)
			(type default)
		)
		(layer "In9.Cu")
	)
	(gr_line
		(start 102.181406 -383.53492)
		(end 102.461568 -383.815082)
		(stroke
			(width 0.508)
			(type default)
		)
		(layer "In9.Cu")
	)
	(gr_line
		(start 102.207822 -264.36828)
		(end 101.737922 -263.558274)
		(stroke
			(width 0.254)
			(type default)
		)
		(layer "In9.Cu")
	)
	(gr_line
		(start 102.279958 -267.340334)
		(end 101.737922 -266.798298)
		(stroke
			(width 0.254)
			(type default)
		)
		(layer "In9.Cu")
	)
	(gr_line
		(start 102.283768 -387.325108)
		(end 102.468934 -387.510274)
		(stroke
			(width 0.508)
			(type default)
		)
		(layer "In9.Cu")
	)
	(gr_line
		(start 102.283768 -386.689346)
		(end 102.283768 -387.325108)
		(stroke
			(width 0.508)
			(type default)
		)
		(layer "In9.Cu")
	)
	(gr_line
		(start 102.283768 -386.689346)
		(end 102.283768 -386.320538)
		(stroke
			(width 0.254)
			(type default)
		)
		(layer "In9.Cu")
	)
	(gr_line
		(start 102.283768 -386.320538)
		(end 102.461568 -386.142738)
		(stroke
			(width 0.254)
			(type default)
		)
		(layer "In9.Cu")
	)
	(gr_line
		(start 102.461568 -386.142738)
		(end 102.461568 -384.62077)
		(stroke
			(width 0.254)
			(type default)
		)
		(layer "In9.Cu")
	)
	(gr_line
		(start 102.461568 -383.815082)
		(end 102.461568 -384.62077)
		(stroke
			(width 0.508)
			(type default)
		)
		(layer "In9.Cu")
	)
	(gr_line
		(start 102.468934 -387.510274)
		(end 102.060756 -387.918452)
		(stroke
			(width 0.508)
			(type default)
		)
		(layer "In9.Cu")
	)
	(gr_line
		(start 102.677976 -267.340334)
		(end 102.279958 -267.340334)
		(stroke
			(width 0.254)
			(type default)
		)
		(layer "In9.Cu")
	)
	(gr_line
		(start 102.855014 -259.73024)
		(end 101.268022 -261.128256)
		(stroke
			(width 0.254)
			(type default)
		)
		(layer "In9.Cu")
	)
	(gr_line
		(start 102.855014 -257.930396)
		(end 102.855014 -259.73024)
		(stroke
			(width 0.254)
			(type default)
		)
		(layer "In9.Cu")
	)
	(gr_line
		(start 103.317802 -250.962414)
		(end 101.907848 -251.77242)
		(stroke
			(width 0.254)
			(type default)
		)
		(layer "In9.Cu")
	)
	(gr_line
		(start 103.61803 -266.798298)
		(end 102.677976 -267.340334)
		(stroke
			(width 0.254)
			(type default)
		)
		(layer "In9.Cu")
	)
	(gr_line
		(start 103.61803 -263.558274)
		(end 102.207822 -264.36828)
		(stroke
			(width 0.254)
			(type default)
		)
		(layer "In9.Cu")
	)
	(gr_line
		(start 103.621078 -291.096192)
		(end 104.561132 -291.096192)
		(stroke
			(width 0.6096)
			(type default)
		)
		(layer "In9.Cu")
	)
	(gr_line
		(start 103.621078 -289.47618)
		(end 104.561132 -289.47618)
		(stroke
			(width 0.6096)
			(type default)
		)
		(layer "In9.Cu")
	)
	(gr_line
		(start 103.621078 -287.856422)
		(end 104.561132 -287.856422)
		(stroke
			(width 0.6096)
			(type default)
		)
		(layer "In9.Cu")
	)
	(gr_circle
		(center 103.74503 -176.106074)
		(end 104.63403 -176.106074)
		(stroke
			(width 0.2)
			(type default)
		)
		(fill no)
		(layer "In9.Cu")
	)
	(gr_circle
		(center 103.74503 -175.369474)
		(end 104.63403 -175.369474)
		(stroke
			(width 0.2)
			(type default)
		)
		(fill no)
		(layer "In9.Cu")
	)
	(gr_circle
		(center 103.74503 -174.632874)
		(end 104.63403 -174.632874)
		(stroke
			(width 0.2)
			(type default)
		)
		(fill no)
		(layer "In9.Cu")
	)
	(gr_line
		(start 103.787956 -251.77242)
		(end 103.317802 -250.962414)
		(stroke
			(width 0.254)
			(type default)
		)
		(layer "In9.Cu")
	)
	(gr_line
		(start 103.886 -96.103948)
		(end 130.416046 -122.633994)
		(stroke
			(width 0.508)
			(type default)
		)
		(layer "In9.Cu")
	)
	(gr_line
		(start 104.08793 -265.988292)
		(end 103.61803 -266.798298)
		(stroke
			(width 0.254)
			(type default)
		)
		(layer "In9.Cu")
	)
	(gr_line
		(start 104.23271 -152.836626)
		(end 94.873826 -162.19551)
		(stroke
			(width 0.508)
			(type default)
		)
		(layer "In9.Cu")
	)
	(gr_line
		(start 104.261158 -247.724422)
		(end 103.321104 -247.724422)
		(stroke
			(width 0.6096)
			(type default)
		)
		(layer "In9.Cu")
	)
	(gr_line
		(start 104.261158 -246.10441)
		(end 103.321104 -246.10441)
		(stroke
			(width 0.6096)
			(type default)
		)
		(layer "In9.Cu")
	)
	(gr_line
		(start 104.261158 -244.484398)
		(end 103.321104 -244.484398)
		(stroke
			(width 0.6096)
			(type default)
		)
		(layer "In9.Cu")
	)
	(gr_circle
		(center 104.27843 -174.988474)
		(end 105.16743 -174.988474)
		(stroke
			(width 0.2)
			(type default)
		)
		(fill no)
		(layer "In9.Cu")
	)
	(gr_circle
		(center 104.30383 -175.750474)
		(end 105.19283 -175.750474)
		(stroke
			(width 0.2)
			(type default)
		)
		(fill no)
		(layer "In9.Cu")
	)
	(gr_circle
		(center 104.420162 -341.927688)
		(end 105.300272 -341.927688)
		(stroke
			(width 0.2)
			(type default)
		)
		(fill no)
		(layer "In9.Cu")
	)
	(gr_line
		(start 104.421178 -187.053474)
		(end 100.47478 -190.999872)
		(stroke
			(width 0.508)
			(type default)
		)
		(layer "In9.Cu")
	)
	(gr_line
		(start 104.561132 -286.23641)
		(end 103.621078 -286.23641)
		(stroke
			(width 0.6096)
			(type default)
		)
		(layer "In9.Cu")
	)
	(gr_line
		(start 104.561132 -284.616398)
		(end 103.621078 -284.616398)
		(stroke
			(width 0.6096)
			(type default)
		)
		(layer "In9.Cu")
	)
	(gr_line
		(start 104.561132 -282.996386)
		(end 103.621078 -282.996386)
		(stroke
			(width 0.6096)
			(type default)
		)
		(layer "In9.Cu")
	)
	(gr_line
		(start 104.589834 -328.418952)
		(end 98.775774 -328.418952)
		(stroke
			(width 0.508)
			(type default)
		)
		(layer "In9.Cu")
	)
	(gr_circle
		(center 104.828594 -175.311054)
		(end 105.717594 -175.311054)
		(stroke
			(width 0.2)
			(type default)
		)
		(fill no)
		(layer "In9.Cu")
	)
	(gr_circle
		(center 104.828594 -174.574454)
		(end 105.717594 -174.574454)
		(stroke
			(width 0.2)
			(type default)
		)
		(fill no)
		(layer "In9.Cu")
	)
	(gr_circle
		(center 105.037382 -341.927688)
		(end 105.917492 -341.927688)
		(stroke
			(width 0.2)
			(type default)
		)
		(fill no)
		(layer "In9.Cu")
	)
	(gr_line
		(start 105.19791 -250.962414)
		(end 103.787956 -251.77242)
		(stroke
			(width 0.254)
			(type default)
		)
		(layer "In9.Cu")
	)
	(gr_circle
		(center 105.336848 -177.65776)
		(end 106.225848 -177.65776)
		(stroke
			(width 0.2)
			(type default)
		)
		(fill no)
		(layer "In9.Cu")
	)
	(gr_circle
		(center 105.336848 -176.92116)
		(end 106.225848 -176.92116)
		(stroke
			(width 0.2)
			(type default)
		)
		(fill no)
		(layer "In9.Cu")
	)
	(gr_line
		(start 105.408222 -327.600564)
		(end 104.589834 -328.418952)
		(stroke
			(width 0.508)
			(type default)
		)
		(layer "In9.Cu")
	)
	(gr_line
		(start 105.490772 -262.180324)
		(end 103.61803 -263.558274)
		(stroke
			(width 0.254)
			(type default)
		)
		(layer "In9.Cu")
	)
	(gr_line
		(start 105.497884 -266.798298)
		(end 104.08793 -265.988292)
		(stroke
			(width 0.254)
			(type default)
		)
		(layer "In9.Cu")
	)
	(gr_circle
		(center 105.53065 -176.183544)
		(end 106.41076 -176.183544)
		(stroke
			(width 0.2)
			(type default)
		)
		(fill no)
		(layer "In9.Cu")
	)
	(gr_line
		(start 105.605834 -327.600564)
		(end 131.818126 -327.600564)
		(stroke
			(width 0.508)
			(type default)
		)
		(layer "In9.Cu")
	)
	(gr_circle
		(center 105.654602 -341.927688)
		(end 106.534712 -341.927688)
		(stroke
			(width 0.2)
			(type default)
		)
		(fill no)
		(layer "In9.Cu")
	)
	(gr_line
		(start 105.66781 -251.77242)
		(end 105.19791 -250.962414)
		(stroke
			(width 0.254)
			(type default)
		)
		(layer "In9.Cu")
	)
	(gr_line
		(start 105.782364 -327.600564)
		(end 105.408222 -327.600564)
		(stroke
			(width 0.508)
			(type default)
		)
		(layer "In9.Cu")
	)
	(gr_circle
		(center 105.934002 -341.229442)
		(end 106.814112 -341.229442)
		(stroke
			(width 0.2)
			(type default)
		)
		(fill no)
		(layer "In9.Cu")
	)
	(gr_circle
		(center 105.934002 -340.492842)
		(end 106.814112 -340.492842)
		(stroke
			(width 0.2)
			(type default)
		)
		(fill no)
		(layer "In9.Cu")
	)
	(gr_line
		(start 105.968038 -267.608304)
		(end 105.497884 -266.798298)
		(stroke
			(width 0.254)
			(type default)
		)
		(layer "In9.Cu")
	)
	(gr_circle
		(center 106.14787 -176.183544)
		(end 107.02798 -176.183544)
		(stroke
			(width 0.2)
			(type default)
		)
		(fill no)
		(layer "In9.Cu")
	)
	(gr_circle
		(center 106.34345 -343.450164)
		(end 107.23245 -343.450164)
		(stroke
			(width 0.2)
			(type default)
		)
		(fill no)
		(layer "In9.Cu")
	)
	(gr_circle
		(center 106.34345 -342.713564)
		(end 107.23245 -342.713564)
		(stroke
			(width 0.2)
			(type default)
		)
		(fill no)
		(layer "In9.Cu")
	)
	(gr_line
		(start 106.348022 -261.323074)
		(end 105.490772 -262.180324)
		(stroke
			(width 0.254)
			(type default)
		)
		(layer "In9.Cu")
	)
	(gr_line
		(start 106.440986 -291.096192)
		(end 107.38104 -291.096192)
		(stroke
			(width 0.6096)
			(type default)
		)
		(layer "In9.Cu")
	)
	(gr_line
		(start 106.440986 -289.47618)
		(end 107.38104 -289.47618)
		(stroke
			(width 0.6096)
			(type default)
		)
		(layer "In9.Cu")
	)
	(gr_line
		(start 106.440986 -287.856422)
		(end 107.38104 -287.856422)
		(stroke
			(width 0.6096)
			(type default)
		)
		(layer "In9.Cu")
	)
	(gr_circle
		(center 106.76509 -176.183544)
		(end 107.6452 -176.183544)
		(stroke
			(width 0.2)
			(type default)
		)
		(fill no)
		(layer "In9.Cu")
	)
	(gr_line
		(start 106.856276 -143.076676)
		(end 113.67008 -143.076676)
		(stroke
			(width 0.508)
			(type default)
		)
		(layer "In9.Cu")
	)
	(gr_circle
		(center 106.98607 -342.540844)
		(end 107.87507 -342.540844)
		(stroke
			(width 0.2)
			(type default)
		)
		(fill no)
		(layer "In9.Cu")
	)
	(gr_circle
		(center 106.98607 -341.804244)
		(end 107.87507 -341.804244)
		(stroke
			(width 0.2)
			(type default)
		)
		(fill no)
		(layer "In9.Cu")
	)
	(gr_circle
		(center 107.01401 -343.986104)
		(end 107.90301 -343.986104)
		(stroke
			(width 0.2)
			(type default)
		)
		(fill no)
		(layer "In9.Cu")
	)
	(gr_circle
		(center 107.01401 -343.249504)
		(end 107.90301 -343.249504)
		(stroke
			(width 0.2)
			(type default)
		)
		(fill no)
		(layer "In9.Cu")
	)
	(gr_line
		(start 107.078018 -250.962414)
		(end 105.66781 -251.77242)
		(stroke
			(width 0.254)
			(type default)
		)
		(layer "In9.Cu")
	)
	(gr_line
		(start 107.081066 -247.724422)
		(end 106.141012 -247.724422)
		(stroke
			(width 0.6096)
			(type default)
		)
		(layer "In9.Cu")
	)
	(gr_line
		(start 107.081066 -246.10441)
		(end 106.141012 -246.10441)
		(stroke
			(width 0.6096)
			(type default)
		)
		(layer "In9.Cu")
	)
	(gr_line
		(start 107.081066 -244.484398)
		(end 106.141012 -244.484398)
		(stroke
			(width 0.6096)
			(type default)
		)
		(layer "In9.Cu")
	)
	(gr_line
		(start 107.377992 -266.798298)
		(end 105.968038 -267.608304)
		(stroke
			(width 0.254)
			(type default)
		)
		(layer "In9.Cu")
	)
	(gr_line
		(start 107.38104 -286.23641)
		(end 106.440986 -286.23641)
		(stroke
			(width 0.6096)
			(type default)
		)
		(layer "In9.Cu")
	)
	(gr_line
		(start 107.38104 -284.616398)
		(end 106.440986 -284.616398)
		(stroke
			(width 0.6096)
			(type default)
		)
		(layer "In9.Cu")
	)
	(gr_line
		(start 107.38104 -282.996386)
		(end 106.440986 -282.996386)
		(stroke
			(width 0.6096)
			(type default)
		)
		(layer "In9.Cu")
	)
	(gr_line
		(start 107.547918 -251.77242)
		(end 107.078018 -250.962414)
		(stroke
			(width 0.254)
			(type default)
		)
		(layer "In9.Cu")
	)
	(gr_line
		(start 107.847892 -265.988292)
		(end 107.377992 -266.798298)
		(stroke
			(width 0.254)
			(type default)
		)
		(layer "In9.Cu")
	)
	(gr_line
		(start 108.388658 -349.812102)
		(end 115.964208 -342.236552)
		(stroke
			(width 0.508)
			(type default)
		)
		(layer "In9.Cu")
	)
	(gr_line
		(start 108.790994 -290.286186)
		(end 109.731048 -290.286186)
		(stroke
			(width 0.6096)
			(type default)
		)
		(layer "In9.Cu")
	)
	(gr_line
		(start 108.790994 -288.666174)
		(end 109.731048 -288.666174)
		(stroke
			(width 0.6096)
			(type default)
		)
		(layer "In9.Cu")
	)
	(gr_line
		(start 108.790994 -287.046162)
		(end 109.731048 -287.046162)
		(stroke
			(width 0.6096)
			(type default)
		)
		(layer "In9.Cu")
	)
	(gr_line
		(start 108.957872 -250.962414)
		(end 107.547918 -251.77242)
		(stroke
			(width 0.254)
			(type default)
		)
		(layer "In9.Cu")
	)
	(gr_line
		(start 109.257846 -266.798298)
		(end 107.847892 -265.988292)
		(stroke
			(width 0.254)
			(type default)
		)
		(layer "In9.Cu")
	)
	(gr_line
		(start 109.428026 -250.152408)
		(end 108.957872 -250.962414)
		(stroke
			(width 0.254)
			(type default)
		)
		(layer "In9.Cu")
	)
	(gr_line
		(start 109.431074 -248.534428)
		(end 108.49102 -248.534428)
		(stroke
			(width 0.6096)
			(type default)
		)
		(layer "In9.Cu")
	)
	(gr_line
		(start 109.431074 -246.914416)
		(end 108.49102 -246.914416)
		(stroke
			(width 0.6096)
			(type default)
		)
		(layer "In9.Cu")
	)
	(gr_line
		(start 109.431074 -245.294404)
		(end 108.49102 -245.294404)
		(stroke
			(width 0.6096)
			(type default)
		)
		(layer "In9.Cu")
	)
	(gr_line
		(start 109.431074 -243.674392)
		(end 108.49102 -243.674392)
		(stroke
			(width 0.6096)
			(type default)
		)
		(layer "In9.Cu")
	)
	(gr_line
		(start 109.728 -267.608304)
		(end 109.257846 -266.798298)
		(stroke
			(width 0.254)
			(type default)
		)
		(layer "In9.Cu")
	)
	(gr_line
		(start 109.731048 -285.426404)
		(end 108.790994 -285.426404)
		(stroke
			(width 0.6096)
			(type default)
		)
		(layer "In9.Cu")
	)
	(gr_line
		(start 109.731048 -283.806392)
		(end 108.790994 -283.806392)
		(stroke
			(width 0.6096)
			(type default)
		)
		(layer "In9.Cu")
	)
	(gr_line
		(start 109.731048 -282.18638)
		(end 108.790994 -282.18638)
		(stroke
			(width 0.6096)
			(type default)
		)
		(layer "In9.Cu")
	)
	(gr_line
		(start 109.759496 -387.510274)
		(end 102.468934 -387.510274)
		(stroke
			(width 0.508)
			(type default)
		)
		(layer "In9.Cu")
	)
	(gr_circle
		(center 110.140496 -150.941786)
		(end 111.537496 -150.941786)
		(stroke
			(width 0.2)
			(type default)
		)
		(fill no)
		(layer "In9.Cu")
	)
	(gr_line
		(start 110.335568 -386.934202)
		(end 109.759496 -387.510274)
		(stroke
			(width 0.508)
			(type default)
		)
		(layer "In9.Cu")
	)
	(gr_line
		(start 110.335568 -384.090926)
		(end 110.335568 -386.934202)
		(stroke
			(width 0.508)
			(type default)
		)
		(layer "In9.Cu")
	)
	(gr_line
		(start 110.74908 -383.677414)
		(end 110.335568 -384.090926)
		(stroke
			(width 0.508)
			(type default)
		)
		(layer "In9.Cu")
	)
	(gr_line
		(start 110.83798 -250.962414)
		(end 109.428026 -250.152408)
		(stroke
			(width 0.254)
			(type default)
		)
		(layer "In9.Cu")
	)
	(gr_line
		(start 111.137954 -266.798298)
		(end 109.728 -267.608304)
		(stroke
			(width 0.254)
			(type default)
		)
		(layer "In9.Cu")
	)
	(gr_line
		(start 111.512858 -187.053474)
		(end 111.893858 -186.672474)
		(stroke
			(width 0.508)
			(type default)
		)
		(layer "In9.Cu")
	)
	(gr_line
		(start 111.893858 -187.434474)
		(end 111.512858 -187.053474)
		(stroke
			(width 0.508)
			(type default)
		)
		(layer "In9.Cu")
	)
	(gr_line
		(start 111.927386 -192.218564)
		(end 131.517898 -211.809076)
		(stroke
			(width 0.508)
			(type default)
		)
		(layer "In9.Cu")
	)
	(gr_line
		(start 111.927386 -187.053474)
		(end 104.421178 -187.053474)
		(stroke
			(width 0.508)
			(type default)
		)
		(layer "In9.Cu")
	)
	(gr_line
		(start 111.927386 -183.963564)
		(end 111.927386 -192.218564)
		(stroke
			(width 0.508)
			(type default)
		)
		(layer "In9.Cu")
	)
	(gr_circle
		(center 111.97463 -169.857674)
		(end 112.86363 -169.857674)
		(stroke
			(width 0.2)
			(type default)
		)
		(fill no)
		(layer "In9.Cu")
	)
	(gr_circle
		(center 111.97463 -169.121074)
		(end 112.86363 -169.121074)
		(stroke
			(width 0.2)
			(type default)
		)
		(fill no)
		(layer "In9.Cu")
	)
	(gr_circle
		(center 111.97463 -168.384474)
		(end 112.86363 -168.384474)
		(stroke
			(width 0.2)
			(type default)
		)
		(fill no)
		(layer "In9.Cu")
	)
	(gr_circle
		(center 112.50803 -168.740074)
		(end 113.39703 -168.740074)
		(stroke
			(width 0.2)
			(type default)
		)
		(fill no)
		(layer "In9.Cu")
	)
	(gr_circle
		(center 112.53343 -169.502074)
		(end 113.42243 -169.502074)
		(stroke
			(width 0.2)
			(type default)
		)
		(fill no)
		(layer "In9.Cu")
	)
	(gr_circle
		(center 113.058194 -169.062654)
		(end 113.947194 -169.062654)
		(stroke
			(width 0.2)
			(type default)
		)
		(fill no)
		(layer "In9.Cu")
	)
	(gr_circle
		(center 113.058194 -168.326054)
		(end 113.947194 -168.326054)
		(stroke
			(width 0.2)
			(type default)
		)
		(fill no)
		(layer "In9.Cu")
	)
	(gr_circle
		(center 113.591848 -171.33316)
		(end 114.480848 -171.33316)
		(stroke
			(width 0.2)
			(type default)
		)
		(fill no)
		(layer "In9.Cu")
	)
	(gr_circle
		(center 113.591848 -170.59656)
		(end 114.480848 -170.59656)
		(stroke
			(width 0.2)
			(type default)
		)
		(fill no)
		(layer "In9.Cu")
	)
	(gr_line
		(start 113.657888 -250.962414)
		(end 110.83798 -250.962414)
		(stroke
			(width 0.254)
			(type default)
		)
		(layer "In9.Cu")
	)
	(gr_line
		(start 113.67008 -143.076676)
		(end 115.1763 -144.582896)
		(stroke
			(width 0.508)
			(type default)
		)
		(layer "In9.Cu")
	)
	(gr_circle
		(center 113.76025 -169.935144)
		(end 114.64036 -169.935144)
		(stroke
			(width 0.2)
			(type default)
		)
		(fill no)
		(layer "In9.Cu")
	)
	(gr_line
		(start 113.957862 -266.798298)
		(end 111.137954 -266.798298)
		(stroke
			(width 0.254)
			(type default)
		)
		(layer "In9.Cu")
	)
	(gr_circle
		(center 114.37747 -169.935144)
		(end 115.25758 -169.935144)
		(stroke
			(width 0.2)
			(type default)
		)
		(fill no)
		(layer "In9.Cu")
	)
	(gr_line
		(start 114.424714 -285.426404)
		(end 115.364768 -285.426404)
		(stroke
			(width 0.6096)
			(type default)
		)
		(layer "In9.Cu")
	)
	(gr_line
		(start 114.424714 -283.806392)
		(end 115.364768 -283.806392)
		(stroke
			(width 0.6096)
			(type default)
		)
		(layer "In9.Cu")
	)
	(gr_line
		(start 114.424714 -282.18638)
		(end 115.364768 -282.18638)
		(stroke
			(width 0.6096)
			(type default)
		)
		(layer "In9.Cu")
	)
	(gr_circle
		(center 114.99469 -169.935144)
		(end 115.8748 -169.935144)
		(stroke
			(width 0.2)
			(type default)
		)
		(fill no)
		(layer "In9.Cu")
	)
	(gr_line
		(start 115.067842 -250.152408)
		(end 113.657888 -250.962414)
		(stroke
			(width 0.254)
			(type default)
		)
		(layer "In9.Cu")
	)
	(gr_line
		(start 115.1763 -146.67992)
		(end 115.7732 -147.27682)
		(stroke
			(width 0.508)
			(type default)
		)
		(layer "In9.Cu")
	)
	(gr_line
		(start 115.1763 -144.582896)
		(end 115.1763 -146.67992)
		(stroke
			(width 0.508)
			(type default)
		)
		(layer "In9.Cu")
	)
	(gr_line
		(start 115.367816 -265.988292)
		(end 113.957862 -266.798298)
		(stroke
			(width 0.254)
			(type default)
		)
		(layer "In9.Cu")
	)
	(gr_line
		(start 115.537996 -250.962414)
		(end 115.067842 -250.152408)
		(stroke
			(width 0.254)
			(type default)
		)
		(layer "In9.Cu")
	)
	(gr_line
		(start 115.7732 -147.27682)
		(end 121.17324 -147.27682)
		(stroke
			(width 0.508)
			(type default)
		)
		(layer "In9.Cu")
	)
	(gr_line
		(start 115.83797 -266.798298)
		(end 115.367816 -265.988292)
		(stroke
			(width 0.254)
			(type default)
		)
		(layer "In9.Cu")
	)
	(gr_line
		(start 115.964208 -342.236552)
		(end 132.236464 -342.236552)
		(stroke
			(width 0.508)
			(type default)
		)
		(layer "In9.Cu")
	)
	(gr_line
		(start 116.197888 -261.323074)
		(end 106.348022 -261.323074)
		(stroke
			(width 0.254)
			(type default)
		)
		(layer "In9.Cu")
	)
	(gr_circle
		(center 116.258594 -152.657556)
		(end 117.147594 -152.657556)
		(stroke
			(width 0.2)
			(type default)
		)
		(fill no)
		(layer "In9.Cu")
	)
	(gr_circle
		(center 116.258594 -152.022556)
		(end 117.147594 -152.022556)
		(stroke
			(width 0.2)
			(type default)
		)
		(fill no)
		(layer "In9.Cu")
	)
	(gr_line
		(start 116.545106 -261.670292)
		(end 116.197888 -261.323074)
		(stroke
			(width 0.254)
			(type default)
		)
		(layer "In9.Cu")
	)
	(gr_line
		(start 116.774722 -286.23641)
		(end 117.714776 -286.23641)
		(stroke
			(width 0.6096)
			(type default)
		)
		(layer "In9.Cu")
	)
	(gr_line
		(start 116.774722 -284.616398)
		(end 117.714776 -284.616398)
		(stroke
			(width 0.6096)
			(type default)
		)
		(layer "In9.Cu")
	)
	(gr_line
		(start 116.774722 -282.996386)
		(end 117.714776 -282.996386)
		(stroke
			(width 0.6096)
			(type default)
		)
		(layer "In9.Cu")
	)
	(gr_circle
		(center 116.893594 -152.657556)
		(end 117.782594 -152.657556)
		(stroke
			(width 0.2)
			(type default)
		)
		(fill no)
		(layer "In9.Cu")
	)
	(gr_circle
		(center 116.893594 -152.022556)
		(end 117.782594 -152.022556)
		(stroke
			(width 0.2)
			(type default)
		)
		(fill no)
		(layer "In9.Cu")
	)
	(gr_line
		(start 116.94795 -251.77242)
		(end 115.537996 -250.962414)
		(stroke
			(width 0.254)
			(type default)
		)
		(layer "In9.Cu")
	)
	(gr_line
		(start 117.247924 -267.608304)
		(end 115.83797 -266.798298)
		(stroke
			(width 0.254)
			(type default)
		)
		(layer "In9.Cu")
	)
	(gr_line
		(start 117.41785 -250.962414)
		(end 116.94795 -251.77242)
		(stroke
			(width 0.254)
			(type default)
		)
		(layer "In9.Cu")
	)
	(gr_circle
		(center 117.559074 -152.657556)
		(end 118.448074 -152.657556)
		(stroke
			(width 0.2)
			(type default)
		)
		(fill no)
		(layer "In9.Cu")
	)
	(gr_circle
		(center 117.559074 -152.022556)
		(end 118.448074 -152.022556)
		(stroke
			(width 0.2)
			(type default)
		)
		(fill no)
		(layer "In9.Cu")
	)
	(gr_line
		(start 117.717824 -266.798298)
		(end 117.247924 -267.608304)
		(stroke
			(width 0.254)
			(type default)
		)
		(layer "In9.Cu")
	)
	(gr_circle
		(center 118.194074 -152.657556)
		(end 119.083074 -152.657556)
		(stroke
			(width 0.2)
			(type default)
		)
		(fill no)
		(layer "In9.Cu")
	)
	(gr_circle
		(center 118.194074 -152.022556)
		(end 119.083074 -152.022556)
		(stroke
			(width 0.2)
			(type default)
		)
		(fill no)
		(layer "In9.Cu")
	)
	(gr_line
		(start 118.827804 -250.152408)
		(end 117.41785 -250.962414)
		(stroke
			(width 0.254)
			(type default)
		)
		(layer "In9.Cu")
	)
	(gr_circle
		(center 118.829074 -152.657556)
		(end 119.718074 -152.657556)
		(stroke
			(width 0.2)
			(type default)
		)
		(fill no)
		(layer "In9.Cu")
	)
	(gr_circle
		(center 118.829074 -152.022556)
		(end 119.718074 -152.022556)
		(stroke
			(width 0.2)
			(type default)
		)
		(fill no)
		(layer "In9.Cu")
	)
	(gr_line
		(start 119.127778 -265.988292)
		(end 117.717824 -266.798298)
		(stroke
			(width 0.254)
			(type default)
		)
		(layer "In9.Cu")
	)
	(gr_line
		(start 119.297958 -250.962414)
		(end 118.827804 -250.152408)
		(stroke
			(width 0.254)
			(type default)
		)
		(layer "In9.Cu")
	)
	(gr_circle
		(center 119.464074 -152.657556)
		(end 120.353074 -152.657556)
		(stroke
			(width 0.2)
			(type default)
		)
		(fill no)
		(layer "In9.Cu")
	)
	(gr_circle
		(center 119.464074 -152.022556)
		(end 120.353074 -152.022556)
		(stroke
			(width 0.2)
			(type default)
		)
		(fill no)
		(layer "In9.Cu")
	)
	(gr_line
		(start 119.59463 -286.23641)
		(end 120.534684 -286.23641)
		(stroke
			(width 0.6096)
			(type default)
		)
		(layer "In9.Cu")
	)
	(gr_line
		(start 119.59463 -284.616398)
		(end 120.534684 -284.616398)
		(stroke
			(width 0.6096)
			(type default)
		)
		(layer "In9.Cu")
	)
	(gr_line
		(start 119.59463 -282.996386)
		(end 120.534684 -282.996386)
		(stroke
			(width 0.6096)
			(type default)
		)
		(layer "In9.Cu")
	)
	(gr_line
		(start 119.597932 -266.798298)
		(end 119.127778 -265.988292)
		(stroke
			(width 0.254)
			(type default)
		)
		(layer "In9.Cu")
	)
	(gr_circle
		(center 120.25503 -163.126674)
		(end 121.14403 -163.126674)
		(stroke
			(width 0.2)
			(type default)
		)
		(fill no)
		(layer "In9.Cu")
	)
	(gr_circle
		(center 120.25503 -162.390074)
		(end 121.14403 -162.390074)
		(stroke
			(width 0.2)
			(type default)
		)
		(fill no)
		(layer "In9.Cu")
	)
	(gr_circle
		(center 120.25503 -161.653474)
		(end 121.14403 -161.653474)
		(stroke
			(width 0.2)
			(type default)
		)
		(fill no)
		(layer "In9.Cu")
	)
	(gr_line
		(start 120.270016 -261.670292)
		(end 116.545106 -261.670292)
		(stroke
			(width 0.254)
			(type default)
		)
		(layer "In9.Cu")
	)
	(gr_line
		(start 120.537986 -261.938262)
		(end 120.270016 -261.670292)
		(stroke
			(width 0.254)
			(type default)
		)
		(layer "In9.Cu")
	)
	(gr_line
		(start 120.707912 -251.77242)
		(end 119.297958 -250.962414)
		(stroke
			(width 0.254)
			(type default)
		)
		(layer "In9.Cu")
	)
	(gr_circle
		(center 120.78843 -162.009074)
		(end 121.67743 -162.009074)
		(stroke
			(width 0.2)
			(type default)
		)
		(fill no)
		(layer "In9.Cu")
	)
	(gr_line
		(start 120.79478 -383.677414)
		(end 110.74908 -383.677414)
		(stroke
			(width 0.508)
			(type default)
		)
		(layer "In9.Cu")
	)
	(gr_circle
		(center 120.81383 -162.771074)
		(end 121.70283 -162.771074)
		(stroke
			(width 0.2)
			(type default)
		)
		(fill no)
		(layer "In9.Cu")
	)
	(gr_line
		(start 121.007886 -267.608304)
		(end 119.597932 -266.798298)
		(stroke
			(width 0.254)
			(type default)
		)
		(layer "In9.Cu")
	)
	(gr_line
		(start 121.159524 -387.733286)
		(end 121.159524 -384.042158)
		(stroke
			(width 0.508)
			(type default)
		)
		(layer "In9.Cu")
	)
	(gr_line
		(start 121.159524 -384.042158)
		(end 120.79478 -383.677414)
		(stroke
			(width 0.508)
			(type default)
		)
		(layer "In9.Cu")
	)
	(gr_line
		(start 121.159524 -384.042158)
		(end 121.23166 -384.042158)
		(stroke
			(width 0.508)
			(type default)
		)
		(layer "In9.Cu")
	)
	(gr_line
		(start 121.17324 -147.27682)
		(end 121.65584 -146.79422)
		(stroke
			(width 0.508)
			(type default)
		)
		(layer "In9.Cu")
	)
	(gr_line
		(start 121.177812 -250.962414)
		(end 120.707912 -251.77242)
		(stroke
			(width 0.254)
			(type default)
		)
		(layer "In9.Cu")
	)
	(gr_line
		(start 121.23166 -384.042158)
		(end 121.796302 -383.477516)
		(stroke
			(width 0.508)
			(type default)
		)
		(layer "In9.Cu")
	)
	(gr_circle
		(center 121.338594 -162.331654)
		(end 122.227594 -162.331654)
		(stroke
			(width 0.2)
			(type default)
		)
		(fill no)
		(layer "In9.Cu")
	)
	(gr_circle
		(center 121.338594 -161.595054)
		(end 122.227594 -161.595054)
		(stroke
			(width 0.2)
			(type default)
		)
		(fill no)
		(layer "In9.Cu")
	)
	(gr_line
		(start 121.477786 -266.798298)
		(end 121.007886 -267.608304)
		(stroke
			(width 0.254)
			(type default)
		)
		(layer "In9.Cu")
	)
	(gr_line
		(start 121.642378 -388.21614)
		(end 121.159524 -387.733286)
		(stroke
			(width 0.508)
			(type default)
		)
		(layer "In9.Cu")
	)
	(gr_line
		(start 121.65584 -146.79422)
		(end 121.65584 -143.12646)
		(stroke
			(width 0.508)
			(type default)
		)
		(layer "In9.Cu")
	)
	(gr_line
		(start 121.65584 -143.12646)
		(end 123.258834 -141.523466)
		(stroke
			(width 0.508)
			(type default)
		)
		(layer "In9.Cu")
	)
	(gr_line
		(start 121.796302 -383.477516)
		(end 136.689338 -383.477516)
		(stroke
			(width 0.508)
			(type default)
		)
		(layer "In9.Cu")
	)
	(gr_circle
		(center 121.872248 -164.62756)
		(end 122.761248 -164.62756)
		(stroke
			(width 0.2)
			(type default)
		)
		(fill no)
		(layer "In9.Cu")
	)
	(gr_circle
		(center 121.872248 -163.89096)
		(end 122.761248 -163.89096)
		(stroke
			(width 0.2)
			(type default)
		)
		(fill no)
		(layer "In9.Cu")
	)
	(gr_line
		(start 121.94794 -262.748268)
		(end 120.537986 -261.938262)
		(stroke
			(width 0.254)
			(type default)
		)
		(layer "In9.Cu")
	)
	(gr_circle
		(center 122.04065 -163.204144)
		(end 122.92076 -163.204144)
		(stroke
			(width 0.2)
			(type default)
		)
		(fill no)
		(layer "In9.Cu")
	)
	(gr_line
		(start 122.414792 -286.23641)
		(end 123.354846 -286.23641)
		(stroke
			(width 0.6096)
			(type default)
		)
		(layer "In9.Cu")
	)
	(gr_line
		(start 122.414792 -284.616398)
		(end 123.354846 -284.616398)
		(stroke
			(width 0.6096)
			(type default)
		)
		(layer "In9.Cu")
	)
	(gr_line
		(start 122.414792 -282.996386)
		(end 123.354846 -282.996386)
		(stroke
			(width 0.6096)
			(type default)
		)
		(layer "In9.Cu")
	)
	(gr_line
		(start 122.414792 -281.376374)
		(end 123.354846 -281.376374)
		(stroke
			(width 0.6096)
			(type default)
		)
		(layer "In9.Cu")
	)
	(gr_line
		(start 122.41784 -261.938262)
		(end 121.94794 -262.748268)
		(stroke
			(width 0.254)
			(type default)
		)
		(layer "In9.Cu")
	)
	(gr_line
		(start 122.58802 -250.152408)
		(end 121.177812 -250.962414)
		(stroke
			(width 0.254)
			(type default)
		)
		(layer "In9.Cu")
	)
	(gr_circle
		(center 122.65787 -163.204144)
		(end 123.53798 -163.204144)
		(stroke
			(width 0.2)
			(type default)
		)
		(fill no)
		(layer "In9.Cu")
	)
	(gr_line
		(start 122.887994 -265.988292)
		(end 121.477786 -266.798298)
		(stroke
			(width 0.254)
			(type default)
		)
		(layer "In9.Cu")
	)
	(gr_line
		(start 123.05792 -250.962414)
		(end 122.58802 -250.152408)
		(stroke
			(width 0.254)
			(type default)
		)
		(layer "In9.Cu")
	)
	(gr_line
		(start 123.258834 -141.523466)
		(end 138.549126 -141.523466)
		(stroke
			(width 0.508)
			(type default)
		)
		(layer "In9.Cu")
	)
	(gr_circle
		(center 123.27509 -163.204144)
		(end 124.1552 -163.204144)
		(stroke
			(width 0.2)
			(type default)
		)
		(fill no)
		(layer "In9.Cu")
	)
	(gr_line
		(start 123.357894 -266.798298)
		(end 122.887994 -265.988292)
		(stroke
			(width 0.254)
			(type default)
		)
		(layer "In9.Cu")
	)
	(gr_line
		(start 123.827794 -262.748268)
		(end 122.41784 -261.938262)
		(stroke
			(width 0.254)
			(type default)
		)
		(layer "In9.Cu")
	)
	(gr_arc
		(start 124.102114 -11.780012)
		(mid 125.516325 -11.194227)
		(end 126.10211 -9.780016)
		(stroke
			(width 3.048)
			(type default)
		)
		(layer "In9.Cu")
	)
	(gr_line
		(start 124.457206 -388.21614)
		(end 121.642378 -388.21614)
		(stroke
			(width 0.508)
			(type default)
		)
		(layer "In9.Cu")
	)
	(gr_line
		(start 124.467874 -251.77242)
		(end 123.05792 -250.962414)
		(stroke
			(width 0.254)
			(type default)
		)
		(layer "In9.Cu")
	)
	(gr_line
		(start 124.767848 -267.608304)
		(end 123.357894 -266.798298)
		(stroke
			(width 0.254)
			(type default)
		)
		(layer "In9.Cu")
	)
	(gr_line
		(start 124.938028 -250.962414)
		(end 124.467874 -251.77242)
		(stroke
			(width 0.254)
			(type default)
		)
		(layer "In9.Cu")
	)
	(gr_line
		(start 125.2347 -284.616398)
		(end 126.174754 -284.616398)
		(stroke
			(width 0.6096)
			(type default)
		)
		(layer "In9.Cu")
	)
	(gr_line
		(start 125.2347 -282.996386)
		(end 126.174754 -282.996386)
		(stroke
			(width 0.6096)
			(type default)
		)
		(layer "In9.Cu")
	)
	(gr_line
		(start 125.2347 -281.376374)
		(end 126.174754 -281.376374)
		(stroke
			(width 0.6096)
			(type default)
		)
		(layer "In9.Cu")
	)
	(gr_line
		(start 125.238002 -266.798298)
		(end 124.767848 -267.608304)
		(stroke
			(width 0.254)
			(type default)
		)
		(layer "In9.Cu")
	)
	(gr_line
		(start 125.238002 -263.558274)
		(end 123.827794 -262.748268)
		(stroke
			(width 0.254)
			(type default)
		)
		(layer "In9.Cu")
	)
	(gr_line
		(start 125.707902 -262.748268)
		(end 125.238002 -263.558274)
		(stroke
			(width 0.254)
			(type default)
		)
		(layer "In9.Cu")
	)
	(gr_line
		(start 125.877828 -238.002318)
		(end 127.287782 -238.812324)
		(stroke
			(width 0.254)
			(type default)
		)
		(layer "In9.Cu")
	)
	(gr_line
		(start 126.100332 -386.573014)
		(end 124.457206 -388.21614)
		(stroke
			(width 0.508)
			(type default)
		)
		(layer "In9.Cu")
	)
	(gr_line
		(start 126.10211 -9.780016)
		(end 126.10211 -5.780024)
		(stroke
			(width 3.048)
			(type default)
		)
		(layer "In9.Cu")
	)
	(gr_line
		(start 126.177802 -279.758394)
		(end 127.58801 -278.948388)
		(stroke
			(width 0.254)
			(type default)
		)
		(layer "In9.Cu")
	)
	(gr_line
		(start 126.177802 -266.798298)
		(end 125.238002 -266.798298)
		(stroke
			(width 0.254)
			(type default)
		)
		(layer "In9.Cu")
	)
	(gr_line
		(start 126.347982 -250.152408)
		(end 124.938028 -250.962414)
		(stroke
			(width 0.254)
			(type default)
		)
		(layer "In9.Cu")
	)
	(gr_line
		(start 126.347982 -246.912384)
		(end 127.287782 -248.532396)
		(stroke
			(width 0.254)
			(type default)
		)
		(layer "In9.Cu")
	)
	(gr_line
		(start 126.347982 -243.67236)
		(end 127.287782 -245.292372)
		(stroke
			(width 0.254)
			(type default)
		)
		(layer "In9.Cu")
	)
	(gr_line
		(start 126.347982 -240.432336)
		(end 127.287782 -242.052348)
		(stroke
			(width 0.254)
			(type default)
		)
		(layer "In9.Cu")
	)
	(gr_line
		(start 126.347982 -235.5723)
		(end 126.817882 -236.382306)
		(stroke
			(width 0.254)
			(type default)
		)
		(layer "In9.Cu")
	)
	(gr_line
		(start 126.347982 -232.332276)
		(end 127.287782 -233.952288)
		(stroke
			(width 0.254)
			(type default)
		)
		(layer "In9.Cu")
	)
	(gr_line
		(start 126.347982 -230.712264)
		(end 126.817882 -231.52227)
		(stroke
			(width 0.254)
			(type default)
		)
		(layer "In9.Cu")
	)
	(gr_line
		(start 126.347982 -229.092252)
		(end 126.817882 -229.902258)
		(stroke
			(width 0.254)
			(type default)
		)
		(layer "In9.Cu")
	)
	(gr_line
		(start 126.426722 -169.464228)
		(end 111.927386 -183.963564)
		(stroke
			(width 0.508)
			(type default)
		)
		(layer "In9.Cu")
	)
	(gr_arc
		(start 126.601982 -5.279898)
		(mid 126.248489 -5.42646)
		(end 126.10211 -5.780024)
		(stroke
			(width 3.048)
			(type default)
		)
		(layer "In9.Cu")
	)
	(gr_line
		(start 126.601982 -5.279898)
		(end 194.20205 -5.279898)
		(stroke
			(width 3.048)
			(type default)
		)
		(layer "In9.Cu")
	)
	(gr_line
		(start 126.647956 -288.66846)
		(end 127.58801 -287.048448)
		(stroke
			(width 0.254)
			(type default)
		)
		(layer "In9.Cu")
	)
	(gr_line
		(start 126.647956 -285.428436)
		(end 127.58801 -283.808424)
		(stroke
			(width 0.254)
			(type default)
		)
		(layer "In9.Cu")
	)
	(gr_line
		(start 126.647956 -282.188412)
		(end 127.117856 -281.378406)
		(stroke
			(width 0.254)
			(type default)
		)
		(layer "In9.Cu")
	)
	(gr_line
		(start 126.647956 -277.328376)
		(end 127.58801 -275.708364)
		(stroke
			(width 0.254)
			(type default)
		)
		(layer "In9.Cu")
	)
	(gr_line
		(start 126.647956 -274.088352)
		(end 127.58801 -272.46834)
		(stroke
			(width 0.254)
			(type default)
		)
		(layer "In9.Cu")
	)
	(gr_line
		(start 126.647956 -270.848328)
		(end 127.58801 -269.228316)
		(stroke
			(width 0.254)
			(type default)
		)
		(layer "In9.Cu")
	)
	(gr_line
		(start 126.817882 -236.382306)
		(end 125.877828 -238.002318)
		(stroke
			(width 0.254)
			(type default)
		)
		(layer "In9.Cu")
	)
	(gr_line
		(start 126.817882 -231.52227)
		(end 126.347982 -232.332276)
		(stroke
			(width 0.254)
			(type default)
		)
		(layer "In9.Cu")
	)
	(gr_line
		(start 126.817882 -229.902258)
		(end 126.347982 -230.712264)
		(stroke
			(width 0.254)
			(type default)
		)
		(layer "In9.Cu")
	)
	(gr_line
		(start 126.817882 -228.282246)
		(end 126.347982 -229.092252)
		(stroke
			(width 0.254)
			(type default)
		)
		(layer "In9.Cu")
	)
	(gr_line
		(start 126.916434 -386.573014)
		(end 126.100332 -386.573014)
		(stroke
			(width 0.508)
			(type default)
		)
		(layer "In9.Cu")
	)
	(gr_line
		(start 127.117856 -281.378406)
		(end 126.177802 -279.758394)
		(stroke
			(width 0.254)
			(type default)
		)
		(layer "In9.Cu")
	)
	(gr_line
		(start 127.117856 -268.41831)
		(end 126.177802 -266.798298)
		(stroke
			(width 0.254)
			(type default)
		)
		(layer "In9.Cu")
	)
	(gr_line
		(start 127.117856 -263.558274)
		(end 125.707902 -262.748268)
		(stroke
			(width 0.254)
			(type default)
		)
		(layer "In9.Cu")
	)
	(gr_line
		(start 127.287782 -248.532396)
		(end 126.347982 -250.152408)
		(stroke
			(width 0.254)
			(type default)
		)
		(layer "In9.Cu")
	)
	(gr_line
		(start 127.287782 -245.292372)
		(end 126.347982 -246.912384)
		(stroke
			(width 0.254)
			(type default)
		)
		(layer "In9.Cu")
	)
	(gr_line
		(start 127.287782 -242.052348)
		(end 126.347982 -243.67236)
		(stroke
			(width 0.254)
			(type default)
		)
		(layer "In9.Cu")
	)
	(gr_line
		(start 127.287782 -238.812324)
		(end 126.347982 -240.432336)
		(stroke
			(width 0.254)
			(type default)
		)
		(layer "In9.Cu")
	)
	(gr_line
		(start 127.287782 -233.952288)
		(end 126.347982 -235.5723)
		(stroke
			(width 0.254)
			(type default)
		)
		(layer "In9.Cu")
	)
	(gr_line
		(start 127.58801 -290.288472)
		(end 126.647956 -288.66846)
		(stroke
			(width 0.254)
			(type default)
		)
		(layer "In9.Cu")
	)
	(gr_line
		(start 127.58801 -290.288472)
		(end 129.467864 -293.528242)
		(stroke
			(width 0.254)
			(type default)
		)
		(layer "In9.Cu")
	)
	(gr_line
		(start 127.58801 -287.048448)
		(end 126.647956 -285.428436)
		(stroke
			(width 0.254)
			(type default)
		)
		(layer "In9.Cu")
	)
	(gr_line
		(start 127.58801 -283.808424)
		(end 126.647956 -282.188412)
		(stroke
			(width 0.254)
			(type default)
		)
		(layer "In9.Cu")
	)
	(gr_line
		(start 127.58801 -278.948388)
		(end 126.647956 -277.328376)
		(stroke
			(width 0.254)
			(type default)
		)
		(layer "In9.Cu")
	)
	(gr_line
		(start 127.58801 -275.708364)
		(end 126.647956 -274.088352)
		(stroke
			(width 0.254)
			(type default)
		)
		(layer "In9.Cu")
	)
	(gr_line
		(start 127.58801 -272.46834)
		(end 126.647956 -270.848328)
		(stroke
			(width 0.254)
			(type default)
		)
		(layer "In9.Cu")
	)
	(gr_line
		(start 127.58801 -269.228316)
		(end 127.117856 -268.41831)
		(stroke
			(width 0.254)
			(type default)
		)
		(layer "In9.Cu")
	)
	(gr_line
		(start 127.58801 -262.748268)
		(end 127.117856 -263.558274)
		(stroke
			(width 0.254)
			(type default)
		)
		(layer "In9.Cu")
	)
	(gr_line
		(start 128.302004 -387.958584)
		(end 126.916434 -386.573014)
		(stroke
			(width 0.508)
			(type default)
		)
		(layer "In9.Cu")
	)
	(gr_line
		(start 128.463802 -169.464228)
		(end 126.426722 -169.464228)
		(stroke
			(width 0.508)
			(type default)
		)
		(layer "In9.Cu")
	)
	(gr_line
		(start 128.69799 -228.282246)
		(end 126.817882 -228.282246)
		(stroke
			(width 0.254)
			(type default)
		)
		(layer "In9.Cu")
	)
	(gr_circle
		(center 128.71323 -154.465274)
		(end 129.60223 -154.465274)
		(stroke
			(width 0.2)
			(type default)
		)
		(fill no)
		(layer "In9.Cu")
	)
	(gr_circle
		(center 128.71323 -153.728674)
		(end 129.60223 -153.728674)
		(stroke
			(width 0.2)
			(type default)
		)
		(fill no)
		(layer "In9.Cu")
	)
	(gr_circle
		(center 128.71323 -152.992074)
		(end 129.60223 -152.992074)
		(stroke
			(width 0.2)
			(type default)
		)
		(fill no)
		(layer "In9.Cu")
	)
	(gr_circle
		(center 129.24663 -153.347674)
		(end 130.13563 -153.347674)
		(stroke
			(width 0.2)
			(type default)
		)
		(fill no)
		(layer "In9.Cu")
	)
	(gr_circle
		(center 129.27203 -154.109674)
		(end 130.16103 -154.109674)
		(stroke
			(width 0.2)
			(type default)
		)
		(fill no)
		(layer "In9.Cu")
	)
	(gr_line
		(start 129.467864 -293.528242)
		(end 130.407918 -293.528242)
		(stroke
			(width 0.254)
			(type default)
		)
		(layer "In9.Cu")
	)
	(gr_circle
		(center 129.796794 -153.670254)
		(end 130.685794 -153.670254)
		(stroke
			(width 0.2)
			(type default)
		)
		(fill no)
		(layer "In9.Cu")
	)
	(gr_circle
		(center 129.796794 -152.933654)
		(end 130.685794 -152.933654)
		(stroke
			(width 0.2)
			(type default)
		)
		(fill no)
		(layer "In9.Cu")
	)
	(gr_line
		(start 129.885186 -168.042844)
		(end 128.463802 -169.464228)
		(stroke
			(width 0.508)
			(type default)
		)
		(layer "In9.Cu")
	)
	(gr_line
		(start 129.885186 -168.042844)
		(end 149.473666 -168.042844)
		(stroke
			(width 0.508)
			(type default)
		)
		(layer "In9.Cu")
	)
	(gr_circle
		(center 130.305048 -155.94076)
		(end 131.194048 -155.94076)
		(stroke
			(width 0.2)
			(type default)
		)
		(fill no)
		(layer "In9.Cu")
	)
	(gr_circle
		(center 130.305048 -155.20416)
		(end 131.194048 -155.20416)
		(stroke
			(width 0.2)
			(type default)
		)
		(fill no)
		(layer "In9.Cu")
	)
	(gr_line
		(start 130.407918 -293.528242)
		(end 131.347972 -295.148254)
		(stroke
			(width 0.254)
			(type default)
		)
		(layer "In9.Cu")
	)
	(gr_line
		(start 130.407918 -262.748268)
		(end 127.58801 -262.748268)
		(stroke
			(width 0.254)
			(type default)
		)
		(layer "In9.Cu")
	)
	(gr_line
		(start 130.416046 -122.633994)
		(end 156.121862 -122.633994)
		(stroke
			(width 0.508)
			(type default)
		)
		(layer "In9.Cu")
	)
	(gr_circle
		(center 130.49885 -154.542744)
		(end 131.37896 -154.542744)
		(stroke
			(width 0.2)
			(type default)
		)
		(fill no)
		(layer "In9.Cu")
	)
	(gr_circle
		(center 131.11607 -154.542744)
		(end 131.99618 -154.542744)
		(stroke
			(width 0.2)
			(type default)
		)
		(fill no)
		(layer "In9.Cu")
	)
	(gr_line
		(start 131.231386 -327.600564)
		(end 131.818126 -327.013824)
		(stroke
			(width 0.508)
			(type default)
		)
		(layer "In9.Cu")
	)
	(gr_line
		(start 131.347972 -295.148254)
		(end 131.818126 -295.95826)
		(stroke
			(width 0.254)
			(type default)
		)
		(layer "In9.Cu")
	)
	(gr_line
		(start 131.517898 -223.422464)
		(end 128.69799 -228.282246)
		(stroke
			(width 0.254)
			(type default)
		)
		(layer "In9.Cu")
	)
	(gr_line
		(start 131.517898 -221.802452)
		(end 131.517898 -223.422464)
		(stroke
			(width 0.254)
			(type default)
		)
		(layer "In9.Cu")
	)
	(gr_line
		(start 131.517898 -211.809076)
		(end 131.517898 -221.802452)
		(stroke
			(width 0.508)
			(type default)
		)
		(layer "In9.Cu")
	)
	(gr_circle
		(center 131.73329 -154.542744)
		(end 132.6134 -154.542744)
		(stroke
			(width 0.2)
			(type default)
		)
		(fill no)
		(layer "In9.Cu")
	)
	(gr_line
		(start 131.817872 -263.558274)
		(end 130.407918 -262.748268)
		(stroke
			(width 0.254)
			(type default)
		)
		(layer "In9.Cu")
	)
	(gr_line
		(start 131.818126 -341.818214)
		(end 131.47802 -342.15832)
		(stroke
			(width 0.508)
			(type default)
		)
		(layer "In9.Cu")
	)
	(gr_line
		(start 131.818126 -341.818214)
		(end 132.236464 -342.236552)
		(stroke
			(width 0.508)
			(type default)
		)
		(layer "In9.Cu")
	)
	(gr_line
		(start 131.818126 -327.600564)
		(end 131.231386 -327.600564)
		(stroke
			(width 0.508)
			(type default)
		)
		(layer "In9.Cu")
	)
	(gr_line
		(start 131.818126 -327.600564)
		(end 131.818126 -341.818214)
		(stroke
			(width 0.508)
			(type default)
		)
		(layer "In9.Cu")
	)
	(gr_line
		(start 131.818126 -327.600564)
		(end 131.818126 -308.979824)
		(stroke
			(width 0.508)
			(type default)
		)
		(layer "In9.Cu")
	)
	(gr_line
		(start 131.818126 -295.95826)
		(end 131.818126 -308.979824)
		(stroke
			(width 0.508)
			(type default)
		)
		(layer "In9.Cu")
	)
	(gr_line
		(start 132.236464 -342.236552)
		(end 193.797174 -342.236552)
		(stroke
			(width 0.508)
			(type default)
		)
		(layer "In9.Cu")
	)
	(gr_line
		(start 135.653018 -152.836626)
		(end 104.23271 -152.836626)
		(stroke
			(width 0.508)
			(type default)
		)
		(layer "In9.Cu")
	)
	(gr_line
		(start 136.398 -167.92956)
		(end 136.398 -153.581608)
		(stroke
			(width 0.508)
			(type default)
		)
		(layer "In9.Cu")
	)
	(gr_line
		(start 136.398 -153.581608)
		(end 135.653018 -152.836626)
		(stroke
			(width 0.508)
			(type default)
		)
		(layer "In9.Cu")
	)
	(gr_line
		(start 136.517888 -263.558274)
		(end 131.817872 -263.558274)
		(stroke
			(width 0.254)
			(type default)
		)
		(layer "In9.Cu")
	)
	(gr_line
		(start 136.531858 -387.958584)
		(end 128.302004 -387.958584)
		(stroke
			(width 0.508)
			(type default)
		)
		(layer "In9.Cu")
	)
	(gr_line
		(start 136.689338 -383.477516)
		(end 137.033762 -383.82194)
		(stroke
			(width 0.508)
			(type default)
		)
		(layer "In9.Cu")
	)
	(gr_line
		(start 136.855962 -387.6167)
		(end 136.864852 -387.62559)
		(stroke
			(width 0.508)
			(type default)
		)
		(layer "In9.Cu")
	)
	(gr_line
		(start 136.855962 -386.689346)
		(end 136.855962 -387.6167)
		(stroke
			(width 0.508)
			(type default)
		)
		(layer "In9.Cu")
	)
	(gr_line
		(start 136.855962 -386.689346)
		(end 136.855962 -386.320538)
		(stroke
			(width 0.254)
			(type default)
		)
		(layer "In9.Cu")
	)
	(gr_line
		(start 136.855962 -386.320538)
		(end 137.033762 -386.142738)
		(stroke
			(width 0.254)
			(type default)
		)
		(layer "In9.Cu")
	)
	(gr_line
		(start 136.864852 -387.62559)
		(end 136.531858 -387.958584)
		(stroke
			(width 0.508)
			(type default)
		)
		(layer "In9.Cu")
	)
	(gr_line
		(start 136.988042 -264.36828)
		(end 136.517888 -263.558274)
		(stroke
			(width 0.254)
			(type default)
		)
		(layer "In9.Cu")
	)
	(gr_line
		(start 137.033762 -386.142738)
		(end 137.033762 -384.62077)
		(stroke
			(width 0.254)
			(type default)
		)
		(layer "In9.Cu")
	)
	(gr_line
		(start 137.033762 -384.62077)
		(end 137.033762 -383.82194)
		(stroke
			(width 0.508)
			(type default)
		)
		(layer "In9.Cu")
	)
	(gr_line
		(start 138.549126 -141.523466)
		(end 182.457598 -185.431938)
		(stroke
			(width 0.508)
			(type default)
		)
		(layer "In9.Cu")
	)
	(gr_line
		(start 138.588496 -387.62559)
		(end 136.864852 -387.62559)
		(stroke
			(width 0.508)
			(type default)
		)
		(layer "In9.Cu")
	)
	(gr_line
		(start 140.222224 -385.991862)
		(end 138.588496 -387.62559)
		(stroke
			(width 0.508)
			(type default)
		)
		(layer "In9.Cu")
	)
	(gr_line
		(start 140.222224 -384.1369)
		(end 140.222224 -385.991862)
		(stroke
			(width 0.508)
			(type default)
		)
		(layer "In9.Cu")
	)
	(gr_line
		(start 141.01953 -383.339594)
		(end 140.222224 -384.1369)
		(stroke
			(width 0.508)
			(type default)
		)
		(layer "In9.Cu")
	)
	(gr_line
		(start 141.687804 -264.36828)
		(end 136.988042 -264.36828)
		(stroke
			(width 0.254)
			(type default)
		)
		(layer "In9.Cu")
	)
	(gr_line
		(start 143.098012 -266.798298)
		(end 141.687804 -264.36828)
		(stroke
			(width 0.254)
			(type default)
		)
		(layer "In9.Cu")
	)
	(gr_line
		(start 143.098012 -266.798298)
		(end 145.690844 -266.798298)
		(stroke
			(width 0.254)
			(type default)
		)
		(layer "In9.Cu")
	)
	(gr_line
		(start 145.690844 -266.798298)
		(end 191.409066 -266.798298)
		(stroke
			(width 0.508)
			(type default)
		)
		(layer "In9.Cu")
	)
	(gr_line
		(start 153.72334 -387.74497)
		(end 153.72334 -383.490724)
		(stroke
			(width 0.508)
			(type default)
		)
		(layer "In9.Cu")
	)
	(gr_line
		(start 153.72334 -383.490724)
		(end 153.710132 -383.477516)
		(stroke
			(width 0.508)
			(type default)
		)
		(layer "In9.Cu")
	)
	(gr_line
		(start 154.297634 -388.319264)
		(end 153.72334 -387.74497)
		(stroke
			(width 0.508)
			(type default)
		)
		(layer "In9.Cu")
	)
	(gr_line
		(start 156.121862 -122.633994)
		(end 161.468816 -127.980948)
		(stroke
			(width 0.508)
			(type default)
		)
		(layer "In9.Cu")
	)
	(gr_line
		(start 157.044136 -388.319264)
		(end 154.297634 -388.319264)
		(stroke
			(width 0.508)
			(type default)
		)
		(layer "In9.Cu")
	)
	(gr_line
		(start 158.882588 -386.480812)
		(end 157.044136 -388.319264)
		(stroke
			(width 0.508)
			(type default)
		)
		(layer "In9.Cu")
	)
	(gr_line
		(start 159.434276 -386.480812)
		(end 158.882588 -386.480812)
		(stroke
			(width 0.508)
			(type default)
		)
		(layer "In9.Cu")
	)
	(gr_line
		(start 160.75025 -397.873728)
		(end 160.75025 -387.952996)
		(stroke
			(width 0.508)
			(type default)
		)
		(layer "In9.Cu")
	)
	(gr_line
		(start 160.75025 -387.952996)
		(end 160.75025 -387.796786)
		(stroke
			(width 0.508)
			(type default)
		)
		(layer "In9.Cu")
	)
	(gr_line
		(start 160.75025 -387.952996)
		(end 164.950902 -387.952996)
		(stroke
			(width 0.508)
			(type default)
		)
		(layer "In9.Cu")
	)
	(gr_line
		(start 160.75025 -387.796786)
		(end 159.434276 -386.480812)
		(stroke
			(width 0.508)
			(type default)
		)
		(layer "In9.Cu")
	)
	(gr_line
		(start 161.468816 -127.980948)
		(end 274.875244 -127.980948)
		(stroke
			(width 0.508)
			(type default)
		)
		(layer "In9.Cu")
	)
	(gr_line
		(start 163.546028 -413.779716)
		(end 165.12286 -412.202884)
		(stroke
			(width 0.508)
			(type default)
		)
		(layer "In9.Cu")
	)
	(gr_line
		(start 164.530786 -266.386564)
		(end 164.187886 -266.729464)
		(stroke
			(width 0.508)
			(type default)
		)
		(layer "In9.Cu")
	)
	(gr_line
		(start 164.530786 -183.099964)
		(end 149.473666 -168.042844)
		(stroke
			(width 0.508)
			(type default)
		)
		(layer "In9.Cu")
	)
	(gr_line
		(start 164.530786 -183.099964)
		(end 164.530786 -266.386564)
		(stroke
			(width 0.508)
			(type default)
		)
		(layer "In9.Cu")
	)
	(gr_line
		(start 164.846 -194.909948)
		(end 164.592508 -195.16344)
		(stroke
			(width 0.508)
			(type default)
		)
		(layer "In9.Cu")
	)
	(gr_line
		(start 164.873686 -266.729464)
		(end 164.530786 -266.386564)
		(stroke
			(width 0.508)
			(type default)
		)
		(layer "In9.Cu")
	)
	(gr_line
		(start 164.950902 -387.952996)
		(end 166.28237 -389.284464)
		(stroke
			(width 0.508)
			(type default)
		)
		(layer "In9.Cu")
	)
	(gr_line
		(start 165.023292 -194.909948)
		(end 164.530786 -194.417442)
		(stroke
			(width 0.508)
			(type default)
		)
		(layer "In9.Cu")
	)
	(gr_line
		(start 165.023292 -194.909948)
		(end 164.846 -194.909948)
		(stroke
			(width 0.508)
			(type default)
		)
		(layer "In9.Cu")
	)
	(gr_line
		(start 165.12286 -412.202884)
		(end 165.12286 -402.246338)
		(stroke
			(width 0.508)
			(type default)
		)
		(layer "In9.Cu")
	)
	(gr_line
		(start 165.12286 -402.246338)
		(end 160.75025 -397.873728)
		(stroke
			(width 0.508)
			(type default)
		)
		(layer "In9.Cu")
	)
	(gr_line
		(start 166.28237 -389.284464)
		(end 168.764458 -389.284464)
		(stroke
			(width 0.508)
			(type default)
		)
		(layer "In9.Cu")
	)
	(gr_line
		(start 168.764458 -389.284464)
		(end 169.545762 -388.50316)
		(stroke
			(width 0.508)
			(type default)
		)
		(layer "In9.Cu")
	)
	(gr_line
		(start 169.051478 -383.339594)
		(end 141.01953 -383.339594)
		(stroke
			(width 0.508)
			(type default)
		)
		(layer "In9.Cu")
	)
	(gr_line
		(start 169.545762 -388.50316)
		(end 169.545762 -388.319518)
		(stroke
			(width 0.508)
			(type default)
		)
		(layer "In9.Cu")
	)
	(gr_line
		(start 169.545762 -388.319518)
		(end 169.545762 -383.833878)
		(stroke
			(width 0.508)
			(type default)
		)
		(layer "In9.Cu")
	)
	(gr_line
		(start 169.545762 -383.833878)
		(end 169.051478 -383.339594)
		(stroke
			(width 0.508)
			(type default)
		)
		(layer "In9.Cu")
	)
	(gr_line
		(start 170.556936 -389.330692)
		(end 169.545762 -388.319518)
		(stroke
			(width 0.508)
			(type default)
		)
		(layer "In9.Cu")
	)
	(gr_circle
		(center 170.995594 -404.792688)
		(end 173.154594 -404.792688)
		(stroke
			(width 4.318)
			(type default)
		)
		(fill no)
		(layer "In9.Cu")
	)
	(gr_circle
		(center 176.332134 -26.634948)
		(end 177.221134 -26.634948)
		(stroke
			(width 0.2)
			(type default)
		)
		(fill no)
		(layer "In9.Cu")
	)
	(gr_circle
		(center 176.713134 -25.949148)
		(end 177.602134 -25.949148)
		(stroke
			(width 0.2)
			(type default)
		)
		(fill no)
		(layer "In9.Cu")
	)
	(gr_circle
		(center 176.878234 -19.942048)
		(end 177.767234 -19.942048)
		(stroke
			(width 0.2)
			(type default)
		)
		(fill no)
		(layer "In9.Cu")
	)
	(gr_circle
		(center 176.968912 -21.349208)
		(end 177.857912 -21.349208)
		(stroke
			(width 0.2)
			(type default)
		)
		(fill no)
		(layer "In9.Cu")
	)
	(gr_circle
		(center 176.968912 -20.714208)
		(end 177.857912 -20.714208)
		(stroke
			(width 0.2)
			(type default)
		)
		(fill no)
		(layer "In9.Cu")
	)
	(gr_line
		(start 177.165 -29.936948)
		(end 66.421 -29.936948)
		(stroke
			(width 0.508)
			(type default)
		)
		(layer "In9.Cu")
	)
	(gr_circle
		(center 177.221134 -26.634948)
		(end 178.110134 -26.634948)
		(stroke
			(width 0.2)
			(type default)
		)
		(fill no)
		(layer "In9.Cu")
	)
	(gr_circle
		(center 177.472594 -21.85289)
		(end 178.361594 -21.85289)
		(stroke
			(width 0.2)
			(type default)
		)
		(fill no)
		(layer "In9.Cu")
	)
	(gr_circle
		(center 177.495454 -376.49658)
		(end 179.654454 -376.49658)
		(stroke
			(width 4.318)
			(type default)
		)
		(fill no)
		(layer "In9.Cu")
	)
	(gr_circle
		(center 177.602134 -25.949148)
		(end 178.491134 -25.949148)
		(stroke
			(width 0.2)
			(type default)
		)
		(fill no)
		(layer "In9.Cu")
	)
	(gr_circle
		(center 178.110134 -26.634948)
		(end 178.999134 -26.634948)
		(stroke
			(width 0.2)
			(type default)
		)
		(fill no)
		(layer "In9.Cu")
	)
	(gr_circle
		(center 178.491134 -25.949148)
		(end 179.380134 -25.949148)
		(stroke
			(width 0.2)
			(type default)
		)
		(fill no)
		(layer "In9.Cu")
	)
	(gr_circle
		(center 179.507134 -25.517348)
		(end 180.396134 -25.517348)
		(stroke
			(width 0.2)
			(type default)
		)
		(fill no)
		(layer "In9.Cu")
	)
	(gr_circle
		(center 180.921914 -27.107388)
		(end 181.810914 -27.107388)
		(stroke
			(width 0.2)
			(type default)
		)
		(fill no)
		(layer "In9.Cu")
	)
	(gr_line
		(start 181.47284 -389.330692)
		(end 170.556936 -389.330692)
		(stroke
			(width 0.508)
			(type default)
		)
		(layer "In9.Cu")
	)
	(gr_line
		(start 181.955948 -366.994186)
		(end 184.391808 -369.430046)
		(stroke
			(width 0.508)
			(type default)
		)
		(layer "In9.Cu")
	)
	(gr_line
		(start 182.457598 -185.431938)
		(end 205.629002 -185.431938)
		(stroke
			(width 0.508)
			(type default)
		)
		(layer "In9.Cu")
	)
	(gr_circle
		(center 183.610758 -353.283774)
		(end 184.490868 -353.283774)
		(stroke
			(width 0.2)
			(type default)
		)
		(fill no)
		(layer "In9.Cu")
	)
	(gr_circle
		(center 184.227978 -353.283774)
		(end 185.108088 -353.283774)
		(stroke
			(width 0.2)
			(type default)
		)
		(fill no)
		(layer "In9.Cu")
	)
	(gr_line
		(start 184.258458 -410.708348)
		(end 184.258458 -400.09572)
		(stroke
			(width 0.635)
			(type default)
		)
		(layer "In9.Cu")
	)
	(gr_line
		(start 184.258458 -400.09572)
		(end 184.463944 -399.890234)
		(stroke
			(width 0.635)
			(type default)
		)
		(layer "In9.Cu")
	)
	(gr_line
		(start 184.391808 -386.411724)
		(end 181.47284 -389.330692)
		(stroke
			(width 0.508)
			(type default)
		)
		(layer "In9.Cu")
	)
	(gr_line
		(start 184.391808 -369.430046)
		(end 184.391808 -386.411724)
		(stroke
			(width 0.508)
			(type default)
		)
		(layer "In9.Cu")
	)
	(gr_line
		(start 184.463944 -399.890234)
		(end 188.119004 -399.890234)
		(stroke
			(width 0.635)
			(type default)
		)
		(layer "In9.Cu")
	)
	(gr_line
		(start 184.8104 -411.26029)
		(end 184.258458 -410.708348)
		(stroke
			(width 0.635)
			(type default)
		)
		(layer "In9.Cu")
	)
	(gr_circle
		(center 184.845198 -353.283774)
		(end 185.725308 -353.283774)
		(stroke
			(width 0.2)
			(type default)
		)
		(fill no)
		(layer "In9.Cu")
	)
	(gr_circle
		(center 184.962292 -352.558604)
		(end 185.851292 -352.558604)
		(stroke
			(width 0.2)
			(type default)
		)
		(fill no)
		(layer "In9.Cu")
	)
	(gr_circle
		(center 184.962292 -351.822004)
		(end 185.851292 -351.822004)
		(stroke
			(width 0.2)
			(type default)
		)
		(fill no)
		(layer "In9.Cu")
	)
	(gr_circle
		(center 185.547254 -354.892864)
		(end 186.436254 -354.892864)
		(stroke
			(width 0.2)
			(type default)
		)
		(fill no)
		(layer "In9.Cu")
	)
	(gr_circle
		(center 185.547254 -354.156264)
		(end 186.436254 -354.156264)
		(stroke
			(width 0.2)
			(type default)
		)
		(fill no)
		(layer "In9.Cu")
	)
	(gr_circle
		(center 186.034172 -362.234988)
		(end 186.923172 -362.234988)
		(stroke
			(width 0.2)
			(type default)
		)
		(fill no)
		(layer "In9.Cu")
	)
	(gr_circle
		(center 186.034172 -361.472988)
		(end 186.923172 -361.472988)
		(stroke
			(width 0.2)
			(type default)
		)
		(fill no)
		(layer "In9.Cu")
	)
	(gr_circle
		(center 186.034172 -360.710988)
		(end 186.923172 -360.710988)
		(stroke
			(width 0.2)
			(type default)
		)
		(fill no)
		(layer "In9.Cu")
	)
	(gr_circle
		(center 186.072018 -353.716844)
		(end 186.961018 -353.716844)
		(stroke
			(width 0.2)
			(type default)
		)
		(fill no)
		(layer "In9.Cu")
	)
	(gr_circle
		(center 186.097418 -354.478844)
		(end 186.986418 -354.478844)
		(stroke
			(width 0.2)
			(type default)
		)
		(fill no)
		(layer "In9.Cu")
	)
	(gr_circle
		(center 186.630818 -354.834444)
		(end 187.519818 -354.834444)
		(stroke
			(width 0.2)
			(type default)
		)
		(fill no)
		(layer "In9.Cu")
	)
	(gr_circle
		(center 186.630818 -354.097844)
		(end 187.519818 -354.097844)
		(stroke
			(width 0.2)
			(type default)
		)
		(fill no)
		(layer "In9.Cu")
	)
	(gr_circle
		(center 186.630818 -353.361244)
		(end 187.519818 -353.361244)
		(stroke
			(width 0.2)
			(type default)
		)
		(fill no)
		(layer "In9.Cu")
	)
	(gr_circle
		(center 186.796172 -362.234988)
		(end 187.685172 -362.234988)
		(stroke
			(width 0.2)
			(type default)
		)
		(fill no)
		(layer "In9.Cu")
	)
	(gr_circle
		(center 186.796172 -361.472988)
		(end 187.685172 -361.472988)
		(stroke
			(width 0.2)
			(type default)
		)
		(fill no)
		(layer "In9.Cu")
	)
	(gr_circle
		(center 186.796172 -360.710988)
		(end 187.685172 -360.710988)
		(stroke
			(width 0.2)
			(type default)
		)
		(fill no)
		(layer "In9.Cu")
	)
	(gr_line
		(start 187.965334 -411.26029)
		(end 184.8104 -411.26029)
		(stroke
			(width 0.635)
			(type default)
		)
		(layer "In9.Cu")
	)
	(gr_line
		(start 188.119004 -399.890234)
		(end 188.303916 -400.075146)
		(stroke
			(width 0.635)
			(type default)
		)
		(layer "In9.Cu")
	)
	(gr_line
		(start 188.303916 -402.905976)
		(end 191.073786 -405.675846)
		(stroke
			(width 0.635)
			(type default)
		)
		(layer "In9.Cu")
	)
	(gr_line
		(start 188.303916 -400.075146)
		(end 188.303916 -402.905976)
		(stroke
			(width 0.635)
			(type default)
		)
		(layer "In9.Cu")
	)
	(gr_line
		(start 188.720222 -412.015178)
		(end 187.965334 -411.26029)
		(stroke
			(width 0.635)
			(type default)
		)
		(layer "In9.Cu")
	)
	(gr_circle
		(center 190.508636 -23.593552)
		(end 191.397636 -23.593552)
		(stroke
			(width 0.2)
			(type default)
		)
		(fill no)
		(layer "In9.Cu")
	)
	(gr_circle
		(center 190.508636 -22.856952)
		(end 191.397636 -22.856952)
		(stroke
			(width 0.2)
			(type default)
		)
		(fill no)
		(layer "In9.Cu")
	)
	(gr_line
		(start 191.073786 -405.675846)
		(end 195.418964 -405.675846)
		(stroke
			(width 0.635)
			(type default)
		)
		(layer "In9.Cu")
	)
	(gr_line
		(start 191.409066 -266.798298)
		(end 192.824354 -268.213586)
		(stroke
			(width 0.508)
			(type default)
		)
		(layer "In9.Cu")
	)
	(gr_circle
		(center 191.67983 -362.430568)
		(end 193.07683 -362.430568)
		(stroke
			(width 0.2)
			(type default)
		)
		(fill no)
		(layer "In9.Cu")
	)
	(gr_circle
		(center 191.927734 -13.106908)
		(end 192.816734 -13.106908)
		(stroke
			(width 0.2)
			(type default)
		)
		(fill no)
		(layer "In9.Cu")
	)
	(gr_circle
		(center 191.937386 -353.309174)
		(end 192.817496 -353.309174)
		(stroke
			(width 0.2)
			(type default)
		)
		(fill no)
		(layer "In9.Cu")
	)
	(gr_circle
		(center 192.461134 -16.416528)
		(end 193.350134 -16.416528)
		(stroke
			(width 0.2)
			(type default)
		)
		(fill no)
		(layer "In9.Cu")
	)
	(gr_circle
		(center 192.461134 -15.781528)
		(end 193.350134 -15.781528)
		(stroke
			(width 0.2)
			(type default)
		)
		(fill no)
		(layer "In9.Cu")
	)
	(gr_circle
		(center 192.554606 -353.309174)
		(end 193.434716 -353.309174)
		(stroke
			(width 0.2)
			(type default)
		)
		(fill no)
		(layer "In9.Cu")
	)
	(gr_circle
		(center 192.689734 -13.106908)
		(end 193.578734 -13.106908)
		(stroke
			(width 0.2)
			(type default)
		)
		(fill no)
		(layer "In9.Cu")
	)
	(gr_circle
		(center 193.096134 -16.416528)
		(end 193.985134 -16.416528)
		(stroke
			(width 0.2)
			(type default)
		)
		(fill no)
		(layer "In9.Cu")
	)
	(gr_circle
		(center 193.096134 -15.781528)
		(end 193.985134 -15.781528)
		(stroke
			(width 0.2)
			(type default)
		)
		(fill no)
		(layer "In9.Cu")
	)
	(gr_circle
		(center 193.171826 -353.309174)
		(end 194.051936 -353.309174)
		(stroke
			(width 0.2)
			(type default)
		)
		(fill no)
		(layer "In9.Cu")
	)
	(gr_circle
		(center 193.28892 -352.563684)
		(end 194.17792 -352.563684)
		(stroke
			(width 0.2)
			(type default)
		)
		(fill no)
		(layer "In9.Cu")
	)
	(gr_circle
		(center 193.28892 -351.827084)
		(end 194.17792 -351.827084)
		(stroke
			(width 0.2)
			(type default)
		)
		(fill no)
		(layer "In9.Cu")
	)
	(gr_circle
		(center 193.731134 -15.781528)
		(end 194.620134 -15.781528)
		(stroke
			(width 0.2)
			(type default)
		)
		(fill no)
		(layer "In9.Cu")
	)
	(gr_line
		(start 193.797174 -342.236552)
		(end 196.293994 -339.739732)
		(stroke
			(width 0.508)
			(type default)
		)
		(layer "In9.Cu")
	)
	(gr_circle
		(center 193.858134 -16.543528)
		(end 194.747134 -16.543528)
		(stroke
			(width 0.2)
			(type default)
		)
		(fill no)
		(layer "In9.Cu")
	)
	(gr_circle
		(center 193.873882 -354.918264)
		(end 194.762882 -354.918264)
		(stroke
			(width 0.2)
			(type default)
		)
		(fill no)
		(layer "In9.Cu")
	)
	(gr_circle
		(center 193.873882 -354.181664)
		(end 194.762882 -354.181664)
		(stroke
			(width 0.2)
			(type default)
		)
		(fill no)
		(layer "In9.Cu")
	)
	(gr_circle
		(center 194.398646 -353.742244)
		(end 195.287646 -353.742244)
		(stroke
			(width 0.2)
			(type default)
		)
		(fill no)
		(layer "In9.Cu")
	)
	(gr_circle
		(center 194.424046 -354.504244)
		(end 195.313046 -354.504244)
		(stroke
			(width 0.2)
			(type default)
		)
		(fill no)
		(layer "In9.Cu")
	)
	(gr_line
		(start 194.505072 -441.989972)
		(end 8.50011 -441.989972)
		(stroke
			(width 3.048)
			(type default)
		)
		(layer "In9.Cu")
	)
	(gr_arc
		(start 194.505072 -441.989972)
		(mid 194.858553 -441.843573)
		(end 195.004944 -441.4901)
		(stroke
			(width 3.048)
			(type default)
		)
		(layer "In9.Cu")
	)
	(gr_line
		(start 194.643502 -325.190612)
		(end 194.643502 -323.540882)
		(stroke
			(width 0.508)
			(type default)
		)
		(layer "In9.Cu")
	)
	(gr_line
		(start 194.643502 -323.540882)
		(end 196.293994 -321.89039)
		(stroke
			(width 0.508)
			(type default)
		)
		(layer "In9.Cu")
	)
	(gr_arc
		(start 194.701922 -9.780016)
		(mid 195.287707 -11.194227)
		(end 196.701918 -11.780012)
		(stroke
			(width 3.048)
			(type default)
		)
		(layer "In9.Cu")
	)
	(gr_arc
		(start 194.701922 -5.780024)
		(mid 194.555654 -5.42634)
		(end 194.20205 -5.279898)
		(stroke
			(width 3.048)
			(type default)
		)
		(layer "In9.Cu")
	)
	(gr_line
		(start 194.701922 -5.780024)
		(end 194.701922 -9.780016)
		(stroke
			(width 3.048)
			(type default)
		)
		(layer "In9.Cu")
	)
	(gr_circle
		(center 194.957446 -354.859844)
		(end 195.846446 -354.859844)
		(stroke
			(width 0.2)
			(type default)
		)
		(fill no)
		(layer "In9.Cu")
	)
	(gr_circle
		(center 194.957446 -354.123244)
		(end 195.846446 -354.123244)
		(stroke
			(width 0.2)
			(type default)
		)
		(fill no)
		(layer "In9.Cu")
	)
	(gr_circle
		(center 194.957446 -353.386644)
		(end 195.846446 -353.386644)
		(stroke
			(width 0.2)
			(type default)
		)
		(fill no)
		(layer "In9.Cu")
	)
	(gr_line
		(start 195.004944 -441.17006)
		(end 195.004944 -441.4901)
		(stroke
			(width 3.048)
			(type default)
		)
		(layer "In9.Cu")
	)
	(gr_line
		(start 195.270882 -412.015178)
		(end 188.720222 -412.015178)
		(stroke
			(width 0.635)
			(type default)
		)
		(layer "In9.Cu")
	)
	(gr_line
		(start 195.418964 -405.675846)
		(end 197.51167 -403.58314)
		(stroke
			(width 0.635)
			(type default)
		)
		(layer "In9.Cu")
	)
	(gr_arc
		(start 195.50507 -440.669934)
		(mid 195.151428 -440.816418)
		(end 195.004944 -441.17006)
		(stroke
			(width 3.048)
			(type default)
		)
		(layer "In9.Cu")
	)
	(gr_line
		(start 196.293994 -339.739732)
		(end 196.293994 -326.841104)
		(stroke
			(width 0.508)
			(type default)
		)
		(layer "In9.Cu")
	)
	(gr_line
		(start 196.293994 -326.841104)
		(end 194.643502 -325.190612)
		(stroke
			(width 0.508)
			(type default)
		)
		(layer "In9.Cu")
	)
	(gr_line
		(start 196.293994 -321.89039)
		(end 196.293994 -271.683226)
		(stroke
			(width 0.508)
			(type default)
		)
		(layer "In9.Cu")
	)
	(gr_line
		(start 196.293994 -271.683226)
		(end 192.824354 -268.213586)
		(stroke
			(width 0.508)
			(type default)
		)
		(layer "In9.Cu")
	)
	(gr_line
		(start 196.29755 -326.84466)
		(end 196.293994 -326.841104)
		(stroke
			(width 0.508)
			(type default)
		)
		(layer "In9.Cu")
	)
	(gr_line
		(start 196.432424 -421.71112)
		(end 196.432424 -413.17672)
		(stroke
			(width 0.635)
			(type default)
		)
		(layer "In9.Cu")
	)
	(gr_line
		(start 196.432424 -421.71112)
		(end 205.73746 -431.016156)
		(stroke
			(width 0.635)
			(type default)
		)
		(layer "In9.Cu")
	)
	(gr_line
		(start 196.432424 -413.17672)
		(end 195.270882 -412.015178)
		(stroke
			(width 0.635)
			(type default)
		)
		(layer "In9.Cu")
	)
	(gr_line
		(start 196.701918 -11.780012)
		(end 221.30004 -11.780012)
		(stroke
			(width 3.048)
			(type default)
		)
		(layer "In9.Cu")
	)
	(gr_line
		(start 197.51167 -403.58314)
		(end 197.51167 -400.104356)
		(stroke
			(width 0.635)
			(type default)
		)
		(layer "In9.Cu")
	)
	(gr_line
		(start 197.51167 -400.104356)
		(end 197.764146 -399.85188)
		(stroke
			(width 0.635)
			(type default)
		)
		(layer "In9.Cu")
	)
	(gr_line
		(start 197.764146 -399.85188)
		(end 201.33818 -399.85188)
		(stroke
			(width 0.635)
			(type default)
		)
		(layer "In9.Cu")
	)
	(gr_circle
		(center 198.160386 -37.328094)
		(end 199.049386 -37.328094)
		(stroke
			(width 0.2)
			(type default)
		)
		(fill no)
		(layer "In9.Cu")
	)
	(gr_circle
		(center 198.486014 -30.133798)
		(end 199.375014 -30.133798)
		(stroke
			(width 0.2)
			(type default)
		)
		(fill no)
		(layer "In9.Cu")
	)
	(gr_circle
		(center 198.836026 -37.965634)
		(end 199.725026 -37.965634)
		(stroke
			(width 0.2)
			(type default)
		)
		(fill no)
		(layer "In9.Cu")
	)
	(gr_circle
		(center 199.121014 -30.133798)
		(end 200.010014 -30.133798)
		(stroke
			(width 0.2)
			(type default)
		)
		(fill no)
		(layer "In9.Cu")
	)
	(gr_circle
		(center 199.435974 -30.720538)
		(end 200.324974 -30.720538)
		(stroke
			(width 0.2)
			(type default)
		)
		(fill no)
		(layer "In9.Cu")
	)
	(gr_circle
		(center 199.756014 -30.133798)
		(end 200.645014 -30.133798)
		(stroke
			(width 0.2)
			(type default)
		)
		(fill no)
		(layer "In9.Cu")
	)
	(gr_circle
		(center 200.070974 -30.720538)
		(end 200.959974 -30.720538)
		(stroke
			(width 0.2)
			(type default)
		)
		(fill no)
		(layer "In9.Cu")
	)
	(gr_circle
		(center 200.33234 -378.160534)
		(end 201.22134 -378.160534)
		(stroke
			(width 0.2)
			(type default)
		)
		(fill no)
		(layer "In9.Cu")
	)
	(gr_circle
		(center 200.391014 -30.133798)
		(end 201.280014 -30.133798)
		(stroke
			(width 0.2)
			(type default)
		)
		(fill no)
		(layer "In9.Cu")
	)
	(gr_circle
		(center 200.705974 -30.720538)
		(end 201.594974 -30.720538)
		(stroke
			(width 0.2)
			(type default)
		)
		(fill no)
		(layer "In9.Cu")
	)
	(gr_line
		(start 201.33818 -399.85188)
		(end 201.59853 -400.11223)
		(stroke
			(width 0.635)
			(type default)
		)
		(layer "In9.Cu")
	)
	(gr_circle
		(center 201.340974 -30.720538)
		(end 202.229974 -30.720538)
		(stroke
			(width 0.2)
			(type default)
		)
		(fill no)
		(layer "In9.Cu")
	)
	(gr_line
		(start 201.59853 -403.575266)
		(end 201.811636 -403.788372)
		(stroke
			(width 0.635)
			(type default)
		)
		(layer "In9.Cu")
	)
	(gr_line
		(start 201.59853 -400.11223)
		(end 201.59853 -403.575266)
		(stroke
			(width 0.635)
			(type default)
		)
		(layer "In9.Cu")
	)
	(gr_circle
		(center 201.745342 -346.583)
		(end 202.634342 -346.583)
		(stroke
			(width 0.2)
			(type default)
		)
		(fill no)
		(layer "In9.Cu")
	)
	(gr_circle
		(center 201.745342 -345.821)
		(end 202.634342 -345.821)
		(stroke
			(width 0.2)
			(type default)
		)
		(fill no)
		(layer "In9.Cu")
	)
	(gr_circle
		(center 201.745342 -344.8304)
		(end 202.634342 -344.8304)
		(stroke
			(width 0.2)
			(type default)
		)
		(fill no)
		(layer "In9.Cu")
	)
	(gr_circle
		(center 201.745342 -344.0684)
		(end 202.634342 -344.0684)
		(stroke
			(width 0.2)
			(type default)
		)
		(fill no)
		(layer "In9.Cu")
	)
	(gr_line
		(start 201.811636 -406.668732)
		(end 203.461112 -408.318208)
		(stroke
			(width 0.635)
			(type default)
		)
		(layer "In9.Cu")
	)
	(gr_line
		(start 201.811636 -403.788372)
		(end 201.811636 -406.668732)
		(stroke
			(width 0.635)
			(type default)
		)
		(layer "In9.Cu")
	)
	(gr_line
		(start 202.819 -55.590948)
		(end 177.165 -29.936948)
		(stroke
			(width 0.508)
			(type default)
		)
		(layer "In9.Cu")
	)
	(gr_line
		(start 203.461112 -408.318208)
		(end 205.948026 -408.318208)
		(stroke
			(width 0.635)
			(type default)
		)
		(layer "In9.Cu")
	)
	(gr_line
		(start 205.566264 -194.909948)
		(end 206.92491 -194.909948)
		(stroke
			(width 0.508)
			(type default)
		)
		(layer "In9.Cu")
	)
	(gr_line
		(start 205.629002 -185.431938)
		(end 207.979772 -187.782708)
		(stroke
			(width 0.508)
			(type default)
		)
		(layer "In9.Cu")
	)
	(gr_line
		(start 205.73746 -435.231032)
		(end 207.302608 -436.79618)
		(stroke
			(width 0.635)
			(type default)
		)
		(layer "In9.Cu")
	)
	(gr_line
		(start 205.73746 -431.016156)
		(end 205.73746 -435.231032)
		(stroke
			(width 0.635)
			(type default)
		)
		(layer "In9.Cu")
	)
	(gr_line
		(start 205.948026 -408.318208)
		(end 207.991202 -406.275032)
		(stroke
			(width 0.635)
			(type default)
		)
		(layer "In9.Cu")
	)
	(gr_line
		(start 206.121 -194.909948)
		(end 165.023292 -194.909948)
		(stroke
			(width 0.508)
			(type default)
		)
		(layer "In9.Cu")
	)
	(gr_line
		(start 206.52486 -326.84466)
		(end 196.29755 -326.84466)
		(stroke
			(width 0.508)
			(type default)
		)
		(layer "In9.Cu")
	)
	(gr_line
		(start 206.92491 -194.909948)
		(end 207.137 -194.697858)
		(stroke
			(width 0.508)
			(type default)
		)
		(layer "In9.Cu")
	)
	(gr_line
		(start 207.137 -326.23252)
		(end 206.52486 -326.84466)
		(stroke
			(width 0.508)
			(type default)
		)
		(layer "In9.Cu")
	)
	(gr_line
		(start 207.137 -195.925948)
		(end 207.137 -326.23252)
		(stroke
			(width 0.508)
			(type default)
		)
		(layer "In9.Cu")
	)
	(gr_line
		(start 207.137 -193.348356)
		(end 207.137 -195.925948)
		(stroke
			(width 0.508)
			(type default)
		)
		(layer "In9.Cu")
	)
	(gr_line
		(start 207.302608 -436.79618)
		(end 229.074472 -436.79618)
		(stroke
			(width 0.635)
			(type default)
		)
		(layer "In9.Cu")
	)
	(gr_line
		(start 207.979772 -192.505584)
		(end 207.137 -193.348356)
		(stroke
			(width 0.508)
			(type default)
		)
		(layer "In9.Cu")
	)
	(gr_line
		(start 207.979772 -187.782708)
		(end 207.979772 -192.505584)
		(stroke
			(width 0.508)
			(type default)
		)
		(layer "In9.Cu")
	)
	(gr_line
		(start 207.991202 -406.275032)
		(end 207.991202 -403.722586)
		(stroke
			(width 0.635)
			(type default)
		)
		(layer "In9.Cu")
	)
	(gr_line
		(start 207.991202 -403.722586)
		(end 208.17967 -403.534118)
		(stroke
			(width 0.635)
			(type default)
		)
		(layer "In9.Cu")
	)
	(gr_line
		(start 208.17967 -403.534118)
		(end 208.17967 -400.079464)
		(stroke
			(width 0.635)
			(type default)
		)
		(layer "In9.Cu")
	)
	(gr_line
		(start 208.17967 -400.079464)
		(end 208.42605 -399.833084)
		(stroke
			(width 0.635)
			(type default)
		)
		(layer "In9.Cu")
	)
	(gr_line
		(start 208.42605 -399.833084)
		(end 211.971128 -399.833084)
		(stroke
			(width 0.635)
			(type default)
		)
		(layer "In9.Cu")
	)
	(gr_circle
		(center 208.508854 -37.366448)
		(end 209.397854 -37.366448)
		(stroke
			(width 0.2)
			(type default)
		)
		(fill no)
		(layer "In9.Cu")
	)
	(gr_line
		(start 211.971128 -399.833084)
		(end 212.28304 -400.144996)
		(stroke
			(width 0.635)
			(type default)
		)
		(layer "In9.Cu")
	)
	(gr_line
		(start 212.28304 -403.63267)
		(end 212.414358 -403.763988)
		(stroke
			(width 0.635)
			(type default)
		)
		(layer "In9.Cu")
	)
	(gr_line
		(start 212.28304 -400.144996)
		(end 212.28304 -403.63267)
		(stroke
			(width 0.635)
			(type default)
		)
		(layer "In9.Cu")
	)
	(gr_line
		(start 212.414358 -406.410668)
		(end 214.347044 -408.343354)
		(stroke
			(width 0.635)
			(type default)
		)
		(layer "In9.Cu")
	)
	(gr_line
		(start 212.414358 -403.763988)
		(end 212.414358 -406.410668)
		(stroke
			(width 0.635)
			(type default)
		)
		(layer "In9.Cu")
	)
	(gr_circle
		(center 213.67496 -360.764074)
		(end 215.83396 -360.764074)
		(stroke
			(width 4.318)
			(type default)
		)
		(fill no)
		(layer "In9.Cu")
	)
	(gr_line
		(start 214.347044 -408.343354)
		(end 216.541604 -408.343354)
		(stroke
			(width 0.635)
			(type default)
		)
		(layer "In9.Cu")
	)
	(gr_line
		(start 216.541604 -408.343354)
		(end 218.667584 -406.217374)
		(stroke
			(width 0.635)
			(type default)
		)
		(layer "In9.Cu")
	)
	(gr_line
		(start 218.667584 -406.217374)
		(end 218.667584 -403.755606)
		(stroke
			(width 0.635)
			(type default)
		)
		(layer "In9.Cu")
	)
	(gr_line
		(start 218.667584 -403.755606)
		(end 218.839796 -403.583394)
		(stroke
			(width 0.635)
			(type default)
		)
		(layer "In9.Cu")
	)
	(gr_line
		(start 218.839796 -403.583394)
		(end 218.839796 -400.095974)
		(stroke
			(width 0.635)
			(type default)
		)
		(layer "In9.Cu")
	)
	(gr_line
		(start 218.839796 -400.095974)
		(end 219.045282 -399.890488)
		(stroke
			(width 0.635)
			(type default)
		)
		(layer "In9.Cu")
	)
	(gr_line
		(start 219.045282 -399.890488)
		(end 222.709232 -399.890488)
		(stroke
			(width 0.635)
			(type default)
		)
		(layer "In9.Cu")
	)
	(gr_line
		(start 222.709232 -399.890488)
		(end 222.906082 -400.087338)
		(stroke
			(width 0.635)
			(type default)
		)
		(layer "In9.Cu")
	)
	(gr_line
		(start 222.906082 -403.607778)
		(end 223.099122 -403.800818)
		(stroke
			(width 0.635)
			(type default)
		)
		(layer "In9.Cu")
	)
	(gr_line
		(start 222.906082 -400.087338)
		(end 222.906082 -403.607778)
		(stroke
			(width 0.635)
			(type default)
		)
		(layer "In9.Cu")
	)
	(gr_line
		(start 223.099122 -406.414732)
		(end 224.990406 -408.306016)
		(stroke
			(width 0.635)
			(type default)
		)
		(layer "In9.Cu")
	)
	(gr_line
		(start 223.099122 -403.800818)
		(end 223.099122 -406.414732)
		(stroke
			(width 0.635)
			(type default)
		)
		(layer "In9.Cu")
	)
	(gr_arc
		(start 223.300036 -34.120074)
		(mid 223.885821 -35.534285)
		(end 225.300032 -36.12007)
		(stroke
			(width 3.048)
			(type default)
		)
		(layer "In9.Cu")
	)
	(gr_arc
		(start 223.300036 -13.780008)
		(mid 222.714256 -12.365778)
		(end 221.30004 -11.780012)
		(stroke
			(width 3.048)
			(type default)
		)
		(layer "In9.Cu")
	)
	(gr_line
		(start 223.300036 -13.780008)
		(end 223.300036 -34.120074)
		(stroke
			(width 3.048)
			(type default)
		)
		(layer "In9.Cu")
	)
	(gr_line
		(start 224.990406 -408.306016)
		(end 227.218748 -408.306016)
		(stroke
			(width 0.635)
			(type default)
		)
		(layer "In9.Cu")
	)
	(gr_line
		(start 225.300032 -36.12007)
		(end 256.800096 -36.12007)
		(stroke
			(width 3.048)
			(type default)
		)
		(layer "In9.Cu")
	)
	(gr_line
		(start 227.218748 -408.306016)
		(end 229.331774 -406.19299)
		(stroke
			(width 0.635)
			(type default)
		)
		(layer "In9.Cu")
	)
	(gr_line
		(start 229.074472 -436.79618)
		(end 229.997 -435.873652)
		(stroke
			(width 0.635)
			(type default)
		)
		(layer "In9.Cu")
	)
	(gr_line
		(start 229.331774 -406.19299)
		(end 229.331774 -403.768052)
		(stroke
			(width 0.635)
			(type default)
		)
		(layer "In9.Cu")
	)
	(gr_line
		(start 229.331774 -403.768052)
		(end 229.516178 -403.583648)
		(stroke
			(width 0.635)
			(type default)
		)
		(layer "In9.Cu")
	)
	(gr_line
		(start 229.516178 -403.583648)
		(end 229.516178 -400.11223)
		(stroke
			(width 0.635)
			(type default)
		)
		(layer "In9.Cu")
	)
	(gr_line
		(start 229.516178 -400.11223)
		(end 229.746302 -399.882106)
		(stroke
			(width 0.635)
			(type default)
		)
		(layer "In9.Cu")
	)
	(gr_line
		(start 229.746302 -399.882106)
		(end 233.352594 -399.882106)
		(stroke
			(width 0.635)
			(type default)
		)
		(layer "In9.Cu")
	)
	(gr_line
		(start 229.997 -435.873652)
		(end 229.997 -422.180766)
		(stroke
			(width 0.635)
			(type default)
		)
		(layer "In9.Cu")
	)
	(gr_line
		(start 233.352594 -399.882106)
		(end 233.574336 -400.103848)
		(stroke
			(width 0.635)
			(type default)
		)
		(layer "In9.Cu")
	)
	(gr_line
		(start 233.574336 -403.673564)
		(end 233.820462 -403.91969)
		(stroke
			(width 0.635)
			(type default)
		)
		(layer "In9.Cu")
	)
	(gr_line
		(start 233.574336 -400.103848)
		(end 233.574336 -403.673564)
		(stroke
			(width 0.635)
			(type default)
		)
		(layer "In9.Cu")
	)
	(gr_line
		(start 233.820462 -404.855172)
		(end 234.522264 -405.556974)
		(stroke
			(width 0.635)
			(type default)
		)
		(layer "In9.Cu")
	)
	(gr_line
		(start 233.820462 -403.91969)
		(end 233.820462 -404.855172)
		(stroke
			(width 0.635)
			(type default)
		)
		(layer "In9.Cu")
	)
	(gr_line
		(start 234.522264 -405.556974)
		(end 238.715804 -405.556974)
		(stroke
			(width 0.635)
			(type default)
		)
		(layer "In9.Cu")
	)
	(gr_line
		(start 234.897676 -417.28009)
		(end 229.997 -422.180766)
		(stroke
			(width 0.635)
			(type default)
		)
		(layer "In9.Cu")
	)
	(gr_circle
		(center 237.629954 -44.025566)
		(end 238.518954 -44.025566)
		(stroke
			(width 0.2)
			(type default)
		)
		(fill no)
		(layer "In9.Cu")
	)
	(gr_circle
		(center 237.640114 -44.716446)
		(end 238.529114 -44.716446)
		(stroke
			(width 0.2)
			(type default)
		)
		(fill no)
		(layer "In9.Cu")
	)
	(gr_circle
		(center 238.292894 -44.802806)
		(end 239.181894 -44.802806)
		(stroke
			(width 0.2)
			(type default)
		)
		(fill no)
		(layer "In9.Cu")
	)
	(gr_circle
		(center 238.292894 -44.040806)
		(end 239.181894 -44.040806)
		(stroke
			(width 0.2)
			(type default)
		)
		(fill no)
		(layer "In9.Cu")
	)
	(gr_arc
		(start 238.695992 -393.003532)
		(mid 238.724179 -393.144586)
		(end 238.804196 -393.264136)
		(stroke
			(width 0.635)
			(type default)
		)
		(layer "In9.Cu")
	)
	(gr_line
		(start 238.695992 -384.337306)
		(end 238.695992 -393.003532)
		(stroke
			(width 0.635)
			(type default)
		)
		(layer "In9.Cu")
	)
	(gr_line
		(start 238.715804 -405.556974)
		(end 238.882682 -405.390096)
		(stroke
			(width 0.635)
			(type default)
		)
		(layer "In9.Cu")
	)
	(gr_line
		(start 238.752126 -384.198876)
		(end 238.695992 -384.337306)
		(stroke
			(width 0.635)
			(type default)
		)
		(layer "In9.Cu")
	)
	(gr_line
		(start 238.804196 -393.264136)
		(end 239.027716 -393.487656)
		(stroke
			(width 0.635)
			(type default)
		)
		(layer "In9.Cu")
	)
	(gr_line
		(start 238.805974 -384.146806)
		(end 238.752126 -384.198876)
		(stroke
			(width 0.635)
			(type default)
		)
		(layer "In9.Cu")
	)
	(gr_line
		(start 238.882682 -405.390096)
		(end 238.882682 -394.210794)
		(stroke
			(width 0.635)
			(type default)
		)
		(layer "In9.Cu")
	)
	(gr_line
		(start 238.882682 -394.210794)
		(end 279.615392 -394.210794)
		(stroke
			(width 0.635)
			(type default)
		)
		(layer "In9.Cu")
	)
	(gr_circle
		(center 238.943134 -44.802806)
		(end 239.832134 -44.802806)
		(stroke
			(width 0.2)
			(type default)
		)
		(fill no)
		(layer "In9.Cu")
	)
	(gr_circle
		(center 238.943134 -44.040806)
		(end 239.832134 -44.040806)
		(stroke
			(width 0.2)
			(type default)
		)
		(fill no)
		(layer "In9.Cu")
	)
	(gr_arc
		(start 239.027716 -393.487656)
		(mid 239.147257 -393.567682)
		(end 239.28832 -393.59586)
		(stroke
			(width 0.635)
			(type default)
		)
		(layer "In9.Cu")
	)
	(gr_line
		(start 239.281716 -383.671064)
		(end 238.805974 -384.146806)
		(stroke
			(width 0.635)
			(type default)
		)
		(layer "In9.Cu")
	)
	(gr_line
		(start 239.28832 -393.59586)
		(end 273.155664 -393.59586)
		(stroke
			(width 0.635)
			(type default)
		)
		(layer "In9.Cu")
	)
	(gr_arc
		(start 239.54232 -383.56286)
		(mid 239.401266 -383.591047)
		(end 239.281716 -383.671064)
		(stroke
			(width 0.635)
			(type default)
		)
		(layer "In9.Cu")
	)
	(gr_circle
		(center 239.578134 -44.802806)
		(end 240.467134 -44.802806)
		(stroke
			(width 0.2)
			(type default)
		)
		(fill no)
		(layer "In9.Cu")
	)
	(gr_circle
		(center 239.578134 -44.040806)
		(end 240.467134 -44.040806)
		(stroke
			(width 0.2)
			(type default)
		)
		(fill no)
		(layer "In9.Cu")
	)
	(gr_circle
		(center 240.213134 -44.802806)
		(end 241.102134 -44.802806)
		(stroke
			(width 0.2)
			(type default)
		)
		(fill no)
		(layer "In9.Cu")
	)
	(gr_circle
		(center 240.213134 -44.040806)
		(end 241.102134 -44.040806)
		(stroke
			(width 0.2)
			(type default)
		)
		(fill no)
		(layer "In9.Cu")
	)
	(gr_circle
		(center 240.893854 -44.830746)
		(end 241.782854 -44.830746)
		(stroke
			(width 0.2)
			(type default)
		)
		(fill no)
		(layer "In9.Cu")
	)
	(gr_circle
		(center 244.518942 -43.246802)
		(end 245.407942 -43.246802)
		(stroke
			(width 0.2)
			(type default)
		)
		(fill no)
		(layer "In9.Cu")
	)
	(gr_circle
		(center 244.518942 -42.611802)
		(end 245.407942 -42.611802)
		(stroke
			(width 0.2)
			(type default)
		)
		(fill no)
		(layer "In9.Cu")
	)
	(gr_circle
		(center 245.857522 -52.022502)
		(end 246.746522 -52.022502)
		(stroke
			(width 0.2)
			(type default)
		)
		(fill no)
		(layer "In9.Cu")
	)
	(gr_circle
		(center 246.873522 -52.022502)
		(end 247.762522 -52.022502)
		(stroke
			(width 0.2)
			(type default)
		)
		(fill no)
		(layer "In9.Cu")
	)
	(gr_circle
		(center 247.825514 -40.94988)
		(end 248.714514 -40.94988)
		(stroke
			(width 0.2)
			(type default)
		)
		(fill no)
		(layer "In9.Cu")
	)
	(gr_circle
		(center 247.840246 -51.320446)
		(end 248.729246 -51.320446)
		(stroke
			(width 0.2)
			(type default)
		)
		(fill no)
		(layer "In9.Cu")
	)
	(gr_circle
		(center 248.214134 -52.171346)
		(end 249.103134 -52.171346)
		(stroke
			(width 0.2)
			(type default)
		)
		(fill no)
		(layer "In9.Cu")
	)
	(gr_circle
		(center 248.881646 -51.320446)
		(end 249.770646 -51.320446)
		(stroke
			(width 0.2)
			(type default)
		)
		(fill no)
		(layer "In9.Cu")
	)
	(gr_circle
		(center 249.202448 -40.945816)
		(end 250.091448 -40.945816)
		(stroke
			(width 0.2)
			(type default)
		)
		(fill no)
		(layer "In9.Cu")
	)
	(gr_circle
		(center 249.905266 -51.349148)
		(end 250.794266 -51.349148)
		(stroke
			(width 0.2)
			(type default)
		)
		(fill no)
		(layer "In9.Cu")
	)
	(gr_circle
		(center 250.449334 -49.555146)
		(end 251.338334 -49.555146)
		(stroke
			(width 0.2)
			(type default)
		)
		(fill no)
		(layer "In9.Cu")
	)
	(gr_circle
		(center 250.779534 -52.222146)
		(end 251.668534 -52.222146)
		(stroke
			(width 0.2)
			(type default)
		)
		(fill no)
		(layer "In9.Cu")
	)
	(gr_circle
		(center 250.779534 -51.333146)
		(end 251.668534 -51.333146)
		(stroke
			(width 0.2)
			(type default)
		)
		(fill no)
		(layer "In9.Cu")
	)
	(gr_circle
		(center 250.779534 -50.444146)
		(end 251.668534 -50.444146)
		(stroke
			(width 0.2)
			(type default)
		)
		(fill no)
		(layer "In9.Cu")
	)
	(gr_circle
		(center 251.516134 -52.501546)
		(end 252.405134 -52.501546)
		(stroke
			(width 0.2)
			(type default)
		)
		(fill no)
		(layer "In9.Cu")
	)
	(gr_circle
		(center 251.516134 -51.612546)
		(end 252.405134 -51.612546)
		(stroke
			(width 0.2)
			(type default)
		)
		(fill no)
		(layer "In9.Cu")
	)
	(gr_circle
		(center 251.516134 -50.723546)
		(end 252.405134 -50.723546)
		(stroke
			(width 0.2)
			(type default)
		)
		(fill no)
		(layer "In9.Cu")
	)
	(gr_line
		(start 253.238 -55.590948)
		(end 202.819 -55.590948)
		(stroke
			(width 0.508)
			(type default)
		)
		(layer "In9.Cu")
	)
	(gr_line
		(start 254.127 -54.701948)
		(end 253.238 -55.590948)
		(stroke
			(width 0.508)
			(type default)
		)
		(layer "In9.Cu")
	)
	(gr_circle
		(center 255.347978 -39.380922)
		(end 256.236978 -39.380922)
		(stroke
			(width 0.2)
			(type default)
		)
		(fill no)
		(layer "In9.Cu")
	)
	(gr_arc
		(start 256.800096 -36.12007)
		(mid 258.214307 -35.534285)
		(end 258.800092 -34.120074)
		(stroke
			(width 3.048)
			(type default)
		)
		(layer "In9.Cu")
	)
	(gr_circle
		(center 258.12496 -360.764074)
		(end 260.28396 -360.764074)
		(stroke
			(width 4.318)
			(type default)
		)
		(fill no)
		(layer "In9.Cu")
	)
	(gr_line
		(start 258.800092 -34.120074)
		(end 258.800092 -13.780008)
		(stroke
			(width 3.048)
			(type default)
		)
		(layer "In9.Cu")
	)
	(gr_arc
		(start 260.800088 -11.780012)
		(mid 259.385888 -12.365802)
		(end 258.800092 -13.780008)
		(stroke
			(width 3.048)
			(type default)
		)
		(layer "In9.Cu")
	)
	(gr_line
		(start 260.800088 -11.780012)
		(end 385.601972 -11.780012)
		(stroke
			(width 3.048)
			(type default)
		)
		(layer "In9.Cu")
	)
	(gr_line
		(start 263.830816 -335.218024)
		(end 263.830816 -194.53733)
		(stroke
			(width 0.508)
			(type default)
		)
		(layer "In9.Cu")
	)
	(gr_line
		(start 263.830816 -194.53733)
		(end 263.830816 -183.479948)
		(stroke
			(width 0.508)
			(type default)
		)
		(layer "In9.Cu")
	)
	(gr_line
		(start 263.830816 -194.53733)
		(end 264.416794 -193.951352)
		(stroke
			(width 0.508)
			(type default)
		)
		(layer "In9.Cu")
	)
	(gr_line
		(start 263.830816 -183.479948)
		(end 266.076684 -181.23408)
		(stroke
			(width 0.508)
			(type default)
		)
		(layer "In9.Cu")
	)
	(gr_line
		(start 264.10031 -335.487518)
		(end 263.830816 -335.218024)
		(stroke
			(width 0.508)
			(type default)
		)
		(layer "In9.Cu")
	)
	(gr_line
		(start 264.416794 -193.951352)
		(end 312.250328 -193.951352)
		(stroke
			(width 0.508)
			(type default)
		)
		(layer "In9.Cu")
	)
	(gr_line
		(start 266.076684 -181.23408)
		(end 291.808408 -181.23408)
		(stroke
			(width 0.508)
			(type default)
		)
		(layer "In9.Cu")
	)
	(gr_line
		(start 271.094962 -354.24491)
		(end 271.094962 -334.941418)
		(stroke
			(width 0.508)
			(type default)
		)
		(layer "In9.Cu")
	)
	(gr_line
		(start 271.094962 -334.941418)
		(end 271.641062 -335.487518)
		(stroke
			(width 0.508)
			(type default)
		)
		(layer "In9.Cu")
	)
	(gr_line
		(start 271.094962 -227.143818)
		(end 271.094962 -334.941418)
		(stroke
			(width 0.508)
			(type default)
		)
		(layer "In9.Cu")
	)
	(gr_line
		(start 271.41043 -335.487518)
		(end 264.10031 -335.487518)
		(stroke
			(width 0.508)
			(type default)
		)
		(layer "In9.Cu")
	)
	(gr_line
		(start 271.41043 -335.487518)
		(end 271.150588 -335.74736)
		(stroke
			(width 0.508)
			(type default)
		)
		(layer "In9.Cu")
	)
	(gr_line
		(start 271.641062 -335.487518)
		(end 271.41043 -335.487518)
		(stroke
			(width 0.508)
			(type default)
		)
		(layer "In9.Cu")
	)
	(gr_line
		(start 271.641062 -335.487518)
		(end 311.623202 -335.487518)
		(stroke
			(width 0.508)
			(type default)
		)
		(layer "In9.Cu")
	)
	(gr_line
		(start 272.19021 -417.28009)
		(end 234.897676 -417.28009)
		(stroke
			(width 0.635)
			(type default)
		)
		(layer "In9.Cu")
	)
	(gr_line
		(start 273.05 -356.199948)
		(end 271.094962 -354.24491)
		(stroke
			(width 0.508)
			(type default)
		)
		(layer "In9.Cu")
	)
	(gr_arc
		(start 273.155664 -393.59586)
		(mid 273.296718 -393.567673)
		(end 273.416268 -393.487656)
		(stroke
			(width 0.635)
			(type default)
		)
		(layer "In9.Cu")
	)
	(gr_line
		(start 273.33067 -394.041884)
		(end 279.547066 -394.041884)
		(stroke
			(width 0.635)
			(type default)
		)
		(layer "In9.Cu")
	)
	(gr_line
		(start 273.416268 -393.487656)
		(end 273.893788 -393.010136)
		(stroke
			(width 0.635)
			(type default)
		)
		(layer "In9.Cu")
	)
	(gr_line
		(start 273.481546 -383.56286)
		(end 239.54232 -383.56286)
		(stroke
			(width 0.635)
			(type default)
		)
		(layer "In9.Cu")
	)
	(gr_line
		(start 273.619976 -383.618994)
		(end 273.481546 -383.56286)
		(stroke
			(width 0.635)
			(type default)
		)
		(layer "In9.Cu")
	)
	(gr_line
		(start 273.672046 -383.672842)
		(end 273.619976 -383.618994)
		(stroke
			(width 0.635)
			(type default)
		)
		(layer "In9.Cu")
	)
	(gr_arc
		(start 273.893788 -393.010136)
		(mid 273.97387 -392.890613)
		(end 274.001992 -392.749532)
		(stroke
			(width 0.635)
			(type default)
		)
		(layer "In9.Cu")
	)
	(gr_line
		(start 273.893788 -383.894584)
		(end 273.672046 -383.672842)
		(stroke
			(width 0.635)
			(type default)
		)
		(layer "In9.Cu")
	)
	(gr_line
		(start 274.001992 -392.749532)
		(end 274.001992 -384.155188)
		(stroke
			(width 0.635)
			(type default)
		)
		(layer "In9.Cu")
	)
	(gr_arc
		(start 274.001992 -384.155188)
		(mid 273.973805 -384.014134)
		(end 273.893788 -383.894584)
		(stroke
			(width 0.635)
			(type default)
		)
		(layer "In9.Cu")
	)
	(gr_line
		(start 274.123404 -393.697206)
		(end 279.133554 -393.697206)
		(stroke
			(width 0.635)
			(type default)
		)
		(layer "In9.Cu")
	)
	(gr_line
		(start 274.433792 -392.938762)
		(end 273.33067 -394.041884)
		(stroke
			(width 0.635)
			(type default)
		)
		(layer "In9.Cu")
	)
	(gr_line
		(start 274.433792 -392.938762)
		(end 274.50288 -392.869674)
		(stroke
			(width 0.635)
			(type default)
		)
		(layer "In9.Cu")
	)
	(gr_line
		(start 274.433792 -384.002788)
		(end 274.433792 -392.938762)
		(stroke
			(width 0.635)
			(type default)
		)
		(layer "In9.Cu")
	)
	(gr_line
		(start 274.433792 -384.002788)
		(end 274.433792 -392.317732)
		(stroke
			(width 0.635)
			(type default)
		)
		(layer "In9.Cu")
	)
	(gr_line
		(start 274.50288 -392.869674)
		(end 279.110694 -392.869674)
		(stroke
			(width 0.635)
			(type default)
		)
		(layer "In9.Cu")
	)
	(gr_line
		(start 274.732496 -393.237466)
		(end 274.433792 -392.938762)
		(stroke
			(width 0.635)
			(type default)
		)
		(layer "In9.Cu")
	)
	(gr_line
		(start 274.778724 -392.605514)
		(end 274.192746 -392.019536)
		(stroke
			(width 0.635)
			(type default)
		)
		(layer "In9.Cu")
	)
	(gr_line
		(start 274.87372 -383.56286)
		(end 274.433792 -384.002788)
		(stroke
			(width 0.635)
			(type default)
		)
		(layer "In9.Cu")
	)
	(gr_line
		(start 274.87372 -383.56286)
		(end 280.202132 -383.56286)
		(stroke
			(width 0.635)
			(type default)
		)
		(layer "In9.Cu")
	)
	(gr_line
		(start 274.875244 -127.980948)
		(end 304.023268 -98.832924)
		(stroke
			(width 0.508)
			(type default)
		)
		(layer "In9.Cu")
	)
	(gr_circle
		(center 276.112986 -348.704662)
		(end 276.993096 -348.704662)
		(stroke
			(width 0.2)
			(type default)
		)
		(fill no)
		(layer "In9.Cu")
	)
	(gr_line
		(start 276.314916 -440.669934)
		(end 195.50507 -440.669934)
		(stroke
			(width 3.048)
			(type default)
		)
		(layer "In9.Cu")
	)
	(gr_circle
		(center 276.730206 -348.704662)
		(end 277.610316 -348.704662)
		(stroke
			(width 0.2)
			(type default)
		)
		(fill no)
		(layer "In9.Cu")
	)
	(gr_line
		(start 276.815042 -441.4901)
		(end 276.815042 -441.17006)
		(stroke
			(width 3.048)
			(type default)
		)
		(layer "In9.Cu")
	)
	(gr_arc
		(start 276.815042 -441.4901)
		(mid 276.961452 -441.843558)
		(end 277.314914 -441.989972)
		(stroke
			(width 3.048)
			(type default)
		)
		(layer "In9.Cu")
	)
	(gr_arc
		(start 276.815042 -441.17006)
		(mid 276.668558 -440.816418)
		(end 276.314916 -440.669934)
		(stroke
			(width 3.048)
			(type default)
		)
		(layer "In9.Cu")
	)
	(gr_circle
		(center 277.347426 -348.704662)
		(end 278.227536 -348.704662)
		(stroke
			(width 0.2)
			(type default)
		)
		(fill no)
		(layer "In9.Cu")
	)
	(gr_circle
		(center 277.593806 -348.025212)
		(end 278.482806 -348.025212)
		(stroke
			(width 0.2)
			(type default)
		)
		(fill no)
		(layer "In9.Cu")
	)
	(gr_circle
		(center 277.593806 -347.288612)
		(end 278.482806 -347.288612)
		(stroke
			(width 0.2)
			(type default)
		)
		(fill no)
		(layer "In9.Cu")
	)
	(gr_circle
		(center 278.049482 -350.313752)
		(end 278.938482 -350.313752)
		(stroke
			(width 0.2)
			(type default)
		)
		(fill no)
		(layer "In9.Cu")
	)
	(gr_circle
		(center 278.049482 -349.577152)
		(end 278.938482 -349.577152)
		(stroke
			(width 0.2)
			(type default)
		)
		(fill no)
		(layer "In9.Cu")
	)
	(gr_circle
		(center 278.574246 -349.137732)
		(end 279.463246 -349.137732)
		(stroke
			(width 0.2)
			(type default)
		)
		(fill no)
		(layer "In9.Cu")
	)
	(gr_circle
		(center 278.599646 -349.899732)
		(end 279.488646 -349.899732)
		(stroke
			(width 0.2)
			(type default)
		)
		(fill no)
		(layer "In9.Cu")
	)
	(gr_line
		(start 278.892508 -393.237466)
		(end 274.732496 -393.237466)
		(stroke
			(width 0.635)
			(type default)
		)
		(layer "In9.Cu")
	)
	(gr_line
		(start 279.110694 -392.869674)
		(end 279.351994 -392.628374)
		(stroke
			(width 0.635)
			(type default)
		)
		(layer "In9.Cu")
	)
	(gr_circle
		(center 279.133046 -350.255332)
		(end 280.022046 -350.255332)
		(stroke
			(width 0.2)
			(type default)
		)
		(fill no)
		(layer "In9.Cu")
	)
	(gr_circle
		(center 279.133046 -349.518732)
		(end 280.022046 -349.518732)
		(stroke
			(width 0.2)
			(type default)
		)
		(fill no)
		(layer "In9.Cu")
	)
	(gr_circle
		(center 279.133046 -348.782132)
		(end 280.022046 -348.782132)
		(stroke
			(width 0.2)
			(type default)
		)
		(fill no)
		(layer "In9.Cu")
	)
	(gr_line
		(start 279.133554 -393.697206)
		(end 279.983946 -392.846814)
		(stroke
			(width 0.635)
			(type default)
		)
		(layer "In9.Cu")
	)
	(gr_line
		(start 279.329134 -392.605514)
		(end 274.778724 -392.605514)
		(stroke
			(width 0.635)
			(type default)
		)
		(layer "In9.Cu")
	)
	(gr_line
		(start 279.351994 -392.628374)
		(end 279.329134 -392.605514)
		(stroke
			(width 0.635)
			(type default)
		)
		(layer "In9.Cu")
	)
	(gr_line
		(start 279.547066 -394.041884)
		(end 280.477976 -393.110974)
		(stroke
			(width 0.635)
			(type default)
		)
		(layer "In9.Cu")
	)
	(gr_line
		(start 279.616408 -392.513566)
		(end 278.892508 -393.237466)
		(stroke
			(width 0.635)
			(type default)
		)
		(layer "In9.Cu")
	)
	(gr_line
		(start 279.616408 -383.780538)
		(end 279.616408 -392.513566)
		(stroke
			(width 0.635)
			(type default)
		)
		(layer "In9.Cu")
	)
	(gr_line
		(start 279.834086 -383.56286)
		(end 279.616408 -383.780538)
		(stroke
			(width 0.635)
			(type default)
		)
		(layer "In9.Cu")
	)
	(gr_arc
		(start 279.875996 -394.318998)
		(mid 279.756473 -394.238916)
		(end 279.615392 -394.210794)
		(stroke
			(width 0.635)
			(type default)
		)
		(layer "In9.Cu")
	)
	(gr_line
		(start 279.875996 -394.318998)
		(end 280.259536 -394.702538)
		(stroke
			(width 0.635)
			(type default)
		)
		(layer "In9.Cu")
	)
	(gr_line
		(start 279.983946 -392.846814)
		(end 279.983946 -383.781046)
		(stroke
			(width 0.635)
			(type default)
		)
		(layer "In9.Cu")
	)
	(gr_line
		(start 279.983946 -383.781046)
		(end 280.202132 -383.56286)
		(stroke
			(width 0.635)
			(type default)
		)
		(layer "In9.Cu")
	)
	(gr_line
		(start 280.202132 -383.56286)
		(end 274.87372 -383.56286)
		(stroke
			(width 0.635)
			(type default)
		)
		(layer "In9.Cu")
	)
	(gr_line
		(start 280.202132 -383.56286)
		(end 279.834086 -383.56286)
		(stroke
			(width 0.635)
			(type default)
		)
		(layer "In9.Cu")
	)
	(gr_line
		(start 280.36774 -409.10256)
		(end 272.19021 -417.28009)
		(stroke
			(width 0.635)
			(type default)
		)
		(layer "In9.Cu")
	)
	(gr_arc
		(start 280.36774 -394.963142)
		(mid 280.339553 -394.822088)
		(end 280.259536 -394.702538)
		(stroke
			(width 0.635)
			(type default)
		)
		(layer "In9.Cu")
	)
	(gr_line
		(start 280.36774 -394.963142)
		(end 280.36774 -409.10256)
		(stroke
			(width 0.635)
			(type default)
		)
		(layer "In9.Cu")
	)
	(gr_line
		(start 280.477976 -393.110974)
		(end 280.477976 -383.838704)
		(stroke
			(width 0.635)
			(type default)
		)
		(layer "In9.Cu")
	)
	(gr_line
		(start 280.477976 -383.838704)
		(end 280.202132 -383.56286)
		(stroke
			(width 0.635)
			(type default)
		)
		(layer "In9.Cu")
	)
	(gr_line
		(start 280.9113 -393.283694)
		(end 279.875996 -394.318998)
		(stroke
			(width 0.635)
			(type default)
		)
		(layer "In9.Cu")
	)
	(gr_line
		(start 280.9113 -384.272028)
		(end 280.202132 -383.56286)
		(stroke
			(width 0.635)
			(type default)
		)
		(layer "In9.Cu")
	)
	(gr_line
		(start 280.9113 -384.272028)
		(end 280.9113 -393.283694)
		(stroke
			(width 0.635)
			(type default)
		)
		(layer "In9.Cu")
	)
	(gr_circle
		(center 284.393386 -348.704662)
		(end 285.273496 -348.704662)
		(stroke
			(width 0.2)
			(type default)
		)
		(fill no)
		(layer "In9.Cu")
	)
	(gr_circle
		(center 285.010606 -348.704662)
		(end 285.890716 -348.704662)
		(stroke
			(width 0.2)
			(type default)
		)
		(fill no)
		(layer "In9.Cu")
	)
	(gr_circle
		(center 285.627826 -348.704662)
		(end 286.507936 -348.704662)
		(stroke
			(width 0.2)
			(type default)
		)
		(fill no)
		(layer "In9.Cu")
	)
	(gr_circle
		(center 285.869126 -347.982032)
		(end 286.758126 -347.982032)
		(stroke
			(width 0.2)
			(type default)
		)
		(fill no)
		(layer "In9.Cu")
	)
	(gr_circle
		(center 285.869126 -347.245432)
		(end 286.758126 -347.245432)
		(stroke
			(width 0.2)
			(type default)
		)
		(fill no)
		(layer "In9.Cu")
	)
	(gr_circle
		(center 286.329882 -350.313752)
		(end 287.218882 -350.313752)
		(stroke
			(width 0.2)
			(type default)
		)
		(fill no)
		(layer "In9.Cu")
	)
	(gr_circle
		(center 286.329882 -349.577152)
		(end 287.218882 -349.577152)
		(stroke
			(width 0.2)
			(type default)
		)
		(fill no)
		(layer "In9.Cu")
	)
	(gr_circle
		(center 286.36595 -355.279198)
		(end 287.25495 -355.279198)
		(stroke
			(width 0.2)
			(type default)
		)
		(fill no)
		(layer "In9.Cu")
	)
	(gr_circle
		(center 286.37611 -356.584758)
		(end 287.26511 -356.584758)
		(stroke
			(width 0.2)
			(type default)
		)
		(fill no)
		(layer "In9.Cu")
	)
	(gr_circle
		(center 286.37611 -355.949758)
		(end 287.26511 -355.949758)
		(stroke
			(width 0.2)
			(type default)
		)
		(fill no)
		(layer "In9.Cu")
	)
	(gr_circle
		(center 286.854646 -349.137732)
		(end 287.743646 -349.137732)
		(stroke
			(width 0.2)
			(type default)
		)
		(fill no)
		(layer "In9.Cu")
	)
	(gr_circle
		(center 286.880046 -349.899732)
		(end 287.769046 -349.899732)
		(stroke
			(width 0.2)
			(type default)
		)
		(fill no)
		(layer "In9.Cu")
	)
	(gr_circle
		(center 287.00095 -355.279198)
		(end 287.88995 -355.279198)
		(stroke
			(width 0.2)
			(type default)
		)
		(fill no)
		(layer "In9.Cu")
	)
	(gr_circle
		(center 287.01111 -356.584758)
		(end 287.90011 -356.584758)
		(stroke
			(width 0.2)
			(type default)
		)
		(fill no)
		(layer "In9.Cu")
	)
	(gr_circle
		(center 287.01111 -355.949758)
		(end 287.90011 -355.949758)
		(stroke
			(width 0.2)
			(type default)
		)
		(fill no)
		(layer "In9.Cu")
	)
	(gr_circle
		(center 287.413446 -350.255332)
		(end 288.302446 -350.255332)
		(stroke
			(width 0.2)
			(type default)
		)
		(fill no)
		(layer "In9.Cu")
	)
	(gr_circle
		(center 287.413446 -349.518732)
		(end 288.302446 -349.518732)
		(stroke
			(width 0.2)
			(type default)
		)
		(fill no)
		(layer "In9.Cu")
	)
	(gr_circle
		(center 287.413446 -348.782132)
		(end 288.302446 -348.782132)
		(stroke
			(width 0.2)
			(type default)
		)
		(fill no)
		(layer "In9.Cu")
	)
	(gr_circle
		(center 287.63595 -355.279198)
		(end 288.52495 -355.279198)
		(stroke
			(width 0.2)
			(type default)
		)
		(fill no)
		(layer "In9.Cu")
	)
	(gr_circle
		(center 287.64611 -356.584758)
		(end 288.53511 -356.584758)
		(stroke
			(width 0.2)
			(type default)
		)
		(fill no)
		(layer "In9.Cu")
	)
	(gr_circle
		(center 287.64611 -355.949758)
		(end 288.53511 -355.949758)
		(stroke
			(width 0.2)
			(type default)
		)
		(fill no)
		(layer "In9.Cu")
	)
	(gr_line
		(start 288.036508 -398.662398)
		(end 289.207194 -399.833084)
		(stroke
			(width 0.508)
			(type default)
		)
		(layer "In9.Cu")
	)
	(gr_line
		(start 288.036508 -376.830082)
		(end 288.036508 -398.662398)
		(stroke
			(width 0.508)
			(type default)
		)
		(layer "In9.Cu")
	)
	(gr_circle
		(center 288.27095 -355.279198)
		(end 289.15995 -355.279198)
		(stroke
			(width 0.2)
			(type default)
		)
		(fill no)
		(layer "In9.Cu")
	)
	(gr_circle
		(center 288.28111 -356.584758)
		(end 289.17011 -356.584758)
		(stroke
			(width 0.2)
			(type default)
		)
		(fill no)
		(layer "In9.Cu")
	)
	(gr_circle
		(center 288.28111 -355.949758)
		(end 289.17011 -355.949758)
		(stroke
			(width 0.2)
			(type default)
		)
		(fill no)
		(layer "In9.Cu")
	)
	(gr_circle
		(center 288.90595 -355.279198)
		(end 289.79495 -355.279198)
		(stroke
			(width 0.2)
			(type default)
		)
		(fill no)
		(layer "In9.Cu")
	)
	(gr_circle
		(center 288.91611 -356.584758)
		(end 289.80511 -356.584758)
		(stroke
			(width 0.2)
			(type default)
		)
		(fill no)
		(layer "In9.Cu")
	)
	(gr_circle
		(center 288.91611 -355.949758)
		(end 289.80511 -355.949758)
		(stroke
			(width 0.2)
			(type default)
		)
		(fill no)
		(layer "In9.Cu")
	)
	(gr_line
		(start 289.207194 -399.833084)
		(end 296.033698 -399.833084)
		(stroke
			(width 0.508)
			(type default)
		)
		(layer "In9.Cu")
	)
	(gr_line
		(start 289.691318 -375.175272)
		(end 288.036508 -376.830082)
		(stroke
			(width 0.508)
			(type default)
		)
		(layer "In9.Cu")
	)
	(gr_circle
		(center 291.06749 -384.87858)
		(end 293.22649 -384.87858)
		(stroke
			(width 4.318)
			(type default)
		)
		(fill no)
		(layer "In9.Cu")
	)
	(gr_line
		(start 291.808408 -181.23408)
		(end 296.551858 -176.49063)
		(stroke
			(width 0.508)
			(type default)
		)
		(layer "In9.Cu")
	)
	(gr_circle
		(center 292.699186 -348.704662)
		(end 293.579296 -348.704662)
		(stroke
			(width 0.2)
			(type default)
		)
		(fill no)
		(layer "In9.Cu")
	)
	(gr_circle
		(center 293.316406 -348.704662)
		(end 294.196516 -348.704662)
		(stroke
			(width 0.2)
			(type default)
		)
		(fill no)
		(layer "In9.Cu")
	)
	(gr_circle
		(center 293.933626 -348.704662)
		(end 294.813736 -348.704662)
		(stroke
			(width 0.2)
			(type default)
		)
		(fill no)
		(layer "In9.Cu")
	)
	(gr_circle
		(center 294.146986 -347.959172)
		(end 295.035986 -347.959172)
		(stroke
			(width 0.2)
			(type default)
		)
		(fill no)
		(layer "In9.Cu")
	)
	(gr_circle
		(center 294.146986 -347.222572)
		(end 295.035986 -347.222572)
		(stroke
			(width 0.2)
			(type default)
		)
		(fill no)
		(layer "In9.Cu")
	)
	(gr_circle
		(center 294.635682 -350.313752)
		(end 295.524682 -350.313752)
		(stroke
			(width 0.2)
			(type default)
		)
		(fill no)
		(layer "In9.Cu")
	)
	(gr_circle
		(center 294.635682 -349.577152)
		(end 295.524682 -349.577152)
		(stroke
			(width 0.2)
			(type default)
		)
		(fill no)
		(layer "In9.Cu")
	)
	(gr_circle
		(center 295.160446 -349.137732)
		(end 296.049446 -349.137732)
		(stroke
			(width 0.2)
			(type default)
		)
		(fill no)
		(layer "In9.Cu")
	)
	(gr_circle
		(center 295.185846 -349.899732)
		(end 296.074846 -349.899732)
		(stroke
			(width 0.2)
			(type default)
		)
		(fill no)
		(layer "In9.Cu")
	)
	(gr_circle
		(center 295.719246 -350.255332)
		(end 296.608246 -350.255332)
		(stroke
			(width 0.2)
			(type default)
		)
		(fill no)
		(layer "In9.Cu")
	)
	(gr_circle
		(center 295.719246 -349.518732)
		(end 296.608246 -349.518732)
		(stroke
			(width 0.2)
			(type default)
		)
		(fill no)
		(layer "In9.Cu")
	)
	(gr_circle
		(center 295.719246 -348.782132)
		(end 296.608246 -348.782132)
		(stroke
			(width 0.2)
			(type default)
		)
		(fill no)
		(layer "In9.Cu")
	)
	(gr_line
		(start 296.033698 -418.729668)
		(end 296.033698 -399.833084)
		(stroke
			(width 0.508)
			(type default)
		)
		(layer "In9.Cu")
	)
	(gr_line
		(start 296.033698 -399.833084)
		(end 301.192946 -394.673836)
		(stroke
			(width 0.508)
			(type default)
		)
		(layer "In9.Cu")
	)
	(gr_circle
		(center 296.29989 -358.769666)
		(end 297.69689 -358.769666)
		(stroke
			(width 0.2)
			(type default)
		)
		(fill no)
		(layer "In9.Cu")
	)
	(gr_line
		(start 296.551858 -176.49063)
		(end 296.551858 -145.930874)
		(stroke
			(width 0.508)
			(type default)
		)
		(layer "In9.Cu")
	)
	(gr_line
		(start 296.551858 -145.930874)
		(end 307.767228 -134.715504)
		(stroke
			(width 0.508)
			(type default)
		)
		(layer "In9.Cu")
	)
	(gr_circle
		(center 297.567604 -413.174688)
		(end 299.726604 -413.174688)
		(stroke
			(width 4.318)
			(type default)
		)
		(fill no)
		(layer "In9.Cu")
	)
	(gr_line
		(start 299.426122 -422.122092)
		(end 296.033698 -418.729668)
		(stroke
			(width 0.508)
			(type default)
		)
		(layer "In9.Cu")
	)
	(gr_circle
		(center 301.055786 -348.704662)
		(end 301.935896 -348.704662)
		(stroke
			(width 0.2)
			(type default)
		)
		(fill no)
		(layer "In9.Cu")
	)
	(gr_line
		(start 301.192946 -394.673836)
		(end 310.062626 -394.673836)
		(stroke
			(width 0.508)
			(type default)
		)
		(layer "In9.Cu")
	)
	(gr_circle
		(center 301.673006 -348.704662)
		(end 302.553116 -348.704662)
		(stroke
			(width 0.2)
			(type default)
		)
		(fill no)
		(layer "In9.Cu")
	)
	(gr_circle
		(center 302.290226 -348.704662)
		(end 303.170336 -348.704662)
		(stroke
			(width 0.2)
			(type default)
		)
		(fill no)
		(layer "In9.Cu")
	)
	(gr_circle
		(center 302.526446 -348.002352)
		(end 303.415446 -348.002352)
		(stroke
			(width 0.2)
			(type default)
		)
		(fill no)
		(layer "In9.Cu")
	)
	(gr_circle
		(center 302.526446 -347.265752)
		(end 303.415446 -347.265752)
		(stroke
			(width 0.2)
			(type default)
		)
		(fill no)
		(layer "In9.Cu")
	)
	(gr_circle
		(center 302.992282 -350.313752)
		(end 303.881282 -350.313752)
		(stroke
			(width 0.2)
			(type default)
		)
		(fill no)
		(layer "In9.Cu")
	)
	(gr_circle
		(center 302.992282 -349.577152)
		(end 303.881282 -349.577152)
		(stroke
			(width 0.2)
			(type default)
		)
		(fill no)
		(layer "In9.Cu")
	)
	(gr_line
		(start 303.281842 -335.487518)
		(end 303.860962 -334.908398)
		(stroke
			(width 0.508)
			(type default)
		)
		(layer "In9.Cu")
	)
	(gr_circle
		(center 303.517046 -349.137732)
		(end 304.406046 -349.137732)
		(stroke
			(width 0.2)
			(type default)
		)
		(fill no)
		(layer "In9.Cu")
	)
	(gr_circle
		(center 303.542446 -349.899732)
		(end 304.431446 -349.899732)
		(stroke
			(width 0.2)
			(type default)
		)
		(fill no)
		(layer "In9.Cu")
	)
	(gr_line
		(start 303.860962 -334.908398)
		(end 303.860962 -309.058818)
		(stroke
			(width 0.508)
			(type default)
		)
		(layer "In9.Cu")
	)
	(gr_line
		(start 303.860962 -309.058818)
		(end 316.961266 -295.958514)
		(stroke
			(width 0.508)
			(type default)
		)
		(layer "In9.Cu")
	)
	(gr_line
		(start 304.023268 -98.832924)
		(end 449.250308 -98.832924)
		(stroke
			(width 0.508)
			(type default)
		)
		(layer "In9.Cu")
	)
	(gr_circle
		(center 304.075846 -350.255332)
		(end 304.964846 -350.255332)
		(stroke
			(width 0.2)
			(type default)
		)
		(fill no)
		(layer "In9.Cu")
	)
	(gr_circle
		(center 304.075846 -349.518732)
		(end 304.964846 -349.518732)
		(stroke
			(width 0.2)
			(type default)
		)
		(fill no)
		(layer "In9.Cu")
	)
	(gr_circle
		(center 304.075846 -348.782132)
		(end 304.964846 -348.782132)
		(stroke
			(width 0.2)
			(type default)
		)
		(fill no)
		(layer "In9.Cu")
	)
	(gr_line
		(start 304.440082 -335.487518)
		(end 303.860962 -334.908398)
		(stroke
			(width 0.508)
			(type default)
		)
		(layer "In9.Cu")
	)
	(gr_line
		(start 304.534062 -335.487518)
		(end 304.440082 -335.487518)
		(stroke
			(width 0.508)
			(type default)
		)
		(layer "In9.Cu")
	)
	(gr_line
		(start 307.767228 -134.715504)
		(end 344.860118 -134.715504)
		(stroke
			(width 0.508)
			(type default)
		)
		(layer "In9.Cu")
	)
	(gr_circle
		(center 309.386986 -348.704662)
		(end 310.267096 -348.704662)
		(stroke
			(width 0.2)
			(type default)
		)
		(fill no)
		(layer "In9.Cu")
	)
	(gr_circle
		(center 310.004206 -348.704662)
		(end 310.884316 -348.704662)
		(stroke
			(width 0.2)
			(type default)
		)
		(fill no)
		(layer "In9.Cu")
	)
	(gr_line
		(start 310.125364 -396.33906)
		(end 310.572404 -396.7861)
		(stroke
			(width 0.508)
			(type default)
		)
		(layer "In9.Cu")
	)
	(gr_line
		(start 310.125364 -392.47064)
		(end 310.125364 -396.33906)
		(stroke
			(width 0.508)
			(type default)
		)
		(layer "In9.Cu")
	)
	(gr_line
		(start 310.463692 -392.132312)
		(end 310.125364 -392.47064)
		(stroke
			(width 0.508)
			(type default)
		)
		(layer "In9.Cu")
	)
	(gr_line
		(start 310.572404 -396.7861)
		(end 313.261248 -396.7861)
		(stroke
			(width 0.508)
			(type default)
		)
		(layer "In9.Cu")
	)
	(gr_circle
		(center 310.621426 -348.704662)
		(end 311.501536 -348.704662)
		(stroke
			(width 0.2)
			(type default)
		)
		(fill no)
		(layer "In9.Cu")
	)
	(gr_line
		(start 310.744362 -391.91438)
		(end 310.57215 -392.086592)
		(stroke
			(width 0.508)
			(type default)
		)
		(layer "In9.Cu")
	)
	(gr_circle
		(center 310.867806 -348.002352)
		(end 311.756806 -348.002352)
		(stroke
			(width 0.2)
			(type default)
		)
		(fill no)
		(layer "In9.Cu")
	)
	(gr_circle
		(center 310.867806 -347.265752)
		(end 311.756806 -347.265752)
		(stroke
			(width 0.2)
			(type default)
		)
		(fill no)
		(layer "In9.Cu")
	)
	(gr_circle
		(center 311.323482 -350.313752)
		(end 312.212482 -350.313752)
		(stroke
			(width 0.2)
			(type default)
		)
		(fill no)
		(layer "In9.Cu")
	)
	(gr_circle
		(center 311.323482 -349.577152)
		(end 312.212482 -349.577152)
		(stroke
			(width 0.2)
			(type default)
		)
		(fill no)
		(layer "In9.Cu")
	)
	(gr_circle
		(center 311.848246 -349.137732)
		(end 312.737246 -349.137732)
		(stroke
			(width 0.2)
			(type default)
		)
		(fill no)
		(layer "In9.Cu")
	)
	(gr_circle
		(center 311.873646 -349.899732)
		(end 312.762646 -349.899732)
		(stroke
			(width 0.2)
			(type default)
		)
		(fill no)
		(layer "In9.Cu")
	)
	(gr_line
		(start 312.115962 -334.994758)
		(end 311.623202 -335.487518)
		(stroke
			(width 0.508)
			(type default)
		)
		(layer "In9.Cu")
	)
	(gr_line
		(start 312.115962 -330.394818)
		(end 312.115962 -334.994758)
		(stroke
			(width 0.508)
			(type default)
		)
		(layer "In9.Cu")
	)
	(gr_line
		(start 312.250328 -193.951352)
		(end 312.541412 -193.660268)
		(stroke
			(width 0.508)
			(type default)
		)
		(layer "In9.Cu")
	)
	(gr_circle
		(center 312.407046 -350.255332)
		(end 313.296046 -350.255332)
		(stroke
			(width 0.2)
			(type default)
		)
		(fill no)
		(layer "In9.Cu")
	)
	(gr_circle
		(center 312.407046 -349.518732)
		(end 313.296046 -349.518732)
		(stroke
			(width 0.2)
			(type default)
		)
		(fill no)
		(layer "In9.Cu")
	)
	(gr_circle
		(center 312.407046 -348.782132)
		(end 313.296046 -348.782132)
		(stroke
			(width 0.2)
			(type default)
		)
		(fill no)
		(layer "In9.Cu")
	)
	(gr_line
		(start 312.591958 -226.438206)
		(end 313.099958 -226.946206)
		(stroke
			(width 0.508)
			(type default)
		)
		(layer "In9.Cu")
	)
	(gr_line
		(start 312.591958 -150.72995)
		(end 312.591958 -226.438206)
		(stroke
			(width 0.508)
			(type default)
		)
		(layer "In9.Cu")
	)
	(gr_line
		(start 312.877962 -329.632818)
		(end 312.115962 -330.394818)
		(stroke
			(width 0.508)
			(type default)
		)
		(layer "In9.Cu")
	)
	(gr_line
		(start 313.261248 -396.7861)
		(end 315.08827 -394.959078)
		(stroke
			(width 0.508)
			(type default)
		)
		(layer "In9.Cu")
	)
	(gr_line
		(start 313.87796 -149.443948)
		(end 312.591958 -150.72995)
		(stroke
			(width 0.508)
			(type default)
		)
		(layer "In9.Cu")
	)
	(gr_line
		(start 315.08827 -394.959078)
		(end 315.789056 -394.959078)
		(stroke
			(width 0.508)
			(type default)
		)
		(layer "In9.Cu")
	)
	(gr_line
		(start 315.789056 -394.959078)
		(end 317.145416 -396.315438)
		(stroke
			(width 0.508)
			(type default)
		)
		(layer "In9.Cu")
	)
	(gr_line
		(start 316.961266 -295.958514)
		(end 327.118472 -295.958514)
		(stroke
			(width 0.508)
			(type default)
		)
		(layer "In9.Cu")
	)
	(gr_line
		(start 317.145416 -396.315438)
		(end 325.182484 -396.315438)
		(stroke
			(width 0.508)
			(type default)
		)
		(layer "In9.Cu")
	)
	(gr_line
		(start 318.719962 -329.632818)
		(end 312.877962 -329.632818)
		(stroke
			(width 0.508)
			(type default)
		)
		(layer "In9.Cu")
	)
	(gr_circle
		(center 319.0367 -336.983578)
		(end 319.91681 -336.983578)
		(stroke
			(width 0.2)
			(type default)
		)
		(fill no)
		(layer "In9.Cu")
	)
	(gr_circle
		(center 319.65392 -336.983578)
		(end 320.53403 -336.983578)
		(stroke
			(width 0.2)
			(type default)
		)
		(fill no)
		(layer "In9.Cu")
	)
	(gr_circle
		(center 320.27114 -336.983578)
		(end 321.15125 -336.983578)
		(stroke
			(width 0.2)
			(type default)
		)
		(fill no)
		(layer "In9.Cu")
	)
	(gr_circle
		(center 320.5607 -336.239612)
		(end 321.4497 -336.239612)
		(stroke
			(width 0.2)
			(type default)
		)
		(fill no)
		(layer "In9.Cu")
	)
	(gr_circle
		(center 320.5607 -335.503012)
		(end 321.4497 -335.503012)
		(stroke
			(width 0.2)
			(type default)
		)
		(fill no)
		(layer "In9.Cu")
	)
	(gr_circle
		(center 320.973196 -338.592668)
		(end 321.862196 -338.592668)
		(stroke
			(width 0.2)
			(type default)
		)
		(fill no)
		(layer "In9.Cu")
	)
	(gr_circle
		(center 320.973196 -337.856068)
		(end 321.862196 -337.856068)
		(stroke
			(width 0.2)
			(type default)
		)
		(fill no)
		(layer "In9.Cu")
	)
	(gr_circle
		(center 321.49796 -337.416648)
		(end 322.38696 -337.416648)
		(stroke
			(width 0.2)
			(type default)
		)
		(fill no)
		(layer "In9.Cu")
	)
	(gr_circle
		(center 321.52336 -338.178648)
		(end 322.41236 -338.178648)
		(stroke
			(width 0.2)
			(type default)
		)
		(fill no)
		(layer "In9.Cu")
	)
	(gr_circle
		(center 322.05676 -338.534248)
		(end 322.94576 -338.534248)
		(stroke
			(width 0.2)
			(type default)
		)
		(fill no)
		(layer "In9.Cu")
	)
	(gr_circle
		(center 322.05676 -337.797648)
		(end 322.94576 -337.797648)
		(stroke
			(width 0.2)
			(type default)
		)
		(fill no)
		(layer "In9.Cu")
	)
	(gr_circle
		(center 322.05676 -337.061048)
		(end 322.94576 -337.061048)
		(stroke
			(width 0.2)
			(type default)
		)
		(fill no)
		(layer "In9.Cu")
	)
	(gr_line
		(start 322.402962 -325.949818)
		(end 318.719962 -329.632818)
		(stroke
			(width 0.508)
			(type default)
		)
		(layer "In9.Cu")
	)
	(gr_line
		(start 325.182484 -396.315438)
		(end 325.780146 -395.717776)
		(stroke
			(width 0.508)
			(type default)
		)
		(layer "In9.Cu")
	)
	(gr_line
		(start 325.372984 -226.968304)
		(end 271.270476 -226.968304)
		(stroke
			(width 0.508)
			(type default)
		)
		(layer "In9.Cu")
	)
	(gr_line
		(start 325.372984 -226.968304)
		(end 327.011284 -226.968304)
		(stroke
			(width 0.508)
			(type default)
		)
		(layer "In9.Cu")
	)
	(gr_line
		(start 325.613522 -391.91438)
		(end 310.744362 -391.91438)
		(stroke
			(width 0.508)
			(type default)
		)
		(layer "In9.Cu")
	)
	(gr_line
		(start 325.780146 -395.717776)
		(end 325.780146 -395.12621)
		(stroke
			(width 0.508)
			(type default)
		)
		(layer "In9.Cu")
	)
	(gr_line
		(start 325.780146 -395.12621)
		(end 325.780146 -394.757402)
		(stroke
			(width 0.254)
			(type default)
		)
		(layer "In9.Cu")
	)
	(gr_line
		(start 325.780146 -394.757402)
		(end 325.957946 -394.579602)
		(stroke
			(width 0.254)
			(type default)
		)
		(layer "In9.Cu")
	)
	(gr_line
		(start 325.957946 -394.579602)
		(end 325.957946 -393.057634)
		(stroke
			(width 0.254)
			(type default)
		)
		(layer "In9.Cu")
	)
	(gr_line
		(start 325.957946 -393.057634)
		(end 325.957946 -392.258804)
		(stroke
			(width 0.508)
			(type default)
		)
		(layer "In9.Cu")
	)
	(gr_line
		(start 325.957946 -392.258804)
		(end 325.613522 -391.91438)
		(stroke
			(width 0.508)
			(type default)
		)
		(layer "In9.Cu")
	)
	(gr_line
		(start 327.011284 -226.968304)
		(end 335.190846 -226.968304)
		(stroke
			(width 0.254)
			(type default)
		)
		(layer "In9.Cu")
	)
	(gr_line
		(start 327.118472 -295.958514)
		(end 340.278466 -295.958514)
		(stroke
			(width 0.254)
			(type default)
		)
		(layer "In9.Cu")
	)
	(gr_circle
		(center 327.392284 -336.976466)
		(end 328.272394 -336.976466)
		(stroke
			(width 0.2)
			(type default)
		)
		(fill no)
		(layer "In9.Cu")
	)
	(gr_circle
		(center 327.692258 -104.30129)
		(end 328.581258 -104.30129)
		(stroke
			(width 0.2)
			(type default)
		)
		(fill no)
		(layer "In9.Cu")
	)
	(gr_line
		(start 327.727056 -395.717776)
		(end 325.780146 -395.717776)
		(stroke
			(width 0.508)
			(type default)
		)
		(layer "In9.Cu")
	)
	(gr_circle
		(center 327.951084 -349.43161)
		(end 329.348084 -349.43161)
		(stroke
			(width 0.2)
			(type default)
		)
		(fill no)
		(layer "In9.Cu")
	)
	(gr_circle
		(center 328.009504 -336.976466)
		(end 328.889614 -336.976466)
		(stroke
			(width 0.2)
			(type default)
		)
		(fill no)
		(layer "In9.Cu")
	)
	(gr_circle
		(center 328.626724 -336.976466)
		(end 329.506834 -336.976466)
		(stroke
			(width 0.2)
			(type default)
		)
		(fill no)
		(layer "In9.Cu")
	)
	(gr_circle
		(center 328.918824 -336.253836)
		(end 329.807824 -336.253836)
		(stroke
			(width 0.2)
			(type default)
		)
		(fill no)
		(layer "In9.Cu")
	)
	(gr_circle
		(center 328.918824 -335.517236)
		(end 329.807824 -335.517236)
		(stroke
			(width 0.2)
			(type default)
		)
		(fill no)
		(layer "In9.Cu")
	)
	(gr_line
		(start 329.302872 -394.14196)
		(end 327.727056 -395.717776)
		(stroke
			(width 0.508)
			(type default)
		)
		(layer "In9.Cu")
	)
	(gr_line
		(start 329.302872 -392.849354)
		(end 329.302872 -394.14196)
		(stroke
			(width 0.508)
			(type default)
		)
		(layer "In9.Cu")
	)
	(gr_circle
		(center 329.32878 -338.585556)
		(end 330.21778 -338.585556)
		(stroke
			(width 0.2)
			(type default)
		)
		(fill no)
		(layer "In9.Cu")
	)
	(gr_circle
		(center 329.32878 -337.848956)
		(end 330.21778 -337.848956)
		(stroke
			(width 0.2)
			(type default)
		)
		(fill no)
		(layer "In9.Cu")
	)
	(gr_circle
		(center 329.853544 -337.409536)
		(end 330.742544 -337.409536)
		(stroke
			(width 0.2)
			(type default)
		)
		(fill no)
		(layer "In9.Cu")
	)
	(gr_circle
		(center 329.878944 -338.171536)
		(end 330.767944 -338.171536)
		(stroke
			(width 0.2)
			(type default)
		)
		(fill no)
		(layer "In9.Cu")
	)
	(gr_line
		(start 330.003404 -392.148822)
		(end 329.302872 -392.849354)
		(stroke
			(width 0.508)
			(type default)
		)
		(layer "In9.Cu")
	)
	(gr_circle
		(center 330.412344 -338.527136)
		(end 331.301344 -338.527136)
		(stroke
			(width 0.2)
			(type default)
		)
		(fill no)
		(layer "In9.Cu")
	)
	(gr_circle
		(center 330.412344 -337.790536)
		(end 331.301344 -337.790536)
		(stroke
			(width 0.2)
			(type default)
		)
		(fill no)
		(layer "In9.Cu")
	)
	(gr_circle
		(center 330.412344 -337.053936)
		(end 331.301344 -337.053936)
		(stroke
			(width 0.2)
			(type default)
		)
		(fill no)
		(layer "In9.Cu")
	)
	(gr_line
		(start 333.165958 -214.990426)
		(end 339.977984 -221.802452)
		(stroke
			(width 0.508)
			(type default)
		)
		(layer "In9.Cu")
	)
	(gr_line
		(start 333.165958 -172.717206)
		(end 333.165958 -214.990426)
		(stroke
			(width 0.508)
			(type default)
		)
		(layer "In9.Cu")
	)
	(gr_line
		(start 333.673958 -172.209206)
		(end 333.165958 -172.717206)
		(stroke
			(width 0.508)
			(type default)
		)
		(layer "In9.Cu")
	)
	(gr_line
		(start 335.190846 -226.968304)
		(end 335.472278 -227.249736)
		(stroke
			(width 0.254)
			(type default)
		)
		(layer "In9.Cu")
	)
	(gr_circle
		(center 335.411064 -349.43161)
		(end 336.808064 -349.43161)
		(stroke
			(width 0.2)
			(type default)
		)
		(fill no)
		(layer "In9.Cu")
	)
	(gr_line
		(start 335.472278 -252.070108)
		(end 339.226652 -255.824482)
		(stroke
			(width 0.254)
			(type default)
		)
		(layer "In9.Cu")
	)
	(gr_line
		(start 335.472278 -227.249736)
		(end 335.472278 -252.070108)
		(stroke
			(width 0.254)
			(type default)
		)
		(layer "In9.Cu")
	)
	(gr_circle
		(center 335.7499 -336.961988)
		(end 336.63001 -336.961988)
		(stroke
			(width 0.2)
			(type default)
		)
		(fill no)
		(layer "In9.Cu")
	)
	(gr_circle
		(center 336.36712 -336.961988)
		(end 337.24723 -336.961988)
		(stroke
			(width 0.2)
			(type default)
		)
		(fill no)
		(layer "In9.Cu")
	)
	(gr_circle
		(center 336.98434 -336.961988)
		(end 337.86445 -336.961988)
		(stroke
			(width 0.2)
			(type default)
		)
		(fill no)
		(layer "In9.Cu")
	)
	(gr_circle
		(center 337.280504 -336.253836)
		(end 338.169504 -336.253836)
		(stroke
			(width 0.2)
			(type default)
		)
		(fill no)
		(layer "In9.Cu")
	)
	(gr_circle
		(center 337.280504 -335.517236)
		(end 338.169504 -335.517236)
		(stroke
			(width 0.2)
			(type default)
		)
		(fill no)
		(layer "In9.Cu")
	)
	(gr_line
		(start 337.382612 -149.443948)
		(end 313.87796 -149.443948)
		(stroke
			(width 0.508)
			(type default)
		)
		(layer "In9.Cu")
	)
	(gr_line
		(start 337.483958 -172.209206)
		(end 333.673958 -172.209206)
		(stroke
			(width 0.508)
			(type default)
		)
		(layer "In9.Cu")
	)
	(gr_line
		(start 337.483958 -172.209206)
		(end 337.899756 -171.793408)
		(stroke
			(width 0.508)
			(type default)
		)
		(layer "In9.Cu")
	)
	(gr_line
		(start 337.5406 -172.152564)
		(end 337.483958 -172.209206)
		(stroke
			(width 0.508)
			(type default)
		)
		(layer "In9.Cu")
	)
	(gr_circle
		(center 337.686396 -338.571078)
		(end 338.575396 -338.571078)
		(stroke
			(width 0.2)
			(type default)
		)
		(fill no)
		(layer "In9.Cu")
	)
	(gr_circle
		(center 337.686396 -337.834478)
		(end 338.575396 -337.834478)
		(stroke
			(width 0.2)
			(type default)
		)
		(fill no)
		(layer "In9.Cu")
	)
	(gr_line
		(start 337.899756 -171.793408)
		(end 337.899756 -149.961092)
		(stroke
			(width 0.508)
			(type default)
		)
		(layer "In9.Cu")
	)
	(gr_line
		(start 337.899756 -149.961092)
		(end 337.382612 -149.443948)
		(stroke
			(width 0.508)
			(type default)
		)
		(layer "In9.Cu")
	)
	(gr_circle
		(center 338.21116 -337.395058)
		(end 339.10016 -337.395058)
		(stroke
			(width 0.2)
			(type default)
		)
		(fill no)
		(layer "In9.Cu")
	)
	(gr_circle
		(center 338.23656 -338.157058)
		(end 339.12556 -338.157058)
		(stroke
			(width 0.2)
			(type default)
		)
		(fill no)
		(layer "In9.Cu")
	)
	(gr_line
		(start 338.258912 -172.152564)
		(end 337.899756 -171.793408)
		(stroke
			(width 0.508)
			(type default)
		)
		(layer "In9.Cu")
	)
	(gr_line
		(start 338.412582 -156.591762)
		(end 337.927696 -156.106876)
		(stroke
			(width 0.508)
			(type default)
		)
		(layer "In9.Cu")
	)
	(gr_line
		(start 338.44357 -156.591762)
		(end 337.981798 -157.053534)
		(stroke
			(width 0.508)
			(type default)
		)
		(layer "In9.Cu")
	)
	(gr_line
		(start 338.44357 -156.591762)
		(end 338.412582 -156.591762)
		(stroke
			(width 0.508)
			(type default)
		)
		(layer "In9.Cu")
	)
	(gr_circle
		(center 338.76996 -338.512658)
		(end 339.65896 -338.512658)
		(stroke
			(width 0.2)
			(type default)
		)
		(fill no)
		(layer "In9.Cu")
	)
	(gr_circle
		(center 338.76996 -337.776058)
		(end 339.65896 -337.776058)
		(stroke
			(width 0.2)
			(type default)
		)
		(fill no)
		(layer "In9.Cu")
	)
	(gr_circle
		(center 338.76996 -337.039458)
		(end 339.65896 -337.039458)
		(stroke
			(width 0.2)
			(type default)
		)
		(fill no)
		(layer "In9.Cu")
	)
	(gr_line
		(start 339.226652 -255.824482)
		(end 343.740994 -255.824482)
		(stroke
			(width 0.254)
			(type default)
		)
		(layer "In9.Cu")
	)
	(gr_circle
		(center 339.73897 -352.973132)
		(end 340.62797 -352.973132)
		(stroke
			(width 0.2)
			(type default)
		)
		(fill no)
		(layer "In9.Cu")
	)
	(gr_circle
		(center 339.739224 -352.215196)
		(end 340.628224 -352.215196)
		(stroke
			(width 0.2)
			(type default)
		)
		(fill no)
		(layer "In9.Cu")
	)
	(gr_circle
		(center 339.739224 -351.453196)
		(end 340.628224 -351.453196)
		(stroke
			(width 0.2)
			(type default)
		)
		(fill no)
		(layer "In9.Cu")
	)
	(gr_line
		(start 339.977984 -221.802452)
		(end 341.387938 -224.23247)
		(stroke
			(width 0.254)
			(type default)
		)
		(layer "In9.Cu")
	)
	(gr_line
		(start 340.278466 -295.958514)
		(end 340.74862 -295.148508)
		(stroke
			(width 0.254)
			(type default)
		)
		(layer "In9.Cu")
	)
	(gr_circle
		(center 340.501224 -352.215196)
		(end 341.390224 -352.215196)
		(stroke
			(width 0.2)
			(type default)
		)
		(fill no)
		(layer "In9.Cu")
	)
	(gr_circle
		(center 340.501224 -351.453196)
		(end 341.390224 -351.453196)
		(stroke
			(width 0.2)
			(type default)
		)
		(fill no)
		(layer "In9.Cu")
	)
	(gr_circle
		(center 340.667848 -353.010216)
		(end 341.556848 -353.010216)
		(stroke
			(width 0.2)
			(type default)
		)
		(fill no)
		(layer "In9.Cu")
	)
	(gr_circle
		(center 341.263224 -352.215196)
		(end 342.152224 -352.215196)
		(stroke
			(width 0.2)
			(type default)
		)
		(fill no)
		(layer "In9.Cu")
	)
	(gr_circle
		(center 341.263224 -351.453196)
		(end 342.152224 -351.453196)
		(stroke
			(width 0.2)
			(type default)
		)
		(fill no)
		(layer "In9.Cu")
	)
	(gr_circle
		(center 341.302848 -353.010216)
		(end 342.191848 -353.010216)
		(stroke
			(width 0.2)
			(type default)
		)
		(fill no)
		(layer "In9.Cu")
	)
	(gr_line
		(start 341.68842 -293.528496)
		(end 340.74862 -295.148508)
		(stroke
			(width 0.254)
			(type default)
		)
		(layer "In9.Cu")
	)
	(gr_circle
		(center 341.937848 -353.010216)
		(end 342.826848 -353.010216)
		(stroke
			(width 0.2)
			(type default)
		)
		(fill no)
		(layer "In9.Cu")
	)
	(gr_circle
		(center 342.025224 -352.215196)
		(end 342.914224 -352.215196)
		(stroke
			(width 0.2)
			(type default)
		)
		(fill no)
		(layer "In9.Cu")
	)
	(gr_circle
		(center 342.025224 -351.453196)
		(end 342.914224 -351.453196)
		(stroke
			(width 0.2)
			(type default)
		)
		(fill no)
		(layer "In9.Cu")
	)
	(gr_line
		(start 342.252808 -392.148822)
		(end 330.003404 -392.148822)
		(stroke
			(width 0.508)
			(type default)
		)
		(layer "In9.Cu")
	)
	(gr_circle
		(center 342.572848 -353.010216)
		(end 343.461848 -353.010216)
		(stroke
			(width 0.2)
			(type default)
		)
		(fill no)
		(layer "In9.Cu")
	)
	(gr_line
		(start 342.628474 -293.528496)
		(end 341.68842 -293.528496)
		(stroke
			(width 0.254)
			(type default)
		)
		(layer "In9.Cu")
	)
	(gr_line
		(start 342.630252 -396.234666)
		(end 342.630252 -392.526266)
		(stroke
			(width 0.508)
			(type default)
		)
		(layer "In9.Cu")
	)
	(gr_line
		(start 342.630252 -392.526266)
		(end 342.252808 -392.148822)
		(stroke
			(width 0.508)
			(type default)
		)
		(layer "In9.Cu")
	)
	(gr_line
		(start 342.630252 -392.526266)
		(end 342.630252 -392.431524)
		(stroke
			(width 0.508)
			(type default)
		)
		(layer "In9.Cu")
	)
	(gr_line
		(start 342.630252 -392.431524)
		(end 343.089992 -391.971784)
		(stroke
			(width 0.508)
			(type default)
		)
		(layer "In9.Cu")
	)
	(gr_circle
		(center 342.787224 -352.215196)
		(end 343.676224 -352.215196)
		(stroke
			(width 0.2)
			(type default)
		)
		(fill no)
		(layer "In9.Cu")
	)
	(gr_circle
		(center 342.787224 -351.453196)
		(end 343.676224 -351.453196)
		(stroke
			(width 0.2)
			(type default)
		)
		(fill no)
		(layer "In9.Cu")
	)
	(gr_line
		(start 343.066878 -396.671292)
		(end 342.630252 -396.234666)
		(stroke
			(width 0.508)
			(type default)
		)
		(layer "In9.Cu")
	)
	(gr_line
		(start 343.089992 -391.971784)
		(end 358.205532 -391.971784)
		(stroke
			(width 0.508)
			(type default)
		)
		(layer "In9.Cu")
	)
	(gr_line
		(start 343.098374 -292.71849)
		(end 342.628474 -293.528496)
		(stroke
			(width 0.254)
			(type default)
		)
		(layer "In9.Cu")
	)
	(gr_circle
		(center 343.46515 -353.006152)
		(end 344.35415 -353.006152)
		(stroke
			(width 0.2)
			(type default)
		)
		(fill no)
		(layer "In9.Cu")
	)
	(gr_circle
		(center 343.465404 -352.248216)
		(end 344.354404 -352.248216)
		(stroke
			(width 0.2)
			(type default)
		)
		(fill no)
		(layer "In9.Cu")
	)
	(gr_circle
		(center 343.465404 -351.486216)
		(end 344.354404 -351.486216)
		(stroke
			(width 0.2)
			(type default)
		)
		(fill no)
		(layer "In9.Cu")
	)
	(gr_line
		(start 343.568528 -291.908484)
		(end 343.098374 -292.71849)
		(stroke
			(width 0.254)
			(type default)
		)
		(layer "In9.Cu")
	)
	(gr_line
		(start 343.737946 -228.282246)
		(end 341.387938 -224.23247)
		(stroke
			(width 0.254)
			(type default)
		)
		(layer "In9.Cu")
	)
	(gr_line
		(start 343.740994 -255.824482)
		(end 345.151202 -256.634488)
		(stroke
			(width 0.254)
			(type default)
		)
		(layer "In9.Cu")
	)
	(gr_circle
		(center 344.016838 -159.073596)
		(end 344.905838 -159.073596)
		(stroke
			(width 0.2)
			(type default)
		)
		(fill no)
		(layer "In9.Cu")
	)
	(gr_circle
		(center 344.016838 -158.336996)
		(end 344.905838 -158.336996)
		(stroke
			(width 0.2)
			(type default)
		)
		(fill no)
		(layer "In9.Cu")
	)
	(gr_circle
		(center 344.016838 -157.600396)
		(end 344.905838 -157.600396)
		(stroke
			(width 0.2)
			(type default)
		)
		(fill no)
		(layer "In9.Cu")
	)
	(gr_line
		(start 344.038428 -291.098478)
		(end 343.568528 -291.908484)
		(stroke
			(width 0.254)
			(type default)
		)
		(layer "In9.Cu")
	)
	(gr_circle
		(center 344.0811 -337.012788)
		(end 344.96121 -337.012788)
		(stroke
			(width 0.2)
			(type default)
		)
		(fill no)
		(layer "In9.Cu")
	)
	(gr_line
		(start 344.207846 -248.532396)
		(end 345.1479 -246.912384)
		(stroke
			(width 0.254)
			(type default)
		)
		(layer "In9.Cu")
	)
	(gr_line
		(start 344.207846 -245.292372)
		(end 345.1479 -243.67236)
		(stroke
			(width 0.254)
			(type default)
		)
		(layer "In9.Cu")
	)
	(gr_line
		(start 344.207846 -242.052348)
		(end 345.1479 -240.432336)
		(stroke
			(width 0.254)
			(type default)
		)
		(layer "In9.Cu")
	)
	(gr_line
		(start 344.207846 -238.812324)
		(end 345.618054 -238.002318)
		(stroke
			(width 0.254)
			(type default)
		)
		(layer "In9.Cu")
	)
	(gr_line
		(start 344.207846 -233.952288)
		(end 345.1479 -232.332276)
		(stroke
			(width 0.254)
			(type default)
		)
		(layer "In9.Cu")
	)
	(gr_line
		(start 344.246962 -325.949818)
		(end 322.402962 -325.949818)
		(stroke
			(width 0.508)
			(type default)
		)
		(layer "In9.Cu")
	)
	(gr_line
		(start 344.508582 -290.288726)
		(end 344.038428 -291.098478)
		(stroke
			(width 0.254)
			(type default)
		)
		(layer "In9.Cu")
	)
	(gr_line
		(start 344.508582 -287.048702)
		(end 345.448382 -288.668714)
		(stroke
			(width 0.254)
			(type default)
		)
		(layer "In9.Cu")
	)
	(gr_line
		(start 344.508582 -283.808678)
		(end 345.448382 -285.42869)
		(stroke
			(width 0.254)
			(type default)
		)
		(layer "In9.Cu")
	)
	(gr_line
		(start 344.508582 -278.948642)
		(end 345.918536 -279.758648)
		(stroke
			(width 0.254)
			(type default)
		)
		(layer "In9.Cu")
	)
	(gr_line
		(start 344.508582 -275.708618)
		(end 345.448382 -277.32863)
		(stroke
			(width 0.254)
			(type default)
		)
		(layer "In9.Cu")
	)
	(gr_line
		(start 344.508582 -272.468594)
		(end 345.448382 -274.088606)
		(stroke
			(width 0.254)
			(type default)
		)
		(layer "In9.Cu")
	)
	(gr_line
		(start 344.508582 -269.22857)
		(end 345.448382 -270.848582)
		(stroke
			(width 0.254)
			(type default)
		)
		(layer "In9.Cu")
	)
	(gr_circle
		(center 344.550238 -157.955996)
		(end 345.439238 -157.955996)
		(stroke
			(width 0.2)
			(type default)
		)
		(fill no)
		(layer "In9.Cu")
	)
	(gr_circle
		(center 344.575638 -158.717996)
		(end 345.464638 -158.717996)
		(stroke
			(width 0.2)
			(type default)
		)
		(fill no)
		(layer "In9.Cu")
	)
	(gr_line
		(start 344.6018 -156.7942)
		(end 344.4494 -156.9466)
		(stroke
			(width 0.254)
			(type default)
		)
		(layer "In9.Cu")
	)
	(gr_line
		(start 344.6018 -156.6926)
		(end 344.6018 -156.7942)
		(stroke
			(width 0.254)
			(type default)
		)
		(layer "In9.Cu")
	)
	(gr_line
		(start 344.678 -236.382306)
		(end 345.1479 -235.5723)
		(stroke
			(width 0.254)
			(type default)
		)
		(layer "In9.Cu")
	)
	(gr_line
		(start 344.678 -231.52227)
		(end 345.1479 -230.712264)
		(stroke
			(width 0.254)
			(type default)
		)
		(layer "In9.Cu")
	)
	(gr_line
		(start 344.678 -229.902258)
		(end 345.1479 -229.092252)
		(stroke
			(width 0.254)
			(type default)
		)
		(layer "In9.Cu")
	)
	(gr_line
		(start 344.678 -228.282246)
		(end 343.737946 -228.282246)
		(stroke
			(width 0.254)
			(type default)
		)
		(layer "In9.Cu")
	)
	(gr_circle
		(center 344.69832 -337.012788)
		(end 345.57843 -337.012788)
		(stroke
			(width 0.2)
			(type default)
		)
		(fill no)
		(layer "In9.Cu")
	)
	(gr_line
		(start 344.860118 -134.715504)
		(end 361.113578 -150.968964)
		(stroke
			(width 0.508)
			(type default)
		)
		(layer "In9.Cu")
	)
	(gr_line
		(start 344.978482 -281.37866)
		(end 345.448382 -282.188666)
		(stroke
			(width 0.254)
			(type default)
		)
		(layer "In9.Cu")
	)
	(gr_circle
		(center 345.100402 -158.278576)
		(end 345.989402 -158.278576)
		(stroke
			(width 0.2)
			(type default)
		)
		(fill no)
		(layer "In9.Cu")
	)
	(gr_circle
		(center 345.100402 -157.541976)
		(end 345.989402 -157.541976)
		(stroke
			(width 0.2)
			(type default)
		)
		(fill no)
		(layer "In9.Cu")
	)
	(gr_line
		(start 345.1479 -246.912384)
		(end 344.207846 -245.292372)
		(stroke
			(width 0.254)
			(type default)
		)
		(layer "In9.Cu")
	)
	(gr_line
		(start 345.1479 -243.67236)
		(end 344.207846 -242.052348)
		(stroke
			(width 0.254)
			(type default)
		)
		(layer "In9.Cu")
	)
	(gr_line
		(start 345.1479 -240.432336)
		(end 344.207846 -238.812324)
		(stroke
			(width 0.254)
			(type default)
		)
		(layer "In9.Cu")
	)
	(gr_line
		(start 345.1479 -235.5723)
		(end 344.207846 -233.952288)
		(stroke
			(width 0.254)
			(type default)
		)
		(layer "In9.Cu")
	)
	(gr_line
		(start 345.1479 -232.332276)
		(end 344.678 -231.52227)
		(stroke
			(width 0.254)
			(type default)
		)
		(layer "In9.Cu")
	)
	(gr_line
		(start 345.1479 -230.712264)
		(end 344.678 -229.902258)
		(stroke
			(width 0.254)
			(type default)
		)
		(layer "In9.Cu")
	)
	(gr_line
		(start 345.1479 -229.092252)
		(end 344.678 -228.282246)
		(stroke
			(width 0.254)
			(type default)
		)
		(layer "In9.Cu")
	)
	(gr_line
		(start 345.151202 -256.634488)
		(end 345.621102 -255.824482)
		(stroke
			(width 0.254)
			(type default)
		)
		(layer "In9.Cu")
	)
	(gr_circle
		(center 345.31554 -337.012788)
		(end 346.19565 -337.012788)
		(stroke
			(width 0.2)
			(type default)
		)
		(fill no)
		(layer "In9.Cu")
	)
	(gr_line
		(start 345.448382 -288.668714)
		(end 344.508582 -290.288726)
		(stroke
			(width 0.254)
			(type default)
		)
		(layer "In9.Cu")
	)
	(gr_line
		(start 345.448382 -285.42869)
		(end 344.508582 -287.048702)
		(stroke
			(width 0.254)
			(type default)
		)
		(layer "In9.Cu")
	)
	(gr_line
		(start 345.448382 -282.188666)
		(end 344.508582 -283.808678)
		(stroke
			(width 0.254)
			(type default)
		)
		(layer "In9.Cu")
	)
	(gr_line
		(start 345.448382 -280.568654)
		(end 344.978482 -281.37866)
		(stroke
			(width 0.254)
			(type default)
		)
		(layer "In9.Cu")
	)
	(gr_line
		(start 345.448382 -277.32863)
		(end 344.508582 -278.948642)
		(stroke
			(width 0.254)
			(type default)
		)
		(layer "In9.Cu")
	)
	(gr_line
		(start 345.448382 -274.088606)
		(end 344.508582 -275.708618)
		(stroke
			(width 0.254)
			(type default)
		)
		(layer "In9.Cu")
	)
	(gr_line
		(start 345.448382 -270.848582)
		(end 344.508582 -272.468594)
		(stroke
			(width 0.254)
			(type default)
		)
		(layer "In9.Cu")
	)
	(gr_line
		(start 345.448382 -267.608558)
		(end 344.508582 -269.22857)
		(stroke
			(width 0.254)
			(type default)
		)
		(layer "In9.Cu")
	)
	(gr_line
		(start 345.618054 -249.342402)
		(end 344.207846 -248.532396)
		(stroke
			(width 0.254)
			(type default)
		)
		(layer "In9.Cu")
	)
	(gr_line
		(start 345.618054 -238.002318)
		(end 344.678 -236.382306)
		(stroke
			(width 0.254)
			(type default)
		)
		(layer "In9.Cu")
	)
	(gr_line
		(start 345.621102 -255.824482)
		(end 347.031056 -256.634488)
		(stroke
			(width 0.254)
			(type default)
		)
		(layer "In9.Cu")
	)
	(gr_circle
		(center 345.623896 -336.317336)
		(end 346.512896 -336.317336)
		(stroke
			(width 0.2)
			(type default)
		)
		(fill no)
		(layer "In9.Cu")
	)
	(gr_circle
		(center 345.623896 -335.580736)
		(end 346.512896 -335.580736)
		(stroke
			(width 0.2)
			(type default)
		)
		(fill no)
		(layer "In9.Cu")
	)
	(gr_circle
		(center 345.684856 -160.633156)
		(end 346.573856 -160.633156)
		(stroke
			(width 0.2)
			(type default)
		)
		(fill no)
		(layer "In9.Cu")
	)
	(gr_circle
		(center 345.684856 -159.896556)
		(end 346.573856 -159.896556)
		(stroke
			(width 0.2)
			(type default)
		)
		(fill no)
		(layer "In9.Cu")
	)
	(gr_circle
		(center 345.802458 -159.151066)
		(end 346.682568 -159.151066)
		(stroke
			(width 0.2)
			(type default)
		)
		(fill no)
		(layer "In9.Cu")
	)
	(gr_line
		(start 345.918536 -279.758648)
		(end 345.448382 -280.568654)
		(stroke
			(width 0.254)
			(type default)
		)
		(layer "In9.Cu")
	)
	(gr_line
		(start 345.921076 -291.095938)
		(end 346.86113 -291.095938)
		(stroke
			(width 0.6096)
			(type default)
		)
		(layer "In9.Cu")
	)
	(gr_line
		(start 345.921076 -289.475926)
		(end 346.86113 -289.475926)
		(stroke
			(width 0.6096)
			(type default)
		)
		(layer "In9.Cu")
	)
	(gr_line
		(start 345.921076 -287.856168)
		(end 346.86113 -287.856168)
		(stroke
			(width 0.6096)
			(type default)
		)
		(layer "In9.Cu")
	)
	(gr_line
		(start 345.921076 -286.236156)
		(end 346.86113 -286.236156)
		(stroke
			(width 0.6096)
			(type default)
		)
		(layer "In9.Cu")
	)
	(gr_circle
		(center 346.017596 -339.358478)
		(end 346.906596 -339.358478)
		(stroke
			(width 0.2)
			(type default)
		)
		(fill no)
		(layer "In9.Cu")
	)
	(gr_circle
		(center 346.017596 -338.621878)
		(end 346.906596 -338.621878)
		(stroke
			(width 0.2)
			(type default)
		)
		(fill no)
		(layer "In9.Cu")
	)
	(gr_circle
		(center 346.017596 -337.885278)
		(end 346.906596 -337.885278)
		(stroke
			(width 0.2)
			(type default)
		)
		(fill no)
		(layer "In9.Cu")
	)
	(gr_line
		(start 346.05468 -396.671292)
		(end 343.066878 -396.671292)
		(stroke
			(width 0.508)
			(type default)
		)
		(layer "In9.Cu")
	)
	(gr_circle
		(center 346.419678 -159.151066)
		(end 347.299788 -159.151066)
		(stroke
			(width 0.2)
			(type default)
		)
		(fill no)
		(layer "In9.Cu")
	)
	(gr_circle
		(center 346.54236 -337.445858)
		(end 347.43136 -337.445858)
		(stroke
			(width 0.2)
			(type default)
		)
		(fill no)
		(layer "In9.Cu")
	)
	(gr_circle
		(center 346.56776 -339.731858)
		(end 347.45676 -339.731858)
		(stroke
			(width 0.2)
			(type default)
		)
		(fill no)
		(layer "In9.Cu")
	)
	(gr_circle
		(center 346.56776 -338.969858)
		(end 347.45676 -338.969858)
		(stroke
			(width 0.2)
			(type default)
		)
		(fill no)
		(layer "In9.Cu")
	)
	(gr_circle
		(center 346.56776 -338.207858)
		(end 347.45676 -338.207858)
		(stroke
			(width 0.2)
			(type default)
		)
		(fill no)
		(layer "In9.Cu")
	)
	(gr_line
		(start 346.71635 -328.419206)
		(end 344.246962 -325.949818)
		(stroke
			(width 0.508)
			(type default)
		)
		(layer "In9.Cu")
	)
	(gr_line
		(start 346.86113 -284.616144)
		(end 345.921076 -284.616144)
		(stroke
			(width 0.6096)
			(type default)
		)
		(layer "In9.Cu")
	)
	(gr_line
		(start 346.86113 -282.996132)
		(end 345.921076 -282.996132)
		(stroke
			(width 0.6096)
			(type default)
		)
		(layer "In9.Cu")
	)
	(gr_line
		(start 346.86113 -281.37612)
		(end 345.921076 -281.37612)
		(stroke
			(width 0.6096)
			(type default)
		)
		(layer "In9.Cu")
	)
	(gr_line
		(start 347.028008 -248.532396)
		(end 345.618054 -249.342402)
		(stroke
			(width 0.254)
			(type default)
		)
		(layer "In9.Cu")
	)
	(gr_line
		(start 347.031056 -256.634488)
		(end 347.50121 -255.824482)
		(stroke
			(width 0.254)
			(type default)
		)
		(layer "In9.Cu")
	)
	(gr_circle
		(center 347.036898 -159.151066)
		(end 347.917008 -159.151066)
		(stroke
			(width 0.2)
			(type default)
		)
		(fill no)
		(layer "In9.Cu")
	)
	(gr_line
		(start 347.32849 -267.608558)
		(end 345.448382 -267.608558)
		(stroke
			(width 0.254)
			(type default)
		)
		(layer "In9.Cu")
	)
	(gr_line
		(start 347.50121 -255.824482)
		(end 348.44101 -255.824482)
		(stroke
			(width 0.254)
			(type default)
		)
		(layer "In9.Cu")
	)
	(gr_line
		(start 347.75521 -394.970762)
		(end 346.05468 -396.671292)
		(stroke
			(width 0.508)
			(type default)
		)
		(layer "In9.Cu")
	)
	(gr_line
		(start 347.79839 -266.798552)
		(end 347.32849 -267.608558)
		(stroke
			(width 0.254)
			(type default)
		)
		(layer "In9.Cu")
	)
	(gr_line
		(start 347.968062 -255.012444)
		(end 349.378016 -254.202438)
		(stroke
			(width 0.254)
			(type default)
		)
		(layer "In9.Cu")
	)
	(gr_line
		(start 347.968062 -253.392432)
		(end 349.378016 -252.582426)
		(stroke
			(width 0.254)
			(type default)
		)
		(layer "In9.Cu")
	)
	(gr_line
		(start 347.968062 -250.152408)
		(end 347.028008 -248.532396)
		(stroke
			(width 0.254)
			(type default)
		)
		(layer "In9.Cu")
	)
	(gr_line
		(start 348.268544 -265.988546)
		(end 347.79839 -266.798552)
		(stroke
			(width 0.254)
			(type default)
		)
		(layer "In9.Cu")
	)
	(gr_line
		(start 348.268544 -264.368534)
		(end 349.678498 -265.17854)
		(stroke
			(width 0.254)
			(type default)
		)
		(layer "In9.Cu")
	)
	(gr_line
		(start 348.44482 -394.970762)
		(end 347.75521 -394.970762)
		(stroke
			(width 0.508)
			(type default)
		)
		(layer "In9.Cu")
	)
	(gr_line
		(start 348.741238 -291.095938)
		(end 349.681292 -291.095938)
		(stroke
			(width 0.6096)
			(type default)
		)
		(layer "In9.Cu")
	)
	(gr_line
		(start 348.741238 -289.475926)
		(end 349.681292 -289.475926)
		(stroke
			(width 0.6096)
			(type default)
		)
		(layer "In9.Cu")
	)
	(gr_line
		(start 348.741238 -287.856168)
		(end 349.681292 -287.856168)
		(stroke
			(width 0.6096)
			(type default)
		)
		(layer "In9.Cu")
	)
	(gr_line
		(start 348.907862 -256.632456)
		(end 347.968062 -255.012444)
		(stroke
			(width 0.254)
			(type default)
		)
		(layer "In9.Cu")
	)
	(gr_line
		(start 348.90837 -256.63271)
		(end 347.96857 -255.012698)
		(stroke
			(width 0.254)
			(type default)
		)
		(layer "In9.Cu")
	)
	(gr_line
		(start 348.90837 -256.63271)
		(end 350.79559 -257.93065)
		(stroke
			(width 0.254)
			(type default)
		)
		(layer "In9.Cu")
	)
	(gr_line
		(start 349.208598 -262.748522)
		(end 349.678498 -263.558528)
		(stroke
			(width 0.254)
			(type default)
		)
		(layer "In9.Cu")
	)
	(gr_line
		(start 349.208598 -261.12851)
		(end 349.678498 -261.938516)
		(stroke
			(width 0.254)
			(type default)
		)
		(layer "In9.Cu")
	)
	(gr_line
		(start 349.378016 -254.202438)
		(end 347.968062 -253.392432)
		(stroke
			(width 0.254)
			(type default)
		)
		(layer "In9.Cu")
	)
	(gr_line
		(start 349.378016 -252.582426)
		(end 349.847916 -251.77242)
		(stroke
			(width 0.254)
			(type default)
		)
		(layer "In9.Cu")
	)
	(gr_line
		(start 349.378016 -250.962414)
		(end 347.968062 -250.152408)
		(stroke
			(width 0.254)
			(type default)
		)
		(layer "In9.Cu")
	)
	(gr_line
		(start 349.678498 -266.798552)
		(end 348.268544 -265.988546)
		(stroke
			(width 0.254)
			(type default)
		)
		(layer "In9.Cu")
	)
	(gr_line
		(start 349.678498 -265.17854)
		(end 348.268544 -265.988546)
		(stroke
			(width 0.254)
			(type default)
		)
		(layer "In9.Cu")
	)
	(gr_line
		(start 349.678498 -263.558528)
		(end 348.268544 -264.368534)
		(stroke
			(width 0.254)
			(type default)
		)
		(layer "In9.Cu")
	)
	(gr_line
		(start 349.678498 -263.558528)
		(end 350.14789 -264.36828)
		(stroke
			(width 0.254)
			(type default)
		)
		(layer "In9.Cu")
	)
	(gr_line
		(start 349.678498 -261.938516)
		(end 349.208598 -262.748522)
		(stroke
			(width 0.254)
			(type default)
		)
		(layer "In9.Cu")
	)
	(gr_line
		(start 349.681292 -286.236156)
		(end 348.741238 -286.236156)
		(stroke
			(width 0.6096)
			(type default)
		)
		(layer "In9.Cu")
	)
	(gr_line
		(start 349.681292 -284.616144)
		(end 348.741238 -284.616144)
		(stroke
			(width 0.6096)
			(type default)
		)
		(layer "In9.Cu")
	)
	(gr_line
		(start 349.681292 -282.996132)
		(end 348.741238 -282.996132)
		(stroke
			(width 0.6096)
			(type default)
		)
		(layer "In9.Cu")
	)
	(gr_line
		(start 349.681292 -281.37612)
		(end 348.741238 -281.37612)
		(stroke
			(width 0.6096)
			(type default)
		)
		(layer "In9.Cu")
	)
	(gr_line
		(start 349.829374 -396.355316)
		(end 348.44482 -394.970762)
		(stroke
			(width 0.508)
			(type default)
		)
		(layer "In9.Cu")
	)
	(gr_line
		(start 349.847916 -251.77242)
		(end 349.378016 -250.962414)
		(stroke
			(width 0.254)
			(type default)
		)
		(layer "In9.Cu")
	)
	(gr_line
		(start 350.14789 -264.36828)
		(end 351.558098 -263.558274)
		(stroke
			(width 0.254)
			(type default)
		)
		(layer "In9.Cu")
	)
	(gr_line
		(start 350.220534 -267.340588)
		(end 349.678498 -266.798552)
		(stroke
			(width 0.254)
			(type default)
		)
		(layer "In9.Cu")
	)
	(gr_line
		(start 350.618552 -267.340588)
		(end 350.220534 -267.340588)
		(stroke
			(width 0.254)
			(type default)
		)
		(layer "In9.Cu")
	)
	(gr_line
		(start 350.79559 -259.730494)
		(end 349.208598 -261.12851)
		(stroke
			(width 0.254)
			(type default)
		)
		(layer "In9.Cu")
	)
	(gr_line
		(start 350.79559 -257.93065)
		(end 350.79559 -259.730494)
		(stroke
			(width 0.254)
			(type default)
		)
		(layer "In9.Cu")
	)
	(gr_line
		(start 351.093532 -172.152564)
		(end 337.5406 -172.152564)
		(stroke
			(width 0.508)
			(type default)
		)
		(layer "In9.Cu")
	)
	(gr_line
		(start 351.093532 -172.152564)
		(end 351.855532 -172.914564)
		(stroke
			(width 0.508)
			(type default)
		)
		(layer "In9.Cu")
	)
	(gr_line
		(start 351.25787 -250.962414)
		(end 349.847916 -251.77242)
		(stroke
			(width 0.254)
			(type default)
		)
		(layer "In9.Cu")
	)
	(gr_line
		(start 351.43567 -156.591762)
		(end 338.44357 -156.591762)
		(stroke
			(width 0.508)
			(type default)
		)
		(layer "In9.Cu")
	)
	(gr_line
		(start 351.558098 -263.558274)
		(end 353.43084 -262.180324)
		(stroke
			(width 0.254)
			(type default)
		)
		(layer "In9.Cu")
	)
	(gr_line
		(start 351.558606 -266.798552)
		(end 350.618552 -267.340588)
		(stroke
			(width 0.254)
			(type default)
		)
		(layer "In9.Cu")
	)
	(gr_line
		(start 351.561146 -291.095938)
		(end 352.5012 -291.095938)
		(stroke
			(width 0.6096)
			(type default)
		)
		(layer "In9.Cu")
	)
	(gr_line
		(start 351.561146 -289.475926)
		(end 352.5012 -289.475926)
		(stroke
			(width 0.6096)
			(type default)
		)
		(layer "In9.Cu")
	)
	(gr_line
		(start 351.561146 -287.856168)
		(end 352.5012 -287.856168)
		(stroke
			(width 0.6096)
			(type default)
		)
		(layer "In9.Cu")
	)
	(gr_line
		(start 351.728024 -251.77242)
		(end 351.25787 -250.962414)
		(stroke
			(width 0.254)
			(type default)
		)
		(layer "In9.Cu")
	)
	(gr_line
		(start 351.855532 -178.629564)
		(end 353.633532 -180.407564)
		(stroke
			(width 0.508)
			(type default)
		)
		(layer "In9.Cu")
	)
	(gr_line
		(start 351.855532 -172.914564)
		(end 351.855532 -178.629564)
		(stroke
			(width 0.508)
			(type default)
		)
		(layer "In9.Cu")
	)
	(gr_line
		(start 352.028506 -265.988546)
		(end 351.558606 -266.798552)
		(stroke
			(width 0.254)
			(type default)
		)
		(layer "In9.Cu")
	)
	(gr_circle
		(center 352.322638 -167.430196)
		(end 353.211638 -167.430196)
		(stroke
			(width 0.2)
			(type default)
		)
		(fill no)
		(layer "In9.Cu")
	)
	(gr_circle
		(center 352.322638 -166.693596)
		(end 353.211638 -166.693596)
		(stroke
			(width 0.2)
			(type default)
		)
		(fill no)
		(layer "In9.Cu")
	)
	(gr_circle
		(center 352.322638 -165.956996)
		(end 353.211638 -165.956996)
		(stroke
			(width 0.2)
			(type default)
		)
		(fill no)
		(layer "In9.Cu")
	)
	(gr_circle
		(center 352.356928 -341.922862)
		(end 353.237038 -341.922862)
		(stroke
			(width 0.2)
			(type default)
		)
		(fill no)
		(layer "In9.Cu")
	)
	(gr_line
		(start 352.5012 -286.236156)
		(end 351.561146 -286.236156)
		(stroke
			(width 0.6096)
			(type default)
		)
		(layer "In9.Cu")
	)
	(gr_line
		(start 352.5012 -284.616144)
		(end 351.561146 -284.616144)
		(stroke
			(width 0.6096)
			(type default)
		)
		(layer "In9.Cu")
	)
	(gr_line
		(start 352.5012 -282.996132)
		(end 351.561146 -282.996132)
		(stroke
			(width 0.6096)
			(type default)
		)
		(layer "In9.Cu")
	)
	(gr_line
		(start 352.53041 -328.419206)
		(end 346.71635 -328.419206)
		(stroke
			(width 0.508)
			(type default)
		)
		(layer "In9.Cu")
	)
	(gr_circle
		(center 352.856038 -166.312596)
		(end 353.745038 -166.312596)
		(stroke
			(width 0.2)
			(type default)
		)
		(fill no)
		(layer "In9.Cu")
	)
	(gr_circle
		(center 352.881438 -167.074596)
		(end 353.770438 -167.074596)
		(stroke
			(width 0.2)
			(type default)
		)
		(fill no)
		(layer "In9.Cu")
	)
	(gr_circle
		(center 352.974148 -341.922862)
		(end 353.854258 -341.922862)
		(stroke
			(width 0.2)
			(type default)
		)
		(fill no)
		(layer "In9.Cu")
	)
	(gr_line
		(start 353.137978 -250.962414)
		(end 351.728024 -251.77242)
		(stroke
			(width 0.254)
			(type default)
		)
		(layer "In9.Cu")
	)
	(gr_line
		(start 353.348798 -327.600818)
		(end 352.53041 -328.419206)
		(stroke
			(width 0.508)
			(type default)
		)
		(layer "In9.Cu")
	)
	(gr_circle
		(center 353.406202 -166.635176)
		(end 354.295202 -166.635176)
		(stroke
			(width 0.2)
			(type default)
		)
		(fill no)
		(layer "In9.Cu")
	)
	(gr_circle
		(center 353.406202 -165.898576)
		(end 354.295202 -165.898576)
		(stroke
			(width 0.2)
			(type default)
		)
		(fill no)
		(layer "In9.Cu")
	)
	(gr_line
		(start 353.43084 -262.180324)
		(end 354.28809 -261.323074)
		(stroke
			(width 0.254)
			(type default)
		)
		(layer "In9.Cu")
	)
	(gr_line
		(start 353.43846 -266.798552)
		(end 352.028506 -265.988546)
		(stroke
			(width 0.254)
			(type default)
		)
		(layer "In9.Cu")
	)
	(gr_line
		(start 353.54641 -327.600818)
		(end 379.758702 -327.600818)
		(stroke
			(width 0.508)
			(type default)
		)
		(layer "In9.Cu")
	)
	(gr_circle
		(center 353.591368 -341.922862)
		(end 354.471478 -341.922862)
		(stroke
			(width 0.2)
			(type default)
		)
		(fill no)
		(layer "In9.Cu")
	)
	(gr_line
		(start 353.607878 -251.77242)
		(end 353.137978 -250.962414)
		(stroke
			(width 0.254)
			(type default)
		)
		(layer "In9.Cu")
	)
	(gr_line
		(start 353.633532 -180.407564)
		(end 359.221532 -180.407564)
		(stroke
			(width 0.508)
			(type default)
		)
		(layer "In9.Cu")
	)
	(gr_line
		(start 353.72294 -327.600818)
		(end 353.348798 -327.600818)
		(stroke
			(width 0.508)
			(type default)
		)
		(layer "In9.Cu")
	)
	(gr_circle
		(center 353.899724 -341.22741)
		(end 354.788724 -341.22741)
		(stroke
			(width 0.2)
			(type default)
		)
		(fill no)
		(layer "In9.Cu")
	)
	(gr_circle
		(center 353.899724 -340.49081)
		(end 354.788724 -340.49081)
		(stroke
			(width 0.2)
			(type default)
		)
		(fill no)
		(layer "In9.Cu")
	)
	(gr_line
		(start 353.908614 -267.608558)
		(end 353.43846 -266.798552)
		(stroke
			(width 0.254)
			(type default)
		)
		(layer "In9.Cu")
	)
	(gr_circle
		(center 353.990656 -168.982136)
		(end 354.879656 -168.982136)
		(stroke
			(width 0.2)
			(type default)
		)
		(fill no)
		(layer "In9.Cu")
	)
	(gr_circle
		(center 353.990656 -168.245536)
		(end 354.879656 -168.245536)
		(stroke
			(width 0.2)
			(type default)
		)
		(fill no)
		(layer "In9.Cu")
	)
	(gr_circle
		(center 354.108258 -167.507666)
		(end 354.988368 -167.507666)
		(stroke
			(width 0.2)
			(type default)
		)
		(fill no)
		(layer "In9.Cu")
	)
	(gr_line
		(start 354.28809 -261.323074)
		(end 364.137956 -261.323074)
		(stroke
			(width 0.254)
			(type default)
		)
		(layer "In9.Cu")
	)
	(gr_circle
		(center 354.293424 -343.531952)
		(end 355.182424 -343.531952)
		(stroke
			(width 0.2)
			(type default)
		)
		(fill no)
		(layer "In9.Cu")
	)
	(gr_circle
		(center 354.293424 -342.795352)
		(end 355.182424 -342.795352)
		(stroke
			(width 0.2)
			(type default)
		)
		(fill no)
		(layer "In9.Cu")
	)
	(gr_line
		(start 354.381054 -291.095938)
		(end 355.321108 -291.095938)
		(stroke
			(width 0.6096)
			(type default)
		)
		(layer "In9.Cu")
	)
	(gr_line
		(start 354.381054 -289.475926)
		(end 355.321108 -289.475926)
		(stroke
			(width 0.6096)
			(type default)
		)
		(layer "In9.Cu")
	)
	(gr_line
		(start 354.381054 -287.856168)
		(end 355.321108 -287.856168)
		(stroke
			(width 0.6096)
			(type default)
		)
		(layer "In9.Cu")
	)
	(gr_circle
		(center 354.725478 -167.507666)
		(end 355.605588 -167.507666)
		(stroke
			(width 0.2)
			(type default)
		)
		(fill no)
		(layer "In9.Cu")
	)
	(gr_circle
		(center 354.818188 -342.355932)
		(end 355.707188 -342.355932)
		(stroke
			(width 0.2)
			(type default)
		)
		(fill no)
		(layer "In9.Cu")
	)
	(gr_circle
		(center 354.843588 -343.117932)
		(end 355.732588 -343.117932)
		(stroke
			(width 0.2)
			(type default)
		)
		(fill no)
		(layer "In9.Cu")
	)
	(gr_line
		(start 355.018086 -250.962414)
		(end 353.607878 -251.77242)
		(stroke
			(width 0.254)
			(type default)
		)
		(layer "In9.Cu")
	)
	(gr_line
		(start 355.318568 -266.798552)
		(end 353.908614 -267.608558)
		(stroke
			(width 0.254)
			(type default)
		)
		(layer "In9.Cu")
	)
	(gr_line
		(start 355.321108 -286.236156)
		(end 354.381054 -286.236156)
		(stroke
			(width 0.6096)
			(type default)
		)
		(layer "In9.Cu")
	)
	(gr_line
		(start 355.321108 -284.616144)
		(end 354.381054 -284.616144)
		(stroke
			(width 0.6096)
			(type default)
		)
		(layer "In9.Cu")
	)
	(gr_line
		(start 355.321108 -282.996132)
		(end 354.381054 -282.996132)
		(stroke
			(width 0.6096)
			(type default)
		)
		(layer "In9.Cu")
	)
	(gr_circle
		(center 355.342698 -167.507666)
		(end 356.222808 -167.507666)
		(stroke
			(width 0.2)
			(type default)
		)
		(fill no)
		(layer "In9.Cu")
	)
	(gr_circle
		(center 355.376988 -343.473532)
		(end 356.265988 -343.473532)
		(stroke
			(width 0.2)
			(type default)
		)
		(fill no)
		(layer "In9.Cu")
	)
	(gr_circle
		(center 355.376988 -342.736932)
		(end 356.265988 -342.736932)
		(stroke
			(width 0.2)
			(type default)
		)
		(fill no)
		(layer "In9.Cu")
	)
	(gr_circle
		(center 355.376988 -342.000332)
		(end 356.265988 -342.000332)
		(stroke
			(width 0.2)
			(type default)
		)
		(fill no)
		(layer "In9.Cu")
	)
	(gr_line
		(start 355.487986 -251.77242)
		(end 355.018086 -250.962414)
		(stroke
			(width 0.254)
			(type default)
		)
		(layer "In9.Cu")
	)
	(gr_line
		(start 355.788468 -265.988546)
		(end 355.318568 -266.798552)
		(stroke
			(width 0.254)
			(type default)
		)
		(layer "In9.Cu")
	)
	(gr_line
		(start 356.731062 -290.285932)
		(end 357.671116 -290.285932)
		(stroke
			(width 0.6096)
			(type default)
		)
		(layer "In9.Cu")
	)
	(gr_line
		(start 356.731062 -288.66592)
		(end 357.671116 -288.66592)
		(stroke
			(width 0.6096)
			(type default)
		)
		(layer "In9.Cu")
	)
	(gr_line
		(start 356.731062 -287.045908)
		(end 357.671116 -287.045908)
		(stroke
			(width 0.6096)
			(type default)
		)
		(layer "In9.Cu")
	)
	(gr_line
		(start 356.89794 -250.962414)
		(end 355.487986 -251.77242)
		(stroke
			(width 0.254)
			(type default)
		)
		(layer "In9.Cu")
	)
	(gr_line
		(start 357.198422 -266.798552)
		(end 355.788468 -265.988546)
		(stroke
			(width 0.254)
			(type default)
		)
		(layer "In9.Cu")
	)
	(gr_line
		(start 357.368094 -250.152408)
		(end 356.89794 -250.962414)
		(stroke
			(width 0.254)
			(type default)
		)
		(layer "In9.Cu")
	)
	(gr_line
		(start 357.668576 -267.608558)
		(end 357.198422 -266.798552)
		(stroke
			(width 0.254)
			(type default)
		)
		(layer "In9.Cu")
	)
	(gr_line
		(start 357.671116 -285.42615)
		(end 356.731062 -285.42615)
		(stroke
			(width 0.6096)
			(type default)
		)
		(layer "In9.Cu")
	)
	(gr_line
		(start 357.671116 -283.806138)
		(end 356.731062 -283.806138)
		(stroke
			(width 0.6096)
			(type default)
		)
		(layer "In9.Cu")
	)
	(gr_line
		(start 357.671116 -282.186126)
		(end 356.731062 -282.186126)
		(stroke
			(width 0.6096)
			(type default)
		)
		(layer "In9.Cu")
	)
	(gr_line
		(start 358.084882 -396.355316)
		(end 349.829374 -396.355316)
		(stroke
			(width 0.508)
			(type default)
		)
		(layer "In9.Cu")
	)
	(gr_line
		(start 358.13365 -163.289742)
		(end 351.43567 -156.591762)
		(stroke
			(width 0.508)
			(type default)
		)
		(layer "In9.Cu")
	)
	(gr_line
		(start 358.205532 -391.971784)
		(end 358.485694 -392.251946)
		(stroke
			(width 0.508)
			(type default)
		)
		(layer "In9.Cu")
	)
	(gr_line
		(start 358.307894 -395.761972)
		(end 358.49306 -395.947138)
		(stroke
			(width 0.508)
			(type default)
		)
		(layer "In9.Cu")
	)
	(gr_line
		(start 358.307894 -395.12621)
		(end 358.307894 -395.761972)
		(stroke
			(width 0.508)
			(type default)
		)
		(layer "In9.Cu")
	)
	(gr_line
		(start 358.307894 -395.12621)
		(end 358.307894 -394.757402)
		(stroke
			(width 0.254)
			(type default)
		)
		(layer "In9.Cu")
	)
	(gr_line
		(start 358.307894 -394.757402)
		(end 358.485694 -394.579602)
		(stroke
			(width 0.254)
			(type default)
		)
		(layer "In9.Cu")
	)
	(gr_line
		(start 358.485694 -394.579602)
		(end 358.485694 -393.057634)
		(stroke
			(width 0.254)
			(type default)
		)
		(layer "In9.Cu")
	)
	(gr_line
		(start 358.485694 -392.251946)
		(end 358.485694 -393.057634)
		(stroke
			(width 0.508)
			(type default)
		)
		(layer "In9.Cu")
	)
	(gr_line
		(start 358.49306 -395.947138)
		(end 358.084882 -396.355316)
		(stroke
			(width 0.508)
			(type default)
		)
		(layer "In9.Cu")
	)
	(gr_line
		(start 358.778048 -250.962414)
		(end 357.368094 -250.152408)
		(stroke
			(width 0.254)
			(type default)
		)
		(layer "In9.Cu")
	)
	(gr_line
		(start 359.07853 -266.798552)
		(end 357.668576 -267.608558)
		(stroke
			(width 0.254)
			(type default)
		)
		(layer "In9.Cu")
	)
	(gr_line
		(start 359.221532 -180.407564)
		(end 360.237532 -181.423564)
		(stroke
			(width 0.508)
			(type default)
		)
		(layer "In9.Cu")
	)
	(gr_circle
		(center 359.58526 -152.71242)
		(end 360.98226 -152.71242)
		(stroke
			(width 0.2)
			(type default)
		)
		(fill no)
		(layer "In9.Cu")
	)
	(gr_line
		(start 360.237532 -187.011564)
		(end 362.015532 -188.789564)
		(stroke
			(width 0.508)
			(type default)
		)
		(layer "In9.Cu")
	)
	(gr_line
		(start 360.237532 -181.423564)
		(end 360.237532 -187.011564)
		(stroke
			(width 0.508)
			(type default)
		)
		(layer "In9.Cu")
	)
	(gr_circle
		(center 360.603038 -175.705516)
		(end 361.492038 -175.705516)
		(stroke
			(width 0.2)
			(type default)
		)
		(fill no)
		(layer "In9.Cu")
	)
	(gr_circle
		(center 360.603038 -174.968916)
		(end 361.492038 -174.968916)
		(stroke
			(width 0.2)
			(type default)
		)
		(fill no)
		(layer "In9.Cu")
	)
	(gr_circle
		(center 360.603038 -174.232316)
		(end 361.492038 -174.232316)
		(stroke
			(width 0.2)
			(type default)
		)
		(fill no)
		(layer "In9.Cu")
	)
	(gr_line
		(start 361.113578 -154.494484)
		(end 365.43742 -158.818326)
		(stroke
			(width 0.508)
			(type default)
		)
		(layer "In9.Cu")
	)
	(gr_line
		(start 361.113578 -150.968964)
		(end 361.113578 -154.494484)
		(stroke
			(width 0.508)
			(type default)
		)
		(layer "In9.Cu")
	)
	(gr_circle
		(center 361.136438 -174.587916)
		(end 362.025438 -174.587916)
		(stroke
			(width 0.2)
			(type default)
		)
		(fill no)
		(layer "In9.Cu")
	)
	(gr_circle
		(center 361.161838 -175.349916)
		(end 362.050838 -175.349916)
		(stroke
			(width 0.2)
			(type default)
		)
		(fill no)
		(layer "In9.Cu")
	)
	(gr_line
		(start 361.597956 -250.962414)
		(end 358.778048 -250.962414)
		(stroke
			(width 0.254)
			(type default)
		)
		(layer "In9.Cu")
	)
	(gr_circle
		(center 361.686602 -174.910496)
		(end 362.575602 -174.910496)
		(stroke
			(width 0.2)
			(type default)
		)
		(fill no)
		(layer "In9.Cu")
	)
	(gr_circle
		(center 361.686602 -174.173896)
		(end 362.575602 -174.173896)
		(stroke
			(width 0.2)
			(type default)
		)
		(fill no)
		(layer "In9.Cu")
	)
	(gr_line
		(start 361.898438 -266.798552)
		(end 359.07853 -266.798552)
		(stroke
			(width 0.254)
			(type default)
		)
		(layer "In9.Cu")
	)
	(gr_line
		(start 362.015532 -188.789564)
		(end 366.907318 -188.789564)
		(stroke
			(width 0.508)
			(type default)
		)
		(layer "In9.Cu")
	)
	(gr_circle
		(center 362.271056 -177.254916)
		(end 363.160056 -177.254916)
		(stroke
			(width 0.2)
			(type default)
		)
		(fill no)
		(layer "In9.Cu")
	)
	(gr_circle
		(center 362.271056 -176.518316)
		(end 363.160056 -176.518316)
		(stroke
			(width 0.2)
			(type default)
		)
		(fill no)
		(layer "In9.Cu")
	)
	(gr_line
		(start 362.364782 -285.42615)
		(end 363.304836 -285.42615)
		(stroke
			(width 0.6096)
			(type default)
		)
		(layer "In9.Cu")
	)
	(gr_line
		(start 362.364782 -283.806138)
		(end 363.304836 -283.806138)
		(stroke
			(width 0.6096)
			(type default)
		)
		(layer "In9.Cu")
	)
	(gr_line
		(start 362.364782 -282.186126)
		(end 363.304836 -282.186126)
		(stroke
			(width 0.6096)
			(type default)
		)
		(layer "In9.Cu")
	)
	(gr_circle
		(center 362.396278 -175.859186)
		(end 363.276388 -175.859186)
		(stroke
			(width 0.2)
			(type default)
		)
		(fill no)
		(layer "In9.Cu")
	)
	(gr_line
		(start 363.004862 -248.534174)
		(end 362.064808 -248.534174)
		(stroke
			(width 0.6096)
			(type default)
		)
		(layer "In9.Cu")
	)
	(gr_line
		(start 363.004862 -246.914162)
		(end 362.064808 -246.914162)
		(stroke
			(width 0.6096)
			(type default)
		)
		(layer "In9.Cu")
	)
	(gr_line
		(start 363.004862 -245.29415)
		(end 362.064808 -245.29415)
		(stroke
			(width 0.6096)
			(type default)
		)
		(layer "In9.Cu")
	)
	(gr_line
		(start 363.004862 -243.674138)
		(end 362.064808 -243.674138)
		(stroke
			(width 0.6096)
			(type default)
		)
		(layer "In9.Cu")
	)
	(gr_line
		(start 363.00791 -250.152408)
		(end 361.597956 -250.962414)
		(stroke
			(width 0.254)
			(type default)
		)
		(layer "In9.Cu")
	)
	(gr_circle
		(center 363.013498 -175.859186)
		(end 363.893608 -175.859186)
		(stroke
			(width 0.2)
			(type default)
		)
		(fill no)
		(layer "In9.Cu")
	)
	(gr_line
		(start 363.308392 -265.988546)
		(end 361.898438 -266.798552)
		(stroke
			(width 0.254)
			(type default)
		)
		(layer "In9.Cu")
	)
	(gr_line
		(start 363.478064 -250.962414)
		(end 363.00791 -250.152408)
		(stroke
			(width 0.254)
			(type default)
		)
		(layer "In9.Cu")
	)
	(gr_circle
		(center 363.630718 -175.859186)
		(end 364.510828 -175.859186)
		(stroke
			(width 0.2)
			(type default)
		)
		(fill no)
		(layer "In9.Cu")
	)
	(gr_line
		(start 363.778546 -266.798552)
		(end 363.308392 -265.988546)
		(stroke
			(width 0.254)
			(type default)
		)
		(layer "In9.Cu")
	)
	(gr_line
		(start 364.137956 -261.323074)
		(end 364.485174 -261.670292)
		(stroke
			(width 0.254)
			(type default)
		)
		(layer "In9.Cu")
	)
	(gr_line
		(start 364.485174 -261.670292)
		(end 368.210084 -261.670292)
		(stroke
			(width 0.254)
			(type default)
		)
		(layer "In9.Cu")
	)
	(gr_line
		(start 364.71479 -286.236156)
		(end 365.654844 -286.236156)
		(stroke
			(width 0.6096)
			(type default)
		)
		(layer "In9.Cu")
	)
	(gr_line
		(start 364.71479 -284.616144)
		(end 365.654844 -284.616144)
		(stroke
			(width 0.6096)
			(type default)
		)
		(layer "In9.Cu")
	)
	(gr_line
		(start 364.71479 -282.996132)
		(end 365.654844 -282.996132)
		(stroke
			(width 0.6096)
			(type default)
		)
		(layer "In9.Cu")
	)
	(gr_line
		(start 364.888018 -251.77242)
		(end 363.478064 -250.962414)
		(stroke
			(width 0.254)
			(type default)
		)
		(layer "In9.Cu")
	)
	(gr_line
		(start 365.1885 -267.608558)
		(end 363.778546 -266.798552)
		(stroke
			(width 0.254)
			(type default)
		)
		(layer "In9.Cu")
	)
	(gr_line
		(start 365.35487 -247.724168)
		(end 364.414816 -247.724168)
		(stroke
			(width 0.6096)
			(type default)
		)
		(layer "In9.Cu")
	)
	(gr_line
		(start 365.35487 -246.104156)
		(end 364.414816 -246.104156)
		(stroke
			(width 0.6096)
			(type default)
		)
		(layer "In9.Cu")
	)
	(gr_line
		(start 365.35487 -244.484144)
		(end 364.414816 -244.484144)
		(stroke
			(width 0.6096)
			(type default)
		)
		(layer "In9.Cu")
	)
	(gr_line
		(start 365.357918 -250.962414)
		(end 364.888018 -251.77242)
		(stroke
			(width 0.254)
			(type default)
		)
		(layer "In9.Cu")
	)
	(gr_line
		(start 365.43742 -158.818326)
		(end 380.716282 -158.818326)
		(stroke
			(width 0.508)
			(type default)
		)
		(layer "In9.Cu")
	)
	(gr_line
		(start 365.6584 -266.798552)
		(end 365.1885 -267.608558)
		(stroke
			(width 0.254)
			(type default)
		)
		(layer "In9.Cu")
	)
	(gr_line
		(start 365.783622 -395.947138)
		(end 358.49306 -395.947138)
		(stroke
			(width 0.508)
			(type default)
		)
		(layer "In9.Cu")
	)
	(gr_line
		(start 366.359694 -395.371066)
		(end 365.783622 -395.947138)
		(stroke
			(width 0.508)
			(type default)
		)
		(layer "In9.Cu")
	)
	(gr_line
		(start 366.359694 -392.52779)
		(end 366.359694 -395.371066)
		(stroke
			(width 0.508)
			(type default)
		)
		(layer "In9.Cu")
	)
	(gr_circle
		(center 366.744504 -164.53358)
		(end 367.633504 -164.53358)
		(stroke
			(width 0.2)
			(type default)
		)
		(fill no)
		(layer "In9.Cu")
	)
	(gr_circle
		(center 366.744504 -163.89858)
		(end 367.633504 -163.89858)
		(stroke
			(width 0.2)
			(type default)
		)
		(fill no)
		(layer "In9.Cu")
	)
	(gr_circle
		(center 366.757204 -165.19398)
		(end 367.646204 -165.19398)
		(stroke
			(width 0.2)
			(type default)
		)
		(fill no)
		(layer "In9.Cu")
	)
	(gr_line
		(start 366.767872 -250.152408)
		(end 365.357918 -250.962414)
		(stroke
			(width 0.254)
			(type default)
		)
		(layer "In9.Cu")
	)
	(gr_line
		(start 366.773206 -392.114278)
		(end 366.359694 -392.52779)
		(stroke
			(width 0.508)
			(type default)
		)
		(layer "In9.Cu")
	)
	(gr_line
		(start 366.907318 -188.789564)
		(end 371.860318 -193.742564)
		(stroke
			(width 0.508)
			(type default)
		)
		(layer "In9.Cu")
	)
	(gr_line
		(start 367.068354 -265.988546)
		(end 365.6584 -266.798552)
		(stroke
			(width 0.254)
			(type default)
		)
		(layer "In9.Cu")
	)
	(gr_line
		(start 367.238026 -250.962414)
		(end 366.767872 -250.152408)
		(stroke
			(width 0.254)
			(type default)
		)
		(layer "In9.Cu")
	)
	(gr_circle
		(center 367.379504 -164.53358)
		(end 368.268504 -164.53358)
		(stroke
			(width 0.2)
			(type default)
		)
		(fill no)
		(layer "In9.Cu")
	)
	(gr_circle
		(center 367.379504 -163.89858)
		(end 368.268504 -163.89858)
		(stroke
			(width 0.2)
			(type default)
		)
		(fill no)
		(layer "In9.Cu")
	)
	(gr_circle
		(center 367.392204 -165.19398)
		(end 368.281204 -165.19398)
		(stroke
			(width 0.2)
			(type default)
		)
		(fill no)
		(layer "In9.Cu")
	)
	(gr_line
		(start 367.534698 -286.236156)
		(end 368.474752 -286.236156)
		(stroke
			(width 0.6096)
			(type default)
		)
		(layer "In9.Cu")
	)
	(gr_line
		(start 367.534698 -284.616144)
		(end 368.474752 -284.616144)
		(stroke
			(width 0.6096)
			(type default)
		)
		(layer "In9.Cu")
	)
	(gr_line
		(start 367.534698 -282.996132)
		(end 368.474752 -282.996132)
		(stroke
			(width 0.6096)
			(type default)
		)
		(layer "In9.Cu")
	)
	(gr_line
		(start 367.538508 -266.798552)
		(end 367.068354 -265.988546)
		(stroke
			(width 0.254)
			(type default)
		)
		(layer "In9.Cu")
	)
	(gr_circle
		(center 368.044984 -164.53358)
		(end 368.933984 -164.53358)
		(stroke
			(width 0.2)
			(type default)
		)
		(fill no)
		(layer "In9.Cu")
	)
	(gr_circle
		(center 368.044984 -163.89858)
		(end 368.933984 -163.89858)
		(stroke
			(width 0.2)
			(type default)
		)
		(fill no)
		(layer "In9.Cu")
	)
	(gr_circle
		(center 368.057684 -165.19398)
		(end 368.946684 -165.19398)
		(stroke
			(width 0.2)
			(type default)
		)
		(fill no)
		(layer "In9.Cu")
	)
	(gr_line
		(start 368.174778 -247.724168)
		(end 367.234724 -247.724168)
		(stroke
			(width 0.6096)
			(type default)
		)
		(layer "In9.Cu")
	)
	(gr_line
		(start 368.174778 -246.104156)
		(end 367.234724 -246.104156)
		(stroke
			(width 0.6096)
			(type default)
		)
		(layer "In9.Cu")
	)
	(gr_line
		(start 368.174778 -244.484144)
		(end 367.234724 -244.484144)
		(stroke
			(width 0.6096)
			(type default)
		)
		(layer "In9.Cu")
	)
	(gr_line
		(start 368.210084 -261.670292)
		(end 368.478054 -261.938262)
		(stroke
			(width 0.254)
			(type default)
		)
		(layer "In9.Cu")
	)
	(gr_line
		(start 368.478054 -261.938262)
		(end 369.888008 -262.748268)
		(stroke
			(width 0.254)
			(type default)
		)
		(layer "In9.Cu")
	)
	(gr_line
		(start 368.64798 -251.77242)
		(end 367.238026 -250.962414)
		(stroke
			(width 0.254)
			(type default)
		)
		(layer "In9.Cu")
	)
	(gr_circle
		(center 368.679984 -164.53358)
		(end 369.568984 -164.53358)
		(stroke
			(width 0.2)
			(type default)
		)
		(fill no)
		(layer "In9.Cu")
	)
	(gr_circle
		(center 368.679984 -163.89858)
		(end 369.568984 -163.89858)
		(stroke
			(width 0.2)
			(type default)
		)
		(fill no)
		(layer "In9.Cu")
	)
	(gr_circle
		(center 368.692684 -165.19398)
		(end 369.581684 -165.19398)
		(stroke
			(width 0.2)
			(type default)
		)
		(fill no)
		(layer "In9.Cu")
	)
	(gr_line
		(start 368.948462 -267.608558)
		(end 367.538508 -266.798552)
		(stroke
			(width 0.254)
			(type default)
		)
		(layer "In9.Cu")
	)
	(gr_circle
		(center 368.96421 -179.204874)
		(end 369.85321 -179.204874)
		(stroke
			(width 0.2)
			(type default)
		)
		(fill no)
		(layer "In9.Cu")
	)
	(gr_line
		(start 369.11788 -250.962414)
		(end 368.64798 -251.77242)
		(stroke
			(width 0.254)
			(type default)
		)
		(layer "In9.Cu")
	)
	(gr_circle
		(center 369.314984 -164.53358)
		(end 370.203984 -164.53358)
		(stroke
			(width 0.2)
			(type default)
		)
		(fill no)
		(layer "In9.Cu")
	)
	(gr_circle
		(center 369.314984 -163.89858)
		(end 370.203984 -163.89858)
		(stroke
			(width 0.2)
			(type default)
		)
		(fill no)
		(layer "In9.Cu")
	)
	(gr_circle
		(center 369.327684 -165.19398)
		(end 370.216684 -165.19398)
		(stroke
			(width 0.2)
			(type default)
		)
		(fill no)
		(layer "In9.Cu")
	)
	(gr_line
		(start 369.418362 -266.798552)
		(end 368.948462 -267.608558)
		(stroke
			(width 0.254)
			(type default)
		)
		(layer "In9.Cu")
	)
	(gr_circle
		(center 369.49761 -179.560474)
		(end 370.38661 -179.560474)
		(stroke
			(width 0.2)
			(type default)
		)
		(fill no)
		(layer "In9.Cu")
	)
	(gr_circle
		(center 369.49761 -178.798474)
		(end 370.38661 -178.798474)
		(stroke
			(width 0.2)
			(type default)
		)
		(fill no)
		(layer "In9.Cu")
	)
	(gr_circle
		(center 369.49761 -178.036474)
		(end 370.38661 -178.036474)
		(stroke
			(width 0.2)
			(type default)
		)
		(fill no)
		(layer "In9.Cu")
	)
	(gr_circle
		(center 369.52301 -180.322474)
		(end 370.41201 -180.322474)
		(stroke
			(width 0.2)
			(type default)
		)
		(fill no)
		(layer "In9.Cu")
	)
	(gr_line
		(start 369.888008 -262.748268)
		(end 370.357908 -261.938262)
		(stroke
			(width 0.254)
			(type default)
		)
		(layer "In9.Cu")
	)
	(gr_circle
		(center 369.949984 -164.53358)
		(end 370.838984 -164.53358)
		(stroke
			(width 0.2)
			(type default)
		)
		(fill no)
		(layer "In9.Cu")
	)
	(gr_circle
		(center 369.949984 -163.89858)
		(end 370.838984 -163.89858)
		(stroke
			(width 0.2)
			(type default)
		)
		(fill no)
		(layer "In9.Cu")
	)
	(gr_circle
		(center 369.962684 -165.19398)
		(end 370.851684 -165.19398)
		(stroke
			(width 0.2)
			(type default)
		)
		(fill no)
		(layer "In9.Cu")
	)
	(gr_circle
		(center 370.047774 -179.883054)
		(end 370.936774 -179.883054)
		(stroke
			(width 0.2)
			(type default)
		)
		(fill no)
		(layer "In9.Cu")
	)
	(gr_circle
		(center 370.047774 -179.146454)
		(end 370.936774 -179.146454)
		(stroke
			(width 0.2)
			(type default)
		)
		(fill no)
		(layer "In9.Cu")
	)
	(gr_line
		(start 370.35486 -286.236156)
		(end 371.294914 -286.236156)
		(stroke
			(width 0.6096)
			(type default)
		)
		(layer "In9.Cu")
	)
	(gr_line
		(start 370.35486 -284.616144)
		(end 371.294914 -284.616144)
		(stroke
			(width 0.6096)
			(type default)
		)
		(layer "In9.Cu")
	)
	(gr_line
		(start 370.35486 -282.996132)
		(end 371.294914 -282.996132)
		(stroke
			(width 0.6096)
			(type default)
		)
		(layer "In9.Cu")
	)
	(gr_line
		(start 370.35486 -281.37612)
		(end 371.294914 -281.37612)
		(stroke
			(width 0.6096)
			(type default)
		)
		(layer "In9.Cu")
	)
	(gr_line
		(start 370.357908 -261.938262)
		(end 371.767862 -262.748268)
		(stroke
			(width 0.254)
			(type default)
		)
		(layer "In9.Cu")
	)
	(gr_line
		(start 370.528088 -250.152408)
		(end 369.11788 -250.962414)
		(stroke
			(width 0.254)
			(type default)
		)
		(layer "In9.Cu")
	)
	(gr_circle
		(center 370.529358 -182.141876)
		(end 371.418358 -182.141876)
		(stroke
			(width 0.2)
			(type default)
		)
		(fill no)
		(layer "In9.Cu")
	)
	(gr_circle
		(center 370.529358 -181.405276)
		(end 371.418358 -181.405276)
		(stroke
			(width 0.2)
			(type default)
		)
		(fill no)
		(layer "In9.Cu")
	)
	(gr_circle
		(center 370.686584 -164.53358)
		(end 371.575584 -164.53358)
		(stroke
			(width 0.2)
			(type default)
		)
		(fill no)
		(layer "In9.Cu")
	)
	(gr_circle
		(center 370.686584 -163.89858)
		(end 371.575584 -163.89858)
		(stroke
			(width 0.2)
			(type default)
		)
		(fill no)
		(layer "In9.Cu")
	)
	(gr_circle
		(center 370.699284 -165.19398)
		(end 371.588284 -165.19398)
		(stroke
			(width 0.2)
			(type default)
		)
		(fill no)
		(layer "In9.Cu")
	)
	(gr_circle
		(center 370.74221 -180.803804)
		(end 371.62232 -180.803804)
		(stroke
			(width 0.2)
			(type default)
		)
		(fill no)
		(layer "In9.Cu")
	)
	(gr_line
		(start 370.82857 -265.988546)
		(end 369.418362 -266.798552)
		(stroke
			(width 0.254)
			(type default)
		)
		(layer "In9.Cu")
	)
	(gr_line
		(start 370.99494 -247.724168)
		(end 370.054886 -247.724168)
		(stroke
			(width 0.6096)
			(type default)
		)
		(layer "In9.Cu")
	)
	(gr_line
		(start 370.99494 -246.104156)
		(end 370.054886 -246.104156)
		(stroke
			(width 0.6096)
			(type default)
		)
		(layer "In9.Cu")
	)
	(gr_line
		(start 370.99494 -244.484144)
		(end 370.054886 -244.484144)
		(stroke
			(width 0.6096)
			(type default)
		)
		(layer "In9.Cu")
	)
	(gr_line
		(start 370.997988 -250.962414)
		(end 370.528088 -250.152408)
		(stroke
			(width 0.254)
			(type default)
		)
		(layer "In9.Cu")
	)
	(gr_line
		(start 371.29847 -266.798552)
		(end 370.82857 -265.988546)
		(stroke
			(width 0.254)
			(type default)
		)
		(layer "In9.Cu")
	)
	(gr_circle
		(center 371.35943 -180.803804)
		(end 372.23954 -180.803804)
		(stroke
			(width 0.2)
			(type default)
		)
		(fill no)
		(layer "In9.Cu")
	)
	(gr_line
		(start 371.767862 -262.748268)
		(end 373.17807 -263.558274)
		(stroke
			(width 0.254)
			(type default)
		)
		(layer "In9.Cu")
	)
	(gr_line
		(start 371.860318 -193.742564)
		(end 393.24661 -193.742564)
		(stroke
			(width 0.508)
			(type default)
		)
		(layer "In9.Cu")
	)
	(gr_circle
		(center 371.97665 -180.803804)
		(end 372.85676 -180.803804)
		(stroke
			(width 0.2)
			(type default)
		)
		(fill no)
		(layer "In9.Cu")
	)
	(gr_line
		(start 372.407942 -251.77242)
		(end 370.997988 -250.962414)
		(stroke
			(width 0.254)
			(type default)
		)
		(layer "In9.Cu")
	)
	(gr_line
		(start 372.708424 -267.608558)
		(end 371.29847 -266.798552)
		(stroke
			(width 0.254)
			(type default)
		)
		(layer "In9.Cu")
	)
	(gr_line
		(start 372.847616 -163.289742)
		(end 358.13365 -163.289742)
		(stroke
			(width 0.508)
			(type default)
		)
		(layer "In9.Cu")
	)
	(gr_line
		(start 372.878096 -250.962414)
		(end 372.407942 -251.77242)
		(stroke
			(width 0.254)
			(type default)
		)
		(layer "In9.Cu")
	)
	(gr_line
		(start 373.174768 -284.616144)
		(end 374.114822 -284.616144)
		(stroke
			(width 0.6096)
			(type default)
		)
		(layer "In9.Cu")
	)
	(gr_line
		(start 373.174768 -282.996132)
		(end 374.114822 -282.996132)
		(stroke
			(width 0.6096)
			(type default)
		)
		(layer "In9.Cu")
	)
	(gr_line
		(start 373.174768 -281.37612)
		(end 374.114822 -281.37612)
		(stroke
			(width 0.6096)
			(type default)
		)
		(layer "In9.Cu")
	)
	(gr_line
		(start 373.17807 -263.558274)
		(end 373.64797 -262.748268)
		(stroke
			(width 0.254)
			(type default)
		)
		(layer "In9.Cu")
	)
	(gr_line
		(start 373.178578 -266.798552)
		(end 372.708424 -267.608558)
		(stroke
			(width 0.254)
			(type default)
		)
		(layer "In9.Cu")
	)
	(gr_line
		(start 373.64797 -262.748268)
		(end 375.057924 -263.558274)
		(stroke
			(width 0.254)
			(type default)
		)
		(layer "In9.Cu")
	)
	(gr_line
		(start 373.814848 -247.724168)
		(end 372.874794 -247.724168)
		(stroke
			(width 0.6096)
			(type default)
		)
		(layer "In9.Cu")
	)
	(gr_line
		(start 373.814848 -246.104156)
		(end 372.874794 -246.104156)
		(stroke
			(width 0.6096)
			(type default)
		)
		(layer "In9.Cu")
	)
	(gr_line
		(start 373.814848 -244.484144)
		(end 372.874794 -244.484144)
		(stroke
			(width 0.6096)
			(type default)
		)
		(layer "In9.Cu")
	)
	(gr_line
		(start 373.817896 -238.002318)
		(end 375.22785 -238.812324)
		(stroke
			(width 0.254)
			(type default)
		)
		(layer "In9.Cu")
	)
	(gr_line
		(start 374.118378 -279.758648)
		(end 375.528586 -278.948642)
		(stroke
			(width 0.254)
			(type default)
		)
		(layer "In9.Cu")
	)
	(gr_line
		(start 374.118378 -266.798552)
		(end 373.178578 -266.798552)
		(stroke
			(width 0.254)
			(type default)
		)
		(layer "In9.Cu")
	)
	(gr_line
		(start 374.28805 -250.152408)
		(end 372.878096 -250.962414)
		(stroke
			(width 0.254)
			(type default)
		)
		(layer "In9.Cu")
	)
	(gr_line
		(start 374.28805 -246.912384)
		(end 375.22785 -248.532396)
		(stroke
			(width 0.254)
			(type default)
		)
		(layer "In9.Cu")
	)
	(gr_line
		(start 374.28805 -243.67236)
		(end 375.22785 -245.292372)
		(stroke
			(width 0.254)
			(type default)
		)
		(layer "In9.Cu")
	)
	(gr_line
		(start 374.28805 -240.432336)
		(end 375.22785 -242.052348)
		(stroke
			(width 0.254)
			(type default)
		)
		(layer "In9.Cu")
	)
	(gr_line
		(start 374.28805 -235.5723)
		(end 374.75795 -236.382306)
		(stroke
			(width 0.254)
			(type default)
		)
		(layer "In9.Cu")
	)
	(gr_line
		(start 374.28805 -232.332276)
		(end 375.22785 -233.952288)
		(stroke
			(width 0.254)
			(type default)
		)
		(layer "In9.Cu")
	)
	(gr_line
		(start 374.28805 -230.712264)
		(end 374.75795 -231.52227)
		(stroke
			(width 0.254)
			(type default)
		)
		(layer "In9.Cu")
	)
	(gr_line
		(start 374.28805 -229.092252)
		(end 374.75795 -229.902258)
		(stroke
			(width 0.254)
			(type default)
		)
		(layer "In9.Cu")
	)
	(gr_line
		(start 374.588532 -288.668714)
		(end 375.528586 -287.048702)
		(stroke
			(width 0.254)
			(type default)
		)
		(layer "In9.Cu")
	)
	(gr_line
		(start 374.588532 -285.42869)
		(end 375.528586 -283.808678)
		(stroke
			(width 0.254)
			(type default)
		)
		(layer "In9.Cu")
	)
	(gr_line
		(start 374.588532 -282.188666)
		(end 375.058432 -281.37866)
		(stroke
			(width 0.254)
			(type default)
		)
		(layer "In9.Cu")
	)
	(gr_line
		(start 374.588532 -277.32863)
		(end 375.528586 -275.708618)
		(stroke
			(width 0.254)
			(type default)
		)
		(layer "In9.Cu")
	)
	(gr_line
		(start 374.588532 -274.088606)
		(end 375.528586 -272.468594)
		(stroke
			(width 0.254)
			(type default)
		)
		(layer "In9.Cu")
	)
	(gr_line
		(start 374.588532 -270.848582)
		(end 375.528586 -269.22857)
		(stroke
			(width 0.254)
			(type default)
		)
		(layer "In9.Cu")
	)
	(gr_line
		(start 374.75795 -236.382306)
		(end 373.817896 -238.002318)
		(stroke
			(width 0.254)
			(type default)
		)
		(layer "In9.Cu")
	)
	(gr_line
		(start 374.75795 -231.52227)
		(end 374.28805 -232.332276)
		(stroke
			(width 0.254)
			(type default)
		)
		(layer "In9.Cu")
	)
	(gr_line
		(start 374.75795 -229.902258)
		(end 374.28805 -230.712264)
		(stroke
			(width 0.254)
			(type default)
		)
		(layer "In9.Cu")
	)
	(gr_line
		(start 374.75795 -228.282246)
		(end 374.28805 -229.092252)
		(stroke
			(width 0.254)
			(type default)
		)
		(layer "In9.Cu")
	)
	(gr_line
		(start 375.057924 -263.558274)
		(end 375.528078 -262.748268)
		(stroke
			(width 0.254)
			(type default)
		)
		(layer "In9.Cu")
	)
	(gr_line
		(start 375.058432 -281.37866)
		(end 374.118378 -279.758648)
		(stroke
			(width 0.254)
			(type default)
		)
		(layer "In9.Cu")
	)
	(gr_line
		(start 375.058432 -268.418564)
		(end 374.118378 -266.798552)
		(stroke
			(width 0.254)
			(type default)
		)
		(layer "In9.Cu")
	)
	(gr_line
		(start 375.22785 -248.532396)
		(end 374.28805 -250.152408)
		(stroke
			(width 0.254)
			(type default)
		)
		(layer "In9.Cu")
	)
	(gr_line
		(start 375.22785 -245.292372)
		(end 374.28805 -246.912384)
		(stroke
			(width 0.254)
			(type default)
		)
		(layer "In9.Cu")
	)
	(gr_line
		(start 375.22785 -242.052348)
		(end 374.28805 -243.67236)
		(stroke
			(width 0.254)
			(type default)
		)
		(layer "In9.Cu")
	)
	(gr_line
		(start 375.22785 -238.812324)
		(end 374.28805 -240.432336)
		(stroke
			(width 0.254)
			(type default)
		)
		(layer "In9.Cu")
	)
	(gr_line
		(start 375.22785 -233.952288)
		(end 374.28805 -235.5723)
		(stroke
			(width 0.254)
			(type default)
		)
		(layer "In9.Cu")
	)
	(gr_line
		(start 375.528078 -262.748268)
		(end 378.347986 -262.748268)
		(stroke
			(width 0.254)
			(type default)
		)
		(layer "In9.Cu")
	)
	(gr_line
		(start 375.528586 -290.288726)
		(end 374.588532 -288.668714)
		(stroke
			(width 0.254)
			(type default)
		)
		(layer "In9.Cu")
	)
	(gr_line
		(start 375.528586 -290.288726)
		(end 377.40844 -293.528496)
		(stroke
			(width 0.254)
			(type default)
		)
		(layer "In9.Cu")
	)
	(gr_line
		(start 375.528586 -287.048702)
		(end 374.588532 -285.42869)
		(stroke
			(width 0.254)
			(type default)
		)
		(layer "In9.Cu")
	)
	(gr_line
		(start 375.528586 -283.808678)
		(end 374.588532 -282.188666)
		(stroke
			(width 0.254)
			(type default)
		)
		(layer "In9.Cu")
	)
	(gr_line
		(start 375.528586 -278.948642)
		(end 374.588532 -277.32863)
		(stroke
			(width 0.254)
			(type default)
		)
		(layer "In9.Cu")
	)
	(gr_line
		(start 375.528586 -275.708618)
		(end 374.588532 -274.088606)
		(stroke
			(width 0.254)
			(type default)
		)
		(layer "In9.Cu")
	)
	(gr_line
		(start 375.528586 -272.468594)
		(end 374.588532 -270.848582)
		(stroke
			(width 0.254)
			(type default)
		)
		(layer "In9.Cu")
	)
	(gr_line
		(start 375.528586 -269.22857)
		(end 375.058432 -268.418564)
		(stroke
			(width 0.254)
			(type default)
		)
		(layer "In9.Cu")
	)
	(gr_line
		(start 375.76506 -166.207186)
		(end 372.847616 -163.289742)
		(stroke
			(width 0.508)
			(type default)
		)
		(layer "In9.Cu")
	)
	(gr_line
		(start 376.638058 -228.282246)
		(end 374.75795 -228.282246)
		(stroke
			(width 0.254)
			(type default)
		)
		(layer "In9.Cu")
	)
	(gr_line
		(start 376.818906 -392.114278)
		(end 366.773206 -392.114278)
		(stroke
			(width 0.508)
			(type default)
		)
		(layer "In9.Cu")
	)
	(gr_line
		(start 377.18365 -396.17015)
		(end 377.18365 -392.479022)
		(stroke
			(width 0.508)
			(type default)
		)
		(layer "In9.Cu")
	)
	(gr_line
		(start 377.18365 -392.479022)
		(end 376.818906 -392.114278)
		(stroke
			(width 0.508)
			(type default)
		)
		(layer "In9.Cu")
	)
	(gr_line
		(start 377.18365 -392.479022)
		(end 377.255786 -392.479022)
		(stroke
			(width 0.508)
			(type default)
		)
		(layer "In9.Cu")
	)
	(gr_line
		(start 377.255786 -392.479022)
		(end 377.820428 -391.91438)
		(stroke
			(width 0.508)
			(type default)
		)
		(layer "In9.Cu")
	)
	(gr_circle
		(center 377.367038 -180.678074)
		(end 378.256038 -180.678074)
		(stroke
			(width 0.2)
			(type default)
		)
		(fill no)
		(layer "In9.Cu")
	)
	(gr_circle
		(center 377.367038 -179.941474)
		(end 378.256038 -179.941474)
		(stroke
			(width 0.2)
			(type default)
		)
		(fill no)
		(layer "In9.Cu")
	)
	(gr_circle
		(center 377.367038 -179.204874)
		(end 378.256038 -179.204874)
		(stroke
			(width 0.2)
			(type default)
		)
		(fill no)
		(layer "In9.Cu")
	)
	(gr_line
		(start 377.40844 -293.528496)
		(end 378.348494 -293.528496)
		(stroke
			(width 0.254)
			(type default)
		)
		(layer "In9.Cu")
	)
	(gr_line
		(start 377.666504 -396.653004)
		(end 377.18365 -396.17015)
		(stroke
			(width 0.508)
			(type default)
		)
		(layer "In9.Cu")
	)
	(gr_line
		(start 377.820428 -391.91438)
		(end 392.713464 -391.91438)
		(stroke
			(width 0.508)
			(type default)
		)
		(layer "In9.Cu")
	)
	(gr_circle
		(center 377.869958 -162.59683)
		(end 379.266958 -162.59683)
		(stroke
			(width 0.2)
			(type default)
		)
		(fill no)
		(layer "In9.Cu")
	)
	(gr_circle
		(center 377.900438 -179.560474)
		(end 378.789438 -179.560474)
		(stroke
			(width 0.2)
			(type default)
		)
		(fill no)
		(layer "In9.Cu")
	)
	(gr_circle
		(center 377.925838 -180.322474)
		(end 378.814838 -180.322474)
		(stroke
			(width 0.2)
			(type default)
		)
		(fill no)
		(layer "In9.Cu")
	)
	(gr_line
		(start 378.347986 -262.748268)
		(end 379.75794 -263.558274)
		(stroke
			(width 0.254)
			(type default)
		)
		(layer "In9.Cu")
	)
	(gr_line
		(start 378.348494 -293.528496)
		(end 379.288548 -295.148508)
		(stroke
			(width 0.254)
			(type default)
		)
		(layer "In9.Cu")
	)
	(gr_circle
		(center 378.450602 -179.883054)
		(end 379.339602 -179.883054)
		(stroke
			(width 0.2)
			(type default)
		)
		(fill no)
		(layer "In9.Cu")
	)
	(gr_circle
		(center 378.450602 -179.146454)
		(end 379.339602 -179.146454)
		(stroke
			(width 0.2)
			(type default)
		)
		(fill no)
		(layer "In9.Cu")
	)
	(gr_circle
		(center 379.035056 -182.230776)
		(end 379.924056 -182.230776)
		(stroke
			(width 0.2)
			(type default)
		)
		(fill no)
		(layer "In9.Cu")
	)
	(gr_circle
		(center 379.035056 -181.494176)
		(end 379.924056 -181.494176)
		(stroke
			(width 0.2)
			(type default)
		)
		(fill no)
		(layer "In9.Cu")
	)
	(gr_circle
		(center 379.152658 -180.755544)
		(end 380.032768 -180.755544)
		(stroke
			(width 0.2)
			(type default)
		)
		(fill no)
		(layer "In9.Cu")
	)
	(gr_line
		(start 379.171962 -327.600818)
		(end 379.758702 -327.014078)
		(stroke
			(width 0.508)
			(type default)
		)
		(layer "In9.Cu")
	)
	(gr_line
		(start 379.288548 -295.148508)
		(end 379.758702 -295.958514)
		(stroke
			(width 0.254)
			(type default)
		)
		(layer "In9.Cu")
	)
	(gr_line
		(start 379.75794 -263.558274)
		(end 384.457956 -263.558274)
		(stroke
			(width 0.254)
			(type default)
		)
		(layer "In9.Cu")
	)
	(gr_line
		(start 379.758702 -327.600818)
		(end 379.171962 -327.600818)
		(stroke
			(width 0.508)
			(type default)
		)
		(layer "In9.Cu")
	)
	(gr_line
		(start 379.758702 -327.600818)
		(end 379.758702 -308.980078)
		(stroke
			(width 0.508)
			(type default)
		)
		(layer "In9.Cu")
	)
	(gr_line
		(start 379.758702 -295.958514)
		(end 379.758702 -308.980078)
		(stroke
			(width 0.508)
			(type default)
		)
		(layer "In9.Cu")
	)
	(gr_circle
		(center 379.769878 -180.755544)
		(end 380.649988 -180.755544)
		(stroke
			(width 0.2)
			(type default)
		)
		(fill no)
		(layer "In9.Cu")
	)
	(gr_circle
		(center 380.387098 -180.755544)
		(end 381.267208 -180.755544)
		(stroke
			(width 0.2)
			(type default)
		)
		(fill no)
		(layer "In9.Cu")
	)
	(gr_line
		(start 380.39802 -221.802452)
		(end 376.638058 -228.282246)
		(stroke
			(width 0.254)
			(type default)
		)
		(layer "In9.Cu")
	)
	(gr_line
		(start 380.39802 -221.080076)
		(end 380.39802 -221.802452)
		(stroke
			(width 0.508)
			(type default)
		)
		(layer "In9.Cu")
	)
	(gr_line
		(start 380.481332 -396.653004)
		(end 377.666504 -396.653004)
		(stroke
			(width 0.508)
			(type default)
		)
		(layer "In9.Cu")
	)
	(gr_line
		(start 380.716282 -158.818326)
		(end 388.272528 -151.26208)
		(stroke
			(width 0.508)
			(type default)
		)
		(layer "In9.Cu")
	)
	(gr_line
		(start 382.124458 -395.009878)
		(end 380.481332 -396.653004)
		(stroke
			(width 0.508)
			(type default)
		)
		(layer "In9.Cu")
	)
	(gr_line
		(start 382.524 -54.701948)
		(end 254.127 -54.701948)
		(stroke
			(width 0.508)
			(type default)
		)
		(layer "In9.Cu")
	)
	(gr_line
		(start 382.94056 -395.009878)
		(end 382.124458 -395.009878)
		(stroke
			(width 0.508)
			(type default)
		)
		(layer "In9.Cu")
	)
	(gr_line
		(start 384.32613 -396.395448)
		(end 382.94056 -395.009878)
		(stroke
			(width 0.508)
			(type default)
		)
		(layer "In9.Cu")
	)
	(gr_line
		(start 384.457956 -263.558274)
		(end 384.92811 -264.36828)
		(stroke
			(width 0.254)
			(type default)
		)
		(layer "In9.Cu")
	)
	(gr_line
		(start 384.92811 -264.36828)
		(end 389.627872 -264.36828)
		(stroke
			(width 0.254)
			(type default)
		)
		(layer "In9.Cu")
	)
	(gr_arc
		(start 385.601972 -11.780012)
		(mid 387.016183 -11.194227)
		(end 387.601968 -9.780016)
		(stroke
			(width 3.048)
			(type default)
		)
		(layer "In9.Cu")
	)
	(gr_circle
		(center 385.698238 -180.678074)
		(end 386.587238 -180.678074)
		(stroke
			(width 0.2)
			(type default)
		)
		(fill no)
		(layer "In9.Cu")
	)
	(gr_circle
		(center 385.698238 -179.941474)
		(end 386.587238 -179.941474)
		(stroke
			(width 0.2)
			(type default)
		)
		(fill no)
		(layer "In9.Cu")
	)
	(gr_circle
		(center 385.698238 -179.204874)
		(end 386.587238 -179.204874)
		(stroke
			(width 0.2)
			(type default)
		)
		(fill no)
		(layer "In9.Cu")
	)
	(gr_circle
		(center 386.231638 -179.560474)
		(end 387.120638 -179.560474)
		(stroke
			(width 0.2)
			(type default)
		)
		(fill no)
		(layer "In9.Cu")
	)
	(gr_circle
		(center 386.257038 -180.322474)
		(end 387.146038 -180.322474)
		(stroke
			(width 0.2)
			(type default)
		)
		(fill no)
		(layer "In9.Cu")
	)
	(gr_circle
		(center 386.781802 -179.883054)
		(end 387.670802 -179.883054)
		(stroke
			(width 0.2)
			(type default)
		)
		(fill no)
		(layer "In9.Cu")
	)
	(gr_circle
		(center 386.781802 -179.146454)
		(end 387.670802 -179.146454)
		(stroke
			(width 0.2)
			(type default)
		)
		(fill no)
		(layer "In9.Cu")
	)
	(gr_circle
		(center 387.206998 -162.65271)
		(end 388.603998 -162.65271)
		(stroke
			(width 0.2)
			(type default)
		)
		(fill no)
		(layer "In9.Cu")
	)
	(gr_circle
		(center 387.293358 -157.001972)
		(end 388.182358 -157.001972)
		(stroke
			(width 0.2)
			(type default)
		)
		(fill no)
		(layer "In9.Cu")
	)
	(gr_circle
		(center 387.293358 -156.366972)
		(end 388.182358 -156.366972)
		(stroke
			(width 0.2)
			(type default)
		)
		(fill no)
		(layer "In9.Cu")
	)
	(gr_circle
		(center 387.293358 -155.724352)
		(end 388.182358 -155.724352)
		(stroke
			(width 0.2)
			(type default)
		)
		(fill no)
		(layer "In9.Cu")
	)
	(gr_circle
		(center 387.293358 -155.089352)
		(end 388.182358 -155.089352)
		(stroke
			(width 0.2)
			(type default)
		)
		(fill no)
		(layer "In9.Cu")
	)
	(gr_circle
		(center 387.293358 -154.428952)
		(end 388.182358 -154.428952)
		(stroke
			(width 0.2)
			(type default)
		)
		(fill no)
		(layer "In9.Cu")
	)
	(gr_circle
		(center 387.293358 -153.793952)
		(end 388.182358 -153.793952)
		(stroke
			(width 0.2)
			(type default)
		)
		(fill no)
		(layer "In9.Cu")
	)
	(gr_circle
		(center 387.366256 -182.230776)
		(end 388.255256 -182.230776)
		(stroke
			(width 0.2)
			(type default)
		)
		(fill no)
		(layer "In9.Cu")
	)
	(gr_circle
		(center 387.366256 -181.494176)
		(end 388.255256 -181.494176)
		(stroke
			(width 0.2)
			(type default)
		)
		(fill no)
		(layer "In9.Cu")
	)
	(gr_circle
		(center 387.483858 -180.755544)
		(end 388.363968 -180.755544)
		(stroke
			(width 0.2)
			(type default)
		)
		(fill no)
		(layer "In9.Cu")
	)
	(gr_line
		(start 387.601968 -9.780016)
		(end 387.601968 -0.500126)
		(stroke
			(width 3.048)
			(type default)
		)
		(layer "In9.Cu")
	)
	(gr_circle
		(center 387.928358 -157.001972)
		(end 388.817358 -157.001972)
		(stroke
			(width 0.2)
			(type default)
		)
		(fill no)
		(layer "In9.Cu")
	)
	(gr_circle
		(center 387.928358 -156.366972)
		(end 388.817358 -156.366972)
		(stroke
			(width 0.2)
			(type default)
		)
		(fill no)
		(layer "In9.Cu")
	)
	(gr_circle
		(center 387.928358 -155.724352)
		(end 388.817358 -155.724352)
		(stroke
			(width 0.2)
			(type default)
		)
		(fill no)
		(layer "In9.Cu")
	)
	(gr_circle
		(center 387.928358 -155.089352)
		(end 388.817358 -155.089352)
		(stroke
			(width 0.2)
			(type default)
		)
		(fill no)
		(layer "In9.Cu")
	)
	(gr_circle
		(center 387.928358 -154.428952)
		(end 388.817358 -154.428952)
		(stroke
			(width 0.2)
			(type default)
		)
		(fill no)
		(layer "In9.Cu")
	)
	(gr_circle
		(center 387.928358 -153.793952)
		(end 388.817358 -153.793952)
		(stroke
			(width 0.2)
			(type default)
		)
		(fill no)
		(layer "In9.Cu")
	)
	(gr_circle
		(center 388.101078 -180.755544)
		(end 388.981188 -180.755544)
		(stroke
			(width 0.2)
			(type default)
		)
		(fill no)
		(layer "In9.Cu")
	)
	(gr_arc
		(start 388.102094 0)
		(mid 387.748465 -0.146487)
		(end 387.601968 -0.500126)
		(stroke
			(width 3.048)
			(type default)
		)
		(layer "In9.Cu")
	)
	(gr_line
		(start 388.102094 0)
		(end 455.701908 0)
		(stroke
			(width 3.048)
			(type default)
		)
		(layer "In9.Cu")
	)
	(gr_line
		(start 388.272528 -151.26208)
		(end 424.666918 -151.26208)
		(stroke
			(width 0.508)
			(type default)
		)
		(layer "In9.Cu")
	)
	(gr_circle
		(center 388.718298 -180.755544)
		(end 389.598408 -180.755544)
		(stroke
			(width 0.2)
			(type default)
		)
		(fill no)
		(layer "In9.Cu")
	)
	(gr_line
		(start 388.983474 -166.207186)
		(end 375.76506 -166.207186)
		(stroke
			(width 0.508)
			(type default)
		)
		(layer "In9.Cu")
	)
	(gr_line
		(start 389.627872 -264.36828)
		(end 391.03808 -266.798298)
		(stroke
			(width 0.254)
			(type default)
		)
		(layer "In9.Cu")
	)
	(gr_line
		(start 390.285224 -338.12734)
		(end 390.99109 -338.833206)
		(stroke
			(width 0.508)
			(type default)
		)
		(layer "In9.Cu")
	)
	(gr_line
		(start 390.909302 -338.751418)
		(end 379.758702 -327.600818)
		(stroke
			(width 0.508)
			(type default)
		)
		(layer "In9.Cu")
	)
	(gr_line
		(start 391.03808 -266.798298)
		(end 393.630912 -266.798298)
		(stroke
			(width 0.254)
			(type default)
		)
		(layer "In9.Cu")
	)
	(gr_line
		(start 392.555984 -396.395448)
		(end 384.32613 -396.395448)
		(stroke
			(width 0.508)
			(type default)
		)
		(layer "In9.Cu")
	)
	(gr_line
		(start 392.713464 -391.91438)
		(end 393.057888 -392.258804)
		(stroke
			(width 0.508)
			(type default)
		)
		(layer "In9.Cu")
	)
	(gr_line
		(start 392.880088 -396.053564)
		(end 392.888978 -396.062454)
		(stroke
			(width 0.508)
			(type default)
		)
		(layer "In9.Cu")
	)
	(gr_line
		(start 392.880088 -395.12621)
		(end 392.880088 -396.053564)
		(stroke
			(width 0.508)
			(type default)
		)
		(layer "In9.Cu")
	)
	(gr_line
		(start 392.880088 -395.12621)
		(end 392.880088 -394.757402)
		(stroke
			(width 0.254)
			(type default)
		)
		(layer "In9.Cu")
	)
	(gr_line
		(start 392.880088 -394.757402)
		(end 393.057888 -394.579602)
		(stroke
			(width 0.254)
			(type default)
		)
		(layer "In9.Cu")
	)
	(gr_line
		(start 392.888978 -396.062454)
		(end 392.555984 -396.395448)
		(stroke
			(width 0.508)
			(type default)
		)
		(layer "In9.Cu")
	)
	(gr_line
		(start 393.057888 -394.579602)
		(end 393.057888 -393.057634)
		(stroke
			(width 0.254)
			(type default)
		)
		(layer "In9.Cu")
	)
	(gr_line
		(start 393.057888 -393.057634)
		(end 393.057888 -392.258804)
		(stroke
			(width 0.508)
			(type default)
		)
		(layer "In9.Cu")
	)
	(gr_line
		(start 393.24661 -193.742564)
		(end 393.638532 -193.350642)
		(stroke
			(width 0.508)
			(type default)
		)
		(layer "In9.Cu")
	)
	(gr_line
		(start 393.275058 -193.742564)
		(end 393.24661 -193.742564)
		(stroke
			(width 0.508)
			(type default)
		)
		(layer "In9.Cu")
	)
	(gr_line
		(start 393.630912 -266.798298)
		(end 439.349388 -266.798298)
		(stroke
			(width 0.508)
			(type default)
		)
		(layer "In9.Cu")
	)
	(gr_line
		(start 393.638532 -207.839564)
		(end 380.39802 -221.080076)
		(stroke
			(width 0.508)
			(type default)
		)
		(layer "In9.Cu")
	)
	(gr_line
		(start 393.638532 -194.106038)
		(end 393.275058 -193.742564)
		(stroke
			(width 0.508)
			(type default)
		)
		(layer "In9.Cu")
	)
	(gr_line
		(start 393.638532 -188.789564)
		(end 393.638532 -207.839564)
		(stroke
			(width 0.508)
			(type default)
		)
		(layer "In9.Cu")
	)
	(gr_line
		(start 394.273532 -188.154564)
		(end 393.638532 -188.789564)
		(stroke
			(width 0.508)
			(type default)
		)
		(layer "In9.Cu")
	)
	(gr_line
		(start 394.612622 -396.062454)
		(end 392.888978 -396.062454)
		(stroke
			(width 0.508)
			(type default)
		)
		(layer "In9.Cu")
	)
	(gr_circle
		(center 394.628878 -173.21911)
		(end 395.517878 -173.21911)
		(stroke
			(width 0.2)
			(type default)
		)
		(fill no)
		(layer "In9.Cu")
	)
	(gr_circle
		(center 394.628878 -172.45711)
		(end 395.517878 -172.45711)
		(stroke
			(width 0.2)
			(type default)
		)
		(fill no)
		(layer "In9.Cu")
	)
	(gr_circle
		(center 394.646658 -173.987714)
		(end 395.535658 -173.987714)
		(stroke
			(width 0.2)
			(type default)
		)
		(fill no)
		(layer "In9.Cu")
	)
	(gr_circle
		(center 394.672058 -174.749714)
		(end 395.561058 -174.749714)
		(stroke
			(width 0.2)
			(type default)
		)
		(fill no)
		(layer "In9.Cu")
	)
	(gr_circle
		(center 395.196822 -174.310294)
		(end 396.085822 -174.310294)
		(stroke
			(width 0.2)
			(type default)
		)
		(fill no)
		(layer "In9.Cu")
	)
	(gr_circle
		(center 395.196822 -173.573694)
		(end 396.085822 -173.573694)
		(stroke
			(width 0.2)
			(type default)
		)
		(fill no)
		(layer "In9.Cu")
	)
	(gr_circle
		(center 395.230858 -172.819314)
		(end 396.119858 -172.819314)
		(stroke
			(width 0.2)
			(type default)
		)
		(fill no)
		(layer "In9.Cu")
	)
	(gr_circle
		(center 395.781276 -176.657254)
		(end 396.670276 -176.657254)
		(stroke
			(width 0.2)
			(type default)
		)
		(fill no)
		(layer "In9.Cu")
	)
	(gr_circle
		(center 395.781276 -175.895254)
		(end 396.670276 -175.895254)
		(stroke
			(width 0.2)
			(type default)
		)
		(fill no)
		(layer "In9.Cu")
	)
	(gr_circle
		(center 395.898878 -175.182784)
		(end 396.778988 -175.182784)
		(stroke
			(width 0.2)
			(type default)
		)
		(fill no)
		(layer "In9.Cu")
	)
	(gr_line
		(start 396.24635 -394.428726)
		(end 394.612622 -396.062454)
		(stroke
			(width 0.508)
			(type default)
		)
		(layer "In9.Cu")
	)
	(gr_line
		(start 396.24635 -392.573764)
		(end 396.24635 -394.428726)
		(stroke
			(width 0.508)
			(type default)
		)
		(layer "In9.Cu")
	)
	(gr_circle
		(center 396.516098 -175.182784)
		(end 397.396208 -175.182784)
		(stroke
			(width 0.2)
			(type default)
		)
		(fill no)
		(layer "In9.Cu")
	)
	(gr_line
		(start 396.602712 -158.587948)
		(end 388.983474 -166.207186)
		(stroke
			(width 0.508)
			(type default)
		)
		(layer "In9.Cu")
	)
	(gr_line
		(start 397.043656 -391.776458)
		(end 396.24635 -392.573764)
		(stroke
			(width 0.508)
			(type default)
		)
		(layer "In9.Cu")
	)
	(gr_circle
		(center 397.133318 -175.182784)
		(end 398.013428 -175.182784)
		(stroke
			(width 0.2)
			(type default)
		)
		(fill no)
		(layer "In9.Cu")
	)
	(gr_circle
		(center 399.165064 -81.051146)
		(end 400.054064 -81.051146)
		(stroke
			(width 0.2)
			(type default)
		)
		(fill no)
		(layer "In9.Cu")
	)
	(gr_line
		(start 399.988532 -188.154564)
		(end 394.273532 -188.154564)
		(stroke
			(width 0.508)
			(type default)
		)
		(layer "In9.Cu")
	)
	(gr_line
		(start 401.893532 -186.249564)
		(end 399.988532 -188.154564)
		(stroke
			(width 0.508)
			(type default)
		)
		(layer "In9.Cu")
	)
	(gr_line
		(start 401.893532 -181.169564)
		(end 401.893532 -186.249564)
		(stroke
			(width 0.508)
			(type default)
		)
		(layer "In9.Cu")
	)
	(gr_circle
		(center 402.436838 -166.527988)
		(end 403.325838 -166.527988)
		(stroke
			(width 0.2)
			(type default)
		)
		(fill no)
		(layer "In9.Cu")
	)
	(gr_circle
		(center 402.436838 -165.791388)
		(end 403.325838 -165.791388)
		(stroke
			(width 0.2)
			(type default)
		)
		(fill no)
		(layer "In9.Cu")
	)
	(gr_circle
		(center 402.436838 -165.054788)
		(end 403.325838 -165.054788)
		(stroke
			(width 0.2)
			(type default)
		)
		(fill no)
		(layer "In9.Cu")
	)
	(gr_circle
		(center 402.970238 -165.410388)
		(end 403.859238 -165.410388)
		(stroke
			(width 0.2)
			(type default)
		)
		(fill no)
		(layer "In9.Cu")
	)
	(gr_circle
		(center 402.995638 -166.172388)
		(end 403.884638 -166.172388)
		(stroke
			(width 0.2)
			(type default)
		)
		(fill no)
		(layer "In9.Cu")
	)
	(gr_circle
		(center 403.520402 -165.732968)
		(end 404.409402 -165.732968)
		(stroke
			(width 0.2)
			(type default)
		)
		(fill no)
		(layer "In9.Cu")
	)
	(gr_circle
		(center 403.520402 -164.996368)
		(end 404.409402 -164.996368)
		(stroke
			(width 0.2)
			(type default)
		)
		(fill no)
		(layer "In9.Cu")
	)
	(gr_line
		(start 403.544532 -179.518564)
		(end 401.893532 -181.169564)
		(stroke
			(width 0.508)
			(type default)
		)
		(layer "In9.Cu")
	)
	(gr_circle
		(center 404.104856 -168.082214)
		(end 404.993856 -168.082214)
		(stroke
			(width 0.2)
			(type default)
		)
		(fill no)
		(layer "In9.Cu")
	)
	(gr_circle
		(center 404.104856 -167.320214)
		(end 404.993856 -167.320214)
		(stroke
			(width 0.2)
			(type default)
		)
		(fill no)
		(layer "In9.Cu")
	)
	(gr_circle
		(center 404.222458 -166.605458)
		(end 405.102568 -166.605458)
		(stroke
			(width 0.2)
			(type default)
		)
		(fill no)
		(layer "In9.Cu")
	)
	(gr_circle
		(center 404.839678 -166.605458)
		(end 405.719788 -166.605458)
		(stroke
			(width 0.2)
			(type default)
		)
		(fill no)
		(layer "In9.Cu")
	)
	(gr_circle
		(center 405.456898 -166.605458)
		(end 406.337008 -166.605458)
		(stroke
			(width 0.2)
			(type default)
		)
		(fill no)
		(layer "In9.Cu")
	)
	(gr_line
		(start 407.100532 -179.518564)
		(end 403.544532 -179.518564)
		(stroke
			(width 0.508)
			(type default)
		)
		(layer "In9.Cu")
	)
	(gr_line
		(start 407.100532 -179.518564)
		(end 411.926532 -174.692564)
		(stroke
			(width 0.508)
			(type default)
		)
		(layer "In9.Cu")
	)
	(gr_line
		(start 409.747466 -396.181834)
		(end 409.747466 -391.927588)
		(stroke
			(width 0.508)
			(type default)
		)
		(layer "In9.Cu")
	)
	(gr_line
		(start 409.747466 -391.927588)
		(end 409.734258 -391.91438)
		(stroke
			(width 0.508)
			(type default)
		)
		(layer "In9.Cu")
	)
	(gr_line
		(start 410.32176 -396.756128)
		(end 409.747466 -396.181834)
		(stroke
			(width 0.508)
			(type default)
		)
		(layer "In9.Cu")
	)
	(gr_circle
		(center 410.818838 -161.701988)
		(end 411.707838 -161.701988)
		(stroke
			(width 0.2)
			(type default)
		)
		(fill no)
		(layer "In9.Cu")
	)
	(gr_circle
		(center 410.818838 -160.965388)
		(end 411.707838 -160.965388)
		(stroke
			(width 0.2)
			(type default)
		)
		(fill no)
		(layer "In9.Cu")
	)
	(gr_circle
		(center 410.818838 -160.228788)
		(end 411.707838 -160.228788)
		(stroke
			(width 0.2)
			(type default)
		)
		(fill no)
		(layer "In9.Cu")
	)
	(gr_circle
		(center 411.352238 -160.584388)
		(end 412.241238 -160.584388)
		(stroke
			(width 0.2)
			(type default)
		)
		(fill no)
		(layer "In9.Cu")
	)
	(gr_circle
		(center 411.377638 -161.346388)
		(end 412.266638 -161.346388)
		(stroke
			(width 0.2)
			(type default)
		)
		(fill no)
		(layer "In9.Cu")
	)
	(gr_circle
		(center 411.902402 -160.906968)
		(end 412.791402 -160.906968)
		(stroke
			(width 0.2)
			(type default)
		)
		(fill no)
		(layer "In9.Cu")
	)
	(gr_circle
		(center 411.902402 -160.170368)
		(end 412.791402 -160.170368)
		(stroke
			(width 0.2)
			(type default)
		)
		(fill no)
		(layer "In9.Cu")
	)
	(gr_line
		(start 411.926532 -174.692564)
		(end 425.076366 -174.692564)
		(stroke
			(width 0.508)
			(type default)
		)
		(layer "In9.Cu")
	)
	(gr_circle
		(center 412.486856 -163.256214)
		(end 413.375856 -163.256214)
		(stroke
			(width 0.2)
			(type default)
		)
		(fill no)
		(layer "In9.Cu")
	)
	(gr_circle
		(center 412.486856 -162.494214)
		(end 413.375856 -162.494214)
		(stroke
			(width 0.2)
			(type default)
		)
		(fill no)
		(layer "In9.Cu")
	)
	(gr_circle
		(center 412.604458 -161.779458)
		(end 413.484568 -161.779458)
		(stroke
			(width 0.2)
			(type default)
		)
		(fill no)
		(layer "In9.Cu")
	)
	(gr_line
		(start 413.068262 -396.756128)
		(end 410.32176 -396.756128)
		(stroke
			(width 0.508)
			(type default)
		)
		(layer "In9.Cu")
	)
	(gr_circle
		(center 413.221678 -161.779458)
		(end 414.101788 -161.779458)
		(stroke
			(width 0.2)
			(type default)
		)
		(fill no)
		(layer "In9.Cu")
	)
	(gr_line
		(start 413.300418 -338.833206)
		(end 390.99109 -338.833206)
		(stroke
			(width 0.508)
			(type default)
		)
		(layer "In9.Cu")
	)
	(gr_circle
		(center 413.838898 -161.779458)
		(end 414.719008 -161.779458)
		(stroke
			(width 0.2)
			(type default)
		)
		(fill no)
		(layer "In9.Cu")
	)
	(gr_line
		(start 414.906714 -394.917676)
		(end 413.068262 -396.756128)
		(stroke
			(width 0.508)
			(type default)
		)
		(layer "In9.Cu")
	)
	(gr_line
		(start 415.458402 -394.917676)
		(end 414.906714 -394.917676)
		(stroke
			(width 0.508)
			(type default)
		)
		(layer "In9.Cu")
	)
	(gr_line
		(start 416.31235 -341.845138)
		(end 413.300418 -338.833206)
		(stroke
			(width 0.508)
			(type default)
		)
		(layer "In9.Cu")
	)
	(gr_line
		(start 416.774376 -396.38986)
		(end 416.774376 -396.23365)
		(stroke
			(width 0.508)
			(type default)
		)
		(layer "In9.Cu")
	)
	(gr_line
		(start 416.774376 -396.23365)
		(end 415.458402 -394.917676)
		(stroke
			(width 0.508)
			(type default)
		)
		(layer "In9.Cu")
	)
	(gr_line
		(start 417.576 -158.587948)
		(end 396.602712 -158.587948)
		(stroke
			(width 0.508)
			(type default)
		)
		(layer "In9.Cu")
	)
	(gr_line
		(start 418.096446 -174.692564)
		(end 418.211 -174.57801)
		(stroke
			(width 0.508)
			(type default)
		)
		(layer "In9.Cu")
	)
	(gr_line
		(start 418.211 -174.57801)
		(end 418.211 -159.222948)
		(stroke
			(width 0.508)
			(type default)
		)
		(layer "In9.Cu")
	)
	(gr_line
		(start 418.211 -159.222948)
		(end 417.576 -158.587948)
		(stroke
			(width 0.508)
			(type default)
		)
		(layer "In9.Cu")
	)
	(gr_line
		(start 420.975028 -396.38986)
		(end 416.774376 -396.38986)
		(stroke
			(width 0.508)
			(type default)
		)
		(layer "In9.Cu")
	)
	(gr_line
		(start 422.306496 -397.721328)
		(end 420.975028 -396.38986)
		(stroke
			(width 0.508)
			(type default)
		)
		(layer "In9.Cu")
	)
	(gr_circle
		(center 424.33494 -353.10318)
		(end 425.21505 -353.10318)
		(stroke
			(width 0.2)
			(type default)
		)
		(fill no)
		(layer "In9.Cu")
	)
	(gr_line
		(start 424.666918 -151.26208)
		(end 455.919586 -182.514748)
		(stroke
			(width 0.508)
			(type default)
		)
		(layer "In9.Cu")
	)
	(gr_line
		(start 424.788584 -397.721328)
		(end 422.306496 -397.721328)
		(stroke
			(width 0.508)
			(type default)
		)
		(layer "In9.Cu")
	)
	(gr_line
		(start 424.788584 -397.721328)
		(end 425.569888 -396.940024)
		(stroke
			(width 0.508)
			(type default)
		)
		(layer "In9.Cu")
	)
	(gr_circle
		(center 424.95216 -353.10318)
		(end 425.83227 -353.10318)
		(stroke
			(width 0.2)
			(type default)
		)
		(fill no)
		(layer "In9.Cu")
	)
	(gr_line
		(start 425.075604 -391.776458)
		(end 397.043656 -391.776458)
		(stroke
			(width 0.508)
			(type default)
		)
		(layer "In9.Cu")
	)
	(gr_line
		(start 425.076366 -174.692564)
		(end 425.797218 -175.413416)
		(stroke
			(width 0.508)
			(type default)
		)
		(layer "In9.Cu")
	)
	(gr_line
		(start 425.289218 -266.745466)
		(end 425.746418 -266.288266)
		(stroke
			(width 0.508)
			(type default)
		)
		(layer "In9.Cu")
	)
	(gr_circle
		(center 425.56938 -353.10318)
		(end 426.44949 -353.10318)
		(stroke
			(width 0.2)
			(type default)
		)
		(fill no)
		(layer "In9.Cu")
	)
	(gr_line
		(start 425.569888 -396.940024)
		(end 426.371766 -397.741902)
		(stroke
			(width 0.508)
			(type default)
		)
		(layer "In9.Cu")
	)
	(gr_line
		(start 425.569888 -396.756382)
		(end 425.569888 -396.940024)
		(stroke
			(width 0.508)
			(type default)
		)
		(layer "In9.Cu")
	)
	(gr_line
		(start 425.569888 -396.756382)
		(end 425.569888 -392.270742)
		(stroke
			(width 0.508)
			(type default)
		)
		(layer "In9.Cu")
	)
	(gr_line
		(start 425.569888 -392.270742)
		(end 425.075604 -391.776458)
		(stroke
			(width 0.508)
			(type default)
		)
		(layer "In9.Cu")
	)
	(gr_circle
		(center 425.686474 -352.35769)
		(end 426.575474 -352.35769)
		(stroke
			(width 0.2)
			(type default)
		)
		(fill no)
		(layer "In9.Cu")
	)
	(gr_circle
		(center 425.686474 -351.62109)
		(end 426.575474 -351.62109)
		(stroke
			(width 0.2)
			(type default)
		)
		(fill no)
		(layer "In9.Cu")
	)
	(gr_line
		(start 425.746418 -266.288266)
		(end 425.746418 -191.078866)
		(stroke
			(width 0.508)
			(type default)
		)
		(layer "In9.Cu")
	)
	(gr_line
		(start 425.797218 -191.028066)
		(end 425.746418 -191.078866)
		(stroke
			(width 0.508)
			(type default)
		)
		(layer "In9.Cu")
	)
	(gr_line
		(start 425.797218 -175.413416)
		(end 425.797218 -191.028066)
		(stroke
			(width 0.508)
			(type default)
		)
		(layer "In9.Cu")
	)
	(gr_line
		(start 426.053504 -195.653406)
		(end 425.797218 -195.39712)
		(stroke
			(width 0.508)
			(type default)
		)
		(layer "In9.Cu")
	)
	(gr_line
		(start 426.178726 -195.653406)
		(end 425.86402 -195.968112)
		(stroke
			(width 0.508)
			(type default)
		)
		(layer "In9.Cu")
	)
	(gr_line
		(start 426.178726 -195.653406)
		(end 426.053504 -195.653406)
		(stroke
			(width 0.508)
			(type default)
		)
		(layer "In9.Cu")
	)
	(gr_line
		(start 426.197776 -375.175272)
		(end 289.691318 -375.175272)
		(stroke
			(width 0.508)
			(type default)
		)
		(layer "In9.Cu")
	)
	(gr_circle
		(center 426.271436 -354.71227)
		(end 427.160436 -354.71227)
		(stroke
			(width 0.2)
			(type default)
		)
		(fill no)
		(layer "In9.Cu")
	)
	(gr_circle
		(center 426.271436 -353.97567)
		(end 427.160436 -353.97567)
		(stroke
			(width 0.2)
			(type default)
		)
		(fill no)
		(layer "In9.Cu")
	)
	(gr_line
		(start 426.371766 -397.741902)
		(end 429.29937 -397.741902)
		(stroke
			(width 0.508)
			(type default)
		)
		(layer "In9.Cu")
	)
	(gr_circle
		(center 426.7962 -353.53625)
		(end 427.6852 -353.53625)
		(stroke
			(width 0.2)
			(type default)
		)
		(fill no)
		(layer "In9.Cu")
	)
	(gr_circle
		(center 426.8216 -354.29825)
		(end 427.7106 -354.29825)
		(stroke
			(width 0.2)
			(type default)
		)
		(fill no)
		(layer "In9.Cu")
	)
	(gr_circle
		(center 426.99559 -413.174688)
		(end 429.15459 -413.174688)
		(stroke
			(width 4.318)
			(type default)
		)
		(fill no)
		(layer "In9.Cu")
	)
	(gr_circle
		(center 427.355 -354.65385)
		(end 428.244 -354.65385)
		(stroke
			(width 0.2)
			(type default)
		)
		(fill no)
		(layer "In9.Cu")
	)
	(gr_circle
		(center 427.355 -353.91725)
		(end 428.244 -353.91725)
		(stroke
			(width 0.2)
			(type default)
		)
		(fill no)
		(layer "In9.Cu")
	)
	(gr_circle
		(center 427.355 -353.18065)
		(end 428.244 -353.18065)
		(stroke
			(width 0.2)
			(type default)
		)
		(fill no)
		(layer "In9.Cu")
	)
	(gr_line
		(start 429.29937 -397.741902)
		(end 430.05756 -396.983712)
		(stroke
			(width 0.508)
			(type default)
		)
		(layer "In9.Cu")
	)
	(gr_line
		(start 430.05756 -396.983712)
		(end 430.05756 -386.633212)
		(stroke
			(width 0.508)
			(type default)
		)
		(layer "In9.Cu")
	)
	(gr_line
		(start 430.05756 -386.633212)
		(end 435.651148 -381.039624)
		(stroke
			(width 0.508)
			(type default)
		)
		(layer "In9.Cu")
	)
	(gr_circle
		(center 432.01336 -361.827826)
		(end 433.41036 -361.827826)
		(stroke
			(width 0.2)
			(type default)
		)
		(fill no)
		(layer "In9.Cu")
	)
	(gr_line
		(start 432.062128 -381.039624)
		(end 426.197776 -375.175272)
		(stroke
			(width 0.508)
			(type default)
		)
		(layer "In9.Cu")
	)
	(gr_circle
		(center 432.661568 -353.12858)
		(end 433.541678 -353.12858)
		(stroke
			(width 0.2)
			(type default)
		)
		(fill no)
		(layer "In9.Cu")
	)
	(gr_circle
		(center 433.278788 -353.12858)
		(end 434.158898 -353.12858)
		(stroke
			(width 0.2)
			(type default)
		)
		(fill no)
		(layer "In9.Cu")
	)
	(gr_circle
		(center 433.49545 -384.87858)
		(end 435.65445 -384.87858)
		(stroke
			(width 4.318)
			(type default)
		)
		(fill no)
		(layer "In9.Cu")
	)
	(gr_circle
		(center 433.896008 -353.12858)
		(end 434.776118 -353.12858)
		(stroke
			(width 0.2)
			(type default)
		)
		(fill no)
		(layer "In9.Cu")
	)
	(gr_circle
		(center 434.013102 -352.38309)
		(end 434.902102 -352.38309)
		(stroke
			(width 0.2)
			(type default)
		)
		(fill no)
		(layer "In9.Cu")
	)
	(gr_circle
		(center 434.013102 -351.64649)
		(end 434.902102 -351.64649)
		(stroke
			(width 0.2)
			(type default)
		)
		(fill no)
		(layer "In9.Cu")
	)
	(gr_circle
		(center 434.598064 -354.73767)
		(end 435.487064 -354.73767)
		(stroke
			(width 0.2)
			(type default)
		)
		(fill no)
		(layer "In9.Cu")
	)
	(gr_circle
		(center 434.598064 -354.00107)
		(end 435.487064 -354.00107)
		(stroke
			(width 0.2)
			(type default)
		)
		(fill no)
		(layer "In9.Cu")
	)
	(gr_circle
		(center 435.122828 -353.56165)
		(end 436.011828 -353.56165)
		(stroke
			(width 0.2)
			(type default)
		)
		(fill no)
		(layer "In9.Cu")
	)
	(gr_circle
		(center 435.148228 -354.32365)
		(end 436.037228 -354.32365)
		(stroke
			(width 0.2)
			(type default)
		)
		(fill no)
		(layer "In9.Cu")
	)
	(gr_line
		(start 435.405022 -422.122092)
		(end 299.426122 -422.122092)
		(stroke
			(width 0.508)
			(type default)
		)
		(layer "In9.Cu")
	)
	(gr_circle
		(center 435.469538 -361.496102)
		(end 436.358538 -361.496102)
		(stroke
			(width 0.2)
			(type default)
		)
		(fill no)
		(layer "In9.Cu")
	)
	(gr_circle
		(center 435.469538 -360.734102)
		(end 436.358538 -360.734102)
		(stroke
			(width 0.2)
			(type default)
		)
		(fill no)
		(layer "In9.Cu")
	)
	(gr_circle
		(center 435.469538 -359.972102)
		(end 436.358538 -359.972102)
		(stroke
			(width 0.2)
			(type default)
		)
		(fill no)
		(layer "In9.Cu")
	)
	(gr_line
		(start 435.651148 -381.039624)
		(end 432.062128 -381.039624)
		(stroke
			(width 0.508)
			(type default)
		)
		(layer "In9.Cu")
	)
	(gr_line
		(start 435.651148 -381.039624)
		(end 464.385152 -381.039624)
		(stroke
			(width 0.508)
			(type default)
		)
		(layer "In9.Cu")
	)
	(gr_circle
		(center 435.681628 -354.67925)
		(end 436.570628 -354.67925)
		(stroke
			(width 0.2)
			(type default)
		)
		(fill no)
		(layer "In9.Cu")
	)
	(gr_circle
		(center 435.681628 -353.94265)
		(end 436.570628 -353.94265)
		(stroke
			(width 0.2)
			(type default)
		)
		(fill no)
		(layer "In9.Cu")
	)
	(gr_circle
		(center 435.681628 -353.20605)
		(end 436.570628 -353.20605)
		(stroke
			(width 0.2)
			(type default)
		)
		(fill no)
		(layer "In9.Cu")
	)
	(gr_circle
		(center 436.231538 -361.496102)
		(end 437.120538 -361.496102)
		(stroke
			(width 0.2)
			(type default)
		)
		(fill no)
		(layer "In9.Cu")
	)
	(gr_circle
		(center 436.231538 -360.734102)
		(end 437.120538 -360.734102)
		(stroke
			(width 0.2)
			(type default)
		)
		(fill no)
		(layer "In9.Cu")
	)
	(gr_circle
		(center 436.231538 -359.972102)
		(end 437.120538 -359.972102)
		(stroke
			(width 0.2)
			(type default)
		)
		(fill no)
		(layer "In9.Cu")
	)
	(gr_circle
		(center 437.703214 -12.400788)
		(end 438.592214 -12.400788)
		(stroke
			(width 0.2)
			(type default)
		)
		(fill no)
		(layer "In9.Cu")
	)
	(gr_circle
		(center 438.06999 -13.069316)
		(end 438.95899 -13.069316)
		(stroke
			(width 0.2)
			(type default)
		)
		(fill no)
		(layer "In9.Cu")
	)
	(gr_circle
		(center 438.592214 -12.400788)
		(end 439.481214 -12.400788)
		(stroke
			(width 0.2)
			(type default)
		)
		(fill no)
		(layer "In9.Cu")
	)
	(gr_circle
		(center 438.71515 -13.061696)
		(end 439.60415 -13.061696)
		(stroke
			(width 0.2)
			(type default)
		)
		(fill no)
		(layer "In9.Cu")
	)
	(gr_line
		(start 439.349388 -266.798298)
		(end 440.841638 -268.290548)
		(stroke
			(width 0.508)
			(type default)
		)
		(layer "In9.Cu")
	)
	(gr_line
		(start 439.349642 -341.845138)
		(end 416.31235 -341.845138)
		(stroke
			(width 0.508)
			(type default)
		)
		(layer "In9.Cu")
	)
	(gr_line
		(start 439.349642 -341.845138)
		(end 440.841638 -340.353142)
		(stroke
			(width 0.508)
			(type default)
		)
		(layer "In9.Cu")
	)
	(gr_line
		(start 439.349642 -266.798552)
		(end 393.63142 -266.798552)
		(stroke
			(width 0.508)
			(type default)
		)
		(layer "In9.Cu")
	)
	(gr_circle
		(center 439.39333 -13.043916)
		(end 440.28233 -13.043916)
		(stroke
			(width 0.2)
			(type default)
		)
		(fill no)
		(layer "In9.Cu")
	)
	(gr_circle
		(center 439.481214 -12.400788)
		(end 440.370214 -12.400788)
		(stroke
			(width 0.2)
			(type default)
		)
		(fill no)
		(layer "In9.Cu")
	)
	(gr_line
		(start 439.674 -356.199948)
		(end 273.05 -356.199948)
		(stroke
			(width 0.508)
			(type default)
		)
		(layer "In9.Cu")
	)
	(gr_line
		(start 440.841638 -355.03231)
		(end 439.674 -356.199948)
		(stroke
			(width 0.508)
			(type default)
		)
		(layer "In9.Cu")
	)
	(gr_line
		(start 440.841638 -268.290548)
		(end 440.841638 -355.03231)
		(stroke
			(width 0.508)
			(type default)
		)
		(layer "In9.Cu")
	)
	(gr_circle
		(center 440.945524 -11.261852)
		(end 441.834524 -11.261852)
		(stroke
			(width 0.2)
			(type default)
		)
		(fill no)
		(layer "In9.Cu")
	)
	(gr_circle
		(center 440.945524 -10.626852)
		(end 441.834524 -10.626852)
		(stroke
			(width 0.2)
			(type default)
		)
		(fill no)
		(layer "In9.Cu")
	)
	(gr_circle
		(center 441.129674 -25.982422)
		(end 442.018674 -25.982422)
		(stroke
			(width 0.2)
			(type default)
		)
		(fill no)
		(layer "In9.Cu")
	)
	(gr_circle
		(center 441.354718 -20.73656)
		(end 442.243718 -20.73656)
		(stroke
			(width 0.2)
			(type default)
		)
		(fill no)
		(layer "In9.Cu")
	)
	(gr_circle
		(center 441.354718 -20.10156)
		(end 442.243718 -20.10156)
		(stroke
			(width 0.2)
			(type default)
		)
		(fill no)
		(layer "In9.Cu")
	)
	(gr_circle
		(center 441.354718 -19.21256)
		(end 442.243718 -19.21256)
		(stroke
			(width 0.2)
			(type default)
		)
		(fill no)
		(layer "In9.Cu")
	)
	(gr_circle
		(center 441.354718 -18.57756)
		(end 442.243718 -18.57756)
		(stroke
			(width 0.2)
			(type default)
		)
		(fill no)
		(layer "In9.Cu")
	)
	(gr_circle
		(center 441.475622 -14.123162)
		(end 442.364622 -14.123162)
		(stroke
			(width 0.2)
			(type default)
		)
		(fill no)
		(layer "In9.Cu")
	)
	(gr_circle
		(center 441.475622 -13.488162)
		(end 442.364622 -13.488162)
		(stroke
			(width 0.2)
			(type default)
		)
		(fill no)
		(layer "In9.Cu")
	)
	(gr_circle
		(center 441.56249 -25.461976)
		(end 442.45149 -25.461976)
		(stroke
			(width 0.2)
			(type default)
		)
		(fill no)
		(layer "In9.Cu")
	)
	(gr_circle
		(center 442.018674 -25.982422)
		(end 442.907674 -25.982422)
		(stroke
			(width 0.2)
			(type default)
		)
		(fill no)
		(layer "In9.Cu")
	)
	(gr_circle
		(center 442.371734 -20.983702)
		(end 443.260734 -20.983702)
		(stroke
			(width 0.2)
			(type default)
		)
		(fill no)
		(layer "In9.Cu")
	)
	(gr_circle
		(center 442.371734 -20.348702)
		(end 443.260734 -20.348702)
		(stroke
			(width 0.2)
			(type default)
		)
		(fill no)
		(layer "In9.Cu")
	)
	(gr_circle
		(center 442.371734 -19.459702)
		(end 443.260734 -19.459702)
		(stroke
			(width 0.2)
			(type default)
		)
		(fill no)
		(layer "In9.Cu")
	)
	(gr_circle
		(center 442.371734 -18.824702)
		(end 443.260734 -18.824702)
		(stroke
			(width 0.2)
			(type default)
		)
		(fill no)
		(layer "In9.Cu")
	)
	(gr_circle
		(center 442.45149 -25.461976)
		(end 443.34049 -25.461976)
		(stroke
			(width 0.2)
			(type default)
		)
		(fill no)
		(layer "In9.Cu")
	)
	(gr_line
		(start 442.612526 -54.701948)
		(end 382.524 -54.701948)
		(stroke
			(width 0.508)
			(type default)
		)
		(layer "In9.Cu")
	)
	(gr_circle
		(center 442.907674 -25.982422)
		(end 443.796674 -25.982422)
		(stroke
			(width 0.2)
			(type default)
		)
		(fill no)
		(layer "In9.Cu")
	)
	(gr_circle
		(center 443.34049 -25.461976)
		(end 444.22949 -25.461976)
		(stroke
			(width 0.2)
			(type default)
		)
		(fill no)
		(layer "In9.Cu")
	)
	(gr_circle
		(center 444.166244 -24.741632)
		(end 445.055244 -24.741632)
		(stroke
			(width 0.2)
			(type default)
		)
		(fill no)
		(layer "In9.Cu")
	)
	(gr_line
		(start 449.250308 -98.832924)
		(end 452.291958 -95.791274)
		(stroke
			(width 0.508)
			(type default)
		)
		(layer "In9.Cu")
	)
	(gr_line
		(start 449.739258 -61.82868)
		(end 442.612526 -54.701948)
		(stroke
			(width 0.508)
			(type default)
		)
		(layer "In9.Cu")
	)
	(gr_circle
		(center 450.669914 -14.526514)
		(end 451.558914 -14.526514)
		(stroke
			(width 0.2)
			(type default)
		)
		(fill no)
		(layer "In9.Cu")
	)
	(gr_circle
		(center 450.670676 -16.010382)
		(end 451.559676 -16.010382)
		(stroke
			(width 0.2)
			(type default)
		)
		(fill no)
		(layer "In9.Cu")
	)
	(gr_circle
		(center 450.670676 -15.273782)
		(end 451.559676 -15.273782)
		(stroke
			(width 0.2)
			(type default)
		)
		(fill no)
		(layer "In9.Cu")
	)
	(gr_circle
		(center 452.054976 -18.535142)
		(end 452.943976 -18.535142)
		(stroke
			(width 0.2)
			(type default)
		)
		(fill no)
		(layer "In9.Cu")
	)
	(gr_circle
		(center 452.054976 -17.798542)
		(end 452.943976 -17.798542)
		(stroke
			(width 0.2)
			(type default)
		)
		(fill no)
		(layer "In9.Cu")
	)
	(gr_line
		(start 452.291958 -95.791274)
		(end 452.291958 -74.851768)
		(stroke
			(width 0.508)
			(type default)
		)
		(layer "In9.Cu")
	)
	(gr_line
		(start 452.291958 -74.851768)
		(end 453.267064 -73.876662)
		(stroke
			(width 0.508)
			(type default)
		)
		(layer "In9.Cu")
	)
	(gr_line
		(start 453.267064 -73.876662)
		(end 457.538582 -73.876662)
		(stroke
			(width 0.508)
			(type default)
		)
		(layer "In9.Cu")
	)
	(gr_line
		(start 455.28992 -195.653406)
		(end 426.178726 -195.653406)
		(stroke
			(width 0.508)
			(type default)
		)
		(layer "In9.Cu")
	)
	(gr_line
		(start 455.919586 -195.02374)
		(end 455.28992 -195.653406)
		(stroke
			(width 0.508)
			(type default)
		)
		(layer "In9.Cu")
	)
	(gr_line
		(start 455.919586 -182.514748)
		(end 455.919586 -195.02374)
		(stroke
			(width 0.508)
			(type default)
		)
		(layer "In9.Cu")
	)
	(gr_arc
		(start 456.202034 -9.780016)
		(mid 456.787819 -11.194227)
		(end 458.20203 -11.780012)
		(stroke
			(width 3.048)
			(type default)
		)
		(layer "In9.Cu")
	)
	(gr_arc
		(start 456.202034 -0.500126)
		(mid 456.05556 -0.146464)
		(end 455.701908 0)
		(stroke
			(width 3.048)
			(type default)
		)
		(layer "In9.Cu")
	)
	(gr_line
		(start 456.202034 -0.500126)
		(end 456.202034 -9.780016)
		(stroke
			(width 3.048)
			(type default)
		)
		(layer "In9.Cu")
	)
	(gr_line
		(start 457.538582 -73.876662)
		(end 459.674214 -71.74103)
		(stroke
			(width 0.508)
			(type default)
		)
		(layer "In9.Cu")
	)
	(gr_line
		(start 457.817728 -61.82868)
		(end 449.739258 -61.82868)
		(stroke
			(width 0.508)
			(type default)
		)
		(layer "In9.Cu")
	)
	(gr_line
		(start 458.20203 -11.780012)
		(end 469.799924 -11.780012)
		(stroke
			(width 3.048)
			(type default)
		)
		(layer "In9.Cu")
	)
	(gr_line
		(start 459.674214 -71.74103)
		(end 459.674214 -63.685166)
		(stroke
			(width 0.508)
			(type default)
		)
		(layer "In9.Cu")
	)
	(gr_line
		(start 459.674214 -63.685166)
		(end 457.817728 -61.82868)
		(stroke
			(width 0.508)
			(type default)
		)
		(layer "In9.Cu")
	)
	(gr_line
		(start 463.300064 -441.989972)
		(end 277.314914 -441.989972)
		(stroke
			(width 3.048)
			(type default)
		)
		(layer "In9.Cu")
	)
	(gr_arc
		(start 463.300064 -441.989972)
		(mid 464.71429 -441.404198)
		(end 465.30006 -439.989976)
		(stroke
			(width 3.048)
			(type default)
		)
		(layer "In9.Cu")
	)
	(gr_line
		(start 464.385152 -381.039624)
		(end 464.779106 -381.433578)
		(stroke
			(width 0.508)
			(type default)
		)
		(layer "In9.Cu")
	)
	(gr_line
		(start 464.779106 -392.748008)
		(end 435.405022 -422.122092)
		(stroke
			(width 0.508)
			(type default)
		)
		(layer "In9.Cu")
	)
	(gr_line
		(start 464.779106 -381.433578)
		(end 464.779106 -392.748008)
		(stroke
			(width 0.508)
			(type default)
		)
		(layer "In9.Cu")
	)
	(gr_line
		(start 465.30006 -409.528518)
		(end 465.30006 -439.989976)
		(stroke
			(width 3.048)
			(type default)
		)
		(layer "In9.Cu")
	)
	(gr_arc
		(start 465.885784 -408.114246)
		(mid 465.452221 -408.76312)
		(end 465.30006 -409.528518)
		(stroke
			(width 3.048)
			(type default)
		)
		(layer "In9.Cu")
	)
	(gr_line
		(start 467.71433 -406.2857)
		(end 465.885784 -408.114246)
		(stroke
			(width 3.048)
			(type default)
		)
		(layer "In9.Cu")
	)
	(gr_arc
		(start 467.71433 -406.2857)
		(mid 468.147828 -405.636947)
		(end 468.300054 -404.871682)
		(stroke
			(width 3.048)
			(type default)
		)
		(layer "In9.Cu")
	)
	(gr_line
		(start 468.300054 -82.828384)
		(end 468.300054 -404.871682)
		(stroke
			(width 3.048)
			(type default)
		)
		(layer "In9.Cu")
	)
	(gr_arc
		(start 468.885778 -81.414112)
		(mid 468.452215 -82.062986)
		(end 468.300054 -82.828384)
		(stroke
			(width 3.048)
			(type default)
		)
		(layer "In9.Cu")
	)
	(gr_line
		(start 471.214196 -79.085694)
		(end 468.885778 -81.414112)
		(stroke
			(width 3.048)
			(type default)
		)
		(layer "In9.Cu")
	)
	(gr_arc
		(start 471.214196 -79.085694)
		(mid 471.6477 -78.436942)
		(end 471.79992 -77.671676)
		(stroke
			(width 3.048)
			(type default)
		)
		(layer "In9.Cu")
	)
	(gr_arc
		(start 471.79992 -13.780008)
		(mid 471.214139 -12.365784)
		(end 469.799924 -11.780012)
		(stroke
			(width 3.048)
			(type default)
		)
		(layer "In9.Cu")
	)
	(gr_line
		(start 471.79992 -13.780008)
		(end 471.79992 -77.671676)
		(stroke
			(width 3.048)
			(type default)
		)
		(layer "In9.Cu")
	)
	(gr_line
		(start 0 -77.671676)
		(end 0 -13.780008)
		(stroke
			(width 1.016)
			(type default)
		)
		(layer "In10.Cu")
	)
	(gr_arc
		(start 0 -77.671676)
		(mid 0.152237 -78.436936)
		(end 0.585724 -79.085694)
		(stroke
			(width 1.016)
			(type default)
		)
		(layer "In10.Cu")
	)
	(gr_poly
		(pts
			(arc
				(start 279.248108 -392.23696)
				(mid 279.284029 -392.222081)
				(end 279.298908 -392.18616)
			)
			(arc
				(start 279.298908 -383.93116)
				(mid 279.284029 -383.895239)
				(end 279.248108 -383.88036)
			)
			(arc
				(start 275.026374 -383.88036)
				(mid 275.006851 -383.884261)
				(end 274.990306 -383.895346)
			)
			(arc
				(start 274.766278 -384.119374)
				(mid 274.755167 -384.135908)
				(end 274.751292 -384.155442)
			)
			(arc
				(start 274.751292 -392.107928)
				(mid 274.755193 -392.127451)
				(end 274.766278 -392.143996)
			)
			(arc
				(start 274.844256 -392.221974)
				(mid 274.86079 -392.233085)
				(end 274.880324 -392.23696)
			)
		)
		(stroke
			(width 0)
			(type solid)
		)
		(fill yes)
		(layer "In10.Cu")
		(net "P12V_MAIN_R_0")
	)
	(gr_poly
		(pts
			(arc
				(start 98.184208 -278.13635)
				(mid 97.777808 -278.13635)
				(end 98.184208 -278.13635)
			)
		)
		(stroke
			(width 0)
			(type solid)
		)
		(fill yes)
		(layer "In10.Cu")
		(net "P5E_CPU1_P1_RX_DN<1>")
	)
	(gr_poly
		(pts
			(arc
				(start 98.184208 -276.516338)
				(mid 97.777808 -276.516338)
				(end 98.184208 -276.516338)
			)
		)
		(stroke
			(width 0)
			(type solid)
		)
		(fill yes)
		(layer "In10.Cu")
		(net "P5E_CPU1_P1_RX_DN<0>")
	)
	(gr_poly
		(pts
			(arc
				(start 98.184208 -274.896326)
				(mid 97.777808 -274.896326)
				(end 98.184208 -274.896326)
			)
		)
		(stroke
			(width 0)
			(type solid)
		)
		(fill yes)
		(layer "In10.Cu")
		(net "P5E_CPU1_P1_RX_DN<2>")
	)
	(gr_poly
		(pts
			(arc
				(start 98.184208 -273.276314)
				(mid 97.777808 -273.276314)
				(end 98.184208 -273.276314)
			)
		)
		(stroke
			(width 0)
			(type solid)
		)
		(fill yes)
		(layer "In10.Cu")
		(net "P5E_CPU1_P0_RX_DN<1>")
	)
	(gr_poly
		(pts
			(arc
				(start 98.184208 -271.656302)
				(mid 97.777808 -271.656302)
				(end 98.184208 -271.656302)
			)
		)
		(stroke
			(width 0)
			(type solid)
		)
		(fill yes)
		(layer "In10.Cu")
		(net "P5E_CPU1_P0_RX_DN<0>")
	)
	(gr_poly
		(pts
			(arc
				(start 98.184208 -270.03629)
				(mid 97.777808 -270.03629)
				(end 98.184208 -270.03629)
			)
		)
		(stroke
			(width 0)
			(type solid)
		)
		(fill yes)
		(layer "In10.Cu")
		(net "P5E_CPU1_P0_RX_DN<2>")
	)
	(gr_poly
		(pts
			(arc
				(start 99.124262 -278.13635)
				(mid 98.717862 -278.13635)
				(end 99.124262 -278.13635)
			)
		)
		(stroke
			(width 0)
			(type solid)
		)
		(fill yes)
		(layer "In10.Cu")
		(net "P5E_CPU1_P1_RX_DP<1>")
	)
	(gr_poly
		(pts
			(arc
				(start 99.124262 -276.516338)
				(mid 98.717862 -276.516338)
				(end 99.124262 -276.516338)
			)
		)
		(stroke
			(width 0)
			(type solid)
		)
		(fill yes)
		(layer "In10.Cu")
		(net "P5E_CPU1_P1_RX_DP<0>")
	)
	(gr_poly
		(pts
			(arc
				(start 99.124262 -274.896326)
				(mid 98.717862 -274.896326)
				(end 99.124262 -274.896326)
			)
		)
		(stroke
			(width 0)
			(type solid)
		)
		(fill yes)
		(layer "In10.Cu")
		(net "P5E_CPU1_P1_RX_DP<2>")
	)
	(gr_poly
		(pts
			(arc
				(start 99.124262 -273.276314)
				(mid 98.717862 -273.276314)
				(end 99.124262 -273.276314)
			)
		)
		(stroke
			(width 0)
			(type solid)
		)
		(fill yes)
		(layer "In10.Cu")
		(net "P5E_CPU1_P0_RX_DP<1>")
	)
	(gr_poly
		(pts
			(arc
				(start 99.124262 -271.656302)
				(mid 98.717862 -271.656302)
				(end 99.124262 -271.656302)
			)
		)
		(stroke
			(width 0)
			(type solid)
		)
		(fill yes)
		(layer "In10.Cu")
		(net "P5E_CPU1_P0_RX_DP<0>")
	)
	(gr_poly
		(pts
			(arc
				(start 99.124262 -270.03629)
				(mid 98.717862 -270.03629)
				(end 99.124262 -270.03629)
			)
		)
		(stroke
			(width 0)
			(type solid)
		)
		(fill yes)
		(layer "In10.Cu")
		(net "P5E_CPU1_P0_RX_DP<2>")
	)
	(gr_poly
		(pts
			(arc
				(start 101.004116 -278.13635)
				(mid 100.597716 -278.13635)
				(end 101.004116 -278.13635)
			)
		)
		(stroke
			(width 0)
			(type solid)
		)
		(fill yes)
		(layer "In10.Cu")
		(net "P5E_CPU1_P1_RX_DN<4>")
	)
	(gr_poly
		(pts
			(arc
				(start 101.004116 -276.516338)
				(mid 100.597716 -276.516338)
				(end 101.004116 -276.516338)
			)
		)
		(stroke
			(width 0)
			(type solid)
		)
		(fill yes)
		(layer "In10.Cu")
		(net "P5E_CPU1_P1_RX_DN<3>")
	)
	(gr_poly
		(pts
			(arc
				(start 101.004116 -274.896326)
				(mid 100.597716 -274.896326)
				(end 101.004116 -274.896326)
			)
		)
		(stroke
			(width 0)
			(type solid)
		)
		(fill yes)
		(layer "In10.Cu")
		(net "P5E_CPU1_P1_RX_DN<5>")
	)
	(gr_poly
		(pts
			(arc
				(start 101.004116 -273.276314)
				(mid 100.597716 -273.276314)
				(end 101.004116 -273.276314)
			)
		)
		(stroke
			(width 0)
			(type solid)
		)
		(fill yes)
		(layer "In10.Cu")
		(net "P5E_CPU1_P0_RX_DN<4>")
	)
	(gr_poly
		(pts
			(arc
				(start 101.004116 -271.656302)
				(mid 100.597716 -271.656302)
				(end 101.004116 -271.656302)
			)
		)
		(stroke
			(width 0)
			(type solid)
		)
		(fill yes)
		(layer "In10.Cu")
		(net "P5E_CPU1_P0_RX_DN<3>")
	)
	(gr_poly
		(pts
			(arc
				(start 101.004116 -270.03629)
				(mid 100.597716 -270.03629)
				(end 101.004116 -270.03629)
			)
		)
		(stroke
			(width 0)
			(type solid)
		)
		(fill yes)
		(layer "In10.Cu")
		(net "P5E_CPU1_P0_RX_DN<5>")
	)
	(gr_poly
		(pts
			(arc
				(start 101.94417 -278.13635)
				(mid 101.53777 -278.13635)
				(end 101.94417 -278.13635)
			)
		)
		(stroke
			(width 0)
			(type solid)
		)
		(fill yes)
		(layer "In10.Cu")
		(net "P5E_CPU1_P1_RX_DP<4>")
	)
	(gr_poly
		(pts
			(arc
				(start 101.94417 -276.516338)
				(mid 101.53777 -276.516338)
				(end 101.94417 -276.516338)
			)
		)
		(stroke
			(width 0)
			(type solid)
		)
		(fill yes)
		(layer "In10.Cu")
		(net "P5E_CPU1_P1_RX_DP<3>")
	)
	(gr_poly
		(pts
			(arc
				(start 101.94417 -274.896326)
				(mid 101.53777 -274.896326)
				(end 101.94417 -274.896326)
			)
		)
		(stroke
			(width 0)
			(type solid)
		)
		(fill yes)
		(layer "In10.Cu")
		(net "P5E_CPU1_P1_RX_DP<5>")
	)
	(gr_poly
		(pts
			(arc
				(start 101.94417 -273.276314)
				(mid 101.53777 -273.276314)
				(end 101.94417 -273.276314)
			)
		)
		(stroke
			(width 0)
			(type solid)
		)
		(fill yes)
		(layer "In10.Cu")
		(net "P5E_CPU1_P0_RX_DP<4>")
	)
	(gr_poly
		(pts
			(arc
				(start 101.94417 -271.656302)
				(mid 101.53777 -271.656302)
				(end 101.94417 -271.656302)
			)
		)
		(stroke
			(width 0)
			(type solid)
		)
		(fill yes)
		(layer "In10.Cu")
		(net "P5E_CPU1_P0_RX_DP<3>")
	)
	(gr_poly
		(pts
			(arc
				(start 101.94417 -270.03629)
				(mid 101.53777 -270.03629)
				(end 101.94417 -270.03629)
			)
		)
		(stroke
			(width 0)
			(type solid)
		)
		(fill yes)
		(layer "In10.Cu")
		(net "P5E_CPU1_P0_RX_DP<5>")
	)
	(gr_poly
		(pts
			(arc
				(start 103.824278 -278.13635)
				(mid 103.417878 -278.13635)
				(end 103.824278 -278.13635)
			)
		)
		(stroke
			(width 0)
			(type solid)
		)
		(fill yes)
		(layer "In10.Cu")
		(net "P5E_CPU1_P1_RX_DN<7>")
	)
	(gr_poly
		(pts
			(arc
				(start 103.824278 -276.516338)
				(mid 103.417878 -276.516338)
				(end 103.824278 -276.516338)
			)
		)
		(stroke
			(width 0)
			(type solid)
		)
		(fill yes)
		(layer "In10.Cu")
		(net "P5E_CPU1_P1_RX_DN<6>")
	)
	(gr_poly
		(pts
			(arc
				(start 103.824278 -274.896326)
				(mid 103.417878 -274.896326)
				(end 103.824278 -274.896326)
			)
		)
		(stroke
			(width 0)
			(type solid)
		)
		(fill yes)
		(layer "In10.Cu")
		(net "P5E_CPU1_P1_RX_DN<8>")
	)
	(gr_poly
		(pts
			(arc
				(start 103.824278 -273.276314)
				(mid 103.417878 -273.276314)
				(end 103.824278 -273.276314)
			)
		)
		(stroke
			(width 0)
			(type solid)
		)
		(fill yes)
		(layer "In10.Cu")
		(net "P5E_CPU1_P0_RX_DN<7>")
	)
	(gr_poly
		(pts
			(arc
				(start 103.824278 -271.656302)
				(mid 103.417878 -271.656302)
				(end 103.824278 -271.656302)
			)
		)
		(stroke
			(width 0)
			(type solid)
		)
		(fill yes)
		(layer "In10.Cu")
		(net "P5E_CPU1_P0_RX_DN<6>")
	)
	(gr_poly
		(pts
			(arc
				(start 103.824278 -270.03629)
				(mid 103.417878 -270.03629)
				(end 103.824278 -270.03629)
			)
		)
		(stroke
			(width 0)
			(type solid)
		)
		(fill yes)
		(layer "In10.Cu")
		(net "P5E_CPU1_P0_RX_DN<8>")
	)
	(gr_poly
		(pts
			(arc
				(start 104.764332 -278.13635)
				(mid 104.357932 -278.13635)
				(end 104.764332 -278.13635)
			)
		)
		(stroke
			(width 0)
			(type solid)
		)
		(fill yes)
		(layer "In10.Cu")
		(net "P5E_CPU1_P1_RX_DP<7>")
	)
	(gr_poly
		(pts
			(arc
				(start 104.764332 -276.516338)
				(mid 104.357932 -276.516338)
				(end 104.764332 -276.516338)
			)
		)
		(stroke
			(width 0)
			(type solid)
		)
		(fill yes)
		(layer "In10.Cu")
		(net "P5E_CPU1_P1_RX_DP<6>")
	)
	(gr_poly
		(pts
			(arc
				(start 104.764332 -274.896326)
				(mid 104.357932 -274.896326)
				(end 104.764332 -274.896326)
			)
		)
		(stroke
			(width 0)
			(type solid)
		)
		(fill yes)
		(layer "In10.Cu")
		(net "P5E_CPU1_P1_RX_DP<8>")
	)
	(gr_poly
		(pts
			(arc
				(start 104.764332 -273.276314)
				(mid 104.357932 -273.276314)
				(end 104.764332 -273.276314)
			)
		)
		(stroke
			(width 0)
			(type solid)
		)
		(fill yes)
		(layer "In10.Cu")
		(net "P5E_CPU1_P0_RX_DP<7>")
	)
	(gr_poly
		(pts
			(arc
				(start 104.764332 -271.656302)
				(mid 104.357932 -271.656302)
				(end 104.764332 -271.656302)
			)
		)
		(stroke
			(width 0)
			(type solid)
		)
		(fill yes)
		(layer "In10.Cu")
		(net "P5E_CPU1_P0_RX_DP<6>")
	)
	(gr_poly
		(pts
			(arc
				(start 104.764332 -270.03629)
				(mid 104.357932 -270.03629)
				(end 104.764332 -270.03629)
			)
		)
		(stroke
			(width 0)
			(type solid)
		)
		(fill yes)
		(layer "In10.Cu")
		(net "P5E_CPU1_P0_RX_DP<8>")
	)
	(gr_poly
		(pts
			(arc
				(start 106.644186 -279.756362)
				(mid 106.237786 -279.756362)
				(end 106.644186 -279.756362)
			)
		)
		(stroke
			(width 0)
			(type solid)
		)
		(fill yes)
		(layer "In10.Cu")
		(net "P5E_CPU1_P1_RX_DN<11>")
	)
	(gr_poly
		(pts
			(arc
				(start 106.644186 -278.13635)
				(mid 106.237786 -278.13635)
				(end 106.644186 -278.13635)
			)
		)
		(stroke
			(width 0)
			(type solid)
		)
		(fill yes)
		(layer "In10.Cu")
		(net "P5E_CPU1_P1_RX_DN<10>")
	)
	(gr_poly
		(pts
			(arc
				(start 106.644186 -276.516338)
				(mid 106.237786 -276.516338)
				(end 106.644186 -276.516338)
			)
		)
		(stroke
			(width 0)
			(type solid)
		)
		(fill yes)
		(layer "In10.Cu")
		(net "P5E_CPU1_P1_RX_DN<9>")
	)
	(gr_poly
		(pts
			(arc
				(start 106.644186 -274.896326)
				(mid 106.237786 -274.896326)
				(end 106.644186 -274.896326)
			)
		)
		(stroke
			(width 0)
			(type solid)
		)
		(fill yes)
		(layer "In10.Cu")
		(net "P5E_CPU1_P1_RX_DN<12>")
	)
	(gr_poly
		(pts
			(arc
				(start 106.644186 -273.276314)
				(mid 106.237786 -273.276314)
				(end 106.644186 -273.276314)
			)
		)
		(stroke
			(width 0)
			(type solid)
		)
		(fill yes)
		(layer "In10.Cu")
		(net "P5E_CPU1_P0_RX_DN<10>")
	)
	(gr_poly
		(pts
			(arc
				(start 106.644186 -271.656302)
				(mid 106.237786 -271.656302)
				(end 106.644186 -271.656302)
			)
		)
		(stroke
			(width 0)
			(type solid)
		)
		(fill yes)
		(layer "In10.Cu")
		(net "P5E_CPU1_P0_RX_DN<9>")
	)
	(gr_poly
		(pts
			(arc
				(start 106.644186 -270.03629)
				(mid 106.237786 -270.03629)
				(end 106.644186 -270.03629)
			)
		)
		(stroke
			(width 0)
			(type solid)
		)
		(fill yes)
		(layer "In10.Cu")
		(net "P5E_CPU1_P0_RX_DN<11>")
	)
	(gr_poly
		(pts
			(arc
				(start 107.58424 -279.756362)
				(mid 107.17784 -279.756362)
				(end 107.58424 -279.756362)
			)
		)
		(stroke
			(width 0)
			(type solid)
		)
		(fill yes)
		(layer "In10.Cu")
		(net "P5E_CPU1_P1_RX_DP<11>")
	)
	(gr_poly
		(pts
			(arc
				(start 107.58424 -278.13635)
				(mid 107.17784 -278.13635)
				(end 107.58424 -278.13635)
			)
		)
		(stroke
			(width 0)
			(type solid)
		)
		(fill yes)
		(layer "In10.Cu")
		(net "P5E_CPU1_P1_RX_DP<10>")
	)
	(gr_poly
		(pts
			(arc
				(start 107.58424 -276.516338)
				(mid 107.17784 -276.516338)
				(end 107.58424 -276.516338)
			)
		)
		(stroke
			(width 0)
			(type solid)
		)
		(fill yes)
		(layer "In10.Cu")
		(net "P5E_CPU1_P1_RX_DP<9>")
	)
	(gr_poly
		(pts
			(arc
				(start 107.58424 -274.896326)
				(mid 107.17784 -274.896326)
				(end 107.58424 -274.896326)
			)
		)
		(stroke
			(width 0)
			(type solid)
		)
		(fill yes)
		(layer "In10.Cu")
		(net "P5E_CPU1_P1_RX_DP<12>")
	)
	(gr_poly
		(pts
			(arc
				(start 107.58424 -273.276314)
				(mid 107.17784 -273.276314)
				(end 107.58424 -273.276314)
			)
		)
		(stroke
			(width 0)
			(type solid)
		)
		(fill yes)
		(layer "In10.Cu")
		(net "P5E_CPU1_P0_RX_DP<10>")
	)
	(gr_poly
		(pts
			(arc
				(start 107.58424 -271.656302)
				(mid 107.17784 -271.656302)
				(end 107.58424 -271.656302)
			)
		)
		(stroke
			(width 0)
			(type solid)
		)
		(fill yes)
		(layer "In10.Cu")
		(net "P5E_CPU1_P0_RX_DP<9>")
	)
	(gr_poly
		(pts
			(arc
				(start 107.58424 -270.03629)
				(mid 107.17784 -270.03629)
				(end 107.58424 -270.03629)
			)
		)
		(stroke
			(width 0)
			(type solid)
		)
		(fill yes)
		(layer "In10.Cu")
		(net "P5E_CPU1_P0_RX_DP<11>")
	)
	(gr_poly
		(pts
			(arc
				(start 108.994194 -278.946356)
				(mid 108.587794 -278.946356)
				(end 108.994194 -278.946356)
			)
		)
		(stroke
			(width 0)
			(type solid)
		)
		(fill yes)
		(layer "In10.Cu")
		(net "P5E_CPU1_P1_RX_DN<13>")
	)
	(gr_poly
		(pts
			(arc
				(start 108.994194 -277.326344)
				(mid 108.587794 -277.326344)
				(end 108.994194 -277.326344)
			)
		)
		(stroke
			(width 0)
			(type solid)
		)
		(fill yes)
		(layer "In10.Cu")
		(net "P5E_CPU1_P1_RX_DN<14>")
	)
	(gr_poly
		(pts
			(arc
				(start 108.994194 -275.706332)
				(mid 108.587794 -275.706332)
				(end 108.994194 -275.706332)
			)
		)
		(stroke
			(width 0)
			(type solid)
		)
		(fill yes)
		(layer "In10.Cu")
		(net "P5E_CPU1_P1_RX_DN<15>")
	)
	(gr_poly
		(pts
			(arc
				(start 108.994194 -274.08632)
				(mid 108.587794 -274.08632)
				(end 108.994194 -274.08632)
			)
		)
		(stroke
			(width 0)
			(type solid)
		)
		(fill yes)
		(layer "In10.Cu")
		(net "P5E_CPU1_P0_RX_DN<13>")
	)
	(gr_poly
		(pts
			(arc
				(start 108.994194 -272.466308)
				(mid 108.587794 -272.466308)
				(end 108.994194 -272.466308)
			)
		)
		(stroke
			(width 0)
			(type solid)
		)
		(fill yes)
		(layer "In10.Cu")
		(net "P5E_CPU1_P0_RX_DN<12>")
	)
	(gr_poly
		(pts
			(arc
				(start 108.994194 -270.846296)
				(mid 108.587794 -270.846296)
				(end 108.994194 -270.846296)
			)
		)
		(stroke
			(width 0)
			(type solid)
		)
		(fill yes)
		(layer "In10.Cu")
		(net "P5E_CPU1_P0_RX_DN<14>")
	)
	(gr_poly
		(pts
			(arc
				(start 108.994194 -269.226284)
				(mid 108.587794 -269.226284)
				(end 108.994194 -269.226284)
			)
		)
		(stroke
			(width 0)
			(type solid)
		)
		(fill yes)
		(layer "In10.Cu")
		(net "P5E_CPU1_P0_RX_DN<15>")
	)
	(gr_poly
		(pts
			(arc
				(start 109.934248 -278.946356)
				(mid 109.527848 -278.946356)
				(end 109.934248 -278.946356)
			)
		)
		(stroke
			(width 0)
			(type solid)
		)
		(fill yes)
		(layer "In10.Cu")
		(net "P5E_CPU1_P1_RX_DP<13>")
	)
	(gr_poly
		(pts
			(arc
				(start 109.934248 -277.326344)
				(mid 109.527848 -277.326344)
				(end 109.934248 -277.326344)
			)
		)
		(stroke
			(width 0)
			(type solid)
		)
		(fill yes)
		(layer "In10.Cu")
		(net "P5E_CPU1_P1_RX_DP<14>")
	)
	(gr_poly
		(pts
			(arc
				(start 109.934248 -275.706332)
				(mid 109.527848 -275.706332)
				(end 109.934248 -275.706332)
			)
		)
		(stroke
			(width 0)
			(type solid)
		)
		(fill yes)
		(layer "In10.Cu")
		(net "P5E_CPU1_P1_RX_DP<15>")
	)
	(gr_poly
		(pts
			(arc
				(start 109.934248 -274.08632)
				(mid 109.527848 -274.08632)
				(end 109.934248 -274.08632)
			)
		)
		(stroke
			(width 0)
			(type solid)
		)
		(fill yes)
		(layer "In10.Cu")
		(net "P5E_CPU1_P0_RX_DP<13>")
	)
	(gr_poly
		(pts
			(arc
				(start 109.934248 -272.466308)
				(mid 109.527848 -272.466308)
				(end 109.934248 -272.466308)
			)
		)
		(stroke
			(width 0)
			(type solid)
		)
		(fill yes)
		(layer "In10.Cu")
		(net "P5E_CPU1_P0_RX_DP<12>")
	)
	(gr_poly
		(pts
			(arc
				(start 109.934248 -270.846296)
				(mid 109.527848 -270.846296)
				(end 109.934248 -270.846296)
			)
		)
		(stroke
			(width 0)
			(type solid)
		)
		(fill yes)
		(layer "In10.Cu")
		(net "P5E_CPU1_P0_RX_DP<14>")
	)
	(gr_poly
		(pts
			(arc
				(start 109.934248 -269.226284)
				(mid 109.527848 -269.226284)
				(end 109.934248 -269.226284)
			)
		)
		(stroke
			(width 0)
			(type solid)
		)
		(fill yes)
		(layer "In10.Cu")
		(net "P5E_CPU1_P0_RX_DP<15>")
	)
	(gr_poly
		(pts
			(arc
				(start 114.627914 -278.946356)
				(mid 114.221514 -278.946356)
				(end 114.627914 -278.946356)
			)
		)
		(stroke
			(width 0)
			(type solid)
		)
		(fill yes)
		(layer "In10.Cu")
		(net "P5E_CPU1_P3_TX_DP<2>")
	)
	(gr_poly
		(pts
			(arc
				(start 114.627914 -277.326344)
				(mid 114.221514 -277.326344)
				(end 114.627914 -277.326344)
			)
		)
		(stroke
			(width 0)
			(type solid)
		)
		(fill yes)
		(layer "In10.Cu")
		(net "P5E_CPU1_P3_TX_DP<1>")
	)
	(gr_poly
		(pts
			(arc
				(start 114.627914 -275.706332)
				(mid 114.221514 -275.706332)
				(end 114.627914 -275.706332)
			)
		)
		(stroke
			(width 0)
			(type solid)
		)
		(fill yes)
		(layer "In10.Cu")
		(net "P5E_CPU1_P3_TX_DP<0>")
	)
	(gr_poly
		(pts
			(arc
				(start 114.627914 -274.08632)
				(mid 114.221514 -274.08632)
				(end 114.627914 -274.08632)
			)
		)
		(stroke
			(width 0)
			(type solid)
		)
		(fill yes)
		(layer "In10.Cu")
		(net "P5E_CPU1_P2_TX_DP<2>")
	)
	(gr_poly
		(pts
			(arc
				(start 114.627914 -272.466308)
				(mid 114.221514 -272.466308)
				(end 114.627914 -272.466308)
			)
		)
		(stroke
			(width 0)
			(type solid)
		)
		(fill yes)
		(layer "In10.Cu")
		(net "P5E_CPU1_P2_TX_DP<3>")
	)
	(gr_poly
		(pts
			(arc
				(start 114.627914 -270.846296)
				(mid 114.221514 -270.846296)
				(end 114.627914 -270.846296)
			)
		)
		(stroke
			(width 0)
			(type solid)
		)
		(fill yes)
		(layer "In10.Cu")
		(net "P5E_CPU1_P2_TX_DP<1>")
	)
	(gr_poly
		(pts
			(arc
				(start 114.627914 -269.226284)
				(mid 114.221514 -269.226284)
				(end 114.627914 -269.226284)
			)
		)
		(stroke
			(width 0)
			(type solid)
		)
		(fill yes)
		(layer "In10.Cu")
		(net "P5E_CPU1_P2_TX_DP<0>")
	)
	(gr_poly
		(pts
			(arc
				(start 115.567968 -278.946356)
				(mid 115.161568 -278.946356)
				(end 115.567968 -278.946356)
			)
		)
		(stroke
			(width 0)
			(type solid)
		)
		(fill yes)
		(layer "In10.Cu")
		(net "P5E_CPU1_P3_TX_DN<2>")
	)
	(gr_poly
		(pts
			(arc
				(start 115.567968 -277.326344)
				(mid 115.161568 -277.326344)
				(end 115.567968 -277.326344)
			)
		)
		(stroke
			(width 0)
			(type solid)
		)
		(fill yes)
		(layer "In10.Cu")
		(net "P5E_CPU1_P3_TX_DN<1>")
	)
	(gr_poly
		(pts
			(arc
				(start 115.567968 -275.706332)
				(mid 115.161568 -275.706332)
				(end 115.567968 -275.706332)
			)
		)
		(stroke
			(width 0)
			(type solid)
		)
		(fill yes)
		(layer "In10.Cu")
		(net "P5E_CPU1_P3_TX_DN<0>")
	)
	(gr_poly
		(pts
			(arc
				(start 115.567968 -274.08632)
				(mid 115.161568 -274.08632)
				(end 115.567968 -274.08632)
			)
		)
		(stroke
			(width 0)
			(type solid)
		)
		(fill yes)
		(layer "In10.Cu")
		(net "P5E_CPU1_P2_TX_DN<2>")
	)
	(gr_poly
		(pts
			(arc
				(start 115.567968 -272.466308)
				(mid 115.161568 -272.466308)
				(end 115.567968 -272.466308)
			)
		)
		(stroke
			(width 0)
			(type solid)
		)
		(fill yes)
		(layer "In10.Cu")
		(net "P5E_CPU1_P2_TX_DN<3>")
	)
	(gr_poly
		(pts
			(arc
				(start 115.567968 -270.846296)
				(mid 115.161568 -270.846296)
				(end 115.567968 -270.846296)
			)
		)
		(stroke
			(width 0)
			(type solid)
		)
		(fill yes)
		(layer "In10.Cu")
		(net "P5E_CPU1_P2_TX_DN<1>")
	)
	(gr_poly
		(pts
			(arc
				(start 115.567968 -269.226284)
				(mid 115.161568 -269.226284)
				(end 115.567968 -269.226284)
			)
		)
		(stroke
			(width 0)
			(type solid)
		)
		(fill yes)
		(layer "In10.Cu")
		(net "P5E_CPU1_P2_TX_DN<0>")
	)
	(gr_poly
		(pts
			(arc
				(start 116.977922 -279.756362)
				(mid 116.571522 -279.756362)
				(end 116.977922 -279.756362)
			)
		)
		(stroke
			(width 0)
			(type solid)
		)
		(fill yes)
		(layer "In10.Cu")
		(net "P5E_CPU1_P3_TX_DP<4>")
	)
	(gr_poly
		(pts
			(arc
				(start 116.977922 -278.13635)
				(mid 116.571522 -278.13635)
				(end 116.977922 -278.13635)
			)
		)
		(stroke
			(width 0)
			(type solid)
		)
		(fill yes)
		(layer "In10.Cu")
		(net "P5E_CPU1_P3_TX_DP<5>")
	)
	(gr_poly
		(pts
			(arc
				(start 116.977922 -276.516338)
				(mid 116.571522 -276.516338)
				(end 116.977922 -276.516338)
			)
		)
		(stroke
			(width 0)
			(type solid)
		)
		(fill yes)
		(layer "In10.Cu")
		(net "P5E_CPU1_P3_TX_DP<6>")
	)
	(gr_poly
		(pts
			(arc
				(start 116.977922 -274.896326)
				(mid 116.571522 -274.896326)
				(end 116.977922 -274.896326)
			)
		)
		(stroke
			(width 0)
			(type solid)
		)
		(fill yes)
		(layer "In10.Cu")
		(net "P5E_CPU1_P3_TX_DP<3>")
	)
	(gr_poly
		(pts
			(arc
				(start 116.977922 -273.276314)
				(mid 116.571522 -273.276314)
				(end 116.977922 -273.276314)
			)
		)
		(stroke
			(width 0)
			(type solid)
		)
		(fill yes)
		(layer "In10.Cu")
		(net "P5E_CPU1_P2_TX_DP<5>")
	)
	(gr_poly
		(pts
			(arc
				(start 116.977922 -271.656302)
				(mid 116.571522 -271.656302)
				(end 116.977922 -271.656302)
			)
		)
		(stroke
			(width 0)
			(type solid)
		)
		(fill yes)
		(layer "In10.Cu")
		(net "P5E_CPU1_P2_TX_DP<6>")
	)
	(gr_poly
		(pts
			(arc
				(start 116.977922 -270.03629)
				(mid 116.571522 -270.03629)
				(end 116.977922 -270.03629)
			)
		)
		(stroke
			(width 0)
			(type solid)
		)
		(fill yes)
		(layer "In10.Cu")
		(net "P5E_CPU1_P2_TX_DP<4>")
	)
	(gr_poly
		(pts
			(arc
				(start 117.917976 -279.756362)
				(mid 117.511576 -279.756362)
				(end 117.917976 -279.756362)
			)
		)
		(stroke
			(width 0)
			(type solid)
		)
		(fill yes)
		(layer "In10.Cu")
		(net "P5E_CPU1_P3_TX_DN<4>")
	)
	(gr_poly
		(pts
			(arc
				(start 117.917976 -278.13635)
				(mid 117.511576 -278.13635)
				(end 117.917976 -278.13635)
			)
		)
		(stroke
			(width 0)
			(type solid)
		)
		(fill yes)
		(layer "In10.Cu")
		(net "P5E_CPU1_P3_TX_DN<5>")
	)
	(gr_poly
		(pts
			(arc
				(start 117.917976 -276.516338)
				(mid 117.511576 -276.516338)
				(end 117.917976 -276.516338)
			)
		)
		(stroke
			(width 0)
			(type solid)
		)
		(fill yes)
		(layer "In10.Cu")
		(net "P5E_CPU1_P3_TX_DN<6>")
	)
	(gr_poly
		(pts
			(arc
				(start 117.917976 -274.896326)
				(mid 117.511576 -274.896326)
				(end 117.917976 -274.896326)
			)
		)
		(stroke
			(width 0)
			(type solid)
		)
		(fill yes)
		(layer "In10.Cu")
		(net "P5E_CPU1_P3_TX_DN<3>")
	)
	(gr_poly
		(pts
			(arc
				(start 117.917976 -273.276314)
				(mid 117.511576 -273.276314)
				(end 117.917976 -273.276314)
			)
		)
		(stroke
			(width 0)
			(type solid)
		)
		(fill yes)
		(layer "In10.Cu")
		(net "P5E_CPU1_P2_TX_DN<5>")
	)
	(gr_poly
		(pts
			(arc
				(start 117.917976 -271.656302)
				(mid 117.511576 -271.656302)
				(end 117.917976 -271.656302)
			)
		)
		(stroke
			(width 0)
			(type solid)
		)
		(fill yes)
		(layer "In10.Cu")
		(net "P5E_CPU1_P2_TX_DN<6>")
	)
	(gr_poly
		(pts
			(arc
				(start 117.917976 -270.03629)
				(mid 117.511576 -270.03629)
				(end 117.917976 -270.03629)
			)
		)
		(stroke
			(width 0)
			(type solid)
		)
		(fill yes)
		(layer "In10.Cu")
		(net "P5E_CPU1_P2_TX_DN<4>")
	)
	(gr_poly
		(pts
			(arc
				(start 119.79783 -278.13635)
				(mid 119.39143 -278.13635)
				(end 119.79783 -278.13635)
			)
		)
		(stroke
			(width 0)
			(type solid)
		)
		(fill yes)
		(layer "In10.Cu")
		(net "P5E_CPU1_P3_TX_DP<8>")
	)
	(gr_poly
		(pts
			(arc
				(start 119.79783 -276.516338)
				(mid 119.39143 -276.516338)
				(end 119.79783 -276.516338)
			)
		)
		(stroke
			(width 0)
			(type solid)
		)
		(fill yes)
		(layer "In10.Cu")
		(net "P5E_CPU1_P3_TX_DP<9>")
	)
	(gr_poly
		(pts
			(arc
				(start 119.79783 -274.896326)
				(mid 119.39143 -274.896326)
				(end 119.79783 -274.896326)
			)
		)
		(stroke
			(width 0)
			(type solid)
		)
		(fill yes)
		(layer "In10.Cu")
		(net "P5E_CPU1_P3_TX_DP<7>")
	)
	(gr_poly
		(pts
			(arc
				(start 119.79783 -273.276314)
				(mid 119.39143 -273.276314)
				(end 119.79783 -273.276314)
			)
		)
		(stroke
			(width 0)
			(type solid)
		)
		(fill yes)
		(layer "In10.Cu")
		(net "P5E_CPU1_P2_TX_DP<8>")
	)
	(gr_poly
		(pts
			(arc
				(start 119.79783 -271.656302)
				(mid 119.39143 -271.656302)
				(end 119.79783 -271.656302)
			)
		)
		(stroke
			(width 0)
			(type solid)
		)
		(fill yes)
		(layer "In10.Cu")
		(net "P5E_CPU1_P2_TX_DP<9>")
	)
	(gr_poly
		(pts
			(arc
				(start 119.79783 -270.03629)
				(mid 119.39143 -270.03629)
				(end 119.79783 -270.03629)
			)
		)
		(stroke
			(width 0)
			(type solid)
		)
		(fill yes)
		(layer "In10.Cu")
		(net "P5E_CPU1_P2_TX_DP<7>")
	)
	(gr_poly
		(pts
			(arc
				(start 120.737884 -278.13635)
				(mid 120.331484 -278.13635)
				(end 120.737884 -278.13635)
			)
		)
		(stroke
			(width 0)
			(type solid)
		)
		(fill yes)
		(layer "In10.Cu")
		(net "P5E_CPU1_P3_TX_DN<8>")
	)
	(gr_poly
		(pts
			(arc
				(start 120.737884 -276.516338)
				(mid 120.331484 -276.516338)
				(end 120.737884 -276.516338)
			)
		)
		(stroke
			(width 0)
			(type solid)
		)
		(fill yes)
		(layer "In10.Cu")
		(net "P5E_CPU1_P3_TX_DN<9>")
	)
	(gr_poly
		(pts
			(arc
				(start 120.737884 -274.896326)
				(mid 120.331484 -274.896326)
				(end 120.737884 -274.896326)
			)
		)
		(stroke
			(width 0)
			(type solid)
		)
		(fill yes)
		(layer "In10.Cu")
		(net "P5E_CPU1_P3_TX_DN<7>")
	)
	(gr_poly
		(pts
			(arc
				(start 120.737884 -273.276314)
				(mid 120.331484 -273.276314)
				(end 120.737884 -273.276314)
			)
		)
		(stroke
			(width 0)
			(type solid)
		)
		(fill yes)
		(layer "In10.Cu")
		(net "P5E_CPU1_P2_TX_DN<8>")
	)
	(gr_poly
		(pts
			(arc
				(start 120.737884 -271.656302)
				(mid 120.331484 -271.656302)
				(end 120.737884 -271.656302)
			)
		)
		(stroke
			(width 0)
			(type solid)
		)
		(fill yes)
		(layer "In10.Cu")
		(net "P5E_CPU1_P2_TX_DN<9>")
	)
	(gr_poly
		(pts
			(arc
				(start 120.737884 -270.03629)
				(mid 120.331484 -270.03629)
				(end 120.737884 -270.03629)
			)
		)
		(stroke
			(width 0)
			(type solid)
		)
		(fill yes)
		(layer "In10.Cu")
		(net "P5E_CPU1_P2_TX_DN<7>")
	)
	(gr_poly
		(pts
			(arc
				(start 122.617992 -278.13635)
				(mid 122.211592 -278.13635)
				(end 122.617992 -278.13635)
			)
		)
		(stroke
			(width 0)
			(type solid)
		)
		(fill yes)
		(layer "In10.Cu")
		(net "P5E_CPU1_P3_TX_DP<11>")
	)
	(gr_poly
		(pts
			(arc
				(start 122.617992 -276.516338)
				(mid 122.211592 -276.516338)
				(end 122.617992 -276.516338)
			)
		)
		(stroke
			(width 0)
			(type solid)
		)
		(fill yes)
		(layer "In10.Cu")
		(net "P5E_CPU1_P3_TX_DP<12>")
	)
	(gr_poly
		(pts
			(arc
				(start 122.617992 -274.896326)
				(mid 122.211592 -274.896326)
				(end 122.617992 -274.896326)
			)
		)
		(stroke
			(width 0)
			(type solid)
		)
		(fill yes)
		(layer "In10.Cu")
		(net "P5E_CPU1_P3_TX_DP<10>")
	)
	(gr_poly
		(pts
			(arc
				(start 122.617992 -273.276314)
				(mid 122.211592 -273.276314)
				(end 122.617992 -273.276314)
			)
		)
		(stroke
			(width 0)
			(type solid)
		)
		(fill yes)
		(layer "In10.Cu")
		(net "P5E_CPU1_P2_TX_DP<11>")
	)
	(gr_poly
		(pts
			(arc
				(start 122.617992 -271.656302)
				(mid 122.211592 -271.656302)
				(end 122.617992 -271.656302)
			)
		)
		(stroke
			(width 0)
			(type solid)
		)
		(fill yes)
		(layer "In10.Cu")
		(net "P5E_CPU1_P2_TX_DP<12>")
	)
	(gr_poly
		(pts
			(arc
				(start 122.617992 -270.03629)
				(mid 122.211592 -270.03629)
				(end 122.617992 -270.03629)
			)
		)
		(stroke
			(width 0)
			(type solid)
		)
		(fill yes)
		(layer "In10.Cu")
		(net "P5E_CPU1_P2_TX_DP<10>")
	)
	(gr_poly
		(pts
			(arc
				(start 123.558046 -278.13635)
				(mid 123.151646 -278.13635)
				(end 123.558046 -278.13635)
			)
		)
		(stroke
			(width 0)
			(type solid)
		)
		(fill yes)
		(layer "In10.Cu")
		(net "P5E_CPU1_P3_TX_DN<11>")
	)
	(gr_poly
		(pts
			(arc
				(start 123.558046 -276.516338)
				(mid 123.151646 -276.516338)
				(end 123.558046 -276.516338)
			)
		)
		(stroke
			(width 0)
			(type solid)
		)
		(fill yes)
		(layer "In10.Cu")
		(net "P5E_CPU1_P3_TX_DN<12>")
	)
	(gr_poly
		(pts
			(arc
				(start 123.558046 -274.896326)
				(mid 123.151646 -274.896326)
				(end 123.558046 -274.896326)
			)
		)
		(stroke
			(width 0)
			(type solid)
		)
		(fill yes)
		(layer "In10.Cu")
		(net "P5E_CPU1_P3_TX_DN<10>")
	)
	(gr_poly
		(pts
			(arc
				(start 123.558046 -273.276314)
				(mid 123.151646 -273.276314)
				(end 123.558046 -273.276314)
			)
		)
		(stroke
			(width 0)
			(type solid)
		)
		(fill yes)
		(layer "In10.Cu")
		(net "P5E_CPU1_P2_TX_DN<11>")
	)
	(gr_poly
		(pts
			(arc
				(start 123.558046 -271.656302)
				(mid 123.151646 -271.656302)
				(end 123.558046 -271.656302)
			)
		)
		(stroke
			(width 0)
			(type solid)
		)
		(fill yes)
		(layer "In10.Cu")
		(net "P5E_CPU1_P2_TX_DN<12>")
	)
	(gr_poly
		(pts
			(arc
				(start 123.558046 -270.03629)
				(mid 123.151646 -270.03629)
				(end 123.558046 -270.03629)
			)
		)
		(stroke
			(width 0)
			(type solid)
		)
		(fill yes)
		(layer "In10.Cu")
		(net "P5E_CPU1_P2_TX_DN<10>")
	)
	(gr_poly
		(pts
			(arc
				(start 125.4379 -278.13635)
				(mid 125.0315 -278.13635)
				(end 125.4379 -278.13635)
			)
		)
		(stroke
			(width 0)
			(type solid)
		)
		(fill yes)
		(layer "In10.Cu")
		(net "P5E_CPU1_P3_TX_DP<14>")
	)
	(gr_poly
		(pts
			(arc
				(start 125.4379 -276.516338)
				(mid 125.0315 -276.516338)
				(end 125.4379 -276.516338)
			)
		)
		(stroke
			(width 0)
			(type solid)
		)
		(fill yes)
		(layer "In10.Cu")
		(net "P5E_CPU1_P3_TX_DP<15>")
	)
	(gr_poly
		(pts
			(arc
				(start 125.4379 -274.896326)
				(mid 125.0315 -274.896326)
				(end 125.4379 -274.896326)
			)
		)
		(stroke
			(width 0)
			(type solid)
		)
		(fill yes)
		(layer "In10.Cu")
		(net "P5E_CPU1_P3_TX_DP<13>")
	)
	(gr_poly
		(pts
			(arc
				(start 125.4379 -273.276314)
				(mid 125.0315 -273.276314)
				(end 125.4379 -273.276314)
			)
		)
		(stroke
			(width 0)
			(type solid)
		)
		(fill yes)
		(layer "In10.Cu")
		(net "P5E_CPU1_P2_TX_DP<14>")
	)
	(gr_poly
		(pts
			(arc
				(start 125.4379 -271.656302)
				(mid 125.0315 -271.656302)
				(end 125.4379 -271.656302)
			)
		)
		(stroke
			(width 0)
			(type solid)
		)
		(fill yes)
		(layer "In10.Cu")
		(net "P5E_CPU1_P2_TX_DP<15>")
	)
	(gr_poly
		(pts
			(arc
				(start 125.4379 -270.03629)
				(mid 125.0315 -270.03629)
				(end 125.4379 -270.03629)
			)
		)
		(stroke
			(width 0)
			(type solid)
		)
		(fill yes)
		(layer "In10.Cu")
		(net "P5E_CPU1_P2_TX_DP<13>")
	)
	(gr_poly
		(pts
			(arc
				(start 126.377954 -278.13635)
				(mid 125.971554 -278.13635)
				(end 126.377954 -278.13635)
			)
		)
		(stroke
			(width 0)
			(type solid)
		)
		(fill yes)
		(layer "In10.Cu")
		(net "P5E_CPU1_P3_TX_DN<14>")
	)
	(gr_poly
		(pts
			(arc
				(start 126.377954 -276.516338)
				(mid 125.971554 -276.516338)
				(end 126.377954 -276.516338)
			)
		)
		(stroke
			(width 0)
			(type solid)
		)
		(fill yes)
		(layer "In10.Cu")
		(net "P5E_CPU1_P3_TX_DN<15>")
	)
	(gr_poly
		(pts
			(arc
				(start 126.377954 -274.896326)
				(mid 125.971554 -274.896326)
				(end 126.377954 -274.896326)
			)
		)
		(stroke
			(width 0)
			(type solid)
		)
		(fill yes)
		(layer "In10.Cu")
		(net "P5E_CPU1_P3_TX_DN<13>")
	)
	(gr_poly
		(pts
			(arc
				(start 126.377954 -273.276314)
				(mid 125.971554 -273.276314)
				(end 126.377954 -273.276314)
			)
		)
		(stroke
			(width 0)
			(type solid)
		)
		(fill yes)
		(layer "In10.Cu")
		(net "P5E_CPU1_P2_TX_DN<14>")
	)
	(gr_poly
		(pts
			(arc
				(start 126.377954 -271.656302)
				(mid 125.971554 -271.656302)
				(end 126.377954 -271.656302)
			)
		)
		(stroke
			(width 0)
			(type solid)
		)
		(fill yes)
		(layer "In10.Cu")
		(net "P5E_CPU1_P2_TX_DN<15>")
	)
	(gr_poly
		(pts
			(arc
				(start 126.377954 -270.03629)
				(mid 125.971554 -270.03629)
				(end 126.377954 -270.03629)
			)
		)
		(stroke
			(width 0)
			(type solid)
		)
		(fill yes)
		(layer "In10.Cu")
		(net "P5E_CPU1_P2_TX_DN<13>")
	)
	(gr_poly
		(pts
			(arc
				(start 346.124276 -278.136096)
				(mid 345.717876 -278.136096)
				(end 346.124276 -278.136096)
			)
		)
		(stroke
			(width 0)
			(type solid)
		)
		(fill yes)
		(layer "In10.Cu")
		(net "P5E_CPU0_P1_RX_DN<1>")
	)
	(gr_poly
		(pts
			(arc
				(start 346.124276 -276.516084)
				(mid 345.717876 -276.516084)
				(end 346.124276 -276.516084)
			)
		)
		(stroke
			(width 0)
			(type solid)
		)
		(fill yes)
		(layer "In10.Cu")
		(net "P5E_CPU0_P1_RX_DN<0>")
	)
	(gr_poly
		(pts
			(arc
				(start 346.124276 -274.896072)
				(mid 345.717876 -274.896072)
				(end 346.124276 -274.896072)
			)
		)
		(stroke
			(width 0)
			(type solid)
		)
		(fill yes)
		(layer "In10.Cu")
		(net "P5E_CPU0_P1_RX_DN<2>")
	)
	(gr_poly
		(pts
			(arc
				(start 346.124276 -273.27606)
				(mid 345.717876 -273.27606)
				(end 346.124276 -273.27606)
			)
		)
		(stroke
			(width 0)
			(type solid)
		)
		(fill yes)
		(layer "In10.Cu")
		(net "P5E_CPU0_P0_RX_DN<1>")
	)
	(gr_poly
		(pts
			(arc
				(start 346.124276 -271.656048)
				(mid 345.717876 -271.656048)
				(end 346.124276 -271.656048)
			)
		)
		(stroke
			(width 0)
			(type solid)
		)
		(fill yes)
		(layer "In10.Cu")
		(net "P5E_CPU0_P0_RX_DN<0>")
	)
	(gr_poly
		(pts
			(arc
				(start 346.124276 -270.036036)
				(mid 345.717876 -270.036036)
				(end 346.124276 -270.036036)
			)
		)
		(stroke
			(width 0)
			(type solid)
		)
		(fill yes)
		(layer "In10.Cu")
		(net "P5E_CPU0_P0_RX_DN<2>")
	)
	(gr_poly
		(pts
			(arc
				(start 347.06433 -278.136096)
				(mid 346.65793 -278.136096)
				(end 347.06433 -278.136096)
			)
		)
		(stroke
			(width 0)
			(type solid)
		)
		(fill yes)
		(layer "In10.Cu")
		(net "P5E_CPU0_P1_RX_DP<1>")
	)
	(gr_poly
		(pts
			(arc
				(start 347.06433 -276.516084)
				(mid 346.65793 -276.516084)
				(end 347.06433 -276.516084)
			)
		)
		(stroke
			(width 0)
			(type solid)
		)
		(fill yes)
		(layer "In10.Cu")
		(net "P5E_CPU0_P1_RX_DP<0>")
	)
	(gr_poly
		(pts
			(arc
				(start 347.06433 -274.896072)
				(mid 346.65793 -274.896072)
				(end 347.06433 -274.896072)
			)
		)
		(stroke
			(width 0)
			(type solid)
		)
		(fill yes)
		(layer "In10.Cu")
		(net "P5E_CPU0_P1_RX_DP<2>")
	)
	(gr_poly
		(pts
			(arc
				(start 347.06433 -273.27606)
				(mid 346.65793 -273.27606)
				(end 347.06433 -273.27606)
			)
		)
		(stroke
			(width 0)
			(type solid)
		)
		(fill yes)
		(layer "In10.Cu")
		(net "P5E_CPU0_P0_RX_DP<1>")
	)
	(gr_poly
		(pts
			(arc
				(start 347.06433 -271.656048)
				(mid 346.65793 -271.656048)
				(end 347.06433 -271.656048)
			)
		)
		(stroke
			(width 0)
			(type solid)
		)
		(fill yes)
		(layer "In10.Cu")
		(net "P5E_CPU0_P0_RX_DP<0>")
	)
	(gr_poly
		(pts
			(arc
				(start 347.06433 -270.036036)
				(mid 346.65793 -270.036036)
				(end 347.06433 -270.036036)
			)
		)
		(stroke
			(width 0)
			(type solid)
		)
		(fill yes)
		(layer "In10.Cu")
		(net "P5E_CPU0_P0_RX_DP<2>")
	)
	(gr_poly
		(pts
			(arc
				(start 348.944184 -278.136096)
				(mid 348.537784 -278.136096)
				(end 348.944184 -278.136096)
			)
		)
		(stroke
			(width 0)
			(type solid)
		)
		(fill yes)
		(layer "In10.Cu")
		(net "P5E_CPU0_P1_RX_DN<4>")
	)
	(gr_poly
		(pts
			(arc
				(start 348.944184 -276.516084)
				(mid 348.537784 -276.516084)
				(end 348.944184 -276.516084)
			)
		)
		(stroke
			(width 0)
			(type solid)
		)
		(fill yes)
		(layer "In10.Cu")
		(net "P5E_CPU0_P1_RX_DN<3>")
	)
	(gr_poly
		(pts
			(arc
				(start 348.944184 -274.896072)
				(mid 348.537784 -274.896072)
				(end 348.944184 -274.896072)
			)
		)
		(stroke
			(width 0)
			(type solid)
		)
		(fill yes)
		(layer "In10.Cu")
		(net "P5E_CPU0_P1_RX_DN<5>")
	)
	(gr_poly
		(pts
			(arc
				(start 348.944184 -273.27606)
				(mid 348.537784 -273.27606)
				(end 348.944184 -273.27606)
			)
		)
		(stroke
			(width 0)
			(type solid)
		)
		(fill yes)
		(layer "In10.Cu")
		(net "P5E_CPU0_P0_RX_DN<4>")
	)
	(gr_poly
		(pts
			(arc
				(start 348.944184 -271.656048)
				(mid 348.537784 -271.656048)
				(end 348.944184 -271.656048)
			)
		)
		(stroke
			(width 0)
			(type solid)
		)
		(fill yes)
		(layer "In10.Cu")
		(net "P5E_CPU0_P0_RX_DN<3>")
	)
	(gr_poly
		(pts
			(arc
				(start 348.944184 -270.036036)
				(mid 348.537784 -270.036036)
				(end 348.944184 -270.036036)
			)
		)
		(stroke
			(width 0)
			(type solid)
		)
		(fill yes)
		(layer "In10.Cu")
		(net "P5E_CPU0_P0_RX_DN<5>")
	)
	(gr_poly
		(pts
			(arc
				(start 349.884238 -278.136096)
				(mid 349.477838 -278.136096)
				(end 349.884238 -278.136096)
			)
		)
		(stroke
			(width 0)
			(type solid)
		)
		(fill yes)
		(layer "In10.Cu")
		(net "P5E_CPU0_P1_RX_DP<4>")
	)
	(gr_poly
		(pts
			(arc
				(start 349.884238 -276.516084)
				(mid 349.477838 -276.516084)
				(end 349.884238 -276.516084)
			)
		)
		(stroke
			(width 0)
			(type solid)
		)
		(fill yes)
		(layer "In10.Cu")
		(net "P5E_CPU0_P1_RX_DP<3>")
	)
	(gr_poly
		(pts
			(arc
				(start 349.884238 -274.896072)
				(mid 349.477838 -274.896072)
				(end 349.884238 -274.896072)
			)
		)
		(stroke
			(width 0)
			(type solid)
		)
		(fill yes)
		(layer "In10.Cu")
		(net "P5E_CPU0_P1_RX_DP<5>")
	)
	(gr_poly
		(pts
			(arc
				(start 349.884238 -273.27606)
				(mid 349.477838 -273.27606)
				(end 349.884238 -273.27606)
			)
		)
		(stroke
			(width 0)
			(type solid)
		)
		(fill yes)
		(layer "In10.Cu")
		(net "P5E_CPU0_P0_RX_DP<4>")
	)
	(gr_poly
		(pts
			(arc
				(start 349.884238 -271.656048)
				(mid 349.477838 -271.656048)
				(end 349.884238 -271.656048)
			)
		)
		(stroke
			(width 0)
			(type solid)
		)
		(fill yes)
		(layer "In10.Cu")
		(net "P5E_CPU0_P0_RX_DP<3>")
	)
	(gr_poly
		(pts
			(arc
				(start 349.884238 -270.036036)
				(mid 349.477838 -270.036036)
				(end 349.884238 -270.036036)
			)
		)
		(stroke
			(width 0)
			(type solid)
		)
		(fill yes)
		(layer "In10.Cu")
		(net "P5E_CPU0_P0_RX_DP<5>")
	)
	(gr_poly
		(pts
			(arc
				(start 351.764346 -278.136096)
				(mid 351.357946 -278.136096)
				(end 351.764346 -278.136096)
			)
		)
		(stroke
			(width 0)
			(type solid)
		)
		(fill yes)
		(layer "In10.Cu")
		(net "P5E_CPU0_P1_RX_DN<7>")
	)
	(gr_poly
		(pts
			(arc
				(start 351.764346 -276.516084)
				(mid 351.357946 -276.516084)
				(end 351.764346 -276.516084)
			)
		)
		(stroke
			(width 0)
			(type solid)
		)
		(fill yes)
		(layer "In10.Cu")
		(net "P5E_CPU0_P1_RX_DN<6>")
	)
	(gr_poly
		(pts
			(arc
				(start 351.764346 -274.896072)
				(mid 351.357946 -274.896072)
				(end 351.764346 -274.896072)
			)
		)
		(stroke
			(width 0)
			(type solid)
		)
		(fill yes)
		(layer "In10.Cu")
		(net "P5E_CPU0_P1_RX_DN<8>")
	)
	(gr_poly
		(pts
			(arc
				(start 351.764346 -273.27606)
				(mid 351.357946 -273.27606)
				(end 351.764346 -273.27606)
			)
		)
		(stroke
			(width 0)
			(type solid)
		)
		(fill yes)
		(layer "In10.Cu")
		(net "P5E_CPU0_P0_RX_DN<7>")
	)
	(gr_poly
		(pts
			(arc
				(start 351.764346 -271.656048)
				(mid 351.357946 -271.656048)
				(end 351.764346 -271.656048)
			)
		)
		(stroke
			(width 0)
			(type solid)
		)
		(fill yes)
		(layer "In10.Cu")
		(net "P5E_CPU0_P0_RX_DN<6>")
	)
	(gr_poly
		(pts
			(arc
				(start 351.764346 -270.036036)
				(mid 351.357946 -270.036036)
				(end 351.764346 -270.036036)
			)
		)
		(stroke
			(width 0)
			(type solid)
		)
		(fill yes)
		(layer "In10.Cu")
		(net "P5E_CPU0_P0_RX_DN<8>")
	)
	(gr_poly
		(pts
			(arc
				(start 352.7044 -278.136096)
				(mid 352.298 -278.136096)
				(end 352.7044 -278.136096)
			)
		)
		(stroke
			(width 0)
			(type solid)
		)
		(fill yes)
		(layer "In10.Cu")
		(net "P5E_CPU0_P1_RX_DP<7>")
	)
	(gr_poly
		(pts
			(arc
				(start 352.7044 -276.516084)
				(mid 352.298 -276.516084)
				(end 352.7044 -276.516084)
			)
		)
		(stroke
			(width 0)
			(type solid)
		)
		(fill yes)
		(layer "In10.Cu")
		(net "P5E_CPU0_P1_RX_DP<6>")
	)
	(gr_poly
		(pts
			(arc
				(start 352.7044 -274.896072)
				(mid 352.298 -274.896072)
				(end 352.7044 -274.896072)
			)
		)
		(stroke
			(width 0)
			(type solid)
		)
		(fill yes)
		(layer "In10.Cu")
		(net "P5E_CPU0_P1_RX_DP<8>")
	)
	(gr_poly
		(pts
			(arc
				(start 352.7044 -273.27606)
				(mid 352.298 -273.27606)
				(end 352.7044 -273.27606)
			)
		)
		(stroke
			(width 0)
			(type solid)
		)
		(fill yes)
		(layer "In10.Cu")
		(net "P5E_CPU0_P0_RX_DP<7>")
	)
	(gr_poly
		(pts
			(arc
				(start 352.7044 -271.656048)
				(mid 352.298 -271.656048)
				(end 352.7044 -271.656048)
			)
		)
		(stroke
			(width 0)
			(type solid)
		)
		(fill yes)
		(layer "In10.Cu")
		(net "P5E_CPU0_P0_RX_DP<6>")
	)
	(gr_poly
		(pts
			(arc
				(start 352.7044 -270.036036)
				(mid 352.298 -270.036036)
				(end 352.7044 -270.036036)
			)
		)
		(stroke
			(width 0)
			(type solid)
		)
		(fill yes)
		(layer "In10.Cu")
		(net "P5E_CPU0_P0_RX_DP<8>")
	)
	(gr_poly
		(pts
			(arc
				(start 354.584254 -279.756108)
				(mid 354.177854 -279.756108)
				(end 354.584254 -279.756108)
			)
		)
		(stroke
			(width 0)
			(type solid)
		)
		(fill yes)
		(layer "In10.Cu")
		(net "P5E_CPU0_P1_RX_DN<11>")
	)
	(gr_poly
		(pts
			(arc
				(start 354.584254 -278.136096)
				(mid 354.177854 -278.136096)
				(end 354.584254 -278.136096)
			)
		)
		(stroke
			(width 0)
			(type solid)
		)
		(fill yes)
		(layer "In10.Cu")
		(net "P5E_CPU0_P1_RX_DN<10>")
	)
	(gr_poly
		(pts
			(arc
				(start 354.584254 -276.516084)
				(mid 354.177854 -276.516084)
				(end 354.584254 -276.516084)
			)
		)
		(stroke
			(width 0)
			(type solid)
		)
		(fill yes)
		(layer "In10.Cu")
		(net "P5E_CPU0_P1_RX_DN<9>")
	)
	(gr_poly
		(pts
			(arc
				(start 354.584254 -274.896072)
				(mid 354.177854 -274.896072)
				(end 354.584254 -274.896072)
			)
		)
		(stroke
			(width 0)
			(type solid)
		)
		(fill yes)
		(layer "In10.Cu")
		(net "P5E_CPU0_P1_RX_DN<12>")
	)
	(gr_poly
		(pts
			(arc
				(start 354.584254 -273.27606)
				(mid 354.177854 -273.27606)
				(end 354.584254 -273.27606)
			)
		)
		(stroke
			(width 0)
			(type solid)
		)
		(fill yes)
		(layer "In10.Cu")
		(net "P5E_CPU0_P0_RX_DN<10>")
	)
	(gr_poly
		(pts
			(arc
				(start 354.584254 -271.656048)
				(mid 354.177854 -271.656048)
				(end 354.584254 -271.656048)
			)
		)
		(stroke
			(width 0)
			(type solid)
		)
		(fill yes)
		(layer "In10.Cu")
		(net "P5E_CPU0_P0_RX_DN<9>")
	)
	(gr_poly
		(pts
			(arc
				(start 354.584254 -270.036036)
				(mid 354.177854 -270.036036)
				(end 354.584254 -270.036036)
			)
		)
		(stroke
			(width 0)
			(type solid)
		)
		(fill yes)
		(layer "In10.Cu")
		(net "P5E_CPU0_P0_RX_DN<11>")
	)
	(gr_poly
		(pts
			(arc
				(start 355.524308 -279.756108)
				(mid 355.117908 -279.756108)
				(end 355.524308 -279.756108)
			)
		)
		(stroke
			(width 0)
			(type solid)
		)
		(fill yes)
		(layer "In10.Cu")
		(net "P5E_CPU0_P1_RX_DP<11>")
	)
	(gr_poly
		(pts
			(arc
				(start 355.524308 -278.136096)
				(mid 355.117908 -278.136096)
				(end 355.524308 -278.136096)
			)
		)
		(stroke
			(width 0)
			(type solid)
		)
		(fill yes)
		(layer "In10.Cu")
		(net "P5E_CPU0_P1_RX_DP<10>")
	)
	(gr_poly
		(pts
			(arc
				(start 355.524308 -276.516084)
				(mid 355.117908 -276.516084)
				(end 355.524308 -276.516084)
			)
		)
		(stroke
			(width 0)
			(type solid)
		)
		(fill yes)
		(layer "In10.Cu")
		(net "P5E_CPU0_P1_RX_DP<9>")
	)
	(gr_poly
		(pts
			(arc
				(start 355.524308 -274.896072)
				(mid 355.117908 -274.896072)
				(end 355.524308 -274.896072)
			)
		)
		(stroke
			(width 0)
			(type solid)
		)
		(fill yes)
		(layer "In10.Cu")
		(net "P5E_CPU0_P1_RX_DP<12>")
	)
	(gr_poly
		(pts
			(arc
				(start 355.524308 -273.27606)
				(mid 355.117908 -273.27606)
				(end 355.524308 -273.27606)
			)
		)
		(stroke
			(width 0)
			(type solid)
		)
		(fill yes)
		(layer "In10.Cu")
		(net "P5E_CPU0_P0_RX_DP<10>")
	)
	(gr_poly
		(pts
			(arc
				(start 355.524308 -271.656048)
				(mid 355.117908 -271.656048)
				(end 355.524308 -271.656048)
			)
		)
		(stroke
			(width 0)
			(type solid)
		)
		(fill yes)
		(layer "In10.Cu")
		(net "P5E_CPU0_P0_RX_DP<9>")
	)
	(gr_poly
		(pts
			(arc
				(start 355.524308 -270.036036)
				(mid 355.117908 -270.036036)
				(end 355.524308 -270.036036)
			)
		)
		(stroke
			(width 0)
			(type solid)
		)
		(fill yes)
		(layer "In10.Cu")
		(net "P5E_CPU0_P0_RX_DP<11>")
	)
	(gr_poly
		(pts
			(arc
				(start 356.934262 -278.946102)
				(mid 356.527862 -278.946102)
				(end 356.934262 -278.946102)
			)
		)
		(stroke
			(width 0)
			(type solid)
		)
		(fill yes)
		(layer "In10.Cu")
		(net "P5E_CPU0_P1_RX_DN<13>")
	)
	(gr_poly
		(pts
			(arc
				(start 356.934262 -277.32609)
				(mid 356.527862 -277.32609)
				(end 356.934262 -277.32609)
			)
		)
		(stroke
			(width 0)
			(type solid)
		)
		(fill yes)
		(layer "In10.Cu")
		(net "P5E_CPU0_P1_RX_DN<14>")
	)
	(gr_poly
		(pts
			(arc
				(start 356.934262 -275.706078)
				(mid 356.527862 -275.706078)
				(end 356.934262 -275.706078)
			)
		)
		(stroke
			(width 0)
			(type solid)
		)
		(fill yes)
		(layer "In10.Cu")
		(net "P5E_CPU0_P1_RX_DN<15>")
	)
	(gr_poly
		(pts
			(arc
				(start 356.934262 -274.086066)
				(mid 356.527862 -274.086066)
				(end 356.934262 -274.086066)
			)
		)
		(stroke
			(width 0)
			(type solid)
		)
		(fill yes)
		(layer "In10.Cu")
		(net "P5E_CPU0_P0_RX_DN<13>")
	)
	(gr_poly
		(pts
			(arc
				(start 356.934262 -272.466054)
				(mid 356.527862 -272.466054)
				(end 356.934262 -272.466054)
			)
		)
		(stroke
			(width 0)
			(type solid)
		)
		(fill yes)
		(layer "In10.Cu")
		(net "P5E_CPU0_P0_RX_DN<12>")
	)
	(gr_poly
		(pts
			(arc
				(start 356.934262 -270.846042)
				(mid 356.527862 -270.846042)
				(end 356.934262 -270.846042)
			)
		)
		(stroke
			(width 0)
			(type solid)
		)
		(fill yes)
		(layer "In10.Cu")
		(net "P5E_CPU0_P0_RX_DN<14>")
	)
	(gr_poly
		(pts
			(arc
				(start 356.934262 -269.22603)
				(mid 356.527862 -269.22603)
				(end 356.934262 -269.22603)
			)
		)
		(stroke
			(width 0)
			(type solid)
		)
		(fill yes)
		(layer "In10.Cu")
		(net "P5E_CPU0_P0_RX_DN<15>")
	)
	(gr_poly
		(pts
			(arc
				(start 357.874316 -278.946102)
				(mid 357.467916 -278.946102)
				(end 357.874316 -278.946102)
			)
		)
		(stroke
			(width 0)
			(type solid)
		)
		(fill yes)
		(layer "In10.Cu")
		(net "P5E_CPU0_P1_RX_DP<13>")
	)
	(gr_poly
		(pts
			(arc
				(start 357.874316 -277.32609)
				(mid 357.467916 -277.32609)
				(end 357.874316 -277.32609)
			)
		)
		(stroke
			(width 0)
			(type solid)
		)
		(fill yes)
		(layer "In10.Cu")
		(net "P5E_CPU0_P1_RX_DP<14>")
	)
	(gr_poly
		(pts
			(arc
				(start 357.874316 -275.706078)
				(mid 357.467916 -275.706078)
				(end 357.874316 -275.706078)
			)
		)
		(stroke
			(width 0)
			(type solid)
		)
		(fill yes)
		(layer "In10.Cu")
		(net "P5E_CPU0_P1_RX_DP<15>")
	)
	(gr_poly
		(pts
			(arc
				(start 357.874316 -274.086066)
				(mid 357.467916 -274.086066)
				(end 357.874316 -274.086066)
			)
		)
		(stroke
			(width 0)
			(type solid)
		)
		(fill yes)
		(layer "In10.Cu")
		(net "P5E_CPU0_P0_RX_DP<13>")
	)
	(gr_poly
		(pts
			(arc
				(start 357.874316 -272.466054)
				(mid 357.467916 -272.466054)
				(end 357.874316 -272.466054)
			)
		)
		(stroke
			(width 0)
			(type solid)
		)
		(fill yes)
		(layer "In10.Cu")
		(net "P5E_CPU0_P0_RX_DP<12>")
	)
	(gr_poly
		(pts
			(arc
				(start 357.874316 -270.846042)
				(mid 357.467916 -270.846042)
				(end 357.874316 -270.846042)
			)
		)
		(stroke
			(width 0)
			(type solid)
		)
		(fill yes)
		(layer "In10.Cu")
		(net "P5E_CPU0_P0_RX_DP<14>")
	)
	(gr_poly
		(pts
			(arc
				(start 357.874316 -269.22603)
				(mid 357.467916 -269.22603)
				(end 357.874316 -269.22603)
			)
		)
		(stroke
			(width 0)
			(type solid)
		)
		(fill yes)
		(layer "In10.Cu")
		(net "P5E_CPU0_P0_RX_DP<15>")
	)
	(gr_poly
		(pts
			(arc
				(start 362.567982 -278.946102)
				(mid 362.161582 -278.946102)
				(end 362.567982 -278.946102)
			)
		)
		(stroke
			(width 0)
			(type solid)
		)
		(fill yes)
		(layer "In10.Cu")
		(net "P5E_CPU0_P3_TX_DP<2>")
	)
	(gr_poly
		(pts
			(arc
				(start 362.567982 -277.32609)
				(mid 362.161582 -277.32609)
				(end 362.567982 -277.32609)
			)
		)
		(stroke
			(width 0)
			(type solid)
		)
		(fill yes)
		(layer "In10.Cu")
		(net "P5E_CPU0_P3_TX_DP<1>")
	)
	(gr_poly
		(pts
			(arc
				(start 362.567982 -275.706078)
				(mid 362.161582 -275.706078)
				(end 362.567982 -275.706078)
			)
		)
		(stroke
			(width 0)
			(type solid)
		)
		(fill yes)
		(layer "In10.Cu")
		(net "P5E_CPU0_P3_TX_DP<0>")
	)
	(gr_poly
		(pts
			(arc
				(start 362.567982 -274.086066)
				(mid 362.161582 -274.086066)
				(end 362.567982 -274.086066)
			)
		)
		(stroke
			(width 0)
			(type solid)
		)
		(fill yes)
		(layer "In10.Cu")
		(net "P5E_CPU0_P2_TX_DP<2>")
	)
	(gr_poly
		(pts
			(arc
				(start 362.567982 -272.466054)
				(mid 362.161582 -272.466054)
				(end 362.567982 -272.466054)
			)
		)
		(stroke
			(width 0)
			(type solid)
		)
		(fill yes)
		(layer "In10.Cu")
		(net "P5E_CPU0_P2_TX_DP<3>")
	)
	(gr_poly
		(pts
			(arc
				(start 362.567982 -270.846042)
				(mid 362.161582 -270.846042)
				(end 362.567982 -270.846042)
			)
		)
		(stroke
			(width 0)
			(type solid)
		)
		(fill yes)
		(layer "In10.Cu")
		(net "P5E_CPU0_P2_TX_DP<1>")
	)
	(gr_poly
		(pts
			(arc
				(start 362.567982 -269.22603)
				(mid 362.161582 -269.22603)
				(end 362.567982 -269.22603)
			)
		)
		(stroke
			(width 0)
			(type solid)
		)
		(fill yes)
		(layer "In10.Cu")
		(net "P5E_CPU0_P2_TX_DP<0>")
	)
	(gr_poly
		(pts
			(arc
				(start 363.508036 -278.946102)
				(mid 363.101636 -278.946102)
				(end 363.508036 -278.946102)
			)
		)
		(stroke
			(width 0)
			(type solid)
		)
		(fill yes)
		(layer "In10.Cu")
		(net "P5E_CPU0_P3_TX_DN<2>")
	)
	(gr_poly
		(pts
			(arc
				(start 363.508036 -277.32609)
				(mid 363.101636 -277.32609)
				(end 363.508036 -277.32609)
			)
		)
		(stroke
			(width 0)
			(type solid)
		)
		(fill yes)
		(layer "In10.Cu")
		(net "P5E_CPU0_P3_TX_DN<1>")
	)
	(gr_poly
		(pts
			(arc
				(start 363.508036 -275.706078)
				(mid 363.101636 -275.706078)
				(end 363.508036 -275.706078)
			)
		)
		(stroke
			(width 0)
			(type solid)
		)
		(fill yes)
		(layer "In10.Cu")
		(net "P5E_CPU0_P3_TX_DN<0>")
	)
	(gr_poly
		(pts
			(arc
				(start 363.508036 -274.086066)
				(mid 363.101636 -274.086066)
				(end 363.508036 -274.086066)
			)
		)
		(stroke
			(width 0)
			(type solid)
		)
		(fill yes)
		(layer "In10.Cu")
		(net "P5E_CPU0_P2_TX_DN<2>")
	)
	(gr_poly
		(pts
			(arc
				(start 363.508036 -272.466054)
				(mid 363.101636 -272.466054)
				(end 363.508036 -272.466054)
			)
		)
		(stroke
			(width 0)
			(type solid)
		)
		(fill yes)
		(layer "In10.Cu")
		(net "P5E_CPU0_P2_TX_DN<3>")
	)
	(gr_poly
		(pts
			(arc
				(start 363.508036 -270.846042)
				(mid 363.101636 -270.846042)
				(end 363.508036 -270.846042)
			)
		)
		(stroke
			(width 0)
			(type solid)
		)
		(fill yes)
		(layer "In10.Cu")
		(net "P5E_CPU0_P2_TX_DN<1>")
	)
	(gr_poly
		(pts
			(arc
				(start 363.508036 -269.22603)
				(mid 363.101636 -269.22603)
				(end 363.508036 -269.22603)
			)
		)
		(stroke
			(width 0)
			(type solid)
		)
		(fill yes)
		(layer "In10.Cu")
		(net "P5E_CPU0_P2_TX_DN<0>")
	)
	(gr_poly
		(pts
			(arc
				(start 364.91799 -279.756108)
				(mid 364.51159 -279.756108)
				(end 364.91799 -279.756108)
			)
		)
		(stroke
			(width 0)
			(type solid)
		)
		(fill yes)
		(layer "In10.Cu")
		(net "P5E_CPU0_P3_TX_DP<4>")
	)
	(gr_poly
		(pts
			(arc
				(start 364.91799 -278.136096)
				(mid 364.51159 -278.136096)
				(end 364.91799 -278.136096)
			)
		)
		(stroke
			(width 0)
			(type solid)
		)
		(fill yes)
		(layer "In10.Cu")
		(net "P5E_CPU0_P3_TX_DP<5>")
	)
	(gr_poly
		(pts
			(arc
				(start 364.91799 -276.516084)
				(mid 364.51159 -276.516084)
				(end 364.91799 -276.516084)
			)
		)
		(stroke
			(width 0)
			(type solid)
		)
		(fill yes)
		(layer "In10.Cu")
		(net "P5E_CPU0_P3_TX_DP<6>")
	)
	(gr_poly
		(pts
			(arc
				(start 364.91799 -274.896072)
				(mid 364.51159 -274.896072)
				(end 364.91799 -274.896072)
			)
		)
		(stroke
			(width 0)
			(type solid)
		)
		(fill yes)
		(layer "In10.Cu")
		(net "P5E_CPU0_P3_TX_DP<3>")
	)
	(gr_poly
		(pts
			(arc
				(start 364.91799 -273.27606)
				(mid 364.51159 -273.27606)
				(end 364.91799 -273.27606)
			)
		)
		(stroke
			(width 0)
			(type solid)
		)
		(fill yes)
		(layer "In10.Cu")
		(net "P5E_CPU0_P2_TX_DP<5>")
	)
	(gr_poly
		(pts
			(arc
				(start 364.91799 -271.656048)
				(mid 364.51159 -271.656048)
				(end 364.91799 -271.656048)
			)
		)
		(stroke
			(width 0)
			(type solid)
		)
		(fill yes)
		(layer "In10.Cu")
		(net "P5E_CPU0_P2_TX_DP<6>")
	)
	(gr_poly
		(pts
			(arc
				(start 364.91799 -270.036036)
				(mid 364.51159 -270.036036)
				(end 364.91799 -270.036036)
			)
		)
		(stroke
			(width 0)
			(type solid)
		)
		(fill yes)
		(layer "In10.Cu")
		(net "P5E_CPU0_P2_TX_DP<4>")
	)
	(gr_poly
		(pts
			(arc
				(start 365.858044 -279.756108)
				(mid 365.451644 -279.756108)
				(end 365.858044 -279.756108)
			)
		)
		(stroke
			(width 0)
			(type solid)
		)
		(fill yes)
		(layer "In10.Cu")
		(net "P5E_CPU0_P3_TX_DN<4>")
	)
	(gr_poly
		(pts
			(arc
				(start 365.858044 -278.136096)
				(mid 365.451644 -278.136096)
				(end 365.858044 -278.136096)
			)
		)
		(stroke
			(width 0)
			(type solid)
		)
		(fill yes)
		(layer "In10.Cu")
		(net "P5E_CPU0_P3_TX_DN<5>")
	)
	(gr_poly
		(pts
			(arc
				(start 365.858044 -276.516084)
				(mid 365.451644 -276.516084)
				(end 365.858044 -276.516084)
			)
		)
		(stroke
			(width 0)
			(type solid)
		)
		(fill yes)
		(layer "In10.Cu")
		(net "P5E_CPU0_P3_TX_DN<6>")
	)
	(gr_poly
		(pts
			(arc
				(start 365.858044 -274.896072)
				(mid 365.451644 -274.896072)
				(end 365.858044 -274.896072)
			)
		)
		(stroke
			(width 0)
			(type solid)
		)
		(fill yes)
		(layer "In10.Cu")
		(net "P5E_CPU0_P3_TX_DN<3>")
	)
	(gr_poly
		(pts
			(arc
				(start 365.858044 -273.27606)
				(mid 365.451644 -273.27606)
				(end 365.858044 -273.27606)
			)
		)
		(stroke
			(width 0)
			(type solid)
		)
		(fill yes)
		(layer "In10.Cu")
		(net "P5E_CPU0_P2_TX_DN<5>")
	)
	(gr_poly
		(pts
			(arc
				(start 365.858044 -271.656048)
				(mid 365.451644 -271.656048)
				(end 365.858044 -271.656048)
			)
		)
		(stroke
			(width 0)
			(type solid)
		)
		(fill yes)
		(layer "In10.Cu")
		(net "P5E_CPU0_P2_TX_DN<6>")
	)
	(gr_poly
		(pts
			(arc
				(start 365.858044 -270.036036)
				(mid 365.451644 -270.036036)
				(end 365.858044 -270.036036)
			)
		)
		(stroke
			(width 0)
			(type solid)
		)
		(fill yes)
		(layer "In10.Cu")
		(net "P5E_CPU0_P2_TX_DN<4>")
	)
	(gr_poly
		(pts
			(arc
				(start 367.737898 -278.136096)
				(mid 367.331498 -278.136096)
				(end 367.737898 -278.136096)
			)
		)
		(stroke
			(width 0)
			(type solid)
		)
		(fill yes)
		(layer "In10.Cu")
		(net "P5E_CPU0_P3_TX_DP<8>")
	)
	(gr_poly
		(pts
			(arc
				(start 367.737898 -276.516084)
				(mid 367.331498 -276.516084)
				(end 367.737898 -276.516084)
			)
		)
		(stroke
			(width 0)
			(type solid)
		)
		(fill yes)
		(layer "In10.Cu")
		(net "P5E_CPU0_P3_TX_DP<9>")
	)
	(gr_poly
		(pts
			(arc
				(start 367.737898 -274.896072)
				(mid 367.331498 -274.896072)
				(end 367.737898 -274.896072)
			)
		)
		(stroke
			(width 0)
			(type solid)
		)
		(fill yes)
		(layer "In10.Cu")
		(net "P5E_CPU0_P3_TX_DP<7>")
	)
	(gr_poly
		(pts
			(arc
				(start 367.737898 -273.27606)
				(mid 367.331498 -273.27606)
				(end 367.737898 -273.27606)
			)
		)
		(stroke
			(width 0)
			(type solid)
		)
		(fill yes)
		(layer "In10.Cu")
		(net "P5E_CPU0_P2_TX_DP<8>")
	)
	(gr_poly
		(pts
			(arc
				(start 367.737898 -271.656048)
				(mid 367.331498 -271.656048)
				(end 367.737898 -271.656048)
			)
		)
		(stroke
			(width 0)
			(type solid)
		)
		(fill yes)
		(layer "In10.Cu")
		(net "P5E_CPU0_P2_TX_DP<9>")
	)
	(gr_poly
		(pts
			(arc
				(start 367.737898 -270.036036)
				(mid 367.331498 -270.036036)
				(end 367.737898 -270.036036)
			)
		)
		(stroke
			(width 0)
			(type solid)
		)
		(fill yes)
		(layer "In10.Cu")
		(net "P5E_CPU0_P2_TX_DP<7>")
	)
	(gr_poly
		(pts
			(arc
				(start 368.677952 -278.136096)
				(mid 368.271552 -278.136096)
				(end 368.677952 -278.136096)
			)
		)
		(stroke
			(width 0)
			(type solid)
		)
		(fill yes)
		(layer "In10.Cu")
		(net "P5E_CPU0_P3_TX_DN<8>")
	)
	(gr_poly
		(pts
			(arc
				(start 368.677952 -276.516084)
				(mid 368.271552 -276.516084)
				(end 368.677952 -276.516084)
			)
		)
		(stroke
			(width 0)
			(type solid)
		)
		(fill yes)
		(layer "In10.Cu")
		(net "P5E_CPU0_P3_TX_DN<9>")
	)
	(gr_poly
		(pts
			(arc
				(start 368.677952 -274.896072)
				(mid 368.271552 -274.896072)
				(end 368.677952 -274.896072)
			)
		)
		(stroke
			(width 0)
			(type solid)
		)
		(fill yes)
		(layer "In10.Cu")
		(net "P5E_CPU0_P3_TX_DN<7>")
	)
	(gr_poly
		(pts
			(arc
				(start 368.677952 -273.27606)
				(mid 368.271552 -273.27606)
				(end 368.677952 -273.27606)
			)
		)
		(stroke
			(width 0)
			(type solid)
		)
		(fill yes)
		(layer "In10.Cu")
		(net "P5E_CPU0_P2_TX_DN<8>")
	)
	(gr_poly
		(pts
			(arc
				(start 368.677952 -271.656048)
				(mid 368.271552 -271.656048)
				(end 368.677952 -271.656048)
			)
		)
		(stroke
			(width 0)
			(type solid)
		)
		(fill yes)
		(layer "In10.Cu")
		(net "P5E_CPU0_P2_TX_DN<9>")
	)
	(gr_poly
		(pts
			(arc
				(start 368.677952 -270.036036)
				(mid 368.271552 -270.036036)
				(end 368.677952 -270.036036)
			)
		)
		(stroke
			(width 0)
			(type solid)
		)
		(fill yes)
		(layer "In10.Cu")
		(net "P5E_CPU0_P2_TX_DN<7>")
	)
	(gr_poly
		(pts
			(arc
				(start 370.55806 -278.136096)
				(mid 370.15166 -278.136096)
				(end 370.55806 -278.136096)
			)
		)
		(stroke
			(width 0)
			(type solid)
		)
		(fill yes)
		(layer "In10.Cu")
		(net "P5E_CPU0_P3_TX_DP<11>")
	)
	(gr_poly
		(pts
			(arc
				(start 370.55806 -276.516084)
				(mid 370.15166 -276.516084)
				(end 370.55806 -276.516084)
			)
		)
		(stroke
			(width 0)
			(type solid)
		)
		(fill yes)
		(layer "In10.Cu")
		(net "P5E_CPU0_P3_TX_DP<12>")
	)
	(gr_poly
		(pts
			(arc
				(start 370.55806 -274.896072)
				(mid 370.15166 -274.896072)
				(end 370.55806 -274.896072)
			)
		)
		(stroke
			(width 0)
			(type solid)
		)
		(fill yes)
		(layer "In10.Cu")
		(net "P5E_CPU0_P3_TX_DP<10>")
	)
	(gr_poly
		(pts
			(arc
				(start 370.55806 -273.27606)
				(mid 370.15166 -273.27606)
				(end 370.55806 -273.27606)
			)
		)
		(stroke
			(width 0)
			(type solid)
		)
		(fill yes)
		(layer "In10.Cu")
		(net "P5E_CPU0_P2_TX_DP<11>")
	)
	(gr_poly
		(pts
			(arc
				(start 370.55806 -271.656048)
				(mid 370.15166 -271.656048)
				(end 370.55806 -271.656048)
			)
		)
		(stroke
			(width 0)
			(type solid)
		)
		(fill yes)
		(layer "In10.Cu")
		(net "P5E_CPU0_P2_TX_DP<12>")
	)
	(gr_poly
		(pts
			(arc
				(start 370.55806 -270.036036)
				(mid 370.15166 -270.036036)
				(end 370.55806 -270.036036)
			)
		)
		(stroke
			(width 0)
			(type solid)
		)
		(fill yes)
		(layer "In10.Cu")
		(net "P5E_CPU0_P2_TX_DP<10>")
	)
	(gr_poly
		(pts
			(arc
				(start 371.498114 -278.136096)
				(mid 371.091714 -278.136096)
				(end 371.498114 -278.136096)
			)
		)
		(stroke
			(width 0)
			(type solid)
		)
		(fill yes)
		(layer "In10.Cu")
		(net "P5E_CPU0_P3_TX_DN<11>")
	)
	(gr_poly
		(pts
			(arc
				(start 371.498114 -276.516084)
				(mid 371.091714 -276.516084)
				(end 371.498114 -276.516084)
			)
		)
		(stroke
			(width 0)
			(type solid)
		)
		(fill yes)
		(layer "In10.Cu")
		(net "P5E_CPU0_P3_TX_DN<12>")
	)
	(gr_poly
		(pts
			(arc
				(start 371.498114 -274.896072)
				(mid 371.091714 -274.896072)
				(end 371.498114 -274.896072)
			)
		)
		(stroke
			(width 0)
			(type solid)
		)
		(fill yes)
		(layer "In10.Cu")
		(net "P5E_CPU0_P3_TX_DN<10>")
	)
	(gr_poly
		(pts
			(arc
				(start 371.498114 -273.27606)
				(mid 371.091714 -273.27606)
				(end 371.498114 -273.27606)
			)
		)
		(stroke
			(width 0)
			(type solid)
		)
		(fill yes)
		(layer "In10.Cu")
		(net "P5E_CPU0_P2_TX_DN<11>")
	)
	(gr_poly
		(pts
			(arc
				(start 371.498114 -271.656048)
				(mid 371.091714 -271.656048)
				(end 371.498114 -271.656048)
			)
		)
		(stroke
			(width 0)
			(type solid)
		)
		(fill yes)
		(layer "In10.Cu")
		(net "P5E_CPU0_P2_TX_DN<12>")
	)
	(gr_poly
		(pts
			(arc
				(start 371.498114 -270.036036)
				(mid 371.091714 -270.036036)
				(end 371.498114 -270.036036)
			)
		)
		(stroke
			(width 0)
			(type solid)
		)
		(fill yes)
		(layer "In10.Cu")
		(net "P5E_CPU0_P2_TX_DN<10>")
	)
	(gr_poly
		(pts
			(arc
				(start 373.377968 -278.136096)
				(mid 372.971568 -278.136096)
				(end 373.377968 -278.136096)
			)
		)
		(stroke
			(width 0)
			(type solid)
		)
		(fill yes)
		(layer "In10.Cu")
		(net "P5E_CPU0_P3_TX_DP<14>")
	)
	(gr_poly
		(pts
			(arc
				(start 373.377968 -276.516084)
				(mid 372.971568 -276.516084)
				(end 373.377968 -276.516084)
			)
		)
		(stroke
			(width 0)
			(type solid)
		)
		(fill yes)
		(layer "In10.Cu")
		(net "P5E_CPU0_P3_TX_DP<15>")
	)
	(gr_poly
		(pts
			(arc
				(start 373.377968 -274.896072)
				(mid 372.971568 -274.896072)
				(end 373.377968 -274.896072)
			)
		)
		(stroke
			(width 0)
			(type solid)
		)
		(fill yes)
		(layer "In10.Cu")
		(net "P5E_CPU0_P3_TX_DP<13>")
	)
	(gr_poly
		(pts
			(arc
				(start 373.377968 -273.27606)
				(mid 372.971568 -273.27606)
				(end 373.377968 -273.27606)
			)
		)
		(stroke
			(width 0)
			(type solid)
		)
		(fill yes)
		(layer "In10.Cu")
		(net "P5E_CPU0_P2_TX_DP<14>")
	)
	(gr_poly
		(pts
			(arc
				(start 373.377968 -271.656048)
				(mid 372.971568 -271.656048)
				(end 373.377968 -271.656048)
			)
		)
		(stroke
			(width 0)
			(type solid)
		)
		(fill yes)
		(layer "In10.Cu")
		(net "P5E_CPU0_P2_TX_DP<15>")
	)
	(gr_poly
		(pts
			(arc
				(start 373.377968 -270.036036)
				(mid 372.971568 -270.036036)
				(end 373.377968 -270.036036)
			)
		)
		(stroke
			(width 0)
			(type solid)
		)
		(fill yes)
		(layer "In10.Cu")
		(net "P5E_CPU0_P2_TX_DP<13>")
	)
	(gr_poly
		(pts
			(arc
				(start 374.318022 -278.136096)
				(mid 373.911622 -278.136096)
				(end 374.318022 -278.136096)
			)
		)
		(stroke
			(width 0)
			(type solid)
		)
		(fill yes)
		(layer "In10.Cu")
		(net "P5E_CPU0_P3_TX_DN<14>")
	)
	(gr_poly
		(pts
			(arc
				(start 374.318022 -276.516084)
				(mid 373.911622 -276.516084)
				(end 374.318022 -276.516084)
			)
		)
		(stroke
			(width 0)
			(type solid)
		)
		(fill yes)
		(layer "In10.Cu")
		(net "P5E_CPU0_P3_TX_DN<15>")
	)
	(gr_poly
		(pts
			(arc
				(start 374.318022 -274.896072)
				(mid 373.911622 -274.896072)
				(end 374.318022 -274.896072)
			)
		)
		(stroke
			(width 0)
			(type solid)
		)
		(fill yes)
		(layer "In10.Cu")
		(net "P5E_CPU0_P3_TX_DN<13>")
	)
	(gr_poly
		(pts
			(arc
				(start 374.318022 -273.27606)
				(mid 373.911622 -273.27606)
				(end 374.318022 -273.27606)
			)
		)
		(stroke
			(width 0)
			(type solid)
		)
		(fill yes)
		(layer "In10.Cu")
		(net "P5E_CPU0_P2_TX_DN<14>")
	)
	(gr_poly
		(pts
			(arc
				(start 374.318022 -271.656048)
				(mid 373.911622 -271.656048)
				(end 374.318022 -271.656048)
			)
		)
		(stroke
			(width 0)
			(type solid)
		)
		(fill yes)
		(layer "In10.Cu")
		(net "P5E_CPU0_P2_TX_DN<15>")
	)
	(gr_poly
		(pts
			(arc
				(start 374.318022 -270.036036)
				(mid 373.911622 -270.036036)
				(end 374.318022 -270.036036)
			)
		)
		(stroke
			(width 0)
			(type solid)
		)
		(fill yes)
		(layer "In10.Cu")
		(net "P5E_CPU0_P2_TX_DN<13>")
	)
	(gr_poly
		(pts
			(arc
				(start 273.15541 -393.27836)
				(mid 273.174933 -393.274459)
				(end 273.191478 -393.263374)
			)
			(xy 273.191732 -393.26312) (xy 273.669252 -392.7856)
			(arc
				(start 273.669506 -392.785346)
				(mid 273.680617 -392.768812)
				(end 273.684492 -392.749278)
			)
			(arc
				(start 273.684492 -384.155442)
				(mid 273.680591 -384.135919)
				(end 273.669506 -384.119374)
			)
			(xy 273.669252 -384.11912) (xy 273.447764 -383.897632) (xy 273.447256 -383.897124)
			(arc
				(start 273.445478 -383.895346)
				(mid 273.428944 -383.884235)
				(end 273.40941 -383.88036)
			)
			(arc
				(start 239.542574 -383.88036)
				(mid 239.523051 -383.884261)
				(end 239.506506 -383.895346)
			)
			(xy 239.506252 -383.8956) (xy 239.03051 -384.371342) (xy 239.030256 -384.371596)
			(arc
				(start 239.028478 -384.373374)
				(mid 239.017367 -384.389908)
				(end 239.013492 -384.409442)
			)
			(arc
				(start 239.013492 -393.003278)
				(mid 239.017393 -393.022801)
				(end 239.028478 -393.039346)
			)
			(xy 239.028732 -393.0396) (xy 239.252252 -393.26312)
			(arc
				(start 239.252506 -393.263374)
				(mid 239.26904 -393.274485)
				(end 239.288574 -393.27836)
			)
		)
		(stroke
			(width 0)
			(type solid)
		)
		(fill yes)
		(layer "In10.Cu")
		(net "P12V_MAIN_R")
	)
	(gr_poly
		(pts
			(arc
				(start 228.921818 -436.47868)
				(mid 228.941341 -436.474779)
				(end 228.957886 -436.463694)
			)
			(arc
				(start 229.664514 -435.757066)
				(mid 229.675625 -435.740532)
				(end 229.6795 -435.720998)
			)
			(arc
				(start 229.6795 -422.180766)
				(mid 229.703653 -422.05925)
				(end 229.772464 -421.95623)
			)
			(arc
				(start 234.67314 -417.055554)
				(mid 234.776172 -416.986773)
				(end 234.897676 -416.96259)
			)
			(arc
				(start 272.037556 -416.96259)
				(mid 272.057079 -416.958689)
				(end 272.073624 -416.947604)
			)
			(arc
				(start 280.035254 -408.985974)
				(mid 280.046365 -408.96944)
				(end 280.05024 -408.949906)
			)
			(arc
				(start 280.05024 -394.963396)
				(mid 280.046339 -394.943873)
				(end 280.035254 -394.927328)
			)
			(xy 280.035 -394.927074) (xy 279.65146 -394.543534)
			(arc
				(start 279.651206 -394.54328)
				(mid 279.634672 -394.532169)
				(end 279.615138 -394.528294)
			)
			(arc
				(start 278.051514 -394.528294)
				(mid 278.036928 -394.530433)
				(end 278.023574 -394.536676)
			)
			(arc
				(start 278.023574 -394.536676)
				(mid 277.823537 -394.629726)
				(end 277.605236 -394.661644)
			)
			(arc
				(start 277.605236 -394.661644)
				(mid 277.421236 -394.639047)
				(end 277.248112 -394.572744)
			)
			(arc
				(start 277.248112 -394.572744)
				(mid 277.224236 -394.566797)
				(end 277.20036 -394.572744)
			)
			(arc
				(start 277.20036 -394.572744)
				(mid 277.027244 -394.639078)
				(end 276.843236 -394.661644)
			)
			(arc
				(start 276.843236 -394.661644)
				(mid 276.624932 -394.629737)
				(end 276.424898 -394.536676)
			)
			(arc
				(start 276.424898 -394.536676)
				(mid 276.411542 -394.53044)
				(end 276.396958 -394.528294)
			)
			(arc
				(start 269.04569 -394.528294)
				(mid 269.030398 -394.53065)
				(end 269.01648 -394.537438)
			)
			(arc
				(start 269.01648 -394.537438)
				(mid 268.808203 -394.640414)
				(end 268.578584 -394.675868)
			)
			(arc
				(start 268.578584 -394.675868)
				(mid 268.394584 -394.653271)
				(end 268.22146 -394.586968)
			)
			(arc
				(start 268.22146 -394.586968)
				(mid 268.197584 -394.581021)
				(end 268.173708 -394.586968)
			)
			(arc
				(start 268.173708 -394.586968)
				(mid 268.000592 -394.653302)
				(end 267.816584 -394.675868)
			)
			(arc
				(start 267.816584 -394.675868)
				(mid 267.586971 -394.640395)
				(end 267.378688 -394.537438)
			)
			(arc
				(start 267.378688 -394.537438)
				(mid 267.364793 -394.530577)
				(end 267.349478 -394.528294)
			)
			(arc
				(start 261.01929 -394.528294)
				(mid 261.003998 -394.53065)
				(end 260.99008 -394.537438)
			)
			(arc
				(start 260.99008 -394.537438)
				(mid 260.781803 -394.640414)
				(end 260.552184 -394.675868)
			)
			(arc
				(start 260.552184 -394.675868)
				(mid 260.368184 -394.653271)
				(end 260.19506 -394.586968)
			)
			(arc
				(start 260.19506 -394.586968)
				(mid 260.171184 -394.581021)
				(end 260.147308 -394.586968)
			)
			(arc
				(start 260.147308 -394.586968)
				(mid 259.974192 -394.653302)
				(end 259.790184 -394.675868)
			)
			(arc
				(start 259.790184 -394.675868)
				(mid 259.560571 -394.640395)
				(end 259.352288 -394.537438)
			)
			(arc
				(start 259.352288 -394.537438)
				(mid 259.338393 -394.530577)
				(end 259.323078 -394.528294)
			)
			(arc
				(start 252.99289 -394.528294)
				(mid 252.977598 -394.53065)
				(end 252.96368 -394.537438)
			)
			(arc
				(start 252.96368 -394.537438)
				(mid 252.755403 -394.640414)
				(end 252.525784 -394.675868)
			)
			(arc
				(start 252.525784 -394.675868)
				(mid 252.341784 -394.653271)
				(end 252.16866 -394.586968)
			)
			(arc
				(start 252.16866 -394.586968)
				(mid 252.144784 -394.581021)
				(end 252.120908 -394.586968)
			)
			(arc
				(start 252.120908 -394.586968)
				(mid 251.947792 -394.653302)
				(end 251.763784 -394.675868)
			)
			(arc
				(start 251.763784 -394.675868)
				(mid 251.534171 -394.640395)
				(end 251.325888 -394.537438)
			)
			(arc
				(start 251.325888 -394.537438)
				(mid 251.311993 -394.530577)
				(end 251.296678 -394.528294)
			)
			(arc
				(start 244.9576 -394.528294)
				(mid 244.942576 -394.530567)
				(end 244.928898 -394.537184)
			)
			(arc
				(start 244.928898 -394.537184)
				(mid 244.722849 -394.637373)
				(end 244.496336 -394.671804)
			)
			(arc
				(start 244.496336 -394.671804)
				(mid 244.312336 -394.649207)
				(end 244.139212 -394.582904)
			)
			(arc
				(start 244.139212 -394.582904)
				(mid 244.115336 -394.576957)
				(end 244.09146 -394.582904)
			)
			(arc
				(start 244.09146 -394.582904)
				(mid 243.918344 -394.649238)
				(end 243.734336 -394.671804)
			)
			(arc
				(start 243.734336 -394.671804)
				(mid 243.507823 -394.637371)
				(end 243.301774 -394.537184)
			)
			(arc
				(start 243.301774 -394.537184)
				(mid 243.288095 -394.53057)
				(end 243.273072 -394.528294)
			)
			(arc
				(start 239.250982 -394.528294)
				(mid 239.215061 -394.543173)
				(end 239.200182 -394.579094)
			)
			(arc
				(start 239.200182 -405.390096)
				(mid 239.176029 -405.511612)
				(end 239.107218 -405.614632)
			)
			(arc
				(start 238.94034 -405.78151)
				(mid 238.837308 -405.850291)
				(end 238.715804 -405.874474)
			)
			(arc
				(start 234.522264 -405.874474)
				(mid 234.400748 -405.850321)
				(end 234.297728 -405.78151)
			)
			(arc
				(start 233.595926 -405.079708)
				(mid 233.527145 -404.976676)
				(end 233.502962 -404.855172)
			)
			(arc
				(start 233.502962 -404.072344)
				(mid 233.499061 -404.052821)
				(end 233.487976 -404.036276)
			)
			(arc
				(start 233.3498 -403.8981)
				(mid 233.281019 -403.795068)
				(end 233.256836 -403.673564)
			)
			(arc
				(start 233.256836 -400.256502)
				(mid 233.252935 -400.236979)
				(end 233.24185 -400.220434)
			)
			(arc
				(start 233.236008 -400.214592)
				(mid 233.219474 -400.203481)
				(end 233.19994 -400.199606)
			)
			(arc
				(start 229.898956 -400.199606)
				(mid 229.879433 -400.203507)
				(end 229.862888 -400.214592)
			)
			(arc
				(start 229.848664 -400.228816)
				(mid 229.837553 -400.24535)
				(end 229.833678 -400.264884)
			)
			(arc
				(start 229.833678 -403.583648)
				(mid 229.809525 -403.705164)
				(end 229.740714 -403.808184)
			)
			(arc
				(start 229.66426 -403.884638)
				(mid 229.653149 -403.901172)
				(end 229.649274 -403.920706)
			)
			(arc
				(start 229.649274 -406.19299)
				(mid 229.625121 -406.314506)
				(end 229.55631 -406.417526)
			)
			(arc
				(start 227.443284 -408.530552)
				(mid 227.340252 -408.599333)
				(end 227.218748 -408.623516)
			)
			(arc
				(start 225.642424 -408.623516)
				(mid 225.623565 -408.627146)
				(end 225.607372 -408.637486)
			)
			(arc
				(start 225.607372 -408.637486)
				(mid 225.364908 -408.792887)
				(end 225.0821 -408.84729)
			)
			(arc
				(start 225.0821 -408.84729)
				(mid 224.549885 -408.630828)
				(end 224.319846 -408.10434)
			)
			(xy 224.319592 -408.094434) (xy 224.311972 -408.076654)
			(arc
				(start 222.874586 -406.639268)
				(mid 222.805805 -406.536236)
				(end 222.781622 -406.414732)
			)
			(arc
				(start 222.781622 -403.953472)
				(mid 222.777721 -403.933949)
				(end 222.766636 -403.917404)
			)
			(arc
				(start 222.681546 -403.832314)
				(mid 222.612765 -403.729282)
				(end 222.588582 -403.607778)
			)
			(xy 222.588582 -400.229832) (xy 222.580962 -400.21129) (xy 222.57766 -400.207988)
			(arc
				(start 219.197936 -400.207988)
				(mid 219.178413 -400.211889)
				(end 219.161868 -400.222974)
			)
			(xy 219.157296 -400.227546)
			(arc
				(start 219.157296 -403.583394)
				(mid 219.133143 -403.70491)
				(end 219.064332 -403.80793)
			)
			(arc
				(start 219.00007 -403.872192)
				(mid 218.988959 -403.888726)
				(end 218.985084 -403.90826)
			)
			(arc
				(start 218.985084 -406.217374)
				(mid 218.960931 -406.33889)
				(end 218.89212 -406.44191)
			)
			(arc
				(start 216.76614 -408.56789)
				(mid 216.663108 -408.636671)
				(end 216.541604 -408.660854)
			)
			(arc
				(start 214.93226 -408.660854)
				(mid 214.915131 -408.66392)
				(end 214.900002 -408.672538)
			)
			(arc
				(start 214.900002 -408.672538)
				(mid 214.672289 -408.802264)
				(end 214.4141 -408.84729)
			)
			(arc
				(start 214.4141 -408.84729)
				(mid 213.886272 -408.635069)
				(end 213.652354 -408.116532)
			)
			(xy 213.651846 -408.10688) (xy 213.644226 -408.089608)
			(arc
				(start 212.189822 -406.635204)
				(mid 212.121041 -406.532172)
				(end 212.096858 -406.410668)
			)
			(arc
				(start 212.096858 -403.916642)
				(mid 212.092957 -403.897119)
				(end 212.081872 -403.880574)
			)
			(arc
				(start 212.058504 -403.857206)
				(mid 211.989723 -403.754174)
				(end 211.96554 -403.63267)
			)
			(arc
				(start 211.96554 -400.29765)
				(mid 211.961639 -400.278127)
				(end 211.950554 -400.261582)
			)
			(arc
				(start 211.854542 -400.16557)
				(mid 211.838008 -400.154459)
				(end 211.818474 -400.150584)
			)
			(arc
				(start 208.578704 -400.150584)
				(mid 208.559181 -400.154485)
				(end 208.542636 -400.16557)
			)
			(arc
				(start 208.512156 -400.19605)
				(mid 208.501045 -400.212584)
				(end 208.49717 -400.232118)
			)
			(arc
				(start 208.49717 -403.534118)
				(mid 208.473017 -403.655634)
				(end 208.404206 -403.758654)
			)
			(arc
				(start 208.323688 -403.839172)
				(mid 208.312577 -403.855706)
				(end 208.308702 -403.87524)
			)
			(arc
				(start 208.308702 -406.275032)
				(mid 208.284549 -406.396548)
				(end 208.215738 -406.499568)
			)
			(arc
				(start 206.172562 -408.542744)
				(mid 206.06953 -408.611525)
				(end 205.948026 -408.635708)
			)
			(arc
				(start 204.293216 -408.635708)
				(mid 204.274946 -408.639107)
				(end 204.25918 -408.648916)
			)
			(arc
				(start 204.25918 -408.648916)
				(mid 204.021144 -408.79596)
				(end 203.7461 -408.84729)
			)
			(arc
				(start 203.7461 -408.84729)
				(mid 203.306844 -408.708001)
				(end 203.028042 -408.341068)
			)
			(xy 203.023978 -408.330146)
			(arc
				(start 201.5871 -406.893268)
				(mid 201.518319 -406.790236)
				(end 201.494136 -406.668732)
			)
			(arc
				(start 201.494136 -403.941026)
				(mid 201.490235 -403.921503)
				(end 201.47915 -403.904958)
			)
			(arc
				(start 201.373994 -403.799802)
				(mid 201.305213 -403.69677)
				(end 201.28103 -403.575266)
			)
			(arc
				(start 201.28103 -400.264884)
				(mid 201.277129 -400.245361)
				(end 201.266044 -400.228816)
			)
			(arc
				(start 201.221594 -400.184366)
				(mid 201.20506 -400.173255)
				(end 201.185526 -400.16938)
			)
			(arc
				(start 197.9168 -400.16938)
				(mid 197.897277 -400.173281)
				(end 197.880732 -400.184366)
			)
			(arc
				(start 197.844156 -400.220942)
				(mid 197.833045 -400.237476)
				(end 197.82917 -400.25701)
			)
			(arc
				(start 197.82917 -403.58314)
				(mid 197.805017 -403.704656)
				(end 197.736206 -403.807676)
			)
			(arc
				(start 195.6435 -405.900382)
				(mid 195.540468 -405.969163)
				(end 195.418964 -405.993346)
			)
			(arc
				(start 191.073786 -405.993346)
				(mid 190.95227 -405.969193)
				(end 190.84925 -405.900382)
			)
			(arc
				(start 188.07938 -403.130512)
				(mid 188.010599 -403.02748)
				(end 187.986416 -402.905976)
			)
			(arc
				(start 187.986416 -400.258534)
				(mid 187.971537 -400.222613)
				(end 187.935616 -400.207734)
			)
			(arc
				(start 184.616598 -400.207734)
				(mid 184.597075 -400.211635)
				(end 184.58053 -400.22272)
			)
			(xy 184.575958 -400.227292) (xy 184.575958 -405.83104) (xy 184.598818 -405.85898)
			(arc
				(start 184.617106 -405.862536)
				(mid 184.925224 -406.236932)
				(end 184.617106 -406.611328)
			)
			(xy 184.598818 -406.614884) (xy 184.575958 -406.642824)
			(arc
				(start 184.575958 -410.555694)
				(mid 184.579859 -410.575217)
				(end 184.590944 -410.591762)
			)
			(arc
				(start 184.926986 -410.927804)
				(mid 184.94352 -410.938915)
				(end 184.963054 -410.94279)
			)
			(arc
				(start 187.965334 -410.94279)
				(mid 188.08685 -410.966943)
				(end 188.18987 -411.035754)
			)
			(arc
				(start 188.836808 -411.682692)
				(mid 188.853342 -411.693803)
				(end 188.872876 -411.697678)
			)
			(arc
				(start 195.270882 -411.697678)
				(mid 195.392398 -411.721831)
				(end 195.495418 -411.790642)
			)
			(arc
				(start 196.65696 -412.952184)
				(mid 196.725741 -413.055216)
				(end 196.749924 -413.17672)
			)
			(arc
				(start 196.749924 -421.558466)
				(mid 196.753825 -421.577989)
				(end 196.76491 -421.594534)
			)
			(arc
				(start 205.961996 -430.79162)
				(mid 206.030777 -430.894652)
				(end 206.05496 -431.016156)
			)
			(arc
				(start 206.05496 -435.078378)
				(mid 206.058861 -435.097901)
				(end 206.069946 -435.114446)
			)
			(arc
				(start 207.419194 -436.463694)
				(mid 207.435728 -436.474805)
				(end 207.455262 -436.47868)
			)
		)
		(stroke
			(width 0)
			(type solid)
		)
		(fill yes)
		(layer "In10.Cu")
		(net "P12V_PSU")
	)
	(gr_poly
		(pts
			(xy 531.7998 -462.519268) (xy 531.855569 -462.518759) (xy 531.966796 -462.510424) (xy 532.077089 -462.4938)
			(xy 532.185831 -462.46898) (xy 532.292414 -462.436103) (xy 532.396243 -462.395354) (xy 532.496736 -462.346959)
			(xy 532.593331 -462.291189) (xy 532.685488 -462.228357) (xy 532.772692 -462.158813) (xy 532.854456 -462.082947)
			(xy 532.930321 -462.001183) (xy 532.999864 -461.913979) (xy 533.062695 -461.821821) (xy 533.118464 -461.725225)
			(xy 533.166858 -461.624732) (xy 533.207607 -461.520903) (xy 533.240483 -461.41432) (xy 533.265302 -461.305577)
			(xy 533.281925 -461.195284) (xy 533.29026 -461.084057) (xy 533.29078 -461.028288) (xy 533.29078 -455.0283)
			(xy 533.290259 -454.972531) (xy 533.281923 -454.861305) (xy 533.265299 -454.751013) (xy 533.24048 -454.642271)
			(xy 533.207603 -454.535688) (xy 533.166854 -454.43186) (xy 533.118459 -454.331368) (xy 533.06269 -454.234773)
			(xy 532.999859 -454.142616) (xy 532.930316 -454.055412) (xy 532.854451 -453.973649) (xy 532.772688 -453.897784)
			(xy 532.685484 -453.828241) (xy 532.593327 -453.76541) (xy 532.496732 -453.709641) (xy 532.39624 -453.661246)
			(xy 532.292412 -453.620497) (xy 532.185829 -453.58762) (xy 532.077087 -453.562801) (xy 531.966795 -453.546177)
			(xy 531.855569 -453.537841) (xy 531.7998 -453.53732) (xy 516.019796 -453.53732) (xy 515.949414 -453.536826)
			(xy 515.808871 -453.528933) (xy 515.668991 -453.513172) (xy 515.530216 -453.489593) (xy 515.392981 -453.45827)
			(xy 515.257718 -453.419302) (xy 515.124852 -453.37281) (xy 514.994803 -453.318942) (xy 514.867978 -453.257866)
			(xy 514.744778 -453.189776) (xy 514.625589 -453.114884) (xy 514.510787 -453.033428) (xy 514.400733 -452.945663)
			(xy 514.295773 -452.851865) (xy 514.196238 -452.75233) (xy 514.10244 -452.64737) (xy 514.014674 -452.537316)
			(xy 513.933218 -452.422514) (xy 513.858326 -452.303325) (xy 513.790236 -452.180125) (xy 513.72916 -452.053301)
			(xy 513.675292 -451.923251) (xy 513.6288 -451.790386) (xy 513.589831 -451.655123) (xy 513.558507 -451.517888)
			(xy 513.534928 -451.379113) (xy 513.519167 -451.239233) (xy 513.511274 -451.09869) (xy 513.510784 -451.028308)
			(xy 513.510784 -312.408316) (xy 513.511268 -312.337933) (xy 513.51916 -312.197389) (xy 513.53492 -312.057508)
			(xy 513.558498 -311.918731) (xy 513.589821 -311.781495) (xy 513.628789 -311.646231) (xy 513.67528 -311.513364)
			(xy 513.729148 -311.383313) (xy 513.790224 -311.256488) (xy 513.858314 -311.133286) (xy 513.933205 -311.014096)
			(xy 514.014662 -310.899292) (xy 514.102427 -310.789237) (xy 514.196225 -310.684276) (xy 514.295761 -310.584739)
			(xy 514.400722 -310.49094) (xy 514.510776 -310.403174) (xy 514.625579 -310.321716) (xy 514.744769 -310.246824)
			(xy 514.86797 -310.178733) (xy 514.994795 -310.117656) (xy 515.124845 -310.063787) (xy 515.257712 -310.017295)
			(xy 515.392976 -309.978326) (xy 515.530212 -309.947002) (xy 515.668989 -309.923423) (xy 515.808869 -309.907662)
			(xy 515.949413 -309.899769) (xy 516.019796 -309.899304) (xy 531.7998 -309.899304) (xy 531.855569 -309.898783)
			(xy 531.966796 -309.890447) (xy 532.077089 -309.873823) (xy 532.185831 -309.849004) (xy 532.292415 -309.816128)
			(xy 532.396243 -309.775378) (xy 532.496737 -309.726984) (xy 532.593332 -309.671215) (xy 532.68549 -309.608384)
			(xy 532.772695 -309.538841) (xy 532.854459 -309.462976) (xy 532.930326 -309.381213) (xy 532.99987 -309.294009)
			(xy 533.062703 -309.201852) (xy 533.118473 -309.105258) (xy 533.166869 -309.004765) (xy 533.20762 -308.900937)
			(xy 533.240498 -308.794355) (xy 533.265319 -308.685613) (xy 533.281945 -308.57532) (xy 533.290282 -308.464093)
			(xy 533.29078 -308.408324) (xy 533.29078 10.40003) (xy 533.290257 10.455798) (xy 533.28192 10.567023)
			(xy 533.265294 10.677313) (xy 533.240473 10.786053) (xy 533.207596 10.892634) (xy 533.166845 10.99646)
			(xy 533.11845 11.09695) (xy 533.06268 11.193543) (xy 532.999848 11.285698) (xy 532.930305 11.3729)
			(xy 532.85444 11.454661) (xy 532.772677 11.530525) (xy 532.685474 11.600066) (xy 532.593318 11.662896)
			(xy 532.496724 11.718664) (xy 532.396232 11.767057) (xy 532.292406 11.807806) (xy 532.185824 11.840681)
			(xy 532.077084 11.8655) (xy 531.966793 11.882123) (xy 531.855568 11.890459) (xy 531.7998 11.89101)
			(xy 475.799912 11.89101) (xy 475.744142 11.890489) (xy 475.632915 11.882155) (xy 475.522621 11.865531)
			(xy 475.413878 11.840713) (xy 475.307293 11.807837) (xy 475.203464 11.767088) (xy 475.10297 11.718694)
			(xy 475.006373 11.662926) (xy 474.914214 11.600094) (xy 474.827008 11.530552) (xy 474.745243 11.454687)
			(xy 474.669376 11.372924) (xy 474.599831 11.28572) (xy 474.536997 11.193563) (xy 474.481225 11.096967)
			(xy 474.432829 10.996475) (xy 474.392077 10.892646) (xy 474.359198 10.786063) (xy 474.334376 10.67732)
			(xy 474.31775 10.567027) (xy 474.309413 10.4558) (xy 474.308932 10.40003) (xy 474.308932 7.335466)
			(xy 526.704041 7.335466) (xy 526.704041 7.464606) (xy 526.711991 7.593501) (xy 526.727861 7.721661)
			(xy 526.75159 7.848602) (xy 526.783089 7.973841) (xy 526.822238 8.096904) (xy 526.868889 8.217323)
			(xy 526.922864 8.334642) (xy 526.983959 8.448416) (xy 527.051942 8.558213) (xy 527.126556 8.663616)
			(xy 527.207517 8.764226) (xy 527.294517 8.859661) (xy 527.387228 8.94956) (xy 527.485298 9.033581)
			(xy 527.588353 9.111405) (xy 527.696004 9.182737) (xy 527.807843 9.247307) (xy 527.923444 9.304869)
			(xy 528.042369 9.355206) (xy 528.164168 9.398126) (xy 528.288378 9.433467) (xy 528.414527 9.461094)
			(xy 528.542139 9.480903) (xy 528.670728 9.492819) (xy 528.799806 9.496796) (xy 528.928884 9.492819)
			(xy 529.057473 9.480903) (xy 529.185085 9.461094) (xy 529.311234 9.433467) (xy 529.435444 9.398126)
			(xy 529.557243 9.355206) (xy 529.676168 9.304869) (xy 529.791769 9.247307) (xy 529.903608 9.182737)
			(xy 530.011259 9.111405) (xy 530.114314 9.033581) (xy 530.212384 8.94956) (xy 530.305095 8.859661)
			(xy 530.392095 8.764226) (xy 530.473056 8.663616) (xy 530.54767 8.558213) (xy 530.615653 8.448416)
			(xy 530.676748 8.334642) (xy 530.730723 8.217323) (xy 530.777374 8.096904) (xy 530.816523 7.973841)
			(xy 530.848022 7.848602) (xy 530.871751 7.721661) (xy 530.887621 7.593501) (xy 530.895571 7.464606)
			(xy 530.896068 7.400036) (xy 530.895571 7.335466) (xy 530.887621 7.206571) (xy 530.871751 7.078411)
			(xy 530.848022 6.95147) (xy 530.816523 6.826231) (xy 530.777374 6.703168) (xy 530.730723 6.582749)
			(xy 530.676748 6.46543) (xy 530.615653 6.351656) (xy 530.54767 6.241859) (xy 530.473056 6.136456)
			(xy 530.392095 6.035846) (xy 530.305095 5.940411) (xy 530.212384 5.850512) (xy 530.114314 5.766491)
			(xy 530.011259 5.688667) (xy 529.903608 5.617335) (xy 529.791769 5.552765) (xy 529.676168 5.495203)
			(xy 529.557243 5.444866) (xy 529.435444 5.401946) (xy 529.311234 5.366605) (xy 529.185085 5.338978)
			(xy 529.057473 5.319169) (xy 528.928884 5.307253) (xy 528.799806 5.303277) (xy 528.670728 5.307253)
			(xy 528.542139 5.319169) (xy 528.414527 5.338978) (xy 528.288378 5.366605) (xy 528.164168 5.401946)
			(xy 528.042369 5.444866) (xy 527.923444 5.495203) (xy 527.807843 5.552765) (xy 527.696004 5.617335)
			(xy 527.588353 5.688667) (xy 527.485298 5.766491) (xy 527.387228 5.850512) (xy 527.294517 5.940411)
			(xy 527.207517 6.035846) (xy 527.126556 6.136456) (xy 527.051942 6.241859) (xy 526.983959 6.351656)
			(xy 526.922864 6.46543) (xy 526.868889 6.582749) (xy 526.822238 6.703168) (xy 526.783089 6.826231)
			(xy 526.75159 6.95147) (xy 526.727861 7.078411) (xy 526.711991 7.206571) (xy 526.704041 7.335466)
			(xy 474.308932 7.335466) (xy 474.308932 -12.515904) (xy 476.704141 -12.515904) (xy 476.704141 -12.386764)
			(xy 476.712091 -12.257869) (xy 476.727961 -12.129709) (xy 476.75169 -12.002768) (xy 476.783189 -11.877529)
			(xy 476.822338 -11.754466) (xy 476.868989 -11.634047) (xy 476.922964 -11.516728) (xy 476.984059 -11.402954)
			(xy 477.052042 -11.293157) (xy 477.126656 -11.187754) (xy 477.207617 -11.087144) (xy 477.294617 -10.991709)
			(xy 477.387328 -10.90181) (xy 477.485398 -10.817789) (xy 477.588453 -10.739965) (xy 477.696104 -10.668633)
			(xy 477.807943 -10.604063) (xy 477.923544 -10.546501) (xy 478.042469 -10.496164) (xy 478.164268 -10.453244)
			(xy 478.288478 -10.417903) (xy 478.414627 -10.390276) (xy 478.542239 -10.370467) (xy 478.670828 -10.358551)
			(xy 478.799906 -10.354575) (xy 478.928984 -10.358551) (xy 479.057573 -10.370467) (xy 479.185185 -10.390276)
			(xy 479.311334 -10.417903) (xy 479.435544 -10.453244) (xy 479.557343 -10.496164) (xy 479.676268 -10.546501)
			(xy 479.791869 -10.604063) (xy 479.903708 -10.668633) (xy 480.011359 -10.739965) (xy 480.114414 -10.817789)
			(xy 480.212484 -10.90181) (xy 480.305195 -10.991709) (xy 480.392195 -11.087144) (xy 480.473156 -11.187754)
			(xy 480.54777 -11.293157) (xy 480.615753 -11.402954) (xy 480.676848 -11.516728) (xy 480.730823 -11.634047)
			(xy 480.777474 -11.754466) (xy 480.816623 -11.877529) (xy 480.848122 -12.002768) (xy 480.871851 -12.129709)
			(xy 480.887721 -12.257869) (xy 480.895671 -12.386764) (xy 480.896168 -12.451334) (xy 480.895671 -12.515904)
			(xy 480.887721 -12.644799) (xy 480.871851 -12.772959) (xy 480.848122 -12.8999) (xy 480.816623 -13.025139)
			(xy 480.777474 -13.148202) (xy 480.730823 -13.268621) (xy 480.676848 -13.38594) (xy 480.615753 -13.499714)
			(xy 480.54777 -13.609511) (xy 480.473156 -13.714914) (xy 480.392195 -13.815524) (xy 480.305195 -13.910959)
			(xy 480.212484 -14.000858) (xy 480.114414 -14.084879) (xy 480.011359 -14.162703) (xy 479.903708 -14.234035)
			(xy 479.791869 -14.298605) (xy 479.676268 -14.356167) (xy 479.557343 -14.406504) (xy 479.435544 -14.449424)
			(xy 479.311334 -14.484765) (xy 479.185185 -14.512392) (xy 479.057573 -14.532201) (xy 478.928984 -14.544117)
			(xy 478.799906 -14.548094) (xy 478.670828 -14.544117) (xy 478.542239 -14.532201) (xy 478.414627 -14.512392)
			(xy 478.288478 -14.484765) (xy 478.164268 -14.449424) (xy 478.042469 -14.406504) (xy 477.923544 -14.356167)
			(xy 477.807943 -14.298605) (xy 477.696104 -14.234035) (xy 477.588453 -14.162703) (xy 477.485398 -14.084879)
			(xy 477.387328 -14.000858) (xy 477.294617 -13.910959) (xy 477.207617 -13.815524) (xy 477.126656 -13.714914)
			(xy 477.052042 -13.609511) (xy 476.984059 -13.499714) (xy 476.922964 -13.38594) (xy 476.868989 -13.268621)
			(xy 476.822338 -13.148202) (xy 476.783189 -13.025139) (xy 476.75169 -12.8999) (xy 476.727961 -12.772959)
			(xy 476.712091 -12.644799) (xy 476.704141 -12.515904) (xy 474.308932 -12.515904) (xy 474.308932 -77.67193)
			(xy 474.308458 -77.765117) (xy 474.300759 -77.951331) (xy 474.28537 -78.137067) (xy 474.262318 -78.32201)
			(xy 474.231642 -78.505841) (xy 474.193396 -78.688247) (xy 474.147643 -78.868917) (xy 474.094463 -79.047542)
			(xy 474.033945 -79.223817) (xy 473.966195 -79.397439) (xy 473.891327 -79.568113) (xy 473.809469 -79.735548)
			(xy 473.720761 -79.899456) (xy 473.625355 -80.059558) (xy 473.523414 -80.21558) (xy 473.415112 -80.367256)
			(xy 473.300633 -80.514327) (xy 473.180175 -80.65654) (xy 473.053942 -80.793654) (xy 472.988386 -80.859884)
			(xy 471.245946 -82.602324) (xy 471.208633 -82.640304) (xy 471.138899 -82.72077) (xy 471.07508 -82.806006)
			(xy 471.017504 -82.895576) (xy 470.966464 -82.989025) (xy 470.922218 -83.085876) (xy 470.884993 -83.185636)
			(xy 470.854978 -83.287798) (xy 470.832326 -83.391839) (xy 470.817153 -83.497232) (xy 470.809535 -83.603438)
			(xy 470.809066 -83.656678) (xy 470.809066 -328.137828) (xy 473.204275 -328.137828) (xy 473.204275 -328.008688)
			(xy 473.212225 -327.879793) (xy 473.228095 -327.751633) (xy 473.251824 -327.624692) (xy 473.283323 -327.499453)
			(xy 473.322472 -327.37639) (xy 473.369123 -327.255971) (xy 473.423098 -327.138652) (xy 473.484193 -327.024878)
			(xy 473.552176 -326.915081) (xy 473.62679 -326.809678) (xy 473.707751 -326.709068) (xy 473.794751 -326.613633)
			(xy 473.887462 -326.523734) (xy 473.985532 -326.439713) (xy 474.088587 -326.361889) (xy 474.196238 -326.290557)
			(xy 474.308077 -326.225987) (xy 474.423678 -326.168425) (xy 474.542603 -326.118088) (xy 474.664402 -326.075168)
			(xy 474.788612 -326.039827) (xy 474.914761 -326.0122) (xy 475.042373 -325.992391) (xy 475.170962 -325.980475)
			(xy 475.30004 -325.976499) (xy 475.429118 -325.980475) (xy 475.557707 -325.992391) (xy 475.685319 -326.0122)
			(xy 475.811468 -326.039827) (xy 475.935678 -326.075168) (xy 476.057477 -326.118088) (xy 476.176402 -326.168425)
			(xy 476.292003 -326.225987) (xy 476.403842 -326.290557) (xy 476.511493 -326.361889) (xy 476.614548 -326.439713)
			(xy 476.712618 -326.523734) (xy 476.805329 -326.613633) (xy 476.892329 -326.709068) (xy 476.97329 -326.809678)
			(xy 477.047904 -326.915081) (xy 477.115887 -327.024878) (xy 477.176982 -327.138652) (xy 477.230957 -327.255971)
			(xy 477.277608 -327.37639) (xy 477.316757 -327.499453) (xy 477.348256 -327.624692) (xy 477.371985 -327.751633)
			(xy 477.387855 -327.879793) (xy 477.395805 -328.008688) (xy 477.396302 -328.073258) (xy 477.395805 -328.137828)
			(xy 477.387855 -328.266723) (xy 477.371985 -328.394883) (xy 477.348256 -328.521824) (xy 477.316757 -328.647063)
			(xy 477.277608 -328.770126) (xy 477.230957 -328.890545) (xy 477.176982 -329.007864) (xy 477.115887 -329.121638)
			(xy 477.047904 -329.231435) (xy 476.97329 -329.336838) (xy 476.892329 -329.437448) (xy 476.805329 -329.532883)
			(xy 476.712618 -329.622782) (xy 476.614548 -329.706803) (xy 476.511493 -329.784627) (xy 476.403842 -329.855959)
			(xy 476.292003 -329.920529) (xy 476.176402 -329.978091) (xy 476.057477 -330.028428) (xy 475.935678 -330.071348)
			(xy 475.811468 -330.106689) (xy 475.685319 -330.134316) (xy 475.557707 -330.154125) (xy 475.429118 -330.166041)
			(xy 475.30004 -330.170018) (xy 475.170962 -330.166041) (xy 475.042373 -330.154125) (xy 474.914761 -330.134316)
			(xy 474.788612 -330.106689) (xy 474.664402 -330.071348) (xy 474.542603 -330.028428) (xy 474.423678 -329.978091)
			(xy 474.308077 -329.920529) (xy 474.196238 -329.855959) (xy 474.088587 -329.784627) (xy 473.985532 -329.706803)
			(xy 473.887462 -329.622782) (xy 473.794751 -329.532883) (xy 473.707751 -329.437448) (xy 473.62679 -329.336838)
			(xy 473.552176 -329.231435) (xy 473.484193 -329.121638) (xy 473.423098 -329.007864) (xy 473.369123 -328.890545)
			(xy 473.322472 -328.770126) (xy 473.283323 -328.647063) (xy 473.251824 -328.521824) (xy 473.228095 -328.394883)
			(xy 473.212225 -328.266723) (xy 473.204275 -328.137828) (xy 470.809066 -328.137828) (xy 470.809066 -404.871936)
			(xy 470.808592 -404.965123) (xy 470.800892 -405.151337) (xy 470.785503 -405.337074) (xy 470.762451 -405.522016)
			(xy 470.731776 -405.705847) (xy 470.693529 -405.888254) (xy 470.647776 -406.068924) (xy 470.594596 -406.247549)
			(xy 470.534079 -406.423823) (xy 470.466329 -406.597446) (xy 470.391461 -406.76812) (xy 470.309603 -406.935555)
			(xy 470.220896 -407.099463) (xy 470.12549 -407.259566) (xy 470.02355 -407.415588) (xy 469.915248 -407.567265)
			(xy 469.80077 -407.714335) (xy 469.680312 -407.856549) (xy 469.554079 -407.993664) (xy 469.48852 -408.05989)
			(xy 468.245698 -409.302712) (xy 468.208406 -409.340689) (xy 468.138712 -409.421147) (xy 468.074932 -409.506369)
			(xy 468.017391 -409.595922) (xy 467.966382 -409.68935) (xy 467.922165 -409.786178) (xy 467.884964 -409.885911)
			(xy 467.85497 -409.988044) (xy 467.832334 -410.092055) (xy 467.817172 -410.197416) (xy 467.809562 -410.303589)
			(xy 467.809072 -410.356812) (xy 467.809072 -439.989976) (xy 467.809593 -440.045746) (xy 467.817926 -440.156975)
			(xy 467.834548 -440.26727) (xy 467.859367 -440.376014) (xy 467.892242 -440.4826) (xy 467.93299 -440.586431)
			(xy 467.981383 -440.686926) (xy 468.037152 -440.783525) (xy 468.099983 -440.875685) (xy 468.169525 -440.962893)
			(xy 468.24539 -441.044659) (xy 468.327153 -441.120528) (xy 468.414357 -441.190075) (xy 468.506514 -441.25291)
			(xy 468.60311 -441.308683) (xy 468.703603 -441.357081) (xy 468.807432 -441.397835) (xy 468.914016 -441.430715)
			(xy 469.022759 -441.455538) (xy 469.133053 -441.472166) (xy 469.244282 -441.480505) (xy 469.300052 -441.480956)
			(xy 471.79992 -441.480956) (xy 471.870302 -441.48145) (xy 472.010845 -441.489344) (xy 472.150724 -441.505105)
			(xy 472.2895 -441.528685) (xy 472.426735 -441.560009) (xy 472.561998 -441.598978) (xy 472.694863 -441.64547)
			(xy 472.824912 -441.699339) (xy 472.951736 -441.760414) (xy 473.074936 -441.828505) (xy 473.194125 -441.903396)
			(xy 473.308927 -441.984852) (xy 473.418981 -442.072617) (xy 473.523941 -442.166415) (xy 473.623477 -442.26595)
			(xy 473.717275 -442.37091) (xy 473.80504 -442.480964) (xy 473.886497 -442.595765) (xy 473.961389 -442.714953)
			(xy 474.02948 -442.838153) (xy 474.090556 -442.964977) (xy 474.144426 -443.095026) (xy 474.190918 -443.227891)
			(xy 474.229888 -443.363154) (xy 474.261212 -443.500389) (xy 474.284793 -443.639164) (xy 474.300555 -443.779043)
			(xy 474.308449 -443.919586) (xy 474.308932 -443.989968) (xy 474.308932 -458.092864) (xy 526.704041 -458.092864)
			(xy 526.704041 -457.963724) (xy 526.711991 -457.834829) (xy 526.727861 -457.706669) (xy 526.75159 -457.579728)
			(xy 526.783089 -457.454489) (xy 526.822238 -457.331426) (xy 526.868889 -457.211007) (xy 526.922864 -457.093688)
			(xy 526.983959 -456.979914) (xy 527.051942 -456.870117) (xy 527.126556 -456.764714) (xy 527.207517 -456.664104)
			(xy 527.294517 -456.568669) (xy 527.387228 -456.47877) (xy 527.485298 -456.394749) (xy 527.588353 -456.316925)
			(xy 527.696004 -456.245593) (xy 527.807843 -456.181023) (xy 527.923444 -456.123461) (xy 528.042369 -456.073124)
			(xy 528.164168 -456.030204) (xy 528.288378 -455.994863) (xy 528.414527 -455.967236) (xy 528.542139 -455.947427)
			(xy 528.670728 -455.935511) (xy 528.799806 -455.931535) (xy 528.928884 -455.935511) (xy 529.057473 -455.947427)
			(xy 529.185085 -455.967236) (xy 529.311234 -455.994863) (xy 529.435444 -456.030204) (xy 529.557243 -456.073124)
			(xy 529.676168 -456.123461) (xy 529.791769 -456.181023) (xy 529.903608 -456.245593) (xy 530.011259 -456.316925)
			(xy 530.114314 -456.394749) (xy 530.212384 -456.47877) (xy 530.305095 -456.568669) (xy 530.392095 -456.664104)
			(xy 530.473056 -456.764714) (xy 530.54767 -456.870117) (xy 530.615653 -456.979914) (xy 530.676748 -457.093688)
			(xy 530.730723 -457.211007) (xy 530.777374 -457.331426) (xy 530.816523 -457.454489) (xy 530.848022 -457.579728)
			(xy 530.871751 -457.706669) (xy 530.887621 -457.834829) (xy 530.895571 -457.963724) (xy 530.896068 -458.028294)
			(xy 530.895571 -458.092864) (xy 530.887621 -458.221759) (xy 530.871751 -458.349919) (xy 530.848022 -458.47686)
			(xy 530.816523 -458.602099) (xy 530.777374 -458.725162) (xy 530.730723 -458.845581) (xy 530.676748 -458.9629)
			(xy 530.615653 -459.076674) (xy 530.54767 -459.186471) (xy 530.473056 -459.291874) (xy 530.392095 -459.392484)
			(xy 530.305095 -459.487919) (xy 530.212384 -459.577818) (xy 530.114314 -459.661839) (xy 530.011259 -459.739663)
			(xy 529.903608 -459.810995) (xy 529.791769 -459.875565) (xy 529.676168 -459.933127) (xy 529.557243 -459.983464)
			(xy 529.435444 -460.026384) (xy 529.311234 -460.061725) (xy 529.185085 -460.089352) (xy 529.057473 -460.109161)
			(xy 528.928884 -460.121077) (xy 528.799806 -460.125054) (xy 528.670728 -460.121077) (xy 528.542139 -460.109161)
			(xy 528.414527 -460.089352) (xy 528.288378 -460.061725) (xy 528.164168 -460.026384) (xy 528.042369 -459.983464)
			(xy 527.923444 -459.933127) (xy 527.807843 -459.875565) (xy 527.696004 -459.810995) (xy 527.588353 -459.739663)
			(xy 527.485298 -459.661839) (xy 527.387228 -459.577818) (xy 527.294517 -459.487919) (xy 527.207517 -459.392484)
			(xy 527.126556 -459.291874) (xy 527.051942 -459.186471) (xy 526.983959 -459.076674) (xy 526.922864 -458.9629)
			(xy 526.868889 -458.845581) (xy 526.822238 -458.725162) (xy 526.783089 -458.602099) (xy 526.75159 -458.47686)
			(xy 526.727861 -458.349919) (xy 526.711991 -458.221759) (xy 526.704041 -458.092864) (xy 474.308932 -458.092864)
			(xy 474.308932 -461.028288) (xy 474.30944 -461.084058) (xy 474.317775 -461.195285) (xy 474.334398 -461.305579)
			(xy 474.359217 -461.414322) (xy 474.392093 -461.520906) (xy 474.432843 -461.624735) (xy 474.481238 -461.725228)
			(xy 474.537007 -461.821824) (xy 474.599839 -461.913982) (xy 474.669383 -462.001187) (xy 474.745248 -462.082952)
			(xy 474.827013 -462.158817) (xy 474.914218 -462.228361) (xy 475.006376 -462.291193) (xy 475.102972 -462.346962)
			(xy 475.203465 -462.395357) (xy 475.307294 -462.436107) (xy 475.413878 -462.468983) (xy 475.522621 -462.493802)
			(xy 475.632915 -462.510425) (xy 475.744142 -462.51876) (xy 475.799912 -462.519268)
		)
		(stroke
			(width 0)
			(type solid)
		)
		(fill yes)
		(layer "In10.Cu")
		(net "T1_GND")
	)
	(gr_poly
		(pts
			(xy 255.800098 -33.611058) (xy 255.832245 -33.610555) (xy 255.89599 -33.602163) (xy 255.958093 -33.585522)
			(xy 256.017493 -33.560917) (xy 256.073173 -33.528769) (xy 256.124181 -33.489628) (xy 256.169643 -33.444164)
			(xy 256.208781 -33.393155) (xy 256.240927 -33.337473) (xy 256.265529 -33.278072) (xy 256.282167 -33.215968)
			(xy 256.290557 -33.152223) (xy 256.29108 -33.120076) (xy 256.29108 -11.780012) (xy 256.291564 -11.709629)
			(xy 256.299456 -11.569085) (xy 256.315217 -11.429205) (xy 256.338795 -11.290428) (xy 256.370118 -11.153191)
			(xy 256.409086 -11.017927) (xy 256.455577 -10.885061) (xy 256.509445 -10.75501) (xy 256.570521 -10.628184)
			(xy 256.638611 -10.504983) (xy 256.713502 -10.385793) (xy 256.794959 -10.27099) (xy 256.882724 -10.160934)
			(xy 256.976523 -10.055973) (xy 257.076059 -9.956436) (xy 257.181019 -9.862637) (xy 257.291074 -9.774871)
			(xy 257.405876 -9.693414) (xy 257.525065 -9.618521) (xy 257.648266 -9.55043) (xy 257.775092 -9.489354)
			(xy 257.905142 -9.435484) (xy 258.038008 -9.388992) (xy 258.173272 -9.350023) (xy 258.310508 -9.318699)
			(xy 258.449285 -9.295119) (xy 258.589165 -9.279358) (xy 258.729709 -9.271465) (xy 258.800092 -9.271)
			(xy 383.601976 -9.271) (xy 383.657746 -9.270492) (xy 383.768975 -9.262159) (xy 383.87927 -9.245536)
			(xy 383.988015 -9.220718) (xy 384.094601 -9.187842) (xy 384.198432 -9.147093) (xy 384.298927 -9.098699)
			(xy 384.395525 -9.04293) (xy 384.487685 -8.980099) (xy 384.574892 -8.910555) (xy 384.656659 -8.83469)
			(xy 384.732527 -8.752926) (xy 384.802073 -8.665721) (xy 384.864907 -8.573562) (xy 384.920679 -8.476966)
			(xy 384.969076 -8.376472) (xy 385.009828 -8.272642) (xy 385.042706 -8.166058) (xy 385.067528 -8.057314)
			(xy 385.084154 -7.947019) (xy 385.092491 -7.83579) (xy 385.092956 -7.78002) (xy 385.092956 0.40005)
			(xy 385.093451 0.470432) (xy 385.101346 0.610973) (xy 385.117109 0.750851) (xy 385.14069 0.889625)
			(xy 385.172015 1.026859) (xy 385.210985 1.16212) (xy 385.257478 1.294984) (xy 385.311348 1.425032)
			(xy 385.372424 1.551855) (xy 385.440515 1.675053) (xy 385.515407 1.79424) (xy 385.596863 1.909041)
			(xy 385.684628 2.019094) (xy 385.778426 2.124052) (xy 385.877961 2.223587) (xy 385.98292 2.317383)
			(xy 386.092974 2.405148) (xy 386.207775 2.486603) (xy 386.326962 2.561494) (xy 386.450161 2.629584)
			(xy 386.576985 2.69066) (xy 386.707033 2.744528) (xy 386.839897 2.79102) (xy 386.975158 2.829989)
			(xy 387.112392 2.861313) (xy 387.251166 2.884893) (xy 387.391045 2.900655) (xy 387.531586 2.908549)
			(xy 387.601968 2.909062) (xy 456.202034 2.909062) (xy 456.272416 2.908567) (xy 456.412959 2.900673)
			(xy 456.552838 2.884911) (xy 456.691613 2.861331) (xy 456.828848 2.830006) (xy 456.96411 2.791037)
			(xy 457.096975 2.744544) (xy 457.227024 2.690676) (xy 457.353848 2.6296) (xy 457.477048 2.561509)
			(xy 457.596236 2.486618) (xy 457.711038 2.405161) (xy 457.821092 2.317396) (xy 457.926052 2.223599)
			(xy 458.025588 2.124064) (xy 458.119386 2.019104) (xy 458.207152 1.909051) (xy 458.288609 1.79425)
			(xy 458.363501 1.675062) (xy 458.431592 1.551862) (xy 458.492669 1.425039) (xy 458.546539 1.29499)
			(xy 458.593032 1.162126) (xy 458.632002 1.026863) (xy 458.663327 0.889629) (xy 458.686909 0.750854)
			(xy 458.702672 0.610975) (xy 458.710567 0.470432) (xy 458.711046 0.40005) (xy 458.711046 -4.844596)
			(xy 464.704165 -4.844596) (xy 464.704165 -4.715456) (xy 464.712115 -4.586561) (xy 464.727985 -4.458401)
			(xy 464.751714 -4.33146) (xy 464.783213 -4.206221) (xy 464.822362 -4.083158) (xy 464.869013 -3.962739)
			(xy 464.922988 -3.84542) (xy 464.984083 -3.731646) (xy 465.052066 -3.621849) (xy 465.12668 -3.516446)
			(xy 465.207641 -3.415836) (xy 465.294641 -3.320401) (xy 465.387352 -3.230502) (xy 465.485422 -3.146481)
			(xy 465.588477 -3.068657) (xy 465.696128 -2.997325) (xy 465.807967 -2.932755) (xy 465.923568 -2.875193)
			(xy 466.042493 -2.824856) (xy 466.164292 -2.781936) (xy 466.288502 -2.746595) (xy 466.414651 -2.718968)
			(xy 466.542263 -2.699159) (xy 466.670852 -2.687243) (xy 466.79993 -2.683267) (xy 466.929008 -2.687243)
			(xy 467.057597 -2.699159) (xy 467.185209 -2.718968) (xy 467.311358 -2.746595) (xy 467.435568 -2.781936)
			(xy 467.557367 -2.824856) (xy 467.676292 -2.875193) (xy 467.791893 -2.932755) (xy 467.903732 -2.997325)
			(xy 468.011383 -3.068657) (xy 468.114438 -3.146481) (xy 468.212508 -3.230502) (xy 468.305219 -3.320401)
			(xy 468.392219 -3.415836) (xy 468.47318 -3.516446) (xy 468.547794 -3.621849) (xy 468.615777 -3.731646)
			(xy 468.676872 -3.84542) (xy 468.730847 -3.962739) (xy 468.777498 -4.083158) (xy 468.816647 -4.206221)
			(xy 468.848146 -4.33146) (xy 468.871875 -4.458401) (xy 468.887745 -4.586561) (xy 468.895695 -4.715456)
			(xy 468.896192 -4.780026) (xy 468.895695 -4.844596) (xy 468.887745 -4.973491) (xy 468.871875 -5.101651)
			(xy 468.848146 -5.228592) (xy 468.816647 -5.353831) (xy 468.777498 -5.476894) (xy 468.730847 -5.597313)
			(xy 468.676872 -5.714632) (xy 468.615777 -5.828406) (xy 468.547794 -5.938203) (xy 468.47318 -6.043606)
			(xy 468.392219 -6.144216) (xy 468.305219 -6.239651) (xy 468.212508 -6.32955) (xy 468.114438 -6.413571)
			(xy 468.011383 -6.491395) (xy 467.903732 -6.562727) (xy 467.791893 -6.627297) (xy 467.676292 -6.684859)
			(xy 467.557367 -6.735196) (xy 467.435568 -6.778116) (xy 467.311358 -6.813457) (xy 467.185209 -6.841084)
			(xy 467.057597 -6.860893) (xy 466.929008 -6.872809) (xy 466.79993 -6.876786) (xy 466.670852 -6.872809)
			(xy 466.542263 -6.860893) (xy 466.414651 -6.841084) (xy 466.288502 -6.813457) (xy 466.164292 -6.778116)
			(xy 466.042493 -6.735196) (xy 465.923568 -6.684859) (xy 465.807967 -6.627297) (xy 465.696128 -6.562727)
			(xy 465.588477 -6.491395) (xy 465.485422 -6.413571) (xy 465.387352 -6.32955) (xy 465.294641 -6.239651)
			(xy 465.207641 -6.144216) (xy 465.12668 -6.043606) (xy 465.052066 -5.938203) (xy 464.984083 -5.828406)
			(xy 464.922988 -5.714632) (xy 464.869013 -5.597313) (xy 464.822362 -5.476894) (xy 464.783213 -5.353831)
			(xy 464.751714 -5.228592) (xy 464.727985 -5.101651) (xy 464.712115 -4.973491) (xy 464.704165 -4.844596)
			(xy 458.711046 -4.844596) (xy 458.711046 -7.78002) (xy 458.711555 -7.835789) (xy 458.719892 -7.947014)
			(xy 458.736517 -8.057305) (xy 458.761338 -8.166046) (xy 458.794216 -8.272628) (xy 458.834967 -8.376454)
			(xy 458.883362 -8.476945) (xy 458.939132 -8.573538) (xy 459.001965 -8.665694) (xy 459.071509 -8.752896)
			(xy 459.147375 -8.834658) (xy 459.229138 -8.910521) (xy 459.316343 -8.980062) (xy 459.4085 -9.042892)
			(xy 459.505096 -9.098659) (xy 459.605588 -9.147052) (xy 459.709416 -9.187799) (xy 459.815999 -9.220674)
			(xy 459.92474 -9.245491) (xy 460.035032 -9.262113) (xy 460.146257 -9.270446) (xy 460.202026 -9.271)
			(xy 469.799924 -9.271) (xy 469.855693 -9.270478) (xy 469.966918 -9.262141) (xy 470.07721 -9.245516)
			(xy 470.18595 -9.220695) (xy 470.292532 -9.187817) (xy 470.396359 -9.147067) (xy 470.49685 -9.098672)
			(xy 470.593444 -9.042903) (xy 470.685601 -8.980071) (xy 470.772804 -8.910528) (xy 470.854566 -8.834664)
			(xy 470.930431 -8.752901) (xy 470.999974 -8.665697) (xy 471.062805 -8.573541) (xy 471.118574 -8.476947)
			(xy 471.166969 -8.376455) (xy 471.207719 -8.272628) (xy 471.240596 -8.166046) (xy 471.265416 -8.057306)
			(xy 471.282041 -7.947014) (xy 471.290378 -7.835789) (xy 471.290904 -7.78002) (xy 471.290904 10.40003)
			(xy 471.290381 10.455799) (xy 471.282044 10.567024) (xy 471.265419 10.677315) (xy 471.240598 10.786055)
			(xy 471.20772 10.892637) (xy 471.16697 10.996464) (xy 471.118574 11.096955) (xy 471.062805 11.193548)
			(xy 470.999973 11.285705) (xy 470.930431 11.372908) (xy 470.854566 11.45467) (xy 470.772803 11.530534)
			(xy 470.6856 11.600077) (xy 470.593443 11.662908) (xy 470.49685 11.718677) (xy 470.396358 11.767072)
			(xy 470.292531 11.807822) (xy 470.18595 11.840699) (xy 470.077209 11.86552) (xy 469.966918 11.882145)
			(xy 469.855693 11.890482) (xy 469.799924 11.89101) (xy 1.999996 11.89101) (xy 1.944227 11.890488)
			(xy 1.833001 11.882153) (xy 1.722709 11.865529) (xy 1.613968 11.840709) (xy 1.507385 11.807832) (xy 1.403558 11.767083)
			(xy 1.303066 11.718688) (xy 1.206471 11.662919) (xy 1.114314 11.600087) (xy 1.027111 11.530545) (xy 0.945348 11.454679)
			(xy 0.869483 11.372916) (xy 0.79994 11.285712) (xy 0.737109 11.193555) (xy 0.68134 11.096961) (xy 0.632946 10.996469)
			(xy 0.592196 10.892641) (xy 0.55932 10.786058) (xy 0.534501 10.677317) (xy 0.517877 10.567025) (xy 0.509541 10.455799)
			(xy 0.509016 10.40003) (xy 0.509016 9.916973) (xy 385.651997 9.916973) (xy 385.651997 10.002723)
			(xy 385.659909 10.088106) (xy 385.675665 10.172396) (xy 385.699132 10.254872) (xy 385.730108 10.334831)
			(xy 385.76833 10.411591) (xy 385.813471 10.484497) (xy 385.865147 10.552926) (xy 385.922916 10.616296)
			(xy 385.986286 10.674065) (xy 386.054715 10.725741) (xy 386.127621 10.770882) (xy 386.204381 10.809104)
			(xy 386.28434 10.84008) (xy 386.366816 10.863547) (xy 386.451106 10.879303) (xy 386.536489 10.887215)
			(xy 386.622239 10.887215) (xy 386.707622 10.879303) (xy 386.791912 10.863547) (xy 386.874388 10.84008)
			(xy 386.954347 10.809104) (xy 387.031107 10.770882) (xy 387.104013 10.725741) (xy 387.172442 10.674065)
			(xy 387.235812 10.616296) (xy 387.293581 10.552926) (xy 387.345257 10.484497) (xy 387.390398 10.411591)
			(xy 387.42862 10.334831) (xy 387.459596 10.254872) (xy 387.483063 10.172396) (xy 387.498819 10.088106)
			(xy 387.506731 10.002723) (xy 387.507226 9.959848) (xy 387.506731 9.916973) (xy 392.001997 9.916973)
			(xy 392.001997 10.002723) (xy 392.009909 10.088106) (xy 392.025665 10.172396) (xy 392.049132 10.254872)
			(xy 392.080108 10.334831) (xy 392.11833 10.411591) (xy 392.163471 10.484497) (xy 392.215147 10.552926)
			(xy 392.272916 10.616296) (xy 392.336286 10.674065) (xy 392.404715 10.725741) (xy 392.477621 10.770882)
			(xy 392.554381 10.809104) (xy 392.63434 10.84008) (xy 392.716816 10.863547) (xy 392.801106 10.879303)
			(xy 392.886489 10.887215) (xy 392.972239 10.887215) (xy 393.057622 10.879303) (xy 393.141912 10.863547)
			(xy 393.224388 10.84008) (xy 393.304347 10.809104) (xy 393.381107 10.770882) (xy 393.454013 10.725741)
			(xy 393.522442 10.674065) (xy 393.585812 10.616296) (xy 393.643581 10.552926) (xy 393.695257 10.484497)
			(xy 393.740398 10.411591) (xy 393.77862 10.334831) (xy 393.809596 10.254872) (xy 393.833063 10.172396)
			(xy 393.848819 10.088106) (xy 393.856731 10.002723) (xy 393.857226 9.959848) (xy 393.856731 9.916973)
			(xy 436.390783 9.916973) (xy 436.390783 10.002723) (xy 436.398695 10.088106) (xy 436.414451 10.172396)
			(xy 436.437918 10.254872) (xy 436.468894 10.334831) (xy 436.507116 10.411591) (xy 436.552257 10.484497)
			(xy 436.603933 10.552926) (xy 436.661702 10.616296) (xy 436.725072 10.674065) (xy 436.793501 10.725741)
			(xy 436.866407 10.770882) (xy 436.943167 10.809104) (xy 437.023126 10.84008) (xy 437.105602 10.863547)
			(xy 437.189892 10.879303) (xy 437.275275 10.887215) (xy 437.361025 10.887215) (xy 437.446408 10.879303)
			(xy 437.530698 10.863547) (xy 437.613174 10.84008) (xy 437.693133 10.809104) (xy 437.769893 10.770882)
			(xy 437.842799 10.725741) (xy 437.911228 10.674065) (xy 437.974598 10.616296) (xy 438.032367 10.552926)
			(xy 438.084043 10.484497) (xy 438.129184 10.411591) (xy 438.167406 10.334831) (xy 438.198382 10.254872)
			(xy 438.221849 10.172396) (xy 438.237605 10.088106) (xy 438.245517 10.002723) (xy 438.246012 9.959848)
			(xy 438.245517 9.916973) (xy 442.740783 9.916973) (xy 442.740783 10.002723) (xy 442.748695 10.088106)
			(xy 442.764451 10.172396) (xy 442.787918 10.254872) (xy 442.818894 10.334831) (xy 442.857116 10.411591)
			(xy 442.902257 10.484497) (xy 442.953933 10.552926) (xy 443.011702 10.616296) (xy 443.075072 10.674065)
			(xy 443.143501 10.725741) (xy 443.216407 10.770882) (xy 443.293167 10.809104) (xy 443.373126 10.84008)
			(xy 443.455602 10.863547) (xy 443.539892 10.879303) (xy 443.625275 10.887215) (xy 443.711025 10.887215)
			(xy 443.796408 10.879303) (xy 443.880698 10.863547) (xy 443.963174 10.84008) (xy 444.043133 10.809104)
			(xy 444.119893 10.770882) (xy 444.192799 10.725741) (xy 444.261228 10.674065) (xy 444.324598 10.616296)
			(xy 444.382367 10.552926) (xy 444.434043 10.484497) (xy 444.479184 10.411591) (xy 444.517406 10.334831)
			(xy 444.548382 10.254872) (xy 444.571849 10.172396) (xy 444.587605 10.088106) (xy 444.595517 10.002723)
			(xy 444.596012 9.959848) (xy 444.595517 9.916973) (xy 444.587605 9.83159) (xy 444.571849 9.7473)
			(xy 444.548382 9.664824) (xy 444.517406 9.584865) (xy 444.479184 9.508105) (xy 444.434043 9.435199)
			(xy 444.382367 9.36677) (xy 444.324598 9.3034) (xy 444.261228 9.245631) (xy 444.192799 9.193955)
			(xy 444.119893 9.148814) (xy 444.043133 9.110592) (xy 443.963174 9.079616) (xy 443.880698 9.056149)
			(xy 443.796408 9.040393) (xy 443.711025 9.032481) (xy 443.625275 9.032481) (xy 443.539892 9.040393)
			(xy 443.455602 9.056149) (xy 443.373126 9.079616) (xy 443.293167 9.110592) (xy 443.216407 9.148814)
			(xy 443.143501 9.193955) (xy 443.075072 9.245631) (xy 443.011702 9.3034) (xy 442.953933 9.36677)
			(xy 442.902257 9.435199) (xy 442.857116 9.508105) (xy 442.818894 9.584865) (xy 442.787918 9.664824)
			(xy 442.764451 9.7473) (xy 442.748695 9.83159) (xy 442.740783 9.916973) (xy 438.245517 9.916973)
			(xy 438.237605 9.83159) (xy 438.221849 9.7473) (xy 438.198382 9.664824) (xy 438.167406 9.584865)
			(xy 438.129184 9.508105) (xy 438.084043 9.435199) (xy 438.032367 9.36677) (xy 437.974598 9.3034)
			(xy 437.911228 9.245631) (xy 437.842799 9.193955) (xy 437.769893 9.148814) (xy 437.693133 9.110592)
			(xy 437.613174 9.079616) (xy 437.530698 9.056149) (xy 437.446408 9.040393) (xy 437.361025 9.032481)
			(xy 437.275275 9.032481) (xy 437.189892 9.040393) (xy 437.105602 9.056149) (xy 437.023126 9.079616)
			(xy 436.943167 9.110592) (xy 436.866407 9.148814) (xy 436.793501 9.193955) (xy 436.725072 9.245631)
			(xy 436.661702 9.3034) (xy 436.603933 9.36677) (xy 436.552257 9.435199) (xy 436.507116 9.508105)
			(xy 436.468894 9.584865) (xy 436.437918 9.664824) (xy 436.414451 9.7473) (xy 436.398695 9.83159)
			(xy 436.390783 9.916973) (xy 393.856731 9.916973) (xy 393.848819 9.83159) (xy 393.833063 9.7473)
			(xy 393.809596 9.664824) (xy 393.77862 9.584865) (xy 393.740398 9.508105) (xy 393.695257 9.435199)
			(xy 393.643581 9.36677) (xy 393.585812 9.3034) (xy 393.522442 9.245631) (xy 393.454013 9.193955)
			(xy 393.381107 9.148814) (xy 393.304347 9.110592) (xy 393.224388 9.079616) (xy 393.141912 9.056149)
			(xy 393.057622 9.040393) (xy 392.972239 9.032481) (xy 392.886489 9.032481) (xy 392.801106 9.040393)
			(xy 392.716816 9.056149) (xy 392.63434 9.079616) (xy 392.554381 9.110592) (xy 392.477621 9.148814)
			(xy 392.404715 9.193955) (xy 392.336286 9.245631) (xy 392.272916 9.3034) (xy 392.215147 9.36677)
			(xy 392.163471 9.435199) (xy 392.11833 9.508105) (xy 392.080108 9.584865) (xy 392.049132 9.664824)
			(xy 392.025665 9.7473) (xy 392.009909 9.83159) (xy 392.001997 9.916973) (xy 387.506731 9.916973)
			(xy 387.498819 9.83159) (xy 387.483063 9.7473) (xy 387.459596 9.664824) (xy 387.42862 9.584865) (xy 387.390398 9.508105)
			(xy 387.345257 9.435199) (xy 387.293581 9.36677) (xy 387.235812 9.3034) (xy 387.172442 9.245631)
			(xy 387.104013 9.193955) (xy 387.031107 9.148814) (xy 386.954347 9.110592) (xy 386.874388 9.079616)
			(xy 386.791912 9.056149) (xy 386.707622 9.040393) (xy 386.622239 9.032481) (xy 386.536489 9.032481)
			(xy 386.451106 9.040393) (xy 386.366816 9.056149) (xy 386.28434 9.079616) (xy 386.204381 9.110592)
			(xy 386.127621 9.148814) (xy 386.054715 9.193955) (xy 385.986286 9.245631) (xy 385.922916 9.3034)
			(xy 385.865147 9.36677) (xy 385.813471 9.435199) (xy 385.76833 9.508105) (xy 385.730108 9.584865)
			(xy 385.699132 9.664824) (xy 385.675665 9.7473) (xy 385.659909 9.83159) (xy 385.651997 9.916973)
			(xy 0.509016 9.916973) (xy 0.509016 7.335466) (xy 2.904225 7.335466) (xy 2.904225 7.464606) (xy 2.912175 7.593501)
			(xy 2.928045 7.721661) (xy 2.951774 7.848602) (xy 2.983273 7.973841) (xy 3.022422 8.096904) (xy 3.069073 8.217323)
			(xy 3.123048 8.334642) (xy 3.184143 8.448416) (xy 3.252126 8.558213) (xy 3.32674 8.663616) (xy 3.407701 8.764226)
			(xy 3.494701 8.859661) (xy 3.587412 8.94956) (xy 3.685482 9.033581) (xy 3.788537 9.111405) (xy 3.896188 9.182737)
			(xy 4.008027 9.247307) (xy 4.123628 9.304869) (xy 4.242553 9.355206) (xy 4.364352 9.398126) (xy 4.488562 9.433467)
			(xy 4.614711 9.461094) (xy 4.742323 9.480903) (xy 4.870912 9.492819) (xy 4.99999 9.496796) (xy 5.129068 9.492819)
			(xy 5.257657 9.480903) (xy 5.385269 9.461094) (xy 5.511418 9.433467) (xy 5.635628 9.398126) (xy 5.757427 9.355206)
			(xy 5.876352 9.304869) (xy 5.991953 9.247307) (xy 6.103792 9.182737) (xy 6.211443 9.111405) (xy 6.314498 9.033581)
			(xy 6.412568 8.94956) (xy 6.505279 8.859661) (xy 6.51416 8.849919) (xy 208.661241 8.849919) (xy 208.661241 8.935669)
			(xy 208.669153 9.021052) (xy 208.684909 9.105342) (xy 208.708376 9.187818) (xy 208.739352 9.267777)
			(xy 208.777574 9.344537) (xy 208.822715 9.417443) (xy 208.874391 9.485872) (xy 208.93216 9.549242)
			(xy 208.99553 9.607011) (xy 209.063959 9.658687) (xy 209.136865 9.703828) (xy 209.213625 9.74205)
			(xy 209.293584 9.773026) (xy 209.37606 9.796493) (xy 209.46035 9.812249) (xy 209.545733 9.820161)
			(xy 209.631483 9.820161) (xy 209.716866 9.812249) (xy 209.801156 9.796493) (xy 209.883632 9.773026)
			(xy 209.963591 9.74205) (xy 210.040351 9.703828) (xy 210.113257 9.658687) (xy 210.181686 9.607011)
			(xy 210.245056 9.549242) (xy 210.302825 9.485872) (xy 210.354501 9.417443) (xy 210.399642 9.344537)
			(xy 210.437864 9.267777) (xy 210.46884 9.187818) (xy 210.492307 9.105342) (xy 210.508063 9.021052)
			(xy 210.515975 8.935669) (xy 210.51647 8.892794) (xy 210.515975 8.849919) (xy 215.011241 8.849919)
			(xy 215.011241 8.935669) (xy 215.019153 9.021052) (xy 215.034909 9.105342) (xy 215.058376 9.187818)
			(xy 215.089352 9.267777) (xy 215.127574 9.344537) (xy 215.172715 9.417443) (xy 215.224391 9.485872)
			(xy 215.28216 9.549242) (xy 215.34553 9.607011) (xy 215.413959 9.658687) (xy 215.486865 9.703828)
			(xy 215.563625 9.74205) (xy 215.643584 9.773026) (xy 215.72606 9.796493) (xy 215.81035 9.812249)
			(xy 215.895733 9.820161) (xy 215.981483 9.820161) (xy 216.066866 9.812249) (xy 216.151156 9.796493)
			(xy 216.233632 9.773026) (xy 216.313591 9.74205) (xy 216.390351 9.703828) (xy 216.463257 9.658687)
			(xy 216.531686 9.607011) (xy 216.595056 9.549242) (xy 216.652825 9.485872) (xy 216.704501 9.417443)
			(xy 216.749642 9.344537) (xy 216.787864 9.267777) (xy 216.81884 9.187818) (xy 216.842307 9.105342)
			(xy 216.858063 9.021052) (xy 216.865975 8.935669) (xy 216.86647 8.892794) (xy 216.865975 8.849919)
			(xy 296.143921 8.849919) (xy 296.143921 8.935669) (xy 296.151833 9.021052) (xy 296.167589 9.105342)
			(xy 296.191056 9.187818) (xy 296.222032 9.267777) (xy 296.260254 9.344537) (xy 296.305395 9.417443)
			(xy 296.357071 9.485872) (xy 296.41484 9.549242) (xy 296.47821 9.607011) (xy 296.546639 9.658687)
			(xy 296.619545 9.703828) (xy 296.696305 9.74205) (xy 296.776264 9.773026) (xy 296.85874 9.796493)
			(xy 296.94303 9.812249) (xy 297.028413 9.820161) (xy 297.114163 9.820161) (xy 297.199546 9.812249)
			(xy 297.283836 9.796493) (xy 297.366312 9.773026) (xy 297.446271 9.74205) (xy 297.523031 9.703828)
			(xy 297.595937 9.658687) (xy 297.664366 9.607011) (xy 297.727736 9.549242) (xy 297.785505 9.485872)
			(xy 297.837181 9.417443) (xy 297.882322 9.344537) (xy 297.920544 9.267777) (xy 297.95152 9.187818)
			(xy 297.974987 9.105342) (xy 297.990743 9.021052) (xy 297.998655 8.935669) (xy 297.99915 8.892794)
			(xy 297.998655 8.849919) (xy 302.493921 8.849919) (xy 302.493921 8.935669) (xy 302.501833 9.021052)
			(xy 302.517589 9.105342) (xy 302.541056 9.187818) (xy 302.572032 9.267777) (xy 302.610254 9.344537)
			(xy 302.655395 9.417443) (xy 302.707071 9.485872) (xy 302.76484 9.549242) (xy 302.82821 9.607011)
			(xy 302.896639 9.658687) (xy 302.969545 9.703828) (xy 303.046305 9.74205) (xy 303.126264 9.773026)
			(xy 303.20874 9.796493) (xy 303.29303 9.812249) (xy 303.378413 9.820161) (xy 303.464163 9.820161)
			(xy 303.549546 9.812249) (xy 303.633836 9.796493) (xy 303.716312 9.773026) (xy 303.796271 9.74205)
			(xy 303.873031 9.703828) (xy 303.945937 9.658687) (xy 304.014366 9.607011) (xy 304.077736 9.549242)
			(xy 304.135505 9.485872) (xy 304.187181 9.417443) (xy 304.232322 9.344537) (xy 304.270544 9.267777)
			(xy 304.30152 9.187818) (xy 304.324987 9.105342) (xy 304.340743 9.021052) (xy 304.348655 8.935669)
			(xy 304.34915 8.892794) (xy 304.348655 8.849919) (xy 311.155321 8.849919) (xy 311.155321 8.935669)
			(xy 311.163233 9.021052) (xy 311.178989 9.105342) (xy 311.202456 9.187818) (xy 311.233432 9.267777)
			(xy 311.271654 9.344537) (xy 311.316795 9.417443) (xy 311.368471 9.485872) (xy 311.42624 9.549242)
			(xy 311.48961 9.607011) (xy 311.558039 9.658687) (xy 311.630945 9.703828) (xy 311.707705 9.74205)
			(xy 311.787664 9.773026) (xy 311.87014 9.796493) (xy 311.95443 9.812249) (xy 312.039813 9.820161)
			(xy 312.125563 9.820161) (xy 312.210946 9.812249) (xy 312.295236 9.796493) (xy 312.377712 9.773026)
			(xy 312.457671 9.74205) (xy 312.534431 9.703828) (xy 312.607337 9.658687) (xy 312.675766 9.607011)
			(xy 312.739136 9.549242) (xy 312.796905 9.485872) (xy 312.848581 9.417443) (xy 312.893722 9.344537)
			(xy 312.931944 9.267777) (xy 312.96292 9.187818) (xy 312.986387 9.105342) (xy 313.002143 9.021052)
			(xy 313.010055 8.935669) (xy 313.01055 8.892794) (xy 313.010055 8.849919) (xy 317.505321 8.849919)
			(xy 317.505321 8.935669) (xy 317.513233 9.021052) (xy 317.528989 9.105342) (xy 317.552456 9.187818)
			(xy 317.583432 9.267777) (xy 317.621654 9.344537) (xy 317.666795 9.417443) (xy 317.718471 9.485872)
			(xy 317.77624 9.549242) (xy 317.83961 9.607011) (xy 317.908039 9.658687) (xy 317.980945 9.703828)
			(xy 318.057705 9.74205) (xy 318.137664 9.773026) (xy 318.22014 9.796493) (xy 318.30443 9.812249)
			(xy 318.389813 9.820161) (xy 318.475563 9.820161) (xy 318.560946 9.812249) (xy 318.645236 9.796493)
			(xy 318.727712 9.773026) (xy 318.807671 9.74205) (xy 318.884431 9.703828) (xy 318.957337 9.658687)
			(xy 319.025766 9.607011) (xy 319.089136 9.549242) (xy 319.146905 9.485872) (xy 319.198581 9.417443)
			(xy 319.243722 9.344537) (xy 319.281944 9.267777) (xy 319.31292 9.187818) (xy 319.336387 9.105342)
			(xy 319.352143 9.021052) (xy 319.360055 8.935669) (xy 319.36055 8.892794) (xy 319.360055 8.849919)
			(xy 361.894107 8.849919) (xy 361.894107 8.935669) (xy 361.902019 9.021052) (xy 361.917775 9.105342)
			(xy 361.941242 9.187818) (xy 361.972218 9.267777) (xy 362.01044 9.344537) (xy 362.055581 9.417443)
			(xy 362.107257 9.485872) (xy 362.165026 9.549242) (xy 362.228396 9.607011) (xy 362.296825 9.658687)
			(xy 362.369731 9.703828) (xy 362.446491 9.74205) (xy 362.52645 9.773026) (xy 362.608926 9.796493)
			(xy 362.693216 9.812249) (xy 362.778599 9.820161) (xy 362.864349 9.820161) (xy 362.949732 9.812249)
			(xy 363.034022 9.796493) (xy 363.116498 9.773026) (xy 363.196457 9.74205) (xy 363.273217 9.703828)
			(xy 363.346123 9.658687) (xy 363.414552 9.607011) (xy 363.477922 9.549242) (xy 363.535691 9.485872)
			(xy 363.587367 9.417443) (xy 363.632508 9.344537) (xy 363.67073 9.267777) (xy 363.701706 9.187818)
			(xy 363.725173 9.105342) (xy 363.740929 9.021052) (xy 363.748841 8.935669) (xy 363.749336 8.892794)
			(xy 363.748841 8.849919) (xy 368.244107 8.849919) (xy 368.244107 8.935669) (xy 368.252019 9.021052)
			(xy 368.267775 9.105342) (xy 368.291242 9.187818) (xy 368.322218 9.267777) (xy 368.36044 9.344537)
			(xy 368.405581 9.417443) (xy 368.457257 9.485872) (xy 368.515026 9.549242) (xy 368.578396 9.607011)
			(xy 368.646825 9.658687) (xy 368.719731 9.703828) (xy 368.796491 9.74205) (xy 368.87645 9.773026)
			(xy 368.958926 9.796493) (xy 369.043216 9.812249) (xy 369.128599 9.820161) (xy 369.214349 9.820161)
			(xy 369.299732 9.812249) (xy 369.384022 9.796493) (xy 369.466498 9.773026) (xy 369.546457 9.74205)
			(xy 369.623217 9.703828) (xy 369.696123 9.658687) (xy 369.764552 9.607011) (xy 369.827922 9.549242)
			(xy 369.885691 9.485872) (xy 369.937367 9.417443) (xy 369.982508 9.344537) (xy 370.02073 9.267777)
			(xy 370.051706 9.187818) (xy 370.075173 9.105342) (xy 370.090929 9.021052) (xy 370.098841 8.935669)
			(xy 370.099336 8.892794) (xy 370.098841 8.849919) (xy 370.090929 8.764536) (xy 370.075173 8.680246)
			(xy 370.051706 8.59777) (xy 370.02073 8.517811) (xy 369.982508 8.441051) (xy 369.937367 8.368145)
			(xy 369.885691 8.299716) (xy 369.827922 8.236346) (xy 369.764552 8.178577) (xy 369.696123 8.126901)
			(xy 369.623217 8.08176) (xy 369.546457 8.043538) (xy 369.466498 8.012562) (xy 369.384022 7.989095)
			(xy 369.299732 7.973339) (xy 369.214349 7.965427) (xy 369.128599 7.965427) (xy 369.043216 7.973339)
			(xy 368.958926 7.989095) (xy 368.87645 8.012562) (xy 368.796491 8.043538) (xy 368.719731 8.08176)
			(xy 368.646825 8.126901) (xy 368.578396 8.178577) (xy 368.515026 8.236346) (xy 368.457257 8.299716)
			(xy 368.405581 8.368145) (xy 368.36044 8.441051) (xy 368.322218 8.517811) (xy 368.291242 8.59777)
			(xy 368.267775 8.680246) (xy 368.252019 8.764536) (xy 368.244107 8.849919) (xy 363.748841 8.849919)
			(xy 363.740929 8.764536) (xy 363.725173 8.680246) (xy 363.701706 8.59777) (xy 363.67073 8.517811)
			(xy 363.632508 8.441051) (xy 363.587367 8.368145) (xy 363.535691 8.299716) (xy 363.477922 8.236346)
			(xy 363.414552 8.178577) (xy 363.346123 8.126901) (xy 363.273217 8.08176) (xy 363.196457 8.043538)
			(xy 363.116498 8.012562) (xy 363.034022 7.989095) (xy 362.949732 7.973339) (xy 362.864349 7.965427)
			(xy 362.778599 7.965427) (xy 362.693216 7.973339) (xy 362.608926 7.989095) (xy 362.52645 8.012562)
			(xy 362.446491 8.043538) (xy 362.369731 8.08176) (xy 362.296825 8.126901) (xy 362.228396 8.178577)
			(xy 362.165026 8.236346) (xy 362.107257 8.299716) (xy 362.055581 8.368145) (xy 362.01044 8.441051)
			(xy 361.972218 8.517811) (xy 361.941242 8.59777) (xy 361.917775 8.680246) (xy 361.902019 8.764536)
			(xy 361.894107 8.849919) (xy 319.360055 8.849919) (xy 319.352143 8.764536) (xy 319.336387 8.680246)
			(xy 319.31292 8.59777) (xy 319.281944 8.517811) (xy 319.243722 8.441051) (xy 319.198581 8.368145)
			(xy 319.146905 8.299716) (xy 319.089136 8.236346) (xy 319.025766 8.178577) (xy 318.957337 8.126901)
			(xy 318.884431 8.08176) (xy 318.807671 8.043538) (xy 318.727712 8.012562) (xy 318.645236 7.989095)
			(xy 318.560946 7.973339) (xy 318.475563 7.965427) (xy 318.389813 7.965427) (xy 318.30443 7.973339)
			(xy 318.22014 7.989095) (xy 318.137664 8.012562) (xy 318.057705 8.043538) (xy 317.980945 8.08176)
			(xy 317.908039 8.126901) (xy 317.83961 8.178577) (xy 317.77624 8.236346) (xy 317.718471 8.299716)
			(xy 317.666795 8.368145) (xy 317.621654 8.441051) (xy 317.583432 8.517811) (xy 317.552456 8.59777)
			(xy 317.528989 8.680246) (xy 317.513233 8.764536) (xy 317.505321 8.849919) (xy 313.010055 8.849919)
			(xy 313.002143 8.764536) (xy 312.986387 8.680246) (xy 312.96292 8.59777) (xy 312.931944 8.517811)
			(xy 312.893722 8.441051) (xy 312.848581 8.368145) (xy 312.796905 8.299716) (xy 312.739136 8.236346)
			(xy 312.675766 8.178577) (xy 312.607337 8.126901) (xy 312.534431 8.08176) (xy 312.457671 8.043538)
			(xy 312.377712 8.012562) (xy 312.295236 7.989095) (xy 312.210946 7.973339) (xy 312.125563 7.965427)
			(xy 312.039813 7.965427) (xy 311.95443 7.973339) (xy 311.87014 7.989095) (xy 311.787664 8.012562)
			(xy 311.707705 8.043538) (xy 311.630945 8.08176) (xy 311.558039 8.126901) (xy 311.48961 8.178577)
			(xy 311.42624 8.236346) (xy 311.368471 8.299716) (xy 311.316795 8.368145) (xy 311.271654 8.441051)
			(xy 311.233432 8.517811) (xy 311.202456 8.59777) (xy 311.178989 8.680246) (xy 311.163233 8.764536)
			(xy 311.155321 8.849919) (xy 304.348655 8.849919) (xy 304.340743 8.764536) (xy 304.324987 8.680246)
			(xy 304.30152 8.59777) (xy 304.270544 8.517811) (xy 304.232322 8.441051) (xy 304.187181 8.368145)
			(xy 304.135505 8.299716) (xy 304.077736 8.236346) (xy 304.014366 8.178577) (xy 303.945937 8.126901)
			(xy 303.873031 8.08176) (xy 303.796271 8.043538) (xy 303.716312 8.012562) (xy 303.633836 7.989095)
			(xy 303.549546 7.973339) (xy 303.464163 7.965427) (xy 303.378413 7.965427) (xy 303.29303 7.973339)
			(xy 303.20874 7.989095) (xy 303.126264 8.012562) (xy 303.046305 8.043538) (xy 302.969545 8.08176)
			(xy 302.896639 8.126901) (xy 302.82821 8.178577) (xy 302.76484 8.236346) (xy 302.707071 8.299716)
			(xy 302.655395 8.368145) (xy 302.610254 8.441051) (xy 302.572032 8.517811) (xy 302.541056 8.59777)
			(xy 302.517589 8.680246) (xy 302.501833 8.764536) (xy 302.493921 8.849919) (xy 297.998655 8.849919)
			(xy 297.990743 8.764536) (xy 297.974987 8.680246) (xy 297.95152 8.59777) (xy 297.920544 8.517811)
			(xy 297.882322 8.441051) (xy 297.837181 8.368145) (xy 297.785505 8.299716) (xy 297.727736 8.236346)
			(xy 297.664366 8.178577) (xy 297.595937 8.126901) (xy 297.523031 8.08176) (xy 297.446271 8.043538)
			(xy 297.366312 8.012562) (xy 297.283836 7.989095) (xy 297.199546 7.973339) (xy 297.114163 7.965427)
			(xy 297.028413 7.965427) (xy 296.94303 7.973339) (xy 296.85874 7.989095) (xy 296.776264 8.012562)
			(xy 296.696305 8.043538) (xy 296.619545 8.08176) (xy 296.546639 8.126901) (xy 296.47821 8.178577)
			(xy 296.41484 8.236346) (xy 296.357071 8.299716) (xy 296.305395 8.368145) (xy 296.260254 8.441051)
			(xy 296.222032 8.517811) (xy 296.191056 8.59777) (xy 296.167589 8.680246) (xy 296.151833 8.764536)
			(xy 296.143921 8.849919) (xy 216.865975 8.849919) (xy 216.858063 8.764536) (xy 216.842307 8.680246)
			(xy 216.81884 8.59777) (xy 216.787864 8.517811) (xy 216.749642 8.441051) (xy 216.704501 8.368145)
			(xy 216.652825 8.299716) (xy 216.595056 8.236346) (xy 216.531686 8.178577) (xy 216.463257 8.126901)
			(xy 216.390351 8.08176) (xy 216.313591 8.043538) (xy 216.233632 8.012562) (xy 216.151156 7.989095)
			(xy 216.066866 7.973339) (xy 215.981483 7.965427) (xy 215.895733 7.965427) (xy 215.81035 7.973339)
			(xy 215.72606 7.989095) (xy 215.643584 8.012562) (xy 215.563625 8.043538) (xy 215.486865 8.08176)
			(xy 215.413959 8.126901) (xy 215.34553 8.178577) (xy 215.28216 8.236346) (xy 215.224391 8.299716)
			(xy 215.172715 8.368145) (xy 215.127574 8.441051) (xy 215.089352 8.517811) (xy 215.058376 8.59777)
			(xy 215.034909 8.680246) (xy 215.019153 8.764536) (xy 215.011241 8.849919) (xy 210.515975 8.849919)
			(xy 210.508063 8.764536) (xy 210.492307 8.680246) (xy 210.46884 8.59777) (xy 210.437864 8.517811)
			(xy 210.399642 8.441051) (xy 210.354501 8.368145) (xy 210.302825 8.299716) (xy 210.245056 8.236346)
			(xy 210.181686 8.178577) (xy 210.113257 8.126901) (xy 210.040351 8.08176) (xy 209.963591 8.043538)
			(xy 209.883632 8.012562) (xy 209.801156 7.989095) (xy 209.716866 7.973339) (xy 209.631483 7.965427)
			(xy 209.545733 7.965427) (xy 209.46035 7.973339) (xy 209.37606 7.989095) (xy 209.293584 8.012562)
			(xy 209.213625 8.043538) (xy 209.136865 8.08176) (xy 209.063959 8.126901) (xy 208.99553 8.178577)
			(xy 208.93216 8.236346) (xy 208.874391 8.299716) (xy 208.822715 8.368145) (xy 208.777574 8.441051)
			(xy 208.739352 8.517811) (xy 208.708376 8.59777) (xy 208.684909 8.680246) (xy 208.669153 8.764536)
			(xy 208.661241 8.849919) (xy 6.51416 8.849919) (xy 6.592279 8.764226) (xy 6.67324 8.663616) (xy 6.747854 8.558213)
			(xy 6.815837 8.448416) (xy 6.876932 8.334642) (xy 6.930907 8.217323) (xy 6.977558 8.096904) (xy 7.016707 7.973841)
			(xy 7.048206 7.848602) (xy 7.071935 7.721661) (xy 7.087805 7.593501) (xy 7.095755 7.464606) (xy 7.096252 7.400036)
			(xy 7.095755 7.335466) (xy 7.092973 7.290359) (xy 93.985575 7.290359) (xy 93.985575 7.376109) (xy 93.993487 7.461492)
			(xy 94.009243 7.545782) (xy 94.03271 7.628258) (xy 94.063686 7.708217) (xy 94.101908 7.784977) (xy 94.147049 7.857883)
			(xy 94.198725 7.926312) (xy 94.256494 7.989682) (xy 94.319864 8.047451) (xy 94.388293 8.099127) (xy 94.461199 8.144268)
			(xy 94.537959 8.18249) (xy 94.617918 8.213466) (xy 94.700394 8.236933) (xy 94.784684 8.252689) (xy 94.870067 8.260601)
			(xy 94.955817 8.260601) (xy 95.0412 8.252689) (xy 95.12549 8.236933) (xy 95.207966 8.213466) (xy 95.287925 8.18249)
			(xy 95.364685 8.144268) (xy 95.437591 8.099127) (xy 95.50602 8.047451) (xy 95.56939 7.989682) (xy 95.627159 7.926312)
			(xy 95.678835 7.857883) (xy 95.723976 7.784977) (xy 95.762198 7.708217) (xy 95.793174 7.628258) (xy 95.816641 7.545782)
			(xy 95.832397 7.461492) (xy 95.840309 7.376109) (xy 95.840804 7.333234) (xy 95.840309 7.290359) (xy 100.335575 7.290359)
			(xy 100.335575 7.376109) (xy 100.343487 7.461492) (xy 100.359243 7.545782) (xy 100.38271 7.628258)
			(xy 100.413686 7.708217) (xy 100.451908 7.784977) (xy 100.497049 7.857883) (xy 100.548725 7.926312)
			(xy 100.606494 7.989682) (xy 100.669864 8.047451) (xy 100.738293 8.099127) (xy 100.811199 8.144268)
			(xy 100.887959 8.18249) (xy 100.967918 8.213466) (xy 101.050394 8.236933) (xy 101.134684 8.252689)
			(xy 101.220067 8.260601) (xy 101.305817 8.260601) (xy 101.3912 8.252689) (xy 101.47549 8.236933)
			(xy 101.557966 8.213466) (xy 101.637925 8.18249) (xy 101.714685 8.144268) (xy 101.787591 8.099127)
			(xy 101.85602 8.047451) (xy 101.91939 7.989682) (xy 101.977159 7.926312) (xy 102.028835 7.857883)
			(xy 102.073976 7.784977) (xy 102.112198 7.708217) (xy 102.143174 7.628258) (xy 102.166641 7.545782)
			(xy 102.182397 7.461492) (xy 102.190309 7.376109) (xy 102.190804 7.333234) (xy 102.190309 7.290359)
			(xy 181.468255 7.290359) (xy 181.468255 7.376109) (xy 181.476167 7.461492) (xy 181.491923 7.545782)
			(xy 181.51539 7.628258) (xy 181.546366 7.708217) (xy 181.584588 7.784977) (xy 181.629729 7.857883)
			(xy 181.681405 7.926312) (xy 181.739174 7.989682) (xy 181.802544 8.047451) (xy 181.870973 8.099127)
			(xy 181.943879 8.144268) (xy 182.020639 8.18249) (xy 182.100598 8.213466) (xy 182.183074 8.236933)
			(xy 182.267364 8.252689) (xy 182.352747 8.260601) (xy 182.438497 8.260601) (xy 182.52388 8.252689)
			(xy 182.60817 8.236933) (xy 182.690646 8.213466) (xy 182.770605 8.18249) (xy 182.847365 8.144268)
			(xy 182.920271 8.099127) (xy 182.9887 8.047451) (xy 183.05207 7.989682) (xy 183.109839 7.926312)
			(xy 183.161515 7.857883) (xy 183.206656 7.784977) (xy 183.244878 7.708217) (xy 183.275854 7.628258)
			(xy 183.299321 7.545782) (xy 183.315077 7.461492) (xy 183.322989 7.376109) (xy 183.323484 7.333234)
			(xy 183.322989 7.290359) (xy 187.818255 7.290359) (xy 187.818255 7.376109) (xy 187.826167 7.461492)
			(xy 187.841923 7.545782) (xy 187.86539 7.628258) (xy 187.896366 7.708217) (xy 187.934588 7.784977)
			(xy 187.979729 7.857883) (xy 188.031405 7.926312) (xy 188.089174 7.989682) (xy 188.152544 8.047451)
			(xy 188.220973 8.099127) (xy 188.293879 8.144268) (xy 188.370639 8.18249) (xy 188.450598 8.213466)
			(xy 188.533074 8.236933) (xy 188.617364 8.252689) (xy 188.702747 8.260601) (xy 188.788497 8.260601)
			(xy 188.87388 8.252689) (xy 188.95817 8.236933) (xy 189.040646 8.213466) (xy 189.120605 8.18249)
			(xy 189.197365 8.144268) (xy 189.270271 8.099127) (xy 189.3387 8.047451) (xy 189.40207 7.989682)
			(xy 189.459839 7.926312) (xy 189.511515 7.857883) (xy 189.556656 7.784977) (xy 189.594878 7.708217)
			(xy 189.625854 7.628258) (xy 189.649321 7.545782) (xy 189.665077 7.461492) (xy 189.672989 7.376109)
			(xy 189.673484 7.333234) (xy 189.672989 7.290359) (xy 189.665077 7.204976) (xy 189.649321 7.120686)
			(xy 189.625854 7.03821) (xy 189.594878 6.958251) (xy 189.556656 6.881491) (xy 189.511515 6.808585)
			(xy 189.459839 6.740156) (xy 189.40207 6.676786) (xy 189.3387 6.619017) (xy 189.270271 6.567341)
			(xy 189.197365 6.5222) (xy 189.120605 6.483978) (xy 189.040646 6.453002) (xy 188.95817 6.429535)
			(xy 188.87388 6.413779) (xy 188.788497 6.405867) (xy 188.702747 6.405867) (xy 188.617364 6.413779)
			(xy 188.533074 6.429535) (xy 188.450598 6.453002) (xy 188.370639 6.483978) (xy 188.293879 6.5222)
			(xy 188.220973 6.567341) (xy 188.152544 6.619017) (xy 188.089174 6.676786) (xy 188.031405 6.740156)
			(xy 187.979729 6.808585) (xy 187.934588 6.881491) (xy 187.896366 6.958251) (xy 187.86539 7.03821)
			(xy 187.841923 7.120686) (xy 187.826167 7.204976) (xy 187.818255 7.290359) (xy 183.322989 7.290359)
			(xy 183.315077 7.204976) (xy 183.299321 7.120686) (xy 183.275854 7.03821) (xy 183.244878 6.958251)
			(xy 183.206656 6.881491) (xy 183.161515 6.808585) (xy 183.109839 6.740156) (xy 183.05207 6.676786)
			(xy 182.9887 6.619017) (xy 182.920271 6.567341) (xy 182.847365 6.5222) (xy 182.770605 6.483978) (xy 182.690646 6.453002)
			(xy 182.60817 6.429535) (xy 182.52388 6.413779) (xy 182.438497 6.405867) (xy 182.352747 6.405867)
			(xy 182.267364 6.413779) (xy 182.183074 6.429535) (xy 182.100598 6.453002) (xy 182.020639 6.483978)
			(xy 181.943879 6.5222) (xy 181.870973 6.567341) (xy 181.802544 6.619017) (xy 181.739174 6.676786)
			(xy 181.681405 6.740156) (xy 181.629729 6.808585) (xy 181.584588 6.881491) (xy 181.546366 6.958251)
			(xy 181.51539 7.03821) (xy 181.491923 7.120686) (xy 181.476167 7.204976) (xy 181.468255 7.290359)
			(xy 102.190309 7.290359) (xy 102.182397 7.204976) (xy 102.166641 7.120686) (xy 102.143174 7.03821)
			(xy 102.112198 6.958251) (xy 102.073976 6.881491) (xy 102.028835 6.808585) (xy 101.977159 6.740156)
			(xy 101.91939 6.676786) (xy 101.85602 6.619017) (xy 101.787591 6.567341) (xy 101.714685 6.5222) (xy 101.637925 6.483978)
			(xy 101.557966 6.453002) (xy 101.47549 6.429535) (xy 101.3912 6.413779) (xy 101.305817 6.405867)
			(xy 101.220067 6.405867) (xy 101.134684 6.413779) (xy 101.050394 6.429535) (xy 100.967918 6.453002)
			(xy 100.887959 6.483978) (xy 100.811199 6.5222) (xy 100.738293 6.567341) (xy 100.669864 6.619017)
			(xy 100.606494 6.676786) (xy 100.548725 6.740156) (xy 100.497049 6.808585) (xy 100.451908 6.881491)
			(xy 100.413686 6.958251) (xy 100.38271 7.03821) (xy 100.359243 7.120686) (xy 100.343487 7.204976)
			(xy 100.335575 7.290359) (xy 95.840309 7.290359) (xy 95.832397 7.204976) (xy 95.816641 7.120686)
			(xy 95.793174 7.03821) (xy 95.762198 6.958251) (xy 95.723976 6.881491) (xy 95.678835 6.808585) (xy 95.627159 6.740156)
			(xy 95.56939 6.676786) (xy 95.50602 6.619017) (xy 95.437591 6.567341) (xy 95.364685 6.5222) (xy 95.287925 6.483978)
			(xy 95.207966 6.453002) (xy 95.12549 6.429535) (xy 95.0412 6.413779) (xy 94.955817 6.405867) (xy 94.870067 6.405867)
			(xy 94.784684 6.413779) (xy 94.700394 6.429535) (xy 94.617918 6.453002) (xy 94.537959 6.483978) (xy 94.461199 6.5222)
			(xy 94.388293 6.567341) (xy 94.319864 6.619017) (xy 94.256494 6.676786) (xy 94.198725 6.740156) (xy 94.147049 6.808585)
			(xy 94.101908 6.881491) (xy 94.063686 6.958251) (xy 94.03271 7.03821) (xy 94.009243 7.120686) (xy 93.993487 7.204976)
			(xy 93.985575 7.290359) (xy 7.092973 7.290359) (xy 7.087805 7.206571) (xy 7.071935 7.078411) (xy 7.048206 6.95147)
			(xy 7.016707 6.826231) (xy 6.977558 6.703168) (xy 6.930907 6.582749) (xy 6.876932 6.46543) (xy 6.815837 6.351656)
			(xy 6.747854 6.241859) (xy 6.67324 6.136456) (xy 6.592279 6.035846) (xy 6.505279 5.940411) (xy 6.412568 5.850512)
			(xy 6.314498 5.766491) (xy 6.211443 5.688667) (xy 6.103792 5.617335) (xy 5.991953 5.552765) (xy 5.876352 5.495203)
			(xy 5.757427 5.444866) (xy 5.635628 5.401946) (xy 5.511418 5.366605) (xy 5.385269 5.338978) (xy 5.257657 5.319169)
			(xy 5.129068 5.307253) (xy 4.99999 5.303277) (xy 4.870912 5.307253) (xy 4.742323 5.319169) (xy 4.614711 5.338978)
			(xy 4.488562 5.366605) (xy 4.364352 5.401946) (xy 4.242553 5.444866) (xy 4.123628 5.495203) (xy 4.008027 5.552765)
			(xy 3.896188 5.617335) (xy 3.788537 5.688667) (xy 3.685482 5.766491) (xy 3.587412 5.850512) (xy 3.494701 5.940411)
			(xy 3.407701 6.035846) (xy 3.32674 6.136456) (xy 3.252126 6.241859) (xy 3.184143 6.351656) (xy 3.123048 6.46543)
			(xy 3.069073 6.582749) (xy 3.022422 6.703168) (xy 2.983273 6.826231) (xy 2.951774 6.95147) (xy 2.928045 7.078411)
			(xy 2.912175 7.206571) (xy 2.904225 7.335466) (xy 0.509016 7.335466) (xy 0.509016 4.750359) (xy 93.985575 4.750359)
			(xy 93.985575 4.836109) (xy 93.993487 4.921492) (xy 94.009243 5.005782) (xy 94.03271 5.088258) (xy 94.063686 5.168217)
			(xy 94.101908 5.244977) (xy 94.147049 5.317883) (xy 94.198725 5.386312) (xy 94.256494 5.449682) (xy 94.319864 5.507451)
			(xy 94.388293 5.559127) (xy 94.461199 5.604268) (xy 94.537959 5.64249) (xy 94.617918 5.673466) (xy 94.700394 5.696933)
			(xy 94.784684 5.712689) (xy 94.870067 5.720601) (xy 94.955817 5.720601) (xy 95.0412 5.712689) (xy 95.12549 5.696933)
			(xy 95.207966 5.673466) (xy 95.287925 5.64249) (xy 95.308598 5.632196) (xy 98.842576 5.632196) (xy 98.842576 6.495796)
			(xy 98.84308 6.525332) (xy 98.851124 6.583854) (xy 98.867061 6.640736) (xy 98.890596 6.694918) (xy 98.921289 6.745391)
			(xy 98.958569 6.791214) (xy 99.001741 6.831534) (xy 99.050001 6.8656) (xy 99.102451 6.892777) (xy 99.158112 6.912559)
			(xy 99.215949 6.924578) (xy 99.274884 6.928609) (xy 99.333819 6.924578) (xy 99.391656 6.912559) (xy 99.447317 6.892777)
			(xy 99.499767 6.8656) (xy 99.548027 6.831534) (xy 99.591199 6.791214) (xy 99.628479 6.745391) (xy 99.659172 6.694918)
			(xy 99.682707 6.640736) (xy 99.698644 6.583854) (xy 99.706688 6.525332) (xy 99.707192 6.495796) (xy 99.707192 5.632196)
			(xy 99.706688 5.60266) (xy 99.698644 5.544138) (xy 99.682707 5.487256) (xy 99.659172 5.433074) (xy 99.628479 5.382601)
			(xy 99.591199 5.336778) (xy 99.548027 5.296458) (xy 99.499767 5.262392) (xy 99.447317 5.235215) (xy 99.391656 5.215433)
			(xy 99.333819 5.203414) (xy 99.274884 5.199383) (xy 99.215949 5.203414) (xy 99.158112 5.215433) (xy 99.102451 5.235215)
			(xy 99.050001 5.262392) (xy 99.001741 5.296458) (xy 98.958569 5.336778) (xy 98.921289 5.382601) (xy 98.890596 5.433074)
			(xy 98.867061 5.487256) (xy 98.851124 5.544138) (xy 98.84308 5.60266) (xy 98.842576 5.632196) (xy 95.308598 5.632196)
			(xy 95.364685 5.604268) (xy 95.437591 5.559127) (xy 95.50602 5.507451) (xy 95.56939 5.449682) (xy 95.627159 5.386312)
			(xy 95.678835 5.317883) (xy 95.723976 5.244977) (xy 95.762198 5.168217) (xy 95.793174 5.088258) (xy 95.816641 5.005782)
			(xy 95.832397 4.921492) (xy 95.840309 4.836109) (xy 95.840804 4.793234) (xy 95.840309 4.750359) (xy 100.335575 4.750359)
			(xy 100.335575 4.836109) (xy 100.343487 4.921492) (xy 100.359243 5.005782) (xy 100.38271 5.088258)
			(xy 100.413686 5.168217) (xy 100.451908 5.244977) (xy 100.497049 5.317883) (xy 100.548725 5.386312)
			(xy 100.606494 5.449682) (xy 100.669864 5.507451) (xy 100.738293 5.559127) (xy 100.811199 5.604268)
			(xy 100.887959 5.64249) (xy 100.967918 5.673466) (xy 101.050394 5.696933) (xy 101.134684 5.712689)
			(xy 101.220067 5.720601) (xy 101.305817 5.720601) (xy 101.3912 5.712689) (xy 101.47549 5.696933)
			(xy 101.557966 5.673466) (xy 101.637925 5.64249) (xy 101.714685 5.604268) (xy 101.787591 5.559127)
			(xy 101.85602 5.507451) (xy 101.91939 5.449682) (xy 101.977159 5.386312) (xy 102.028835 5.317883)
			(xy 102.073976 5.244977) (xy 102.112198 5.168217) (xy 102.143174 5.088258) (xy 102.166641 5.005782)
			(xy 102.182397 4.921492) (xy 102.190309 4.836109) (xy 102.190804 4.793234) (xy 102.190309 4.750359)
			(xy 181.468255 4.750359) (xy 181.468255 4.836109) (xy 181.476167 4.921492) (xy 181.491923 5.005782)
			(xy 181.51539 5.088258) (xy 181.546366 5.168217) (xy 181.584588 5.244977) (xy 181.629729 5.317883)
			(xy 181.681405 5.386312) (xy 181.739174 5.449682) (xy 181.802544 5.507451) (xy 181.870973 5.559127)
			(xy 181.943879 5.604268) (xy 182.020639 5.64249) (xy 182.100598 5.673466) (xy 182.183074 5.696933)
			(xy 182.267364 5.712689) (xy 182.352747 5.720601) (xy 182.438497 5.720601) (xy 182.52388 5.712689)
			(xy 182.60817 5.696933) (xy 182.690646 5.673466) (xy 182.770605 5.64249) (xy 182.791278 5.632196)
			(xy 183.953912 5.632196) (xy 183.953912 6.495796) (xy 183.954416 6.525332) (xy 183.96246 6.583854)
			(xy 183.978397 6.640736) (xy 184.001932 6.694918) (xy 184.032625 6.745391) (xy 184.069905 6.791214)
			(xy 184.113077 6.831534) (xy 184.161337 6.8656) (xy 184.213787 6.892777) (xy 184.269448 6.912559)
			(xy 184.327285 6.924578) (xy 184.38622 6.928609) (xy 184.445155 6.924578) (xy 184.502992 6.912559)
			(xy 184.558653 6.892777) (xy 184.611103 6.8656) (xy 184.659363 6.831534) (xy 184.702535 6.791214)
			(xy 184.739815 6.745391) (xy 184.770508 6.694918) (xy 184.794043 6.640736) (xy 184.80998 6.583854)
			(xy 184.818024 6.525332) (xy 184.818528 6.495796) (xy 184.818528 6.309919) (xy 208.661241 6.309919)
			(xy 208.661241 6.395669) (xy 208.669153 6.481052) (xy 208.684909 6.565342) (xy 208.708376 6.647818)
			(xy 208.739352 6.727777) (xy 208.777574 6.804537) (xy 208.822715 6.877443) (xy 208.874391 6.945872)
			(xy 208.93216 7.009242) (xy 208.99553 7.067011) (xy 209.063959 7.118687) (xy 209.136865 7.163828)
			(xy 209.213625 7.20205) (xy 209.293584 7.233026) (xy 209.37606 7.256493) (xy 209.46035 7.272249)
			(xy 209.545733 7.280161) (xy 209.631483 7.280161) (xy 209.716866 7.272249) (xy 209.801156 7.256493)
			(xy 209.883632 7.233026) (xy 209.963591 7.20205) (xy 210.040351 7.163828) (xy 210.113257 7.118687)
			(xy 210.181686 7.067011) (xy 210.245056 7.009242) (xy 210.302825 6.945872) (xy 210.354501 6.877443)
			(xy 210.399642 6.804537) (xy 210.437864 6.727777) (xy 210.46884 6.647818) (xy 210.492307 6.565342)
			(xy 210.508063 6.481052) (xy 210.515975 6.395669) (xy 210.51647 6.352794) (xy 210.515975 6.309919)
			(xy 215.011241 6.309919) (xy 215.011241 6.395669) (xy 215.019153 6.481052) (xy 215.034909 6.565342)
			(xy 215.058376 6.647818) (xy 215.089352 6.727777) (xy 215.127574 6.804537) (xy 215.172715 6.877443)
			(xy 215.224391 6.945872) (xy 215.28216 7.009242) (xy 215.34553 7.067011) (xy 215.413959 7.118687)
			(xy 215.486865 7.163828) (xy 215.563625 7.20205) (xy 215.643584 7.233026) (xy 215.72606 7.256493)
			(xy 215.81035 7.272249) (xy 215.895733 7.280161) (xy 215.981483 7.280161) (xy 216.066866 7.272249)
			(xy 216.151156 7.256493) (xy 216.233632 7.233026) (xy 216.313591 7.20205) (xy 216.390351 7.163828)
			(xy 216.463257 7.118687) (xy 216.531686 7.067011) (xy 216.595056 7.009242) (xy 216.652825 6.945872)
			(xy 216.704501 6.877443) (xy 216.749642 6.804537) (xy 216.787864 6.727777) (xy 216.81884 6.647818)
			(xy 216.842307 6.565342) (xy 216.858063 6.481052) (xy 216.865975 6.395669) (xy 216.86647 6.352794)
			(xy 216.865975 6.309919) (xy 296.143921 6.309919) (xy 296.143921 6.395669) (xy 296.151833 6.481052)
			(xy 296.167589 6.565342) (xy 296.191056 6.647818) (xy 296.222032 6.727777) (xy 296.260254 6.804537)
			(xy 296.305395 6.877443) (xy 296.357071 6.945872) (xy 296.41484 7.009242) (xy 296.47821 7.067011)
			(xy 296.546639 7.118687) (xy 296.619545 7.163828) (xy 296.696305 7.20205) (xy 296.776264 7.233026)
			(xy 296.85874 7.256493) (xy 296.94303 7.272249) (xy 297.028413 7.280161) (xy 297.114163 7.280161)
			(xy 297.199546 7.272249) (xy 297.283836 7.256493) (xy 297.366312 7.233026) (xy 297.446271 7.20205)
			(xy 297.523031 7.163828) (xy 297.595937 7.118687) (xy 297.664366 7.067011) (xy 297.727736 7.009242)
			(xy 297.785505 6.945872) (xy 297.837181 6.877443) (xy 297.882322 6.804537) (xy 297.920544 6.727777)
			(xy 297.95152 6.647818) (xy 297.974987 6.565342) (xy 297.990743 6.481052) (xy 297.998655 6.395669)
			(xy 297.99915 6.352794) (xy 297.998655 6.309919) (xy 302.493921 6.309919) (xy 302.493921 6.395669)
			(xy 302.501833 6.481052) (xy 302.517589 6.565342) (xy 302.541056 6.647818) (xy 302.572032 6.727777)
			(xy 302.610254 6.804537) (xy 302.655395 6.877443) (xy 302.707071 6.945872) (xy 302.76484 7.009242)
			(xy 302.82821 7.067011) (xy 302.896639 7.118687) (xy 302.969545 7.163828) (xy 303.046305 7.20205)
			(xy 303.126264 7.233026) (xy 303.20874 7.256493) (xy 303.29303 7.272249) (xy 303.378413 7.280161)
			(xy 303.464163 7.280161) (xy 303.549546 7.272249) (xy 303.633836 7.256493) (xy 303.716312 7.233026)
			(xy 303.796271 7.20205) (xy 303.873031 7.163828) (xy 303.945937 7.118687) (xy 304.014366 7.067011)
			(xy 304.077736 7.009242) (xy 304.135505 6.945872) (xy 304.187181 6.877443) (xy 304.232322 6.804537)
			(xy 304.270544 6.727777) (xy 304.30152 6.647818) (xy 304.324987 6.565342) (xy 304.340743 6.481052)
			(xy 304.348655 6.395669) (xy 304.34915 6.352794) (xy 304.348655 6.309919) (xy 311.155321 6.309919)
			(xy 311.155321 6.395669) (xy 311.163233 6.481052) (xy 311.178989 6.565342) (xy 311.202456 6.647818)
			(xy 311.233432 6.727777) (xy 311.271654 6.804537) (xy 311.316795 6.877443) (xy 311.368471 6.945872)
			(xy 311.42624 7.009242) (xy 311.48961 7.067011) (xy 311.558039 7.118687) (xy 311.630945 7.163828)
			(xy 311.707705 7.20205) (xy 311.787664 7.233026) (xy 311.87014 7.256493) (xy 311.95443 7.272249)
			(xy 312.039813 7.280161) (xy 312.125563 7.280161) (xy 312.210946 7.272249) (xy 312.295236 7.256493)
			(xy 312.377712 7.233026) (xy 312.457671 7.20205) (xy 312.478344 7.191756) (xy 316.012068 7.191756)
			(xy 316.012068 8.055356) (xy 316.012572 8.08491) (xy 316.020621 8.143466) (xy 316.036567 8.200381)
			(xy 316.060116 8.254595) (xy 316.090827 8.305098) (xy 316.128129 8.350948) (xy 316.171326 8.391291)
			(xy 316.219615 8.425377) (xy 316.272095 8.45257) (xy 316.32779 8.472364) (xy 316.385661 8.48439)
			(xy 316.44463 8.488424) (xy 316.503599 8.48439) (xy 316.56147 8.472364) (xy 316.617165 8.45257) (xy 316.669645 8.425377)
			(xy 316.717934 8.391291) (xy 316.761131 8.350948) (xy 316.798433 8.305098) (xy 316.829144 8.254595)
			(xy 316.852693 8.200381) (xy 316.868639 8.143466) (xy 316.876688 8.08491) (xy 316.877192 8.055356)
			(xy 316.877192 7.191756) (xy 316.876688 7.162202) (xy 316.868639 7.103646) (xy 316.852693 7.046731)
			(xy 316.829144 6.992517) (xy 316.798433 6.942014) (xy 316.761131 6.896164) (xy 316.717934 6.855821)
			(xy 316.669645 6.821735) (xy 316.617165 6.794542) (xy 316.56147 6.774748) (xy 316.503599 6.762722)
			(xy 316.44463 6.758689) (xy 316.385661 6.762722) (xy 316.32779 6.774748) (xy 316.272095 6.794542)
			(xy 316.219615 6.821735) (xy 316.171326 6.855821) (xy 316.128129 6.896164) (xy 316.090827 6.942014)
			(xy 316.060116 6.992517) (xy 316.036567 7.046731) (xy 316.020621 7.103646) (xy 316.012572 7.162202)
			(xy 316.012068 7.191756) (xy 312.478344 7.191756) (xy 312.534431 7.163828) (xy 312.607337 7.118687)
			(xy 312.675766 7.067011) (xy 312.739136 7.009242) (xy 312.796905 6.945872) (xy 312.848581 6.877443)
			(xy 312.893722 6.804537) (xy 312.931944 6.727777) (xy 312.96292 6.647818) (xy 312.986387 6.565342)
			(xy 313.002143 6.481052) (xy 313.010055 6.395669) (xy 313.01055 6.352794) (xy 313.010055 6.309919)
			(xy 317.505321 6.309919) (xy 317.505321 6.395669) (xy 317.513233 6.481052) (xy 317.528989 6.565342)
			(xy 317.552456 6.647818) (xy 317.583432 6.727777) (xy 317.621654 6.804537) (xy 317.666795 6.877443)
			(xy 317.718471 6.945872) (xy 317.77624 7.009242) (xy 317.83961 7.067011) (xy 317.908039 7.118687)
			(xy 317.980945 7.163828) (xy 318.057705 7.20205) (xy 318.137664 7.233026) (xy 318.22014 7.256493)
			(xy 318.30443 7.272249) (xy 318.389813 7.280161) (xy 318.475563 7.280161) (xy 318.560946 7.272249)
			(xy 318.645236 7.256493) (xy 318.727712 7.233026) (xy 318.807671 7.20205) (xy 318.884431 7.163828)
			(xy 318.957337 7.118687) (xy 319.025766 7.067011) (xy 319.089136 7.009242) (xy 319.146905 6.945872)
			(xy 319.198581 6.877443) (xy 319.243722 6.804537) (xy 319.281944 6.727777) (xy 319.31292 6.647818)
			(xy 319.336387 6.565342) (xy 319.352143 6.481052) (xy 319.360055 6.395669) (xy 319.36055 6.352794)
			(xy 319.360055 6.309919) (xy 361.894107 6.309919) (xy 361.894107 6.395669) (xy 361.902019 6.481052)
			(xy 361.917775 6.565342) (xy 361.941242 6.647818) (xy 361.972218 6.727777) (xy 362.01044 6.804537)
			(xy 362.055581 6.877443) (xy 362.107257 6.945872) (xy 362.165026 7.009242) (xy 362.228396 7.067011)
			(xy 362.296825 7.118687) (xy 362.369731 7.163828) (xy 362.446491 7.20205) (xy 362.52645 7.233026)
			(xy 362.608926 7.256493) (xy 362.693216 7.272249) (xy 362.778599 7.280161) (xy 362.864349 7.280161)
			(xy 362.949732 7.272249) (xy 363.034022 7.256493) (xy 363.116498 7.233026) (xy 363.196457 7.20205)
			(xy 363.21713 7.191756) (xy 364.379764 7.191756) (xy 364.379764 8.055356) (xy 364.380268 8.084892)
			(xy 364.388312 8.143414) (xy 364.404249 8.200296) (xy 364.427784 8.254478) (xy 364.458477 8.304951)
			(xy 364.495757 8.350774) (xy 364.538929 8.391094) (xy 364.587189 8.42516) (xy 364.639639 8.452337)
			(xy 364.6953 8.472119) (xy 364.753137 8.484138) (xy 364.812072 8.488169) (xy 364.871007 8.484138)
			(xy 364.928844 8.472119) (xy 364.984505 8.452337) (xy 365.036955 8.42516) (xy 365.085215 8.391094)
			(xy 365.128387 8.350774) (xy 365.165667 8.304951) (xy 365.19636 8.254478) (xy 365.219895 8.200296)
			(xy 365.235832 8.143414) (xy 365.243876 8.084892) (xy 365.24438 8.055356) (xy 365.24438 7.376973)
			(xy 385.651997 7.376973) (xy 385.651997 7.462723) (xy 385.659909 7.548106) (xy 385.675665 7.632396)
			(xy 385.699132 7.714872) (xy 385.730108 7.794831) (xy 385.76833 7.871591) (xy 385.813471 7.944497)
			(xy 385.865147 8.012926) (xy 385.922916 8.076296) (xy 385.986286 8.134065) (xy 386.054715 8.185741)
			(xy 386.127621 8.230882) (xy 386.204381 8.269104) (xy 386.28434 8.30008) (xy 386.366816 8.323547)
			(xy 386.451106 8.339303) (xy 386.536489 8.347215) (xy 386.622239 8.347215) (xy 386.707622 8.339303)
			(xy 386.791912 8.323547) (xy 386.874388 8.30008) (xy 386.954347 8.269104) (xy 386.97502 8.25881)
			(xy 390.508744 8.25881) (xy 390.508744 9.12241) (xy 390.509248 9.151964) (xy 390.517297 9.21052)
			(xy 390.533243 9.267435) (xy 390.556792 9.321649) (xy 390.587503 9.372152) (xy 390.624805 9.418002)
			(xy 390.668002 9.458345) (xy 390.716291 9.492431) (xy 390.768771 9.519624) (xy 390.824466 9.539418)
			(xy 390.882337 9.551444) (xy 390.941306 9.555478) (xy 391.000275 9.551444) (xy 391.058146 9.539418)
			(xy 391.113841 9.519624) (xy 391.166321 9.492431) (xy 391.21461 9.458345) (xy 391.257807 9.418002)
			(xy 391.295109 9.372152) (xy 391.32582 9.321649) (xy 391.349369 9.267435) (xy 391.365315 9.21052)
			(xy 391.373364 9.151964) (xy 391.373868 9.12241) (xy 391.373868 8.25881) (xy 391.373364 8.229256)
			(xy 391.365315 8.1707) (xy 391.349369 8.113785) (xy 391.32582 8.059571) (xy 391.295109 8.009068)
			(xy 391.257807 7.963218) (xy 391.21461 7.922875) (xy 391.166321 7.888789) (xy 391.113841 7.861596)
			(xy 391.058146 7.841802) (xy 391.000275 7.829776) (xy 390.941306 7.825743) (xy 390.882337 7.829776)
			(xy 390.824466 7.841802) (xy 390.768771 7.861596) (xy 390.716291 7.888789) (xy 390.668002 7.922875)
			(xy 390.624805 7.963218) (xy 390.587503 8.009068) (xy 390.556792 8.059571) (xy 390.533243 8.113785)
			(xy 390.517297 8.1707) (xy 390.509248 8.229256) (xy 390.508744 8.25881) (xy 386.97502 8.25881) (xy 387.031107 8.230882)
			(xy 387.104013 8.185741) (xy 387.172442 8.134065) (xy 387.235812 8.076296) (xy 387.293581 8.012926)
			(xy 387.345257 7.944497) (xy 387.390398 7.871591) (xy 387.42862 7.794831) (xy 387.459596 7.714872)
			(xy 387.483063 7.632396) (xy 387.498819 7.548106) (xy 387.506731 7.462723) (xy 387.507226 7.419848)
			(xy 387.506731 7.376973) (xy 392.001997 7.376973) (xy 392.001997 7.462723) (xy 392.009909 7.548106)
			(xy 392.025665 7.632396) (xy 392.049132 7.714872) (xy 392.080108 7.794831) (xy 392.11833 7.871591)
			(xy 392.163471 7.944497) (xy 392.215147 8.012926) (xy 392.272916 8.076296) (xy 392.336286 8.134065)
			(xy 392.404715 8.185741) (xy 392.477621 8.230882) (xy 392.554381 8.269104) (xy 392.63434 8.30008)
			(xy 392.716816 8.323547) (xy 392.801106 8.339303) (xy 392.886489 8.347215) (xy 392.972239 8.347215)
			(xy 393.057622 8.339303) (xy 393.141912 8.323547) (xy 393.224388 8.30008) (xy 393.304347 8.269104)
			(xy 393.381107 8.230882) (xy 393.454013 8.185741) (xy 393.522442 8.134065) (xy 393.585812 8.076296)
			(xy 393.643581 8.012926) (xy 393.695257 7.944497) (xy 393.740398 7.871591) (xy 393.77862 7.794831)
			(xy 393.809596 7.714872) (xy 393.833063 7.632396) (xy 393.848819 7.548106) (xy 393.856731 7.462723)
			(xy 393.857226 7.419848) (xy 393.856731 7.376973) (xy 436.390783 7.376973) (xy 436.390783 7.462723)
			(xy 436.398695 7.548106) (xy 436.414451 7.632396) (xy 436.437918 7.714872) (xy 436.468894 7.794831)
			(xy 436.507116 7.871591) (xy 436.552257 7.944497) (xy 436.603933 8.012926) (xy 436.661702 8.076296)
			(xy 436.725072 8.134065) (xy 436.793501 8.185741) (xy 436.866407 8.230882) (xy 436.943167 8.269104)
			(xy 437.023126 8.30008) (xy 437.105602 8.323547) (xy 437.189892 8.339303) (xy 437.275275 8.347215)
			(xy 437.361025 8.347215) (xy 437.446408 8.339303) (xy 437.530698 8.323547) (xy 437.613174 8.30008)
			(xy 437.693133 8.269104) (xy 437.713806 8.25881) (xy 438.87644 8.25881) (xy 438.87644 9.12241) (xy 438.876944 9.151946)
			(xy 438.884988 9.210468) (xy 438.900925 9.26735) (xy 438.92446 9.321532) (xy 438.955153 9.372005)
			(xy 438.992433 9.417828) (xy 439.035605 9.458148) (xy 439.083865 9.492214) (xy 439.136315 9.519391)
			(xy 439.191976 9.539173) (xy 439.249813 9.551192) (xy 439.308748 9.555223) (xy 439.367683 9.551192)
			(xy 439.42552 9.539173) (xy 439.481181 9.519391) (xy 439.533631 9.492214) (xy 439.581891 9.458148)
			(xy 439.625063 9.417828) (xy 439.662343 9.372005) (xy 439.693036 9.321532) (xy 439.716571 9.26735)
			(xy 439.732508 9.210468) (xy 439.740552 9.151946) (xy 439.741056 9.12241) (xy 439.741056 8.25881)
			(xy 439.740552 8.229274) (xy 439.732508 8.170752) (xy 439.716571 8.11387) (xy 439.693036 8.059688)
			(xy 439.662343 8.009215) (xy 439.625063 7.963392) (xy 439.581891 7.923072) (xy 439.533631 7.889006)
			(xy 439.481181 7.861829) (xy 439.42552 7.842047) (xy 439.367683 7.830028) (xy 439.308748 7.825997)
			(xy 439.249813 7.830028) (xy 439.191976 7.842047) (xy 439.136315 7.861829) (xy 439.083865 7.889006)
			(xy 439.035605 7.923072) (xy 438.992433 7.963392) (xy 438.955153 8.009215) (xy 438.92446 8.059688)
			(xy 438.900925 8.11387) (xy 438.884988 8.170752) (xy 438.876944 8.229274) (xy 438.87644 8.25881)
			(xy 437.713806 8.25881) (xy 437.769893 8.230882) (xy 437.842799 8.185741) (xy 437.911228 8.134065)
			(xy 437.974598 8.076296) (xy 438.032367 8.012926) (xy 438.084043 7.944497) (xy 438.129184 7.871591)
			(xy 438.167406 7.794831) (xy 438.198382 7.714872) (xy 438.221849 7.632396) (xy 438.237605 7.548106)
			(xy 438.245517 7.462723) (xy 438.246012 7.419848) (xy 438.245517 7.376973) (xy 442.740783 7.376973)
			(xy 442.740783 7.462723) (xy 442.748695 7.548106) (xy 442.764451 7.632396) (xy 442.787918 7.714872)
			(xy 442.818894 7.794831) (xy 442.857116 7.871591) (xy 442.902257 7.944497) (xy 442.953933 8.012926)
			(xy 443.011702 8.076296) (xy 443.075072 8.134065) (xy 443.143501 8.185741) (xy 443.216407 8.230882)
			(xy 443.293167 8.269104) (xy 443.373126 8.30008) (xy 443.455602 8.323547) (xy 443.539892 8.339303)
			(xy 443.625275 8.347215) (xy 443.711025 8.347215) (xy 443.796408 8.339303) (xy 443.880698 8.323547)
			(xy 443.963174 8.30008) (xy 444.043133 8.269104) (xy 444.119893 8.230882) (xy 444.192799 8.185741)
			(xy 444.261228 8.134065) (xy 444.324598 8.076296) (xy 444.382367 8.012926) (xy 444.434043 7.944497)
			(xy 444.479184 7.871591) (xy 444.517406 7.794831) (xy 444.548382 7.714872) (xy 444.571849 7.632396)
			(xy 444.587605 7.548106) (xy 444.595517 7.462723) (xy 444.596012 7.419848) (xy 444.595517 7.376973)
			(xy 444.587605 7.29159) (xy 444.571849 7.2073) (xy 444.548382 7.124824) (xy 444.517406 7.044865)
			(xy 444.479184 6.968105) (xy 444.434043 6.895199) (xy 444.382367 6.82677) (xy 444.324598 6.7634)
			(xy 444.261228 6.705631) (xy 444.192799 6.653955) (xy 444.119893 6.608814) (xy 444.043133 6.570592)
			(xy 443.963174 6.539616) (xy 443.880698 6.516149) (xy 443.796408 6.500393) (xy 443.711025 6.492481)
			(xy 443.625275 6.492481) (xy 443.539892 6.500393) (xy 443.455602 6.516149) (xy 443.373126 6.539616)
			(xy 443.293167 6.570592) (xy 443.216407 6.608814) (xy 443.143501 6.653955) (xy 443.075072 6.705631)
			(xy 443.011702 6.7634) (xy 442.953933 6.82677) (xy 442.902257 6.895199) (xy 442.857116 6.968105)
			(xy 442.818894 7.044865) (xy 442.787918 7.124824) (xy 442.764451 7.2073) (xy 442.748695 7.29159)
			(xy 442.740783 7.376973) (xy 438.245517 7.376973) (xy 438.237605 7.29159) (xy 438.221849 7.2073)
			(xy 438.198382 7.124824) (xy 438.167406 7.044865) (xy 438.129184 6.968105) (xy 438.084043 6.895199)
			(xy 438.032367 6.82677) (xy 437.974598 6.7634) (xy 437.911228 6.705631) (xy 437.842799 6.653955)
			(xy 437.769893 6.608814) (xy 437.693133 6.570592) (xy 437.613174 6.539616) (xy 437.530698 6.516149)
			(xy 437.446408 6.500393) (xy 437.361025 6.492481) (xy 437.275275 6.492481) (xy 437.189892 6.500393)
			(xy 437.105602 6.516149) (xy 437.023126 6.539616) (xy 436.943167 6.570592) (xy 436.866407 6.608814)
			(xy 436.793501 6.653955) (xy 436.725072 6.705631) (xy 436.661702 6.7634) (xy 436.603933 6.82677)
			(xy 436.552257 6.895199) (xy 436.507116 6.968105) (xy 436.468894 7.044865) (xy 436.437918 7.124824)
			(xy 436.414451 7.2073) (xy 436.398695 7.29159) (xy 436.390783 7.376973) (xy 393.856731 7.376973)
			(xy 393.848819 7.29159) (xy 393.833063 7.2073) (xy 393.809596 7.124824) (xy 393.77862 7.044865) (xy 393.740398 6.968105)
			(xy 393.695257 6.895199) (xy 393.643581 6.82677) (xy 393.585812 6.7634) (xy 393.522442 6.705631)
			(xy 393.454013 6.653955) (xy 393.381107 6.608814) (xy 393.304347 6.570592) (xy 393.224388 6.539616)
			(xy 393.141912 6.516149) (xy 393.057622 6.500393) (xy 392.972239 6.492481) (xy 392.886489 6.492481)
			(xy 392.801106 6.500393) (xy 392.716816 6.516149) (xy 392.63434 6.539616) (xy 392.554381 6.570592)
			(xy 392.477621 6.608814) (xy 392.404715 6.653955) (xy 392.336286 6.705631) (xy 392.272916 6.7634)
			(xy 392.215147 6.82677) (xy 392.163471 6.895199) (xy 392.11833 6.968105) (xy 392.080108 7.044865)
			(xy 392.049132 7.124824) (xy 392.025665 7.2073) (xy 392.009909 7.29159) (xy 392.001997 7.376973)
			(xy 387.506731 7.376973) (xy 387.498819 7.29159) (xy 387.483063 7.2073) (xy 387.459596 7.124824)
			(xy 387.42862 7.044865) (xy 387.390398 6.968105) (xy 387.345257 6.895199) (xy 387.293581 6.82677)
			(xy 387.235812 6.7634) (xy 387.172442 6.705631) (xy 387.104013 6.653955) (xy 387.031107 6.608814)
			(xy 386.954347 6.570592) (xy 386.874388 6.539616) (xy 386.791912 6.516149) (xy 386.707622 6.500393)
			(xy 386.622239 6.492481) (xy 386.536489 6.492481) (xy 386.451106 6.500393) (xy 386.366816 6.516149)
			(xy 386.28434 6.539616) (xy 386.204381 6.570592) (xy 386.127621 6.608814) (xy 386.054715 6.653955)
			(xy 385.986286 6.705631) (xy 385.922916 6.7634) (xy 385.865147 6.82677) (xy 385.813471 6.895199)
			(xy 385.76833 6.968105) (xy 385.730108 7.044865) (xy 385.699132 7.124824) (xy 385.675665 7.2073)
			(xy 385.659909 7.29159) (xy 385.651997 7.376973) (xy 365.24438 7.376973) (xy 365.24438 7.191756)
			(xy 365.243876 7.16222) (xy 365.235832 7.103698) (xy 365.219895 7.046816) (xy 365.19636 6.992634)
			(xy 365.165667 6.942161) (xy 365.128387 6.896338) (xy 365.085215 6.856018) (xy 365.036955 6.821952)
			(xy 364.984505 6.794775) (xy 364.928844 6.774993) (xy 364.871007 6.762974) (xy 364.812072 6.758943)
			(xy 364.753137 6.762974) (xy 364.6953 6.774993) (xy 364.639639 6.794775) (xy 364.587189 6.821952)
			(xy 364.538929 6.856018) (xy 364.495757 6.896338) (xy 364.458477 6.942161) (xy 364.427784 6.992634)
			(xy 364.404249 7.046816) (xy 364.388312 7.103698) (xy 364.380268 7.16222) (xy 364.379764 7.191756)
			(xy 363.21713 7.191756) (xy 363.273217 7.163828) (xy 363.346123 7.118687) (xy 363.414552 7.067011)
			(xy 363.477922 7.009242) (xy 363.535691 6.945872) (xy 363.587367 6.877443) (xy 363.632508 6.804537)
			(xy 363.67073 6.727777) (xy 363.701706 6.647818) (xy 363.725173 6.565342) (xy 363.740929 6.481052)
			(xy 363.748841 6.395669) (xy 363.749336 6.352794) (xy 363.748841 6.309919) (xy 368.244107 6.309919)
			(xy 368.244107 6.395669) (xy 368.252019 6.481052) (xy 368.267775 6.565342) (xy 368.291242 6.647818)
			(xy 368.322218 6.727777) (xy 368.36044 6.804537) (xy 368.405581 6.877443) (xy 368.457257 6.945872)
			(xy 368.515026 7.009242) (xy 368.578396 7.067011) (xy 368.646825 7.118687) (xy 368.719731 7.163828)
			(xy 368.796491 7.20205) (xy 368.87645 7.233026) (xy 368.958926 7.256493) (xy 369.043216 7.272249)
			(xy 369.128599 7.280161) (xy 369.214349 7.280161) (xy 369.299732 7.272249) (xy 369.384022 7.256493)
			(xy 369.466498 7.233026) (xy 369.546457 7.20205) (xy 369.623217 7.163828) (xy 369.696123 7.118687)
			(xy 369.764552 7.067011) (xy 369.827922 7.009242) (xy 369.885691 6.945872) (xy 369.937367 6.877443)
			(xy 369.982508 6.804537) (xy 370.02073 6.727777) (xy 370.051706 6.647818) (xy 370.075173 6.565342)
			(xy 370.090929 6.481052) (xy 370.098841 6.395669) (xy 370.099336 6.352794) (xy 370.098841 6.309919)
			(xy 370.090929 6.224536) (xy 370.075173 6.140246) (xy 370.051706 6.05777) (xy 370.02073 5.977811)
			(xy 369.982508 5.901051) (xy 369.937367 5.828145) (xy 369.885691 5.759716) (xy 369.827922 5.696346)
			(xy 369.764552 5.638577) (xy 369.696123 5.586901) (xy 369.623217 5.54176) (xy 369.546457 5.503538)
			(xy 369.466498 5.472562) (xy 369.384022 5.449095) (xy 369.299732 5.433339) (xy 369.214349 5.425427)
			(xy 369.128599 5.425427) (xy 369.043216 5.433339) (xy 368.958926 5.449095) (xy 368.87645 5.472562)
			(xy 368.796491 5.503538) (xy 368.719731 5.54176) (xy 368.646825 5.586901) (xy 368.578396 5.638577)
			(xy 368.515026 5.696346) (xy 368.457257 5.759716) (xy 368.405581 5.828145) (xy 368.36044 5.901051)
			(xy 368.322218 5.977811) (xy 368.291242 6.05777) (xy 368.267775 6.140246) (xy 368.252019 6.224536)
			(xy 368.244107 6.309919) (xy 363.748841 6.309919) (xy 363.740929 6.224536) (xy 363.725173 6.140246)
			(xy 363.701706 6.05777) (xy 363.67073 5.977811) (xy 363.632508 5.901051) (xy 363.587367 5.828145)
			(xy 363.535691 5.759716) (xy 363.477922 5.696346) (xy 363.414552 5.638577) (xy 363.346123 5.586901)
			(xy 363.273217 5.54176) (xy 363.196457 5.503538) (xy 363.116498 5.472562) (xy 363.034022 5.449095)
			(xy 362.949732 5.433339) (xy 362.864349 5.425427) (xy 362.778599 5.425427) (xy 362.693216 5.433339)
			(xy 362.608926 5.449095) (xy 362.52645 5.472562) (xy 362.446491 5.503538) (xy 362.369731 5.54176)
			(xy 362.296825 5.586901) (xy 362.228396 5.638577) (xy 362.165026 5.696346) (xy 362.107257 5.759716)
			(xy 362.055581 5.828145) (xy 362.01044 5.901051) (xy 361.972218 5.977811) (xy 361.941242 6.05777)
			(xy 361.917775 6.140246) (xy 361.902019 6.224536) (xy 361.894107 6.309919) (xy 319.360055 6.309919)
			(xy 319.352143 6.224536) (xy 319.336387 6.140246) (xy 319.31292 6.05777) (xy 319.281944 5.977811)
			(xy 319.243722 5.901051) (xy 319.198581 5.828145) (xy 319.146905 5.759716) (xy 319.089136 5.696346)
			(xy 319.025766 5.638577) (xy 318.957337 5.586901) (xy 318.884431 5.54176) (xy 318.807671 5.503538)
			(xy 318.727712 5.472562) (xy 318.645236 5.449095) (xy 318.560946 5.433339) (xy 318.475563 5.425427)
			(xy 318.389813 5.425427) (xy 318.30443 5.433339) (xy 318.22014 5.449095) (xy 318.137664 5.472562)
			(xy 318.057705 5.503538) (xy 317.980945 5.54176) (xy 317.908039 5.586901) (xy 317.83961 5.638577)
			(xy 317.77624 5.696346) (xy 317.718471 5.759716) (xy 317.666795 5.828145) (xy 317.621654 5.901051)
			(xy 317.583432 5.977811) (xy 317.552456 6.05777) (xy 317.528989 6.140246) (xy 317.513233 6.224536)
			(xy 317.505321 6.309919) (xy 313.010055 6.309919) (xy 313.002143 6.224536) (xy 312.986387 6.140246)
			(xy 312.96292 6.05777) (xy 312.931944 5.977811) (xy 312.893722 5.901051) (xy 312.848581 5.828145)
			(xy 312.796905 5.759716) (xy 312.739136 5.696346) (xy 312.675766 5.638577) (xy 312.607337 5.586901)
			(xy 312.534431 5.54176) (xy 312.457671 5.503538) (xy 312.377712 5.472562) (xy 312.295236 5.449095)
			(xy 312.210946 5.433339) (xy 312.125563 5.425427) (xy 312.039813 5.425427) (xy 311.95443 5.433339)
			(xy 311.87014 5.449095) (xy 311.787664 5.472562) (xy 311.707705 5.503538) (xy 311.630945 5.54176)
			(xy 311.558039 5.586901) (xy 311.48961 5.638577) (xy 311.42624 5.696346) (xy 311.368471 5.759716)
			(xy 311.316795 5.828145) (xy 311.271654 5.901051) (xy 311.233432 5.977811) (xy 311.202456 6.05777)
			(xy 311.178989 6.140246) (xy 311.163233 6.224536) (xy 311.155321 6.309919) (xy 304.348655 6.309919)
			(xy 304.340743 6.224536) (xy 304.324987 6.140246) (xy 304.30152 6.05777) (xy 304.270544 5.977811)
			(xy 304.232322 5.901051) (xy 304.187181 5.828145) (xy 304.135505 5.759716) (xy 304.077736 5.696346)
			(xy 304.014366 5.638577) (xy 303.945937 5.586901) (xy 303.873031 5.54176) (xy 303.796271 5.503538)
			(xy 303.716312 5.472562) (xy 303.633836 5.449095) (xy 303.549546 5.433339) (xy 303.464163 5.425427)
			(xy 303.378413 5.425427) (xy 303.29303 5.433339) (xy 303.20874 5.449095) (xy 303.126264 5.472562)
			(xy 303.046305 5.503538) (xy 302.969545 5.54176) (xy 302.896639 5.586901) (xy 302.82821 5.638577)
			(xy 302.76484 5.696346) (xy 302.707071 5.759716) (xy 302.655395 5.828145) (xy 302.610254 5.901051)
			(xy 302.572032 5.977811) (xy 302.541056 6.05777) (xy 302.517589 6.140246) (xy 302.501833 6.224536)
			(xy 302.493921 6.309919) (xy 297.998655 6.309919) (xy 297.990743 6.224536) (xy 297.974987 6.140246)
			(xy 297.95152 6.05777) (xy 297.920544 5.977811) (xy 297.882322 5.901051) (xy 297.837181 5.828145)
			(xy 297.785505 5.759716) (xy 297.727736 5.696346) (xy 297.664366 5.638577) (xy 297.595937 5.586901)
			(xy 297.523031 5.54176) (xy 297.446271 5.503538) (xy 297.366312 5.472562) (xy 297.283836 5.449095)
			(xy 297.199546 5.433339) (xy 297.114163 5.425427) (xy 297.028413 5.425427) (xy 296.94303 5.433339)
			(xy 296.85874 5.449095) (xy 296.776264 5.472562) (xy 296.696305 5.503538) (xy 296.619545 5.54176)
			(xy 296.546639 5.586901) (xy 296.47821 5.638577) (xy 296.41484 5.696346) (xy 296.357071 5.759716)
			(xy 296.305395 5.828145) (xy 296.260254 5.901051) (xy 296.222032 5.977811) (xy 296.191056 6.05777)
			(xy 296.167589 6.140246) (xy 296.151833 6.224536) (xy 296.143921 6.309919) (xy 216.865975 6.309919)
			(xy 216.858063 6.224536) (xy 216.842307 6.140246) (xy 216.81884 6.05777) (xy 216.787864 5.977811)
			(xy 216.749642 5.901051) (xy 216.704501 5.828145) (xy 216.652825 5.759716) (xy 216.595056 5.696346)
			(xy 216.531686 5.638577) (xy 216.463257 5.586901) (xy 216.390351 5.54176) (xy 216.313591 5.503538)
			(xy 216.233632 5.472562) (xy 216.151156 5.449095) (xy 216.066866 5.433339) (xy 215.981483 5.425427)
			(xy 215.895733 5.425427) (xy 215.81035 5.433339) (xy 215.72606 5.449095) (xy 215.643584 5.472562)
			(xy 215.563625 5.503538) (xy 215.486865 5.54176) (xy 215.413959 5.586901) (xy 215.34553 5.638577)
			(xy 215.28216 5.696346) (xy 215.224391 5.759716) (xy 215.172715 5.828145) (xy 215.127574 5.901051)
			(xy 215.089352 5.977811) (xy 215.058376 6.05777) (xy 215.034909 6.140246) (xy 215.019153 6.224536)
			(xy 215.011241 6.309919) (xy 210.515975 6.309919) (xy 210.508063 6.224536) (xy 210.492307 6.140246)
			(xy 210.46884 6.05777) (xy 210.437864 5.977811) (xy 210.399642 5.901051) (xy 210.354501 5.828145)
			(xy 210.302825 5.759716) (xy 210.245056 5.696346) (xy 210.181686 5.638577) (xy 210.113257 5.586901)
			(xy 210.040351 5.54176) (xy 209.963591 5.503538) (xy 209.883632 5.472562) (xy 209.801156 5.449095)
			(xy 209.716866 5.433339) (xy 209.631483 5.425427) (xy 209.545733 5.425427) (xy 209.46035 5.433339)
			(xy 209.37606 5.449095) (xy 209.293584 5.472562) (xy 209.213625 5.503538) (xy 209.136865 5.54176)
			(xy 209.063959 5.586901) (xy 208.99553 5.638577) (xy 208.93216 5.696346) (xy 208.874391 5.759716)
			(xy 208.822715 5.828145) (xy 208.777574 5.901051) (xy 208.739352 5.977811) (xy 208.708376 6.05777)
			(xy 208.684909 6.140246) (xy 208.669153 6.224536) (xy 208.661241 6.309919) (xy 184.818528 6.309919)
			(xy 184.818528 5.632196) (xy 184.818024 5.60266) (xy 184.80998 5.544138) (xy 184.794043 5.487256)
			(xy 184.770508 5.433074) (xy 184.739815 5.382601) (xy 184.702535 5.336778) (xy 184.659363 5.296458)
			(xy 184.611103 5.262392) (xy 184.558653 5.235215) (xy 184.502992 5.215433) (xy 184.445155 5.203414)
			(xy 184.38622 5.199383) (xy 184.327285 5.203414) (xy 184.269448 5.215433) (xy 184.213787 5.235215)
			(xy 184.161337 5.262392) (xy 184.113077 5.296458) (xy 184.069905 5.336778) (xy 184.032625 5.382601)
			(xy 184.001932 5.433074) (xy 183.978397 5.487256) (xy 183.96246 5.544138) (xy 183.954416 5.60266)
			(xy 183.953912 5.632196) (xy 182.791278 5.632196) (xy 182.847365 5.604268) (xy 182.920271 5.559127)
			(xy 182.9887 5.507451) (xy 183.05207 5.449682) (xy 183.109839 5.386312) (xy 183.161515 5.317883)
			(xy 183.206656 5.244977) (xy 183.244878 5.168217) (xy 183.275854 5.088258) (xy 183.299321 5.005782)
			(xy 183.315077 4.921492) (xy 183.322989 4.836109) (xy 183.323484 4.793234) (xy 183.322989 4.750359)
			(xy 187.818255 4.750359) (xy 187.818255 4.836109) (xy 187.826167 4.921492) (xy 187.841923 5.005782)
			(xy 187.86539 5.088258) (xy 187.896366 5.168217) (xy 187.934588 5.244977) (xy 187.979729 5.317883)
			(xy 188.031405 5.386312) (xy 188.089174 5.449682) (xy 188.152544 5.507451) (xy 188.220973 5.559127)
			(xy 188.293879 5.604268) (xy 188.370639 5.64249) (xy 188.450598 5.673466) (xy 188.533074 5.696933)
			(xy 188.617364 5.712689) (xy 188.702747 5.720601) (xy 188.788497 5.720601) (xy 188.87388 5.712689)
			(xy 188.95817 5.696933) (xy 189.040646 5.673466) (xy 189.120605 5.64249) (xy 189.197365 5.604268)
			(xy 189.270271 5.559127) (xy 189.3387 5.507451) (xy 189.40207 5.449682) (xy 189.459839 5.386312)
			(xy 189.511515 5.317883) (xy 189.556656 5.244977) (xy 189.594878 5.168217) (xy 189.625854 5.088258)
			(xy 189.649321 5.005782) (xy 189.665077 4.921492) (xy 189.672989 4.836109) (xy 189.673484 4.793234)
			(xy 189.672989 4.750359) (xy 189.665077 4.664976) (xy 189.649321 4.580686) (xy 189.625854 4.49821)
			(xy 189.594878 4.418251) (xy 189.556656 4.341491) (xy 189.511515 4.268585) (xy 189.459839 4.200156)
			(xy 189.40207 4.136786) (xy 189.3387 4.079017) (xy 189.270271 4.027341) (xy 189.197365 3.9822) (xy 189.120605 3.943978)
			(xy 189.040646 3.913002) (xy 188.95817 3.889535) (xy 188.87388 3.873779) (xy 188.788497 3.865867)
			(xy 188.702747 3.865867) (xy 188.617364 3.873779) (xy 188.533074 3.889535) (xy 188.450598 3.913002)
			(xy 188.370639 3.943978) (xy 188.293879 3.9822) (xy 188.220973 4.027341) (xy 188.152544 4.079017)
			(xy 188.089174 4.136786) (xy 188.031405 4.200156) (xy 187.979729 4.268585) (xy 187.934588 4.341491)
			(xy 187.896366 4.418251) (xy 187.86539 4.49821) (xy 187.841923 4.580686) (xy 187.826167 4.664976)
			(xy 187.818255 4.750359) (xy 183.322989 4.750359) (xy 183.315077 4.664976) (xy 183.299321 4.580686)
			(xy 183.275854 4.49821) (xy 183.244878 4.418251) (xy 183.206656 4.341491) (xy 183.161515 4.268585)
			(xy 183.109839 4.200156) (xy 183.05207 4.136786) (xy 182.9887 4.079017) (xy 182.920271 4.027341)
			(xy 182.847365 3.9822) (xy 182.770605 3.943978) (xy 182.690646 3.913002) (xy 182.60817 3.889535)
			(xy 182.52388 3.873779) (xy 182.438497 3.865867) (xy 182.352747 3.865867) (xy 182.267364 3.873779)
			(xy 182.183074 3.889535) (xy 182.100598 3.913002) (xy 182.020639 3.943978) (xy 181.943879 3.9822)
			(xy 181.870973 4.027341) (xy 181.802544 4.079017) (xy 181.739174 4.136786) (xy 181.681405 4.200156)
			(xy 181.629729 4.268585) (xy 181.584588 4.341491) (xy 181.546366 4.418251) (xy 181.51539 4.49821)
			(xy 181.491923 4.580686) (xy 181.476167 4.664976) (xy 181.468255 4.750359) (xy 102.190309 4.750359)
			(xy 102.182397 4.664976) (xy 102.166641 4.580686) (xy 102.143174 4.49821) (xy 102.112198 4.418251)
			(xy 102.073976 4.341491) (xy 102.028835 4.268585) (xy 101.977159 4.200156) (xy 101.91939 4.136786)
			(xy 101.85602 4.079017) (xy 101.787591 4.027341) (xy 101.714685 3.9822) (xy 101.637925 3.943978)
			(xy 101.557966 3.913002) (xy 101.47549 3.889535) (xy 101.3912 3.873779) (xy 101.305817 3.865867)
			(xy 101.220067 3.865867) (xy 101.134684 3.873779) (xy 101.050394 3.889535) (xy 100.967918 3.913002)
			(xy 100.887959 3.943978) (xy 100.811199 3.9822) (xy 100.738293 4.027341) (xy 100.669864 4.079017)
			(xy 100.606494 4.136786) (xy 100.548725 4.200156) (xy 100.497049 4.268585) (xy 100.451908 4.341491)
			(xy 100.413686 4.418251) (xy 100.38271 4.49821) (xy 100.359243 4.580686) (xy 100.343487 4.664976)
			(xy 100.335575 4.750359) (xy 95.840309 4.750359) (xy 95.832397 4.664976) (xy 95.816641 4.580686)
			(xy 95.793174 4.49821) (xy 95.762198 4.418251) (xy 95.723976 4.341491) (xy 95.678835 4.268585) (xy 95.627159 4.200156)
			(xy 95.56939 4.136786) (xy 95.50602 4.079017) (xy 95.437591 4.027341) (xy 95.364685 3.9822) (xy 95.287925 3.943978)
			(xy 95.207966 3.913002) (xy 95.12549 3.889535) (xy 95.0412 3.873779) (xy 94.955817 3.865867) (xy 94.870067 3.865867)
			(xy 94.784684 3.873779) (xy 94.700394 3.889535) (xy 94.617918 3.913002) (xy 94.537959 3.943978) (xy 94.461199 3.9822)
			(xy 94.388293 4.027341) (xy 94.319864 4.079017) (xy 94.256494 4.136786) (xy 94.198725 4.200156) (xy 94.147049 4.268585)
			(xy 94.101908 4.341491) (xy 94.063686 4.418251) (xy 94.03271 4.49821) (xy 94.009243 4.580686) (xy 93.993487 4.664976)
			(xy 93.985575 4.750359) (xy 0.509016 4.750359) (xy 0.509016 -7.78002) (xy 0.509537 -7.835789) (xy 0.517873 -7.947015)
			(xy 0.534497 -8.057308) (xy 0.559316 -8.166049) (xy 0.592193 -8.272632) (xy 0.632942 -8.37646) (xy 0.681336 -8.476953)
			(xy 0.737105 -8.573548) (xy 0.799937 -8.665705) (xy 0.86948 -8.752909) (xy 0.945345 -8.834672) (xy 1.027108 -8.910538)
			(xy 1.114312 -8.980081) (xy 1.206469 -9.042912) (xy 1.303064 -9.098682) (xy 1.403556 -9.147076) (xy 1.507384 -9.187826)
			(xy 1.613967 -9.220703) (xy 1.722708 -9.245523) (xy 1.833001 -9.262147) (xy 1.944227 -9.270482) (xy 1.999996 -9.271)
			(xy 9.10209 -9.271) (xy 9.15786 -9.270479) (xy 9.269087 -9.262144) (xy 9.37938 -9.245521) (xy 9.488123 -9.220702)
			(xy 9.594707 -9.187826) (xy 9.698536 -9.147077) (xy 9.79903 -9.098683) (xy 9.895626 -9.042915) (xy 9.987784 -8.980083)
			(xy 10.07499 -8.910541) (xy 10.156754 -8.834676) (xy 10.232621 -8.752912) (xy 10.302165 -8.665708)
			(xy 10.364999 -8.573551) (xy 10.420769 -8.476956) (xy 10.469165 -8.376463) (xy 10.509916 -8.272635)
			(xy 10.542794 -8.166052) (xy 10.567616 -8.05731) (xy 10.584241 -7.947017) (xy 10.592578 -7.83579)
			(xy 10.59307 -7.78002) (xy 10.59307 0.40005) (xy 10.593555 0.470432) (xy 10.601447 0.610976) (xy 10.617208 0.750856)
			(xy 10.640787 0.889632) (xy 10.67211 1.026868) (xy 10.711079 1.162131) (xy 10.757571 1.294997) (xy 10.811439 1.425046)
			(xy 10.872515 1.551871) (xy 10.940606 1.675072) (xy 11.015497 1.794261) (xy 11.096954 1.909063) (xy 11.184719 2.019118)
			(xy 11.278518 2.124078) (xy 11.378053 2.223614) (xy 11.483014 2.317412) (xy 11.593068 2.405178) (xy 11.707871 2.486634)
			(xy 11.82706 2.561525) (xy 11.950261 2.629616) (xy 12.077085 2.690692) (xy 12.207135 2.74456) (xy 12.340001 2.791052)
			(xy 12.475264 2.83002) (xy 12.6125 2.861343) (xy 12.751276 2.884922) (xy 12.891156 2.900683) (xy 13.0317 2.908575)
			(xy 13.102082 2.909062) (xy 81.701894 2.909062) (xy 81.772277 2.908568) (xy 81.912821 2.900676) (xy 82.052702 2.884916)
			(xy 82.191479 2.861337) (xy 82.328715 2.830015) (xy 82.46398 2.791046) (xy 82.596846 2.744555) (xy 82.726897 2.690688)
			(xy 82.853723 2.629613) (xy 82.976925 2.561522) (xy 83.096116 2.486632) (xy 83.210919 2.405176) (xy 83.320975 2.317411)
			(xy 83.425937 2.223613) (xy 83.439191 2.210359) (xy 93.985575 2.210359) (xy 93.985575 2.296109) (xy 93.993487 2.381492)
			(xy 94.009243 2.465782) (xy 94.03271 2.548258) (xy 94.063686 2.628217) (xy 94.101908 2.704977) (xy 94.147049 2.777883)
			(xy 94.198725 2.846312) (xy 94.256494 2.909682) (xy 94.319864 2.967451) (xy 94.388293 3.019127) (xy 94.461199 3.064268)
			(xy 94.537959 3.10249) (xy 94.617918 3.133466) (xy 94.700394 3.156933) (xy 94.784684 3.172689) (xy 94.870067 3.180601)
			(xy 94.955817 3.180601) (xy 95.0412 3.172689) (xy 95.12549 3.156933) (xy 95.207966 3.133466) (xy 95.287925 3.10249)
			(xy 95.308598 3.092196) (xy 98.842576 3.092196) (xy 98.842576 3.955796) (xy 98.84308 3.985332) (xy 98.851124 4.043854)
			(xy 98.867061 4.100736) (xy 98.890596 4.154918) (xy 98.921289 4.205391) (xy 98.958569 4.251214) (xy 99.001741 4.291534)
			(xy 99.050001 4.3256) (xy 99.102451 4.352777) (xy 99.158112 4.372559) (xy 99.215949 4.384578) (xy 99.274884 4.388609)
			(xy 99.333819 4.384578) (xy 99.391656 4.372559) (xy 99.447317 4.352777) (xy 99.499767 4.3256) (xy 99.548027 4.291534)
			(xy 99.591199 4.251214) (xy 99.628479 4.205391) (xy 99.659172 4.154918) (xy 99.682707 4.100736) (xy 99.698644 4.043854)
			(xy 99.706688 3.985332) (xy 99.707192 3.955796) (xy 99.707192 3.092196) (xy 99.706688 3.06266) (xy 99.698644 3.004138)
			(xy 99.682707 2.947256) (xy 99.659172 2.893074) (xy 99.628479 2.842601) (xy 99.591199 2.796778) (xy 99.548027 2.756458)
			(xy 99.499767 2.722392) (xy 99.447317 2.695215) (xy 99.391656 2.675433) (xy 99.333819 2.663414) (xy 99.274884 2.659383)
			(xy 99.215949 2.663414) (xy 99.158112 2.675433) (xy 99.102451 2.695215) (xy 99.050001 2.722392) (xy 99.001741 2.756458)
			(xy 98.958569 2.796778) (xy 98.921289 2.842601) (xy 98.890596 2.893074) (xy 98.867061 2.947256) (xy 98.851124 3.004138)
			(xy 98.84308 3.06266) (xy 98.842576 3.092196) (xy 95.308598 3.092196) (xy 95.364685 3.064268) (xy 95.437591 3.019127)
			(xy 95.50602 2.967451) (xy 95.56939 2.909682) (xy 95.627159 2.846312) (xy 95.678835 2.777883) (xy 95.723976 2.704977)
			(xy 95.762198 2.628217) (xy 95.793174 2.548258) (xy 95.816641 2.465782) (xy 95.832397 2.381492) (xy 95.840309 2.296109)
			(xy 95.840804 2.253234) (xy 95.840309 2.210359) (xy 100.335575 2.210359) (xy 100.335575 2.296109)
			(xy 100.343487 2.381492) (xy 100.359243 2.465782) (xy 100.38271 2.548258) (xy 100.413686 2.628217)
			(xy 100.451908 2.704977) (xy 100.497049 2.777883) (xy 100.548725 2.846312) (xy 100.606494 2.909682)
			(xy 100.669864 2.967451) (xy 100.738293 3.019127) (xy 100.811199 3.064268) (xy 100.887959 3.10249)
			(xy 100.967918 3.133466) (xy 101.050394 3.156933) (xy 101.134684 3.172689) (xy 101.220067 3.180601)
			(xy 101.305817 3.180601) (xy 101.3912 3.172689) (xy 101.47549 3.156933) (xy 101.557966 3.133466)
			(xy 101.637925 3.10249) (xy 101.714685 3.064268) (xy 101.787591 3.019127) (xy 101.85602 2.967451)
			(xy 101.91939 2.909682) (xy 101.977159 2.846312) (xy 102.028835 2.777883) (xy 102.073976 2.704977)
			(xy 102.112198 2.628217) (xy 102.143174 2.548258) (xy 102.166641 2.465782) (xy 102.182397 2.381492)
			(xy 102.190309 2.296109) (xy 102.190804 2.253234) (xy 102.190309 2.210359) (xy 181.468255 2.210359)
			(xy 181.468255 2.296109) (xy 181.476167 2.381492) (xy 181.491923 2.465782) (xy 181.51539 2.548258)
			(xy 181.546366 2.628217) (xy 181.584588 2.704977) (xy 181.629729 2.777883) (xy 181.681405 2.846312)
			(xy 181.739174 2.909682) (xy 181.802544 2.967451) (xy 181.870973 3.019127) (xy 181.943879 3.064268)
			(xy 182.020639 3.10249) (xy 182.100598 3.133466) (xy 182.183074 3.156933) (xy 182.267364 3.172689)
			(xy 182.352747 3.180601) (xy 182.438497 3.180601) (xy 182.52388 3.172689) (xy 182.60817 3.156933)
			(xy 182.690646 3.133466) (xy 182.770605 3.10249) (xy 182.791278 3.092196) (xy 183.953912 3.092196)
			(xy 183.953912 3.955796) (xy 183.954416 3.985332) (xy 183.96246 4.043854) (xy 183.978397 4.100736)
			(xy 184.001932 4.154918) (xy 184.032625 4.205391) (xy 184.069905 4.251214) (xy 184.113077 4.291534)
			(xy 184.161337 4.3256) (xy 184.213787 4.352777) (xy 184.269448 4.372559) (xy 184.327285 4.384578)
			(xy 184.38622 4.388609) (xy 184.445155 4.384578) (xy 184.502992 4.372559) (xy 184.558653 4.352777)
			(xy 184.611103 4.3256) (xy 184.659363 4.291534) (xy 184.702535 4.251214) (xy 184.739815 4.205391)
			(xy 184.770508 4.154918) (xy 184.794043 4.100736) (xy 184.80998 4.043854) (xy 184.818024 3.985332)
			(xy 184.818528 3.955796) (xy 184.818528 3.769919) (xy 208.661241 3.769919) (xy 208.661241 3.855669)
			(xy 208.669153 3.941052) (xy 208.684909 4.025342) (xy 208.708376 4.107818) (xy 208.739352 4.187777)
			(xy 208.777574 4.264537) (xy 208.822715 4.337443) (xy 208.874391 4.405872) (xy 208.93216 4.469242)
			(xy 208.99553 4.527011) (xy 209.063959 4.578687) (xy 209.136865 4.623828) (xy 209.213625 4.66205)
			(xy 209.293584 4.693026) (xy 209.37606 4.716493) (xy 209.46035 4.732249) (xy 209.545733 4.740161)
			(xy 209.631483 4.740161) (xy 209.716866 4.732249) (xy 209.801156 4.716493) (xy 209.883632 4.693026)
			(xy 209.963591 4.66205) (xy 209.984264 4.651756) (xy 213.517988 4.651756) (xy 213.517988 5.515356)
			(xy 213.518492 5.54491) (xy 213.526541 5.603466) (xy 213.542487 5.660381) (xy 213.566036 5.714595)
			(xy 213.596747 5.765098) (xy 213.634049 5.810948) (xy 213.677246 5.851291) (xy 213.725535 5.885377)
			(xy 213.778015 5.91257) (xy 213.83371 5.932364) (xy 213.891581 5.94439) (xy 213.95055 5.948424) (xy 214.009519 5.94439)
			(xy 214.06739 5.932364) (xy 214.123085 5.91257) (xy 214.175565 5.885377) (xy 214.223854 5.851291)
			(xy 214.267051 5.810948) (xy 214.304353 5.765098) (xy 214.335064 5.714595) (xy 214.358613 5.660381)
			(xy 214.374559 5.603466) (xy 214.382608 5.54491) (xy 214.383112 5.515356) (xy 214.383112 4.651756)
			(xy 214.382608 4.622202) (xy 214.374559 4.563646) (xy 214.358613 4.506731) (xy 214.335064 4.452517)
			(xy 214.304353 4.402014) (xy 214.267051 4.356164) (xy 214.223854 4.315821) (xy 214.175565 4.281735)
			(xy 214.123085 4.254542) (xy 214.06739 4.234748) (xy 214.009519 4.222722) (xy 213.95055 4.218689)
			(xy 213.891581 4.222722) (xy 213.83371 4.234748) (xy 213.778015 4.254542) (xy 213.725535 4.281735)
			(xy 213.677246 4.315821) (xy 213.634049 4.356164) (xy 213.596747 4.402014) (xy 213.566036 4.452517)
			(xy 213.542487 4.506731) (xy 213.526541 4.563646) (xy 213.518492 4.622202) (xy 213.517988 4.651756)
			(xy 209.984264 4.651756) (xy 210.040351 4.623828) (xy 210.113257 4.578687) (xy 210.181686 4.527011)
			(xy 210.245056 4.469242) (xy 210.302825 4.405872) (xy 210.354501 4.337443) (xy 210.399642 4.264537)
			(xy 210.437864 4.187777) (xy 210.46884 4.107818) (xy 210.492307 4.025342) (xy 210.508063 3.941052)
			(xy 210.515975 3.855669) (xy 210.51647 3.812794) (xy 210.515975 3.769919) (xy 215.011241 3.769919)
			(xy 215.011241 3.855669) (xy 215.019153 3.941052) (xy 215.034909 4.025342) (xy 215.058376 4.107818)
			(xy 215.089352 4.187777) (xy 215.127574 4.264537) (xy 215.172715 4.337443) (xy 215.224391 4.405872)
			(xy 215.28216 4.469242) (xy 215.34553 4.527011) (xy 215.413959 4.578687) (xy 215.486865 4.623828)
			(xy 215.563625 4.66205) (xy 215.643584 4.693026) (xy 215.72606 4.716493) (xy 215.81035 4.732249)
			(xy 215.895733 4.740161) (xy 215.981483 4.740161) (xy 216.066866 4.732249) (xy 216.151156 4.716493)
			(xy 216.233632 4.693026) (xy 216.313591 4.66205) (xy 216.390351 4.623828) (xy 216.463257 4.578687)
			(xy 216.531686 4.527011) (xy 216.595056 4.469242) (xy 216.652825 4.405872) (xy 216.704501 4.337443)
			(xy 216.749642 4.264537) (xy 216.787864 4.187777) (xy 216.81884 4.107818) (xy 216.842307 4.025342)
			(xy 216.858063 3.941052) (xy 216.865975 3.855669) (xy 216.86647 3.812794) (xy 216.865975 3.769919)
			(xy 296.143921 3.769919) (xy 296.143921 3.855669) (xy 296.151833 3.941052) (xy 296.167589 4.025342)
			(xy 296.191056 4.107818) (xy 296.222032 4.187777) (xy 296.260254 4.264537) (xy 296.305395 4.337443)
			(xy 296.357071 4.405872) (xy 296.41484 4.469242) (xy 296.47821 4.527011) (xy 296.546639 4.578687)
			(xy 296.619545 4.623828) (xy 296.696305 4.66205) (xy 296.776264 4.693026) (xy 296.85874 4.716493)
			(xy 296.94303 4.732249) (xy 297.028413 4.740161) (xy 297.114163 4.740161) (xy 297.199546 4.732249)
			(xy 297.283836 4.716493) (xy 297.366312 4.693026) (xy 297.446271 4.66205) (xy 297.466944 4.651756)
			(xy 298.629324 4.651756) (xy 298.629324 5.515356) (xy 298.629828 5.54491) (xy 298.637877 5.603466)
			(xy 298.653823 5.660381) (xy 298.677372 5.714595) (xy 298.708083 5.765098) (xy 298.745385 5.810948)
			(xy 298.788582 5.851291) (xy 298.836871 5.885377) (xy 298.889351 5.91257) (xy 298.945046 5.932364)
			(xy 299.002917 5.94439) (xy 299.061886 5.948424) (xy 299.120855 5.94439) (xy 299.178726 5.932364)
			(xy 299.234421 5.91257) (xy 299.286901 5.885377) (xy 299.33519 5.851291) (xy 299.378387 5.810948)
			(xy 299.415689 5.765098) (xy 299.4464 5.714595) (xy 299.469949 5.660381) (xy 299.485895 5.603466)
			(xy 299.493944 5.54491) (xy 299.494448 5.515356) (xy 299.494448 4.651756) (xy 299.493944 4.622202)
			(xy 299.485895 4.563646) (xy 299.469949 4.506731) (xy 299.4464 4.452517) (xy 299.415689 4.402014)
			(xy 299.378387 4.356164) (xy 299.33519 4.315821) (xy 299.286901 4.281735) (xy 299.234421 4.254542)
			(xy 299.178726 4.234748) (xy 299.120855 4.222722) (xy 299.061886 4.218689) (xy 299.002917 4.222722)
			(xy 298.945046 4.234748) (xy 298.889351 4.254542) (xy 298.836871 4.281735) (xy 298.788582 4.315821)
			(xy 298.745385 4.356164) (xy 298.708083 4.402014) (xy 298.677372 4.452517) (xy 298.653823 4.506731)
			(xy 298.637877 4.563646) (xy 298.629828 4.622202) (xy 298.629324 4.651756) (xy 297.466944 4.651756)
			(xy 297.523031 4.623828) (xy 297.595937 4.578687) (xy 297.664366 4.527011) (xy 297.727736 4.469242)
			(xy 297.785505 4.405872) (xy 297.837181 4.337443) (xy 297.882322 4.264537) (xy 297.920544 4.187777)
			(xy 297.95152 4.107818) (xy 297.974987 4.025342) (xy 297.990743 3.941052) (xy 297.998655 3.855669)
			(xy 297.99915 3.812794) (xy 297.998655 3.769919) (xy 302.493921 3.769919) (xy 302.493921 3.855669)
			(xy 302.501833 3.941052) (xy 302.517589 4.025342) (xy 302.541056 4.107818) (xy 302.572032 4.187777)
			(xy 302.610254 4.264537) (xy 302.655395 4.337443) (xy 302.707071 4.405872) (xy 302.76484 4.469242)
			(xy 302.82821 4.527011) (xy 302.896639 4.578687) (xy 302.969545 4.623828) (xy 303.046305 4.66205)
			(xy 303.126264 4.693026) (xy 303.20874 4.716493) (xy 303.29303 4.732249) (xy 303.378413 4.740161)
			(xy 303.464163 4.740161) (xy 303.549546 4.732249) (xy 303.633836 4.716493) (xy 303.716312 4.693026)
			(xy 303.796271 4.66205) (xy 303.873031 4.623828) (xy 303.945937 4.578687) (xy 304.014366 4.527011)
			(xy 304.077736 4.469242) (xy 304.135505 4.405872) (xy 304.187181 4.337443) (xy 304.232322 4.264537)
			(xy 304.270544 4.187777) (xy 304.30152 4.107818) (xy 304.324987 4.025342) (xy 304.340743 3.941052)
			(xy 304.348655 3.855669) (xy 304.34915 3.812794) (xy 304.348655 3.769919) (xy 311.155321 3.769919)
			(xy 311.155321 3.855669) (xy 311.163233 3.941052) (xy 311.178989 4.025342) (xy 311.202456 4.107818)
			(xy 311.233432 4.187777) (xy 311.271654 4.264537) (xy 311.316795 4.337443) (xy 311.368471 4.405872)
			(xy 311.42624 4.469242) (xy 311.48961 4.527011) (xy 311.558039 4.578687) (xy 311.630945 4.623828)
			(xy 311.707705 4.66205) (xy 311.787664 4.693026) (xy 311.87014 4.716493) (xy 311.95443 4.732249)
			(xy 312.039813 4.740161) (xy 312.125563 4.740161) (xy 312.210946 4.732249) (xy 312.295236 4.716493)
			(xy 312.377712 4.693026) (xy 312.457671 4.66205) (xy 312.478344 4.651756) (xy 316.012068 4.651756)
			(xy 316.012068 5.515356) (xy 316.012572 5.54491) (xy 316.020621 5.603466) (xy 316.036567 5.660381)
			(xy 316.060116 5.714595) (xy 316.090827 5.765098) (xy 316.128129 5.810948) (xy 316.171326 5.851291)
			(xy 316.219615 5.885377) (xy 316.272095 5.91257) (xy 316.32779 5.932364) (xy 316.385661 5.94439)
			(xy 316.44463 5.948424) (xy 316.503599 5.94439) (xy 316.56147 5.932364) (xy 316.617165 5.91257) (xy 316.669645 5.885377)
			(xy 316.717934 5.851291) (xy 316.761131 5.810948) (xy 316.798433 5.765098) (xy 316.829144 5.714595)
			(xy 316.852693 5.660381) (xy 316.868639 5.603466) (xy 316.876688 5.54491) (xy 316.877192 5.515356)
			(xy 316.877192 4.651756) (xy 316.876688 4.622202) (xy 316.868639 4.563646) (xy 316.852693 4.506731)
			(xy 316.829144 4.452517) (xy 316.798433 4.402014) (xy 316.761131 4.356164) (xy 316.717934 4.315821)
			(xy 316.669645 4.281735) (xy 316.617165 4.254542) (xy 316.56147 4.234748) (xy 316.503599 4.222722)
			(xy 316.44463 4.218689) (xy 316.385661 4.222722) (xy 316.32779 4.234748) (xy 316.272095 4.254542)
			(xy 316.219615 4.281735) (xy 316.171326 4.315821) (xy 316.128129 4.356164) (xy 316.090827 4.402014)
			(xy 316.060116 4.452517) (xy 316.036567 4.506731) (xy 316.020621 4.563646) (xy 316.012572 4.622202)
			(xy 316.012068 4.651756) (xy 312.478344 4.651756) (xy 312.534431 4.623828) (xy 312.607337 4.578687)
			(xy 312.675766 4.527011) (xy 312.739136 4.469242) (xy 312.796905 4.405872) (xy 312.848581 4.337443)
			(xy 312.893722 4.264537) (xy 312.931944 4.187777) (xy 312.96292 4.107818) (xy 312.986387 4.025342)
			(xy 313.002143 3.941052) (xy 313.010055 3.855669) (xy 313.01055 3.812794) (xy 313.010055 3.769919)
			(xy 317.505321 3.769919) (xy 317.505321 3.855669) (xy 317.513233 3.941052) (xy 317.528989 4.025342)
			(xy 317.552456 4.107818) (xy 317.583432 4.187777) (xy 317.621654 4.264537) (xy 317.666795 4.337443)
			(xy 317.718471 4.405872) (xy 317.77624 4.469242) (xy 317.83961 4.527011) (xy 317.908039 4.578687)
			(xy 317.980945 4.623828) (xy 318.057705 4.66205) (xy 318.137664 4.693026) (xy 318.22014 4.716493)
			(xy 318.30443 4.732249) (xy 318.389813 4.740161) (xy 318.475563 4.740161) (xy 318.560946 4.732249)
			(xy 318.645236 4.716493) (xy 318.727712 4.693026) (xy 318.807671 4.66205) (xy 318.884431 4.623828)
			(xy 318.957337 4.578687) (xy 319.025766 4.527011) (xy 319.089136 4.469242) (xy 319.146905 4.405872)
			(xy 319.198581 4.337443) (xy 319.243722 4.264537) (xy 319.281944 4.187777) (xy 319.31292 4.107818)
			(xy 319.336387 4.025342) (xy 319.352143 3.941052) (xy 319.360055 3.855669) (xy 319.36055 3.812794)
			(xy 319.360055 3.769919) (xy 361.894107 3.769919) (xy 361.894107 3.855669) (xy 361.902019 3.941052)
			(xy 361.917775 4.025342) (xy 361.941242 4.107818) (xy 361.972218 4.187777) (xy 362.01044 4.264537)
			(xy 362.055581 4.337443) (xy 362.107257 4.405872) (xy 362.165026 4.469242) (xy 362.228396 4.527011)
			(xy 362.296825 4.578687) (xy 362.369731 4.623828) (xy 362.446491 4.66205) (xy 362.52645 4.693026)
			(xy 362.608926 4.716493) (xy 362.693216 4.732249) (xy 362.778599 4.740161) (xy 362.864349 4.740161)
			(xy 362.949732 4.732249) (xy 363.034022 4.716493) (xy 363.116498 4.693026) (xy 363.196457 4.66205)
			(xy 363.21713 4.651756) (xy 364.379764 4.651756) (xy 364.379764 5.515356) (xy 364.380268 5.544892)
			(xy 364.388312 5.603414) (xy 364.404249 5.660296) (xy 364.427784 5.714478) (xy 364.458477 5.764951)
			(xy 364.495757 5.810774) (xy 364.538929 5.851094) (xy 364.587189 5.88516) (xy 364.639639 5.912337)
			(xy 364.6953 5.932119) (xy 364.753137 5.944138) (xy 364.812072 5.948169) (xy 364.871007 5.944138)
			(xy 364.928844 5.932119) (xy 364.984505 5.912337) (xy 365.036955 5.88516) (xy 365.085215 5.851094)
			(xy 365.128387 5.810774) (xy 365.165667 5.764951) (xy 365.19636 5.714478) (xy 365.219895 5.660296)
			(xy 365.235832 5.603414) (xy 365.243876 5.544892) (xy 365.24438 5.515356) (xy 365.24438 4.836973)
			(xy 385.651997 4.836973) (xy 385.651997 4.922723) (xy 385.659909 5.008106) (xy 385.675665 5.092396)
			(xy 385.699132 5.174872) (xy 385.730108 5.254831) (xy 385.76833 5.331591) (xy 385.813471 5.404497)
			(xy 385.865147 5.472926) (xy 385.922916 5.536296) (xy 385.986286 5.594065) (xy 386.054715 5.645741)
			(xy 386.127621 5.690882) (xy 386.204381 5.729104) (xy 386.28434 5.76008) (xy 386.366816 5.783547)
			(xy 386.451106 5.799303) (xy 386.536489 5.807215) (xy 386.622239 5.807215) (xy 386.707622 5.799303)
			(xy 386.791912 5.783547) (xy 386.874388 5.76008) (xy 386.954347 5.729104) (xy 386.97502 5.71881)
			(xy 390.508744 5.71881) (xy 390.508744 6.58241) (xy 390.509248 6.611964) (xy 390.517297 6.67052)
			(xy 390.533243 6.727435) (xy 390.556792 6.781649) (xy 390.587503 6.832152) (xy 390.624805 6.878002)
			(xy 390.668002 6.918345) (xy 390.716291 6.952431) (xy 390.768771 6.979624) (xy 390.824466 6.999418)
			(xy 390.882337 7.011444) (xy 390.941306 7.015478) (xy 391.000275 7.011444) (xy 391.058146 6.999418)
			(xy 391.113841 6.979624) (xy 391.166321 6.952431) (xy 391.21461 6.918345) (xy 391.257807 6.878002)
			(xy 391.295109 6.832152) (xy 391.32582 6.781649) (xy 391.349369 6.727435) (xy 391.365315 6.67052)
			(xy 391.373364 6.611964) (xy 391.373868 6.58241) (xy 391.373868 5.71881) (xy 391.373364 5.689256)
			(xy 391.365315 5.6307) (xy 391.349369 5.573785) (xy 391.32582 5.519571) (xy 391.295109 5.469068)
			(xy 391.257807 5.423218) (xy 391.21461 5.382875) (xy 391.166321 5.348789) (xy 391.113841 5.321596)
			(xy 391.058146 5.301802) (xy 391.000275 5.289776) (xy 390.941306 5.285743) (xy 390.882337 5.289776)
			(xy 390.824466 5.301802) (xy 390.768771 5.321596) (xy 390.716291 5.348789) (xy 390.668002 5.382875)
			(xy 390.624805 5.423218) (xy 390.587503 5.469068) (xy 390.556792 5.519571) (xy 390.533243 5.573785)
			(xy 390.517297 5.6307) (xy 390.509248 5.689256) (xy 390.508744 5.71881) (xy 386.97502 5.71881) (xy 387.031107 5.690882)
			(xy 387.104013 5.645741) (xy 387.172442 5.594065) (xy 387.235812 5.536296) (xy 387.293581 5.472926)
			(xy 387.345257 5.404497) (xy 387.390398 5.331591) (xy 387.42862 5.254831) (xy 387.459596 5.174872)
			(xy 387.483063 5.092396) (xy 387.498819 5.008106) (xy 387.506731 4.922723) (xy 387.507226 4.879848)
			(xy 387.506731 4.836973) (xy 392.001997 4.836973) (xy 392.001997 4.922723) (xy 392.009909 5.008106)
			(xy 392.025665 5.092396) (xy 392.049132 5.174872) (xy 392.080108 5.254831) (xy 392.11833 5.331591)
			(xy 392.163471 5.404497) (xy 392.215147 5.472926) (xy 392.272916 5.536296) (xy 392.336286 5.594065)
			(xy 392.404715 5.645741) (xy 392.477621 5.690882) (xy 392.554381 5.729104) (xy 392.63434 5.76008)
			(xy 392.716816 5.783547) (xy 392.801106 5.799303) (xy 392.886489 5.807215) (xy 392.972239 5.807215)
			(xy 393.057622 5.799303) (xy 393.141912 5.783547) (xy 393.224388 5.76008) (xy 393.304347 5.729104)
			(xy 393.381107 5.690882) (xy 393.454013 5.645741) (xy 393.522442 5.594065) (xy 393.585812 5.536296)
			(xy 393.643581 5.472926) (xy 393.695257 5.404497) (xy 393.740398 5.331591) (xy 393.77862 5.254831)
			(xy 393.809596 5.174872) (xy 393.833063 5.092396) (xy 393.848819 5.008106) (xy 393.856731 4.922723)
			(xy 393.857226 4.879848) (xy 393.856731 4.836973) (xy 436.390783 4.836973) (xy 436.390783 4.922723)
			(xy 436.398695 5.008106) (xy 436.414451 5.092396) (xy 436.437918 5.174872) (xy 436.468894 5.254831)
			(xy 436.507116 5.331591) (xy 436.552257 5.404497) (xy 436.603933 5.472926) (xy 436.661702 5.536296)
			(xy 436.725072 5.594065) (xy 436.793501 5.645741) (xy 436.866407 5.690882) (xy 436.943167 5.729104)
			(xy 437.023126 5.76008) (xy 437.105602 5.783547) (xy 437.189892 5.799303) (xy 437.275275 5.807215)
			(xy 437.361025 5.807215) (xy 437.446408 5.799303) (xy 437.530698 5.783547) (xy 437.613174 5.76008)
			(xy 437.693133 5.729104) (xy 437.713806 5.71881) (xy 438.87644 5.71881) (xy 438.87644 6.58241) (xy 438.876944 6.611946)
			(xy 438.884988 6.670468) (xy 438.900925 6.72735) (xy 438.92446 6.781532) (xy 438.955153 6.832005)
			(xy 438.992433 6.877828) (xy 439.035605 6.918148) (xy 439.083865 6.952214) (xy 439.136315 6.979391)
			(xy 439.191976 6.999173) (xy 439.249813 7.011192) (xy 439.308748 7.015223) (xy 439.367683 7.011192)
			(xy 439.42552 6.999173) (xy 439.481181 6.979391) (xy 439.533631 6.952214) (xy 439.581891 6.918148)
			(xy 439.625063 6.877828) (xy 439.662343 6.832005) (xy 439.693036 6.781532) (xy 439.716571 6.72735)
			(xy 439.732508 6.670468) (xy 439.740552 6.611946) (xy 439.741056 6.58241) (xy 439.741056 5.71881)
			(xy 439.740552 5.689274) (xy 439.732508 5.630752) (xy 439.716571 5.57387) (xy 439.693036 5.519688)
			(xy 439.662343 5.469215) (xy 439.625063 5.423392) (xy 439.581891 5.383072) (xy 439.533631 5.349006)
			(xy 439.481181 5.321829) (xy 439.42552 5.302047) (xy 439.367683 5.290028) (xy 439.308748 5.285997)
			(xy 439.249813 5.290028) (xy 439.191976 5.302047) (xy 439.136315 5.321829) (xy 439.083865 5.349006)
			(xy 439.035605 5.383072) (xy 438.992433 5.423392) (xy 438.955153 5.469215) (xy 438.92446 5.519688)
			(xy 438.900925 5.57387) (xy 438.884988 5.630752) (xy 438.876944 5.689274) (xy 438.87644 5.71881)
			(xy 437.713806 5.71881) (xy 437.769893 5.690882) (xy 437.842799 5.645741) (xy 437.911228 5.594065)
			(xy 437.974598 5.536296) (xy 438.032367 5.472926) (xy 438.084043 5.404497) (xy 438.129184 5.331591)
			(xy 438.167406 5.254831) (xy 438.198382 5.174872) (xy 438.221849 5.092396) (xy 438.237605 5.008106)
			(xy 438.245517 4.922723) (xy 438.246012 4.879848) (xy 438.245517 4.836973) (xy 442.740783 4.836973)
			(xy 442.740783 4.922723) (xy 442.748695 5.008106) (xy 442.764451 5.092396) (xy 442.787918 5.174872)
			(xy 442.818894 5.254831) (xy 442.857116 5.331591) (xy 442.902257 5.404497) (xy 442.953933 5.472926)
			(xy 443.011702 5.536296) (xy 443.075072 5.594065) (xy 443.143501 5.645741) (xy 443.216407 5.690882)
			(xy 443.293167 5.729104) (xy 443.373126 5.76008) (xy 443.455602 5.783547) (xy 443.539892 5.799303)
			(xy 443.625275 5.807215) (xy 443.711025 5.807215) (xy 443.796408 5.799303) (xy 443.880698 5.783547)
			(xy 443.963174 5.76008) (xy 444.043133 5.729104) (xy 444.119893 5.690882) (xy 444.192799 5.645741)
			(xy 444.261228 5.594065) (xy 444.324598 5.536296) (xy 444.382367 5.472926) (xy 444.434043 5.404497)
			(xy 444.479184 5.331591) (xy 444.517406 5.254831) (xy 444.548382 5.174872) (xy 444.571849 5.092396)
			(xy 444.587605 5.008106) (xy 444.595517 4.922723) (xy 444.596012 4.879848) (xy 444.595517 4.836973)
			(xy 444.587605 4.75159) (xy 444.571849 4.6673) (xy 444.548382 4.584824) (xy 444.517406 4.504865)
			(xy 444.479184 4.428105) (xy 444.434043 4.355199) (xy 444.382367 4.28677) (xy 444.324598 4.2234)
			(xy 444.261228 4.165631) (xy 444.192799 4.113955) (xy 444.119893 4.068814) (xy 444.043133 4.030592)
			(xy 443.963174 3.999616) (xy 443.880698 3.976149) (xy 443.796408 3.960393) (xy 443.711025 3.952481)
			(xy 443.625275 3.952481) (xy 443.539892 3.960393) (xy 443.455602 3.976149) (xy 443.373126 3.999616)
			(xy 443.293167 4.030592) (xy 443.216407 4.068814) (xy 443.143501 4.113955) (xy 443.075072 4.165631)
			(xy 443.011702 4.2234) (xy 442.953933 4.28677) (xy 442.902257 4.355199) (xy 442.857116 4.428105)
			(xy 442.818894 4.504865) (xy 442.787918 4.584824) (xy 442.764451 4.6673) (xy 442.748695 4.75159)
			(xy 442.740783 4.836973) (xy 438.245517 4.836973) (xy 438.237605 4.75159) (xy 438.221849 4.6673)
			(xy 438.198382 4.584824) (xy 438.167406 4.504865) (xy 438.129184 4.428105) (xy 438.084043 4.355199)
			(xy 438.032367 4.28677) (xy 437.974598 4.2234) (xy 437.911228 4.165631) (xy 437.842799 4.113955)
			(xy 437.769893 4.068814) (xy 437.693133 4.030592) (xy 437.613174 3.999616) (xy 437.530698 3.976149)
			(xy 437.446408 3.960393) (xy 437.361025 3.952481) (xy 437.275275 3.952481) (xy 437.189892 3.960393)
			(xy 437.105602 3.976149) (xy 437.023126 3.999616) (xy 436.943167 4.030592) (xy 436.866407 4.068814)
			(xy 436.793501 4.113955) (xy 436.725072 4.165631) (xy 436.661702 4.2234) (xy 436.603933 4.28677)
			(xy 436.552257 4.355199) (xy 436.507116 4.428105) (xy 436.468894 4.504865) (xy 436.437918 4.584824)
			(xy 436.414451 4.6673) (xy 436.398695 4.75159) (xy 436.390783 4.836973) (xy 393.856731 4.836973)
			(xy 393.848819 4.75159) (xy 393.833063 4.6673) (xy 393.809596 4.584824) (xy 393.77862 4.504865) (xy 393.740398 4.428105)
			(xy 393.695257 4.355199) (xy 393.643581 4.28677) (xy 393.585812 4.2234) (xy 393.522442 4.165631)
			(xy 393.454013 4.113955) (xy 393.381107 4.068814) (xy 393.304347 4.030592) (xy 393.224388 3.999616)
			(xy 393.141912 3.976149) (xy 393.057622 3.960393) (xy 392.972239 3.952481) (xy 392.886489 3.952481)
			(xy 392.801106 3.960393) (xy 392.716816 3.976149) (xy 392.63434 3.999616) (xy 392.554381 4.030592)
			(xy 392.477621 4.068814) (xy 392.404715 4.113955) (xy 392.336286 4.165631) (xy 392.272916 4.2234)
			(xy 392.215147 4.28677) (xy 392.163471 4.355199) (xy 392.11833 4.428105) (xy 392.080108 4.504865)
			(xy 392.049132 4.584824) (xy 392.025665 4.6673) (xy 392.009909 4.75159) (xy 392.001997 4.836973)
			(xy 387.506731 4.836973) (xy 387.498819 4.75159) (xy 387.483063 4.6673) (xy 387.459596 4.584824)
			(xy 387.42862 4.504865) (xy 387.390398 4.428105) (xy 387.345257 4.355199) (xy 387.293581 4.28677)
			(xy 387.235812 4.2234) (xy 387.172442 4.165631) (xy 387.104013 4.113955) (xy 387.031107 4.068814)
			(xy 386.954347 4.030592) (xy 386.874388 3.999616) (xy 386.791912 3.976149) (xy 386.707622 3.960393)
			(xy 386.622239 3.952481) (xy 386.536489 3.952481) (xy 386.451106 3.960393) (xy 386.366816 3.976149)
			(xy 386.28434 3.999616) (xy 386.204381 4.030592) (xy 386.127621 4.068814) (xy 386.054715 4.113955)
			(xy 385.986286 4.165631) (xy 385.922916 4.2234) (xy 385.865147 4.28677) (xy 385.813471 4.355199)
			(xy 385.76833 4.428105) (xy 385.730108 4.504865) (xy 385.699132 4.584824) (xy 385.675665 4.6673)
			(xy 385.659909 4.75159) (xy 385.651997 4.836973) (xy 365.24438 4.836973) (xy 365.24438 4.651756)
			(xy 365.243876 4.62222) (xy 365.235832 4.563698) (xy 365.219895 4.506816) (xy 365.19636 4.452634)
			(xy 365.165667 4.402161) (xy 365.128387 4.356338) (xy 365.085215 4.316018) (xy 365.036955 4.281952)
			(xy 364.984505 4.254775) (xy 364.928844 4.234993) (xy 364.871007 4.222974) (xy 364.812072 4.218943)
			(xy 364.753137 4.222974) (xy 364.6953 4.234993) (xy 364.639639 4.254775) (xy 364.587189 4.281952)
			(xy 364.538929 4.316018) (xy 364.495757 4.356338) (xy 364.458477 4.402161) (xy 364.427784 4.452634)
			(xy 364.404249 4.506816) (xy 364.388312 4.563698) (xy 364.380268 4.62222) (xy 364.379764 4.651756)
			(xy 363.21713 4.651756) (xy 363.273217 4.623828) (xy 363.346123 4.578687) (xy 363.414552 4.527011)
			(xy 363.477922 4.469242) (xy 363.535691 4.405872) (xy 363.587367 4.337443) (xy 363.632508 4.264537)
			(xy 363.67073 4.187777) (xy 363.701706 4.107818) (xy 363.725173 4.025342) (xy 363.740929 3.941052)
			(xy 363.748841 3.855669) (xy 363.749336 3.812794) (xy 363.748841 3.769919) (xy 368.244107 3.769919)
			(xy 368.244107 3.855669) (xy 368.252019 3.941052) (xy 368.267775 4.025342) (xy 368.291242 4.107818)
			(xy 368.322218 4.187777) (xy 368.36044 4.264537) (xy 368.405581 4.337443) (xy 368.457257 4.405872)
			(xy 368.515026 4.469242) (xy 368.578396 4.527011) (xy 368.646825 4.578687) (xy 368.719731 4.623828)
			(xy 368.796491 4.66205) (xy 368.87645 4.693026) (xy 368.958926 4.716493) (xy 369.043216 4.732249)
			(xy 369.128599 4.740161) (xy 369.214349 4.740161) (xy 369.299732 4.732249) (xy 369.384022 4.716493)
			(xy 369.466498 4.693026) (xy 369.546457 4.66205) (xy 369.623217 4.623828) (xy 369.696123 4.578687)
			(xy 369.764552 4.527011) (xy 369.827922 4.469242) (xy 369.885691 4.405872) (xy 369.937367 4.337443)
			(xy 369.982508 4.264537) (xy 370.02073 4.187777) (xy 370.051706 4.107818) (xy 370.075173 4.025342)
			(xy 370.090929 3.941052) (xy 370.098841 3.855669) (xy 370.099336 3.812794) (xy 370.098841 3.769919)
			(xy 370.090929 3.684536) (xy 370.075173 3.600246) (xy 370.051706 3.51777) (xy 370.02073 3.437811)
			(xy 369.982508 3.361051) (xy 369.937367 3.288145) (xy 369.885691 3.219716) (xy 369.827922 3.156346)
			(xy 369.764552 3.098577) (xy 369.696123 3.046901) (xy 369.623217 3.00176) (xy 369.546457 2.963538)
			(xy 369.466498 2.932562) (xy 369.384022 2.909095) (xy 369.299732 2.893339) (xy 369.214349 2.885427)
			(xy 369.128599 2.885427) (xy 369.043216 2.893339) (xy 368.958926 2.909095) (xy 368.87645 2.932562)
			(xy 368.796491 2.963538) (xy 368.719731 3.00176) (xy 368.646825 3.046901) (xy 368.578396 3.098577)
			(xy 368.515026 3.156346) (xy 368.457257 3.219716) (xy 368.405581 3.288145) (xy 368.36044 3.361051)
			(xy 368.322218 3.437811) (xy 368.291242 3.51777) (xy 368.267775 3.600246) (xy 368.252019 3.684536)
			(xy 368.244107 3.769919) (xy 363.748841 3.769919) (xy 363.740929 3.684536) (xy 363.725173 3.600246)
			(xy 363.701706 3.51777) (xy 363.67073 3.437811) (xy 363.632508 3.361051) (xy 363.587367 3.288145)
			(xy 363.535691 3.219716) (xy 363.477922 3.156346) (xy 363.414552 3.098577) (xy 363.346123 3.046901)
			(xy 363.273217 3.00176) (xy 363.196457 2.963538) (xy 363.116498 2.932562) (xy 363.034022 2.909095)
			(xy 362.949732 2.893339) (xy 362.864349 2.885427) (xy 362.778599 2.885427) (xy 362.693216 2.893339)
			(xy 362.608926 2.909095) (xy 362.52645 2.932562) (xy 362.446491 2.963538) (xy 362.369731 3.00176)
			(xy 362.296825 3.046901) (xy 362.228396 3.098577) (xy 362.165026 3.156346) (xy 362.107257 3.219716)
			(xy 362.055581 3.288145) (xy 362.01044 3.361051) (xy 361.972218 3.437811) (xy 361.941242 3.51777)
			(xy 361.917775 3.600246) (xy 361.902019 3.684536) (xy 361.894107 3.769919) (xy 319.360055 3.769919)
			(xy 319.352143 3.684536) (xy 319.336387 3.600246) (xy 319.31292 3.51777) (xy 319.281944 3.437811)
			(xy 319.243722 3.361051) (xy 319.198581 3.288145) (xy 319.146905 3.219716) (xy 319.089136 3.156346)
			(xy 319.025766 3.098577) (xy 318.957337 3.046901) (xy 318.884431 3.00176) (xy 318.807671 2.963538)
			(xy 318.727712 2.932562) (xy 318.645236 2.909095) (xy 318.560946 2.893339) (xy 318.475563 2.885427)
			(xy 318.389813 2.885427) (xy 318.30443 2.893339) (xy 318.22014 2.909095) (xy 318.137664 2.932562)
			(xy 318.057705 2.963538) (xy 317.980945 3.00176) (xy 317.908039 3.046901) (xy 317.83961 3.098577)
			(xy 317.77624 3.156346) (xy 317.718471 3.219716) (xy 317.666795 3.288145) (xy 317.621654 3.361051)
			(xy 317.583432 3.437811) (xy 317.552456 3.51777) (xy 317.528989 3.600246) (xy 317.513233 3.684536)
			(xy 317.505321 3.769919) (xy 313.010055 3.769919) (xy 313.002143 3.684536) (xy 312.986387 3.600246)
			(xy 312.96292 3.51777) (xy 312.931944 3.437811) (xy 312.893722 3.361051) (xy 312.848581 3.288145)
			(xy 312.796905 3.219716) (xy 312.739136 3.156346) (xy 312.675766 3.098577) (xy 312.607337 3.046901)
			(xy 312.534431 3.00176) (xy 312.457671 2.963538) (xy 312.377712 2.932562) (xy 312.295236 2.909095)
			(xy 312.210946 2.893339) (xy 312.125563 2.885427) (xy 312.039813 2.885427) (xy 311.95443 2.893339)
			(xy 311.87014 2.909095) (xy 311.787664 2.932562) (xy 311.707705 2.963538) (xy 311.630945 3.00176)
			(xy 311.558039 3.046901) (xy 311.48961 3.098577) (xy 311.42624 3.156346) (xy 311.368471 3.219716)
			(xy 311.316795 3.288145) (xy 311.271654 3.361051) (xy 311.233432 3.437811) (xy 311.202456 3.51777)
			(xy 311.178989 3.600246) (xy 311.163233 3.684536) (xy 311.155321 3.769919) (xy 304.348655 3.769919)
			(xy 304.340743 3.684536) (xy 304.324987 3.600246) (xy 304.30152 3.51777) (xy 304.270544 3.437811)
			(xy 304.232322 3.361051) (xy 304.187181 3.288145) (xy 304.135505 3.219716) (xy 304.077736 3.156346)
			(xy 304.014366 3.098577) (xy 303.945937 3.046901) (xy 303.873031 3.00176) (xy 303.796271 2.963538)
			(xy 303.716312 2.932562) (xy 303.633836 2.909095) (xy 303.549546 2.893339) (xy 303.464163 2.885427)
			(xy 303.378413 2.885427) (xy 303.29303 2.893339) (xy 303.20874 2.909095) (xy 303.126264 2.932562)
			(xy 303.046305 2.963538) (xy 302.969545 3.00176) (xy 302.896639 3.046901) (xy 302.82821 3.098577)
			(xy 302.76484 3.156346) (xy 302.707071 3.219716) (xy 302.655395 3.288145) (xy 302.610254 3.361051)
			(xy 302.572032 3.437811) (xy 302.541056 3.51777) (xy 302.517589 3.600246) (xy 302.501833 3.684536)
			(xy 302.493921 3.769919) (xy 297.998655 3.769919) (xy 297.990743 3.684536) (xy 297.974987 3.600246)
			(xy 297.95152 3.51777) (xy 297.920544 3.437811) (xy 297.882322 3.361051) (xy 297.837181 3.288145)
			(xy 297.785505 3.219716) (xy 297.727736 3.156346) (xy 297.664366 3.098577) (xy 297.595937 3.046901)
			(xy 297.523031 3.00176) (xy 297.446271 2.963538) (xy 297.366312 2.932562) (xy 297.283836 2.909095)
			(xy 297.199546 2.893339) (xy 297.114163 2.885427) (xy 297.028413 2.885427) (xy 296.94303 2.893339)
			(xy 296.85874 2.909095) (xy 296.776264 2.932562) (xy 296.696305 2.963538) (xy 296.619545 3.00176)
			(xy 296.546639 3.046901) (xy 296.47821 3.098577) (xy 296.41484 3.156346) (xy 296.357071 3.219716)
			(xy 296.305395 3.288145) (xy 296.260254 3.361051) (xy 296.222032 3.437811) (xy 296.191056 3.51777)
			(xy 296.167589 3.600246) (xy 296.151833 3.684536) (xy 296.143921 3.769919) (xy 216.865975 3.769919)
			(xy 216.858063 3.684536) (xy 216.842307 3.600246) (xy 216.81884 3.51777) (xy 216.787864 3.437811)
			(xy 216.749642 3.361051) (xy 216.704501 3.288145) (xy 216.652825 3.219716) (xy 216.595056 3.156346)
			(xy 216.531686 3.098577) (xy 216.463257 3.046901) (xy 216.390351 3.00176) (xy 216.313591 2.963538)
			(xy 216.233632 2.932562) (xy 216.151156 2.909095) (xy 216.066866 2.893339) (xy 215.981483 2.885427)
			(xy 215.895733 2.885427) (xy 215.81035 2.893339) (xy 215.72606 2.909095) (xy 215.643584 2.932562)
			(xy 215.563625 2.963538) (xy 215.486865 3.00176) (xy 215.413959 3.046901) (xy 215.34553 3.098577)
			(xy 215.28216 3.156346) (xy 215.224391 3.219716) (xy 215.172715 3.288145) (xy 215.127574 3.361051)
			(xy 215.089352 3.437811) (xy 215.058376 3.51777) (xy 215.034909 3.600246) (xy 215.019153 3.684536)
			(xy 215.011241 3.769919) (xy 210.515975 3.769919) (xy 210.508063 3.684536) (xy 210.492307 3.600246)
			(xy 210.46884 3.51777) (xy 210.437864 3.437811) (xy 210.399642 3.361051) (xy 210.354501 3.288145)
			(xy 210.302825 3.219716) (xy 210.245056 3.156346) (xy 210.181686 3.098577) (xy 210.113257 3.046901)
			(xy 210.040351 3.00176) (xy 209.963591 2.963538) (xy 209.883632 2.932562) (xy 209.801156 2.909095)
			(xy 209.716866 2.893339) (xy 209.631483 2.885427) (xy 209.545733 2.885427) (xy 209.46035 2.893339)
			(xy 209.37606 2.909095) (xy 209.293584 2.932562) (xy 209.213625 2.963538) (xy 209.136865 3.00176)
			(xy 209.063959 3.046901) (xy 208.99553 3.098577) (xy 208.93216 3.156346) (xy 208.874391 3.219716)
			(xy 208.822715 3.288145) (xy 208.777574 3.361051) (xy 208.739352 3.437811) (xy 208.708376 3.51777)
			(xy 208.684909 3.600246) (xy 208.669153 3.684536) (xy 208.661241 3.769919) (xy 184.818528 3.769919)
			(xy 184.818528 3.092196) (xy 184.818024 3.06266) (xy 184.80998 3.004138) (xy 184.794043 2.947256)
			(xy 184.770508 2.893074) (xy 184.739815 2.842601) (xy 184.702535 2.796778) (xy 184.659363 2.756458)
			(xy 184.611103 2.722392) (xy 184.558653 2.695215) (xy 184.502992 2.675433) (xy 184.445155 2.663414)
			(xy 184.38622 2.659383) (xy 184.327285 2.663414) (xy 184.269448 2.675433) (xy 184.213787 2.695215)
			(xy 184.161337 2.722392) (xy 184.113077 2.756458) (xy 184.069905 2.796778) (xy 184.032625 2.842601)
			(xy 184.001932 2.893074) (xy 183.978397 2.947256) (xy 183.96246 3.004138) (xy 183.954416 3.06266)
			(xy 183.953912 3.092196) (xy 182.791278 3.092196) (xy 182.847365 3.064268) (xy 182.920271 3.019127)
			(xy 182.9887 2.967451) (xy 183.05207 2.909682) (xy 183.109839 2.846312) (xy 183.161515 2.777883)
			(xy 183.206656 2.704977) (xy 183.244878 2.628217) (xy 183.275854 2.548258) (xy 183.299321 2.465782)
			(xy 183.315077 2.381492) (xy 183.322989 2.296109) (xy 183.323484 2.253234) (xy 183.322989 2.210359)
			(xy 187.818255 2.210359) (xy 187.818255 2.296109) (xy 187.826167 2.381492) (xy 187.841923 2.465782)
			(xy 187.86539 2.548258) (xy 187.896366 2.628217) (xy 187.934588 2.704977) (xy 187.979729 2.777883)
			(xy 188.031405 2.846312) (xy 188.089174 2.909682) (xy 188.152544 2.967451) (xy 188.220973 3.019127)
			(xy 188.293879 3.064268) (xy 188.370639 3.10249) (xy 188.450598 3.133466) (xy 188.533074 3.156933)
			(xy 188.617364 3.172689) (xy 188.702747 3.180601) (xy 188.788497 3.180601) (xy 188.87388 3.172689)
			(xy 188.95817 3.156933) (xy 189.040646 3.133466) (xy 189.120605 3.10249) (xy 189.197365 3.064268)
			(xy 189.270271 3.019127) (xy 189.3387 2.967451) (xy 189.40207 2.909682) (xy 189.459839 2.846312)
			(xy 189.511515 2.777883) (xy 189.556656 2.704977) (xy 189.594878 2.628217) (xy 189.625854 2.548258)
			(xy 189.649321 2.465782) (xy 189.665077 2.381492) (xy 189.672989 2.296109) (xy 189.673484 2.253234)
			(xy 189.672989 2.210359) (xy 189.665077 2.124976) (xy 189.649321 2.040686) (xy 189.625854 1.95821)
			(xy 189.594878 1.878251) (xy 189.556656 1.801491) (xy 189.511515 1.728585) (xy 189.459839 1.660156)
			(xy 189.40207 1.596786) (xy 189.3387 1.539017) (xy 189.270271 1.487341) (xy 189.197365 1.4422) (xy 189.120605 1.403978)
			(xy 189.040646 1.373002) (xy 188.95817 1.349535) (xy 188.87388 1.333779) (xy 188.788497 1.325867)
			(xy 188.702747 1.325867) (xy 188.617364 1.333779) (xy 188.533074 1.349535) (xy 188.450598 1.373002)
			(xy 188.370639 1.403978) (xy 188.293879 1.4422) (xy 188.220973 1.487341) (xy 188.152544 1.539017)
			(xy 188.089174 1.596786) (xy 188.031405 1.660156) (xy 187.979729 1.728585) (xy 187.934588 1.801491)
			(xy 187.896366 1.878251) (xy 187.86539 1.95821) (xy 187.841923 2.040686) (xy 187.826167 2.124976)
			(xy 187.818255 2.210359) (xy 183.322989 2.210359) (xy 183.315077 2.124976) (xy 183.299321 2.040686)
			(xy 183.275854 1.95821) (xy 183.244878 1.878251) (xy 183.206656 1.801491) (xy 183.161515 1.728585)
			(xy 183.109839 1.660156) (xy 183.05207 1.596786) (xy 182.9887 1.539017) (xy 182.920271 1.487341)
			(xy 182.847365 1.4422) (xy 182.770605 1.403978) (xy 182.690646 1.373002) (xy 182.60817 1.349535)
			(xy 182.52388 1.333779) (xy 182.438497 1.325867) (xy 182.352747 1.325867) (xy 182.267364 1.333779)
			(xy 182.183074 1.349535) (xy 182.100598 1.373002) (xy 182.020639 1.403978) (xy 181.943879 1.4422)
			(xy 181.870973 1.487341) (xy 181.802544 1.539017) (xy 181.739174 1.596786) (xy 181.681405 1.660156)
			(xy 181.629729 1.728585) (xy 181.584588 1.801491) (xy 181.546366 1.878251) (xy 181.51539 1.95821)
			(xy 181.491923 2.040686) (xy 181.476167 2.124976) (xy 181.468255 2.210359) (xy 102.190309 2.210359)
			(xy 102.182397 2.124976) (xy 102.166641 2.040686) (xy 102.143174 1.95821) (xy 102.112198 1.878251)
			(xy 102.073976 1.801491) (xy 102.028835 1.728585) (xy 101.977159 1.660156) (xy 101.91939 1.596786)
			(xy 101.85602 1.539017) (xy 101.787591 1.487341) (xy 101.714685 1.4422) (xy 101.637925 1.403978)
			(xy 101.557966 1.373002) (xy 101.47549 1.349535) (xy 101.3912 1.333779) (xy 101.305817 1.325867)
			(xy 101.220067 1.325867) (xy 101.134684 1.333779) (xy 101.050394 1.349535) (xy 100.967918 1.373002)
			(xy 100.887959 1.403978) (xy 100.811199 1.4422) (xy 100.738293 1.487341) (xy 100.669864 1.539017)
			(xy 100.606494 1.596786) (xy 100.548725 1.660156) (xy 100.497049 1.728585) (xy 100.451908 1.801491)
			(xy 100.413686 1.878251) (xy 100.38271 1.95821) (xy 100.359243 2.040686) (xy 100.343487 2.124976)
			(xy 100.335575 2.210359) (xy 95.840309 2.210359) (xy 95.832397 2.124976) (xy 95.816641 2.040686)
			(xy 95.793174 1.95821) (xy 95.762198 1.878251) (xy 95.723976 1.801491) (xy 95.678835 1.728585) (xy 95.627159 1.660156)
			(xy 95.56939 1.596786) (xy 95.50602 1.539017) (xy 95.437591 1.487341) (xy 95.364685 1.4422) (xy 95.287925 1.403978)
			(xy 95.207966 1.373002) (xy 95.12549 1.349535) (xy 95.0412 1.333779) (xy 94.955817 1.325867) (xy 94.870067 1.325867)
			(xy 94.784684 1.333779) (xy 94.700394 1.349535) (xy 94.617918 1.373002) (xy 94.537959 1.403978) (xy 94.461199 1.4422)
			(xy 94.388293 1.487341) (xy 94.319864 1.539017) (xy 94.256494 1.596786) (xy 94.198725 1.660156) (xy 94.147049 1.728585)
			(xy 94.101908 1.801491) (xy 94.063686 1.878251) (xy 94.03271 1.95821) (xy 94.009243 2.040686) (xy 93.993487 2.124976)
			(xy 93.985575 2.210359) (xy 83.439191 2.210359) (xy 83.525475 2.124078) (xy 83.619275 2.019118) (xy 83.707042 1.909064)
			(xy 83.788501 1.794262) (xy 83.863394 1.675073) (xy 83.931487 1.551873) (xy 83.992565 1.425048) (xy 84.046435 1.294999)
			(xy 84.069209 1.229919) (xy 208.661241 1.229919) (xy 208.661241 1.315669) (xy 208.669153 1.401052)
			(xy 208.684909 1.485342) (xy 208.708376 1.567818) (xy 208.739352 1.647777) (xy 208.777574 1.724537)
			(xy 208.822715 1.797443) (xy 208.874391 1.865872) (xy 208.93216 1.929242) (xy 208.99553 1.987011)
			(xy 209.063959 2.038687) (xy 209.136865 2.083828) (xy 209.213625 2.12205) (xy 209.293584 2.153026)
			(xy 209.37606 2.176493) (xy 209.46035 2.192249) (xy 209.545733 2.200161) (xy 209.631483 2.200161)
			(xy 209.716866 2.192249) (xy 209.801156 2.176493) (xy 209.883632 2.153026) (xy 209.963591 2.12205)
			(xy 209.984264 2.111756) (xy 213.517988 2.111756) (xy 213.517988 2.975356) (xy 213.518492 3.00491)
			(xy 213.526541 3.063466) (xy 213.542487 3.120381) (xy 213.566036 3.174595) (xy 213.596747 3.225098)
			(xy 213.634049 3.270948) (xy 213.677246 3.311291) (xy 213.725535 3.345377) (xy 213.778015 3.37257)
			(xy 213.83371 3.392364) (xy 213.891581 3.40439) (xy 213.95055 3.408424) (xy 214.009519 3.40439) (xy 214.06739 3.392364)
			(xy 214.123085 3.37257) (xy 214.175565 3.345377) (xy 214.223854 3.311291) (xy 214.267051 3.270948)
			(xy 214.304353 3.225098) (xy 214.335064 3.174595) (xy 214.358613 3.120381) (xy 214.374559 3.063466)
			(xy 214.382608 3.00491) (xy 214.383112 2.975356) (xy 214.383112 2.111756) (xy 214.382608 2.082202)
			(xy 214.374559 2.023646) (xy 214.358613 1.966731) (xy 214.335064 1.912517) (xy 214.304353 1.862014)
			(xy 214.267051 1.816164) (xy 214.223854 1.775821) (xy 214.175565 1.741735) (xy 214.123085 1.714542)
			(xy 214.06739 1.694748) (xy 214.009519 1.682722) (xy 213.95055 1.678689) (xy 213.891581 1.682722)
			(xy 213.83371 1.694748) (xy 213.778015 1.714542) (xy 213.725535 1.741735) (xy 213.677246 1.775821)
			(xy 213.634049 1.816164) (xy 213.596747 1.862014) (xy 213.566036 1.912517) (xy 213.542487 1.966731)
			(xy 213.526541 2.023646) (xy 213.518492 2.082202) (xy 213.517988 2.111756) (xy 209.984264 2.111756)
			(xy 210.040351 2.083828) (xy 210.113257 2.038687) (xy 210.181686 1.987011) (xy 210.245056 1.929242)
			(xy 210.302825 1.865872) (xy 210.354501 1.797443) (xy 210.399642 1.724537) (xy 210.437864 1.647777)
			(xy 210.46884 1.567818) (xy 210.492307 1.485342) (xy 210.508063 1.401052) (xy 210.515975 1.315669)
			(xy 210.51647 1.272794) (xy 210.515975 1.229919) (xy 215.011241 1.229919) (xy 215.011241 1.315669)
			(xy 215.019153 1.401052) (xy 215.034909 1.485342) (xy 215.058376 1.567818) (xy 215.089352 1.647777)
			(xy 215.127574 1.724537) (xy 215.172715 1.797443) (xy 215.224391 1.865872) (xy 215.28216 1.929242)
			(xy 215.34553 1.987011) (xy 215.413959 2.038687) (xy 215.486865 2.083828) (xy 215.563625 2.12205)
			(xy 215.643584 2.153026) (xy 215.72606 2.176493) (xy 215.81035 2.192249) (xy 215.895733 2.200161)
			(xy 215.981483 2.200161) (xy 216.066866 2.192249) (xy 216.151156 2.176493) (xy 216.233632 2.153026)
			(xy 216.313591 2.12205) (xy 216.390351 2.083828) (xy 216.463257 2.038687) (xy 216.531686 1.987011)
			(xy 216.595056 1.929242) (xy 216.652825 1.865872) (xy 216.704501 1.797443) (xy 216.749642 1.724537)
			(xy 216.787864 1.647777) (xy 216.81884 1.567818) (xy 216.842307 1.485342) (xy 216.858063 1.401052)
			(xy 216.865975 1.315669) (xy 216.86647 1.272794) (xy 216.865975 1.229919) (xy 296.143921 1.229919)
			(xy 296.143921 1.315669) (xy 296.151833 1.401052) (xy 296.167589 1.485342) (xy 296.191056 1.567818)
			(xy 296.222032 1.647777) (xy 296.260254 1.724537) (xy 296.305395 1.797443) (xy 296.357071 1.865872)
			(xy 296.41484 1.929242) (xy 296.47821 1.987011) (xy 296.546639 2.038687) (xy 296.619545 2.083828)
			(xy 296.696305 2.12205) (xy 296.776264 2.153026) (xy 296.85874 2.176493) (xy 296.94303 2.192249)
			(xy 297.028413 2.200161) (xy 297.114163 2.200161) (xy 297.199546 2.192249) (xy 297.283836 2.176493)
			(xy 297.366312 2.153026) (xy 297.446271 2.12205) (xy 297.466944 2.111756) (xy 298.629324 2.111756)
			(xy 298.629324 2.975356) (xy 298.629828 3.00491) (xy 298.637877 3.063466) (xy 298.653823 3.120381)
			(xy 298.677372 3.174595) (xy 298.708083 3.225098) (xy 298.745385 3.270948) (xy 298.788582 3.311291)
			(xy 298.836871 3.345377) (xy 298.889351 3.37257) (xy 298.945046 3.392364) (xy 299.002917 3.40439)
			(xy 299.061886 3.408424) (xy 299.120855 3.40439) (xy 299.178726 3.392364) (xy 299.234421 3.37257)
			(xy 299.286901 3.345377) (xy 299.33519 3.311291) (xy 299.378387 3.270948) (xy 299.415689 3.225098)
			(xy 299.4464 3.174595) (xy 299.469949 3.120381) (xy 299.485895 3.063466) (xy 299.493944 3.00491)
			(xy 299.494448 2.975356) (xy 299.494448 2.111756) (xy 299.493944 2.082202) (xy 299.485895 2.023646)
			(xy 299.469949 1.966731) (xy 299.4464 1.912517) (xy 299.415689 1.862014) (xy 299.378387 1.816164)
			(xy 299.33519 1.775821) (xy 299.286901 1.741735) (xy 299.234421 1.714542) (xy 299.178726 1.694748)
			(xy 299.120855 1.682722) (xy 299.061886 1.678689) (xy 299.002917 1.682722) (xy 298.945046 1.694748)
			(xy 298.889351 1.714542) (xy 298.836871 1.741735) (xy 298.788582 1.775821) (xy 298.745385 1.816164)
			(xy 298.708083 1.862014) (xy 298.677372 1.912517) (xy 298.653823 1.966731) (xy 298.637877 2.023646)
			(xy 298.629828 2.082202) (xy 298.629324 2.111756) (xy 297.466944 2.111756) (xy 297.523031 2.083828)
			(xy 297.595937 2.038687) (xy 297.664366 1.987011) (xy 297.727736 1.929242) (xy 297.785505 1.865872)
			(xy 297.837181 1.797443) (xy 297.882322 1.724537) (xy 297.920544 1.647777) (xy 297.95152 1.567818)
			(xy 297.974987 1.485342) (xy 297.990743 1.401052) (xy 297.998655 1.315669) (xy 297.99915 1.272794)
			(xy 297.998655 1.229919) (xy 302.493921 1.229919) (xy 302.493921 1.315669) (xy 302.501833 1.401052)
			(xy 302.517589 1.485342) (xy 302.541056 1.567818) (xy 302.572032 1.647777) (xy 302.610254 1.724537)
			(xy 302.655395 1.797443) (xy 302.707071 1.865872) (xy 302.76484 1.929242) (xy 302.82821 1.987011)
			(xy 302.896639 2.038687) (xy 302.969545 2.083828) (xy 303.046305 2.12205) (xy 303.126264 2.153026)
			(xy 303.20874 2.176493) (xy 303.29303 2.192249) (xy 303.378413 2.200161) (xy 303.464163 2.200161)
			(xy 303.549546 2.192249) (xy 303.633836 2.176493) (xy 303.716312 2.153026) (xy 303.796271 2.12205)
			(xy 303.873031 2.083828) (xy 303.945937 2.038687) (xy 304.014366 1.987011) (xy 304.077736 1.929242)
			(xy 304.135505 1.865872) (xy 304.187181 1.797443) (xy 304.232322 1.724537) (xy 304.270544 1.647777)
			(xy 304.30152 1.567818) (xy 304.324987 1.485342) (xy 304.340743 1.401052) (xy 304.348655 1.315669)
			(xy 304.34915 1.272794) (xy 304.348655 1.229919) (xy 311.155321 1.229919) (xy 311.155321 1.315669)
			(xy 311.163233 1.401052) (xy 311.178989 1.485342) (xy 311.202456 1.567818) (xy 311.233432 1.647777)
			(xy 311.271654 1.724537) (xy 311.316795 1.797443) (xy 311.368471 1.865872) (xy 311.42624 1.929242)
			(xy 311.48961 1.987011) (xy 311.558039 2.038687) (xy 311.630945 2.083828) (xy 311.707705 2.12205)
			(xy 311.787664 2.153026) (xy 311.87014 2.176493) (xy 311.95443 2.192249) (xy 312.039813 2.200161)
			(xy 312.125563 2.200161) (xy 312.210946 2.192249) (xy 312.295236 2.176493) (xy 312.377712 2.153026)
			(xy 312.457671 2.12205) (xy 312.534431 2.083828) (xy 312.607337 2.038687) (xy 312.675766 1.987011)
			(xy 312.739136 1.929242) (xy 312.796905 1.865872) (xy 312.848581 1.797443) (xy 312.893722 1.724537)
			(xy 312.931944 1.647777) (xy 312.96292 1.567818) (xy 312.986387 1.485342) (xy 313.002143 1.401052)
			(xy 313.010055 1.315669) (xy 313.01055 1.272794) (xy 313.010055 1.229919) (xy 317.505321 1.229919)
			(xy 317.505321 1.315669) (xy 317.513233 1.401052) (xy 317.528989 1.485342) (xy 317.552456 1.567818)
			(xy 317.583432 1.647777) (xy 317.621654 1.724537) (xy 317.666795 1.797443) (xy 317.718471 1.865872)
			(xy 317.77624 1.929242) (xy 317.83961 1.987011) (xy 317.908039 2.038687) (xy 317.980945 2.083828)
			(xy 318.057705 2.12205) (xy 318.137664 2.153026) (xy 318.22014 2.176493) (xy 318.30443 2.192249)
			(xy 318.389813 2.200161) (xy 318.475563 2.200161) (xy 318.560946 2.192249) (xy 318.645236 2.176493)
			(xy 318.727712 2.153026) (xy 318.807671 2.12205) (xy 318.884431 2.083828) (xy 318.957337 2.038687)
			(xy 319.025766 1.987011) (xy 319.089136 1.929242) (xy 319.146905 1.865872) (xy 319.198581 1.797443)
			(xy 319.243722 1.724537) (xy 319.281944 1.647777) (xy 319.31292 1.567818) (xy 319.336387 1.485342)
			(xy 319.352143 1.401052) (xy 319.360055 1.315669) (xy 319.36055 1.272794) (xy 319.360055 1.229919)
			(xy 361.894107 1.229919) (xy 361.894107 1.315669) (xy 361.902019 1.401052) (xy 361.917775 1.485342)
			(xy 361.941242 1.567818) (xy 361.972218 1.647777) (xy 362.01044 1.724537) (xy 362.055581 1.797443)
			(xy 362.107257 1.865872) (xy 362.165026 1.929242) (xy 362.228396 1.987011) (xy 362.296825 2.038687)
			(xy 362.369731 2.083828) (xy 362.446491 2.12205) (xy 362.52645 2.153026) (xy 362.608926 2.176493)
			(xy 362.693216 2.192249) (xy 362.778599 2.200161) (xy 362.864349 2.200161) (xy 362.949732 2.192249)
			(xy 363.034022 2.176493) (xy 363.116498 2.153026) (xy 363.196457 2.12205) (xy 363.273217 2.083828)
			(xy 363.346123 2.038687) (xy 363.414552 1.987011) (xy 363.477922 1.929242) (xy 363.535691 1.865872)
			(xy 363.587367 1.797443) (xy 363.632508 1.724537) (xy 363.67073 1.647777) (xy 363.701706 1.567818)
			(xy 363.725173 1.485342) (xy 363.740929 1.401052) (xy 363.748841 1.315669) (xy 363.749336 1.272794)
			(xy 363.748841 1.229919) (xy 368.244107 1.229919) (xy 368.244107 1.315669) (xy 368.252019 1.401052)
			(xy 368.267775 1.485342) (xy 368.291242 1.567818) (xy 368.322218 1.647777) (xy 368.36044 1.724537)
			(xy 368.405581 1.797443) (xy 368.457257 1.865872) (xy 368.515026 1.929242) (xy 368.578396 1.987011)
			(xy 368.646825 2.038687) (xy 368.719731 2.083828) (xy 368.796491 2.12205) (xy 368.87645 2.153026)
			(xy 368.958926 2.176493) (xy 369.043216 2.192249) (xy 369.128599 2.200161) (xy 369.214349 2.200161)
			(xy 369.299732 2.192249) (xy 369.384022 2.176493) (xy 369.466498 2.153026) (xy 369.546457 2.12205)
			(xy 369.623217 2.083828) (xy 369.696123 2.038687) (xy 369.764552 1.987011) (xy 369.827922 1.929242)
			(xy 369.885691 1.865872) (xy 369.937367 1.797443) (xy 369.982508 1.724537) (xy 370.02073 1.647777)
			(xy 370.051706 1.567818) (xy 370.075173 1.485342) (xy 370.090929 1.401052) (xy 370.098841 1.315669)
			(xy 370.099336 1.272794) (xy 370.098841 1.229919) (xy 370.090929 1.144536) (xy 370.075173 1.060246)
			(xy 370.051706 0.97777) (xy 370.02073 0.897811) (xy 369.982508 0.821051) (xy 369.937367 0.748145)
			(xy 369.885691 0.679716) (xy 369.827922 0.616346) (xy 369.764552 0.558577) (xy 369.696123 0.506901)
			(xy 369.623217 0.46176) (xy 369.546457 0.423538) (xy 369.466498 0.392562) (xy 369.384022 0.369095)
			(xy 369.299732 0.353339) (xy 369.214349 0.345427) (xy 369.128599 0.345427) (xy 369.043216 0.353339)
			(xy 368.958926 0.369095) (xy 368.87645 0.392562) (xy 368.796491 0.423538) (xy 368.719731 0.46176)
			(xy 368.646825 0.506901) (xy 368.578396 0.558577) (xy 368.515026 0.616346) (xy 368.457257 0.679716)
			(xy 368.405581 0.748145) (xy 368.36044 0.821051) (xy 368.322218 0.897811) (xy 368.291242 0.97777)
			(xy 368.267775 1.060246) (xy 368.252019 1.144536) (xy 368.244107 1.229919) (xy 363.748841 1.229919)
			(xy 363.740929 1.144536) (xy 363.725173 1.060246) (xy 363.701706 0.97777) (xy 363.67073 0.897811)
			(xy 363.632508 0.821051) (xy 363.587367 0.748145) (xy 363.535691 0.679716) (xy 363.477922 0.616346)
			(xy 363.414552 0.558577) (xy 363.346123 0.506901) (xy 363.273217 0.46176) (xy 363.196457 0.423538)
			(xy 363.116498 0.392562) (xy 363.034022 0.369095) (xy 362.949732 0.353339) (xy 362.864349 0.345427)
			(xy 362.778599 0.345427) (xy 362.693216 0.353339) (xy 362.608926 0.369095) (xy 362.52645 0.392562)
			(xy 362.446491 0.423538) (xy 362.369731 0.46176) (xy 362.296825 0.506901) (xy 362.228396 0.558577)
			(xy 362.165026 0.616346) (xy 362.107257 0.679716) (xy 362.055581 0.748145) (xy 362.01044 0.821051)
			(xy 361.972218 0.897811) (xy 361.941242 0.97777) (xy 361.917775 1.060246) (xy 361.902019 1.144536)
			(xy 361.894107 1.229919) (xy 319.360055 1.229919) (xy 319.352143 1.144536) (xy 319.336387 1.060246)
			(xy 319.31292 0.97777) (xy 319.281944 0.897811) (xy 319.243722 0.821051) (xy 319.198581 0.748145)
			(xy 319.146905 0.679716) (xy 319.089136 0.616346) (xy 319.025766 0.558577) (xy 318.957337 0.506901)
			(xy 318.884431 0.46176) (xy 318.807671 0.423538) (xy 318.727712 0.392562) (xy 318.645236 0.369095)
			(xy 318.560946 0.353339) (xy 318.475563 0.345427) (xy 318.389813 0.345427) (xy 318.30443 0.353339)
			(xy 318.22014 0.369095) (xy 318.137664 0.392562) (xy 318.057705 0.423538) (xy 317.980945 0.46176)
			(xy 317.908039 0.506901) (xy 317.83961 0.558577) (xy 317.77624 0.616346) (xy 317.718471 0.679716)
			(xy 317.666795 0.748145) (xy 317.621654 0.821051) (xy 317.583432 0.897811) (xy 317.552456 0.97777)
			(xy 317.528989 1.060246) (xy 317.513233 1.144536) (xy 317.505321 1.229919) (xy 313.010055 1.229919)
			(xy 313.002143 1.144536) (xy 312.986387 1.060246) (xy 312.96292 0.97777) (xy 312.931944 0.897811)
			(xy 312.893722 0.821051) (xy 312.848581 0.748145) (xy 312.796905 0.679716) (xy 312.739136 0.616346)
			(xy 312.675766 0.558577) (xy 312.607337 0.506901) (xy 312.534431 0.46176) (xy 312.457671 0.423538)
			(xy 312.377712 0.392562) (xy 312.295236 0.369095) (xy 312.210946 0.353339) (xy 312.125563 0.345427)
			(xy 312.039813 0.345427) (xy 311.95443 0.353339) (xy 311.87014 0.369095) (xy 311.787664 0.392562)
			(xy 311.707705 0.423538) (xy 311.630945 0.46176) (xy 311.558039 0.506901) (xy 311.48961 0.558577)
			(xy 311.42624 0.616346) (xy 311.368471 0.679716) (xy 311.316795 0.748145) (xy 311.271654 0.821051)
			(xy 311.233432 0.897811) (xy 311.202456 0.97777) (xy 311.178989 1.060246) (xy 311.163233 1.144536)
			(xy 311.155321 1.229919) (xy 304.348655 1.229919) (xy 304.340743 1.144536) (xy 304.324987 1.060246)
			(xy 304.30152 0.97777) (xy 304.270544 0.897811) (xy 304.232322 0.821051) (xy 304.187181 0.748145)
			(xy 304.135505 0.679716) (xy 304.077736 0.616346) (xy 304.014366 0.558577) (xy 303.945937 0.506901)
			(xy 303.873031 0.46176) (xy 303.796271 0.423538) (xy 303.716312 0.392562) (xy 303.633836 0.369095)
			(xy 303.549546 0.353339) (xy 303.464163 0.345427) (xy 303.378413 0.345427) (xy 303.29303 0.353339)
			(xy 303.20874 0.369095) (xy 303.126264 0.392562) (xy 303.046305 0.423538) (xy 302.969545 0.46176)
			(xy 302.896639 0.506901) (xy 302.82821 0.558577) (xy 302.76484 0.616346) (xy 302.707071 0.679716)
			(xy 302.655395 0.748145) (xy 302.610254 0.821051) (xy 302.572032 0.897811) (xy 302.541056 0.97777)
			(xy 302.517589 1.060246) (xy 302.501833 1.144536) (xy 302.493921 1.229919) (xy 297.998655 1.229919)
			(xy 297.990743 1.144536) (xy 297.974987 1.060246) (xy 297.95152 0.97777) (xy 297.920544 0.897811)
			(xy 297.882322 0.821051) (xy 297.837181 0.748145) (xy 297.785505 0.679716) (xy 297.727736 0.616346)
			(xy 297.664366 0.558577) (xy 297.595937 0.506901) (xy 297.523031 0.46176) (xy 297.446271 0.423538)
			(xy 297.366312 0.392562) (xy 297.283836 0.369095) (xy 297.199546 0.353339) (xy 297.114163 0.345427)
			(xy 297.028413 0.345427) (xy 296.94303 0.353339) (xy 296.85874 0.369095) (xy 296.776264 0.392562)
			(xy 296.696305 0.423538) (xy 296.619545 0.46176) (xy 296.546639 0.506901) (xy 296.47821 0.558577)
			(xy 296.41484 0.616346) (xy 296.357071 0.679716) (xy 296.305395 0.748145) (xy 296.260254 0.821051)
			(xy 296.222032 0.897811) (xy 296.191056 0.97777) (xy 296.167589 1.060246) (xy 296.151833 1.144536)
			(xy 296.143921 1.229919) (xy 216.865975 1.229919) (xy 216.858063 1.144536) (xy 216.842307 1.060246)
			(xy 216.81884 0.97777) (xy 216.787864 0.897811) (xy 216.749642 0.821051) (xy 216.704501 0.748145)
			(xy 216.652825 0.679716) (xy 216.595056 0.616346) (xy 216.531686 0.558577) (xy 216.463257 0.506901)
			(xy 216.390351 0.46176) (xy 216.313591 0.423538) (xy 216.233632 0.392562) (xy 216.151156 0.369095)
			(xy 216.066866 0.353339) (xy 215.981483 0.345427) (xy 215.895733 0.345427) (xy 215.81035 0.353339)
			(xy 215.72606 0.369095) (xy 215.643584 0.392562) (xy 215.563625 0.423538) (xy 215.486865 0.46176)
			(xy 215.413959 0.506901) (xy 215.34553 0.558577) (xy 215.28216 0.616346) (xy 215.224391 0.679716)
			(xy 215.172715 0.748145) (xy 215.127574 0.821051) (xy 215.089352 0.897811) (xy 215.058376 0.97777)
			(xy 215.034909 1.060246) (xy 215.019153 1.144536) (xy 215.011241 1.229919) (xy 210.515975 1.229919)
			(xy 210.508063 1.144536) (xy 210.492307 1.060246) (xy 210.46884 0.97777) (xy 210.437864 0.897811)
			(xy 210.399642 0.821051) (xy 210.354501 0.748145) (xy 210.302825 0.679716) (xy 210.245056 0.616346)
			(xy 210.181686 0.558577) (xy 210.113257 0.506901) (xy 210.040351 0.46176) (xy 209.963591 0.423538)
			(xy 209.883632 0.392562) (xy 209.801156 0.369095) (xy 209.716866 0.353339) (xy 209.631483 0.345427)
			(xy 209.545733 0.345427) (xy 209.46035 0.353339) (xy 209.37606 0.369095) (xy 209.293584 0.392562)
			(xy 209.213625 0.423538) (xy 209.136865 0.46176) (xy 209.063959 0.506901) (xy 208.99553 0.558577)
			(xy 208.93216 0.616346) (xy 208.874391 0.679716) (xy 208.822715 0.748145) (xy 208.777574 0.821051)
			(xy 208.739352 0.897811) (xy 208.708376 0.97777) (xy 208.684909 1.060246) (xy 208.669153 1.144536)
			(xy 208.661241 1.229919) (xy 84.069209 1.229919) (xy 84.092929 1.162133) (xy 84.131901 1.02687) (xy 84.163226 0.889634)
			(xy 84.186808 0.750857) (xy 84.202571 0.610977) (xy 84.210467 0.470433) (xy 84.210906 0.40005) (xy 84.210906 -1.310081)
			(xy 208.661241 -1.310081) (xy 208.661241 -1.224331) (xy 208.669153 -1.138948) (xy 208.684909 -1.054658)
			(xy 208.708376 -0.972182) (xy 208.739352 -0.892223) (xy 208.777574 -0.815463) (xy 208.822715 -0.742557)
			(xy 208.874391 -0.674128) (xy 208.93216 -0.610758) (xy 208.99553 -0.552989) (xy 209.063959 -0.501313)
			(xy 209.136865 -0.456172) (xy 209.213625 -0.41795) (xy 209.293584 -0.386974) (xy 209.37606 -0.363507)
			(xy 209.46035 -0.347751) (xy 209.545733 -0.339839) (xy 209.631483 -0.339839) (xy 209.716866 -0.347751)
			(xy 209.801156 -0.363507) (xy 209.883632 -0.386974) (xy 209.963591 -0.41795) (xy 210.040351 -0.456172)
			(xy 210.113257 -0.501313) (xy 210.181686 -0.552989) (xy 210.245056 -0.610758) (xy 210.302825 -0.674128)
			(xy 210.354501 -0.742557) (xy 210.399642 -0.815463) (xy 210.437864 -0.892223) (xy 210.46884 -0.972182)
			(xy 210.492307 -1.054658) (xy 210.508063 -1.138948) (xy 210.515975 -1.224331) (xy 210.51647 -1.267206)
			(xy 210.515975 -1.310081) (xy 215.011241 -1.310081) (xy 215.011241 -1.224331) (xy 215.019153 -1.138948)
			(xy 215.034909 -1.054658) (xy 215.058376 -0.972182) (xy 215.089352 -0.892223) (xy 215.127574 -0.815463)
			(xy 215.172715 -0.742557) (xy 215.224391 -0.674128) (xy 215.28216 -0.610758) (xy 215.34553 -0.552989)
			(xy 215.413959 -0.501313) (xy 215.486865 -0.456172) (xy 215.563625 -0.41795) (xy 215.643584 -0.386974)
			(xy 215.72606 -0.363507) (xy 215.81035 -0.347751) (xy 215.895733 -0.339839) (xy 215.981483 -0.339839)
			(xy 216.066866 -0.347751) (xy 216.151156 -0.363507) (xy 216.233632 -0.386974) (xy 216.313591 -0.41795)
			(xy 216.390351 -0.456172) (xy 216.463257 -0.501313) (xy 216.531686 -0.552989) (xy 216.595056 -0.610758)
			(xy 216.652825 -0.674128) (xy 216.704501 -0.742557) (xy 216.749642 -0.815463) (xy 216.787864 -0.892223)
			(xy 216.81884 -0.972182) (xy 216.842307 -1.054658) (xy 216.858063 -1.138948) (xy 216.865975 -1.224331)
			(xy 216.86647 -1.267206) (xy 216.865975 -1.310081) (xy 296.143921 -1.310081) (xy 296.143921 -1.224331)
			(xy 296.151833 -1.138948) (xy 296.167589 -1.054658) (xy 296.191056 -0.972182) (xy 296.222032 -0.892223)
			(xy 296.260254 -0.815463) (xy 296.305395 -0.742557) (xy 296.357071 -0.674128) (xy 296.41484 -0.610758)
			(xy 296.47821 -0.552989) (xy 296.546639 -0.501313) (xy 296.619545 -0.456172) (xy 296.696305 -0.41795)
			(xy 296.776264 -0.386974) (xy 296.85874 -0.363507) (xy 296.94303 -0.347751) (xy 297.028413 -0.339839)
			(xy 297.114163 -0.339839) (xy 297.199546 -0.347751) (xy 297.283836 -0.363507) (xy 297.366312 -0.386974)
			(xy 297.446271 -0.41795) (xy 297.523031 -0.456172) (xy 297.595937 -0.501313) (xy 297.664366 -0.552989)
			(xy 297.727736 -0.610758) (xy 297.785505 -0.674128) (xy 297.837181 -0.742557) (xy 297.882322 -0.815463)
			(xy 297.920544 -0.892223) (xy 297.95152 -0.972182) (xy 297.974987 -1.054658) (xy 297.990743 -1.138948)
			(xy 297.998655 -1.224331) (xy 297.99915 -1.267206) (xy 297.998655 -1.310081) (xy 302.493921 -1.310081)
			(xy 302.493921 -1.224331) (xy 302.501833 -1.138948) (xy 302.517589 -1.054658) (xy 302.541056 -0.972182)
			(xy 302.572032 -0.892223) (xy 302.610254 -0.815463) (xy 302.655395 -0.742557) (xy 302.707071 -0.674128)
			(xy 302.76484 -0.610758) (xy 302.82821 -0.552989) (xy 302.896639 -0.501313) (xy 302.969545 -0.456172)
			(xy 303.046305 -0.41795) (xy 303.126264 -0.386974) (xy 303.20874 -0.363507) (xy 303.29303 -0.347751)
			(xy 303.378413 -0.339839) (xy 303.464163 -0.339839) (xy 303.549546 -0.347751) (xy 303.633836 -0.363507)
			(xy 303.716312 -0.386974) (xy 303.796271 -0.41795) (xy 303.873031 -0.456172) (xy 303.945937 -0.501313)
			(xy 304.014366 -0.552989) (xy 304.077736 -0.610758) (xy 304.135505 -0.674128) (xy 304.187181 -0.742557)
			(xy 304.232322 -0.815463) (xy 304.270544 -0.892223) (xy 304.30152 -0.972182) (xy 304.324987 -1.054658)
			(xy 304.340743 -1.138948) (xy 304.348655 -1.224331) (xy 304.34915 -1.267206) (xy 304.348655 -1.310081)
			(xy 311.155321 -1.310081) (xy 311.155321 -1.224331) (xy 311.163233 -1.138948) (xy 311.178989 -1.054658)
			(xy 311.202456 -0.972182) (xy 311.233432 -0.892223) (xy 311.271654 -0.815463) (xy 311.316795 -0.742557)
			(xy 311.368471 -0.674128) (xy 311.42624 -0.610758) (xy 311.48961 -0.552989) (xy 311.558039 -0.501313)
			(xy 311.630945 -0.456172) (xy 311.707705 -0.41795) (xy 311.787664 -0.386974) (xy 311.87014 -0.363507)
			(xy 311.95443 -0.347751) (xy 312.039813 -0.339839) (xy 312.125563 -0.339839) (xy 312.210946 -0.347751)
			(xy 312.295236 -0.363507) (xy 312.377712 -0.386974) (xy 312.457671 -0.41795) (xy 312.478344 -0.428244)
			(xy 316.012068 -0.428244) (xy 316.012068 0.435356) (xy 316.012572 0.46491) (xy 316.020621 0.523466)
			(xy 316.036567 0.580381) (xy 316.060116 0.634595) (xy 316.090827 0.685098) (xy 316.128129 0.730948)
			(xy 316.171326 0.771291) (xy 316.219615 0.805377) (xy 316.272095 0.83257) (xy 316.32779 0.852364)
			(xy 316.385661 0.86439) (xy 316.44463 0.868424) (xy 316.503599 0.86439) (xy 316.56147 0.852364) (xy 316.617165 0.83257)
			(xy 316.669645 0.805377) (xy 316.717934 0.771291) (xy 316.761131 0.730948) (xy 316.798433 0.685098)
			(xy 316.829144 0.634595) (xy 316.852693 0.580381) (xy 316.868639 0.523466) (xy 316.876688 0.46491)
			(xy 316.877192 0.435356) (xy 316.877192 -0.428244) (xy 316.876688 -0.457798) (xy 316.868639 -0.516354)
			(xy 316.852693 -0.573269) (xy 316.829144 -0.627483) (xy 316.798433 -0.677986) (xy 316.761131 -0.723836)
			(xy 316.717934 -0.764179) (xy 316.669645 -0.798265) (xy 316.617165 -0.825458) (xy 316.56147 -0.845252)
			(xy 316.503599 -0.857278) (xy 316.44463 -0.861312) (xy 316.385661 -0.857278) (xy 316.32779 -0.845252)
			(xy 316.272095 -0.825458) (xy 316.219615 -0.798265) (xy 316.171326 -0.764179) (xy 316.128129 -0.723836)
			(xy 316.090827 -0.677986) (xy 316.060116 -0.627483) (xy 316.036567 -0.573269) (xy 316.020621 -0.516354)
			(xy 316.012572 -0.457798) (xy 316.012068 -0.428244) (xy 312.478344 -0.428244) (xy 312.534431 -0.456172)
			(xy 312.607337 -0.501313) (xy 312.675766 -0.552989) (xy 312.739136 -0.610758) (xy 312.796905 -0.674128)
			(xy 312.848581 -0.742557) (xy 312.893722 -0.815463) (xy 312.931944 -0.892223) (xy 312.96292 -0.972182)
			(xy 312.986387 -1.054658) (xy 313.002143 -1.138948) (xy 313.010055 -1.224331) (xy 313.01055 -1.267206)
			(xy 313.010055 -1.310081) (xy 317.505321 -1.310081) (xy 317.505321 -1.224331) (xy 317.513233 -1.138948)
			(xy 317.528989 -1.054658) (xy 317.552456 -0.972182) (xy 317.583432 -0.892223) (xy 317.621654 -0.815463)
			(xy 317.666795 -0.742557) (xy 317.718471 -0.674128) (xy 317.77624 -0.610758) (xy 317.83961 -0.552989)
			(xy 317.908039 -0.501313) (xy 317.980945 -0.456172) (xy 318.057705 -0.41795) (xy 318.137664 -0.386974)
			(xy 318.22014 -0.363507) (xy 318.30443 -0.347751) (xy 318.389813 -0.339839) (xy 318.475563 -0.339839)
			(xy 318.560946 -0.347751) (xy 318.645236 -0.363507) (xy 318.727712 -0.386974) (xy 318.807671 -0.41795)
			(xy 318.884431 -0.456172) (xy 318.957337 -0.501313) (xy 319.025766 -0.552989) (xy 319.089136 -0.610758)
			(xy 319.146905 -0.674128) (xy 319.198581 -0.742557) (xy 319.243722 -0.815463) (xy 319.281944 -0.892223)
			(xy 319.31292 -0.972182) (xy 319.336387 -1.054658) (xy 319.352143 -1.138948) (xy 319.360055 -1.224331)
			(xy 319.36055 -1.267206) (xy 319.360055 -1.310081) (xy 361.894107 -1.310081) (xy 361.894107 -1.224331)
			(xy 361.902019 -1.138948) (xy 361.917775 -1.054658) (xy 361.941242 -0.972182) (xy 361.972218 -0.892223)
			(xy 362.01044 -0.815463) (xy 362.055581 -0.742557) (xy 362.107257 -0.674128) (xy 362.165026 -0.610758)
			(xy 362.228396 -0.552989) (xy 362.296825 -0.501313) (xy 362.369731 -0.456172) (xy 362.446491 -0.41795)
			(xy 362.52645 -0.386974) (xy 362.608926 -0.363507) (xy 362.693216 -0.347751) (xy 362.778599 -0.339839)
			(xy 362.864349 -0.339839) (xy 362.949732 -0.347751) (xy 363.034022 -0.363507) (xy 363.116498 -0.386974)
			(xy 363.196457 -0.41795) (xy 363.21713 -0.428244) (xy 364.379764 -0.428244) (xy 364.379764 0.435356)
			(xy 364.380268 0.464892) (xy 364.388312 0.523414) (xy 364.404249 0.580296) (xy 364.427784 0.634478)
			(xy 364.458477 0.684951) (xy 364.495757 0.730774) (xy 364.538929 0.771094) (xy 364.587189 0.80516)
			(xy 364.639639 0.832337) (xy 364.6953 0.852119) (xy 364.753137 0.864138) (xy 364.812072 0.868169)
			(xy 364.871007 0.864138) (xy 364.928844 0.852119) (xy 364.984505 0.832337) (xy 365.036955 0.80516)
			(xy 365.085215 0.771094) (xy 365.128387 0.730774) (xy 365.165667 0.684951) (xy 365.19636 0.634478)
			(xy 365.219895 0.580296) (xy 365.235832 0.523414) (xy 365.243876 0.464892) (xy 365.24438 0.435356)
			(xy 365.24438 -0.428244) (xy 365.243876 -0.45778) (xy 365.235832 -0.516302) (xy 365.219895 -0.573184)
			(xy 365.19636 -0.627366) (xy 365.165667 -0.677839) (xy 365.128387 -0.723662) (xy 365.085215 -0.763982)
			(xy 365.036955 -0.798048) (xy 364.984505 -0.825225) (xy 364.928844 -0.845007) (xy 364.871007 -0.857026)
			(xy 364.812072 -0.861057) (xy 364.753137 -0.857026) (xy 364.6953 -0.845007) (xy 364.639639 -0.825225)
			(xy 364.587189 -0.798048) (xy 364.538929 -0.763982) (xy 364.495757 -0.723662) (xy 364.458477 -0.677839)
			(xy 364.427784 -0.627366) (xy 364.404249 -0.573184) (xy 364.388312 -0.516302) (xy 364.380268 -0.45778)
			(xy 364.379764 -0.428244) (xy 363.21713 -0.428244) (xy 363.273217 -0.456172) (xy 363.346123 -0.501313)
			(xy 363.414552 -0.552989) (xy 363.477922 -0.610758) (xy 363.535691 -0.674128) (xy 363.587367 -0.742557)
			(xy 363.632508 -0.815463) (xy 363.67073 -0.892223) (xy 363.701706 -0.972182) (xy 363.725173 -1.054658)
			(xy 363.740929 -1.138948) (xy 363.748841 -1.224331) (xy 363.749336 -1.267206) (xy 363.748841 -1.310081)
			(xy 368.244107 -1.310081) (xy 368.244107 -1.224331) (xy 368.252019 -1.138948) (xy 368.267775 -1.054658)
			(xy 368.291242 -0.972182) (xy 368.322218 -0.892223) (xy 368.36044 -0.815463) (xy 368.405581 -0.742557)
			(xy 368.457257 -0.674128) (xy 368.515026 -0.610758) (xy 368.578396 -0.552989) (xy 368.646825 -0.501313)
			(xy 368.719731 -0.456172) (xy 368.796491 -0.41795) (xy 368.87645 -0.386974) (xy 368.958926 -0.363507)
			(xy 369.043216 -0.347751) (xy 369.128599 -0.339839) (xy 369.214349 -0.339839) (xy 369.299732 -0.347751)
			(xy 369.384022 -0.363507) (xy 369.466498 -0.386974) (xy 369.546457 -0.41795) (xy 369.623217 -0.456172)
			(xy 369.696123 -0.501313) (xy 369.764552 -0.552989) (xy 369.827922 -0.610758) (xy 369.885691 -0.674128)
			(xy 369.937367 -0.742557) (xy 369.982508 -0.815463) (xy 370.02073 -0.892223) (xy 370.051706 -0.972182)
			(xy 370.075173 -1.054658) (xy 370.090929 -1.138948) (xy 370.098841 -1.224331) (xy 370.099336 -1.267206)
			(xy 370.098841 -1.310081) (xy 370.090929 -1.395464) (xy 370.075173 -1.479754) (xy 370.051706 -1.56223)
			(xy 370.02073 -1.642189) (xy 369.982508 -1.718949) (xy 369.937367 -1.791855) (xy 369.885691 -1.860284)
			(xy 369.827922 -1.923654) (xy 369.764552 -1.981423) (xy 369.696123 -2.033099) (xy 369.623217 -2.07824)
			(xy 369.546457 -2.116462) (xy 369.466498 -2.147438) (xy 369.384022 -2.170905) (xy 369.299732 -2.186661)
			(xy 369.214349 -2.194573) (xy 369.128599 -2.194573) (xy 369.043216 -2.186661) (xy 368.958926 -2.170905)
			(xy 368.87645 -2.147438) (xy 368.796491 -2.116462) (xy 368.719731 -2.07824) (xy 368.646825 -2.033099)
			(xy 368.578396 -1.981423) (xy 368.515026 -1.923654) (xy 368.457257 -1.860284) (xy 368.405581 -1.791855)
			(xy 368.36044 -1.718949) (xy 368.322218 -1.642189) (xy 368.291242 -1.56223) (xy 368.267775 -1.479754)
			(xy 368.252019 -1.395464) (xy 368.244107 -1.310081) (xy 363.748841 -1.310081) (xy 363.740929 -1.395464)
			(xy 363.725173 -1.479754) (xy 363.701706 -1.56223) (xy 363.67073 -1.642189) (xy 363.632508 -1.718949)
			(xy 363.587367 -1.791855) (xy 363.535691 -1.860284) (xy 363.477922 -1.923654) (xy 363.414552 -1.981423)
			(xy 363.346123 -2.033099) (xy 363.273217 -2.07824) (xy 363.196457 -2.116462) (xy 363.116498 -2.147438)
			(xy 363.034022 -2.170905) (xy 362.949732 -2.186661) (xy 362.864349 -2.194573) (xy 362.778599 -2.194573)
			(xy 362.693216 -2.186661) (xy 362.608926 -2.170905) (xy 362.52645 -2.147438) (xy 362.446491 -2.116462)
			(xy 362.369731 -2.07824) (xy 362.296825 -2.033099) (xy 362.228396 -1.981423) (xy 362.165026 -1.923654)
			(xy 362.107257 -1.860284) (xy 362.055581 -1.791855) (xy 362.01044 -1.718949) (xy 361.972218 -1.642189)
			(xy 361.941242 -1.56223) (xy 361.917775 -1.479754) (xy 361.902019 -1.395464) (xy 361.894107 -1.310081)
			(xy 319.360055 -1.310081) (xy 319.352143 -1.395464) (xy 319.336387 -1.479754) (xy 319.31292 -1.56223)
			(xy 319.281944 -1.642189) (xy 319.243722 -1.718949) (xy 319.198581 -1.791855) (xy 319.146905 -1.860284)
			(xy 319.089136 -1.923654) (xy 319.025766 -1.981423) (xy 318.957337 -2.033099) (xy 318.884431 -2.07824)
			(xy 318.807671 -2.116462) (xy 318.727712 -2.147438) (xy 318.645236 -2.170905) (xy 318.560946 -2.186661)
			(xy 318.475563 -2.194573) (xy 318.389813 -2.194573) (xy 318.30443 -2.186661) (xy 318.22014 -2.170905)
			(xy 318.137664 -2.147438) (xy 318.057705 -2.116462) (xy 317.980945 -2.07824) (xy 317.908039 -2.033099)
			(xy 317.83961 -1.981423) (xy 317.77624 -1.923654) (xy 317.718471 -1.860284) (xy 317.666795 -1.791855)
			(xy 317.621654 -1.718949) (xy 317.583432 -1.642189) (xy 317.552456 -1.56223) (xy 317.528989 -1.479754)
			(xy 317.513233 -1.395464) (xy 317.505321 -1.310081) (xy 313.010055 -1.310081) (xy 313.002143 -1.395464)
			(xy 312.986387 -1.479754) (xy 312.96292 -1.56223) (xy 312.931944 -1.642189) (xy 312.893722 -1.718949)
			(xy 312.848581 -1.791855) (xy 312.796905 -1.860284) (xy 312.739136 -1.923654) (xy 312.675766 -1.981423)
			(xy 312.607337 -2.033099) (xy 312.534431 -2.07824) (xy 312.457671 -2.116462) (xy 312.377712 -2.147438)
			(xy 312.295236 -2.170905) (xy 312.210946 -2.186661) (xy 312.125563 -2.194573) (xy 312.039813 -2.194573)
			(xy 311.95443 -2.186661) (xy 311.87014 -2.170905) (xy 311.787664 -2.147438) (xy 311.707705 -2.116462)
			(xy 311.630945 -2.07824) (xy 311.558039 -2.033099) (xy 311.48961 -1.981423) (xy 311.42624 -1.923654)
			(xy 311.368471 -1.860284) (xy 311.316795 -1.791855) (xy 311.271654 -1.718949) (xy 311.233432 -1.642189)
			(xy 311.202456 -1.56223) (xy 311.178989 -1.479754) (xy 311.163233 -1.395464) (xy 311.155321 -1.310081)
			(xy 304.348655 -1.310081) (xy 304.340743 -1.395464) (xy 304.324987 -1.479754) (xy 304.30152 -1.56223)
			(xy 304.270544 -1.642189) (xy 304.232322 -1.718949) (xy 304.187181 -1.791855) (xy 304.135505 -1.860284)
			(xy 304.077736 -1.923654) (xy 304.014366 -1.981423) (xy 303.945937 -2.033099) (xy 303.873031 -2.07824)
			(xy 303.796271 -2.116462) (xy 303.716312 -2.147438) (xy 303.633836 -2.170905) (xy 303.549546 -2.186661)
			(xy 303.464163 -2.194573) (xy 303.378413 -2.194573) (xy 303.29303 -2.186661) (xy 303.20874 -2.170905)
			(xy 303.126264 -2.147438) (xy 303.046305 -2.116462) (xy 302.969545 -2.07824) (xy 302.896639 -2.033099)
			(xy 302.82821 -1.981423) (xy 302.76484 -1.923654) (xy 302.707071 -1.860284) (xy 302.655395 -1.791855)
			(xy 302.610254 -1.718949) (xy 302.572032 -1.642189) (xy 302.541056 -1.56223) (xy 302.517589 -1.479754)
			(xy 302.501833 -1.395464) (xy 302.493921 -1.310081) (xy 297.998655 -1.310081) (xy 297.990743 -1.395464)
			(xy 297.974987 -1.479754) (xy 297.95152 -1.56223) (xy 297.920544 -1.642189) (xy 297.882322 -1.718949)
			(xy 297.837181 -1.791855) (xy 297.785505 -1.860284) (xy 297.727736 -1.923654) (xy 297.664366 -1.981423)
			(xy 297.595937 -2.033099) (xy 297.523031 -2.07824) (xy 297.446271 -2.116462) (xy 297.366312 -2.147438)
			(xy 297.283836 -2.170905) (xy 297.199546 -2.186661) (xy 297.114163 -2.194573) (xy 297.028413 -2.194573)
			(xy 296.94303 -2.186661) (xy 296.85874 -2.170905) (xy 296.776264 -2.147438) (xy 296.696305 -2.116462)
			(xy 296.619545 -2.07824) (xy 296.546639 -2.033099) (xy 296.47821 -1.981423) (xy 296.41484 -1.923654)
			(xy 296.357071 -1.860284) (xy 296.305395 -1.791855) (xy 296.260254 -1.718949) (xy 296.222032 -1.642189)
			(xy 296.191056 -1.56223) (xy 296.167589 -1.479754) (xy 296.151833 -1.395464) (xy 296.143921 -1.310081)
			(xy 216.865975 -1.310081) (xy 216.858063 -1.395464) (xy 216.842307 -1.479754) (xy 216.81884 -1.56223)
			(xy 216.787864 -1.642189) (xy 216.749642 -1.718949) (xy 216.704501 -1.791855) (xy 216.652825 -1.860284)
			(xy 216.595056 -1.923654) (xy 216.531686 -1.981423) (xy 216.463257 -2.033099) (xy 216.390351 -2.07824)
			(xy 216.313591 -2.116462) (xy 216.233632 -2.147438) (xy 216.151156 -2.170905) (xy 216.066866 -2.186661)
			(xy 215.981483 -2.194573) (xy 215.895733 -2.194573) (xy 215.81035 -2.186661) (xy 215.72606 -2.170905)
			(xy 215.643584 -2.147438) (xy 215.563625 -2.116462) (xy 215.486865 -2.07824) (xy 215.413959 -2.033099)
			(xy 215.34553 -1.981423) (xy 215.28216 -1.923654) (xy 215.224391 -1.860284) (xy 215.172715 -1.791855)
			(xy 215.127574 -1.718949) (xy 215.089352 -1.642189) (xy 215.058376 -1.56223) (xy 215.034909 -1.479754)
			(xy 215.019153 -1.395464) (xy 215.011241 -1.310081) (xy 210.515975 -1.310081) (xy 210.508063 -1.395464)
			(xy 210.492307 -1.479754) (xy 210.46884 -1.56223) (xy 210.437864 -1.642189) (xy 210.399642 -1.718949)
			(xy 210.354501 -1.791855) (xy 210.302825 -1.860284) (xy 210.245056 -1.923654) (xy 210.181686 -1.981423)
			(xy 210.113257 -2.033099) (xy 210.040351 -2.07824) (xy 209.963591 -2.116462) (xy 209.883632 -2.147438)
			(xy 209.801156 -2.170905) (xy 209.716866 -2.186661) (xy 209.631483 -2.194573) (xy 209.545733 -2.194573)
			(xy 209.46035 -2.186661) (xy 209.37606 -2.170905) (xy 209.293584 -2.147438) (xy 209.213625 -2.116462)
			(xy 209.136865 -2.07824) (xy 209.063959 -2.033099) (xy 208.99553 -1.981423) (xy 208.93216 -1.923654)
			(xy 208.874391 -1.860284) (xy 208.822715 -1.791855) (xy 208.777574 -1.718949) (xy 208.739352 -1.642189)
			(xy 208.708376 -1.56223) (xy 208.684909 -1.479754) (xy 208.669153 -1.395464) (xy 208.661241 -1.310081)
			(xy 84.210906 -1.310081) (xy 84.210906 -7.78002) (xy 84.211428 -7.835789) (xy 84.219765 -7.947014)
			(xy 84.23639 -8.057306) (xy 84.26121 -8.166046) (xy 84.294088 -8.272628) (xy 84.334838 -8.376455)
			(xy 84.383233 -8.476947) (xy 84.439002 -8.573541) (xy 84.501834 -8.665697) (xy 84.571376 -8.7529)
			(xy 84.647241 -8.834663) (xy 84.729004 -8.910527) (xy 84.816208 -8.98007) (xy 84.908364 -9.042901)
			(xy 85.004959 -9.09867) (xy 85.10545 -9.147065) (xy 85.209277 -9.187814) (xy 85.315859 -9.220691)
			(xy 85.4246 -9.245511) (xy 85.534892 -9.262136) (xy 85.646117 -9.270472) (xy 85.701886 -9.271) (xy 122.102118 -9.271)
			(xy 122.157887 -9.270478) (xy 122.269113 -9.262141) (xy 122.379404 -9.245517) (xy 122.488145 -9.220696)
			(xy 122.594728 -9.187819) (xy 122.698555 -9.147069) (xy 122.799047 -9.098674) (xy 122.895641 -9.042905)
			(xy 122.987798 -8.980073) (xy 123.075001 -8.910531) (xy 123.156764 -8.834666) (xy 123.232629 -8.752903)
			(xy 123.302172 -8.665699) (xy 123.365004 -8.573543) (xy 123.420773 -8.476948) (xy 123.469168 -8.376457)
			(xy 123.509918 -8.27263) (xy 123.542796 -8.166047) (xy 123.567616 -8.057306) (xy 123.584241 -7.947015)
			(xy 123.592578 -7.835789) (xy 123.593098 -7.78002) (xy 123.593098 -4.879848) (xy 123.593581 -4.809465)
			(xy 123.601472 -4.66892) (xy 123.61723 -4.529038) (xy 123.640807 -4.39026) (xy 123.672128 -4.253022)
			(xy 123.711095 -4.117757) (xy 123.757586 -3.984889) (xy 123.811453 -3.854837) (xy 123.872528 -3.72801)
			(xy 123.940618 -3.604807) (xy 124.015509 -3.485616) (xy 124.096965 -3.370811) (xy 124.184731 -3.260755)
			(xy 124.278529 -3.155793) (xy 124.378065 -3.056255) (xy 124.483026 -2.962455) (xy 124.593081 -2.874688)
			(xy 124.707884 -2.79323) (xy 124.827074 -2.718337) (xy 124.950276 -2.650245) (xy 125.077102 -2.589169)
			(xy 125.207153 -2.535299) (xy 125.340021 -2.488807) (xy 125.475285 -2.449838) (xy 125.612523 -2.418514)
			(xy 125.7513 -2.394935) (xy 125.891182 -2.379175) (xy 126.031727 -2.371282) (xy 126.10211 -2.370836)
			(xy 194.701922 -2.370836) (xy 194.772304 -2.371321) (xy 194.912845 -2.379215) (xy 195.052723 -2.394977)
			(xy 195.191497 -2.418557) (xy 195.328731 -2.449881) (xy 195.463992 -2.488851) (xy 195.596856 -2.535344)
			(xy 195.726904 -2.589213) (xy 195.853726 -2.650289) (xy 195.976925 -2.71838) (xy 196.096111 -2.793273)
			(xy 196.210911 -2.87473) (xy 196.320963 -2.962495) (xy 196.425921 -3.056294) (xy 196.525454 -3.15583)
			(xy 196.61925 -3.26079) (xy 196.707012 -3.370845) (xy 196.788466 -3.485647) (xy 196.863355 -3.604836)
			(xy 196.931443 -3.728036) (xy 196.990215 -3.850081) (xy 208.661241 -3.850081) (xy 208.661241 -3.764331)
			(xy 208.669153 -3.678948) (xy 208.684909 -3.594658) (xy 208.708376 -3.512182) (xy 208.739352 -3.432223)
			(xy 208.777574 -3.355463) (xy 208.822715 -3.282557) (xy 208.874391 -3.214128) (xy 208.93216 -3.150758)
			(xy 208.99553 -3.092989) (xy 209.063959 -3.041313) (xy 209.136865 -2.996172) (xy 209.213625 -2.95795)
			(xy 209.293584 -2.926974) (xy 209.37606 -2.903507) (xy 209.46035 -2.887751) (xy 209.545733 -2.879839)
			(xy 209.631483 -2.879839) (xy 209.716866 -2.887751) (xy 209.801156 -2.903507) (xy 209.883632 -2.926974)
			(xy 209.963591 -2.95795) (xy 209.984264 -2.968244) (xy 213.517988 -2.968244) (xy 213.517988 -2.104644)
			(xy 213.518492 -2.07509) (xy 213.526541 -2.016534) (xy 213.542487 -1.959619) (xy 213.566036 -1.905405)
			(xy 213.596747 -1.854902) (xy 213.634049 -1.809052) (xy 213.677246 -1.768709) (xy 213.725535 -1.734623)
			(xy 213.778015 -1.70743) (xy 213.83371 -1.687636) (xy 213.891581 -1.67561) (xy 213.95055 -1.671577)
			(xy 214.009519 -1.67561) (xy 214.06739 -1.687636) (xy 214.123085 -1.70743) (xy 214.175565 -1.734623)
			(xy 214.223854 -1.768709) (xy 214.267051 -1.809052) (xy 214.304353 -1.854902) (xy 214.335064 -1.905405)
			(xy 214.358613 -1.959619) (xy 214.374559 -2.016534) (xy 214.382608 -2.07509) (xy 214.383112 -2.104644)
			(xy 214.383112 -2.968244) (xy 214.382608 -2.997798) (xy 214.374559 -3.056354) (xy 214.358613 -3.113269)
			(xy 214.335064 -3.167483) (xy 214.304353 -3.217986) (xy 214.267051 -3.263836) (xy 214.223854 -3.304179)
			(xy 214.175565 -3.338265) (xy 214.123085 -3.365458) (xy 214.06739 -3.385252) (xy 214.009519 -3.397278)
			(xy 213.95055 -3.401312) (xy 213.891581 -3.397278) (xy 213.83371 -3.385252) (xy 213.778015 -3.365458)
			(xy 213.725535 -3.338265) (xy 213.677246 -3.304179) (xy 213.634049 -3.263836) (xy 213.596747 -3.217986)
			(xy 213.566036 -3.167483) (xy 213.542487 -3.113269) (xy 213.526541 -3.056354) (xy 213.518492 -2.997798)
			(xy 213.517988 -2.968244) (xy 209.984264 -2.968244) (xy 210.040351 -2.996172) (xy 210.113257 -3.041313)
			(xy 210.181686 -3.092989) (xy 210.245056 -3.150758) (xy 210.302825 -3.214128) (xy 210.354501 -3.282557)
			(xy 210.399642 -3.355463) (xy 210.437864 -3.432223) (xy 210.46884 -3.512182) (xy 210.492307 -3.594658)
			(xy 210.508063 -3.678948) (xy 210.515975 -3.764331) (xy 210.51647 -3.807206) (xy 210.515975 -3.850081)
			(xy 215.011241 -3.850081) (xy 215.011241 -3.764331) (xy 215.019153 -3.678948) (xy 215.034909 -3.594658)
			(xy 215.058376 -3.512182) (xy 215.089352 -3.432223) (xy 215.127574 -3.355463) (xy 215.172715 -3.282557)
			(xy 215.224391 -3.214128) (xy 215.28216 -3.150758) (xy 215.34553 -3.092989) (xy 215.413959 -3.041313)
			(xy 215.486865 -2.996172) (xy 215.563625 -2.95795) (xy 215.643584 -2.926974) (xy 215.72606 -2.903507)
			(xy 215.81035 -2.887751) (xy 215.895733 -2.879839) (xy 215.981483 -2.879839) (xy 216.066866 -2.887751)
			(xy 216.151156 -2.903507) (xy 216.233632 -2.926974) (xy 216.313591 -2.95795) (xy 216.390351 -2.996172)
			(xy 216.463257 -3.041313) (xy 216.531686 -3.092989) (xy 216.595056 -3.150758) (xy 216.652825 -3.214128)
			(xy 216.704501 -3.282557) (xy 216.749642 -3.355463) (xy 216.787864 -3.432223) (xy 216.81884 -3.512182)
			(xy 216.842307 -3.594658) (xy 216.858063 -3.678948) (xy 216.865975 -3.764331) (xy 216.86647 -3.807206)
			(xy 216.865975 -3.850081) (xy 296.143921 -3.850081) (xy 296.143921 -3.764331) (xy 296.151833 -3.678948)
			(xy 296.167589 -3.594658) (xy 296.191056 -3.512182) (xy 296.222032 -3.432223) (xy 296.260254 -3.355463)
			(xy 296.305395 -3.282557) (xy 296.357071 -3.214128) (xy 296.41484 -3.150758) (xy 296.47821 -3.092989)
			(xy 296.546639 -3.041313) (xy 296.619545 -2.996172) (xy 296.696305 -2.95795) (xy 296.776264 -2.926974)
			(xy 296.85874 -2.903507) (xy 296.94303 -2.887751) (xy 297.028413 -2.879839) (xy 297.114163 -2.879839)
			(xy 297.199546 -2.887751) (xy 297.283836 -2.903507) (xy 297.366312 -2.926974) (xy 297.446271 -2.95795)
			(xy 297.466944 -2.968244) (xy 298.629324 -2.968244) (xy 298.629324 -2.104644) (xy 298.629828 -2.07509)
			(xy 298.637877 -2.016534) (xy 298.653823 -1.959619) (xy 298.677372 -1.905405) (xy 298.708083 -1.854902)
			(xy 298.745385 -1.809052) (xy 298.788582 -1.768709) (xy 298.836871 -1.734623) (xy 298.889351 -1.70743)
			(xy 298.945046 -1.687636) (xy 299.002917 -1.67561) (xy 299.061886 -1.671577) (xy 299.120855 -1.67561)
			(xy 299.178726 -1.687636) (xy 299.234421 -1.70743) (xy 299.286901 -1.734623) (xy 299.33519 -1.768709)
			(xy 299.378387 -1.809052) (xy 299.415689 -1.854902) (xy 299.4464 -1.905405) (xy 299.469949 -1.959619)
			(xy 299.485895 -2.016534) (xy 299.493944 -2.07509) (xy 299.494448 -2.104644) (xy 299.494448 -2.968244)
			(xy 299.493944 -2.997798) (xy 299.485895 -3.056354) (xy 299.469949 -3.113269) (xy 299.4464 -3.167483)
			(xy 299.415689 -3.217986) (xy 299.378387 -3.263836) (xy 299.33519 -3.304179) (xy 299.286901 -3.338265)
			(xy 299.234421 -3.365458) (xy 299.178726 -3.385252) (xy 299.120855 -3.397278) (xy 299.061886 -3.401312)
			(xy 299.002917 -3.397278) (xy 298.945046 -3.385252) (xy 298.889351 -3.365458) (xy 298.836871 -3.338265)
			(xy 298.788582 -3.304179) (xy 298.745385 -3.263836) (xy 298.708083 -3.217986) (xy 298.677372 -3.167483)
			(xy 298.653823 -3.113269) (xy 298.637877 -3.056354) (xy 298.629828 -2.997798) (xy 298.629324 -2.968244)
			(xy 297.466944 -2.968244) (xy 297.523031 -2.996172) (xy 297.595937 -3.041313) (xy 297.664366 -3.092989)
			(xy 297.727736 -3.150758) (xy 297.785505 -3.214128) (xy 297.837181 -3.282557) (xy 297.882322 -3.355463)
			(xy 297.920544 -3.432223) (xy 297.95152 -3.512182) (xy 297.974987 -3.594658) (xy 297.990743 -3.678948)
			(xy 297.998655 -3.764331) (xy 297.99915 -3.807206) (xy 297.998655 -3.850081) (xy 302.493921 -3.850081)
			(xy 302.493921 -3.764331) (xy 302.501833 -3.678948) (xy 302.517589 -3.594658) (xy 302.541056 -3.512182)
			(xy 302.572032 -3.432223) (xy 302.610254 -3.355463) (xy 302.655395 -3.282557) (xy 302.707071 -3.214128)
			(xy 302.76484 -3.150758) (xy 302.82821 -3.092989) (xy 302.896639 -3.041313) (xy 302.969545 -2.996172)
			(xy 303.046305 -2.95795) (xy 303.126264 -2.926974) (xy 303.20874 -2.903507) (xy 303.29303 -2.887751)
			(xy 303.378413 -2.879839) (xy 303.464163 -2.879839) (xy 303.549546 -2.887751) (xy 303.633836 -2.903507)
			(xy 303.716312 -2.926974) (xy 303.796271 -2.95795) (xy 303.873031 -2.996172) (xy 303.945937 -3.041313)
			(xy 304.014366 -3.092989) (xy 304.077736 -3.150758) (xy 304.135505 -3.214128) (xy 304.187181 -3.282557)
			(xy 304.232322 -3.355463) (xy 304.270544 -3.432223) (xy 304.30152 -3.512182) (xy 304.324987 -3.594658)
			(xy 304.340743 -3.678948) (xy 304.348655 -3.764331) (xy 304.34915 -3.807206) (xy 304.348655 -3.850081)
			(xy 311.155321 -3.850081) (xy 311.155321 -3.764331) (xy 311.163233 -3.678948) (xy 311.178989 -3.594658)
			(xy 311.202456 -3.512182) (xy 311.233432 -3.432223) (xy 311.271654 -3.355463) (xy 311.316795 -3.282557)
			(xy 311.368471 -3.214128) (xy 311.42624 -3.150758) (xy 311.48961 -3.092989) (xy 311.558039 -3.041313)
			(xy 311.630945 -2.996172) (xy 311.707705 -2.95795) (xy 311.787664 -2.926974) (xy 311.87014 -2.903507)
			(xy 311.95443 -2.887751) (xy 312.039813 -2.879839) (xy 312.125563 -2.879839) (xy 312.210946 -2.887751)
			(xy 312.295236 -2.903507) (xy 312.377712 -2.926974) (xy 312.457671 -2.95795) (xy 312.478344 -2.968244)
			(xy 316.012068 -2.968244) (xy 316.012068 -2.104644) (xy 316.012572 -2.07509) (xy 316.020621 -2.016534)
			(xy 316.036567 -1.959619) (xy 316.060116 -1.905405) (xy 316.090827 -1.854902) (xy 316.128129 -1.809052)
			(xy 316.171326 -1.768709) (xy 316.219615 -1.734623) (xy 316.272095 -1.70743) (xy 316.32779 -1.687636)
			(xy 316.385661 -1.67561) (xy 316.44463 -1.671577) (xy 316.503599 -1.67561) (xy 316.56147 -1.687636)
			(xy 316.617165 -1.70743) (xy 316.669645 -1.734623) (xy 316.717934 -1.768709) (xy 316.761131 -1.809052)
			(xy 316.798433 -1.854902) (xy 316.829144 -1.905405) (xy 316.852693 -1.959619) (xy 316.868639 -2.016534)
			(xy 316.876688 -2.07509) (xy 316.877192 -2.104644) (xy 316.877192 -2.968244) (xy 316.876688 -2.997798)
			(xy 316.868639 -3.056354) (xy 316.852693 -3.113269) (xy 316.829144 -3.167483) (xy 316.798433 -3.217986)
			(xy 316.761131 -3.263836) (xy 316.717934 -3.304179) (xy 316.669645 -3.338265) (xy 316.617165 -3.365458)
			(xy 316.56147 -3.385252) (xy 316.503599 -3.397278) (xy 316.44463 -3.401312) (xy 316.385661 -3.397278)
			(xy 316.32779 -3.385252) (xy 316.272095 -3.365458) (xy 316.219615 -3.338265) (xy 316.171326 -3.304179)
			(xy 316.128129 -3.263836) (xy 316.090827 -3.217986) (xy 316.060116 -3.167483) (xy 316.036567 -3.113269)
			(xy 316.020621 -3.056354) (xy 316.012572 -2.997798) (xy 316.012068 -2.968244) (xy 312.478344 -2.968244)
			(xy 312.534431 -2.996172) (xy 312.607337 -3.041313) (xy 312.675766 -3.092989) (xy 312.739136 -3.150758)
			(xy 312.796905 -3.214128) (xy 312.848581 -3.282557) (xy 312.893722 -3.355463) (xy 312.931944 -3.432223)
			(xy 312.96292 -3.512182) (xy 312.986387 -3.594658) (xy 313.002143 -3.678948) (xy 313.010055 -3.764331)
			(xy 313.01055 -3.807206) (xy 313.010055 -3.850081) (xy 317.505321 -3.850081) (xy 317.505321 -3.764331)
			(xy 317.513233 -3.678948) (xy 317.528989 -3.594658) (xy 317.552456 -3.512182) (xy 317.583432 -3.432223)
			(xy 317.621654 -3.355463) (xy 317.666795 -3.282557) (xy 317.718471 -3.214128) (xy 317.77624 -3.150758)
			(xy 317.83961 -3.092989) (xy 317.908039 -3.041313) (xy 317.980945 -2.996172) (xy 318.057705 -2.95795)
			(xy 318.137664 -2.926974) (xy 318.22014 -2.903507) (xy 318.30443 -2.887751) (xy 318.389813 -2.879839)
			(xy 318.475563 -2.879839) (xy 318.560946 -2.887751) (xy 318.645236 -2.903507) (xy 318.727712 -2.926974)
			(xy 318.807671 -2.95795) (xy 318.884431 -2.996172) (xy 318.957337 -3.041313) (xy 319.025766 -3.092989)
			(xy 319.089136 -3.150758) (xy 319.146905 -3.214128) (xy 319.198581 -3.282557) (xy 319.243722 -3.355463)
			(xy 319.281944 -3.432223) (xy 319.31292 -3.512182) (xy 319.336387 -3.594658) (xy 319.352143 -3.678948)
			(xy 319.360055 -3.764331) (xy 319.36055 -3.807206) (xy 319.360055 -3.850081) (xy 361.894107 -3.850081)
			(xy 361.894107 -3.764331) (xy 361.902019 -3.678948) (xy 361.917775 -3.594658) (xy 361.941242 -3.512182)
			(xy 361.972218 -3.432223) (xy 362.01044 -3.355463) (xy 362.055581 -3.282557) (xy 362.107257 -3.214128)
			(xy 362.165026 -3.150758) (xy 362.228396 -3.092989) (xy 362.296825 -3.041313) (xy 362.369731 -2.996172)
			(xy 362.446491 -2.95795) (xy 362.52645 -2.926974) (xy 362.608926 -2.903507) (xy 362.693216 -2.887751)
			(xy 362.778599 -2.879839) (xy 362.864349 -2.879839) (xy 362.949732 -2.887751) (xy 363.034022 -2.903507)
			(xy 363.116498 -2.926974) (xy 363.196457 -2.95795) (xy 363.21713 -2.968244) (xy 364.379764 -2.968244)
			(xy 364.379764 -2.104644) (xy 364.380268 -2.075108) (xy 364.388312 -2.016586) (xy 364.404249 -1.959704)
			(xy 364.427784 -1.905522) (xy 364.458477 -1.855049) (xy 364.495757 -1.809226) (xy 364.538929 -1.768906)
			(xy 364.587189 -1.73484) (xy 364.639639 -1.707663) (xy 364.6953 -1.687881) (xy 364.753137 -1.675862)
			(xy 364.812072 -1.671831) (xy 364.871007 -1.675862) (xy 364.928844 -1.687881) (xy 364.984505 -1.707663)
			(xy 365.036955 -1.73484) (xy 365.085215 -1.768906) (xy 365.128387 -1.809226) (xy 365.165667 -1.855049)
			(xy 365.19636 -1.905522) (xy 365.219895 -1.959704) (xy 365.235832 -2.016586) (xy 365.243876 -2.075108)
			(xy 365.24438 -2.104644) (xy 365.24438 -2.968244) (xy 365.243876 -2.99778) (xy 365.235832 -3.056302)
			(xy 365.219895 -3.113184) (xy 365.19636 -3.167366) (xy 365.165667 -3.217839) (xy 365.128387 -3.263662)
			(xy 365.085215 -3.303982) (xy 365.036955 -3.338048) (xy 364.984505 -3.365225) (xy 364.928844 -3.385007)
			(xy 364.871007 -3.397026) (xy 364.812072 -3.401057) (xy 364.753137 -3.397026) (xy 364.6953 -3.385007)
			(xy 364.639639 -3.365225) (xy 364.587189 -3.338048) (xy 364.538929 -3.303982) (xy 364.495757 -3.263662)
			(xy 364.458477 -3.217839) (xy 364.427784 -3.167366) (xy 364.404249 -3.113184) (xy 364.388312 -3.056302)
			(xy 364.380268 -2.99778) (xy 364.379764 -2.968244) (xy 363.21713 -2.968244) (xy 363.273217 -2.996172)
			(xy 363.346123 -3.041313) (xy 363.414552 -3.092989) (xy 363.477922 -3.150758) (xy 363.535691 -3.214128)
			(xy 363.587367 -3.282557) (xy 363.632508 -3.355463) (xy 363.67073 -3.432223) (xy 363.701706 -3.512182)
			(xy 363.725173 -3.594658) (xy 363.740929 -3.678948) (xy 363.748841 -3.764331) (xy 363.749336 -3.807206)
			(xy 363.748841 -3.850081) (xy 368.244107 -3.850081) (xy 368.244107 -3.764331) (xy 368.252019 -3.678948)
			(xy 368.267775 -3.594658) (xy 368.291242 -3.512182) (xy 368.322218 -3.432223) (xy 368.36044 -3.355463)
			(xy 368.405581 -3.282557) (xy 368.457257 -3.214128) (xy 368.515026 -3.150758) (xy 368.578396 -3.092989)
			(xy 368.646825 -3.041313) (xy 368.719731 -2.996172) (xy 368.796491 -2.95795) (xy 368.87645 -2.926974)
			(xy 368.958926 -2.903507) (xy 369.043216 -2.887751) (xy 369.128599 -2.879839) (xy 369.214349 -2.879839)
			(xy 369.299732 -2.887751) (xy 369.384022 -2.903507) (xy 369.466498 -2.926974) (xy 369.546457 -2.95795)
			(xy 369.623217 -2.996172) (xy 369.696123 -3.041313) (xy 369.764552 -3.092989) (xy 369.827922 -3.150758)
			(xy 369.885691 -3.214128) (xy 369.937367 -3.282557) (xy 369.982508 -3.355463) (xy 370.02073 -3.432223)
			(xy 370.051706 -3.512182) (xy 370.075173 -3.594658) (xy 370.090929 -3.678948) (xy 370.098841 -3.764331)
			(xy 370.099336 -3.807206) (xy 370.098841 -3.850081) (xy 370.090929 -3.935464) (xy 370.075173 -4.019754)
			(xy 370.051706 -4.10223) (xy 370.02073 -4.182189) (xy 369.982508 -4.258949) (xy 369.937367 -4.331855)
			(xy 369.885691 -4.400284) (xy 369.827922 -4.463654) (xy 369.764552 -4.521423) (xy 369.696123 -4.573099)
			(xy 369.623217 -4.61824) (xy 369.546457 -4.656462) (xy 369.466498 -4.687438) (xy 369.384022 -4.710905)
			(xy 369.299732 -4.726661) (xy 369.214349 -4.734573) (xy 369.128599 -4.734573) (xy 369.043216 -4.726661)
			(xy 368.958926 -4.710905) (xy 368.87645 -4.687438) (xy 368.796491 -4.656462) (xy 368.719731 -4.61824)
			(xy 368.646825 -4.573099) (xy 368.578396 -4.521423) (xy 368.515026 -4.463654) (xy 368.457257 -4.400284)
			(xy 368.405581 -4.331855) (xy 368.36044 -4.258949) (xy 368.322218 -4.182189) (xy 368.291242 -4.10223)
			(xy 368.267775 -4.019754) (xy 368.252019 -3.935464) (xy 368.244107 -3.850081) (xy 363.748841 -3.850081)
			(xy 363.740929 -3.935464) (xy 363.725173 -4.019754) (xy 363.701706 -4.10223) (xy 363.67073 -4.182189)
			(xy 363.632508 -4.258949) (xy 363.587367 -4.331855) (xy 363.535691 -4.400284) (xy 363.477922 -4.463654)
			(xy 363.414552 -4.521423) (xy 363.346123 -4.573099) (xy 363.273217 -4.61824) (xy 363.196457 -4.656462)
			(xy 363.116498 -4.687438) (xy 363.034022 -4.710905) (xy 362.949732 -4.726661) (xy 362.864349 -4.734573)
			(xy 362.778599 -4.734573) (xy 362.693216 -4.726661) (xy 362.608926 -4.710905) (xy 362.52645 -4.687438)
			(xy 362.446491 -4.656462) (xy 362.369731 -4.61824) (xy 362.296825 -4.573099) (xy 362.228396 -4.521423)
			(xy 362.165026 -4.463654) (xy 362.107257 -4.400284) (xy 362.055581 -4.331855) (xy 362.01044 -4.258949)
			(xy 361.972218 -4.182189) (xy 361.941242 -4.10223) (xy 361.917775 -4.019754) (xy 361.902019 -3.935464)
			(xy 361.894107 -3.850081) (xy 319.360055 -3.850081) (xy 319.352143 -3.935464) (xy 319.336387 -4.019754)
			(xy 319.31292 -4.10223) (xy 319.281944 -4.182189) (xy 319.243722 -4.258949) (xy 319.198581 -4.331855)
			(xy 319.146905 -4.400284) (xy 319.089136 -4.463654) (xy 319.025766 -4.521423) (xy 318.957337 -4.573099)
			(xy 318.884431 -4.61824) (xy 318.807671 -4.656462) (xy 318.727712 -4.687438) (xy 318.645236 -4.710905)
			(xy 318.560946 -4.726661) (xy 318.475563 -4.734573) (xy 318.389813 -4.734573) (xy 318.30443 -4.726661)
			(xy 318.22014 -4.710905) (xy 318.137664 -4.687438) (xy 318.057705 -4.656462) (xy 317.980945 -4.61824)
			(xy 317.908039 -4.573099) (xy 317.83961 -4.521423) (xy 317.77624 -4.463654) (xy 317.718471 -4.400284)
			(xy 317.666795 -4.331855) (xy 317.621654 -4.258949) (xy 317.583432 -4.182189) (xy 317.552456 -4.10223)
			(xy 317.528989 -4.019754) (xy 317.513233 -3.935464) (xy 317.505321 -3.850081) (xy 313.010055 -3.850081)
			(xy 313.002143 -3.935464) (xy 312.986387 -4.019754) (xy 312.96292 -4.10223) (xy 312.931944 -4.182189)
			(xy 312.893722 -4.258949) (xy 312.848581 -4.331855) (xy 312.796905 -4.400284) (xy 312.739136 -4.463654)
			(xy 312.675766 -4.521423) (xy 312.607337 -4.573099) (xy 312.534431 -4.61824) (xy 312.457671 -4.656462)
			(xy 312.377712 -4.687438) (xy 312.295236 -4.710905) (xy 312.210946 -4.726661) (xy 312.125563 -4.734573)
			(xy 312.039813 -4.734573) (xy 311.95443 -4.726661) (xy 311.87014 -4.710905) (xy 311.787664 -4.687438)
			(xy 311.707705 -4.656462) (xy 311.630945 -4.61824) (xy 311.558039 -4.573099) (xy 311.48961 -4.521423)
			(xy 311.42624 -4.463654) (xy 311.368471 -4.400284) (xy 311.316795 -4.331855) (xy 311.271654 -4.258949)
			(xy 311.233432 -4.182189) (xy 311.202456 -4.10223) (xy 311.178989 -4.019754) (xy 311.163233 -3.935464)
			(xy 311.155321 -3.850081) (xy 304.348655 -3.850081) (xy 304.340743 -3.935464) (xy 304.324987 -4.019754)
			(xy 304.30152 -4.10223) (xy 304.270544 -4.182189) (xy 304.232322 -4.258949) (xy 304.187181 -4.331855)
			(xy 304.135505 -4.400284) (xy 304.077736 -4.463654) (xy 304.014366 -4.521423) (xy 303.945937 -4.573099)
			(xy 303.873031 -4.61824) (xy 303.796271 -4.656462) (xy 303.716312 -4.687438) (xy 303.633836 -4.710905)
			(xy 303.549546 -4.726661) (xy 303.464163 -4.734573) (xy 303.378413 -4.734573) (xy 303.29303 -4.726661)
			(xy 303.20874 -4.710905) (xy 303.126264 -4.687438) (xy 303.046305 -4.656462) (xy 302.969545 -4.61824)
			(xy 302.896639 -4.573099) (xy 302.82821 -4.521423) (xy 302.76484 -4.463654) (xy 302.707071 -4.400284)
			(xy 302.655395 -4.331855) (xy 302.610254 -4.258949) (xy 302.572032 -4.182189) (xy 302.541056 -4.10223)
			(xy 302.517589 -4.019754) (xy 302.501833 -3.935464) (xy 302.493921 -3.850081) (xy 297.998655 -3.850081)
			(xy 297.990743 -3.935464) (xy 297.974987 -4.019754) (xy 297.95152 -4.10223) (xy 297.920544 -4.182189)
			(xy 297.882322 -4.258949) (xy 297.837181 -4.331855) (xy 297.785505 -4.400284) (xy 297.727736 -4.463654)
			(xy 297.664366 -4.521423) (xy 297.595937 -4.573099) (xy 297.523031 -4.61824) (xy 297.446271 -4.656462)
			(xy 297.366312 -4.687438) (xy 297.283836 -4.710905) (xy 297.199546 -4.726661) (xy 297.114163 -4.734573)
			(xy 297.028413 -4.734573) (xy 296.94303 -4.726661) (xy 296.85874 -4.710905) (xy 296.776264 -4.687438)
			(xy 296.696305 -4.656462) (xy 296.619545 -4.61824) (xy 296.546639 -4.573099) (xy 296.47821 -4.521423)
			(xy 296.41484 -4.463654) (xy 296.357071 -4.400284) (xy 296.305395 -4.331855) (xy 296.260254 -4.258949)
			(xy 296.222032 -4.182189) (xy 296.191056 -4.10223) (xy 296.167589 -4.019754) (xy 296.151833 -3.935464)
			(xy 296.143921 -3.850081) (xy 216.865975 -3.850081) (xy 216.858063 -3.935464) (xy 216.842307 -4.019754)
			(xy 216.81884 -4.10223) (xy 216.787864 -4.182189) (xy 216.749642 -4.258949) (xy 216.704501 -4.331855)
			(xy 216.652825 -4.400284) (xy 216.595056 -4.463654) (xy 216.531686 -4.521423) (xy 216.463257 -4.573099)
			(xy 216.390351 -4.61824) (xy 216.313591 -4.656462) (xy 216.233632 -4.687438) (xy 216.151156 -4.710905)
			(xy 216.066866 -4.726661) (xy 215.981483 -4.734573) (xy 215.895733 -4.734573) (xy 215.81035 -4.726661)
			(xy 215.72606 -4.710905) (xy 215.643584 -4.687438) (xy 215.563625 -4.656462) (xy 215.486865 -4.61824)
			(xy 215.413959 -4.573099) (xy 215.34553 -4.521423) (xy 215.28216 -4.463654) (xy 215.224391 -4.400284)
			(xy 215.172715 -4.331855) (xy 215.127574 -4.258949) (xy 215.089352 -4.182189) (xy 215.058376 -4.10223)
			(xy 215.034909 -4.019754) (xy 215.019153 -3.935464) (xy 215.011241 -3.850081) (xy 210.515975 -3.850081)
			(xy 210.508063 -3.935464) (xy 210.492307 -4.019754) (xy 210.46884 -4.10223) (xy 210.437864 -4.182189)
			(xy 210.399642 -4.258949) (xy 210.354501 -4.331855) (xy 210.302825 -4.400284) (xy 210.245056 -4.463654)
			(xy 210.181686 -4.521423) (xy 210.113257 -4.573099) (xy 210.040351 -4.61824) (xy 209.963591 -4.656462)
			(xy 209.883632 -4.687438) (xy 209.801156 -4.710905) (xy 209.716866 -4.726661) (xy 209.631483 -4.734573)
			(xy 209.545733 -4.734573) (xy 209.46035 -4.726661) (xy 209.37606 -4.710905) (xy 209.293584 -4.687438)
			(xy 209.213625 -4.656462) (xy 209.136865 -4.61824) (xy 209.063959 -4.573099) (xy 208.99553 -4.521423)
			(xy 208.93216 -4.463654) (xy 208.874391 -4.400284) (xy 208.822715 -4.331855) (xy 208.777574 -4.258949)
			(xy 208.739352 -4.182189) (xy 208.708376 -4.10223) (xy 208.684909 -4.019754) (xy 208.669153 -3.935464)
			(xy 208.661241 -3.850081) (xy 196.990215 -3.850081) (xy 196.992516 -3.85486) (xy 197.046381 -3.984909)
			(xy 197.09287 -4.117774) (xy 197.131836 -4.253037) (xy 197.163157 -4.390271) (xy 197.186733 -4.529046)
			(xy 197.202491 -4.668924) (xy 197.210381 -4.809466) (xy 197.210934 -4.879848) (xy 197.210934 -6.390081)
			(xy 208.661241 -6.390081) (xy 208.661241 -6.304331) (xy 208.669153 -6.218948) (xy 208.684909 -6.134658)
			(xy 208.708376 -6.052182) (xy 208.739352 -5.972223) (xy 208.777574 -5.895463) (xy 208.822715 -5.822557)
			(xy 208.874391 -5.754128) (xy 208.93216 -5.690758) (xy 208.99553 -5.632989) (xy 209.063959 -5.581313)
			(xy 209.136865 -5.536172) (xy 209.213625 -5.49795) (xy 209.293584 -5.466974) (xy 209.37606 -5.443507)
			(xy 209.46035 -5.427751) (xy 209.545733 -5.419839) (xy 209.631483 -5.419839) (xy 209.716866 -5.427751)
			(xy 209.801156 -5.443507) (xy 209.883632 -5.466974) (xy 209.963591 -5.49795) (xy 209.984264 -5.508244)
			(xy 213.517988 -5.508244) (xy 213.517988 -4.644644) (xy 213.518492 -4.61509) (xy 213.526541 -4.556534)
			(xy 213.542487 -4.499619) (xy 213.566036 -4.445405) (xy 213.596747 -4.394902) (xy 213.634049 -4.349052)
			(xy 213.677246 -4.308709) (xy 213.725535 -4.274623) (xy 213.778015 -4.24743) (xy 213.83371 -4.227636)
			(xy 213.891581 -4.21561) (xy 213.95055 -4.211577) (xy 214.009519 -4.21561) (xy 214.06739 -4.227636)
			(xy 214.123085 -4.24743) (xy 214.175565 -4.274623) (xy 214.223854 -4.308709) (xy 214.267051 -4.349052)
			(xy 214.304353 -4.394902) (xy 214.335064 -4.445405) (xy 214.358613 -4.499619) (xy 214.374559 -4.556534)
			(xy 214.382608 -4.61509) (xy 214.383112 -4.644644) (xy 214.383112 -5.508244) (xy 214.382608 -5.537798)
			(xy 214.374559 -5.596354) (xy 214.358613 -5.653269) (xy 214.335064 -5.707483) (xy 214.304353 -5.757986)
			(xy 214.267051 -5.803836) (xy 214.223854 -5.844179) (xy 214.175565 -5.878265) (xy 214.123085 -5.905458)
			(xy 214.06739 -5.925252) (xy 214.009519 -5.937278) (xy 213.95055 -5.941312) (xy 213.891581 -5.937278)
			(xy 213.83371 -5.925252) (xy 213.778015 -5.905458) (xy 213.725535 -5.878265) (xy 213.677246 -5.844179)
			(xy 213.634049 -5.803836) (xy 213.596747 -5.757986) (xy 213.566036 -5.707483) (xy 213.542487 -5.653269)
			(xy 213.526541 -5.596354) (xy 213.518492 -5.537798) (xy 213.517988 -5.508244) (xy 209.984264 -5.508244)
			(xy 210.040351 -5.536172) (xy 210.113257 -5.581313) (xy 210.181686 -5.632989) (xy 210.245056 -5.690758)
			(xy 210.302825 -5.754128) (xy 210.354501 -5.822557) (xy 210.399642 -5.895463) (xy 210.437864 -5.972223)
			(xy 210.46884 -6.052182) (xy 210.492307 -6.134658) (xy 210.508063 -6.218948) (xy 210.515975 -6.304331)
			(xy 210.51647 -6.347206) (xy 210.515975 -6.390081) (xy 215.011241 -6.390081) (xy 215.011241 -6.304331)
			(xy 215.019153 -6.218948) (xy 215.034909 -6.134658) (xy 215.058376 -6.052182) (xy 215.089352 -5.972223)
			(xy 215.127574 -5.895463) (xy 215.172715 -5.822557) (xy 215.224391 -5.754128) (xy 215.28216 -5.690758)
			(xy 215.34553 -5.632989) (xy 215.413959 -5.581313) (xy 215.486865 -5.536172) (xy 215.563625 -5.49795)
			(xy 215.643584 -5.466974) (xy 215.72606 -5.443507) (xy 215.81035 -5.427751) (xy 215.895733 -5.419839)
			(xy 215.981483 -5.419839) (xy 216.066866 -5.427751) (xy 216.151156 -5.443507) (xy 216.233632 -5.466974)
			(xy 216.313591 -5.49795) (xy 216.390351 -5.536172) (xy 216.463257 -5.581313) (xy 216.531686 -5.632989)
			(xy 216.595056 -5.690758) (xy 216.652825 -5.754128) (xy 216.704501 -5.822557) (xy 216.749642 -5.895463)
			(xy 216.787864 -5.972223) (xy 216.81884 -6.052182) (xy 216.842307 -6.134658) (xy 216.858063 -6.218948)
			(xy 216.865975 -6.304331) (xy 216.86647 -6.347206) (xy 216.865975 -6.390081) (xy 296.143921 -6.390081)
			(xy 296.143921 -6.304331) (xy 296.151833 -6.218948) (xy 296.167589 -6.134658) (xy 296.191056 -6.052182)
			(xy 296.222032 -5.972223) (xy 296.260254 -5.895463) (xy 296.305395 -5.822557) (xy 296.357071 -5.754128)
			(xy 296.41484 -5.690758) (xy 296.47821 -5.632989) (xy 296.546639 -5.581313) (xy 296.619545 -5.536172)
			(xy 296.696305 -5.49795) (xy 296.776264 -5.466974) (xy 296.85874 -5.443507) (xy 296.94303 -5.427751)
			(xy 297.028413 -5.419839) (xy 297.114163 -5.419839) (xy 297.199546 -5.427751) (xy 297.283836 -5.443507)
			(xy 297.366312 -5.466974) (xy 297.446271 -5.49795) (xy 297.466944 -5.508244) (xy 298.629324 -5.508244)
			(xy 298.629324 -4.644644) (xy 298.629828 -4.61509) (xy 298.637877 -4.556534) (xy 298.653823 -4.499619)
			(xy 298.677372 -4.445405) (xy 298.708083 -4.394902) (xy 298.745385 -4.349052) (xy 298.788582 -4.308709)
			(xy 298.836871 -4.274623) (xy 298.889351 -4.24743) (xy 298.945046 -4.227636) (xy 299.002917 -4.21561)
			(xy 299.061886 -4.211577) (xy 299.120855 -4.21561) (xy 299.178726 -4.227636) (xy 299.234421 -4.24743)
			(xy 299.286901 -4.274623) (xy 299.33519 -4.308709) (xy 299.378387 -4.349052) (xy 299.415689 -4.394902)
			(xy 299.4464 -4.445405) (xy 299.469949 -4.499619) (xy 299.485895 -4.556534) (xy 299.493944 -4.61509)
			(xy 299.494448 -4.644644) (xy 299.494448 -5.508244) (xy 299.493944 -5.537798) (xy 299.485895 -5.596354)
			(xy 299.469949 -5.653269) (xy 299.4464 -5.707483) (xy 299.415689 -5.757986) (xy 299.378387 -5.803836)
			(xy 299.33519 -5.844179) (xy 299.286901 -5.878265) (xy 299.234421 -5.905458) (xy 299.178726 -5.925252)
			(xy 299.120855 -5.937278) (xy 299.061886 -5.941312) (xy 299.002917 -5.937278) (xy 298.945046 -5.925252)
			(xy 298.889351 -5.905458) (xy 298.836871 -5.878265) (xy 298.788582 -5.844179) (xy 298.745385 -5.803836)
			(xy 298.708083 -5.757986) (xy 298.677372 -5.707483) (xy 298.653823 -5.653269) (xy 298.637877 -5.596354)
			(xy 298.629828 -5.537798) (xy 298.629324 -5.508244) (xy 297.466944 -5.508244) (xy 297.523031 -5.536172)
			(xy 297.595937 -5.581313) (xy 297.664366 -5.632989) (xy 297.727736 -5.690758) (xy 297.785505 -5.754128)
			(xy 297.837181 -5.822557) (xy 297.882322 -5.895463) (xy 297.920544 -5.972223) (xy 297.95152 -6.052182)
			(xy 297.974987 -6.134658) (xy 297.990743 -6.218948) (xy 297.998655 -6.304331) (xy 297.99915 -6.347206)
			(xy 297.998655 -6.390081) (xy 302.493921 -6.390081) (xy 302.493921 -6.304331) (xy 302.501833 -6.218948)
			(xy 302.517589 -6.134658) (xy 302.541056 -6.052182) (xy 302.572032 -5.972223) (xy 302.610254 -5.895463)
			(xy 302.655395 -5.822557) (xy 302.707071 -5.754128) (xy 302.76484 -5.690758) (xy 302.82821 -5.632989)
			(xy 302.896639 -5.581313) (xy 302.969545 -5.536172) (xy 303.046305 -5.49795) (xy 303.126264 -5.466974)
			(xy 303.20874 -5.443507) (xy 303.29303 -5.427751) (xy 303.378413 -5.419839) (xy 303.464163 -5.419839)
			(xy 303.549546 -5.427751) (xy 303.633836 -5.443507) (xy 303.716312 -5.466974) (xy 303.796271 -5.49795)
			(xy 303.873031 -5.536172) (xy 303.945937 -5.581313) (xy 304.014366 -5.632989) (xy 304.077736 -5.690758)
			(xy 304.135505 -5.754128) (xy 304.187181 -5.822557) (xy 304.232322 -5.895463) (xy 304.270544 -5.972223)
			(xy 304.30152 -6.052182) (xy 304.324987 -6.134658) (xy 304.340743 -6.218948) (xy 304.348655 -6.304331)
			(xy 304.34915 -6.347206) (xy 304.348655 -6.390081) (xy 311.155321 -6.390081) (xy 311.155321 -6.304331)
			(xy 311.163233 -6.218948) (xy 311.178989 -6.134658) (xy 311.202456 -6.052182) (xy 311.233432 -5.972223)
			(xy 311.271654 -5.895463) (xy 311.316795 -5.822557) (xy 311.368471 -5.754128) (xy 311.42624 -5.690758)
			(xy 311.48961 -5.632989) (xy 311.558039 -5.581313) (xy 311.630945 -5.536172) (xy 311.707705 -5.49795)
			(xy 311.787664 -5.466974) (xy 311.87014 -5.443507) (xy 311.95443 -5.427751) (xy 312.039813 -5.419839)
			(xy 312.125563 -5.419839) (xy 312.210946 -5.427751) (xy 312.295236 -5.443507) (xy 312.377712 -5.466974)
			(xy 312.457671 -5.49795) (xy 312.534431 -5.536172) (xy 312.607337 -5.581313) (xy 312.675766 -5.632989)
			(xy 312.739136 -5.690758) (xy 312.796905 -5.754128) (xy 312.848581 -5.822557) (xy 312.893722 -5.895463)
			(xy 312.931944 -5.972223) (xy 312.96292 -6.052182) (xy 312.986387 -6.134658) (xy 313.002143 -6.218948)
			(xy 313.010055 -6.304331) (xy 313.01055 -6.347206) (xy 313.010055 -6.390081) (xy 317.505321 -6.390081)
			(xy 317.505321 -6.304331) (xy 317.513233 -6.218948) (xy 317.528989 -6.134658) (xy 317.552456 -6.052182)
			(xy 317.583432 -5.972223) (xy 317.621654 -5.895463) (xy 317.666795 -5.822557) (xy 317.718471 -5.754128)
			(xy 317.77624 -5.690758) (xy 317.83961 -5.632989) (xy 317.908039 -5.581313) (xy 317.980945 -5.536172)
			(xy 318.057705 -5.49795) (xy 318.137664 -5.466974) (xy 318.22014 -5.443507) (xy 318.30443 -5.427751)
			(xy 318.389813 -5.419839) (xy 318.475563 -5.419839) (xy 318.560946 -5.427751) (xy 318.645236 -5.443507)
			(xy 318.727712 -5.466974) (xy 318.807671 -5.49795) (xy 318.884431 -5.536172) (xy 318.957337 -5.581313)
			(xy 319.025766 -5.632989) (xy 319.089136 -5.690758) (xy 319.146905 -5.754128) (xy 319.198581 -5.822557)
			(xy 319.243722 -5.895463) (xy 319.281944 -5.972223) (xy 319.31292 -6.052182) (xy 319.336387 -6.134658)
			(xy 319.352143 -6.218948) (xy 319.360055 -6.304331) (xy 319.36055 -6.347206) (xy 319.360055 -6.390081)
			(xy 361.894107 -6.390081) (xy 361.894107 -6.304331) (xy 361.902019 -6.218948) (xy 361.917775 -6.134658)
			(xy 361.941242 -6.052182) (xy 361.972218 -5.972223) (xy 362.01044 -5.895463) (xy 362.055581 -5.822557)
			(xy 362.107257 -5.754128) (xy 362.165026 -5.690758) (xy 362.228396 -5.632989) (xy 362.296825 -5.581313)
			(xy 362.369731 -5.536172) (xy 362.446491 -5.49795) (xy 362.52645 -5.466974) (xy 362.608926 -5.443507)
			(xy 362.693216 -5.427751) (xy 362.778599 -5.419839) (xy 362.864349 -5.419839) (xy 362.949732 -5.427751)
			(xy 363.034022 -5.443507) (xy 363.116498 -5.466974) (xy 363.196457 -5.49795) (xy 363.273217 -5.536172)
			(xy 363.346123 -5.581313) (xy 363.414552 -5.632989) (xy 363.477922 -5.690758) (xy 363.535691 -5.754128)
			(xy 363.587367 -5.822557) (xy 363.632508 -5.895463) (xy 363.67073 -5.972223) (xy 363.701706 -6.052182)
			(xy 363.725173 -6.134658) (xy 363.740929 -6.218948) (xy 363.748841 -6.304331) (xy 363.749336 -6.347206)
			(xy 363.748841 -6.390081) (xy 368.244107 -6.390081) (xy 368.244107 -6.304331) (xy 368.252019 -6.218948)
			(xy 368.267775 -6.134658) (xy 368.291242 -6.052182) (xy 368.322218 -5.972223) (xy 368.36044 -5.895463)
			(xy 368.405581 -5.822557) (xy 368.457257 -5.754128) (xy 368.515026 -5.690758) (xy 368.578396 -5.632989)
			(xy 368.646825 -5.581313) (xy 368.719731 -5.536172) (xy 368.796491 -5.49795) (xy 368.87645 -5.466974)
			(xy 368.958926 -5.443507) (xy 369.043216 -5.427751) (xy 369.128599 -5.419839) (xy 369.214349 -5.419839)
			(xy 369.299732 -5.427751) (xy 369.384022 -5.443507) (xy 369.466498 -5.466974) (xy 369.546457 -5.49795)
			(xy 369.623217 -5.536172) (xy 369.696123 -5.581313) (xy 369.764552 -5.632989) (xy 369.827922 -5.690758)
			(xy 369.885691 -5.754128) (xy 369.937367 -5.822557) (xy 369.982508 -5.895463) (xy 370.02073 -5.972223)
			(xy 370.051706 -6.052182) (xy 370.075173 -6.134658) (xy 370.090929 -6.218948) (xy 370.098841 -6.304331)
			(xy 370.099336 -6.347206) (xy 370.098841 -6.390081) (xy 370.090929 -6.475464) (xy 370.075173 -6.559754)
			(xy 370.051706 -6.64223) (xy 370.02073 -6.722189) (xy 369.982508 -6.798949) (xy 369.937367 -6.871855)
			(xy 369.885691 -6.940284) (xy 369.827922 -7.003654) (xy 369.764552 -7.061423) (xy 369.696123 -7.113099)
			(xy 369.623217 -7.15824) (xy 369.546457 -7.196462) (xy 369.466498 -7.227438) (xy 369.384022 -7.250905)
			(xy 369.299732 -7.266661) (xy 369.214349 -7.274573) (xy 369.128599 -7.274573) (xy 369.043216 -7.266661)
			(xy 368.958926 -7.250905) (xy 368.87645 -7.227438) (xy 368.796491 -7.196462) (xy 368.719731 -7.15824)
			(xy 368.646825 -7.113099) (xy 368.578396 -7.061423) (xy 368.515026 -7.003654) (xy 368.457257 -6.940284)
			(xy 368.405581 -6.871855) (xy 368.36044 -6.798949) (xy 368.322218 -6.722189) (xy 368.291242 -6.64223)
			(xy 368.267775 -6.559754) (xy 368.252019 -6.475464) (xy 368.244107 -6.390081) (xy 363.748841 -6.390081)
			(xy 363.740929 -6.475464) (xy 363.725173 -6.559754) (xy 363.701706 -6.64223) (xy 363.67073 -6.722189)
			(xy 363.632508 -6.798949) (xy 363.587367 -6.871855) (xy 363.535691 -6.940284) (xy 363.477922 -7.003654)
			(xy 363.414552 -7.061423) (xy 363.346123 -7.113099) (xy 363.273217 -7.15824) (xy 363.196457 -7.196462)
			(xy 363.116498 -7.227438) (xy 363.034022 -7.250905) (xy 362.949732 -7.266661) (xy 362.864349 -7.274573)
			(xy 362.778599 -7.274573) (xy 362.693216 -7.266661) (xy 362.608926 -7.250905) (xy 362.52645 -7.227438)
			(xy 362.446491 -7.196462) (xy 362.369731 -7.15824) (xy 362.296825 -7.113099) (xy 362.228396 -7.061423)
			(xy 362.165026 -7.003654) (xy 362.107257 -6.940284) (xy 362.055581 -6.871855) (xy 362.01044 -6.798949)
			(xy 361.972218 -6.722189) (xy 361.941242 -6.64223) (xy 361.917775 -6.559754) (xy 361.902019 -6.475464)
			(xy 361.894107 -6.390081) (xy 319.360055 -6.390081) (xy 319.352143 -6.475464) (xy 319.336387 -6.559754)
			(xy 319.31292 -6.64223) (xy 319.281944 -6.722189) (xy 319.243722 -6.798949) (xy 319.198581 -6.871855)
			(xy 319.146905 -6.940284) (xy 319.089136 -7.003654) (xy 319.025766 -7.061423) (xy 318.957337 -7.113099)
			(xy 318.884431 -7.15824) (xy 318.807671 -7.196462) (xy 318.727712 -7.227438) (xy 318.645236 -7.250905)
			(xy 318.560946 -7.266661) (xy 318.475563 -7.274573) (xy 318.389813 -7.274573) (xy 318.30443 -7.266661)
			(xy 318.22014 -7.250905) (xy 318.137664 -7.227438) (xy 318.057705 -7.196462) (xy 317.980945 -7.15824)
			(xy 317.908039 -7.113099) (xy 317.83961 -7.061423) (xy 317.77624 -7.003654) (xy 317.718471 -6.940284)
			(xy 317.666795 -6.871855) (xy 317.621654 -6.798949) (xy 317.583432 -6.722189) (xy 317.552456 -6.64223)
			(xy 317.528989 -6.559754) (xy 317.513233 -6.475464) (xy 317.505321 -6.390081) (xy 313.010055 -6.390081)
			(xy 313.002143 -6.475464) (xy 312.986387 -6.559754) (xy 312.96292 -6.64223) (xy 312.931944 -6.722189)
			(xy 312.893722 -6.798949) (xy 312.848581 -6.871855) (xy 312.796905 -6.940284) (xy 312.739136 -7.003654)
			(xy 312.675766 -7.061423) (xy 312.607337 -7.113099) (xy 312.534431 -7.15824) (xy 312.457671 -7.196462)
			(xy 312.377712 -7.227438) (xy 312.295236 -7.250905) (xy 312.210946 -7.266661) (xy 312.125563 -7.274573)
			(xy 312.039813 -7.274573) (xy 311.95443 -7.266661) (xy 311.87014 -7.250905) (xy 311.787664 -7.227438)
			(xy 311.707705 -7.196462) (xy 311.630945 -7.15824) (xy 311.558039 -7.113099) (xy 311.48961 -7.061423)
			(xy 311.42624 -7.003654) (xy 311.368471 -6.940284) (xy 311.316795 -6.871855) (xy 311.271654 -6.798949)
			(xy 311.233432 -6.722189) (xy 311.202456 -6.64223) (xy 311.178989 -6.559754) (xy 311.163233 -6.475464)
			(xy 311.155321 -6.390081) (xy 304.348655 -6.390081) (xy 304.340743 -6.475464) (xy 304.324987 -6.559754)
			(xy 304.30152 -6.64223) (xy 304.270544 -6.722189) (xy 304.232322 -6.798949) (xy 304.187181 -6.871855)
			(xy 304.135505 -6.940284) (xy 304.077736 -7.003654) (xy 304.014366 -7.061423) (xy 303.945937 -7.113099)
			(xy 303.873031 -7.15824) (xy 303.796271 -7.196462) (xy 303.716312 -7.227438) (xy 303.633836 -7.250905)
			(xy 303.549546 -7.266661) (xy 303.464163 -7.274573) (xy 303.378413 -7.274573) (xy 303.29303 -7.266661)
			(xy 303.20874 -7.250905) (xy 303.126264 -7.227438) (xy 303.046305 -7.196462) (xy 302.969545 -7.15824)
			(xy 302.896639 -7.113099) (xy 302.82821 -7.061423) (xy 302.76484 -7.003654) (xy 302.707071 -6.940284)
			(xy 302.655395 -6.871855) (xy 302.610254 -6.798949) (xy 302.572032 -6.722189) (xy 302.541056 -6.64223)
			(xy 302.517589 -6.559754) (xy 302.501833 -6.475464) (xy 302.493921 -6.390081) (xy 297.998655 -6.390081)
			(xy 297.990743 -6.475464) (xy 297.974987 -6.559754) (xy 297.95152 -6.64223) (xy 297.920544 -6.722189)
			(xy 297.882322 -6.798949) (xy 297.837181 -6.871855) (xy 297.785505 -6.940284) (xy 297.727736 -7.003654)
			(xy 297.664366 -7.061423) (xy 297.595937 -7.113099) (xy 297.523031 -7.15824) (xy 297.446271 -7.196462)
			(xy 297.366312 -7.227438) (xy 297.283836 -7.250905) (xy 297.199546 -7.266661) (xy 297.114163 -7.274573)
			(xy 297.028413 -7.274573) (xy 296.94303 -7.266661) (xy 296.85874 -7.250905) (xy 296.776264 -7.227438)
			(xy 296.696305 -7.196462) (xy 296.619545 -7.15824) (xy 296.546639 -7.113099) (xy 296.47821 -7.061423)
			(xy 296.41484 -7.003654) (xy 296.357071 -6.940284) (xy 296.305395 -6.871855) (xy 296.260254 -6.798949)
			(xy 296.222032 -6.722189) (xy 296.191056 -6.64223) (xy 296.167589 -6.559754) (xy 296.151833 -6.475464)
			(xy 296.143921 -6.390081) (xy 216.865975 -6.390081) (xy 216.858063 -6.475464) (xy 216.842307 -6.559754)
			(xy 216.81884 -6.64223) (xy 216.787864 -6.722189) (xy 216.749642 -6.798949) (xy 216.704501 -6.871855)
			(xy 216.652825 -6.940284) (xy 216.595056 -7.003654) (xy 216.531686 -7.061423) (xy 216.463257 -7.113099)
			(xy 216.390351 -7.15824) (xy 216.313591 -7.196462) (xy 216.233632 -7.227438) (xy 216.151156 -7.250905)
			(xy 216.066866 -7.266661) (xy 215.981483 -7.274573) (xy 215.895733 -7.274573) (xy 215.81035 -7.266661)
			(xy 215.72606 -7.250905) (xy 215.643584 -7.227438) (xy 215.563625 -7.196462) (xy 215.486865 -7.15824)
			(xy 215.413959 -7.113099) (xy 215.34553 -7.061423) (xy 215.28216 -7.003654) (xy 215.224391 -6.940284)
			(xy 215.172715 -6.871855) (xy 215.127574 -6.798949) (xy 215.089352 -6.722189) (xy 215.058376 -6.64223)
			(xy 215.034909 -6.559754) (xy 215.019153 -6.475464) (xy 215.011241 -6.390081) (xy 210.515975 -6.390081)
			(xy 210.508063 -6.475464) (xy 210.492307 -6.559754) (xy 210.46884 -6.64223) (xy 210.437864 -6.722189)
			(xy 210.399642 -6.798949) (xy 210.354501 -6.871855) (xy 210.302825 -6.940284) (xy 210.245056 -7.003654)
			(xy 210.181686 -7.061423) (xy 210.113257 -7.113099) (xy 210.040351 -7.15824) (xy 209.963591 -7.196462)
			(xy 209.883632 -7.227438) (xy 209.801156 -7.250905) (xy 209.716866 -7.266661) (xy 209.631483 -7.274573)
			(xy 209.545733 -7.274573) (xy 209.46035 -7.266661) (xy 209.37606 -7.250905) (xy 209.293584 -7.227438)
			(xy 209.213625 -7.196462) (xy 209.136865 -7.15824) (xy 209.063959 -7.113099) (xy 208.99553 -7.061423)
			(xy 208.93216 -7.003654) (xy 208.874391 -6.940284) (xy 208.822715 -6.871855) (xy 208.777574 -6.798949)
			(xy 208.739352 -6.722189) (xy 208.708376 -6.64223) (xy 208.684909 -6.559754) (xy 208.669153 -6.475464)
			(xy 208.661241 -6.390081) (xy 197.210934 -6.390081) (xy 197.210934 -7.78002) (xy 197.211456 -7.835788)
			(xy 197.219793 -7.947013) (xy 197.236418 -8.057304) (xy 197.261239 -8.166044) (xy 197.294116 -8.272625)
			(xy 197.334866 -8.376451) (xy 197.383261 -8.476941) (xy 197.439031 -8.573534) (xy 197.501863 -8.66569)
			(xy 197.571406 -8.752892) (xy 197.647271 -8.834653) (xy 197.729034 -8.910516) (xy 197.816238 -8.980057)
			(xy 197.908394 -9.042887) (xy 198.004989 -9.098654) (xy 198.10548 -9.147047) (xy 198.209307 -9.187795)
			(xy 198.315889 -9.22067) (xy 198.42463 -9.245488) (xy 198.534921 -9.262111) (xy 198.646146 -9.270445)
			(xy 198.701914 -9.271) (xy 223.300036 -9.271) (xy 223.370417 -9.271495) (xy 223.510959 -9.279389)
			(xy 223.650836 -9.295152) (xy 223.78961 -9.318732) (xy 223.926844 -9.350057) (xy 224.062105 -9.389027)
			(xy 224.194968 -9.435519) (xy 224.325015 -9.489388) (xy 224.451838 -9.550465) (xy 224.575036 -9.618556)
			(xy 224.694222 -9.693447) (xy 224.809022 -9.774904) (xy 224.919074 -9.862669) (xy 225.024032 -9.956467)
			(xy 225.123566 -10.056003) (xy 225.217361 -10.160962) (xy 225.305125 -10.271016) (xy 225.386579 -10.385818)
			(xy 225.461469 -10.505006) (xy 225.529557 -10.628205) (xy 225.590631 -10.755029) (xy 225.644498 -10.885077)
			(xy 225.690988 -11.017941) (xy 225.729955 -11.153203) (xy 225.761277 -11.290437) (xy 225.784855 -11.429211)
			(xy 225.800615 -11.569089) (xy 225.808507 -11.709631) (xy 225.809048 -11.780012) (xy 225.809048 -33.120076)
			(xy 225.809549 -33.152224) (xy 225.817939 -33.21597) (xy 225.834578 -33.278076) (xy 225.859182 -33.337478)
			(xy 225.891329 -33.39316) (xy 225.93047 -33.44417) (xy 225.975934 -33.489634) (xy 226.026945 -33.528774)
			(xy 226.082627 -33.560921) (xy 226.14203 -33.585524) (xy 226.204136 -33.602162) (xy 226.267882 -33.610551)
			(xy 226.30003 -33.611058)
		)
		(stroke
			(width 0)
			(type solid)
		)
		(fill yes)
		(layer "In10.Cu")
		(net "DELTA_L_GND_1")
	)
	(gr_poly
		(pts
			(xy 194.445128 -441.480956) (xy 194.455142 -441.480531) (xy 194.473642 -441.472854) (xy 194.487795 -441.458682)
			(xy 194.495445 -441.440171) (xy 194.495928 -441.430156) (xy 194.495928 -441.17006) (xy 194.49641 -441.126022)
			(xy 194.50409 -441.03828) (xy 194.519387 -440.951542) (xy 194.542185 -440.866466) (xy 194.572311 -440.783702)
			(xy 194.609536 -440.703878) (xy 194.653576 -440.627602) (xy 194.704095 -440.555454) (xy 194.760711 -440.487984)
			(xy 194.822991 -440.425704) (xy 194.890462 -440.369089) (xy 194.96261 -440.31857) (xy 195.038887 -440.274531)
			(xy 195.118711 -440.237308) (xy 195.201476 -440.207182) (xy 195.286551 -440.184385) (xy 195.37329 -440.169088)
			(xy 195.461032 -440.16141) (xy 195.50507 -440.160918) (xy 276.314916 -440.160918) (xy 276.358955 -440.161399)
			(xy 276.446699 -440.169077) (xy 276.533439 -440.184372) (xy 276.618516 -440.207169) (xy 276.701283 -440.237294)
			(xy 276.781109 -440.274518) (xy 276.857388 -440.318557) (xy 276.929538 -440.369076) (xy 276.99701 -440.425692)
			(xy 277.059292 -440.487972) (xy 277.115909 -440.555443) (xy 277.16643 -440.627592) (xy 277.210471 -440.703869)
			(xy 277.247697 -440.783695) (xy 277.277823 -440.866461) (xy 277.300622 -440.951538) (xy 277.31592 -441.038278)
			(xy 277.3236 -441.126021) (xy 277.324058 -441.17006) (xy 277.324058 -441.430156) (xy 277.324469 -441.440186)
			(xy 277.33213 -441.458725) (xy 277.346302 -441.472922) (xy 277.364828 -441.480614) (xy 277.374858 -441.480956)
			(xy 463.300064 -441.480956) (xy 463.355834 -441.480449) (xy 463.467062 -441.472116) (xy 463.577357 -441.455494)
			(xy 463.686101 -441.430676) (xy 463.792686 -441.397801) (xy 463.896517 -441.357052) (xy 463.997011 -441.308658)
			(xy 464.093608 -441.252889) (xy 464.185768 -441.190057) (xy 464.272974 -441.120513) (xy 464.354739 -441.044647)
			(xy 464.430606 -440.962883) (xy 464.50015 -440.875677) (xy 464.562982 -440.783519) (xy 464.618752 -440.686922)
			(xy 464.667147 -440.586428) (xy 464.707897 -440.482598) (xy 464.740773 -440.376013) (xy 464.765592 -440.267269)
			(xy 464.782215 -440.156974) (xy 464.790548 -440.045746) (xy 464.791044 -439.989976) (xy 464.791044 -409.528264)
			(xy 464.791546 -409.457891) (xy 464.799454 -409.317366) (xy 464.815227 -409.177505) (xy 464.838815 -409.038749)
			(xy 464.870143 -408.901532) (xy 464.909113 -408.766288) (xy 464.955604 -408.633441) (xy 465.009467 -408.503408)
			(xy 465.070535 -408.376599) (xy 465.138615 -408.253413) (xy 465.213493 -408.134236) (xy 465.294933 -408.019444)
			(xy 465.38268 -407.909398) (xy 465.476458 -407.804443) (xy 465.525866 -407.754328) (xy 467.354412 -405.925782)
			(xy 467.391703 -405.887819) (xy 467.461396 -405.807388) (xy 467.525176 -405.722192) (xy 467.582717 -405.632663)
			(xy 467.633725 -405.539259) (xy 467.677942 -405.442454) (xy 467.715142 -405.342742) (xy 467.745135 -405.240631)
			(xy 467.767768 -405.136641) (xy 467.782928 -405.031301) (xy 467.790535 -404.925148) (xy 467.791038 -404.871936)
			(xy 467.791038 -82.82813) (xy 467.791541 -82.757757) (xy 467.799451 -82.617233) (xy 467.815226 -82.477373)
			(xy 467.838815 -82.338618) (xy 467.870145 -82.201402) (xy 467.909116 -82.066159) (xy 467.955608 -81.933313)
			(xy 468.009473 -81.803282) (xy 468.070541 -81.676474) (xy 468.138622 -81.553289) (xy 468.213501 -81.434114)
			(xy 468.294942 -81.319323) (xy 468.382689 -81.209278) (xy 468.476467 -81.104324) (xy 468.52586 -81.054194)
			(xy 470.854278 -78.725776) (xy 470.891569 -78.687813) (xy 470.961264 -78.607383) (xy 471.025045 -78.522187)
			(xy 471.082586 -78.432659) (xy 471.133596 -78.339255) (xy 471.177813 -78.24245) (xy 471.215013 -78.142738)
			(xy 471.245007 -78.040626) (xy 471.267641 -77.936636) (xy 471.2828 -77.831296) (xy 471.290407 -77.725143)
			(xy 471.290904 -77.67193) (xy 471.290904 -13.780008) (xy 471.290383 -13.724238) (xy 471.282048 -13.613011)
			(xy 471.265425 -13.502718) (xy 471.240606 -13.393975) (xy 471.20773 -13.287391) (xy 471.166981 -13.183562)
			(xy 471.118587 -13.083068) (xy 471.062818 -12.986472) (xy 470.999987 -12.894314) (xy 470.930444 -12.807108)
			(xy 470.854579 -12.725344) (xy 470.772816 -12.649477) (xy 470.685612 -12.579932) (xy 470.593455 -12.517099)
			(xy 470.49686 -12.461328) (xy 470.396367 -12.412932) (xy 470.292539 -12.372181) (xy 470.185956 -12.339303)
			(xy 470.077214 -12.314481) (xy 469.966921 -12.297855) (xy 469.855694 -12.289518) (xy 469.799924 -12.289028)
			(xy 458.20203 -12.289028) (xy 458.131647 -12.288544) (xy 457.991102 -12.280653) (xy 457.85122 -12.264894)
			(xy 457.712443 -12.241316) (xy 457.575205 -12.209994) (xy 457.43994 -12.171027) (xy 457.307072 -12.124536)
			(xy 457.177021 -12.070668) (xy 457.050194 -12.009593) (xy 456.926991 -11.941503) (xy 456.8078 -11.866612)
			(xy 456.692996 -11.785156) (xy 456.582939 -11.69739) (xy 456.477977 -11.603592) (xy 456.378439 -11.504056)
			(xy 456.284639 -11.399096) (xy 456.196872 -11.289041) (xy 456.115413 -11.174238) (xy 456.04052 -11.055048)
			(xy 455.972428 -10.931847) (xy 455.911351 -10.805021) (xy 455.857481 -10.674971) (xy 455.810987 -10.542104)
			(xy 455.772017 -10.406839) (xy 455.740693 -10.269603) (xy 455.717113 -10.130825) (xy 455.701351 -9.990944)
			(xy 455.693457 -9.850399) (xy 455.693018 -9.780016) (xy 455.693018 -0.559816) (xy 455.692533 -0.549805)
			(xy 455.684877 -0.531304) (xy 455.670724 -0.517142) (xy 455.652229 -0.509474) (xy 455.642218 -0.509016)
			(xy 388.161784 -0.509016) (xy 388.15178 -0.509507) (xy 388.133296 -0.51717) (xy 388.119152 -0.531323)
			(xy 388.111501 -0.549811) (xy 388.110984 -0.559816) (xy 388.110984 -5.169916) (xy 388.850131 -5.169916)
			(xy 388.854136 -5.082008) (xy 388.866119 -4.994828) (xy 388.885979 -4.909099) (xy 388.913554 -4.825531)
			(xy 388.948613 -4.744817) (xy 388.990866 -4.667625) (xy 389.039964 -4.594596) (xy 389.0955 -4.526334)
			(xy 389.157012 -4.463404) (xy 389.223993 -4.40633) (xy 389.295886 -4.355582) (xy 389.372095 -4.311582)
			(xy 389.45199 -4.274695) (xy 389.534909 -4.245226) (xy 389.620164 -4.223419) (xy 389.707048 -4.209455)
			(xy 389.794842 -4.203449) (xy 389.882819 -4.205453) (xy 389.970249 -4.215448) (xy 390.056408 -4.233352)
			(xy 390.140582 -4.259016) (xy 390.222073 -4.292229) (xy 390.300207 -4.332715) (xy 390.374335 -4.380137)
			(xy 390.443843 -4.434104) (xy 390.508157 -4.494169) (xy 390.566741 -4.559833) (xy 390.619112 -4.630552)
			(xy 390.664835 -4.70574) (xy 390.703532 -4.784775) (xy 390.734881 -4.867001) (xy 390.758623 -4.951737)
			(xy 390.765792 -4.990667) (xy 394.939038 -4.990667) (xy 394.939038 -4.936133) (xy 394.946799 -4.882155)
			(xy 394.962162 -4.82983) (xy 394.984815 -4.780224) (xy 395.014296 -4.734346) (xy 395.050007 -4.693131)
			(xy 395.091219 -4.657417) (xy 395.137094 -4.627931) (xy 395.186698 -4.605274) (xy 395.239021 -4.589906)
			(xy 395.292999 -4.582141) (xy 395.320266 -4.581652) (xy 396.183866 -4.581652) (xy 396.21114 -4.582085)
			(xy 396.265132 -4.589844) (xy 396.317471 -4.605208) (xy 396.36709 -4.627864) (xy 396.41298 -4.657352)
			(xy 396.454205 -4.693071) (xy 396.489928 -4.734293) (xy 396.51942 -4.78018) (xy 396.542081 -4.829797)
			(xy 396.557449 -4.882135) (xy 396.565212 -4.936126) (xy 396.565212 -4.99067) (xy 398.538915 -4.99067)
			(xy 398.538915 -4.93613) (xy 398.546678 -4.882144) (xy 398.562044 -4.829813) (xy 398.584701 -4.780201)
			(xy 398.614188 -4.734318) (xy 398.649905 -4.6931) (xy 398.691125 -4.657383) (xy 398.737008 -4.627897)
			(xy 398.78662 -4.605241) (xy 398.838952 -4.589876) (xy 398.892938 -4.582115) (xy 398.920208 -4.581652)
			(xy 399.783808 -4.581652) (xy 399.811078 -4.582111) (xy 399.865063 -4.589874) (xy 399.917393 -4.60524)
			(xy 399.967004 -4.627898) (xy 400.012886 -4.657385) (xy 400.054104 -4.693102) (xy 400.08982 -4.734321)
			(xy 400.119306 -4.780203) (xy 400.141962 -4.829814) (xy 400.157328 -4.882145) (xy 400.16509 -4.93613)
			(xy 400.16509 -4.990666) (xy 402.138938 -4.990666) (xy 402.138938 -4.936134) (xy 402.146698 -4.882157)
			(xy 402.162061 -4.829833) (xy 402.184712 -4.780228) (xy 402.214192 -4.734351) (xy 402.249901 -4.693136)
			(xy 402.291111 -4.657422) (xy 402.336984 -4.627936) (xy 402.386586 -4.605278) (xy 402.438908 -4.589909)
			(xy 402.492884 -4.582142) (xy 402.52015 -4.581652) (xy 403.38375 -4.581652) (xy 403.411024 -4.582084)
			(xy 403.465019 -4.589841) (xy 403.517359 -4.605203) (xy 403.56698 -4.627859) (xy 403.612872 -4.657346)
			(xy 403.6541 -4.693065) (xy 403.689824 -4.734288) (xy 403.719317 -4.780176) (xy 403.741979 -4.829794)
			(xy 403.757349 -4.882132) (xy 403.765112 -4.936126) (xy 403.765112 -4.990672) (xy 405.739016 -4.990672)
			(xy 405.739016 -4.936128) (xy 405.746779 -4.882139) (xy 405.762147 -4.829805) (xy 405.784807 -4.78019)
			(xy 405.814298 -4.734306) (xy 405.850019 -4.693086) (xy 405.891243 -4.65737) (xy 405.937131 -4.627885)
			(xy 405.986748 -4.605231) (xy 406.039084 -4.589869) (xy 406.093074 -4.582112) (xy 406.120346 -4.581652)
			(xy 406.983946 -4.581652) (xy 407.011214 -4.582114) (xy 407.065195 -4.589881) (xy 407.117521 -4.605251)
			(xy 407.167127 -4.62791) (xy 407.213004 -4.657399) (xy 407.254217 -4.693115) (xy 407.289929 -4.734333)
			(xy 407.319412 -4.780213) (xy 407.342065 -4.829822) (xy 407.357429 -4.88215) (xy 407.36519 -4.936132)
			(xy 407.36519 -4.990668) (xy 407.36519 -4.99067) (xy 414.849015 -4.99067) (xy 414.849015 -4.93613)
			(xy 414.856778 -4.882144) (xy 414.872144 -4.829812) (xy 414.894801 -4.7802) (xy 414.924289 -4.734318)
			(xy 414.960006 -4.693099) (xy 415.001226 -4.657383) (xy 415.047109 -4.627896) (xy 415.096722 -4.60524)
			(xy 415.149054 -4.589875) (xy 415.20304 -4.582115) (xy 415.23031 -4.581652) (xy 416.09391 -4.581652)
			(xy 416.12118 -4.582111) (xy 416.175164 -4.589874) (xy 416.227495 -4.605241) (xy 416.277105 -4.627899)
			(xy 416.322987 -4.657386) (xy 416.364205 -4.693102) (xy 416.39992 -4.734321) (xy 416.429406 -4.780203)
			(xy 416.452062 -4.829815) (xy 416.467428 -4.882145) (xy 416.47519 -4.93613) (xy 416.47519 -4.990666)
			(xy 418.449038 -4.990666) (xy 418.449038 -4.936134) (xy 418.456798 -4.882156) (xy 418.472161 -4.829833)
			(xy 418.494813 -4.780227) (xy 418.524293 -4.734351) (xy 418.560002 -4.693136) (xy 418.601212 -4.657422)
			(xy 418.647085 -4.627936) (xy 418.696688 -4.605278) (xy 418.749009 -4.589909) (xy 418.802986 -4.582142)
			(xy 418.830252 -4.581652) (xy 419.693852 -4.581652) (xy 419.721126 -4.582084) (xy 419.77512 -4.589841)
			(xy 419.827461 -4.605204) (xy 419.877082 -4.627859) (xy 419.922973 -4.657347) (xy 419.9642 -4.693066)
			(xy 419.999924 -4.734288) (xy 420.029418 -4.780176) (xy 420.052079 -4.829794) (xy 420.067449 -4.882133)
			(xy 420.075212 -4.936126) (xy 420.075212 -4.990672) (xy 426.059016 -4.990672) (xy 426.059016 -4.936128)
			(xy 426.066779 -4.882139) (xy 426.082147 -4.829805) (xy 426.104807 -4.78019) (xy 426.134298 -4.734306)
			(xy 426.170019 -4.693086) (xy 426.211243 -4.65737) (xy 426.257131 -4.627885) (xy 426.306748 -4.605231)
			(xy 426.359084 -4.589869) (xy 426.413074 -4.582112) (xy 426.440346 -4.581652) (xy 427.303946 -4.581652)
			(xy 427.331214 -4.582114) (xy 427.385195 -4.589881) (xy 427.437521 -4.605251) (xy 427.487127 -4.62791)
			(xy 427.533004 -4.657399) (xy 427.574217 -4.693115) (xy 427.609929 -4.734333) (xy 427.639412 -4.780213)
			(xy 427.662065 -4.829822) (xy 427.677429 -4.88215) (xy 427.68519 -4.936132) (xy 427.68519 -4.990668)
			(xy 429.659038 -4.990668) (xy 429.659038 -4.936132) (xy 429.666799 -4.882152) (xy 429.682164 -4.829825)
			(xy 429.704818 -4.780217) (xy 429.734302 -4.734339) (xy 429.770014 -4.693123) (xy 429.811229 -4.657409)
			(xy 429.857107 -4.627924) (xy 429.906714 -4.605268) (xy 429.95904 -4.589902) (xy 430.01302 -4.582139)
			(xy 430.040288 -4.581652) (xy 430.903888 -4.581652) (xy 430.931161 -4.582087) (xy 430.985151 -4.589848)
			(xy 431.037487 -4.605214) (xy 431.087103 -4.627871) (xy 431.13299 -4.65736) (xy 431.174213 -4.693078)
			(xy 431.209933 -4.7343) (xy 431.239423 -4.780186) (xy 431.262082 -4.829802) (xy 431.27745 -4.882138)
			(xy 431.285212 -4.936127) (xy 431.285212 -4.990673) (xy 431.27745 -5.044662) (xy 431.262082 -5.096998)
			(xy 431.239423 -5.146614) (xy 431.209933 -5.1925) (xy 431.174213 -5.233722) (xy 431.13299 -5.26944)
			(xy 431.087103 -5.298929) (xy 431.037487 -5.321586) (xy 430.985151 -5.336952) (xy 430.931161 -5.344713)
			(xy 430.903888 -5.345176) (xy 430.040288 -5.345176) (xy 430.01302 -5.344661) (xy 429.95904 -5.336898)
			(xy 429.906714 -5.321532) (xy 429.857107 -5.298876) (xy 429.811229 -5.269391) (xy 429.770014 -5.233677)
			(xy 429.734302 -5.192461) (xy 429.704818 -5.146583) (xy 429.682164 -5.096975) (xy 429.666799 -5.044648)
			(xy 429.659038 -4.990668) (xy 427.68519 -4.990668) (xy 427.677429 -5.04465) (xy 427.662065 -5.096978)
			(xy 427.639412 -5.146587) (xy 427.609929 -5.192467) (xy 427.574217 -5.233685) (xy 427.533004 -5.269401)
			(xy 427.487127 -5.29889) (xy 427.437521 -5.321549) (xy 427.385195 -5.336919) (xy 427.331214 -5.344686)
			(xy 427.303946 -5.345176) (xy 426.440346 -5.345176) (xy 426.413074 -5.344688) (xy 426.359084 -5.336931)
			(xy 426.306748 -5.321569) (xy 426.257131 -5.298915) (xy 426.211243 -5.26943) (xy 426.170019 -5.233714)
			(xy 426.134298 -5.192494) (xy 426.104807 -5.14661) (xy 426.082147 -5.096995) (xy 426.066779 -5.044661)
			(xy 426.059016 -4.990672) (xy 420.075212 -4.990672) (xy 420.075212 -4.990674) (xy 420.067449 -5.044667)
			(xy 420.052079 -5.097006) (xy 420.029418 -5.146624) (xy 419.999924 -5.192512) (xy 419.9642 -5.233734)
			(xy 419.922973 -5.269453) (xy 419.877082 -5.298941) (xy 419.827461 -5.321596) (xy 419.77512 -5.336959)
			(xy 419.721126 -5.344716) (xy 419.693852 -5.345176) (xy 418.830252 -5.345176) (xy 418.802986 -5.344658)
			(xy 418.749009 -5.336891) (xy 418.696688 -5.321522) (xy 418.647085 -5.298864) (xy 418.601212 -5.269378)
			(xy 418.560002 -5.233664) (xy 418.524293 -5.192449) (xy 418.494813 -5.146573) (xy 418.472161 -5.096967)
			(xy 418.456798 -5.044644) (xy 418.449038 -4.990666) (xy 416.47519 -4.990666) (xy 416.47519 -4.99067)
			(xy 416.467428 -5.044655) (xy 416.452062 -5.096985) (xy 416.429406 -5.146597) (xy 416.39992 -5.192479)
			(xy 416.364205 -5.233698) (xy 416.322987 -5.269414) (xy 416.277105 -5.298901) (xy 416.227495 -5.321559)
			(xy 416.175164 -5.336926) (xy 416.12118 -5.344689) (xy 416.09391 -5.345176) (xy 415.23031 -5.345176)
			(xy 415.20304 -5.344685) (xy 415.149054 -5.336925) (xy 415.096722 -5.32156) (xy 415.047109 -5.298904)
			(xy 415.001226 -5.269417) (xy 414.960006 -5.233701) (xy 414.924289 -5.192482) (xy 414.894801 -5.1466)
			(xy 414.872144 -5.096988) (xy 414.856778 -5.044656) (xy 414.849015 -4.99067) (xy 407.36519 -4.99067)
			(xy 407.357429 -5.04465) (xy 407.342065 -5.096978) (xy 407.319412 -5.146587) (xy 407.289929 -5.192467)
			(xy 407.254217 -5.233685) (xy 407.213004 -5.269401) (xy 407.167127 -5.29889) (xy 407.117521 -5.321549)
			(xy 407.065195 -5.336919) (xy 407.011214 -5.344686) (xy 406.983946 -5.345176) (xy 406.120346 -5.345176)
			(xy 406.093074 -5.344688) (xy 406.039084 -5.336931) (xy 405.986748 -5.321569) (xy 405.937131 -5.298915)
			(xy 405.891243 -5.26943) (xy 405.850019 -5.233714) (xy 405.814298 -5.192494) (xy 405.784807 -5.14661)
			(xy 405.762147 -5.096995) (xy 405.746779 -5.044661) (xy 405.739016 -4.990672) (xy 403.765112 -4.990672)
			(xy 403.765112 -4.990674) (xy 403.757349 -5.044668) (xy 403.741979 -5.097006) (xy 403.719317 -5.146624)
			(xy 403.689824 -5.192512) (xy 403.6541 -5.233735) (xy 403.612872 -5.269454) (xy 403.56698 -5.298941)
			(xy 403.517359 -5.321597) (xy 403.465019 -5.336959) (xy 403.411024 -5.344716) (xy 403.38375 -5.345176)
			(xy 402.52015 -5.345176) (xy 402.492884 -5.344658) (xy 402.438908 -5.336891) (xy 402.386586 -5.321522)
			(xy 402.336984 -5.298864) (xy 402.291111 -5.269378) (xy 402.249901 -5.233664) (xy 402.214192 -5.192449)
			(xy 402.184712 -5.146572) (xy 402.162061 -5.096967) (xy 402.146698 -5.044643) (xy 402.138938 -4.990666)
			(xy 400.16509 -4.990666) (xy 400.16509 -4.99067) (xy 400.157328 -5.044655) (xy 400.141962 -5.096986)
			(xy 400.119306 -5.146597) (xy 400.08982 -5.192479) (xy 400.054104 -5.233698) (xy 400.012886 -5.269415)
			(xy 399.967004 -5.298902) (xy 399.917393 -5.32156) (xy 399.865063 -5.336926) (xy 399.811078 -5.344689)
			(xy 399.783808 -5.345176) (xy 398.920208 -5.345176) (xy 398.892938 -5.344685) (xy 398.838952 -5.336924)
			(xy 398.78662 -5.321559) (xy 398.737008 -5.298903) (xy 398.691125 -5.269417) (xy 398.649905 -5.2337)
			(xy 398.614188 -5.192482) (xy 398.584701 -5.146599) (xy 398.562044 -5.096987) (xy 398.546678 -5.044656)
			(xy 398.538915 -4.99067) (xy 396.565212 -4.99067) (xy 396.565212 -4.990674) (xy 396.557449 -5.044665)
			(xy 396.542081 -5.097003) (xy 396.51942 -5.14662) (xy 396.489928 -5.192507) (xy 396.454205 -5.233729)
			(xy 396.41298 -5.269448) (xy 396.36709 -5.298936) (xy 396.317471 -5.321592) (xy 396.265132 -5.336956)
			(xy 396.21114 -5.344715) (xy 396.183866 -5.345176) (xy 395.320266 -5.345176) (xy 395.292999 -5.344659)
			(xy 395.239021 -5.336894) (xy 395.186698 -5.321526) (xy 395.137094 -5.298869) (xy 395.091219 -5.269383)
			(xy 395.050007 -5.233669) (xy 395.014296 -5.192454) (xy 394.984815 -5.146576) (xy 394.962162 -5.09697)
			(xy 394.946799 -5.044645) (xy 394.939038 -4.990667) (xy 390.765792 -4.990667) (xy 390.774561 -5.038281)
			(xy 390.782563 -5.125916) (xy 390.783064 -5.169916) (xy 390.782563 -5.213916) (xy 390.774561 -5.301551)
			(xy 390.758623 -5.388095) (xy 390.734881 -5.472831) (xy 390.703532 -5.555057) (xy 390.664835 -5.634092)
			(xy 390.619112 -5.70928) (xy 390.566741 -5.779999) (xy 390.508157 -5.845663) (xy 390.443843 -5.905728)
			(xy 390.374335 -5.959695) (xy 390.300207 -6.007117) (xy 390.222073 -6.047603) (xy 390.140582 -6.080816)
			(xy 390.056408 -6.10648) (xy 389.970249 -6.124384) (xy 389.882819 -6.134379) (xy 389.794842 -6.136383)
			(xy 389.707048 -6.130377) (xy 389.620164 -6.116413) (xy 389.534909 -6.094606) (xy 389.45199 -6.065137)
			(xy 389.372095 -6.02825) (xy 389.295886 -5.98425) (xy 389.223993 -5.933502) (xy 389.157012 -5.876428)
			(xy 389.0955 -5.813498) (xy 389.039964 -5.745236) (xy 388.990866 -5.672207) (xy 388.948613 -5.595015)
			(xy 388.913554 -5.514301) (xy 388.885979 -5.430733) (xy 388.866119 -5.345004) (xy 388.854136 -5.257824)
			(xy 388.850131 -5.169916) (xy 388.110984 -5.169916) (xy 388.110984 -6.169914) (xy 453.015103 -6.169914)
			(xy 453.019108 -6.082006) (xy 453.031091 -5.994826) (xy 453.050951 -5.909097) (xy 453.078526 -5.825529)
			(xy 453.113585 -5.744815) (xy 453.155838 -5.667623) (xy 453.204936 -5.594594) (xy 453.260472 -5.526332)
			(xy 453.321984 -5.463402) (xy 453.388965 -5.406328) (xy 453.460858 -5.35558) (xy 453.537067 -5.31158)
			(xy 453.616962 -5.274693) (xy 453.699881 -5.245224) (xy 453.785136 -5.223417) (xy 453.87202 -5.209453)
			(xy 453.959814 -5.203447) (xy 454.047791 -5.205451) (xy 454.135221 -5.215446) (xy 454.22138 -5.23335)
			(xy 454.305554 -5.259014) (xy 454.387045 -5.292227) (xy 454.465179 -5.332713) (xy 454.539307 -5.380135)
			(xy 454.608815 -5.434102) (xy 454.673129 -5.494167) (xy 454.731713 -5.559831) (xy 454.784084 -5.63055)
			(xy 454.829807 -5.705738) (xy 454.868504 -5.784773) (xy 454.899853 -5.866999) (xy 454.923595 -5.951735)
			(xy 454.939533 -6.038279) (xy 454.947535 -6.125914) (xy 454.948036 -6.169914) (xy 454.947535 -6.213914)
			(xy 454.939533 -6.301549) (xy 454.923595 -6.388093) (xy 454.899853 -6.472829) (xy 454.868504 -6.555055)
			(xy 454.829807 -6.63409) (xy 454.784084 -6.709278) (xy 454.731713 -6.779997) (xy 454.673129 -6.845661)
			(xy 454.608815 -6.905726) (xy 454.539307 -6.959693) (xy 454.465179 -7.007115) (xy 454.387045 -7.047601)
			(xy 454.305554 -7.080814) (xy 454.22138 -7.106478) (xy 454.135221 -7.124382) (xy 454.047791 -7.134377)
			(xy 453.959814 -7.136381) (xy 453.87202 -7.130375) (xy 453.785136 -7.116411) (xy 453.699881 -7.094604)
			(xy 453.616962 -7.065135) (xy 453.537067 -7.028248) (xy 453.460858 -6.984248) (xy 453.388965 -6.9335)
			(xy 453.321984 -6.876426) (xy 453.260472 -6.813496) (xy 453.204936 -6.745234) (xy 453.155838 -6.672205)
			(xy 453.113585 -6.595013) (xy 453.078526 -6.514299) (xy 453.050951 -6.430731) (xy 453.031091 -6.345002)
			(xy 453.019108 -6.257822) (xy 453.015103 -6.169914) (xy 388.110984 -6.169914) (xy 388.110984 -6.752472)
			(xy 393.134283 -6.752472) (xy 393.134283 -6.697928) (xy 393.142045 -6.643939) (xy 393.157412 -6.591604)
			(xy 393.18007 -6.541988) (xy 393.209559 -6.496103) (xy 393.245278 -6.454881) (xy 393.286499 -6.419161)
			(xy 393.332385 -6.389672) (xy 393.382 -6.367013) (xy 393.434335 -6.351646) (xy 393.488324 -6.343883)
			(xy 393.515596 -6.343396) (xy 394.379196 -6.343396) (xy 394.406464 -6.343943) (xy 394.460446 -6.351704)
			(xy 394.512773 -6.367068) (xy 394.562381 -6.389723) (xy 394.60826 -6.419207) (xy 394.649476 -6.454921)
			(xy 394.68519 -6.496136) (xy 394.714675 -6.542015) (xy 394.73733 -6.591623) (xy 394.752695 -6.643951)
			(xy 394.760457 -6.697932) (xy 394.760457 -6.752468) (xy 394.760456 -6.752476) (xy 396.73416 -6.752476)
			(xy 396.73416 -6.697924) (xy 396.741924 -6.643928) (xy 396.757294 -6.591587) (xy 396.779956 -6.541966)
			(xy 396.809451 -6.496075) (xy 396.845176 -6.454849) (xy 396.886405 -6.419128) (xy 396.932299 -6.389638)
			(xy 396.981922 -6.36698) (xy 397.034265 -6.351616) (xy 397.088262 -6.343857) (xy 397.115538 -6.343396)
			(xy 397.979138 -6.343396) (xy 398.006403 -6.343969) (xy 398.060376 -6.351734) (xy 398.112695 -6.367101)
			(xy 398.162295 -6.389757) (xy 398.208166 -6.419241) (xy 398.249375 -6.454952) (xy 398.285082 -6.496164)
			(xy 398.314561 -6.542038) (xy 398.337212 -6.59164) (xy 398.352574 -6.643961) (xy 398.360334 -6.697935)
			(xy 398.360334 -6.752465) (xy 398.360333 -6.752471) (xy 400.334182 -6.752471) (xy 400.334182 -6.697929)
			(xy 400.341944 -6.643941) (xy 400.35731 -6.591607) (xy 400.379968 -6.541993) (xy 400.409455 -6.496108)
			(xy 400.445172 -6.454886) (xy 400.486392 -6.419167) (xy 400.532275 -6.389677) (xy 400.581888 -6.367017)
			(xy 400.634221 -6.351649) (xy 400.688209 -6.343884) (xy 400.71548 -6.343396) (xy 401.57908 -6.343396)
			(xy 401.606349 -6.343942) (xy 401.660332 -6.351701) (xy 401.712661 -6.367064) (xy 401.762272 -6.389718)
			(xy 401.808153 -6.419202) (xy 401.849371 -6.454915) (xy 401.885086 -6.496131) (xy 401.914573 -6.542011)
			(xy 401.937229 -6.59162) (xy 401.952595 -6.643948) (xy 401.960357 -6.697931) (xy 401.960357 -6.752469)
			(xy 401.960357 -6.752471) (xy 403.934382 -6.752471) (xy 403.934382 -6.697929) (xy 403.942144 -6.643941)
			(xy 403.95751 -6.591608) (xy 403.980167 -6.541994) (xy 404.009654 -6.496109) (xy 404.045371 -6.454888)
			(xy 404.08659 -6.419168) (xy 404.132473 -6.389679) (xy 404.182085 -6.367019) (xy 404.234418 -6.351649)
			(xy 404.288405 -6.343884) (xy 404.315676 -6.343396) (xy 405.179276 -6.343396) (xy 405.206545 -6.343942)
			(xy 405.260529 -6.3517) (xy 405.312858 -6.367063) (xy 405.362469 -6.389716) (xy 405.408351 -6.4192)
			(xy 405.449569 -6.454914) (xy 405.485285 -6.49613) (xy 405.514772 -6.54201) (xy 405.537429 -6.591619)
			(xy 405.552795 -6.643948) (xy 405.560557 -6.697931) (xy 405.560557 -6.752469) (xy 405.560556 -6.752476)
			(xy 413.04426 -6.752476) (xy 413.04426 -6.697924) (xy 413.052024 -6.643928) (xy 413.067394 -6.591586)
			(xy 413.090057 -6.541965) (xy 413.119551 -6.496074) (xy 413.155277 -6.454849) (xy 413.196506 -6.419127)
			(xy 413.2424 -6.389638) (xy 413.292024 -6.36698) (xy 413.344367 -6.351615) (xy 413.398364 -6.343857)
			(xy 413.42564 -6.343396) (xy 414.28924 -6.343396) (xy 414.316504 -6.343969) (xy 414.370478 -6.351734)
			(xy 414.422797 -6.367102) (xy 414.472397 -6.389758) (xy 414.518267 -6.419241) (xy 414.559476 -6.454953)
			(xy 414.595183 -6.496165) (xy 414.624662 -6.542039) (xy 414.647312 -6.591641) (xy 414.662674 -6.643961)
			(xy 414.670434 -6.697935) (xy 414.670434 -6.752465) (xy 414.670433 -6.752472) (xy 416.644282 -6.752472)
			(xy 416.644282 -6.697928) (xy 416.652045 -6.64394) (xy 416.667411 -6.591607) (xy 416.690068 -6.541992)
			(xy 416.719555 -6.496107) (xy 416.755273 -6.454885) (xy 416.796493 -6.419166) (xy 416.842376 -6.389677)
			(xy 416.89199 -6.367017) (xy 416.944323 -6.351648) (xy 416.99831 -6.343884) (xy 417.025582 -6.343396)
			(xy 417.889182 -6.343396) (xy 417.916451 -6.343942) (xy 417.970434 -6.351701) (xy 418.022763 -6.367064)
			(xy 418.072373 -6.389718) (xy 418.118254 -6.419202) (xy 418.159471 -6.454916) (xy 418.195187 -6.496132)
			(xy 418.224673 -6.542011) (xy 418.247329 -6.59162) (xy 418.262695 -6.643949) (xy 418.270457 -6.697931)
			(xy 418.270457 -6.752469) (xy 418.270457 -6.752471) (xy 424.254382 -6.752471) (xy 424.254382 -6.697929)
			(xy 424.262144 -6.643941) (xy 424.27751 -6.591608) (xy 424.300167 -6.541994) (xy 424.329654 -6.496109)
			(xy 424.365371 -6.454888) (xy 424.40659 -6.419168) (xy 424.452473 -6.389679) (xy 424.502085 -6.367019)
			(xy 424.554418 -6.351649) (xy 424.608405 -6.343884) (xy 424.635676 -6.343396) (xy 425.499276 -6.343396)
			(xy 425.526545 -6.343942) (xy 425.580529 -6.3517) (xy 425.632858 -6.367063) (xy 425.682469 -6.389716)
			(xy 425.728351 -6.4192) (xy 425.769569 -6.454914) (xy 425.805285 -6.49613) (xy 425.834772 -6.54201)
			(xy 425.857429 -6.591619) (xy 425.872795 -6.643948) (xy 425.880557 -6.697931) (xy 425.880557 -6.752469)
			(xy 425.880556 -6.752475) (xy 427.85426 -6.752475) (xy 427.85426 -6.697925) (xy 427.862023 -6.643931)
			(xy 427.877392 -6.591591) (xy 427.900053 -6.541971) (xy 427.929546 -6.496082) (xy 427.965269 -6.454856)
			(xy 428.006496 -6.419135) (xy 428.052387 -6.389645) (xy 428.102008 -6.366986) (xy 428.154348 -6.351619)
			(xy 428.208343 -6.343858) (xy 428.235618 -6.343396) (xy 429.099218 -6.343396) (xy 429.126484 -6.343968)
			(xy 429.180459 -6.35173) (xy 429.232781 -6.367096) (xy 429.282383 -6.38975) (xy 429.328257 -6.419234)
			(xy 429.369468 -6.454945) (xy 429.405177 -6.496157) (xy 429.434658 -6.542032) (xy 429.457311 -6.591636)
			(xy 429.472673 -6.643958) (xy 429.480434 -6.697934) (xy 429.480434 -6.752466) (xy 429.479412 -6.759571)
			(xy 431.465194 -6.759571) (xy 431.465194 -6.705029) (xy 431.472956 -6.651043) (xy 431.488322 -6.598711)
			(xy 431.510979 -6.549098) (xy 431.540465 -6.503214) (xy 431.576181 -6.461994) (xy 431.6174 -6.426276)
			(xy 431.663282 -6.396787) (xy 431.712894 -6.374128) (xy 431.765225 -6.35876) (xy 431.819211 -6.350996)
			(xy 431.846482 -6.350508) (xy 432.710082 -6.350508) (xy 432.737352 -6.35103) (xy 432.791336 -6.35879)
			(xy 432.843667 -6.374153) (xy 432.893279 -6.396808) (xy 432.939161 -6.426293) (xy 432.98038 -6.462007)
			(xy 433.016096 -6.503225) (xy 433.045583 -6.549106) (xy 433.068241 -6.598716) (xy 433.083607 -6.651046)
			(xy 433.091369 -6.70503) (xy 433.091369 -6.75247) (xy 445.449182 -6.75247) (xy 445.449182 -6.69793)
			(xy 445.456944 -6.643944) (xy 445.472308 -6.591613) (xy 445.494963 -6.542001) (xy 445.524448 -6.496117)
			(xy 445.560162 -6.454896) (xy 445.601379 -6.419177) (xy 445.647258 -6.389686) (xy 445.696868 -6.367025)
			(xy 445.749198 -6.351654) (xy 445.803182 -6.343886) (xy 445.830452 -6.343396) (xy 446.694052 -6.343396)
			(xy 446.721322 -6.34394) (xy 446.775308 -6.351696) (xy 446.827641 -6.367056) (xy 446.877255 -6.389709)
			(xy 446.923139 -6.419192) (xy 446.964361 -6.454905) (xy 447.00008 -6.496122) (xy 447.029568 -6.542003)
			(xy 447.052227 -6.591614) (xy 447.067594 -6.643945) (xy 447.075356 -6.69793) (xy 447.075356 -6.75247)
			(xy 447.067594 -6.806455) (xy 447.052227 -6.858786) (xy 447.029568 -6.908397) (xy 447.000079 -6.954278)
			(xy 446.964361 -6.995495) (xy 446.923139 -7.031208) (xy 446.877255 -7.060691) (xy 446.827641 -7.083344)
			(xy 446.775308 -7.098704) (xy 446.721322 -7.10646) (xy 446.694052 -7.10692) (xy 445.830452 -7.10692)
			(xy 445.803182 -7.106514) (xy 445.749198 -7.098746) (xy 445.696868 -7.083375) (xy 445.647258 -7.060714)
			(xy 445.601378 -7.031223) (xy 445.560162 -6.995504) (xy 445.524448 -6.954283) (xy 445.494963 -6.908399)
			(xy 445.472308 -6.858787) (xy 445.456944 -6.806455) (xy 445.449182 -6.75247) (xy 433.091369 -6.75247)
			(xy 433.091369 -6.75957) (xy 433.083607 -6.813554) (xy 433.068241 -6.865884) (xy 433.045583 -6.915494)
			(xy 433.016096 -6.961375) (xy 432.98038 -7.002593) (xy 432.939161 -7.038307) (xy 432.893279 -7.067792)
			(xy 432.843667 -7.090447) (xy 432.791336 -7.10581) (xy 432.737352 -7.11357) (xy 432.710082 -7.114032)
			(xy 431.846482 -7.114032) (xy 431.819211 -7.113604) (xy 431.765225 -7.10584) (xy 431.712894 -7.090472)
			(xy 431.663282 -7.067813) (xy 431.6174 -7.038324) (xy 431.576181 -7.002606) (xy 431.540465 -6.961386)
			(xy 431.510979 -6.915502) (xy 431.488322 -6.865889) (xy 431.472956 -6.813557) (xy 431.465194 -6.759571)
			(xy 429.479412 -6.759571) (xy 429.472673 -6.806442) (xy 429.457311 -6.858764) (xy 429.434658 -6.908368)
			(xy 429.405177 -6.954243) (xy 429.369468 -6.995455) (xy 429.328257 -7.031166) (xy 429.282383 -7.06065)
			(xy 429.232781 -7.083304) (xy 429.180459 -7.09867) (xy 429.126484 -7.106432) (xy 429.099218 -7.10692)
			(xy 428.235618 -7.10692) (xy 428.208343 -7.106542) (xy 428.154348 -7.098781) (xy 428.102008 -7.083414)
			(xy 428.052387 -7.060755) (xy 428.006496 -7.031265) (xy 427.965269 -6.995544) (xy 427.929546 -6.954318)
			(xy 427.900053 -6.908429) (xy 427.877392 -6.858809) (xy 427.862023 -6.806469) (xy 427.85426 -6.752475)
			(xy 425.880556 -6.752475) (xy 425.872795 -6.806452) (xy 425.857429 -6.858781) (xy 425.834772 -6.90839)
			(xy 425.805285 -6.95427) (xy 425.769569 -6.995486) (xy 425.728351 -7.0312) (xy 425.682469 -7.060684)
			(xy 425.632858 -7.083337) (xy 425.580529 -7.0987) (xy 425.526545 -7.106458) (xy 425.499276 -7.10692)
			(xy 424.635676 -7.10692) (xy 424.608405 -7.106516) (xy 424.554418 -7.098751) (xy 424.502085 -7.083381)
			(xy 424.452473 -7.060721) (xy 424.40659 -7.031232) (xy 424.365371 -6.995512) (xy 424.329654 -6.954291)
			(xy 424.300167 -6.908406) (xy 424.27751 -6.858792) (xy 424.262144 -6.806459) (xy 424.254382 -6.752471)
			(xy 418.270457 -6.752471) (xy 418.262695 -6.806451) (xy 418.247329 -6.85878) (xy 418.224673 -6.908389)
			(xy 418.195187 -6.954268) (xy 418.159471 -6.995484) (xy 418.118254 -7.031198) (xy 418.072373 -7.060682)
			(xy 418.022763 -7.083336) (xy 417.970434 -7.098699) (xy 417.916451 -7.106458) (xy 417.889182 -7.10692)
			(xy 417.025582 -7.10692) (xy 416.99831 -7.106516) (xy 416.944323 -7.098752) (xy 416.89199 -7.083383)
			(xy 416.842376 -7.060723) (xy 416.796493 -7.031234) (xy 416.755273 -6.995515) (xy 416.719555 -6.954293)
			(xy 416.690068 -6.908408) (xy 416.667411 -6.858793) (xy 416.652045 -6.806459) (xy 416.644282 -6.752472)
			(xy 414.670433 -6.752472) (xy 414.662674 -6.806439) (xy 414.647312 -6.858759) (xy 414.624662 -6.908361)
			(xy 414.595183 -6.954235) (xy 414.559476 -6.995447) (xy 414.518267 -7.031159) (xy 414.472397 -7.060642)
			(xy 414.422797 -7.083298) (xy 414.370478 -7.098666) (xy 414.316505 -7.106431) (xy 414.28924 -7.10692)
			(xy 413.42564 -7.10692) (xy 413.398364 -7.106543) (xy 413.344367 -7.098785) (xy 413.292024 -7.08342)
			(xy 413.2424 -7.060762) (xy 413.196506 -7.031273) (xy 413.155277 -6.995551) (xy 413.119551 -6.954326)
			(xy 413.090057 -6.908435) (xy 413.067394 -6.858814) (xy 413.052024 -6.806472) (xy 413.04426 -6.752476)
			(xy 405.560556 -6.752476) (xy 405.552795 -6.806452) (xy 405.537429 -6.858781) (xy 405.514772 -6.90839)
			(xy 405.485285 -6.95427) (xy 405.449569 -6.995486) (xy 405.408351 -7.0312) (xy 405.362469 -7.060684)
			(xy 405.312858 -7.083337) (xy 405.260529 -7.0987) (xy 405.206545 -7.106458) (xy 405.179276 -7.10692)
			(xy 404.315676 -7.10692) (xy 404.288405 -7.106516) (xy 404.234418 -7.098751) (xy 404.182085 -7.083381)
			(xy 404.132473 -7.060721) (xy 404.08659 -7.031232) (xy 404.045371 -6.995512) (xy 404.009654 -6.954291)
			(xy 403.980167 -6.908406) (xy 403.95751 -6.858792) (xy 403.942144 -6.806459) (xy 403.934382 -6.752471)
			(xy 401.960357 -6.752471) (xy 401.952595 -6.806452) (xy 401.937229 -6.85878) (xy 401.914573 -6.908389)
			(xy 401.885086 -6.954269) (xy 401.849371 -6.995485) (xy 401.808153 -7.031198) (xy 401.762272 -7.060682)
			(xy 401.712661 -7.083336) (xy 401.660332 -7.098699) (xy 401.606349 -7.106458) (xy 401.57908 -7.10692)
			(xy 400.71548 -7.10692) (xy 400.688209 -7.106516) (xy 400.634221 -7.098751) (xy 400.581888 -7.083383)
			(xy 400.532275 -7.060723) (xy 400.486392 -7.031233) (xy 400.445172 -6.995514) (xy 400.409455 -6.954292)
			(xy 400.379968 -6.908407) (xy 400.35731 -6.858793) (xy 400.341944 -6.806459) (xy 400.334182 -6.752471)
			(xy 398.360333 -6.752471) (xy 398.352574 -6.806439) (xy 398.337212 -6.85876) (xy 398.314561 -6.908362)
			(xy 398.285082 -6.954236) (xy 398.249375 -6.995448) (xy 398.208166 -7.031159) (xy 398.162295 -7.060643)
			(xy 398.112695 -7.083299) (xy 398.060376 -7.098666) (xy 398.006403 -7.106431) (xy 397.979138 -7.10692)
			(xy 397.115538 -7.10692) (xy 397.088262 -7.106543) (xy 397.034265 -7.098784) (xy 396.981922 -7.08342)
			(xy 396.932299 -7.060762) (xy 396.886405 -7.031272) (xy 396.845176 -6.995551) (xy 396.809451 -6.954325)
			(xy 396.779956 -6.908434) (xy 396.757294 -6.858813) (xy 396.741924 -6.806472) (xy 396.73416 -6.752476)
			(xy 394.760456 -6.752476) (xy 394.752695 -6.806449) (xy 394.73733 -6.858777) (xy 394.714675 -6.908385)
			(xy 394.68519 -6.954264) (xy 394.649476 -6.995479) (xy 394.60826 -7.031193) (xy 394.562381 -7.060677)
			(xy 394.512773 -7.083332) (xy 394.460446 -7.098696) (xy 394.406464 -7.106457) (xy 394.379196 -7.10692)
			(xy 393.515596 -7.10692) (xy 393.488324 -7.106517) (xy 393.434335 -7.098754) (xy 393.382 -7.083387)
			(xy 393.332385 -7.060728) (xy 393.286499 -7.031239) (xy 393.245278 -6.995519) (xy 393.209559 -6.954297)
			(xy 393.18007 -6.908412) (xy 393.157412 -6.858796) (xy 393.142045 -6.806461) (xy 393.134283 -6.752472)
			(xy 388.110984 -6.752472) (xy 388.110984 -9.780016) (xy 388.110499 -9.850398) (xy 388.102605 -9.99094)
			(xy 388.086844 -10.130819) (xy 388.063264 -10.269594) (xy 388.03194 -10.406828) (xy 387.992971 -10.54209)
			(xy 387.946478 -10.674954) (xy 387.892609 -10.805003) (xy 387.831533 -10.931826) (xy 387.763442 -11.055026)
			(xy 387.68855 -11.174213) (xy 387.607093 -11.289014) (xy 387.519328 -11.399067) (xy 387.425529 -11.504025)
			(xy 387.325993 -11.60356) (xy 387.221033 -11.697356) (xy 387.110979 -11.78512) (xy 386.996176 -11.866575)
			(xy 386.876988 -11.941465) (xy 386.753787 -12.009554) (xy 386.626963 -12.070627) (xy 386.496913 -12.124494)
			(xy 386.364048 -12.170984) (xy 386.228785 -12.209951) (xy 386.091551 -12.241273) (xy 385.952775 -12.26485)
			(xy 385.812896 -12.280609) (xy 385.672354 -12.2885) (xy 385.601972 -12.289028) (xy 260.800088 -12.289028)
			(xy 260.744319 -12.28955) (xy 260.633094 -12.297886) (xy 260.522803 -12.314511) (xy 260.414062 -12.339331)
			(xy 260.30748 -12.372208) (xy 260.234662 -12.400788) (xy 436.813452 -12.400788) (xy 436.813941 -12.359678)
			(xy 436.821529 -12.27781) (xy 436.83664 -12.196991) (xy 436.859145 -12.117912) (xy 436.888851 -12.041247)
			(xy 436.925505 -11.96765) (xy 436.968795 -11.89775) (xy 437.01835 -11.832142) (xy 437.073748 -11.771388)
			(xy 437.134516 -11.716006) (xy 437.200136 -11.666467) (xy 437.270047 -11.623195) (xy 437.343653 -11.58656)
			(xy 437.420326 -11.556873) (xy 437.499411 -11.534389) (xy 437.580234 -11.519298) (xy 437.662104 -11.511731)
			(xy 437.703214 -11.51128) (xy 437.747029 -11.511772) (xy 437.83424 -11.520318) (xy 437.920187 -11.537406)
			(xy 438.004035 -11.562868) (xy 438.084971 -11.596458) (xy 438.123838 -11.61669) (xy 438.135191 -11.622017)
			(xy 438.160237 -11.622017) (xy 438.17159 -11.61669) (xy 438.210465 -11.596477) (xy 438.291405 -11.562905)
			(xy 438.375252 -11.537448) (xy 438.461195 -11.520353) (xy 438.548401 -11.511784) (xy 438.592214 -11.51128)
			(xy 438.636029 -11.511772) (xy 438.72324 -11.520318) (xy 438.809187 -11.537406) (xy 438.893035 -11.562868)
			(xy 438.973971 -11.596458) (xy 439.012838 -11.61669) (xy 439.024191 -11.622017) (xy 439.049237 -11.622017)
			(xy 439.06059 -11.61669) (xy 439.099465 -11.596477) (xy 439.180405 -11.562905) (xy 439.264252 -11.537448)
			(xy 439.350195 -11.520353) (xy 439.437401 -11.511784) (xy 439.481214 -11.51128) (xy 439.521951 -11.511719)
			(xy 439.603086 -11.519152) (xy 439.683202 -11.533973) (xy 439.761626 -11.556057) (xy 439.837703 -11.585219)
			(xy 439.910794 -11.621216) (xy 439.94578 -11.64209) (xy 439.954798 -11.647053) (xy 439.975154 -11.650004)
			(xy 439.995036 -11.644737) (xy 440.003438 -11.638788) (xy 440.091322 -11.570462) (xy 440.10072 -11.54049)
			(xy 440.095894 -11.52525) (xy 440.083229 -11.482506) (xy 440.065483 -11.395136) (xy 440.056563 -11.306429)
			(xy 440.056016 -11.261852) (xy 440.056016 -11.26109) (xy 440.056438 -11.22287) (xy 440.062998 -11.146712)
			(xy 440.076079 -11.071399) (xy 440.095582 -10.997489) (xy 440.108086 -10.96137) (xy 440.110695 -10.953059)
			(xy 440.110679 -10.935651) (xy 440.108086 -10.927334) (xy 440.095582 -10.891215) (xy 440.076095 -10.817302)
			(xy 440.063015 -10.74199) (xy 440.056437 -10.665834) (xy 440.056016 -10.627614) (xy 440.056016 -10.626852)
			(xy 440.05652 -10.584504) (xy 440.064571 -10.50019) (xy 440.0806 -10.417024) (xy 440.104461 -10.335757)
			(xy 440.13594 -10.257127) (xy 440.174751 -10.181846) (xy 440.220541 -10.110594) (xy 440.272897 -10.044018)
			(xy 440.331345 -9.98272) (xy 440.395355 -9.927255) (xy 440.464347 -9.878126) (xy 440.537697 -9.835777)
			(xy 440.61474 -9.800593) (xy 440.694779 -9.772891) (xy 440.777088 -9.752923) (xy 440.860923 -9.74087)
			(xy 440.945524 -9.73684) (xy 441.030125 -9.74087) (xy 441.11396 -9.752923) (xy 441.196269 -9.772891)
			(xy 441.276308 -9.800593) (xy 441.353351 -9.835777) (xy 441.426701 -9.878126) (xy 441.495693 -9.927255)
			(xy 441.559703 -9.98272) (xy 441.618151 -10.044018) (xy 441.670507 -10.110594) (xy 441.716297 -10.181846)
			(xy 441.755108 -10.257127) (xy 441.786587 -10.335757) (xy 441.810448 -10.417024) (xy 441.826477 -10.50019)
			(xy 441.834528 -10.584504) (xy 441.835032 -10.626852) (xy 441.835032 -10.627614) (xy 441.834614 -10.665834)
			(xy 441.828053 -10.741992) (xy 441.814972 -10.817305) (xy 441.795467 -10.891215) (xy 441.782962 -10.927334)
			(xy 441.780399 -10.935656) (xy 441.780383 -10.953054) (xy 441.782962 -10.96137) (xy 441.795465 -10.997489)
			(xy 441.814952 -11.071403) (xy 441.828033 -11.146715) (xy 441.834611 -11.22287) (xy 441.835032 -11.26109)
			(xy 441.835032 -11.261852) (xy 441.834502 -11.302954) (xy 441.826922 -11.384807) (xy 441.811821 -11.465611)
			(xy 441.789329 -11.544677) (xy 441.759637 -11.621331) (xy 441.722999 -11.694918) (xy 441.679728 -11.764811)
			(xy 441.630192 -11.830413) (xy 441.574815 -11.891164) (xy 441.514068 -11.946546) (xy 441.44847 -11.996087)
			(xy 441.378581 -12.039364) (xy 441.304997 -12.076008) (xy 441.228346 -12.105706) (xy 441.149281 -12.128204)
			(xy 441.068478 -12.143312) (xy 440.986626 -12.150899) (xy 440.945524 -12.15136) (xy 440.945016 -12.15136)
			(xy 440.904322 -12.150875) (xy 440.823276 -12.143416) (xy 440.74325 -12.128584) (xy 440.664913 -12.106505)
			(xy 440.58892 -12.077363) (xy 440.515907 -12.041401) (xy 440.480958 -12.02055) (xy 440.471926 -12.015614)
			(xy 440.451579 -12.012649) (xy 440.431701 -12.017907) (xy 440.4233 -12.023852) (xy 440.335416 -12.092178)
			(xy 440.326018 -12.12215) (xy 440.330844 -12.13739) (xy 440.343568 -12.180123) (xy 440.361398 -12.267491)
			(xy 440.370394 -12.356204) (xy 440.370976 -12.400788) (xy 440.370415 -12.444238) (xy 440.361895 -12.530719)
			(xy 440.344992 -12.615959) (xy 440.319868 -12.699148) (xy 440.286761 -12.779495) (xy 440.266836 -12.81811)
			(xy 440.262961 -12.82623) (xy 440.260628 -12.84406) (xy 440.262264 -12.852908) (xy 440.272023 -12.900055)
			(xy 440.282457 -12.995773) (xy 440.283092 -13.043916) (xy 440.282667 -13.085188) (xy 440.275027 -13.167377)
			(xy 440.259804 -13.248505) (xy 440.23713 -13.327874) (xy 440.2072 -13.4048) (xy 440.170271 -13.478622)
			(xy 440.126661 -13.548705) (xy 440.076745 -13.614446) (xy 440.020952 -13.675279) (xy 439.959763 -13.730681)
			(xy 439.893704 -13.780175) (xy 439.823344 -13.823336) (xy 439.786522 -13.841984) (xy 439.778885 -13.846179)
			(xy 439.766763 -13.858679) (xy 439.759479 -13.874495) (xy 439.758328 -13.883132) (xy 439.755251 -13.911241)
			(xy 439.741951 -13.966197) (xy 439.720685 -14.018587) (xy 439.69192 -14.067266) (xy 439.656285 -14.111165)
			(xy 439.643167 -14.123162) (xy 440.58586 -14.123162) (xy 440.586283 -14.084873) (xy 440.592885 -14.008579)
			(xy 440.60603 -13.933136) (xy 440.625619 -13.859105) (xy 440.638184 -13.822934) (xy 440.640853 -13.814502)
			(xy 440.64084 -13.796827) (xy 440.638184 -13.78839) (xy 440.625655 -13.752208) (xy 440.606078 -13.678176)
			(xy 440.592927 -13.602738) (xy 440.586298 -13.52645) (xy 440.58586 -13.488162) (xy 440.586364 -13.445801)
			(xy 440.594417 -13.361464) (xy 440.610451 -13.278274) (xy 440.634319 -13.196984) (xy 440.665807 -13.118332)
			(xy 440.704629 -13.043029) (xy 440.750432 -12.971757) (xy 440.802803 -12.905161) (xy 440.861268 -12.843846)
			(xy 440.925296 -12.788365) (xy 440.994308 -12.739222) (xy 441.067678 -12.696862) (xy 441.144743 -12.661667)
			(xy 441.224805 -12.633958) (xy 441.307138 -12.613984) (xy 441.390997 -12.601927) (xy 441.475622 -12.597896)
			(xy 441.560247 -12.601927) (xy 441.644106 -12.613984) (xy 441.726439 -12.633958) (xy 441.806501 -12.661667)
			(xy 441.883566 -12.696862) (xy 441.956936 -12.739222) (xy 442.025948 -12.788365) (xy 442.089976 -12.843846)
			(xy 442.135955 -12.892066) (xy 445.44847 -12.892066) (xy 445.44847 -12.837534) (xy 445.456231 -12.783558)
			(xy 445.471594 -12.731236) (xy 445.494246 -12.681632) (xy 445.523728 -12.635757) (xy 445.559438 -12.594545)
			(xy 445.600649 -12.558834) (xy 445.646523 -12.529351) (xy 445.696126 -12.506697) (xy 445.748448 -12.491333)
			(xy 445.802424 -12.483571) (xy 445.82969 -12.483084) (xy 446.69329 -12.483084) (xy 446.720565 -12.483455)
			(xy 446.774559 -12.491217) (xy 446.826899 -12.506584) (xy 446.87652 -12.529244) (xy 446.92241 -12.558735)
			(xy 446.963636 -12.594456) (xy 446.999359 -12.635682) (xy 447.028851 -12.681571) (xy 447.051512 -12.731191)
			(xy 447.066881 -12.783531) (xy 447.074644 -12.837525) (xy 447.074644 -12.892075) (xy 447.066881 -12.946069)
			(xy 447.051512 -12.998409) (xy 447.028851 -13.048029) (xy 446.999359 -13.093918) (xy 446.963636 -13.135144)
			(xy 446.92241 -13.170865) (xy 446.87652 -13.200356) (xy 446.826899 -13.223016) (xy 446.774559 -13.238383)
			(xy 446.720565 -13.246145) (xy 446.69329 -13.246608) (xy 445.82969 -13.246608) (xy 445.802424 -13.246029)
			(xy 445.748448 -13.238267) (xy 445.696126 -13.222903) (xy 445.646523 -13.200249) (xy 445.600649 -13.170766)
			(xy 445.559438 -13.135055) (xy 445.523728 -13.093843) (xy 445.494246 -13.047968) (xy 445.471594 -12.998364)
			(xy 445.456231 -12.946042) (xy 445.44847 -12.892066) (xy 442.135955 -12.892066) (xy 442.148441 -12.905161)
			(xy 442.200812 -12.971757) (xy 442.246615 -13.043029) (xy 442.285437 -13.118332) (xy 442.316925 -13.196984)
			(xy 442.340793 -13.278274) (xy 442.356827 -13.361464) (xy 442.36488 -13.445801) (xy 442.365384 -13.488162)
			(xy 442.364966 -13.526452) (xy 442.358362 -13.602745) (xy 442.345216 -13.678188) (xy 442.325626 -13.752219)
			(xy 442.31306 -13.78839) (xy 442.310428 -13.796831) (xy 442.310415 -13.814498) (xy 442.31306 -13.822934)
			(xy 442.325598 -13.859113) (xy 442.345172 -13.933146) (xy 442.358321 -14.008585) (xy 442.364947 -14.084874)
			(xy 442.365384 -14.123162) (xy 442.36488 -14.165523) (xy 442.356827 -14.24986) (xy 442.340793 -14.33305)
			(xy 442.316925 -14.41434) (xy 442.285437 -14.492992) (xy 442.268155 -14.526514) (xy 449.780152 -14.526514)
			(xy 449.780656 -14.484153) (xy 449.788709 -14.399816) (xy 449.804743 -14.316626) (xy 449.828611 -14.235336)
			(xy 449.860099 -14.156684) (xy 449.898921 -14.081381) (xy 449.944724 -14.010109) (xy 449.997095 -13.943513)
			(xy 450.05556 -13.882198) (xy 450.119588 -13.826717) (xy 450.1886 -13.777574) (xy 450.26197 -13.735214)
			(xy 450.339035 -13.700019) (xy 450.419097 -13.67231) (xy 450.50143 -13.652336) (xy 450.585289 -13.640279)
			(xy 450.669914 -13.636248) (xy 450.754539 -13.640279) (xy 450.838398 -13.652336) (xy 450.920731 -13.67231)
			(xy 451.000793 -13.700019) (xy 451.077858 -13.735214) (xy 451.151228 -13.777574) (xy 451.22024 -13.826717)
			(xy 451.284268 -13.882198) (xy 451.342733 -13.943513) (xy 451.395104 -14.010109) (xy 451.440907 -14.081381)
			(xy 451.479729 -14.156684) (xy 451.511217 -14.235336) (xy 451.535085 -14.316626) (xy 451.551119 -14.399816)
			(xy 451.559172 -14.484153) (xy 451.559676 -14.526514) (xy 451.559114 -14.571839) (xy 451.549887 -14.662018)
			(xy 451.531531 -14.750791) (xy 451.504235 -14.837234) (xy 451.486778 -14.879066) (xy 451.483143 -14.888844)
			(xy 451.483128 -14.909681) (xy 451.486778 -14.919452) (xy 451.504318 -14.961366) (xy 451.53178 -15.047983)
			(xy 451.550267 -15.136947) (xy 451.559587 -15.227334) (xy 451.560184 -15.272766) (xy 451.560184 -15.273782)
			(xy 451.559623 -15.318552) (xy 451.550621 -15.407639) (xy 451.532717 -15.495371) (xy 451.506092 -15.580861)
			(xy 451.489064 -15.62227) (xy 451.485509 -15.631864) (xy 451.485503 -15.652304) (xy 451.489064 -15.661894)
			(xy 451.50607 -15.703278) (xy 451.532693 -15.788702) (xy 451.550602 -15.876368) (xy 451.559616 -15.96539)
			(xy 451.560184 -16.010128) (xy 451.560184 -16.010382) (xy 451.55968 -16.05273) (xy 451.551629 -16.137044)
			(xy 451.5356 -16.22021) (xy 451.511739 -16.301477) (xy 451.48026 -16.380107) (xy 451.441449 -16.455388)
			(xy 451.395659 -16.52664) (xy 451.343303 -16.593216) (xy 451.284855 -16.654514) (xy 451.220845 -16.709979)
			(xy 451.151853 -16.759108) (xy 451.078503 -16.801457) (xy 451.00146 -16.836641) (xy 450.921421 -16.864343)
			(xy 450.839112 -16.884311) (xy 450.755277 -16.896364) (xy 450.670676 -16.900395) (xy 450.586075 -16.896364)
			(xy 450.50224 -16.884311) (xy 450.419931 -16.864343) (xy 450.339892 -16.836641) (xy 450.262849 -16.801457)
			(xy 450.189499 -16.759108) (xy 450.120507 -16.709979) (xy 450.056497 -16.654514) (xy 449.998049 -16.593216)
			(xy 449.945693 -16.52664) (xy 449.899903 -16.455388) (xy 449.861092 -16.380107) (xy 449.829613 -16.301477)
			(xy 449.805752 -16.22021) (xy 449.789723 -16.137044) (xy 449.781672 -16.05273) (xy 449.781168 -16.010382)
			(xy 449.781168 -16.010128) (xy 449.781731 -15.96539) (xy 449.790749 -15.876368) (xy 449.808655 -15.788701)
			(xy 449.83527 -15.703273) (xy 449.852288 -15.661894) (xy 449.855865 -15.652307) (xy 449.855859 -15.63186)
			(xy 449.852288 -15.62227) (xy 449.835263 -15.580859) (xy 449.808628 -15.495372) (xy 449.790721 -15.40764)
			(xy 449.781723 -15.318552) (xy 449.781168 -15.273782) (xy 449.781749 -15.228458) (xy 449.79099 -15.138283)
			(xy 449.809345 -15.049513) (xy 449.836623 -14.963067) (xy 449.854066 -14.92123) (xy 449.857691 -14.911438)
			(xy 449.857571 -14.890584) (xy 449.853812 -14.880844) (xy 449.836183 -14.838823) (xy 449.808624 -14.751958)
			(xy 449.790079 -14.662732) (xy 449.780742 -14.57208) (xy 449.780152 -14.526514) (xy 442.268155 -14.526514)
			(xy 442.246615 -14.568295) (xy 442.200812 -14.639567) (xy 442.148441 -14.706163) (xy 442.089976 -14.767478)
			(xy 442.025948 -14.822959) (xy 441.956936 -14.872102) (xy 441.883566 -14.914462) (xy 441.806501 -14.949657)
			(xy 441.726439 -14.977366) (xy 441.644106 -14.99734) (xy 441.560247 -15.009397) (xy 441.475622 -15.013429)
			(xy 441.390997 -15.009397) (xy 441.307138 -14.99734) (xy 441.224805 -14.977366) (xy 441.144743 -14.949657)
			(xy 441.067678 -14.914462) (xy 440.994308 -14.872102) (xy 440.925296 -14.822959) (xy 440.861268 -14.767478)
			(xy 440.802803 -14.706163) (xy 440.750432 -14.639567) (xy 440.704629 -14.568295) (xy 440.665807 -14.492992)
			(xy 440.634319 -14.41434) (xy 440.610451 -14.33305) (xy 440.594417 -14.24986) (xy 440.586364 -14.165523)
			(xy 440.58586 -14.123162) (xy 439.643167 -14.123162) (xy 439.614561 -14.149324) (xy 439.567661 -14.180907)
			(xy 439.516614 -14.205222) (xy 439.462537 -14.221736) (xy 439.406615 -14.230088) (xy 439.378344 -14.230604)
			(xy 439.350975 -14.230111) (xy 439.296797 -14.2223) (xy 439.244294 -14.206817) (xy 439.194547 -14.183981)
			(xy 439.148579 -14.154262) (xy 439.127646 -14.136624) (xy 439.127392 -14.13637) (xy 439.120314 -14.130771)
			(xy 439.103391 -14.124533) (xy 439.094372 -14.124178) (xy 439.027316 -14.124178) (xy 439.018301 -14.124547)
			(xy 439.001384 -14.130787) (xy 438.994296 -14.13637) (xy 438.994296 -14.136624) (xy 438.994042 -14.136624)
			(xy 438.973108 -14.154261) (xy 438.927135 -14.183972) (xy 438.877388 -14.206808) (xy 438.824888 -14.2223)
			(xy 438.770713 -14.230129) (xy 438.743344 -14.230604) (xy 438.713998 -14.230028) (xy 438.656001 -14.221024)
			(xy 438.600065 -14.203253) (xy 438.547506 -14.177132) (xy 438.499563 -14.143277) (xy 438.457364 -14.102486)
			(xy 438.421903 -14.055718) (xy 438.394015 -14.004075) (xy 438.38368 -13.976604) (xy 438.380221 -13.968026)
			(xy 438.368225 -13.953963) (xy 438.360312 -13.949172) (xy 438.333388 -13.93444) (xy 438.324705 -13.93016)
			(xy 438.305508 -13.927807) (xy 438.29605 -13.929868) (xy 438.259095 -13.939128) (xy 438.184005 -13.952036)
			(xy 438.108086 -13.958466) (xy 438.06999 -13.958824) (xy 438.028658 -13.958363) (xy 437.94635 -13.95071)
			(xy 437.865107 -13.935453) (xy 437.78563 -13.912724) (xy 437.708605 -13.882718) (xy 437.634696 -13.845694)
			(xy 437.564542 -13.801972) (xy 437.498747 -13.751929) (xy 437.43788 -13.695998) (xy 437.382465 -13.634659)
			(xy 437.332981 -13.568444) (xy 437.289854 -13.497922) (xy 437.253456 -13.423703) (xy 437.224103 -13.346427)
			(xy 437.202046 -13.266761) (xy 437.187477 -13.185391) (xy 437.18353 -13.144246) (xy 437.182106 -13.133691)
			(xy 437.171856 -13.11505) (xy 437.163718 -13.108178) (xy 437.131484 -13.082996) (xy 437.071245 -13.027653)
			(xy 437.016344 -12.967011) (xy 436.967245 -12.901582) (xy 436.924364 -12.831919) (xy 436.888063 -12.758612)
			(xy 436.858649 -12.682281) (xy 436.83637 -12.603571) (xy 436.821416 -12.523147) (xy 436.813913 -12.441689)
			(xy 436.813452 -12.400788) (xy 260.234662 -12.400788) (xy 260.203654 -12.412958) (xy 260.103162 -12.461353)
			(xy 260.006569 -12.517122) (xy 259.914413 -12.579954) (xy 259.82721 -12.649497) (xy 259.745448 -12.725362)
			(xy 259.669584 -12.807125) (xy 259.601843 -12.89207) (xy 431.453248 -12.89207) (xy 431.453248 -12.83753)
			(xy 431.46101 -12.783546) (xy 431.476376 -12.731216) (xy 431.499035 -12.681606) (xy 431.528523 -12.635726)
			(xy 431.564241 -12.594509) (xy 431.605461 -12.558796) (xy 431.651345 -12.529313) (xy 431.700957 -12.506661)
			(xy 431.753289 -12.4913) (xy 431.807274 -12.483544) (xy 431.834544 -12.483084) (xy 432.698144 -12.483084)
			(xy 432.725415 -12.483482) (xy 432.7794 -12.491249) (xy 432.83173 -12.50662) (xy 432.881341 -12.529282)
			(xy 432.927222 -12.558772) (xy 432.968439 -12.594492) (xy 433.004154 -12.635713) (xy 433.033639 -12.681598)
			(xy 433.056295 -12.731211) (xy 433.07166 -12.783543) (xy 433.079422 -12.837529) (xy 433.079422 -12.892071)
			(xy 433.07166 -12.946057) (xy 433.056295 -12.998389) (xy 433.033639 -13.048002) (xy 433.004154 -13.093887)
			(xy 432.968439 -13.135108) (xy 432.927222 -13.170828) (xy 432.881341 -13.200318) (xy 432.83173 -13.22298)
			(xy 432.7794 -13.238351) (xy 432.725415 -13.246118) (xy 432.698144 -13.246608) (xy 431.834544 -13.246608)
			(xy 431.807274 -13.246056) (xy 431.753289 -13.2383) (xy 431.700957 -13.222939) (xy 431.651345 -13.200287)
			(xy 431.605461 -13.170804) (xy 431.564241 -13.135091) (xy 431.528523 -13.093874) (xy 431.499035 -13.047994)
			(xy 431.476376 -12.998384) (xy 431.46101 -12.946054) (xy 431.453248 -12.89207) (xy 259.601843 -12.89207)
			(xy 259.600042 -12.894329) (xy 259.537211 -12.986486) (xy 259.481443 -13.08308) (xy 259.43305 -13.183572)
			(xy 259.392301 -13.287399) (xy 259.359426 -13.393981) (xy 259.334607 -13.502722) (xy 259.317984 -13.613014)
			(xy 259.309649 -13.724239) (xy 259.309108 -13.780008) (xy 259.309108 -17.126458) (xy 310.265572 -17.126458)
			(xy 310.265992 -17.082972) (xy 310.273576 -16.996331) (xy 310.288682 -16.910681) (xy 310.311195 -16.826674)
			(xy 310.340944 -16.744948) (xy 310.377702 -16.666126) (xy 310.421191 -16.590808) (xy 310.471078 -16.519566)
			(xy 310.526985 -16.452943) (xy 310.588485 -16.391447) (xy 310.65511 -16.335544) (xy 310.726355 -16.285661)
			(xy 310.801676 -16.242177) (xy 310.8805 -16.205422) (xy 310.962227 -16.175678) (xy 311.046236 -16.15317)
			(xy 311.131887 -16.138068) (xy 311.218528 -16.13049) (xy 311.262014 -16.130016) (xy 311.287414 -16.130016)
			(xy 311.33271 -16.130609) (xy 311.422936 -16.13873) (xy 311.512071 -16.154907) (xy 311.599397 -16.179009)
			(xy 311.684211 -16.210841) (xy 311.76583 -16.250148) (xy 311.843598 -16.296613) (xy 311.916887 -16.349861)
			(xy 311.985108 -16.409465) (xy 312.047712 -16.474944) (xy 312.104194 -16.545772) (xy 312.1541 -16.621377)
			(xy 312.197028 -16.701151) (xy 312.232632 -16.784452) (xy 312.260626 -16.870609) (xy 312.280784 -16.958929)
			(xy 312.292944 -17.0487) (xy 312.297009 -17.1392) (xy 312.292944 -17.2297) (xy 312.280784 -17.319471)
			(xy 312.260626 -17.407791) (xy 312.232632 -17.493948) (xy 312.197028 -17.577249) (xy 312.163448 -17.639652)
			(xy 389.652738 -17.639652) (xy 389.652738 -17.585148) (xy 389.660494 -17.531197) (xy 389.675849 -17.4789)
			(xy 389.69849 -17.42932) (xy 389.727956 -17.383466) (xy 389.763647 -17.342273) (xy 389.804838 -17.306578)
			(xy 389.850688 -17.277107) (xy 389.900266 -17.254462) (xy 389.952562 -17.239102) (xy 390.006512 -17.23134)
			(xy 390.033764 -17.230852) (xy 390.897364 -17.230852) (xy 390.924616 -17.231393) (xy 390.978565 -17.239145)
			(xy 391.030862 -17.254496) (xy 391.080441 -17.277134) (xy 391.126294 -17.306598) (xy 391.167486 -17.342288)
			(xy 391.20318 -17.383477) (xy 391.232649 -17.429327) (xy 391.255291 -17.478905) (xy 391.270648 -17.5312)
			(xy 391.278405 -17.585148) (xy 391.278405 -17.639652) (xy 395.240738 -17.639652) (xy 395.240738 -17.585148)
			(xy 395.248494 -17.531197) (xy 395.263849 -17.4789) (xy 395.28649 -17.42932) (xy 395.315956 -17.383466)
			(xy 395.351647 -17.342273) (xy 395.392838 -17.306578) (xy 395.438688 -17.277107) (xy 395.488266 -17.254462)
			(xy 395.540562 -17.239102) (xy 395.594512 -17.23134) (xy 395.621764 -17.230852) (xy 396.485364 -17.230852)
			(xy 396.512616 -17.231393) (xy 396.566565 -17.239145) (xy 396.618862 -17.254496) (xy 396.668441 -17.277134)
			(xy 396.714294 -17.306598) (xy 396.755486 -17.342288) (xy 396.79118 -17.383477) (xy 396.820649 -17.429327)
			(xy 396.843291 -17.478905) (xy 396.858648 -17.5312) (xy 396.866405 -17.585148) (xy 396.866405 -17.639652)
			(xy 400.828738 -17.639652) (xy 400.828738 -17.585148) (xy 400.836494 -17.531197) (xy 400.851849 -17.4789)
			(xy 400.87449 -17.42932) (xy 400.903956 -17.383466) (xy 400.939647 -17.342273) (xy 400.980838 -17.306578)
			(xy 401.026688 -17.277107) (xy 401.076266 -17.254462) (xy 401.128562 -17.239102) (xy 401.182512 -17.23134)
			(xy 401.209764 -17.230852) (xy 402.073364 -17.230852) (xy 402.100616 -17.231393) (xy 402.154565 -17.239145)
			(xy 402.206862 -17.254496) (xy 402.256441 -17.277134) (xy 402.302294 -17.306598) (xy 402.343486 -17.342288)
			(xy 402.37918 -17.383477) (xy 402.408649 -17.429327) (xy 402.431291 -17.478905) (xy 402.446648 -17.5312)
			(xy 402.454405 -17.585148) (xy 402.454405 -17.639652) (xy 402.454301 -17.640372) (xy 406.415424 -17.640372)
			(xy 406.415424 -17.585828) (xy 406.423187 -17.53184) (xy 406.438554 -17.479507) (xy 406.461214 -17.429893)
			(xy 406.490704 -17.38401) (xy 406.526425 -17.342791) (xy 406.567649 -17.307076) (xy 406.613536 -17.277591)
			(xy 406.663152 -17.254938) (xy 406.715487 -17.239576) (xy 406.769476 -17.23182) (xy 406.796748 -17.23136)
			(xy 407.660348 -17.23136) (xy 407.687617 -17.231806) (xy 407.741598 -17.239573) (xy 407.793925 -17.254944)
			(xy 407.843532 -17.277604) (xy 407.88941 -17.307093) (xy 407.930624 -17.34281) (xy 407.966336 -17.384029)
			(xy 407.995819 -17.42991) (xy 408.018473 -17.47952) (xy 408.033837 -17.531849) (xy 408.041598 -17.585831)
			(xy 408.041598 -17.640369) (xy 408.041598 -17.640372) (xy 412.003424 -17.640372) (xy 412.003424 -17.585828)
			(xy 412.011187 -17.53184) (xy 412.026554 -17.479507) (xy 412.049214 -17.429893) (xy 412.078704 -17.38401)
			(xy 412.114425 -17.342791) (xy 412.155649 -17.307076) (xy 412.201536 -17.277591) (xy 412.251152 -17.254938)
			(xy 412.303487 -17.239576) (xy 412.357476 -17.23182) (xy 412.384748 -17.23136) (xy 413.248348 -17.23136)
			(xy 413.275617 -17.231806) (xy 413.329598 -17.239573) (xy 413.381925 -17.254944) (xy 413.431532 -17.277604)
			(xy 413.47741 -17.307093) (xy 413.518624 -17.34281) (xy 413.554336 -17.384029) (xy 413.583819 -17.42991)
			(xy 413.606473 -17.47952) (xy 413.621837 -17.531849) (xy 413.629598 -17.585831) (xy 413.629598 -17.639653)
			(xy 417.898538 -17.639653) (xy 417.898538 -17.585147) (xy 417.906295 -17.531195) (xy 417.92165 -17.478897)
			(xy 417.944292 -17.429315) (xy 417.97376 -17.383461) (xy 418.009453 -17.342267) (xy 418.050645 -17.306572)
			(xy 418.096498 -17.277102) (xy 418.146078 -17.254457) (xy 418.198376 -17.239099) (xy 418.252327 -17.231339)
			(xy 418.27958 -17.230852) (xy 419.14318 -17.230852) (xy 419.170431 -17.231394) (xy 419.224378 -17.239148)
			(xy 419.276673 -17.2545) (xy 419.326251 -17.277139) (xy 419.372101 -17.306604) (xy 419.413292 -17.342294)
			(xy 419.448984 -17.383483) (xy 419.478451 -17.429332) (xy 419.501093 -17.478908) (xy 419.516448 -17.531202)
			(xy 419.524205 -17.585149) (xy 419.524205 -17.639651) (xy 419.524205 -17.639653) (xy 423.486538 -17.639653)
			(xy 423.486538 -17.585147) (xy 423.494295 -17.531195) (xy 423.50965 -17.478897) (xy 423.532292 -17.429315)
			(xy 423.56176 -17.383461) (xy 423.597453 -17.342267) (xy 423.638645 -17.306572) (xy 423.684498 -17.277102)
			(xy 423.734078 -17.254457) (xy 423.786376 -17.239099) (xy 423.840327 -17.231339) (xy 423.86758 -17.230852)
			(xy 424.73118 -17.230852) (xy 424.758431 -17.231394) (xy 424.812378 -17.239148) (xy 424.864673 -17.2545)
			(xy 424.914251 -17.277139) (xy 424.960101 -17.306604) (xy 425.001292 -17.342294) (xy 425.036984 -17.383483)
			(xy 425.066451 -17.429332) (xy 425.089093 -17.478908) (xy 425.104448 -17.531202) (xy 425.112205 -17.585149)
			(xy 425.112205 -17.639651) (xy 425.112102 -17.640368) (xy 429.107346 -17.640368) (xy 429.107346 -17.585832)
			(xy 429.115108 -17.531852) (xy 429.130472 -17.479525) (xy 429.153127 -17.429918) (xy 429.182611 -17.38404)
			(xy 429.218324 -17.342824) (xy 429.25954 -17.307111) (xy 429.305418 -17.277627) (xy 429.355025 -17.254972)
			(xy 429.407352 -17.239608) (xy 429.461332 -17.231846) (xy 429.4886 -17.23136) (xy 430.3522 -17.23136)
			(xy 430.379471 -17.231802) (xy 430.433458 -17.239565) (xy 430.48579 -17.254931) (xy 430.535403 -17.277588)
			(xy 430.581287 -17.307076) (xy 430.622507 -17.342793) (xy 430.658224 -17.384013) (xy 430.687712 -17.429897)
			(xy 430.710369 -17.47951) (xy 430.725735 -17.531842) (xy 430.733498 -17.585829) (xy 430.733498 -17.640371)
			(xy 430.725735 -17.694358) (xy 430.710369 -17.74669) (xy 430.687712 -17.796303) (xy 430.658224 -17.842187)
			(xy 430.622507 -17.883407) (xy 430.581287 -17.919124) (xy 430.535403 -17.948612) (xy 430.48579 -17.971269)
			(xy 430.433458 -17.986635) (xy 430.379471 -17.994398) (xy 430.3522 -17.994884) (xy 429.4886 -17.994884)
			(xy 429.461332 -17.994354) (xy 429.407352 -17.986592) (xy 429.355025 -17.971228) (xy 429.305418 -17.948573)
			(xy 429.25954 -17.919089) (xy 429.218324 -17.883376) (xy 429.182611 -17.84216) (xy 429.153127 -17.796282)
			(xy 429.130472 -17.746675) (xy 429.115108 -17.694348) (xy 429.107346 -17.640368) (xy 425.112102 -17.640368)
			(xy 425.104448 -17.693598) (xy 425.089093 -17.745892) (xy 425.066451 -17.795468) (xy 425.036984 -17.841317)
			(xy 425.001292 -17.882506) (xy 424.960101 -17.918196) (xy 424.914251 -17.947661) (xy 424.864673 -17.9703)
			(xy 424.812378 -17.985652) (xy 424.758431 -17.993406) (xy 424.73118 -17.993868) (xy 423.86758 -17.993868)
			(xy 423.840327 -17.993461) (xy 423.786376 -17.985701) (xy 423.734078 -17.970343) (xy 423.684498 -17.947698)
			(xy 423.638645 -17.918228) (xy 423.597453 -17.882533) (xy 423.56176 -17.841339) (xy 423.532292 -17.795485)
			(xy 423.50965 -17.745903) (xy 423.494295 -17.693605) (xy 423.486538 -17.639653) (xy 419.524205 -17.639653)
			(xy 419.516448 -17.693598) (xy 419.501093 -17.745892) (xy 419.478451 -17.795468) (xy 419.448984 -17.841317)
			(xy 419.413292 -17.882506) (xy 419.372101 -17.918196) (xy 419.326251 -17.947661) (xy 419.276673 -17.9703)
			(xy 419.224378 -17.985652) (xy 419.170431 -17.993406) (xy 419.14318 -17.993868) (xy 418.27958 -17.993868)
			(xy 418.252327 -17.993461) (xy 418.198376 -17.985701) (xy 418.146078 -17.970343) (xy 418.096498 -17.947698)
			(xy 418.050645 -17.918228) (xy 418.009453 -17.882533) (xy 417.97376 -17.841339) (xy 417.944292 -17.795485)
			(xy 417.92165 -17.745903) (xy 417.906295 -17.693605) (xy 417.898538 -17.639653) (xy 413.629598 -17.639653)
			(xy 413.629598 -17.640369) (xy 413.621837 -17.694351) (xy 413.606473 -17.74668) (xy 413.583819 -17.79629)
			(xy 413.554336 -17.842171) (xy 413.518624 -17.88339) (xy 413.47741 -17.919107) (xy 413.431532 -17.948596)
			(xy 413.381925 -17.971256) (xy 413.329598 -17.986627) (xy 413.275617 -17.994394) (xy 413.248348 -17.994884)
			(xy 412.384748 -17.994884) (xy 412.357476 -17.99438) (xy 412.303487 -17.986624) (xy 412.251152 -17.971262)
			(xy 412.201536 -17.948609) (xy 412.155649 -17.919124) (xy 412.114425 -17.883409) (xy 412.078704 -17.84219)
			(xy 412.049214 -17.796307) (xy 412.026554 -17.746693) (xy 412.011187 -17.69436) (xy 412.003424 -17.640372)
			(xy 408.041598 -17.640372) (xy 408.033837 -17.694351) (xy 408.018473 -17.74668) (xy 407.995819 -17.79629)
			(xy 407.966336 -17.842171) (xy 407.930624 -17.88339) (xy 407.88941 -17.919107) (xy 407.843532 -17.948596)
			(xy 407.793925 -17.971256) (xy 407.741598 -17.986627) (xy 407.687617 -17.994394) (xy 407.660348 -17.994884)
			(xy 406.796748 -17.994884) (xy 406.769476 -17.99438) (xy 406.715487 -17.986624) (xy 406.663152 -17.971262)
			(xy 406.613536 -17.948609) (xy 406.567649 -17.919124) (xy 406.526425 -17.883409) (xy 406.490704 -17.84219)
			(xy 406.461214 -17.796307) (xy 406.438554 -17.746693) (xy 406.423187 -17.69436) (xy 406.415424 -17.640372)
			(xy 402.454301 -17.640372) (xy 402.446648 -17.6936) (xy 402.431291 -17.745895) (xy 402.408649 -17.795473)
			(xy 402.37918 -17.841323) (xy 402.343486 -17.882512) (xy 402.302294 -17.918202) (xy 402.256441 -17.947666)
			(xy 402.206862 -17.970304) (xy 402.154565 -17.985655) (xy 402.100616 -17.993407) (xy 402.073364 -17.993868)
			(xy 401.209764 -17.993868) (xy 401.182512 -17.99346) (xy 401.128562 -17.985698) (xy 401.076266 -17.970338)
			(xy 401.026688 -17.947693) (xy 400.980838 -17.918222) (xy 400.939647 -17.882527) (xy 400.903956 -17.841334)
			(xy 400.87449 -17.79548) (xy 400.851849 -17.7459) (xy 400.836494 -17.693603) (xy 400.828738 -17.639652)
			(xy 396.866405 -17.639652) (xy 396.858648 -17.6936) (xy 396.843291 -17.745895) (xy 396.820649 -17.795473)
			(xy 396.79118 -17.841323) (xy 396.755486 -17.882512) (xy 396.714294 -17.918202) (xy 396.668441 -17.947666)
			(xy 396.618862 -17.970304) (xy 396.566565 -17.985655) (xy 396.512616 -17.993407) (xy 396.485364 -17.993868)
			(xy 395.621764 -17.993868) (xy 395.594512 -17.99346) (xy 395.540562 -17.985698) (xy 395.488266 -17.970338)
			(xy 395.438688 -17.947693) (xy 395.392838 -17.918222) (xy 395.351647 -17.882527) (xy 395.315956 -17.841334)
			(xy 395.28649 -17.79548) (xy 395.263849 -17.7459) (xy 395.248494 -17.693603) (xy 395.240738 -17.639652)
			(xy 391.278405 -17.639652) (xy 391.270648 -17.6936) (xy 391.255291 -17.745895) (xy 391.232649 -17.795473)
			(xy 391.20318 -17.841323) (xy 391.167486 -17.882512) (xy 391.126294 -17.918202) (xy 391.080441 -17.947666)
			(xy 391.030862 -17.970304) (xy 390.978565 -17.985655) (xy 390.924616 -17.993407) (xy 390.897364 -17.993868)
			(xy 390.033764 -17.993868) (xy 390.006512 -17.99346) (xy 389.952562 -17.985698) (xy 389.900266 -17.970338)
			(xy 389.850688 -17.947693) (xy 389.804838 -17.918222) (xy 389.763647 -17.882527) (xy 389.727956 -17.841334)
			(xy 389.69849 -17.79548) (xy 389.675849 -17.7459) (xy 389.660494 -17.693603) (xy 389.652738 -17.639652)
			(xy 312.163448 -17.639652) (xy 312.1541 -17.657023) (xy 312.104194 -17.732628) (xy 312.047712 -17.803456)
			(xy 311.985108 -17.868935) (xy 311.916887 -17.928539) (xy 311.843598 -17.981787) (xy 311.76583 -18.028252)
			(xy 311.684211 -18.067559) (xy 311.599397 -18.099391) (xy 311.512071 -18.123493) (xy 311.422936 -18.13967)
			(xy 311.33271 -18.147791) (xy 311.287414 -18.1483) (xy 311.28716 -18.1483) (xy 311.242573 -18.147831)
			(xy 311.153739 -18.140039) (xy 311.065923 -18.124536) (xy 310.979792 -18.101438) (xy 310.896001 -18.070922)
			(xy 310.815188 -18.033221) (xy 310.737969 -17.988621) (xy 310.664929 -17.937461) (xy 310.596626 -17.88013)
			(xy 310.533579 -17.817066) (xy 310.476268 -17.748747) (xy 310.425128 -17.675693) (xy 310.380549 -17.598461)
			(xy 310.34287 -17.517638) (xy 310.312377 -17.433839) (xy 310.289303 -17.347701) (xy 310.273824 -17.259881)
			(xy 310.266056 -17.171045) (xy 310.265572 -17.126458) (xy 259.309108 -17.126458) (xy 259.309108 -19.164372)
			(xy 392.445424 -19.164372) (xy 392.445424 -19.109828) (xy 392.453187 -19.05584) (xy 392.468554 -19.003507)
			(xy 392.491214 -18.953893) (xy 392.520704 -18.90801) (xy 392.556425 -18.866791) (xy 392.597649 -18.831076)
			(xy 392.643536 -18.801591) (xy 392.693152 -18.778938) (xy 392.745487 -18.763576) (xy 392.799476 -18.75582)
			(xy 392.826748 -18.75536) (xy 393.690348 -18.75536) (xy 393.717617 -18.755806) (xy 393.771598 -18.763573)
			(xy 393.823925 -18.778944) (xy 393.873532 -18.801604) (xy 393.91941 -18.831093) (xy 393.960624 -18.86681)
			(xy 393.996336 -18.908029) (xy 394.025819 -18.95391) (xy 394.048473 -19.00352) (xy 394.063837 -19.055849)
			(xy 394.071598 -19.109831) (xy 394.071598 -19.163652) (xy 398.034738 -19.163652) (xy 398.034738 -19.109148)
			(xy 398.042494 -19.055197) (xy 398.057849 -19.0029) (xy 398.08049 -18.95332) (xy 398.109956 -18.907466)
			(xy 398.145647 -18.866273) (xy 398.186838 -18.830578) (xy 398.232688 -18.801107) (xy 398.282266 -18.778462)
			(xy 398.334562 -18.763102) (xy 398.388512 -18.75534) (xy 398.415764 -18.754852) (xy 399.279364 -18.754852)
			(xy 399.306616 -18.755393) (xy 399.360565 -18.763145) (xy 399.412862 -18.778496) (xy 399.462441 -18.801134)
			(xy 399.508294 -18.830598) (xy 399.549486 -18.866288) (xy 399.58518 -18.907477) (xy 399.614649 -18.953327)
			(xy 399.637291 -19.002905) (xy 399.652648 -19.0552) (xy 399.660405 -19.109148) (xy 399.660405 -19.163652)
			(xy 403.622738 -19.163652) (xy 403.622738 -19.109148) (xy 403.630494 -19.055197) (xy 403.645849 -19.0029)
			(xy 403.66849 -18.95332) (xy 403.697956 -18.907466) (xy 403.733647 -18.866273) (xy 403.774838 -18.830578)
			(xy 403.820688 -18.801107) (xy 403.870266 -18.778462) (xy 403.922562 -18.763102) (xy 403.976512 -18.75534)
			(xy 404.003764 -18.754852) (xy 404.867364 -18.754852) (xy 404.894616 -18.755393) (xy 404.948565 -18.763145)
			(xy 405.000862 -18.778496) (xy 405.050441 -18.801134) (xy 405.096294 -18.830598) (xy 405.137486 -18.866288)
			(xy 405.17318 -18.907477) (xy 405.202649 -18.953327) (xy 405.225291 -19.002905) (xy 405.240648 -19.0552)
			(xy 405.248405 -19.109148) (xy 405.248405 -19.163652) (xy 409.210738 -19.163652) (xy 409.210738 -19.109148)
			(xy 409.218494 -19.055197) (xy 409.233849 -19.0029) (xy 409.25649 -18.95332) (xy 409.285956 -18.907466)
			(xy 409.321647 -18.866273) (xy 409.362838 -18.830578) (xy 409.408688 -18.801107) (xy 409.458266 -18.778462)
			(xy 409.510562 -18.763102) (xy 409.564512 -18.75534) (xy 409.591764 -18.754852) (xy 410.455364 -18.754852)
			(xy 410.482616 -18.755393) (xy 410.536565 -18.763145) (xy 410.588862 -18.778496) (xy 410.638441 -18.801134)
			(xy 410.684294 -18.830598) (xy 410.725486 -18.866288) (xy 410.76118 -18.907477) (xy 410.790649 -18.953327)
			(xy 410.813291 -19.002905) (xy 410.828648 -19.0552) (xy 410.836405 -19.109148) (xy 410.836405 -19.163652)
			(xy 410.836405 -19.163653) (xy 415.104538 -19.163653) (xy 415.104538 -19.109147) (xy 415.112295 -19.055195)
			(xy 415.12765 -19.002897) (xy 415.150292 -18.953315) (xy 415.17976 -18.907461) (xy 415.215453 -18.866267)
			(xy 415.256645 -18.830572) (xy 415.302498 -18.801102) (xy 415.352078 -18.778457) (xy 415.404376 -18.763099)
			(xy 415.458327 -18.755339) (xy 415.48558 -18.754852) (xy 416.34918 -18.754852) (xy 416.376431 -18.755394)
			(xy 416.430378 -18.763148) (xy 416.482673 -18.7785) (xy 416.532251 -18.801139) (xy 416.578101 -18.830604)
			(xy 416.619292 -18.866294) (xy 416.654984 -18.907483) (xy 416.684451 -18.953332) (xy 416.707093 -19.002908)
			(xy 416.722448 -19.055202) (xy 416.730205 -19.109149) (xy 416.730205 -19.163651) (xy 416.730102 -19.164366)
			(xy 420.691346 -19.164366) (xy 420.691346 -19.109834) (xy 420.699107 -19.055857) (xy 420.714469 -19.003533)
			(xy 420.737121 -18.953928) (xy 420.766602 -18.908051) (xy 420.802312 -18.866837) (xy 420.843523 -18.831124)
			(xy 420.889396 -18.801639) (xy 420.938999 -18.778982) (xy 420.991321 -18.763614) (xy 421.045298 -18.755849)
			(xy 421.072564 -18.75536) (xy 421.936164 -18.75536) (xy 421.963438 -18.755777) (xy 422.017432 -18.763536)
			(xy 422.069772 -18.7789) (xy 422.119393 -18.801556) (xy 422.165284 -18.831045) (xy 422.20651 -18.866764)
			(xy 422.242234 -18.907988) (xy 422.271726 -18.953876) (xy 422.294388 -19.003494) (xy 422.309757 -19.055833)
			(xy 422.31752 -19.109826) (xy 422.31752 -19.163656) (xy 426.314515 -19.163656) (xy 426.314515 -19.109144)
			(xy 426.322273 -19.055185) (xy 426.337632 -19.002881) (xy 426.360278 -18.953294) (xy 426.38975 -18.907436)
			(xy 426.42545 -18.866238) (xy 426.466648 -18.830541) (xy 426.512508 -18.80107) (xy 426.562096 -18.778426)
			(xy 426.614401 -18.76307) (xy 426.66836 -18.755314) (xy 426.695616 -18.754852) (xy 427.559216 -18.754852)
			(xy 427.586464 -18.755419) (xy 427.640404 -18.763177) (xy 427.692691 -18.778532) (xy 427.742261 -18.801171)
			(xy 427.788105 -18.830635) (xy 427.829289 -18.866323) (xy 427.864975 -18.907508) (xy 427.894436 -18.953353)
			(xy 427.917074 -19.002924) (xy 427.932427 -19.055212) (xy 427.940182 -19.109152) (xy 427.940182 -19.163648)
			(xy 427.940181 -19.163656) (xy 431.902515 -19.163656) (xy 431.902515 -19.109144) (xy 431.910273 -19.055185)
			(xy 431.925632 -19.002881) (xy 431.948278 -18.953294) (xy 431.97775 -18.907436) (xy 432.01345 -18.866238)
			(xy 432.054648 -18.830541) (xy 432.100508 -18.80107) (xy 432.150096 -18.778426) (xy 432.202401 -18.76307)
			(xy 432.25636 -18.755314) (xy 432.283616 -18.754852) (xy 433.147216 -18.754852) (xy 433.174464 -18.755419)
			(xy 433.228404 -18.763177) (xy 433.280691 -18.778532) (xy 433.330261 -18.801171) (xy 433.376105 -18.830635)
			(xy 433.417289 -18.866323) (xy 433.452975 -18.907508) (xy 433.482436 -18.953353) (xy 433.505074 -19.002924)
			(xy 433.520427 -19.055212) (xy 433.528182 -19.109152) (xy 433.528182 -19.163648) (xy 433.520427 -19.217588)
			(xy 433.505074 -19.269876) (xy 433.482436 -19.319447) (xy 433.452975 -19.365292) (xy 433.417289 -19.406477)
			(xy 433.376105 -19.442165) (xy 433.330261 -19.471629) (xy 433.280691 -19.494268) (xy 433.228404 -19.509623)
			(xy 433.174464 -19.517381) (xy 433.147216 -19.517868) (xy 432.283616 -19.517868) (xy 432.25636 -19.517486)
			(xy 432.202401 -19.50973) (xy 432.150096 -19.494374) (xy 432.100508 -19.47173) (xy 432.054648 -19.442259)
			(xy 432.01345 -19.406562) (xy 431.97775 -19.365364) (xy 431.948278 -19.319506) (xy 431.925632 -19.269919)
			(xy 431.910273 -19.217615) (xy 431.902515 -19.163656) (xy 427.940181 -19.163656) (xy 427.932427 -19.217588)
			(xy 427.917074 -19.269876) (xy 427.894436 -19.319447) (xy 427.864975 -19.365292) (xy 427.829289 -19.406477)
			(xy 427.788105 -19.442165) (xy 427.742261 -19.471629) (xy 427.692691 -19.494268) (xy 427.640404 -19.509623)
			(xy 427.586464 -19.517381) (xy 427.559216 -19.517868) (xy 426.695616 -19.517868) (xy 426.66836 -19.517486)
			(xy 426.614401 -19.50973) (xy 426.562096 -19.494374) (xy 426.512508 -19.47173) (xy 426.466648 -19.442259)
			(xy 426.42545 -19.406562) (xy 426.38975 -19.365364) (xy 426.360278 -19.319506) (xy 426.337632 -19.269919)
			(xy 426.322273 -19.217615) (xy 426.314515 -19.163656) (xy 422.31752 -19.163656) (xy 422.31752 -19.164374)
			(xy 422.309757 -19.218367) (xy 422.294388 -19.270706) (xy 422.271726 -19.320324) (xy 422.242234 -19.366212)
			(xy 422.20651 -19.407436) (xy 422.165284 -19.443155) (xy 422.119393 -19.472644) (xy 422.069772 -19.4953)
			(xy 422.017432 -19.510664) (xy 421.963438 -19.518423) (xy 421.936164 -19.518884) (xy 421.072564 -19.518884)
			(xy 421.045298 -19.518351) (xy 420.991321 -19.510586) (xy 420.938999 -19.495218) (xy 420.889396 -19.472561)
			(xy 420.843523 -19.443076) (xy 420.802312 -19.407363) (xy 420.766602 -19.366149) (xy 420.737121 -19.320272)
			(xy 420.714469 -19.270667) (xy 420.699107 -19.218343) (xy 420.691346 -19.164366) (xy 416.730102 -19.164366)
			(xy 416.722448 -19.217598) (xy 416.707093 -19.269892) (xy 416.684451 -19.319468) (xy 416.654984 -19.365317)
			(xy 416.619292 -19.406506) (xy 416.578101 -19.442196) (xy 416.532251 -19.471661) (xy 416.482673 -19.4943)
			(xy 416.430378 -19.509652) (xy 416.376431 -19.517406) (xy 416.34918 -19.517868) (xy 415.48558 -19.517868)
			(xy 415.458327 -19.517461) (xy 415.404376 -19.509701) (xy 415.352078 -19.494343) (xy 415.302498 -19.471698)
			(xy 415.256645 -19.442228) (xy 415.215453 -19.406533) (xy 415.17976 -19.365339) (xy 415.150292 -19.319485)
			(xy 415.12765 -19.269903) (xy 415.112295 -19.217605) (xy 415.104538 -19.163653) (xy 410.836405 -19.163653)
			(xy 410.828648 -19.2176) (xy 410.813291 -19.269895) (xy 410.790649 -19.319473) (xy 410.76118 -19.365323)
			(xy 410.725486 -19.406512) (xy 410.684294 -19.442202) (xy 410.638441 -19.471666) (xy 410.588862 -19.494304)
			(xy 410.536565 -19.509655) (xy 410.482616 -19.517407) (xy 410.455364 -19.517868) (xy 409.591764 -19.517868)
			(xy 409.564512 -19.51746) (xy 409.510562 -19.509698) (xy 409.458266 -19.494338) (xy 409.408688 -19.471693)
			(xy 409.362838 -19.442222) (xy 409.321647 -19.406527) (xy 409.285956 -19.365334) (xy 409.25649 -19.31948)
			(xy 409.233849 -19.2699) (xy 409.218494 -19.217603) (xy 409.210738 -19.163652) (xy 405.248405 -19.163652)
			(xy 405.240648 -19.2176) (xy 405.225291 -19.269895) (xy 405.202649 -19.319473) (xy 405.17318 -19.365323)
			(xy 405.137486 -19.406512) (xy 405.096294 -19.442202) (xy 405.050441 -19.471666) (xy 405.000862 -19.494304)
			(xy 404.948565 -19.509655) (xy 404.894616 -19.517407) (xy 404.867364 -19.517868) (xy 404.003764 -19.517868)
			(xy 403.976512 -19.51746) (xy 403.922562 -19.509698) (xy 403.870266 -19.494338) (xy 403.820688 -19.471693)
			(xy 403.774838 -19.442222) (xy 403.733647 -19.406527) (xy 403.697956 -19.365334) (xy 403.66849 -19.31948)
			(xy 403.645849 -19.2699) (xy 403.630494 -19.217603) (xy 403.622738 -19.163652) (xy 399.660405 -19.163652)
			(xy 399.652648 -19.2176) (xy 399.637291 -19.269895) (xy 399.614649 -19.319473) (xy 399.58518 -19.365323)
			(xy 399.549486 -19.406512) (xy 399.508294 -19.442202) (xy 399.462441 -19.471666) (xy 399.412862 -19.494304)
			(xy 399.360565 -19.509655) (xy 399.306616 -19.517407) (xy 399.279364 -19.517868) (xy 398.415764 -19.517868)
			(xy 398.388512 -19.51746) (xy 398.334562 -19.509698) (xy 398.282266 -19.494338) (xy 398.232688 -19.471693)
			(xy 398.186838 -19.442222) (xy 398.145647 -19.406527) (xy 398.109956 -19.365334) (xy 398.08049 -19.31948)
			(xy 398.057849 -19.2699) (xy 398.042494 -19.217603) (xy 398.034738 -19.163652) (xy 394.071598 -19.163652)
			(xy 394.071598 -19.164369) (xy 394.063837 -19.218351) (xy 394.048473 -19.27068) (xy 394.025819 -19.32029)
			(xy 393.996336 -19.366171) (xy 393.960624 -19.40739) (xy 393.91941 -19.443107) (xy 393.873532 -19.472596)
			(xy 393.823925 -19.495256) (xy 393.771598 -19.510627) (xy 393.717617 -19.518394) (xy 393.690348 -19.518884)
			(xy 392.826748 -19.518884) (xy 392.799476 -19.51838) (xy 392.745487 -19.510624) (xy 392.693152 -19.495262)
			(xy 392.643536 -19.472609) (xy 392.597649 -19.443124) (xy 392.556425 -19.407409) (xy 392.520704 -19.36619)
			(xy 392.491214 -19.320307) (xy 392.468554 -19.270693) (xy 392.453187 -19.21836) (xy 392.445424 -19.164372)
			(xy 259.309108 -19.164372) (xy 259.309108 -20.4061) (xy 368.50594 -20.4061) (xy 368.510005 -20.315592)
			(xy 368.522167 -20.225813) (xy 368.542328 -20.137486) (xy 368.570325 -20.051322) (xy 368.605934 -19.968014)
			(xy 368.648867 -19.888233) (xy 368.698779 -19.812623) (xy 368.755267 -19.741791) (xy 368.817878 -19.676308)
			(xy 368.886107 -19.616701) (xy 368.959405 -19.56345) (xy 369.037181 -19.516984) (xy 369.118809 -19.477677)
			(xy 369.203632 -19.445846) (xy 369.290966 -19.421746) (xy 369.38011 -19.405573) (xy 369.470345 -19.397455)
			(xy 369.515644 -19.396964) (xy 369.560233 -19.397442) (xy 369.649072 -19.405219) (xy 369.736895 -19.420711)
			(xy 369.823033 -19.443798) (xy 369.906831 -19.474305) (xy 369.987651 -19.512001) (xy 370.064878 -19.556597)
			(xy 370.137923 -19.607756) (xy 370.206232 -19.665086) (xy 370.269283 -19.728153) (xy 370.326597 -19.796475)
			(xy 370.377737 -19.869533) (xy 370.422315 -19.946771) (xy 370.459991 -20.0276) (xy 370.490478 -20.111405)
			(xy 370.513544 -20.197549) (xy 370.529013 -20.285376) (xy 370.536768 -20.374217) (xy 370.537232 -20.418806)
			(xy 370.536774 -20.462284) (xy 370.529196 -20.54891) (xy 370.514098 -20.634545) (xy 370.491595 -20.71854)
			(xy 370.485037 -20.73656) (xy 440.464956 -20.73656) (xy 440.465378 -20.698271) (xy 440.471981 -20.621977)
			(xy 440.485126 -20.546534) (xy 440.504715 -20.472503) (xy 440.51728 -20.436332) (xy 440.51995 -20.4279)
			(xy 440.519937 -20.410225) (xy 440.51728 -20.401788) (xy 440.50475 -20.365606) (xy 440.485173 -20.291575)
			(xy 440.472022 -20.216136) (xy 440.465394 -20.139848) (xy 440.464956 -20.10156) (xy 440.46549 -20.057765)
			(xy 440.474106 -19.9706) (xy 440.49125 -19.884704) (xy 440.516756 -19.80091) (xy 440.550377 -19.72003)
			(xy 440.57062 -19.68119) (xy 440.576064 -19.669733) (xy 440.576046 -19.644397) (xy 440.57062 -19.63293)
			(xy 440.550398 -19.594081) (xy 440.51679 -19.513198) (xy 440.491286 -19.429406) (xy 440.474133 -19.343514)
			(xy 440.465497 -19.256354) (xy 440.464956 -19.21256) (xy 440.465378 -19.174271) (xy 440.471981 -19.097977)
			(xy 440.485126 -19.022534) (xy 440.504715 -18.948503) (xy 440.51728 -18.912332) (xy 440.51995 -18.9039)
			(xy 440.519937 -18.886225) (xy 440.51728 -18.877788) (xy 440.50475 -18.841606) (xy 440.485173 -18.767575)
			(xy 440.472022 -18.692136) (xy 440.465394 -18.615848) (xy 440.464956 -18.57756) (xy 440.465414 -18.53645)
			(xy 440.473005 -18.45458) (xy 440.488119 -18.373761) (xy 440.510626 -18.294681) (xy 440.540334 -18.218015)
			(xy 440.576991 -18.144418) (xy 440.620282 -18.074518) (xy 440.66984 -18.008911) (xy 440.72524 -17.948157)
			(xy 440.78601 -17.892775) (xy 440.851631 -17.843237) (xy 440.921544 -17.799965) (xy 440.995152 -17.76333)
			(xy 441.071826 -17.733644) (xy 441.150912 -17.71116) (xy 441.231736 -17.69607) (xy 441.313608 -17.688502)
			(xy 441.354718 -17.688052) (xy 441.395668 -17.688478) (xy 441.477223 -17.695989) (xy 441.557742 -17.710965)
			(xy 441.636544 -17.733279) (xy 441.712961 -17.762742) (xy 441.786347 -17.799105) (xy 441.856079 -17.842059)
			(xy 441.921567 -17.891241) (xy 441.982258 -17.946234) (xy 442.010292 -17.976088) (xy 442.017449 -17.983101)
			(xy 442.035585 -17.991562) (xy 442.055576 -17.99248) (xy 442.065156 -17.98955) (xy 442.102033 -17.976445)
			(xy 442.177582 -17.955997) (xy 442.254637 -17.94227) (xy 442.3326 -17.935373) (xy 442.371734 -17.93494)
			(xy 442.412849 -17.93538) (xy 442.494727 -17.942971) (xy 442.575557 -17.958083) (xy 442.654646 -17.980589)
			(xy 442.731323 -18.010296) (xy 442.804931 -18.046951) (xy 442.874843 -18.090241) (xy 442.940462 -18.139797)
			(xy 443.001229 -18.195196) (xy 443.056626 -18.255966) (xy 443.106179 -18.321587) (xy 443.149467 -18.391501)
			(xy 443.186119 -18.46511) (xy 443.213248 -18.535142) (xy 451.165468 -18.535142) (xy 451.165468 -18.534888)
			(xy 451.166052 -18.49015) (xy 451.175063 -18.401129) (xy 451.192964 -18.313462) (xy 451.219572 -18.228034)
			(xy 451.236588 -18.186654) (xy 451.240131 -18.177057) (xy 451.240147 -18.15662) (xy 451.236588 -18.14703)
			(xy 451.219555 -18.105656) (xy 451.192939 -18.020228) (xy 451.175038 -17.932559) (xy 451.166032 -17.843535)
			(xy 451.165468 -17.798796) (xy 451.165468 -17.798542) (xy 451.165972 -17.756194) (xy 451.174023 -17.67188)
			(xy 451.190052 -17.588714) (xy 451.213913 -17.507447) (xy 451.245392 -17.428817) (xy 451.284203 -17.353536)
			(xy 451.329993 -17.282284) (xy 451.382349 -17.215708) (xy 451.440797 -17.15441) (xy 451.504807 -17.098945)
			(xy 451.573799 -17.049816) (xy 451.647149 -17.007467) (xy 451.724192 -16.972283) (xy 451.804231 -16.944581)
			(xy 451.88654 -16.924613) (xy 451.970375 -16.91256) (xy 452.054976 -16.90853) (xy 452.139577 -16.91256)
			(xy 452.223412 -16.924613) (xy 452.305721 -16.944581) (xy 452.38576 -16.972283) (xy 452.462803 -17.007467)
			(xy 452.536153 -17.049816) (xy 452.605145 -17.098945) (xy 452.669155 -17.15441) (xy 452.727603 -17.215708)
			(xy 452.779959 -17.282284) (xy 452.825749 -17.353536) (xy 452.86456 -17.428817) (xy 452.896039 -17.507447)
			(xy 452.9199 -17.588714) (xy 452.935929 -17.67188) (xy 452.94398 -17.756194) (xy 452.944484 -17.798542)
			(xy 452.944484 -17.798796) (xy 452.943898 -17.843534) (xy 452.934888 -17.932555) (xy 452.916988 -18.020222)
			(xy 452.890379 -18.10565) (xy 452.873364 -18.14703) (xy 452.869775 -18.156614) (xy 452.869791 -18.177063)
			(xy 452.873364 -18.186654) (xy 452.890389 -18.228031) (xy 452.917007 -18.313458) (xy 452.934911 -18.401126)
			(xy 452.943919 -18.490149) (xy 452.944484 -18.534888) (xy 452.944484 -18.535142) (xy 452.94398 -18.57749)
			(xy 452.935929 -18.661804) (xy 452.9199 -18.74497) (xy 452.896039 -18.826237) (xy 452.86456 -18.904867)
			(xy 452.825749 -18.980148) (xy 452.779959 -19.0514) (xy 452.727603 -19.117976) (xy 452.669155 -19.179274)
			(xy 452.605145 -19.234739) (xy 452.536153 -19.283868) (xy 452.462803 -19.326217) (xy 452.38576 -19.361401)
			(xy 452.305721 -19.389103) (xy 452.223412 -19.409071) (xy 452.139577 -19.421124) (xy 452.054976 -19.425155)
			(xy 451.970375 -19.421124) (xy 451.88654 -19.409071) (xy 451.804231 -19.389103) (xy 451.724192 -19.361401)
			(xy 451.647149 -19.326217) (xy 451.573799 -19.283868) (xy 451.504807 -19.234739) (xy 451.440797 -19.179274)
			(xy 451.382349 -19.117976) (xy 451.329993 -19.0514) (xy 451.284203 -18.980148) (xy 451.245392 -18.904867)
			(xy 451.213913 -18.826237) (xy 451.190052 -18.74497) (xy 451.174023 -18.661804) (xy 451.165972 -18.57749)
			(xy 451.165468 -18.535142) (xy 443.213248 -18.535142) (xy 443.215823 -18.541788) (xy 443.238325 -18.620878)
			(xy 443.253434 -18.701708) (xy 443.261021 -18.783587) (xy 443.261496 -18.824702) (xy 443.261095 -18.862992)
			(xy 443.254486 -18.939286) (xy 443.241336 -19.014729) (xy 443.221741 -19.088759) (xy 443.209172 -19.12493)
			(xy 443.206519 -19.133366) (xy 443.20652 -19.151037) (xy 443.209172 -19.159474) (xy 443.221718 -19.195651)
			(xy 443.24129 -19.269684) (xy 443.254437 -19.345124) (xy 443.261061 -19.421414) (xy 443.261496 -19.459702)
			(xy 443.260982 -19.503497) (xy 443.252361 -19.590663) (xy 443.235212 -19.676559) (xy 443.209701 -19.760353)
			(xy 443.176076 -19.841233) (xy 443.155832 -19.880072) (xy 443.15041 -19.891537) (xy 443.150411 -19.916866)
			(xy 443.155832 -19.928332) (xy 443.176073 -19.967172) (xy 443.209679 -20.048057) (xy 443.235179 -20.131851)
			(xy 443.252328 -20.217745) (xy 443.260958 -20.304908) (xy 443.261496 -20.348702) (xy 443.261095 -20.386992)
			(xy 443.254486 -20.463286) (xy 443.241336 -20.538729) (xy 443.221741 -20.612759) (xy 443.209172 -20.64893)
			(xy 443.206519 -20.657366) (xy 443.20652 -20.675037) (xy 443.209172 -20.683474) (xy 443.221718 -20.719651)
			(xy 443.24129 -20.793684) (xy 443.254437 -20.869124) (xy 443.261061 -20.945414) (xy 443.261496 -20.983702)
			(xy 443.260989 -21.024815) (xy 443.253402 -21.106691) (xy 443.238293 -21.187518) (xy 443.215791 -21.266605)
			(xy 443.186088 -21.343279) (xy 443.149437 -21.416886) (xy 443.106152 -21.486797) (xy 443.0566 -21.552416)
			(xy 443.001205 -21.613183) (xy 442.94044 -21.66858) (xy 442.874823 -21.718133) (xy 442.804914 -21.761422)
			(xy 442.731309 -21.798075) (xy 442.654636 -21.827781) (xy 442.575549 -21.850286) (xy 442.494723 -21.865398)
			(xy 442.412847 -21.872988) (xy 442.371734 -21.873464) (xy 442.330778 -21.872996) (xy 442.249213 -21.865468)
			(xy 442.168686 -21.850472) (xy 442.089879 -21.828136) (xy 442.013459 -21.798648) (xy 441.940074 -21.762259)
			(xy 441.870346 -21.719277) (xy 441.804865 -21.670066) (xy 441.744186 -21.615042) (xy 441.71616 -21.585174)
			(xy 441.709037 -21.578124) (xy 441.690882 -21.569676) (xy 441.670879 -21.568774) (xy 441.661296 -21.571712)
			(xy 441.624502 -21.584749) (xy 441.549137 -21.605106) (xy 441.472276 -21.618771) (xy 441.394513 -21.625637)
			(xy 441.35548 -21.626068) (xy 441.354718 -21.626068) (xy 441.313612 -21.62557) (xy 441.23175 -21.617988)
			(xy 441.150936 -21.602885) (xy 441.07186 -21.580392) (xy 440.995197 -21.5507) (xy 440.9216 -21.514062)
			(xy 440.851696 -21.470791) (xy 440.786082 -21.421255) (xy 440.725318 -21.365878) (xy 440.669922 -21.305132)
			(xy 440.620366 -21.239533) (xy 440.577073 -21.169643) (xy 440.540412 -21.096058) (xy 440.510696 -21.019403)
			(xy 440.488178 -20.940335) (xy 440.473051 -20.859526) (xy 440.465443 -20.777666) (xy 440.464956 -20.73656)
			(xy 370.485037 -20.73656) (xy 370.461858 -20.800254) (xy 370.425114 -20.879065) (xy 370.381641 -20.954375)
			(xy 370.331772 -21.02561) (xy 370.275884 -21.092228) (xy 370.214404 -21.153723) (xy 370.147799 -21.209627)
			(xy 370.076576 -21.259513) (xy 370.001276 -21.303004) (xy 369.922473 -21.339767) (xy 369.840767 -21.369523)
			(xy 369.756778 -21.392046) (xy 369.671146 -21.407165) (xy 369.584522 -21.414763) (xy 369.541044 -21.415248)
			(xy 369.515644 -21.415248) (xy 369.470345 -21.414745) (xy 369.38011 -21.406627) (xy 369.290966 -21.390454)
			(xy 369.203632 -21.366354) (xy 369.118809 -21.334523) (xy 369.037181 -21.295216) (xy 368.959405 -21.24875)
			(xy 368.886107 -21.195499) (xy 368.817878 -21.135892) (xy 368.755267 -21.070409) (xy 368.698779 -20.999577)
			(xy 368.648867 -20.923967) (xy 368.605934 -20.844186) (xy 368.570325 -20.760878) (xy 368.542328 -20.674714)
			(xy 368.522167 -20.586387) (xy 368.510005 -20.496608) (xy 368.50594 -20.4061) (xy 259.309108 -20.4061)
			(xy 259.309108 -25.982422) (xy 440.239912 -25.982422) (xy 440.240419 -25.939461) (xy 440.248702 -25.85394)
			(xy 440.265193 -25.769616) (xy 440.289738 -25.687275) (xy 440.322109 -25.607684) (xy 440.362003 -25.531586)
			(xy 440.40905 -25.459689) (xy 440.46281 -25.392664) (xy 440.522782 -25.331135) (xy 440.588408 -25.275676)
			(xy 440.659076 -25.226803) (xy 440.69635 -25.205436) (xy 440.704332 -25.200469) (xy 440.716316 -25.186006)
			(xy 440.719718 -25.177242) (xy 440.733823 -25.137039) (xy 440.768699 -25.059297) (xy 440.810847 -24.985247)
			(xy 440.859883 -24.915565) (xy 440.915357 -24.850891) (xy 440.97676 -24.791817) (xy 441.043529 -24.738885)
			(xy 441.115054 -24.692579) (xy 441.190679 -24.653323) (xy 441.26971 -24.621478) (xy 441.351424 -24.597336)
			(xy 441.435072 -24.581116) (xy 441.519887 -24.572969) (xy 441.56249 -24.572468) (xy 441.562998 -24.572468)
			(xy 441.606762 -24.572982) (xy 441.693869 -24.581557) (xy 441.77971 -24.598653) (xy 441.863455 -24.624106)
			(xy 441.944293 -24.657667) (xy 441.983114 -24.677878) (xy 441.994467 -24.683205) (xy 442.019513 -24.683205)
			(xy 442.030866 -24.677878) (xy 442.069745 -24.657673) (xy 442.150684 -24.6241) (xy 442.23453 -24.598641)
			(xy 442.320472 -24.581544) (xy 442.407677 -24.572973) (xy 442.45149 -24.572468) (xy 442.495305 -24.572971)
			(xy 442.582516 -24.581515) (xy 442.668462 -24.5986) (xy 442.752311 -24.62406) (xy 442.833246 -24.657648)
			(xy 442.872114 -24.677878) (xy 442.883467 -24.683205) (xy 442.908513 -24.683205) (xy 442.919866 -24.677878)
			(xy 442.959061 -24.657499) (xy 443.040701 -24.623735) (xy 443.125286 -24.598229) (xy 443.211982 -24.581233)
			(xy 443.255908 -24.576532) (xy 443.266358 -24.575008) (xy 443.284755 -24.564681) (xy 443.297434 -24.547819)
			(xy 443.300358 -24.53767) (xy 443.310609 -24.496358) (xy 443.337964 -24.415751) (xy 443.372893 -24.338124)
			(xy 443.415077 -24.264189) (xy 443.464129 -24.19462) (xy 443.519603 -24.130055) (xy 443.580989 -24.071084)
			(xy 443.647727 -24.018245) (xy 443.719207 -23.972023) (xy 443.794775 -23.932839) (xy 443.87374 -23.901052)
			(xy 443.955381 -23.876952) (xy 444.038949 -23.86076) (xy 444.123683 -23.852625) (xy 444.166244 -23.852124)
			(xy 444.207348 -23.852525) (xy 444.289205 -23.860114) (xy 444.370013 -23.875224) (xy 444.449082 -23.897725)
			(xy 444.525738 -23.927425) (xy 444.599326 -23.964072) (xy 444.669219 -24.007352) (xy 444.734821 -24.056897)
			(xy 444.795571 -24.112283) (xy 444.850952 -24.173038) (xy 444.900491 -24.238644) (xy 444.943765 -24.30854)
			(xy 444.980405 -24.382132) (xy 445.0101 -24.45879) (xy 445.032594 -24.537861) (xy 445.047697 -24.61867)
			(xy 445.055279 -24.700528) (xy 445.055752 -24.741632) (xy 445.055238 -24.782654) (xy 445.04768 -24.864348)
			(xy 445.032631 -24.944999) (xy 445.01022 -25.023921) (xy 444.980635 -25.100445) (xy 444.94413 -25.173919)
			(xy 444.901014 -25.243719) (xy 444.851653 -25.309252) (xy 444.796467 -25.369961) (xy 444.735925 -25.425331)
			(xy 444.670542 -25.47489) (xy 444.600873 -25.518217) (xy 444.52751 -25.554945) (xy 444.451076 -25.584761)
			(xy 444.372222 -25.607412) (xy 444.291617 -25.622705) (xy 444.250826 -25.627076) (xy 444.240379 -25.628618)
			(xy 444.221981 -25.638935) (xy 444.2093 -25.655791) (xy 444.206376 -25.665938) (xy 444.196473 -25.705794)
			(xy 444.170375 -25.783666) (xy 444.137208 -25.8588) (xy 444.097254 -25.930555) (xy 444.050854 -25.998321)
			(xy 443.998403 -26.061519) (xy 443.940348 -26.119612) (xy 443.877184 -26.172104) (xy 443.809448 -26.218548)
			(xy 443.773814 -26.238962) (xy 443.765845 -26.243946) (xy 443.753852 -26.258396) (xy 443.750446 -26.267156)
			(xy 443.736369 -26.307378) (xy 443.701515 -26.385148) (xy 443.659384 -26.459228) (xy 443.61036 -26.528939)
			(xy 443.554893 -26.593641) (xy 443.493492 -26.652741) (xy 443.42672 -26.705698) (xy 443.355189 -26.752025)
			(xy 443.279554 -26.791298) (xy 443.200511 -26.823158) (xy 443.118782 -26.847311) (xy 443.035118 -26.863536)
			(xy 442.950285 -26.871685) (xy 442.907674 -26.872184) (xy 442.863879 -26.871639) (xy 442.776715 -26.863025)
			(xy 442.690819 -26.845883) (xy 442.607025 -26.82038) (xy 442.526144 -26.786761) (xy 442.487304 -26.76652)
			(xy 442.475838 -26.761102) (xy 442.45051 -26.761102) (xy 442.439044 -26.76652) (xy 442.400209 -26.786769)
			(xy 442.319322 -26.820374) (xy 442.235526 -26.845873) (xy 442.149632 -26.863019) (xy 442.062468 -26.871647)
			(xy 442.018674 -26.872184) (xy 441.974879 -26.871639) (xy 441.887715 -26.863025) (xy 441.801819 -26.845883)
			(xy 441.718025 -26.82038) (xy 441.637144 -26.786761) (xy 441.598304 -26.76652) (xy 441.586838 -26.761102)
			(xy 441.56151 -26.761102) (xy 441.550044 -26.76652) (xy 441.511209 -26.786769) (xy 441.430322 -26.820374)
			(xy 441.346526 -26.845873) (xy 441.260632 -26.863019) (xy 441.173468 -26.871647) (xy 441.129674 -26.872184)
			(xy 441.08856 -26.871712) (xy 441.006683 -26.864123) (xy 440.925855 -26.849012) (xy 440.846767 -26.826507)
			(xy 440.770092 -26.796802) (xy 440.696485 -26.760149) (xy 440.626574 -26.71686) (xy 440.560955 -26.667306)
			(xy 440.500188 -26.61191) (xy 440.444791 -26.551142) (xy 440.395237 -26.485523) (xy 440.351949 -26.415612)
			(xy 440.315297 -26.342004) (xy 440.285592 -26.265329) (xy 440.263088 -26.186241) (xy 440.247977 -26.105413)
			(xy 440.240388 -26.023536) (xy 440.239912 -25.982422) (xy 259.309108 -25.982422) (xy 259.309108 -32.117846)
			(xy 455.218281 -32.117846) (xy 455.218281 -31.988706) (xy 455.226231 -31.859811) (xy 455.242101 -31.731651)
			(xy 455.26583 -31.60471) (xy 455.297329 -31.479471) (xy 455.336478 -31.356408) (xy 455.383129 -31.235989)
			(xy 455.437104 -31.11867) (xy 455.498199 -31.004896) (xy 455.566182 -30.895099) (xy 455.640796 -30.789696)
			(xy 455.721757 -30.689086) (xy 455.808757 -30.593651) (xy 455.901468 -30.503752) (xy 455.999538 -30.419731)
			(xy 456.102593 -30.341907) (xy 456.210244 -30.270575) (xy 456.322083 -30.206005) (xy 456.437684 -30.148443)
			(xy 456.556609 -30.098106) (xy 456.678408 -30.055186) (xy 456.802618 -30.019845) (xy 456.928767 -29.992218)
			(xy 457.056379 -29.972409) (xy 457.184968 -29.960493) (xy 457.314046 -29.956517) (xy 457.443124 -29.960493)
			(xy 457.571713 -29.972409) (xy 457.699325 -29.992218) (xy 457.825474 -30.019845) (xy 457.949684 -30.055186)
			(xy 458.071483 -30.098106) (xy 458.190408 -30.148443) (xy 458.306009 -30.206005) (xy 458.417848 -30.270575)
			(xy 458.525499 -30.341907) (xy 458.628554 -30.419731) (xy 458.726624 -30.503752) (xy 458.819335 -30.593651)
			(xy 458.906335 -30.689086) (xy 458.987296 -30.789696) (xy 459.06191 -30.895099) (xy 459.129893 -31.004896)
			(xy 459.190988 -31.11867) (xy 459.244963 -31.235989) (xy 459.291614 -31.356408) (xy 459.330763 -31.479471)
			(xy 459.362262 -31.60471) (xy 459.385991 -31.731651) (xy 459.401861 -31.859811) (xy 459.409811 -31.988706)
			(xy 459.410308 -32.053276) (xy 459.409811 -32.117846) (xy 459.401861 -32.246741) (xy 459.385991 -32.374901)
			(xy 459.362262 -32.501842) (xy 459.330763 -32.627081) (xy 459.291614 -32.750144) (xy 459.244963 -32.870563)
			(xy 459.190988 -32.987882) (xy 459.129893 -33.101656) (xy 459.06191 -33.211453) (xy 458.987296 -33.316856)
			(xy 458.906335 -33.417466) (xy 458.819335 -33.512901) (xy 458.726624 -33.6028) (xy 458.628554 -33.686821)
			(xy 458.525499 -33.764645) (xy 458.417848 -33.835977) (xy 458.307206 -33.899856) (xy 461.798924 -33.899856)
			(xy 461.798924 -32.299656) (xy 461.799422 -32.222373) (xy 461.807378 -32.068013) (xy 461.823271 -31.914267)
			(xy 461.847057 -31.761543) (xy 461.878674 -31.610247) (xy 461.918037 -31.460778) (xy 461.965042 -31.313534)
			(xy 462.019566 -31.168904) (xy 462.081462 -31.027274) (xy 462.150567 -30.889017) (xy 462.226698 -30.754502)
			(xy 462.309652 -30.624083) (xy 462.399211 -30.498108) (xy 462.495135 -30.376911) (xy 462.597172 -30.260812)
			(xy 462.705049 -30.15012) (xy 462.818482 -30.045128) (xy 462.93717 -29.946115) (xy 463.060797 -29.853342)
			(xy 463.189036 -29.767057) (xy 463.321547 -29.687488) (xy 463.457979 -29.614846) (xy 463.597969 -29.549324)
			(xy 463.741146 -29.491095) (xy 463.887131 -29.440314) (xy 464.035537 -29.397115) (xy 464.185969 -29.361613)
			(xy 464.33803 -29.333903) (xy 464.491316 -29.314057) (xy 464.64542 -29.302128) (xy 464.799934 -29.298149)
			(xy 464.954448 -29.302128) (xy 465.108552 -29.314057) (xy 465.261838 -29.333903) (xy 465.413899 -29.361613)
			(xy 465.564331 -29.397115) (xy 465.712737 -29.440314) (xy 465.858722 -29.491095) (xy 466.001899 -29.549324)
			(xy 466.141889 -29.614846) (xy 466.278321 -29.687488) (xy 466.410832 -29.767057) (xy 466.539071 -29.853342)
			(xy 466.662698 -29.946115) (xy 466.781386 -30.045128) (xy 466.894819 -30.15012) (xy 467.002696 -30.260812)
			(xy 467.104733 -30.376911) (xy 467.200657 -30.498108) (xy 467.290216 -30.624083) (xy 467.37317 -30.754502)
			(xy 467.449301 -30.889017) (xy 467.518406 -31.027274) (xy 467.580302 -31.168904) (xy 467.634826 -31.313534)
			(xy 467.681831 -31.460778) (xy 467.721194 -31.610247) (xy 467.752811 -31.761543) (xy 467.776597 -31.914267)
			(xy 467.79249 -32.068013) (xy 467.800446 -32.222373) (xy 467.800944 -32.299656) (xy 467.800944 -33.899856)
			(xy 467.800446 -33.977139) (xy 467.79249 -34.131499) (xy 467.776597 -34.285245) (xy 467.752811 -34.437969)
			(xy 467.721194 -34.589265) (xy 467.681831 -34.738734) (xy 467.634826 -34.885978) (xy 467.580302 -35.030608)
			(xy 467.518406 -35.172238) (xy 467.449301 -35.310495) (xy 467.37317 -35.44501) (xy 467.290216 -35.575429)
			(xy 467.200657 -35.701404) (xy 467.104733 -35.822601) (xy 467.002696 -35.9387) (xy 466.894819 -36.049392)
			(xy 466.781386 -36.154384) (xy 466.662698 -36.253397) (xy 466.539071 -36.34617) (xy 466.410832 -36.432455)
			(xy 466.278321 -36.512024) (xy 466.141889 -36.584666) (xy 466.001899 -36.650188) (xy 465.858722 -36.708417)
			(xy 465.712737 -36.759198) (xy 465.564331 -36.802397) (xy 465.413899 -36.837899) (xy 465.261838 -36.865609)
			(xy 465.108552 -36.885455) (xy 464.954448 -36.897384) (xy 464.799934 -36.901364) (xy 464.64542 -36.897384)
			(xy 464.491316 -36.885455) (xy 464.33803 -36.865609) (xy 464.185969 -36.837899) (xy 464.035537 -36.802397)
			(xy 463.887131 -36.759198) (xy 463.741146 -36.708417) (xy 463.597969 -36.650188) (xy 463.457979 -36.584666)
			(xy 463.321547 -36.512024) (xy 463.189036 -36.432455) (xy 463.060797 -36.34617) (xy 462.93717 -36.253397)
			(xy 462.818482 -36.154384) (xy 462.705049 -36.049392) (xy 462.597172 -35.9387) (xy 462.495135 -35.822601)
			(xy 462.399211 -35.701404) (xy 462.309652 -35.575429) (xy 462.226698 -35.44501) (xy 462.150567 -35.310495)
			(xy 462.081462 -35.172238) (xy 462.019566 -35.030608) (xy 461.965042 -34.885978) (xy 461.918037 -34.738734)
			(xy 461.878674 -34.589265) (xy 461.847057 -34.437969) (xy 461.823271 -34.285245) (xy 461.807378 -34.131499)
			(xy 461.799422 -33.977139) (xy 461.798924 -33.899856) (xy 458.307206 -33.899856) (xy 458.306009 -33.900547)
			(xy 458.190408 -33.958109) (xy 458.071483 -34.008446) (xy 457.949684 -34.051366) (xy 457.825474 -34.086707)
			(xy 457.699325 -34.114334) (xy 457.571713 -34.134143) (xy 457.443124 -34.146059) (xy 457.314046 -34.150036)
			(xy 457.184968 -34.146059) (xy 457.056379 -34.134143) (xy 456.928767 -34.114334) (xy 456.802618 -34.086707)
			(xy 456.678408 -34.051366) (xy 456.556609 -34.008446) (xy 456.437684 -33.958109) (xy 456.322083 -33.900547)
			(xy 456.210244 -33.835977) (xy 456.102593 -33.764645) (xy 455.999538 -33.686821) (xy 455.901468 -33.6028)
			(xy 455.808757 -33.512901) (xy 455.721757 -33.417466) (xy 455.640796 -33.316856) (xy 455.566182 -33.211453)
			(xy 455.498199 -33.101656) (xy 455.437104 -32.987882) (xy 455.383129 -32.870563) (xy 455.336478 -32.750144)
			(xy 455.297329 -32.627081) (xy 455.26583 -32.501842) (xy 455.242101 -32.374901) (xy 455.226231 -32.246741)
			(xy 455.218281 -32.117846) (xy 259.309108 -32.117846) (xy 259.309108 -34.120074) (xy 259.308624 -34.190457)
			(xy 259.300733 -34.331001) (xy 259.284973 -34.470882) (xy 259.261395 -34.609659) (xy 259.230073 -34.746896)
			(xy 259.191105 -34.882161) (xy 259.144614 -35.015028) (xy 259.090747 -35.145079) (xy 259.029671 -35.271905)
			(xy 258.961581 -35.395107) (xy 258.88669 -35.514297) (xy 258.805233 -35.629101) (xy 258.717468 -35.739156)
			(xy 258.62367 -35.844118) (xy 258.524134 -35.943655) (xy 258.419173 -36.037454) (xy 258.309118 -36.12522)
			(xy 258.194315 -36.206678) (xy 258.075126 -36.28157) (xy 257.951924 -36.349661) (xy 257.825099 -36.410738)
			(xy 257.695048 -36.464606) (xy 257.562182 -36.511099) (xy 257.426917 -36.550068) (xy 257.289681 -36.581391)
			(xy 257.150904 -36.60497) (xy 257.011023 -36.620731) (xy 256.870479 -36.628623) (xy 256.800096 -36.629086)
			(xy 225.300032 -36.629086) (xy 225.229649 -36.628602) (xy 225.089105 -36.620711) (xy 224.949224 -36.604952)
			(xy 224.810447 -36.581374) (xy 224.673211 -36.550052) (xy 224.537946 -36.511084) (xy 224.40508 -36.464594)
			(xy 224.275029 -36.410726) (xy 224.148203 -36.349651) (xy 224.025001 -36.28156) (xy 223.905811 -36.206669)
			(xy 223.791008 -36.125213) (xy 223.680953 -36.037447) (xy 223.575992 -35.943648) (xy 223.476456 -35.844112)
			(xy 223.382657 -35.739152) (xy 223.294891 -35.629097) (xy 223.213434 -35.514294) (xy 223.138543 -35.395104)
			(xy 223.070452 -35.271902) (xy 223.009377 -35.145077) (xy 222.955509 -35.015026) (xy 222.909017 -34.882159)
			(xy 222.870049 -34.746895) (xy 222.838727 -34.609659) (xy 222.815149 -34.470882) (xy 222.799389 -34.331001)
			(xy 222.791498 -34.190457) (xy 222.79102 -34.120074) (xy 222.79102 -13.780008) (xy 222.790499 -13.724238)
			(xy 222.782164 -13.613011) (xy 222.765541 -13.502717) (xy 222.740722 -13.393974) (xy 222.707846 -13.287389)
			(xy 222.667097 -13.183559) (xy 222.618703 -13.083065) (xy 222.562935 -12.986469) (xy 222.500103 -12.894309)
			(xy 222.430561 -12.807103) (xy 222.354696 -12.725338) (xy 222.272933 -12.64947) (xy 222.185729 -12.579925)
			(xy 222.093572 -12.517091) (xy 221.996977 -12.461319) (xy 221.896485 -12.412922) (xy 221.792656 -12.37217)
			(xy 221.686073 -12.339291) (xy 221.57733 -12.314468) (xy 221.467037 -12.297841) (xy 221.35581 -12.289503)
			(xy 221.30004 -12.289028) (xy 196.701918 -12.289028) (xy 196.631535 -12.288544) (xy 196.49099 -12.280652)
			(xy 196.35111 -12.264892) (xy 196.212332 -12.241314) (xy 196.075095 -12.209992) (xy 195.939831 -12.171024)
			(xy 195.806964 -12.124532) (xy 195.676913 -12.070665) (xy 195.550086 -12.009589) (xy 195.426884 -11.941499)
			(xy 195.307694 -11.866608) (xy 195.19289 -11.785152) (xy 195.082834 -11.697386) (xy 194.977873 -11.603588)
			(xy 194.878335 -11.504052) (xy 194.784536 -11.399092) (xy 194.696769 -11.289037) (xy 194.615311 -11.174234)
			(xy 194.540418 -11.055045) (xy 194.472326 -10.931844) (xy 194.411249 -10.805018) (xy 194.35738 -10.674968)
			(xy 194.310887 -10.542102) (xy 194.271917 -10.406837) (xy 194.240593 -10.269601) (xy 194.217013 -10.130824)
			(xy 194.201251 -9.990943) (xy 194.193357 -9.850399) (xy 194.192906 -9.780016) (xy 194.192906 -5.839714)
			(xy 194.192489 -5.82969) (xy 194.184822 -5.811168) (xy 194.170649 -5.79699) (xy 194.152129 -5.789315)
			(xy 194.142106 -5.788914) (xy 126.661926 -5.788914) (xy 126.651902 -5.789329) (xy 126.633379 -5.796995)
			(xy 126.619202 -5.811169) (xy 126.611531 -5.82969) (xy 126.611126 -5.839714) (xy 126.611126 -9.780016)
			(xy 126.610632 -9.850398) (xy 126.602738 -9.990941) (xy 126.586977 -10.13082) (xy 126.563397 -10.269595)
			(xy 126.532074 -10.40683) (xy 126.51969 -10.449814) (xy 127.350273 -10.449814) (xy 127.354278 -10.361906)
			(xy 127.366261 -10.274726) (xy 127.386121 -10.188997) (xy 127.413696 -10.105429) (xy 127.448755 -10.024715)
			(xy 127.491008 -9.947523) (xy 127.540106 -9.874494) (xy 127.595642 -9.806232) (xy 127.657154 -9.743302)
			(xy 127.724135 -9.686228) (xy 127.796028 -9.63548) (xy 127.872237 -9.59148) (xy 127.952132 -9.554593)
			(xy 128.035051 -9.525124) (xy 128.120306 -9.503317) (xy 128.20719 -9.489353) (xy 128.294984 -9.483347)
			(xy 128.382961 -9.485351) (xy 128.470391 -9.495346) (xy 128.55655 -9.51325) (xy 128.640724 -9.538914)
			(xy 128.722215 -9.572127) (xy 128.800349 -9.612613) (xy 128.874477 -9.660035) (xy 128.943985 -9.714002)
			(xy 129.008299 -9.774067) (xy 129.066883 -9.839731) (xy 129.119254 -9.91045) (xy 129.164977 -9.985638)
			(xy 129.203674 -10.064673) (xy 129.235023 -10.146899) (xy 129.258765 -10.231635) (xy 129.265932 -10.270552)
			(xy 131.639267 -10.270552) (xy 131.639267 -10.216048) (xy 131.647024 -10.162097) (xy 131.66238 -10.1098)
			(xy 131.685023 -10.060221) (xy 131.714491 -10.014369) (xy 131.750185 -9.973177) (xy 131.791377 -9.937485)
			(xy 131.83723 -9.908018) (xy 131.88681 -9.885377) (xy 131.939107 -9.870022) (xy 131.993058 -9.862267)
			(xy 132.02031 -9.861804) (xy 132.88391 -9.861804) (xy 132.911162 -9.862266) (xy 132.96511 -9.870024)
			(xy 133.017405 -9.885381) (xy 133.066983 -9.908023) (xy 133.112833 -9.937491) (xy 133.154024 -9.973183)
			(xy 133.189715 -10.014375) (xy 133.219181 -10.060226) (xy 133.241823 -10.109804) (xy 133.257178 -10.1621)
			(xy 133.264934 -10.216048) (xy 133.264934 -10.270552) (xy 133.257178 -10.3245) (xy 133.241823 -10.376796)
			(xy 133.219181 -10.426374) (xy 133.189715 -10.472225) (xy 133.154024 -10.513417) (xy 133.112833 -10.549109)
			(xy 133.066983 -10.578577) (xy 133.017405 -10.601219) (xy 132.96511 -10.616576) (xy 132.911162 -10.624334)
			(xy 132.88391 -10.62482) (xy 132.02031 -10.62482) (xy 131.993058 -10.624333) (xy 131.939107 -10.616578)
			(xy 131.88681 -10.601223) (xy 131.83723 -10.578582) (xy 131.791377 -10.549115) (xy 131.750185 -10.513423)
			(xy 131.714491 -10.472231) (xy 131.685023 -10.426379) (xy 131.66238 -10.3768) (xy 131.647024 -10.324503)
			(xy 131.639267 -10.270552) (xy 129.265932 -10.270552) (xy 129.274703 -10.318179) (xy 129.282705 -10.405814)
			(xy 129.283206 -10.449814) (xy 129.282705 -10.493814) (xy 129.274703 -10.581449) (xy 129.258765 -10.667993)
			(xy 129.235023 -10.752729) (xy 129.211985 -10.813156) (xy 169.954611 -10.813156) (xy 169.954611 -10.758644)
			(xy 169.962369 -10.704687) (xy 169.977727 -10.652382) (xy 170.000372 -10.602796) (xy 170.029844 -10.556938)
			(xy 170.065542 -10.51574) (xy 170.106739 -10.480043) (xy 170.152598 -10.450571) (xy 170.202184 -10.427926)
			(xy 170.254488 -10.412568) (xy 170.308446 -10.404811) (xy 170.335702 -10.404348) (xy 171.199302 -10.404348)
			(xy 171.22655 -10.404922) (xy 171.280491 -10.412678) (xy 171.33278 -10.428032) (xy 171.382351 -10.45067)
			(xy 171.428196 -10.480133) (xy 171.469381 -10.515821) (xy 171.505068 -10.557006) (xy 171.534531 -10.602851)
			(xy 171.557169 -10.652422) (xy 171.572522 -10.704711) (xy 171.580278 -10.758652) (xy 171.580278 -10.813148)
			(xy 171.572522 -10.867089) (xy 171.557169 -10.919378) (xy 171.534531 -10.968949) (xy 171.505068 -11.014794)
			(xy 171.469381 -11.055979) (xy 171.428196 -11.091667) (xy 171.382351 -11.12113) (xy 171.33278 -11.143768)
			(xy 171.280491 -11.159122) (xy 171.22655 -11.166878) (xy 171.199302 -11.167364) (xy 170.335702 -11.167364)
			(xy 170.308446 -11.166989) (xy 170.254488 -11.159232) (xy 170.202184 -11.143874) (xy 170.152598 -11.121229)
			(xy 170.106739 -11.091757) (xy 170.065542 -11.05606) (xy 170.029844 -11.014862) (xy 170.000372 -10.969004)
			(xy 169.977727 -10.919418) (xy 169.962369 -10.867113) (xy 169.954611 -10.813156) (xy 129.211985 -10.813156)
			(xy 129.203674 -10.834955) (xy 129.164977 -10.91399) (xy 129.119254 -10.989178) (xy 129.066883 -11.059897)
			(xy 129.008299 -11.125561) (xy 128.943985 -11.185626) (xy 128.874477 -11.239593) (xy 128.800349 -11.287015)
			(xy 128.722215 -11.327501) (xy 128.640724 -11.360714) (xy 128.55655 -11.386378) (xy 128.470391 -11.404282)
			(xy 128.382961 -11.414277) (xy 128.294984 -11.416281) (xy 128.20719 -11.410275) (xy 128.120306 -11.396311)
			(xy 128.035051 -11.374504) (xy 127.952132 -11.345035) (xy 127.872237 -11.308148) (xy 127.796028 -11.264148)
			(xy 127.724135 -11.2134) (xy 127.657154 -11.156326) (xy 127.595642 -11.093396) (xy 127.540106 -11.025134)
			(xy 127.491008 -10.952105) (xy 127.448755 -10.874913) (xy 127.413696 -10.794199) (xy 127.386121 -10.710631)
			(xy 127.366261 -10.624902) (xy 127.354278 -10.537722) (xy 127.350273 -10.449814) (xy 126.51969 -10.449814)
			(xy 126.493105 -10.542092) (xy 126.446613 -10.674957) (xy 126.392744 -10.805006) (xy 126.331668 -10.93183)
			(xy 126.263578 -11.05503) (xy 126.188687 -11.174218) (xy 126.10723 -11.28902) (xy 126.019465 -11.399074)
			(xy 125.925667 -11.504033) (xy 125.826132 -11.603569) (xy 125.721172 -11.697366) (xy 125.611118 -11.785131)
			(xy 125.496317 -11.866588) (xy 125.495706 -11.866972) (xy 129.833804 -11.866972) (xy 129.833804 -11.812428)
			(xy 129.841567 -11.758438) (xy 129.856934 -11.706103) (xy 129.879594 -11.656488) (xy 129.909085 -11.610603)
			(xy 129.944805 -11.569383) (xy 129.986029 -11.533665) (xy 130.031916 -11.504179) (xy 130.081533 -11.481523)
			(xy 130.13387 -11.46616) (xy 130.18786 -11.458401) (xy 130.215132 -11.45794) (xy 131.078732 -11.45794)
			(xy 131.106 -11.458425) (xy 131.15998 -11.46619) (xy 131.212306 -11.481558) (xy 131.261913 -11.504216)
			(xy 131.30779 -11.533703) (xy 131.349004 -11.569419) (xy 131.384716 -11.610636) (xy 131.414199 -11.656515)
			(xy 131.436853 -11.706124) (xy 131.452217 -11.758451) (xy 131.459978 -11.812432) (xy 131.459978 -11.866968)
			(xy 131.452217 -11.920949) (xy 131.436853 -11.973276) (xy 131.432747 -11.982267) (xy 135.233942 -11.982267)
			(xy 135.233942 -11.927733) (xy 135.241703 -11.873755) (xy 135.257066 -11.82143) (xy 135.279719 -11.771824)
			(xy 135.309201 -11.725946) (xy 135.344912 -11.684731) (xy 135.386124 -11.649018) (xy 135.431999 -11.619533)
			(xy 135.481603 -11.596876) (xy 135.533927 -11.581509) (xy 135.587905 -11.573744) (xy 135.615172 -11.573256)
			(xy 136.478772 -11.573256) (xy 136.506046 -11.573682) (xy 136.560038 -11.581441) (xy 136.612377 -11.596805)
			(xy 136.661996 -11.619462) (xy 136.707885 -11.648951) (xy 136.74911 -11.68467) (xy 136.784832 -11.725893)
			(xy 136.814324 -11.77178) (xy 136.836985 -11.821397) (xy 136.852353 -11.873735) (xy 136.860116 -11.927726)
			(xy 136.860116 -11.982274) (xy 136.852353 -12.036265) (xy 136.836985 -12.088603) (xy 136.814324 -12.13822)
			(xy 136.784832 -12.184107) (xy 136.74911 -12.22533) (xy 136.707885 -12.261049) (xy 136.661996 -12.290538)
			(xy 136.612377 -12.313195) (xy 136.560038 -12.328559) (xy 136.506046 -12.336318) (xy 136.478772 -12.33678)
			(xy 135.615172 -12.33678) (xy 135.587905 -12.336256) (xy 135.533927 -12.328491) (xy 135.481603 -12.313124)
			(xy 135.431999 -12.290467) (xy 135.386124 -12.260982) (xy 135.344912 -12.225269) (xy 135.309201 -12.184054)
			(xy 135.279719 -12.138176) (xy 135.257066 -12.08857) (xy 135.241703 -12.036245) (xy 135.233942 -11.982267)
			(xy 131.432747 -11.982267) (xy 131.414199 -12.022885) (xy 131.384716 -12.068764) (xy 131.349004 -12.109981)
			(xy 131.30779 -12.145697) (xy 131.261913 -12.175184) (xy 131.212306 -12.197842) (xy 131.15998 -12.21321)
			(xy 131.106 -12.220975) (xy 131.078732 -12.221464) (xy 130.215132 -12.221464) (xy 130.18786 -12.220999)
			(xy 130.13387 -12.21324) (xy 130.081533 -12.197877) (xy 130.031916 -12.175221) (xy 129.986029 -12.145735)
			(xy 129.944805 -12.110017) (xy 129.909085 -12.068797) (xy 129.879594 -12.022912) (xy 129.856934 -11.973297)
			(xy 129.841567 -11.920962) (xy 129.833804 -11.866972) (xy 125.495706 -11.866972) (xy 125.377128 -11.941479)
			(xy 125.253928 -12.009569) (xy 125.127104 -12.070645) (xy 124.997055 -12.124513) (xy 124.86419 -12.171005)
			(xy 124.728928 -12.209974) (xy 124.591693 -12.241298) (xy 124.452918 -12.264877) (xy 124.313039 -12.280639)
			(xy 124.172496 -12.288532) (xy 124.102114 -12.289028) (xy 83.70189 -12.289028) (xy 83.631508 -12.288534)
			(xy 83.490965 -12.280641) (xy 83.351086 -12.26488) (xy 83.21231 -12.2413) (xy 83.075075 -12.209977)
			(xy 82.939812 -12.171008) (xy 82.806947 -12.124516) (xy 82.676898 -12.070648) (xy 82.550073 -12.009572)
			(xy 82.426873 -11.941482) (xy 82.307684 -11.866591) (xy 82.192882 -11.785134) (xy 82.082828 -11.697369)
			(xy 81.977868 -11.603571) (xy 81.878333 -11.504036) (xy 81.784535 -11.399076) (xy 81.696769 -11.289022)
			(xy 81.615313 -11.174221) (xy 81.540421 -11.055032) (xy 81.47233 -10.931832) (xy 81.411254 -10.805008)
			(xy 81.357386 -10.674959) (xy 81.310894 -10.542094) (xy 81.271924 -10.406831) (xy 81.240601 -10.269596)
			(xy 81.217021 -10.13082) (xy 81.20126 -9.990941) (xy 81.193366 -9.850398) (xy 81.192878 -9.780016)
			(xy 81.192878 -0.559816) (xy 81.192461 -0.549794) (xy 81.184793 -0.531276) (xy 81.170619 -0.517104)
			(xy 81.1521 -0.509438) (xy 81.142078 -0.509016) (xy 13.661898 -0.509016) (xy 13.651878 -0.509436)
			(xy 13.633365 -0.517107) (xy 13.619197 -0.53128) (xy 13.611532 -0.549796) (xy 13.611098 -0.559816)
			(xy 13.611098 -5.169916) (xy 14.350245 -5.169916) (xy 14.35425 -5.082008) (xy 14.366233 -4.994828)
			(xy 14.386093 -4.909099) (xy 14.413668 -4.825531) (xy 14.448727 -4.744817) (xy 14.49098 -4.667625)
			(xy 14.540078 -4.594596) (xy 14.595614 -4.526334) (xy 14.657126 -4.463404) (xy 14.724107 -4.40633)
			(xy 14.796 -4.355582) (xy 14.872209 -4.311582) (xy 14.952104 -4.274695) (xy 15.035023 -4.245226)
			(xy 15.120278 -4.223419) (xy 15.207162 -4.209455) (xy 15.294956 -4.203449) (xy 15.382933 -4.205453)
			(xy 15.470363 -4.215448) (xy 15.556522 -4.233352) (xy 15.640696 -4.259016) (xy 15.722187 -4.292229)
			(xy 15.800321 -4.332715) (xy 15.874449 -4.380137) (xy 15.943957 -4.434104) (xy 16.008271 -4.494169)
			(xy 16.066855 -4.559833) (xy 16.119226 -4.630552) (xy 16.164949 -4.70574) (xy 16.203646 -4.784775)
			(xy 16.234995 -4.867001) (xy 16.258737 -4.951737) (xy 16.265906 -4.990667) (xy 20.439138 -4.990667)
			(xy 20.439138 -4.936133) (xy 20.446899 -4.882153) (xy 20.462263 -4.829827) (xy 20.484917 -4.78022)
			(xy 20.5144 -4.734341) (xy 20.550112 -4.693126) (xy 20.591325 -4.657412) (xy 20.637202 -4.627926)
			(xy 20.686808 -4.60527) (xy 20.739133 -4.589903) (xy 20.793113 -4.58214) (xy 20.82038 -4.581652)
			(xy 21.68398 -4.581652) (xy 21.711253 -4.582086) (xy 21.765244 -4.589846) (xy 21.817581 -4.605211)
			(xy 21.867198 -4.627869) (xy 21.913086 -4.657357) (xy 21.95431 -4.693076) (xy 21.990031 -4.734298)
			(xy 22.019522 -4.780184) (xy 22.042182 -4.8298) (xy 22.057549 -4.882136) (xy 22.065312 -4.936127)
			(xy 22.065312 -4.990671) (xy 24.039016 -4.990671) (xy 24.039016 -4.936129) (xy 24.046778 -4.882142)
			(xy 24.062145 -4.82981) (xy 24.084803 -4.780197) (xy 24.114292 -4.734314) (xy 24.15001 -4.693095)
			(xy 24.191231 -4.657379) (xy 24.237116 -4.627893) (xy 24.28673 -4.605237) (xy 24.339064 -4.589873)
			(xy 24.393051 -4.582114) (xy 24.420322 -4.581652) (xy 25.283922 -4.581652) (xy 25.311191 -4.582112)
			(xy 25.365175 -4.589876) (xy 25.417503 -4.605244) (xy 25.467113 -4.627903) (xy 25.512992 -4.65739)
			(xy 25.554209 -4.693107) (xy 25.589923 -4.734325) (xy 25.619408 -4.780207) (xy 25.642063 -4.829817)
			(xy 25.657428 -4.882147) (xy 25.66519 -4.936131) (xy 25.66519 -4.990667) (xy 27.639038 -4.990667)
			(xy 27.639038 -4.936133) (xy 27.646799 -4.882155) (xy 27.662162 -4.82983) (xy 27.684814 -4.780224)
			(xy 27.714296 -4.734347) (xy 27.750006 -4.693131) (xy 27.791218 -4.657417) (xy 27.837092 -4.627932)
			(xy 27.886696 -4.605274) (xy 27.93902 -4.589906) (xy 27.992997 -4.582141) (xy 28.020264 -4.581652)
			(xy 28.883864 -4.581652) (xy 28.911138 -4.582085) (xy 28.96513 -4.589843) (xy 29.017469 -4.605207)
			(xy 29.067089 -4.627863) (xy 29.112979 -4.657351) (xy 29.154205 -4.69307) (xy 29.189927 -4.734292)
			(xy 29.219419 -4.78018) (xy 29.24208 -4.829797) (xy 29.257449 -4.882134) (xy 29.265212 -4.936126)
			(xy 29.265212 -4.990667) (xy 31.239238 -4.990667) (xy 31.239238 -4.936133) (xy 31.246999 -4.882155)
			(xy 31.262361 -4.829831) (xy 31.285014 -4.780225) (xy 31.314495 -4.734348) (xy 31.350205 -4.693133)
			(xy 31.391416 -4.657419) (xy 31.43729 -4.627933) (xy 31.486893 -4.605275) (xy 31.539216 -4.589907)
			(xy 31.593193 -4.582141) (xy 31.62046 -4.581652) (xy 32.48406 -4.581652) (xy 32.511334 -4.582085)
			(xy 32.565327 -4.589843) (xy 32.617666 -4.605206) (xy 32.667286 -4.627862) (xy 32.713177 -4.65735)
			(xy 32.754403 -4.693068) (xy 32.790126 -4.734291) (xy 32.819619 -4.780178) (xy 32.84228 -4.829796)
			(xy 32.857649 -4.882134) (xy 32.865412 -4.936126) (xy 32.865412 -4.990671) (xy 40.349116 -4.990671)
			(xy 40.349116 -4.936129) (xy 40.356878 -4.882142) (xy 40.372245 -4.829809) (xy 40.394903 -4.780196)
			(xy 40.424392 -4.734313) (xy 40.460111 -4.693094) (xy 40.501332 -4.657378) (xy 40.547217 -4.627892)
			(xy 40.596832 -4.605237) (xy 40.649165 -4.589873) (xy 40.703153 -4.582114) (xy 40.730424 -4.581652)
			(xy 41.594024 -4.581652) (xy 41.621293 -4.582112) (xy 41.675276 -4.589877) (xy 41.727605 -4.605245)
			(xy 41.777214 -4.627903) (xy 41.823093 -4.657391) (xy 41.86431 -4.693107) (xy 41.900024 -4.734326)
			(xy 41.929508 -4.780207) (xy 41.952164 -4.829818) (xy 41.967528 -4.882147) (xy 41.97529 -4.936131)
			(xy 41.97529 -4.990667) (xy 43.949138 -4.990667) (xy 43.949138 -4.936133) (xy 43.956899 -4.882155)
			(xy 43.972262 -4.82983) (xy 43.994915 -4.780224) (xy 44.024396 -4.734346) (xy 44.060107 -4.693131)
			(xy 44.101319 -4.657417) (xy 44.147194 -4.627931) (xy 44.196798 -4.605274) (xy 44.249121 -4.589906)
			(xy 44.303099 -4.582141) (xy 44.330366 -4.581652) (xy 45.193966 -4.581652) (xy 45.22124 -4.582085)
			(xy 45.275232 -4.589844) (xy 45.327571 -4.605208) (xy 45.37719 -4.627864) (xy 45.42308 -4.657352)
			(xy 45.464305 -4.693071) (xy 45.500028 -4.734293) (xy 45.52952 -4.78018) (xy 45.552181 -4.829797)
			(xy 45.567549 -4.882135) (xy 45.575312 -4.936126) (xy 45.575312 -4.990667) (xy 51.559238 -4.990667)
			(xy 51.559238 -4.936133) (xy 51.566999 -4.882155) (xy 51.582361 -4.829831) (xy 51.605014 -4.780225)
			(xy 51.634495 -4.734348) (xy 51.670205 -4.693133) (xy 51.711416 -4.657419) (xy 51.75729 -4.627933)
			(xy 51.806893 -4.605275) (xy 51.859216 -4.589907) (xy 51.913193 -4.582141) (xy 51.94046 -4.581652)
			(xy 52.80406 -4.581652) (xy 52.831334 -4.582085) (xy 52.885327 -4.589843) (xy 52.937666 -4.605206)
			(xy 52.987286 -4.627862) (xy 53.033177 -4.65735) (xy 53.074403 -4.693068) (xy 53.110126 -4.734291)
			(xy 53.139619 -4.780178) (xy 53.16228 -4.829796) (xy 53.177649 -4.882134) (xy 53.185412 -4.936126)
			(xy 53.185412 -4.99067) (xy 55.159115 -4.99067) (xy 55.159115 -4.93613) (xy 55.166877 -4.882145)
			(xy 55.182243 -4.829814) (xy 55.2049 -4.780202) (xy 55.234387 -4.73432) (xy 55.270103 -4.693102)
			(xy 55.311322 -4.657386) (xy 55.357204 -4.627899) (xy 55.406816 -4.605242) (xy 55.459147 -4.589877)
			(xy 55.513132 -4.582115) (xy 55.540402 -4.581652) (xy 56.404002 -4.581652) (xy 56.431272 -4.582111)
			(xy 56.485258 -4.589873) (xy 56.537589 -4.605239) (xy 56.587201 -4.627896) (xy 56.633083 -4.657383)
			(xy 56.674302 -4.6931) (xy 56.710018 -4.734319) (xy 56.739505 -4.780201) (xy 56.762162 -4.829813)
			(xy 56.777528 -4.882144) (xy 56.78529 -4.93613) (xy 56.78529 -4.99067) (xy 56.777528 -5.044656) (xy 56.762162 -5.096987)
			(xy 56.739505 -5.146599) (xy 56.710018 -5.192481) (xy 56.674302 -5.2337) (xy 56.633083 -5.269417)
			(xy 56.587201 -5.298904) (xy 56.537589 -5.321561) (xy 56.485258 -5.336927) (xy 56.431272 -5.344689)
			(xy 56.404002 -5.345176) (xy 55.540402 -5.345176) (xy 55.513132 -5.344685) (xy 55.459147 -5.336923)
			(xy 55.406816 -5.321558) (xy 55.357204 -5.298901) (xy 55.311322 -5.269414) (xy 55.270103 -5.233698)
			(xy 55.234387 -5.19248) (xy 55.2049 -5.146598) (xy 55.182243 -5.096986) (xy 55.166877 -5.044655)
			(xy 55.159115 -4.99067) (xy 53.185412 -4.99067) (xy 53.185412 -4.990674) (xy 53.177649 -5.044666)
			(xy 53.16228 -5.097004) (xy 53.139619 -5.146622) (xy 53.110126 -5.192509) (xy 53.074403 -5.233732)
			(xy 53.033177 -5.26945) (xy 52.987286 -5.298938) (xy 52.937666 -5.321594) (xy 52.885327 -5.336957)
			(xy 52.831334 -5.344715) (xy 52.80406 -5.345176) (xy 51.94046 -5.345176) (xy 51.913194 -5.344659)
			(xy 51.859216 -5.336893) (xy 51.806893 -5.321525) (xy 51.75729 -5.298867) (xy 51.711416 -5.269381)
			(xy 51.670205 -5.233667) (xy 51.634495 -5.192452) (xy 51.605014 -5.146575) (xy 51.582361 -5.096969)
			(xy 51.566999 -5.044645) (xy 51.559238 -4.990667) (xy 45.575312 -4.990667) (xy 45.575312 -4.990674)
			(xy 45.567549 -5.044665) (xy 45.552181 -5.097003) (xy 45.52952 -5.14662) (xy 45.500028 -5.192507)
			(xy 45.464305 -5.233729) (xy 45.42308 -5.269448) (xy 45.37719 -5.298936) (xy 45.327571 -5.321592)
			(xy 45.275232 -5.336956) (xy 45.22124 -5.344715) (xy 45.193966 -5.345176) (xy 44.330366 -5.345176)
			(xy 44.303099 -5.344659) (xy 44.249121 -5.336894) (xy 44.196798 -5.321526) (xy 44.147194 -5.298869)
			(xy 44.101319 -5.269383) (xy 44.060107 -5.233669) (xy 44.024396 -5.192454) (xy 43.994915 -5.146576)
			(xy 43.972262 -5.09697) (xy 43.956899 -5.044645) (xy 43.949138 -4.990667) (xy 41.97529 -4.990667)
			(xy 41.97529 -4.990669) (xy 41.967528 -5.044653) (xy 41.952164 -5.096982) (xy 41.929508 -5.146593)
			(xy 41.900024 -5.192474) (xy 41.86431 -5.233693) (xy 41.823093 -5.269409) (xy 41.777214 -5.298897)
			(xy 41.727605 -5.321555) (xy 41.675276 -5.336923) (xy 41.621293 -5.344688) (xy 41.594024 -5.345176)
			(xy 40.730424 -5.345176) (xy 40.703153 -5.344686) (xy 40.649165 -5.336927) (xy 40.596832 -5.321563)
			(xy 40.547217 -5.298908) (xy 40.501332 -5.269422) (xy 40.460111 -5.233706) (xy 40.424392 -5.192487)
			(xy 40.394903 -5.146604) (xy 40.372245 -5.096991) (xy 40.356878 -5.044658) (xy 40.349116 -4.990671)
			(xy 32.865412 -4.990671) (xy 32.865412 -4.990674) (xy 32.857649 -5.044666) (xy 32.84228 -5.097004)
			(xy 32.819619 -5.146622) (xy 32.790126 -5.192509) (xy 32.754403 -5.233732) (xy 32.713177 -5.26945)
			(xy 32.667286 -5.298938) (xy 32.617666 -5.321594) (xy 32.565327 -5.336957) (xy 32.511334 -5.344715)
			(xy 32.48406 -5.345176) (xy 31.62046 -5.345176) (xy 31.593194 -5.344659) (xy 31.539216 -5.336893)
			(xy 31.486893 -5.321525) (xy 31.43729 -5.298867) (xy 31.391416 -5.269381) (xy 31.350205 -5.233667)
			(xy 31.314495 -5.192452) (xy 31.285014 -5.146575) (xy 31.262361 -5.096969) (xy 31.246999 -5.044645)
			(xy 31.239238 -4.990667) (xy 29.265212 -4.990667) (xy 29.265212 -4.990674) (xy 29.257449 -5.044666)
			(xy 29.24208 -5.097003) (xy 29.219419 -5.14662) (xy 29.189927 -5.192508) (xy 29.154205 -5.23373)
			(xy 29.112979 -5.269449) (xy 29.067089 -5.298937) (xy 29.017469 -5.321593) (xy 28.96513 -5.336957)
			(xy 28.911138 -5.344715) (xy 28.883864 -5.345176) (xy 28.020264 -5.345176) (xy 27.992997 -5.344659)
			(xy 27.93902 -5.336894) (xy 27.886696 -5.321526) (xy 27.837092 -5.298868) (xy 27.791218 -5.269383)
			(xy 27.750006 -5.233669) (xy 27.714296 -5.192453) (xy 27.684814 -5.146576) (xy 27.662162 -5.09697)
			(xy 27.646799 -5.044645) (xy 27.639038 -4.990667) (xy 25.66519 -4.990667) (xy 25.66519 -4.990669)
			(xy 25.657428 -5.044653) (xy 25.642063 -5.096983) (xy 25.619408 -5.146593) (xy 25.589923 -5.192475)
			(xy 25.554209 -5.233693) (xy 25.512992 -5.26941) (xy 25.467113 -5.298897) (xy 25.417503 -5.321556)
			(xy 25.365175 -5.336924) (xy 25.311191 -5.344688) (xy 25.283922 -5.345176) (xy 24.420322 -5.345176)
			(xy 24.393051 -5.344686) (xy 24.339064 -5.336927) (xy 24.28673 -5.321563) (xy 24.237116 -5.298907)
			(xy 24.191231 -5.269421) (xy 24.15001 -5.233705) (xy 24.114292 -5.192486) (xy 24.084803 -5.146603)
			(xy 24.062145 -5.09699) (xy 24.046778 -5.044658) (xy 24.039016 -4.990671) (xy 22.065312 -4.990671)
			(xy 22.065312 -4.990673) (xy 22.057549 -5.044664) (xy 22.042182 -5.097) (xy 22.019522 -5.146616)
			(xy 21.990031 -5.192502) (xy 21.95431 -5.233724) (xy 21.913086 -5.269443) (xy 21.867198 -5.298931)
			(xy 21.817581 -5.321589) (xy 21.765244 -5.336954) (xy 21.711253 -5.344714) (xy 21.68398 -5.345176)
			(xy 20.82038 -5.345176) (xy 20.793113 -5.34466) (xy 20.739133 -5.336897) (xy 20.686808 -5.32153)
			(xy 20.637202 -5.298874) (xy 20.591325 -5.269388) (xy 20.550112 -5.233674) (xy 20.5144 -5.192459)
			(xy 20.484917 -5.14658) (xy 20.462263 -5.096973) (xy 20.446899 -5.044647) (xy 20.439138 -4.990667)
			(xy 16.265906 -4.990667) (xy 16.274675 -5.038281) (xy 16.282677 -5.125916) (xy 16.283178 -5.169916)
			(xy 16.282677 -5.213916) (xy 16.274675 -5.301551) (xy 16.258737 -5.388095) (xy 16.234995 -5.472831)
			(xy 16.203646 -5.555057) (xy 16.164949 -5.634092) (xy 16.119226 -5.70928) (xy 16.066855 -5.779999)
			(xy 16.008271 -5.845663) (xy 15.943957 -5.905728) (xy 15.874449 -5.959695) (xy 15.800321 -6.007117)
			(xy 15.722187 -6.047603) (xy 15.640696 -6.080816) (xy 15.556522 -6.10648) (xy 15.470363 -6.124384)
			(xy 15.382933 -6.134379) (xy 15.294956 -6.136383) (xy 15.207162 -6.130377) (xy 15.120278 -6.116413)
			(xy 15.035023 -6.094606) (xy 14.952104 -6.065137) (xy 14.872209 -6.02825) (xy 14.796 -5.98425) (xy 14.724107 -5.933502)
			(xy 14.657126 -5.876428) (xy 14.595614 -5.813498) (xy 14.540078 -5.745236) (xy 14.49098 -5.672207)
			(xy 14.448727 -5.595015) (xy 14.413668 -5.514301) (xy 14.386093 -5.430733) (xy 14.366233 -5.345004)
			(xy 14.35425 -5.257824) (xy 14.350245 -5.169916) (xy 13.611098 -5.169916) (xy 13.611098 -6.169914)
			(xy 78.515217 -6.169914) (xy 78.519222 -6.082006) (xy 78.531205 -5.994826) (xy 78.551065 -5.909097)
			(xy 78.57864 -5.825529) (xy 78.613699 -5.744815) (xy 78.655952 -5.667623) (xy 78.70505 -5.594594)
			(xy 78.760586 -5.526332) (xy 78.822098 -5.463402) (xy 78.889079 -5.406328) (xy 78.960972 -5.35558)
			(xy 79.037181 -5.31158) (xy 79.117076 -5.274693) (xy 79.199995 -5.245224) (xy 79.28525 -5.223417)
			(xy 79.372134 -5.209453) (xy 79.459928 -5.203447) (xy 79.547905 -5.205451) (xy 79.635335 -5.215446)
			(xy 79.721494 -5.23335) (xy 79.805668 -5.259014) (xy 79.887159 -5.292227) (xy 79.965293 -5.332713)
			(xy 80.039421 -5.380135) (xy 80.108929 -5.434102) (xy 80.173243 -5.494167) (xy 80.231827 -5.559831)
			(xy 80.284198 -5.63055) (xy 80.329921 -5.705738) (xy 80.368618 -5.784773) (xy 80.399967 -5.866999)
			(xy 80.423709 -5.951735) (xy 80.439647 -6.038279) (xy 80.447649 -6.125914) (xy 80.44815 -6.169914)
			(xy 80.447649 -6.213914) (xy 80.439647 -6.301549) (xy 80.423709 -6.388093) (xy 80.399967 -6.472829)
			(xy 80.368618 -6.555055) (xy 80.329921 -6.63409) (xy 80.284198 -6.709278) (xy 80.231827 -6.779997)
			(xy 80.173243 -6.845661) (xy 80.108929 -6.905726) (xy 80.039421 -6.959693) (xy 79.965293 -7.007115)
			(xy 79.887159 -7.047601) (xy 79.805668 -7.080814) (xy 79.721494 -7.106478) (xy 79.635335 -7.124382)
			(xy 79.547905 -7.134377) (xy 79.459928 -7.136381) (xy 79.372134 -7.130375) (xy 79.28525 -7.116411)
			(xy 79.199995 -7.094604) (xy 79.117076 -7.065135) (xy 79.037181 -7.028248) (xy 78.960972 -6.984248)
			(xy 78.889079 -6.9335) (xy 78.822098 -6.876426) (xy 78.760586 -6.813496) (xy 78.70505 -6.745234)
			(xy 78.655952 -6.672205) (xy 78.613699 -6.595013) (xy 78.57864 -6.514299) (xy 78.551065 -6.430731)
			(xy 78.531205 -6.345002) (xy 78.519222 -6.257822) (xy 78.515217 -6.169914) (xy 13.611098 -6.169914)
			(xy 13.611098 -6.75243) (xy 18.634432 -6.75243) (xy 18.634432 -6.69789) (xy 18.642194 -6.643907)
			(xy 18.65756 -6.591577) (xy 18.680216 -6.541966) (xy 18.709702 -6.496085) (xy 18.745417 -6.454867)
			(xy 18.786635 -6.419152) (xy 18.832516 -6.389666) (xy 18.882127 -6.36701) (xy 18.934457 -6.351644)
			(xy 18.98844 -6.343882) (xy 19.01571 -6.343396) (xy 19.87931 -6.343396) (xy 19.906579 -6.343886)
			(xy 19.960563 -6.351648) (xy 20.012892 -6.367013) (xy 20.062502 -6.389669) (xy 20.108382 -6.419155)
			(xy 20.1496 -6.45487) (xy 20.185315 -6.496088) (xy 20.214801 -6.541968) (xy 20.237457 -6.591578)
			(xy 20.252822 -6.643907) (xy 20.260584 -6.697891) (xy 20.260584 -6.752429) (xy 20.260584 -6.752431)
			(xy 22.234349 -6.752431) (xy 22.234349 -6.697889) (xy 22.242112 -6.643901) (xy 22.257478 -6.591568)
			(xy 22.280136 -6.541955) (xy 22.309624 -6.496071) (xy 22.345342 -6.45485) (xy 22.386562 -6.419133)
			(xy 22.432447 -6.389645) (xy 22.48206 -6.366987) (xy 22.534393 -6.351621) (xy 22.588381 -6.343859)
			(xy 22.615652 -6.343396) (xy 23.479252 -6.343396) (xy 23.506521 -6.343887) (xy 23.560504 -6.351648)
			(xy 23.612833 -6.367014) (xy 23.662443 -6.38967) (xy 23.708323 -6.419156) (xy 23.749541 -6.454871)
			(xy 23.785255 -6.496088) (xy 23.814741 -6.541969) (xy 23.837397 -6.591579) (xy 23.852762 -6.643908)
			(xy 23.860524 -6.697891) (xy 23.860524 -6.752429) (xy 23.860518 -6.752472) (xy 25.834283 -6.752472)
			(xy 25.834283 -6.697928) (xy 25.842045 -6.643939) (xy 25.857412 -6.591604) (xy 25.88007 -6.541989)
			(xy 25.909558 -6.496103) (xy 25.945277 -6.454881) (xy 25.986498 -6.419162) (xy 26.032384 -6.389673)
			(xy 26.081998 -6.367014) (xy 26.134333 -6.351646) (xy 26.188322 -6.343883) (xy 26.215594 -6.343396)
			(xy 27.079194 -6.343396) (xy 27.106462 -6.343943) (xy 27.160444 -6.351704) (xy 27.212772 -6.367068)
			(xy 27.26238 -6.389722) (xy 27.308259 -6.419207) (xy 27.349476 -6.45492) (xy 27.38519 -6.496136)
			(xy 27.414675 -6.542015) (xy 27.43733 -6.591623) (xy 27.452695 -6.64395) (xy 27.460457 -6.697932)
			(xy 27.460457 -6.752468) (xy 27.460456 -6.752472) (xy 29.434483 -6.752472) (xy 29.434483 -6.697928)
			(xy 29.442245 -6.643939) (xy 29.457611 -6.591605) (xy 29.480269 -6.54199) (xy 29.509757 -6.496105)
			(xy 29.545476 -6.454883) (xy 29.586697 -6.419163) (xy 29.632581 -6.389674) (xy 29.682196 -6.367015)
			(xy 29.73453 -6.351647) (xy 29.788518 -6.343883) (xy 29.81579 -6.343396) (xy 30.67939 -6.343396)
			(xy 30.706658 -6.343943) (xy 30.76064 -6.351703) (xy 30.812969 -6.367067) (xy 30.862578 -6.389721)
			(xy 30.908457 -6.419205) (xy 30.949674 -6.454919) (xy 30.985389 -6.496135) (xy 31.014874 -6.542014)
			(xy 31.03753 -6.591622) (xy 31.052895 -6.64395) (xy 31.060657 -6.697932) (xy 31.060657 -6.752468)
			(xy 31.060657 -6.75247) (xy 38.544482 -6.75247) (xy 38.544482 -6.69793) (xy 38.552244 -6.643944)
			(xy 38.567608 -6.591613) (xy 38.590264 -6.542) (xy 38.619749 -6.496116) (xy 38.655463 -6.454895)
			(xy 38.696679 -6.419176) (xy 38.74256 -6.389686) (xy 38.792169 -6.367025) (xy 38.844499 -6.351654)
			(xy 38.898484 -6.343886) (xy 38.925754 -6.343396) (xy 39.789354 -6.343396) (xy 39.816624 -6.34394)
			(xy 39.87061 -6.351696) (xy 39.922943 -6.367057) (xy 39.972556 -6.389709) (xy 40.01844 -6.419192)
			(xy 40.059662 -6.454906) (xy 40.09538 -6.496123) (xy 40.124869 -6.542004) (xy 40.147527 -6.591614)
			(xy 40.162894 -6.643945) (xy 40.170656 -6.69793) (xy 40.170656 -6.75247) (xy 40.170656 -6.752472)
			(xy 42.144383 -6.752472) (xy 42.144383 -6.697928) (xy 42.152145 -6.643939) (xy 42.167512 -6.591604)
			(xy 42.19017 -6.541988) (xy 42.219659 -6.496103) (xy 42.255378 -6.454881) (xy 42.296599 -6.419161)
			(xy 42.342485 -6.389672) (xy 42.3921 -6.367013) (xy 42.444435 -6.351646) (xy 42.498424 -6.343883)
			(xy 42.525696 -6.343396) (xy 43.389296 -6.343396) (xy 43.416564 -6.343943) (xy 43.470546 -6.351704)
			(xy 43.522873 -6.367068) (xy 43.572481 -6.389723) (xy 43.61836 -6.419207) (xy 43.659576 -6.454921)
			(xy 43.69529 -6.496136) (xy 43.724775 -6.542015) (xy 43.74743 -6.591623) (xy 43.762795 -6.643951)
			(xy 43.770557 -6.697932) (xy 43.770557 -6.752468) (xy 43.770556 -6.752472) (xy 49.754483 -6.752472)
			(xy 49.754483 -6.697928) (xy 49.762245 -6.643939) (xy 49.777611 -6.591605) (xy 49.800269 -6.54199)
			(xy 49.829757 -6.496105) (xy 49.865476 -6.454883) (xy 49.906697 -6.419163) (xy 49.952581 -6.389674)
			(xy 50.002196 -6.367015) (xy 50.05453 -6.351647) (xy 50.108518 -6.343883) (xy 50.13579 -6.343396)
			(xy 50.99939 -6.343396) (xy 51.026658 -6.343943) (xy 51.08064 -6.351703) (xy 51.132969 -6.367067)
			(xy 51.182578 -6.389721) (xy 51.228457 -6.419205) (xy 51.269674 -6.454919) (xy 51.305389 -6.496135)
			(xy 51.334874 -6.542014) (xy 51.35753 -6.591622) (xy 51.372895 -6.64395) (xy 51.380657 -6.697932)
			(xy 51.380657 -6.752468) (xy 51.380656 -6.752475) (xy 53.35436 -6.752475) (xy 53.35436 -6.697925)
			(xy 53.362124 -6.643929) (xy 53.377493 -6.591588) (xy 53.400155 -6.541967) (xy 53.429649 -6.496077)
			(xy 53.465374 -6.454851) (xy 53.506603 -6.41913) (xy 53.552495 -6.38964) (xy 53.602118 -6.366982)
			(xy 53.65446 -6.351617) (xy 53.708457 -6.343857) (xy 53.735732 -6.343396) (xy 54.599332 -6.343396)
			(xy 54.626597 -6.343969) (xy 54.680571 -6.351733) (xy 54.732891 -6.367099) (xy 54.782492 -6.389755)
			(xy 54.828364 -6.419238) (xy 54.869573 -6.45495) (xy 54.905281 -6.496162) (xy 54.93476 -6.542036)
			(xy 54.957412 -6.591639) (xy 54.972774 -6.64396) (xy 54.980534 -6.697935) (xy 54.980534 -6.752465)
			(xy 54.980533 -6.752471) (xy 56.954382 -6.752471) (xy 56.954382 -6.697929) (xy 56.962144 -6.643942)
			(xy 56.97751 -6.591608) (xy 57.000167 -6.541994) (xy 57.029654 -6.49611) (xy 57.06537 -6.454888)
			(xy 57.106589 -6.419169) (xy 57.152472 -6.389679) (xy 57.202084 -6.367019) (xy 57.254416 -6.35165)
			(xy 57.308403 -6.343884) (xy 57.335674 -6.343396) (xy 58.199274 -6.343396) (xy 58.226543 -6.343942)
			(xy 58.280527 -6.3517) (xy 58.332857 -6.367062) (xy 58.382468 -6.389716) (xy 58.42835 -6.4192) (xy 58.469569 -6.454913)
			(xy 58.505285 -6.496129) (xy 58.534772 -6.542009) (xy 58.557429 -6.591619) (xy 58.564228 -6.614772)
			(xy 70.948992 -6.614772) (xy 70.948992 -6.560228) (xy 70.956754 -6.506238) (xy 70.972121 -6.453903)
			(xy 70.994781 -6.404288) (xy 71.02427 -6.358403) (xy 71.05999 -6.317181) (xy 71.101212 -6.281463)
			(xy 71.147099 -6.251975) (xy 71.196715 -6.229317) (xy 71.24905 -6.213952) (xy 71.30304 -6.206191)
			(xy 71.330312 -6.205728) (xy 72.193912 -6.205728) (xy 72.22118 -6.206235) (xy 72.275161 -6.213998)
			(xy 72.327488 -6.229364) (xy 72.377095 -6.25202) (xy 72.422973 -6.281506) (xy 72.464188 -6.31722)
			(xy 72.499901 -6.358436) (xy 72.529385 -6.404315) (xy 72.55204 -6.453924) (xy 72.567404 -6.506251)
			(xy 72.575166 -6.560232) (xy 72.575166 -6.614768) (xy 72.567404 -6.668749) (xy 72.55204 -6.721076)
			(xy 72.529385 -6.770685) (xy 72.499901 -6.816564) (xy 72.464188 -6.85778) (xy 72.422973 -6.893494)
			(xy 72.377095 -6.92298) (xy 72.327488 -6.945636) (xy 72.275161 -6.961002) (xy 72.22118 -6.968765)
			(xy 72.193912 -6.969252) (xy 71.330312 -6.969252) (xy 71.30304 -6.968809) (xy 71.24905 -6.961048)
			(xy 71.196715 -6.945683) (xy 71.147099 -6.923025) (xy 71.101212 -6.893537) (xy 71.05999 -6.857819)
			(xy 71.02427 -6.816597) (xy 70.994781 -6.770712) (xy 70.972121 -6.721097) (xy 70.956754 -6.668762)
			(xy 70.948992 -6.614772) (xy 58.564228 -6.614772) (xy 58.572795 -6.643948) (xy 58.580557 -6.697931)
			(xy 58.580557 -6.752469) (xy 58.572795 -6.806452) (xy 58.557429 -6.858781) (xy 58.534772 -6.908391)
			(xy 58.505285 -6.954271) (xy 58.469569 -6.995487) (xy 58.42835 -7.0312) (xy 58.382468 -7.060684)
			(xy 58.332857 -7.083338) (xy 58.280527 -7.0987) (xy 58.226543 -7.106458) (xy 58.199274 -7.10692)
			(xy 57.335674 -7.10692) (xy 57.308403 -7.106516) (xy 57.254416 -7.09875) (xy 57.202084 -7.083381)
			(xy 57.152472 -7.060721) (xy 57.106589 -7.031231) (xy 57.06537 -6.995512) (xy 57.029654 -6.95429)
			(xy 57.000167 -6.908406) (xy 56.97751 -6.858792) (xy 56.962144 -6.806458) (xy 56.954382 -6.752471)
			(xy 54.980533 -6.752471) (xy 54.972774 -6.80644) (xy 54.957412 -6.858761) (xy 54.93476 -6.908364)
			(xy 54.905281 -6.954238) (xy 54.869573 -6.99545) (xy 54.828364 -7.031162) (xy 54.782492 -7.060645)
			(xy 54.732891 -7.083301) (xy 54.680571 -7.098667) (xy 54.626597 -7.106431) (xy 54.599332 -7.10692)
			(xy 53.735732 -7.10692) (xy 53.708457 -7.106543) (xy 53.65446 -7.098783) (xy 53.602118 -7.083418)
			(xy 53.552495 -7.06076) (xy 53.506603 -7.03127) (xy 53.465374 -6.995549) (xy 53.429649 -6.954323)
			(xy 53.400155 -6.908433) (xy 53.377493 -6.858812) (xy 53.362124 -6.806471) (xy 53.35436 -6.752475)
			(xy 51.380656 -6.752475) (xy 51.372895 -6.80645) (xy 51.35753 -6.858778) (xy 51.334874 -6.908386)
			(xy 51.305389 -6.954265) (xy 51.269674 -6.995481) (xy 51.228457 -7.031195) (xy 51.182578 -7.060679)
			(xy 51.132969 -7.083333) (xy 51.08064 -7.098697) (xy 51.026658 -7.106457) (xy 50.99939 -7.10692)
			(xy 50.13579 -7.10692) (xy 50.108518 -7.106517) (xy 50.05453 -7.098753) (xy 50.002196 -7.083385)
			(xy 49.952581 -7.060726) (xy 49.906697 -7.031237) (xy 49.865476 -6.995517) (xy 49.829757 -6.954295)
			(xy 49.800269 -6.90841) (xy 49.777611 -6.858795) (xy 49.762245 -6.806461) (xy 49.754483 -6.752472)
			(xy 43.770556 -6.752472) (xy 43.762795 -6.806449) (xy 43.74743 -6.858777) (xy 43.724775 -6.908385)
			(xy 43.69529 -6.954264) (xy 43.659576 -6.995479) (xy 43.61836 -7.031193) (xy 43.572481 -7.060677)
			(xy 43.522873 -7.083332) (xy 43.470546 -7.098696) (xy 43.416564 -7.106457) (xy 43.389296 -7.10692)
			(xy 42.525696 -7.10692) (xy 42.498424 -7.106517) (xy 42.444435 -7.098754) (xy 42.3921 -7.083387)
			(xy 42.342485 -7.060728) (xy 42.296599 -7.031239) (xy 42.255378 -6.995519) (xy 42.219659 -6.954297)
			(xy 42.19017 -6.908412) (xy 42.167512 -6.858796) (xy 42.152145 -6.806461) (xy 42.144383 -6.752472)
			(xy 40.170656 -6.752472) (xy 40.162894 -6.806455) (xy 40.147527 -6.858786) (xy 40.124869 -6.908396)
			(xy 40.09538 -6.954277) (xy 40.059661 -6.995494) (xy 40.01844 -7.031208) (xy 39.972556 -7.060691)
			(xy 39.922943 -7.083343) (xy 39.87061 -7.098704) (xy 39.816624 -7.10646) (xy 39.789354 -7.10692)
			(xy 38.925754 -7.10692) (xy 38.898484 -7.106514) (xy 38.844499 -7.098746) (xy 38.792169 -7.083375)
			(xy 38.74256 -7.060714) (xy 38.696679 -7.031224) (xy 38.655463 -6.995505) (xy 38.619749 -6.954284)
			(xy 38.590264 -6.9084) (xy 38.567608 -6.858787) (xy 38.552244 -6.806456) (xy 38.544482 -6.75247)
			(xy 31.060657 -6.75247) (xy 31.052895 -6.80645) (xy 31.03753 -6.858778) (xy 31.014874 -6.908386)
			(xy 30.985389 -6.954265) (xy 30.949674 -6.995481) (xy 30.908457 -7.031195) (xy 30.862578 -7.060679)
			(xy 30.812969 -7.083333) (xy 30.76064 -7.098697) (xy 30.706658 -7.106457) (xy 30.67939 -7.10692)
			(xy 29.81579 -7.10692) (xy 29.788518 -7.106517) (xy 29.73453 -7.098753) (xy 29.682196 -7.083385)
			(xy 29.632581 -7.060726) (xy 29.586697 -7.031237) (xy 29.545476 -6.995517) (xy 29.509757 -6.954295)
			(xy 29.480269 -6.90841) (xy 29.457611 -6.858795) (xy 29.442245 -6.806461) (xy 29.434483 -6.752472)
			(xy 27.460456 -6.752472) (xy 27.452695 -6.80645) (xy 27.43733 -6.858777) (xy 27.414675 -6.908385)
			(xy 27.38519 -6.954264) (xy 27.349476 -6.99548) (xy 27.308259 -7.031193) (xy 27.26238 -7.060678)
			(xy 27.212772 -7.083332) (xy 27.160444 -7.098696) (xy 27.106462 -7.106457) (xy 27.079194 -7.10692)
			(xy 26.215594 -7.10692) (xy 26.188322 -7.106517) (xy 26.134333 -7.098754) (xy 26.081998 -7.083386)
			(xy 26.032384 -7.060727) (xy 25.986498 -7.031238) (xy 25.945277 -6.995519) (xy 25.909558 -6.954297)
			(xy 25.88007 -6.908411) (xy 25.857412 -6.858796) (xy 25.842045 -6.806461) (xy 25.834283 -6.752472)
			(xy 23.860518 -6.752472) (xy 23.852762 -6.806412) (xy 23.837397 -6.858741) (xy 23.814741 -6.908351)
			(xy 23.785255 -6.954232) (xy 23.749541 -6.995449) (xy 23.708323 -7.031164) (xy 23.662443 -7.06065)
			(xy 23.612833 -7.083306) (xy 23.560504 -7.098672) (xy 23.506521 -7.106433) (xy 23.479252 -7.10692)
			(xy 22.615652 -7.10692) (xy 22.588381 -7.106461) (xy 22.534393 -7.098699) (xy 22.48206 -7.083333)
			(xy 22.432447 -7.060675) (xy 22.386562 -7.031187) (xy 22.345342 -6.99547) (xy 22.309624 -6.954249)
			(xy 22.280136 -6.908365) (xy 22.257478 -6.858752) (xy 22.242112 -6.806419) (xy 22.234349 -6.752431)
			(xy 20.260584 -6.752431) (xy 20.252822 -6.806413) (xy 20.237457 -6.858742) (xy 20.214801 -6.908352)
			(xy 20.185315 -6.954232) (xy 20.1496 -6.99545) (xy 20.108382 -7.031165) (xy 20.062502 -7.060651)
			(xy 20.012892 -7.083307) (xy 19.960563 -7.098672) (xy 19.906579 -7.106434) (xy 19.87931 -7.10692)
			(xy 19.01571 -7.10692) (xy 18.98844 -7.106438) (xy 18.934457 -7.098676) (xy 18.882127 -7.08331) (xy 18.832516 -7.060654)
			(xy 18.786635 -7.031168) (xy 18.745417 -6.995453) (xy 18.709702 -6.954235) (xy 18.680216 -6.908354)
			(xy 18.65756 -6.858743) (xy 18.642194 -6.806413) (xy 18.634432 -6.75243) (xy 13.611098 -6.75243)
			(xy 13.611098 -9.780016) (xy 13.610604 -9.850398) (xy 13.602711 -9.990941) (xy 13.58695 -10.13082)
			(xy 13.563371 -10.269596) (xy 13.532048 -10.406831) (xy 13.493079 -10.542094) (xy 13.446587 -10.674959)
			(xy 13.392719 -10.805008) (xy 13.331643 -10.931832) (xy 13.263553 -11.055033) (xy 13.188662 -11.174221)
			(xy 13.107205 -11.289023) (xy 13.01944 -11.399077) (xy 12.925642 -11.504037) (xy 12.826107 -11.603572)
			(xy 12.721147 -11.69737) (xy 12.611093 -11.785135) (xy 12.496291 -11.866592) (xy 12.377103 -11.941483)
			(xy 12.253902 -12.009573) (xy 12.127078 -12.070649) (xy 11.997029 -12.124517) (xy 11.864164 -12.171009)
			(xy 11.728901 -12.209978) (xy 11.591666 -12.241301) (xy 11.45289 -12.26488) (xy 11.313011 -12.280641)
			(xy 11.172468 -12.288534) (xy 11.102086 -12.289028) (xy 1.999996 -12.289028) (xy 1.944227 -12.289537)
			(xy 1.833 -12.297872) (xy 1.722707 -12.314497) (xy 1.613965 -12.339317) (xy 1.507382 -12.372193)
			(xy 1.403554 -12.412943) (xy 1.353372 -12.43711) (xy 62.309756 -12.43711) (xy 62.310222 -12.396003)
			(xy 62.317806 -12.314139) (xy 62.332909 -12.233324) (xy 62.355404 -12.154247) (xy 62.385098 -12.077583)
			(xy 62.421737 -12.003984) (xy 62.46501 -11.93408) (xy 62.514548 -11.868466) (xy 62.569927 -11.807701)
			(xy 62.630676 -11.752305) (xy 62.696277 -11.70275) (xy 62.766169 -11.659457) (xy 62.839757 -11.622797)
			(xy 62.916414 -11.593082) (xy 62.995485 -11.570566) (xy 63.076295 -11.55544) (xy 63.158157 -11.547833)
			(xy 63.199264 -11.547348) (xy 63.243059 -11.547873) (xy 63.330225 -11.556491) (xy 63.416121 -11.573637)
			(xy 63.499915 -11.599145) (xy 63.580795 -11.632768) (xy 63.619634 -11.653012) (xy 63.6311 -11.65843)
			(xy 63.656428 -11.65843) (xy 63.667894 -11.653012) (xy 63.706738 -11.632781) (xy 63.787623 -11.599174)
			(xy 63.871416 -11.573672) (xy 63.957309 -11.556521) (xy 64.04447 -11.547888) (xy 64.088264 -11.547348)
			(xy 64.132059 -11.547873) (xy 64.219225 -11.556491) (xy 64.305121 -11.573637) (xy 64.388915 -11.599145)
			(xy 64.469795 -11.632768) (xy 64.508634 -11.653012) (xy 64.5201 -11.65843) (xy 64.545428 -11.65843)
			(xy 64.556894 -11.653012) (xy 64.595738 -11.632781) (xy 64.676623 -11.599174) (xy 64.760416 -11.573672)
			(xy 64.846309 -11.556521) (xy 64.93347 -11.547888) (xy 64.977264 -11.547348) (xy 65.021059 -11.547873)
			(xy 65.108225 -11.556491) (xy 65.194121 -11.573637) (xy 65.277915 -11.599145) (xy 65.358795 -11.632768)
			(xy 65.397634 -11.653012) (xy 65.4091 -11.65843) (xy 65.434428 -11.65843) (xy 65.445894 -11.653012)
			(xy 65.484738 -11.632781) (xy 65.565623 -11.599174) (xy 65.649416 -11.573672) (xy 65.735309 -11.556521)
			(xy 65.82247 -11.547888) (xy 65.866264 -11.547348) (xy 65.904554 -11.547763) (xy 65.980848 -11.554368)
			(xy 66.05629 -11.567515) (xy 66.130321 -11.587105) (xy 66.166492 -11.599672) (xy 66.174929 -11.602323)
			(xy 66.192599 -11.602323) (xy 66.201036 -11.599672) (xy 66.237216 -11.587135) (xy 66.311248 -11.56756)
			(xy 66.386687 -11.554411) (xy 66.462976 -11.547785) (xy 66.501264 -11.547348) (xy 66.54268 -11.547848)
			(xy 66.625149 -11.555593) (xy 66.706543 -11.570964) (xy 66.786158 -11.593827) (xy 66.863305 -11.623986)
			(xy 66.937318 -11.661178) (xy 66.972688 -11.68273) (xy 66.980074 -11.686987) (xy 66.996689 -11.690769)
			(xy 67.013625 -11.688896) (xy 67.021456 -11.685524) (xy 67.057233 -11.668994) (xy 67.131154 -11.641645)
			(xy 67.207206 -11.620946) (xy 67.284791 -11.607058) (xy 67.363301 -11.600092) (xy 67.40271 -11.599672)
			(xy 67.443826 -11.600089) (xy 67.525707 -11.607677) (xy 67.606539 -11.622789) (xy 67.685632 -11.645294)
			(xy 67.76231 -11.675001) (xy 67.835921 -11.711656) (xy 67.905835 -11.754947) (xy 67.971457 -11.804505)
			(xy 68.032226 -11.859906) (xy 68.087623 -11.920677) (xy 68.137178 -11.986301) (xy 68.180465 -12.056218)
			(xy 68.217117 -12.12983) (xy 68.24682 -12.20651) (xy 68.269321 -12.285604) (xy 68.284429 -12.366436)
			(xy 68.292013 -12.448318) (xy 68.292472 -12.489434) (xy 68.291907 -12.533047) (xy 68.283357 -12.619854)
			(xy 68.266352 -12.705408) (xy 68.241056 -12.788886) (xy 68.207711 -12.869488) (xy 68.195659 -12.892068)
			(xy 70.948547 -12.892068) (xy 70.948547 -12.837532) (xy 70.956309 -12.783551) (xy 70.971673 -12.731225)
			(xy 70.994328 -12.681617) (xy 71.023813 -12.635739) (xy 71.059526 -12.594524) (xy 71.100742 -12.558811)
			(xy 71.146621 -12.529327) (xy 71.196228 -12.506672) (xy 71.248555 -12.491308) (xy 71.302536 -12.483547)
			(xy 71.329804 -12.483084) (xy 72.193404 -12.483084) (xy 72.220676 -12.483479) (xy 72.274666 -12.491242)
			(xy 72.327001 -12.506609) (xy 72.376617 -12.529269) (xy 72.422503 -12.558758) (xy 72.463725 -12.594478)
			(xy 72.499444 -12.6357) (xy 72.528933 -12.681586) (xy 72.551592 -12.731202) (xy 72.566959 -12.783538)
			(xy 72.574721 -12.837528) (xy 72.574721 -12.892072) (xy 72.566959 -12.946062) (xy 72.551592 -12.998398)
			(xy 72.528933 -13.048014) (xy 72.499444 -13.0939) (xy 72.488173 -13.106908) (xy 191.037972 -13.106908)
			(xy 191.03849 -13.065179) (xy 191.046314 -12.98209) (xy 191.061883 -12.900098) (xy 191.085062 -12.819924)
			(xy 191.115646 -12.742273) (xy 191.153367 -12.667827) (xy 191.197893 -12.59724) (xy 191.248833 -12.531132)
			(xy 191.305739 -12.470085) (xy 191.368112 -12.414635) (xy 191.435403 -12.365269) (xy 191.507021 -12.32242)
			(xy 191.582336 -12.286466) (xy 191.660687 -12.257723) (xy 191.700912 -12.24661) (xy 191.713612 -12.243308)
			(xy 191.732408 -12.225274) (xy 191.765936 -12.117578) (xy 191.760348 -12.091924) (xy 191.751712 -12.082018)
			(xy 191.723476 -12.048682) (xy 191.672486 -11.977736) (xy 191.628113 -11.902474) (xy 191.590718 -11.823512)
			(xy 191.560607 -11.741496) (xy 191.538028 -11.657095) (xy 191.523163 -11.571) (xy 191.516135 -11.483915)
			(xy 191.517001 -11.39655) (xy 191.525753 -11.309621) (xy 191.542322 -11.223837) (xy 191.56657 -11.139901)
			(xy 191.5983 -11.058497) (xy 191.637253 -10.980292) (xy 191.683109 -10.905925) (xy 191.735495 -10.836003)
			(xy 191.793982 -10.771099) (xy 191.858092 -10.711742) (xy 191.927301 -10.658417) (xy 192.001043 -10.611562)
			(xy 192.078715 -10.571558) (xy 192.159684 -10.538733) (xy 192.243285 -10.513355) (xy 192.328838 -10.495631)
			(xy 192.415641 -10.485707) (xy 192.502986 -10.483662) (xy 192.590159 -10.489515) (xy 192.676446 -10.503218)
			(xy 192.761144 -10.524657) (xy 192.843559 -10.553659) (xy 192.923018 -10.589985) (xy 192.998871 -10.63334)
			(xy 193.070499 -10.683368) (xy 193.137315 -10.739661) (xy 193.198774 -10.801758) (xy 193.254374 -10.869153)
			(xy 193.303659 -10.941294) (xy 193.346227 -11.017591) (xy 193.381731 -11.097421) (xy 193.409879 -11.180131)
			(xy 193.430442 -11.265046) (xy 193.443252 -11.35147) (xy 193.448204 -11.438699) (xy 193.445257 -11.526018)
			(xy 193.434436 -11.612714) (xy 193.415829 -11.698079) (xy 193.389589 -11.781414) (xy 193.355929 -11.862038)
			(xy 193.315124 -11.939293) (xy 193.267509 -12.012547) (xy 193.213473 -12.081201) (xy 193.153457 -12.144694)
			(xy 193.121026 -12.173966) (xy 193.112347 -12.182457) (xy 193.103466 -12.205016) (xy 193.104008 -12.217146)
			(xy 193.112136 -12.298934) (xy 193.113935 -12.310868) (xy 193.126948 -12.331156) (xy 193.137028 -12.337796)
			(xy 193.137282 -12.33805) (xy 193.173525 -12.359702) (xy 193.242152 -12.408882) (xy 193.305811 -12.464344)
			(xy 193.363928 -12.525589) (xy 193.415979 -12.592065) (xy 193.461498 -12.663174) (xy 193.500073 -12.738277)
			(xy 193.531358 -12.816697) (xy 193.555071 -12.897729) (xy 193.570999 -12.980643) (xy 193.578999 -13.064693)
			(xy 193.579496 -13.106908) (xy 193.579055 -13.148019) (xy 193.571467 -13.22989) (xy 193.556355 -13.310712)
			(xy 193.533849 -13.389794) (xy 193.504141 -13.466462) (xy 193.467484 -13.540061) (xy 193.424192 -13.609963)
			(xy 193.374634 -13.675571) (xy 193.319232 -13.736326) (xy 193.25846 -13.791709) (xy 193.192836 -13.841247)
			(xy 193.122921 -13.884518) (xy 193.049311 -13.921151) (xy 192.972634 -13.950836) (xy 192.893545 -13.973317)
			(xy 192.812719 -13.988404) (xy 192.730845 -13.995968) (xy 192.689734 -13.996416) (xy 192.643339 -13.99582)
			(xy 192.551051 -13.986179) (xy 192.460267 -13.966987) (xy 192.371973 -13.938452) (xy 192.329308 -13.920216)
			(xy 192.319366 -13.91641) (xy 192.298102 -13.91641) (xy 192.28816 -13.920216) (xy 192.245553 -13.938427)
			(xy 192.157387 -13.966948) (xy 192.066733 -13.986143) (xy 191.974574 -13.995806) (xy 191.928242 -13.996416)
			(xy 191.927734 -13.996416) (xy 191.886626 -13.995955) (xy 191.804762 -13.988373) (xy 191.723946 -13.973271)
			(xy 191.644867 -13.950778) (xy 191.568202 -13.921085) (xy 191.494602 -13.884445) (xy 191.424697 -13.841172)
			(xy 191.359082 -13.791634) (xy 191.298317 -13.736254) (xy 191.24292 -13.675504) (xy 191.193365 -13.609903)
			(xy 191.150073 -13.540009) (xy 191.113413 -13.46642) (xy 191.083699 -13.389762) (xy 191.061184 -13.31069)
			(xy 191.04606 -13.229878) (xy 191.038456 -13.148015) (xy 191.037972 -13.106908) (xy 72.488173 -13.106908)
			(xy 72.463725 -13.135122) (xy 72.422503 -13.170842) (xy 72.376617 -13.200331) (xy 72.327001 -13.222991)
			(xy 72.274666 -13.238358) (xy 72.220676 -13.246121) (xy 72.193404 -13.246608) (xy 71.329804 -13.246608)
			(xy 71.302536 -13.246053) (xy 71.248555 -13.238292) (xy 71.196228 -13.222928) (xy 71.146621 -13.200273)
			(xy 71.100742 -13.170789) (xy 71.059526 -13.135076) (xy 71.023813 -13.093861) (xy 70.994328 -13.047983)
			(xy 70.971673 -12.998375) (xy 70.956309 -12.946049) (xy 70.948547 -12.892068) (xy 68.195659 -12.892068)
			(xy 68.166638 -12.946439) (xy 68.118231 -13.019001) (xy 68.062955 -13.086478) (xy 68.00134 -13.14822)
			(xy 67.933978 -13.203636) (xy 67.861516 -13.252193) (xy 67.823334 -13.273278) (xy 67.814055 -13.278811)
			(xy 67.800889 -13.295908) (xy 67.797934 -13.306298) (xy 67.787525 -13.3474) (xy 67.759881 -13.427561)
			(xy 67.724737 -13.504728) (xy 67.682409 -13.578201) (xy 67.633283 -13.647314) (xy 67.577804 -13.711439)
			(xy 67.516475 -13.769995) (xy 67.449854 -13.82245) (xy 67.378544 -13.868328) (xy 67.303192 -13.907213)
			(xy 67.224482 -13.938753) (xy 67.143129 -13.96266) (xy 67.05987 -13.978719) (xy 66.975461 -13.986784)
			(xy 66.933064 -13.987272) (xy 66.894775 -13.986847) (xy 66.818481 -13.980245) (xy 66.743038 -13.967101)
			(xy 66.669007 -13.947513) (xy 66.632836 -13.934948) (xy 66.624399 -13.932297) (xy 66.606729 -13.932297)
			(xy 66.598292 -13.934948) (xy 66.56211 -13.947478) (xy 66.488079 -13.967055) (xy 66.41264 -13.980205)
			(xy 66.336352 -13.986834) (xy 66.298064 -13.987272) (xy 66.254269 -13.986733) (xy 66.167104 -13.978118)
			(xy 66.081208 -13.960975) (xy 65.997414 -13.93547) (xy 65.916534 -13.90185) (xy 65.877694 -13.881608)
			(xy 65.866228 -13.87619) (xy 65.8409 -13.87619) (xy 65.829434 -13.881608) (xy 65.790581 -13.901822)
			(xy 65.709699 -13.935433) (xy 65.625908 -13.96094) (xy 65.540018 -13.978094) (xy 65.452857 -13.986731)
			(xy 65.409064 -13.987272) (xy 65.365269 -13.986733) (xy 65.278104 -13.978118) (xy 65.192208 -13.960975)
			(xy 65.108414 -13.93547) (xy 65.027534 -13.90185) (xy 64.988694 -13.881608) (xy 64.977228 -13.87619)
			(xy 64.9519 -13.87619) (xy 64.940434 -13.881608) (xy 64.901581 -13.901822) (xy 64.820699 -13.935433)
			(xy 64.736908 -13.96094) (xy 64.651018 -13.978094) (xy 64.563857 -13.986731) (xy 64.520064 -13.987272)
			(xy 64.476269 -13.986733) (xy 64.389104 -13.978118) (xy 64.303208 -13.960975) (xy 64.219414 -13.93547)
			(xy 64.138534 -13.90185) (xy 64.099694 -13.881608) (xy 64.088228 -13.87619) (xy 64.0629 -13.87619)
			(xy 64.051434 -13.881608) (xy 64.012581 -13.901822) (xy 63.931699 -13.935433) (xy 63.847908 -13.96094)
			(xy 63.762018 -13.978094) (xy 63.674857 -13.986731) (xy 63.631064 -13.987272) (xy 63.588804 -13.98679)
			(xy 63.504665 -13.978779) (xy 63.421665 -13.962822) (xy 63.340553 -13.939064) (xy 63.26206 -13.907718)
			(xy 63.186895 -13.869068) (xy 63.115735 -13.823463) (xy 63.049222 -13.771312) (xy 62.987956 -13.713088)
			(xy 62.93249 -13.649314) (xy 62.883323 -13.580566) (xy 62.840899 -13.507464) (xy 62.805601 -13.430668)
			(xy 62.777747 -13.35087) (xy 62.757589 -13.268789) (xy 62.750954 -13.22705) (xy 62.748768 -13.216225)
			(xy 62.736658 -13.197787) (xy 62.727586 -13.19149) (xy 62.693115 -13.169417) (xy 62.628004 -13.119803)
			(xy 62.567725 -13.064419) (xy 62.512788 -13.003732) (xy 62.463657 -12.938255) (xy 62.420747 -12.868543)
			(xy 62.384422 -12.795185) (xy 62.354987 -12.7188) (xy 62.332693 -12.640034) (xy 62.317728 -12.559554)
			(xy 62.310218 -12.47804) (xy 62.309756 -12.43711) (xy 1.353372 -12.43711) (xy 1.303061 -12.461339)
			(xy 1.206466 -12.517108) (xy 1.114309 -12.579941) (xy 1.027105 -12.649484) (xy 0.945341 -12.72535)
			(xy 0.869476 -12.807114) (xy 0.801731 -12.892064) (xy 56.95347 -12.892064) (xy 56.95347 -12.837536)
			(xy 56.96123 -12.783562) (xy 56.976591 -12.731243) (xy 56.999242 -12.681641) (xy 57.02872 -12.635768)
			(xy 57.064426 -12.594556) (xy 57.105634 -12.558845) (xy 57.151504 -12.529362) (xy 57.201103 -12.506706)
			(xy 57.253421 -12.491339) (xy 57.307394 -12.483573) (xy 57.334658 -12.483084) (xy 58.198258 -12.483084)
			(xy 58.225534 -12.483453) (xy 58.279532 -12.491211) (xy 58.331876 -12.506575) (xy 58.381501 -12.529233)
			(xy 58.427395 -12.558723) (xy 58.468625 -12.594445) (xy 58.504351 -12.635671) (xy 58.533847 -12.681562)
			(xy 58.55651 -12.731184) (xy 58.57188 -12.783527) (xy 58.579644 -12.837524) (xy 58.579644 -12.892076)
			(xy 58.57188 -12.946073) (xy 58.55651 -12.998416) (xy 58.533847 -13.048037) (xy 58.504351 -13.093929)
			(xy 58.468625 -13.135155) (xy 58.427395 -13.170877) (xy 58.381501 -13.200367) (xy 58.331876 -13.223025)
			(xy 58.279532 -13.238389) (xy 58.225534 -13.246147) (xy 58.198258 -13.246608) (xy 57.334658 -13.246608)
			(xy 57.307394 -13.246027) (xy 57.253421 -13.238261) (xy 57.201103 -13.222894) (xy 57.151504 -13.200238)
			(xy 57.105634 -13.170755) (xy 57.064426 -13.135044) (xy 57.02872 -13.093832) (xy 56.999242 -13.047959)
			(xy 56.976591 -12.998357) (xy 56.96123 -12.946038) (xy 56.95347 -12.892064) (xy 0.801731 -12.892064)
			(xy 0.799933 -12.894318) (xy 0.737102 -12.986476) (xy 0.681333 -13.083072) (xy 0.632939 -13.183565)
			(xy 0.59219 -13.287393) (xy 0.559313 -13.393977) (xy 0.534494 -13.502719) (xy 0.517871 -13.613012)
			(xy 0.509536 -13.724239) (xy 0.509016 -13.780008) (xy 0.509016 -16.5207) (xy 76.28834 -16.5207) (xy 76.29237 -16.436094)
			(xy 76.304425 -16.352254) (xy 76.324394 -16.26994) (xy 76.352098 -16.189896) (xy 76.387284 -16.112849)
			(xy 76.429635 -16.039495) (xy 76.478768 -15.970499) (xy 76.534236 -15.906485) (xy 76.595538 -15.848035)
			(xy 76.662118 -15.795676) (xy 76.733375 -15.749883) (xy 76.808661 -15.711071) (xy 76.887296 -15.679591)
			(xy 76.968567 -15.655728) (xy 77.051738 -15.639698) (xy 77.136057 -15.631648) (xy 77.178408 -15.63116)
			(xy 77.178916 -15.63116) (xy 77.224101 -15.631724) (xy 77.314005 -15.640873) (xy 77.402518 -15.659097)
			(xy 77.488725 -15.686205) (xy 77.530452 -15.70355) (xy 77.539034 -15.706862) (xy 77.557395 -15.707764)
			(xy 77.566266 -15.705328) (xy 77.610936 -15.69133) (xy 77.702468 -15.671687) (xy 77.795557 -15.661772)
			(xy 77.842364 -15.661132) (xy 77.84338 -15.661132) (xy 77.885732 -15.661539) (xy 77.970052 -15.669589)
			(xy 78.053225 -15.685618) (xy 78.134498 -15.70948) (xy 78.213134 -15.74096) (xy 78.288422 -15.779772)
			(xy 78.35968 -15.825565) (xy 78.426262 -15.877924) (xy 78.487566 -15.936376) (xy 78.543035 -16.00039)
			(xy 78.592169 -16.069387) (xy 78.634521 -16.142742) (xy 78.669709 -16.219791) (xy 78.697413 -16.299835)
			(xy 78.717383 -16.382151) (xy 78.722326 -16.416528) (xy 191.571372 -16.416528) (xy 191.571784 -16.378238)
			(xy 191.57839 -16.301944) (xy 191.591537 -16.226502) (xy 191.611129 -16.152471) (xy 191.623696 -16.1163)
			(xy 191.626331 -16.10786) (xy 191.62634 -16.090193) (xy 191.623696 -16.081756) (xy 191.611158 -16.045577)
			(xy 191.591583 -15.971544) (xy 191.578434 -15.896105) (xy 191.571809 -15.819816) (xy 191.571372 -15.781528)
			(xy 191.571879 -15.740418) (xy 191.579464 -15.65855) (xy 191.594572 -15.577731) (xy 191.617074 -15.498651)
			(xy 191.646778 -15.421985) (xy 191.68343 -15.348387) (xy 191.726718 -15.278486) (xy 191.776272 -15.212878)
			(xy 191.831669 -15.152124) (xy 191.892437 -15.096741) (xy 191.958056 -15.047202) (xy 192.027967 -15.00393)
			(xy 192.101573 -14.967295) (xy 192.178246 -14.937609) (xy 192.257331 -14.915125) (xy 192.338154 -14.900036)
			(xy 192.420024 -14.89247) (xy 192.461134 -14.89202) (xy 192.499451 -14.892376) (xy 192.575804 -14.898912)
			(xy 192.651311 -14.912) (xy 192.72541 -14.931543) (xy 192.761616 -14.94409) (xy 192.769932 -14.946676)
			(xy 192.787336 -14.946676) (xy 192.795652 -14.94409) (xy 192.831863 -14.931562) (xy 192.905965 -14.912041)
			(xy 192.981469 -14.898959) (xy 193.057819 -14.892413) (xy 193.096134 -14.89202) (xy 193.134451 -14.892376)
			(xy 193.210804 -14.898912) (xy 193.286311 -14.912) (xy 193.36041 -14.931543) (xy 193.396616 -14.94409)
			(xy 193.404932 -14.946676) (xy 193.422336 -14.946676) (xy 193.430652 -14.94409) (xy 193.466772 -14.93159)
			(xy 193.540685 -14.912102) (xy 193.615997 -14.899021) (xy 193.692153 -14.892442) (xy 193.730372 -14.89202)
			(xy 193.731134 -14.89202) (xy 193.772241 -14.89248) (xy 193.854104 -14.900067) (xy 193.934917 -14.915174)
			(xy 194.013993 -14.937671) (xy 194.090656 -14.967367) (xy 194.164253 -15.004008) (xy 194.234156 -15.047282)
			(xy 194.299769 -15.09682) (xy 194.360532 -15.152199) (xy 194.415928 -15.212948) (xy 194.465484 -15.278547)
			(xy 194.508776 -15.348439) (xy 194.545437 -15.422026) (xy 194.575153 -15.498681) (xy 194.597672 -15.577751)
			(xy 194.6128 -15.658561) (xy 194.620409 -15.740421) (xy 194.620896 -15.781528) (xy 194.620451 -15.819809)
			(xy 194.613795 -15.896082) (xy 194.600605 -15.971499) (xy 194.591178 -16.008604) (xy 194.588893 -16.019174)
			(xy 194.592456 -16.040487) (xy 194.598036 -16.049752) (xy 194.621836 -16.08633) (xy 194.662956 -16.163308)
			(xy 194.696348 -16.24394) (xy 194.721691 -16.327453) (xy 194.738741 -16.413043) (xy 194.747336 -16.499892)
			(xy 194.747896 -16.543528) (xy 194.747474 -16.584639) (xy 194.739884 -16.666511) (xy 194.72477 -16.747333)
			(xy 194.702263 -16.826416) (xy 194.672553 -16.903083) (xy 194.635895 -16.976682) (xy 194.592602 -17.046584)
			(xy 194.543042 -17.112192) (xy 194.487639 -17.172947) (xy 194.426866 -17.22833) (xy 194.361241 -17.277868)
			(xy 194.291325 -17.321138) (xy 194.217714 -17.357772) (xy 194.141037 -17.387456) (xy 194.061947 -17.409938)
			(xy 193.98112 -17.425024) (xy 193.899246 -17.432588) (xy 193.858134 -17.433036) (xy 193.814503 -17.432505)
			(xy 193.727659 -17.42397) (xy 193.642069 -17.40697) (xy 193.558556 -17.381667) (xy 193.477923 -17.348306)
			(xy 193.400945 -17.307207) (xy 193.364358 -17.28343) (xy 193.355108 -17.277824) (xy 193.333785 -17.274289)
			(xy 193.32321 -17.276572) (xy 193.286097 -17.285942) (xy 193.210677 -17.299046) (xy 193.134409 -17.305624)
			(xy 193.096134 -17.306036) (xy 193.057818 -17.305656) (xy 192.981465 -17.299127) (xy 192.905958 -17.286046)
			(xy 192.831859 -17.26651) (xy 192.795652 -17.253966) (xy 192.787336 -17.25138) (xy 192.769932 -17.25138)
			(xy 192.761616 -17.253966) (xy 192.725489 -17.266445) (xy 192.651578 -17.285939) (xy 192.576269 -17.299026)
			(xy 192.500115 -17.305611) (xy 192.461896 -17.306036) (xy 192.461134 -17.306036) (xy 192.420027 -17.305555)
			(xy 192.338163 -17.297973) (xy 192.257348 -17.282872) (xy 192.178271 -17.260379) (xy 192.101606 -17.230687)
			(xy 192.028008 -17.194048) (xy 191.958103 -17.150776) (xy 191.892489 -17.10124) (xy 191.831724 -17.045861)
			(xy 191.776328 -16.985113) (xy 191.726772 -16.919513) (xy 191.683479 -16.849621) (xy 191.646819 -16.776033)
			(xy 191.617104 -16.699377) (xy 191.594588 -16.620307) (xy 191.579463 -16.539496) (xy 191.571857 -16.457635)
			(xy 191.571372 -16.416528) (xy 78.722326 -16.416528) (xy 78.729438 -16.465992) (xy 78.733468 -16.5506)
			(xy 78.729438 -16.635208) (xy 78.717383 -16.719049) (xy 78.697413 -16.801365) (xy 78.669709 -16.881409)
			(xy 78.634521 -16.958458) (xy 78.592169 -17.031813) (xy 78.543035 -17.10081) (xy 78.487566 -17.164824)
			(xy 78.426262 -17.223276) (xy 78.35968 -17.275635) (xy 78.288422 -17.321428) (xy 78.213134 -17.36024)
			(xy 78.134498 -17.39172) (xy 78.053225 -17.415582) (xy 77.970052 -17.431611) (xy 77.885732 -17.439661)
			(xy 77.84338 -17.440148) (xy 77.842872 -17.440148) (xy 77.797687 -17.439588) (xy 77.707782 -17.430437)
			(xy 77.61927 -17.412213) (xy 77.533063 -17.385103) (xy 77.491336 -17.367758) (xy 77.482756 -17.36444)
			(xy 77.464393 -17.363542) (xy 77.455522 -17.36598) (xy 77.410853 -17.379982) (xy 77.319321 -17.399623)
			(xy 77.226231 -17.409537) (xy 77.179424 -17.410176) (xy 77.178408 -17.410176) (xy 77.136057 -17.409752)
			(xy 77.051738 -17.401702) (xy 76.968567 -17.385672) (xy 76.887296 -17.361809) (xy 76.808661 -17.330329)
			(xy 76.733375 -17.291517) (xy 76.662118 -17.245724) (xy 76.595538 -17.193365) (xy 76.534236 -17.134915)
			(xy 76.478768 -17.070901) (xy 76.429635 -17.001905) (xy 76.387284 -16.928551) (xy 76.352098 -16.851504)
			(xy 76.324394 -16.77146) (xy 76.304425 -16.689146) (xy 76.29237 -16.605306) (xy 76.28834 -16.5207)
			(xy 0.509016 -16.5207) (xy 0.509016 -17.639611) (xy 15.152858 -17.639611) (xy 15.152858 -17.585109)
			(xy 15.160614 -17.531161) (xy 15.175969 -17.478867) (xy 15.19861 -17.42929) (xy 15.228076 -17.383439)
			(xy 15.263768 -17.342249) (xy 15.304958 -17.306558) (xy 15.350808 -17.277091) (xy 15.400385 -17.25445)
			(xy 15.452679 -17.239095) (xy 15.506627 -17.231338) (xy 15.533878 -17.230852) (xy 16.397478 -17.230852)
			(xy 16.424731 -17.231315) (xy 16.478682 -17.239072) (xy 16.53098 -17.254428) (xy 16.580561 -17.27707)
			(xy 16.626414 -17.306538) (xy 16.667607 -17.342232) (xy 16.703301 -17.383424) (xy 16.732769 -17.429278)
			(xy 16.755412 -17.478858) (xy 16.770768 -17.531156) (xy 16.778525 -17.585107) (xy 16.778525 -17.639611)
			(xy 20.740858 -17.639611) (xy 20.740858 -17.585109) (xy 20.748614 -17.531161) (xy 20.763969 -17.478867)
			(xy 20.78661 -17.42929) (xy 20.816076 -17.383439) (xy 20.851768 -17.342249) (xy 20.892958 -17.306558)
			(xy 20.938808 -17.277091) (xy 20.988385 -17.25445) (xy 21.040679 -17.239095) (xy 21.094627 -17.231338)
			(xy 21.121878 -17.230852) (xy 21.985478 -17.230852) (xy 22.012729 -17.231394) (xy 22.066677 -17.239147)
			(xy 22.118972 -17.2545) (xy 22.168549 -17.277139) (xy 22.2144 -17.306603) (xy 22.255591 -17.342293)
			(xy 22.291284 -17.383482) (xy 22.320751 -17.429331) (xy 22.343392 -17.478908) (xy 22.358748 -17.531202)
			(xy 22.366505 -17.585149) (xy 22.366505 -17.639651) (xy 22.366505 -17.639653) (xy 26.328838 -17.639653)
			(xy 26.328838 -17.585147) (xy 26.336595 -17.531195) (xy 26.35195 -17.478897) (xy 26.374592 -17.429316)
			(xy 26.404059 -17.383462) (xy 26.439752 -17.342268) (xy 26.480944 -17.306573) (xy 26.526797 -17.277103)
			(xy 26.576376 -17.254458) (xy 26.628674 -17.239099) (xy 26.682625 -17.231339) (xy 26.709878 -17.230852)
			(xy 27.573478 -17.230852) (xy 27.600729 -17.231394) (xy 27.654677 -17.239147) (xy 27.706972 -17.2545)
			(xy 27.756549 -17.277139) (xy 27.8024 -17.306603) (xy 27.843591 -17.342293) (xy 27.879284 -17.383482)
			(xy 27.908751 -17.429331) (xy 27.931392 -17.478908) (xy 27.946748 -17.531202) (xy 27.954505 -17.585149)
			(xy 27.954505 -17.639651) (xy 27.954402 -17.640366) (xy 31.915646 -17.640366) (xy 31.915646 -17.585834)
			(xy 31.923406 -17.531857) (xy 31.938769 -17.479533) (xy 31.961421 -17.429928) (xy 31.990902 -17.384052)
			(xy 32.026611 -17.342838) (xy 32.067822 -17.307125) (xy 32.113695 -17.277639) (xy 32.163298 -17.254982)
			(xy 32.21562 -17.239615) (xy 32.269596 -17.231849) (xy 32.296862 -17.23136) (xy 33.160462 -17.23136)
			(xy 33.187736 -17.231777) (xy 33.24173 -17.239535) (xy 33.294071 -17.254899) (xy 33.343691 -17.277556)
			(xy 33.389583 -17.307044) (xy 33.43081 -17.342764) (xy 33.466533 -17.383987) (xy 33.496026 -17.429875)
			(xy 33.518688 -17.479494) (xy 33.534057 -17.531832) (xy 33.54182 -17.585826) (xy 33.54182 -17.640366)
			(xy 37.503646 -17.640366) (xy 37.503646 -17.585834) (xy 37.511406 -17.531857) (xy 37.526769 -17.479533)
			(xy 37.549421 -17.429928) (xy 37.578902 -17.384052) (xy 37.614611 -17.342838) (xy 37.655822 -17.307125)
			(xy 37.701695 -17.277639) (xy 37.751298 -17.254982) (xy 37.80362 -17.239615) (xy 37.857596 -17.231849)
			(xy 37.884862 -17.23136) (xy 38.748462 -17.23136) (xy 38.775736 -17.231777) (xy 38.82973 -17.239535)
			(xy 38.882071 -17.254899) (xy 38.931691 -17.277556) (xy 38.977583 -17.307044) (xy 39.01881 -17.342764)
			(xy 39.054533 -17.383987) (xy 39.084026 -17.429875) (xy 39.106688 -17.479494) (xy 39.122057 -17.531832)
			(xy 39.12982 -17.585826) (xy 39.12982 -17.639654) (xy 43.398638 -17.639654) (xy 43.398638 -17.585146)
			(xy 43.406395 -17.531193) (xy 43.421751 -17.478894) (xy 43.444395 -17.429312) (xy 43.473863 -17.383457)
			(xy 43.509558 -17.342262) (xy 43.550752 -17.306567) (xy 43.596606 -17.277097) (xy 43.646188 -17.254454)
			(xy 43.698487 -17.239096) (xy 43.75244 -17.231338) (xy 43.779694 -17.230852) (xy 44.643294 -17.230852)
			(xy 44.670544 -17.231395) (xy 44.72449 -17.23915) (xy 44.776783 -17.254504) (xy 44.826359 -17.277144)
			(xy 44.872208 -17.306609) (xy 44.913397 -17.342299) (xy 44.949088 -17.383487) (xy 44.978553 -17.429336)
			(xy 45.001194 -17.478911) (xy 45.016548 -17.531204) (xy 45.024305 -17.58515) (xy 45.024305 -17.63965)
			(xy 45.024304 -17.639654) (xy 48.986638 -17.639654) (xy 48.986638 -17.585146) (xy 48.994395 -17.531193)
			(xy 49.009751 -17.478894) (xy 49.032395 -17.429312) (xy 49.061863 -17.383457) (xy 49.097558 -17.342262)
			(xy 49.138752 -17.306567) (xy 49.184606 -17.277097) (xy 49.234188 -17.254454) (xy 49.286487 -17.239096)
			(xy 49.34044 -17.231338) (xy 49.367694 -17.230852) (xy 50.231294 -17.230852) (xy 50.258544 -17.231395)
			(xy 50.31249 -17.23915) (xy 50.364783 -17.254504) (xy 50.414359 -17.277144) (xy 50.460208 -17.306609)
			(xy 50.501397 -17.342299) (xy 50.537088 -17.383487) (xy 50.566553 -17.429336) (xy 50.589194 -17.478911)
			(xy 50.604548 -17.531204) (xy 50.612305 -17.58515) (xy 50.612305 -17.63965) (xy 50.612201 -17.64037)
			(xy 54.607423 -17.64037) (xy 54.607423 -17.58583) (xy 54.615186 -17.531845) (xy 54.630552 -17.479514)
			(xy 54.653209 -17.429903) (xy 54.682696 -17.384021) (xy 54.718413 -17.342803) (xy 54.759632 -17.307088)
			(xy 54.805515 -17.277602) (xy 54.855127 -17.254947) (xy 54.907459 -17.239583) (xy 54.961444 -17.231822)
			(xy 54.988714 -17.23136) (xy 55.852314 -17.23136) (xy 55.879584 -17.231803) (xy 55.933569 -17.239567)
			(xy 55.9859 -17.254935) (xy 56.035512 -17.277593) (xy 56.081393 -17.307081) (xy 56.122612 -17.342798)
			(xy 56.158328 -17.384018) (xy 56.187814 -17.429901) (xy 56.21047 -17.479513) (xy 56.225836 -17.531844)
			(xy 56.233598 -17.58583) (xy 56.233598 -17.64037) (xy 56.225836 -17.694356) (xy 56.21047 -17.746687)
			(xy 56.187814 -17.796299) (xy 56.158328 -17.842182) (xy 56.122612 -17.883402) (xy 56.081393 -17.919119)
			(xy 56.035512 -17.948607) (xy 55.9859 -17.971265) (xy 55.933569 -17.986633) (xy 55.879584 -17.994397)
			(xy 55.852314 -17.994884) (xy 54.988714 -17.994884) (xy 54.961444 -17.994378) (xy 54.907459 -17.986617)
			(xy 54.855127 -17.971253) (xy 54.805515 -17.948598) (xy 54.759632 -17.919112) (xy 54.718413 -17.883397)
			(xy 54.682696 -17.842179) (xy 54.653209 -17.796297) (xy 54.630552 -17.746686) (xy 54.615186 -17.694355)
			(xy 54.607423 -17.64037) (xy 50.612201 -17.64037) (xy 50.604548 -17.693596) (xy 50.589194 -17.745889)
			(xy 50.566553 -17.795464) (xy 50.537088 -17.841313) (xy 50.501397 -17.882501) (xy 50.460208 -17.918191)
			(xy 50.414359 -17.947656) (xy 50.364783 -17.970296) (xy 50.31249 -17.98565) (xy 50.258544 -17.993405)
			(xy 50.231294 -17.993868) (xy 49.367694 -17.993868) (xy 49.34044 -17.993462) (xy 49.286487 -17.985704)
			(xy 49.234188 -17.970346) (xy 49.184606 -17.947703) (xy 49.138752 -17.918233) (xy 49.097558 -17.882538)
			(xy 49.061863 -17.841343) (xy 49.032395 -17.795488) (xy 49.009751 -17.745906) (xy 48.994395 -17.693607)
			(xy 48.986638 -17.639654) (xy 45.024304 -17.639654) (xy 45.016548 -17.693596) (xy 45.001194 -17.745889)
			(xy 44.978553 -17.795464) (xy 44.949088 -17.841313) (xy 44.913397 -17.882501) (xy 44.872208 -17.918191)
			(xy 44.826359 -17.947656) (xy 44.776783 -17.970296) (xy 44.72449 -17.98565) (xy 44.670544 -17.993405)
			(xy 44.643294 -17.993868) (xy 43.779694 -17.993868) (xy 43.75244 -17.993462) (xy 43.698487 -17.985704)
			(xy 43.646188 -17.970346) (xy 43.596606 -17.947703) (xy 43.550752 -17.918233) (xy 43.509558 -17.882538)
			(xy 43.473863 -17.841343) (xy 43.444395 -17.795488) (xy 43.421751 -17.745906) (xy 43.406395 -17.693607)
			(xy 43.398638 -17.639654) (xy 39.12982 -17.639654) (xy 39.12982 -17.640374) (xy 39.122057 -17.694368)
			(xy 39.106688 -17.746706) (xy 39.084026 -17.796325) (xy 39.054533 -17.842213) (xy 39.01881 -17.883436)
			(xy 38.977583 -17.919156) (xy 38.931691 -17.948644) (xy 38.882071 -17.971301) (xy 38.82973 -17.986665)
			(xy 38.775736 -17.994423) (xy 38.748462 -17.994884) (xy 37.884862 -17.994884) (xy 37.857596 -17.994351)
			(xy 37.80362 -17.986585) (xy 37.751298 -17.971218) (xy 37.701695 -17.948561) (xy 37.655822 -17.919075)
			(xy 37.614611 -17.883362) (xy 37.578902 -17.842148) (xy 37.549421 -17.796272) (xy 37.526769 -17.746667)
			(xy 37.511406 -17.694343) (xy 37.503646 -17.640366) (xy 33.54182 -17.640366) (xy 33.54182 -17.640374)
			(xy 33.534057 -17.694368) (xy 33.518688 -17.746706) (xy 33.496026 -17.796325) (xy 33.466533 -17.842213)
			(xy 33.43081 -17.883436) (xy 33.389583 -17.919156) (xy 33.343691 -17.948644) (xy 33.294071 -17.971301)
			(xy 33.24173 -17.986665) (xy 33.187736 -17.994423) (xy 33.160462 -17.994884) (xy 32.296862 -17.994884)
			(xy 32.269596 -17.994351) (xy 32.21562 -17.986585) (xy 32.163298 -17.971218) (xy 32.113695 -17.948561)
			(xy 32.067822 -17.919075) (xy 32.026611 -17.883362) (xy 31.990902 -17.842148) (xy 31.961421 -17.796272)
			(xy 31.938769 -17.746667) (xy 31.923406 -17.694343) (xy 31.915646 -17.640366) (xy 27.954402 -17.640366)
			(xy 27.946748 -17.693598) (xy 27.931392 -17.745892) (xy 27.908751 -17.795469) (xy 27.879284 -17.841318)
			(xy 27.843591 -17.882507) (xy 27.8024 -17.918197) (xy 27.756549 -17.947661) (xy 27.706972 -17.9703)
			(xy 27.654677 -17.985653) (xy 27.600729 -17.993406) (xy 27.573478 -17.993868) (xy 26.709878 -17.993868)
			(xy 26.682625 -17.993461) (xy 26.628674 -17.985701) (xy 26.576376 -17.970342) (xy 26.526797 -17.947697)
			(xy 26.480944 -17.918227) (xy 26.439752 -17.882532) (xy 26.404059 -17.841338) (xy 26.374592 -17.795484)
			(xy 26.35195 -17.745903) (xy 26.336595 -17.693605) (xy 26.328838 -17.639653) (xy 22.366505 -17.639653)
			(xy 22.358748 -17.693598) (xy 22.343392 -17.745892) (xy 22.320751 -17.795469) (xy 22.291284 -17.841318)
			(xy 22.255591 -17.882507) (xy 22.2144 -17.918197) (xy 22.168549 -17.947661) (xy 22.118972 -17.9703)
			(xy 22.066677 -17.985653) (xy 22.012729 -17.993406) (xy 21.985478 -17.993868) (xy 21.121878 -17.993868)
			(xy 21.094627 -17.993382) (xy 21.040679 -17.985625) (xy 20.988385 -17.97027) (xy 20.938808 -17.947629)
			(xy 20.892958 -17.918162) (xy 20.851768 -17.882471) (xy 20.816076 -17.841281) (xy 20.78661 -17.79543)
			(xy 20.763969 -17.745853) (xy 20.748614 -17.693559) (xy 20.740858 -17.639611) (xy 16.778525 -17.639611)
			(xy 16.778525 -17.639613) (xy 16.770768 -17.693564) (xy 16.755412 -17.745862) (xy 16.732769 -17.795442)
			(xy 16.703301 -17.841296) (xy 16.667607 -17.882488) (xy 16.626414 -17.918182) (xy 16.580561 -17.94765)
			(xy 16.53098 -17.970292) (xy 16.478682 -17.985648) (xy 16.424731 -17.993405) (xy 16.397478 -17.993868)
			(xy 15.533878 -17.993868) (xy 15.506627 -17.993382) (xy 15.452679 -17.985625) (xy 15.400385 -17.97027)
			(xy 15.350808 -17.947629) (xy 15.304958 -17.918162) (xy 15.263768 -17.882471) (xy 15.228076 -17.841281)
			(xy 15.19861 -17.79543) (xy 15.175969 -17.745853) (xy 15.160614 -17.693559) (xy 15.152858 -17.639611)
			(xy 0.509016 -17.639611) (xy 0.509016 -19.164391) (xy 17.945563 -19.164391) (xy 17.945563 -19.109849)
			(xy 17.953326 -19.055862) (xy 17.968692 -19.00353) (xy 17.99135 -18.953917) (xy 18.020837 -18.908033)
			(xy 18.056555 -18.866813) (xy 18.097775 -18.831096) (xy 18.143658 -18.801609) (xy 18.193272 -18.778951)
			(xy 18.245604 -18.763585) (xy 18.299591 -18.755823) (xy 18.326862 -18.75536) (xy 19.190462 -18.75536)
			(xy 19.217731 -18.755843) (xy 19.271715 -18.763605) (xy 19.324045 -18.77897) (xy 19.373655 -18.801627)
			(xy 19.419536 -18.831113) (xy 19.460753 -18.866828) (xy 19.496469 -18.908046) (xy 19.525954 -18.953927)
			(xy 19.548611 -19.003537) (xy 19.563976 -19.055867) (xy 19.571738 -19.109851) (xy 19.571738 -19.163653)
			(xy 23.534838 -19.163653) (xy 23.534838 -19.109147) (xy 23.542595 -19.055195) (xy 23.55795 -19.002897)
			(xy 23.580592 -18.953316) (xy 23.610059 -18.907462) (xy 23.645752 -18.866268) (xy 23.686944 -18.830573)
			(xy 23.732797 -18.801103) (xy 23.782376 -18.778458) (xy 23.834674 -18.763099) (xy 23.888625 -18.755339)
			(xy 23.915878 -18.754852) (xy 24.779478 -18.754852) (xy 24.806729 -18.755394) (xy 24.860677 -18.763147)
			(xy 24.912972 -18.7785) (xy 24.962549 -18.801139) (xy 25.0084 -18.830603) (xy 25.049591 -18.866293)
			(xy 25.085284 -18.907482) (xy 25.114751 -18.953331) (xy 25.137392 -19.002908) (xy 25.152748 -19.055202)
			(xy 25.160505 -19.109149) (xy 25.160505 -19.163651) (xy 25.160505 -19.163653) (xy 29.122838 -19.163653)
			(xy 29.122838 -19.109147) (xy 29.130595 -19.055195) (xy 29.14595 -19.002897) (xy 29.168592 -18.953316)
			(xy 29.198059 -18.907462) (xy 29.233752 -18.866268) (xy 29.274944 -18.830573) (xy 29.320797 -18.801103)
			(xy 29.370376 -18.778458) (xy 29.422674 -18.763099) (xy 29.476625 -18.755339) (xy 29.503878 -18.754852)
			(xy 30.367478 -18.754852) (xy 30.394729 -18.755394) (xy 30.448677 -18.763147) (xy 30.500972 -18.7785)
			(xy 30.550549 -18.801139) (xy 30.5964 -18.830603) (xy 30.637591 -18.866293) (xy 30.673284 -18.907482)
			(xy 30.702751 -18.953331) (xy 30.725392 -19.002908) (xy 30.740748 -19.055202) (xy 30.748505 -19.109149)
			(xy 30.748505 -19.163651) (xy 30.748505 -19.163653) (xy 34.710838 -19.163653) (xy 34.710838 -19.109147)
			(xy 34.718595 -19.055195) (xy 34.73395 -19.002897) (xy 34.756592 -18.953316) (xy 34.786059 -18.907462)
			(xy 34.821752 -18.866268) (xy 34.862944 -18.830573) (xy 34.908797 -18.801103) (xy 34.958376 -18.778458)
			(xy 35.010674 -18.763099) (xy 35.064625 -18.755339) (xy 35.091878 -18.754852) (xy 35.955478 -18.754852)
			(xy 35.982729 -18.755394) (xy 36.036677 -18.763147) (xy 36.088972 -18.7785) (xy 36.138549 -18.801139)
			(xy 36.1844 -18.830603) (xy 36.225591 -18.866293) (xy 36.261284 -18.907482) (xy 36.290751 -18.953331)
			(xy 36.313392 -19.002908) (xy 36.328748 -19.055202) (xy 36.336505 -19.109149) (xy 36.336505 -19.163651)
			(xy 36.336505 -19.163654) (xy 40.604638 -19.163654) (xy 40.604638 -19.109146) (xy 40.612395 -19.055193)
			(xy 40.627751 -19.002894) (xy 40.650395 -18.953312) (xy 40.679863 -18.907457) (xy 40.715558 -18.866262)
			(xy 40.756752 -18.830567) (xy 40.802606 -18.801097) (xy 40.852188 -18.778454) (xy 40.904487 -18.763096)
			(xy 40.95844 -18.755338) (xy 40.985694 -18.754852) (xy 41.849294 -18.754852) (xy 41.876544 -18.755395)
			(xy 41.93049 -18.76315) (xy 41.982783 -18.778504) (xy 42.032359 -18.801144) (xy 42.078208 -18.830609)
			(xy 42.119397 -18.866299) (xy 42.155088 -18.907487) (xy 42.184553 -18.953336) (xy 42.207194 -19.002911)
			(xy 42.222548 -19.055204) (xy 42.230305 -19.10915) (xy 42.230305 -19.16365) (xy 42.230202 -19.164367)
			(xy 46.191446 -19.164367) (xy 46.191446 -19.109833) (xy 46.199207 -19.055855) (xy 46.21457 -19.00353)
			(xy 46.237224 -18.953924) (xy 46.266706 -18.908047) (xy 46.302417 -18.866832) (xy 46.343629 -18.831119)
			(xy 46.389505 -18.801634) (xy 46.439109 -18.778978) (xy 46.491433 -18.763612) (xy 46.545411 -18.755848)
			(xy 46.572678 -18.75536) (xy 47.436278 -18.75536) (xy 47.463552 -18.755778) (xy 47.517544 -18.763538)
			(xy 47.569882 -18.778903) (xy 47.619501 -18.801561) (xy 47.66539 -18.83105) (xy 47.706615 -18.866769)
			(xy 47.742337 -18.907992) (xy 47.771828 -18.95388) (xy 47.794489 -19.003497) (xy 47.809857 -19.055835)
			(xy 47.81762 -19.109826) (xy 47.81762 -19.163657) (xy 51.814615 -19.163657) (xy 51.814615 -19.109143)
			(xy 51.822374 -19.055184) (xy 51.837733 -19.002878) (xy 51.86038 -18.95329) (xy 51.889854 -18.907431)
			(xy 51.925554 -18.866233) (xy 51.966755 -18.830536) (xy 52.012617 -18.801065) (xy 52.062206 -18.778422)
			(xy 52.114513 -18.763067) (xy 52.168473 -18.755313) (xy 52.19573 -18.754852) (xy 53.05933 -18.754852)
			(xy 53.086577 -18.75542) (xy 53.140516 -18.763179) (xy 53.192801 -18.778535) (xy 53.24237 -18.801176)
			(xy 53.288211 -18.83064) (xy 53.329394 -18.866328) (xy 53.365078 -18.907513) (xy 53.394538 -18.953357)
			(xy 53.417175 -19.002927) (xy 53.432527 -19.055214) (xy 53.440282 -19.109153) (xy 53.440282 -19.163647)
			(xy 53.440281 -19.163657) (xy 57.402615 -19.163657) (xy 57.402615 -19.109143) (xy 57.410374 -19.055184)
			(xy 57.425733 -19.002878) (xy 57.44838 -18.95329) (xy 57.477854 -18.907431) (xy 57.513554 -18.866233)
			(xy 57.554755 -18.830536) (xy 57.600617 -18.801065) (xy 57.650206 -18.778422) (xy 57.702513 -18.763067)
			(xy 57.756473 -18.755313) (xy 57.78373 -18.754852) (xy 58.64733 -18.754852) (xy 58.674577 -18.75542)
			(xy 58.728516 -18.763179) (xy 58.780801 -18.778535) (xy 58.83037 -18.801176) (xy 58.876211 -18.83064)
			(xy 58.917394 -18.866328) (xy 58.953078 -18.907513) (xy 58.982538 -18.953357) (xy 59.005175 -19.002927)
			(xy 59.020527 -19.055214) (xy 59.028282 -19.109153) (xy 59.028282 -19.163647) (xy 59.020527 -19.217586)
			(xy 59.005175 -19.269873) (xy 58.982538 -19.319443) (xy 58.953078 -19.365287) (xy 58.917394 -19.406472)
			(xy 58.876211 -19.44216) (xy 58.83037 -19.471624) (xy 58.780801 -19.494265) (xy 58.728516 -19.509621)
			(xy 58.674577 -19.51738) (xy 58.64733 -19.517868) (xy 57.78373 -19.517868) (xy 57.756473 -19.517487)
			(xy 57.702513 -19.509733) (xy 57.650206 -19.494378) (xy 57.600617 -19.471735) (xy 57.554755 -19.442264)
			(xy 57.513554 -19.406567) (xy 57.477854 -19.365369) (xy 57.44838 -19.31951) (xy 57.425733 -19.269922)
			(xy 57.410374 -19.217616) (xy 57.402615 -19.163657) (xy 53.440281 -19.163657) (xy 53.432527 -19.217586)
			(xy 53.417175 -19.269873) (xy 53.394538 -19.319443) (xy 53.365078 -19.365287) (xy 53.329394 -19.406472)
			(xy 53.288211 -19.44216) (xy 53.24237 -19.471624) (xy 53.192801 -19.494265) (xy 53.140516 -19.509621)
			(xy 53.086577 -19.51738) (xy 53.05933 -19.517868) (xy 52.19573 -19.517868) (xy 52.168473 -19.517487)
			(xy 52.114513 -19.509733) (xy 52.062206 -19.494378) (xy 52.012617 -19.471735) (xy 51.966755 -19.442264)
			(xy 51.925554 -19.406567) (xy 51.889854 -19.365369) (xy 51.86038 -19.31951) (xy 51.837733 -19.269922)
			(xy 51.822374 -19.217616) (xy 51.814615 -19.163657) (xy 47.81762 -19.163657) (xy 47.81762 -19.164374)
			(xy 47.809857 -19.218365) (xy 47.794489 -19.270703) (xy 47.771828 -19.32032) (xy 47.742337 -19.366208)
			(xy 47.706615 -19.407431) (xy 47.66539 -19.44315) (xy 47.619501 -19.472639) (xy 47.569882 -19.495297)
			(xy 47.517544 -19.510662) (xy 47.463552 -19.518422) (xy 47.436278 -19.518884) (xy 46.572678 -19.518884)
			(xy 46.545411 -19.518352) (xy 46.491433 -19.510588) (xy 46.439109 -19.495222) (xy 46.389505 -19.472566)
			(xy 46.343629 -19.443081) (xy 46.302417 -19.407368) (xy 46.266706 -19.366153) (xy 46.237224 -19.320276)
			(xy 46.21457 -19.27067) (xy 46.199207 -19.218345) (xy 46.191446 -19.164367) (xy 42.230202 -19.164367)
			(xy 42.222548 -19.217596) (xy 42.207194 -19.269889) (xy 42.184553 -19.319464) (xy 42.155088 -19.365313)
			(xy 42.119397 -19.406501) (xy 42.078208 -19.442191) (xy 42.032359 -19.471656) (xy 41.982783 -19.494296)
			(xy 41.93049 -19.50965) (xy 41.876544 -19.517405) (xy 41.849294 -19.517868) (xy 40.985694 -19.517868)
			(xy 40.95844 -19.517462) (xy 40.904487 -19.509704) (xy 40.852188 -19.494346) (xy 40.802606 -19.471703)
			(xy 40.756752 -19.442233) (xy 40.715558 -19.406538) (xy 40.679863 -19.365343) (xy 40.650395 -19.319488)
			(xy 40.627751 -19.269906) (xy 40.612395 -19.217607) (xy 40.604638 -19.163654) (xy 36.336505 -19.163654)
			(xy 36.328748 -19.217598) (xy 36.313392 -19.269892) (xy 36.290751 -19.319469) (xy 36.261284 -19.365318)
			(xy 36.225591 -19.406507) (xy 36.1844 -19.442197) (xy 36.138549 -19.471661) (xy 36.088972 -19.4943)
			(xy 36.036677 -19.509653) (xy 35.982729 -19.517406) (xy 35.955478 -19.517868) (xy 35.091878 -19.517868)
			(xy 35.064625 -19.517461) (xy 35.010674 -19.509701) (xy 34.958376 -19.494342) (xy 34.908797 -19.471697)
			(xy 34.862944 -19.442227) (xy 34.821752 -19.406532) (xy 34.786059 -19.365338) (xy 34.756592 -19.319484)
			(xy 34.73395 -19.269903) (xy 34.718595 -19.217605) (xy 34.710838 -19.163653) (xy 30.748505 -19.163653)
			(xy 30.740748 -19.217598) (xy 30.725392 -19.269892) (xy 30.702751 -19.319469) (xy 30.673284 -19.365318)
			(xy 30.637591 -19.406507) (xy 30.5964 -19.442197) (xy 30.550549 -19.471661) (xy 30.500972 -19.4943)
			(xy 30.448677 -19.509653) (xy 30.394729 -19.517406) (xy 30.367478 -19.517868) (xy 29.503878 -19.517868)
			(xy 29.476625 -19.517461) (xy 29.422674 -19.509701) (xy 29.370376 -19.494342) (xy 29.320797 -19.471697)
			(xy 29.274944 -19.442227) (xy 29.233752 -19.406532) (xy 29.198059 -19.365338) (xy 29.168592 -19.319484)
			(xy 29.14595 -19.269903) (xy 29.130595 -19.217605) (xy 29.122838 -19.163653) (xy 25.160505 -19.163653)
			(xy 25.152748 -19.217598) (xy 25.137392 -19.269892) (xy 25.114751 -19.319469) (xy 25.085284 -19.365318)
			(xy 25.049591 -19.406507) (xy 25.0084 -19.442197) (xy 24.962549 -19.471661) (xy 24.912972 -19.4943)
			(xy 24.860677 -19.509653) (xy 24.806729 -19.517406) (xy 24.779478 -19.517868) (xy 23.915878 -19.517868)
			(xy 23.888625 -19.517461) (xy 23.834674 -19.509701) (xy 23.782376 -19.494342) (xy 23.732797 -19.471697)
			(xy 23.686944 -19.442227) (xy 23.645752 -19.406532) (xy 23.610059 -19.365338) (xy 23.580592 -19.319484)
			(xy 23.55795 -19.269903) (xy 23.542595 -19.217605) (xy 23.534838 -19.163653) (xy 19.571738 -19.163653)
			(xy 19.571738 -19.164389) (xy 19.563976 -19.218373) (xy 19.548611 -19.270703) (xy 19.525954 -19.320313)
			(xy 19.496469 -19.366194) (xy 19.460753 -19.407412) (xy 19.419536 -19.443127) (xy 19.373655 -19.472613)
			(xy 19.324045 -19.49527) (xy 19.271715 -19.510635) (xy 19.217731 -19.518397) (xy 19.190462 -19.518884)
			(xy 18.326862 -19.518884) (xy 18.299591 -19.518417) (xy 18.245604 -19.510655) (xy 18.193272 -19.495289)
			(xy 18.143658 -19.472631) (xy 18.097775 -19.443144) (xy 18.056555 -19.407427) (xy 18.020837 -19.366207)
			(xy 17.99135 -19.320323) (xy 17.968692 -19.27071) (xy 17.953326 -19.218378) (xy 17.945563 -19.164391)
			(xy 0.509016 -19.164391) (xy 0.509016 -20.327366) (xy 65.88506 -20.327366) (xy 65.885484 -20.289077)
			(xy 65.892086 -20.212783) (xy 65.90523 -20.13734) (xy 65.924819 -20.063309) (xy 65.937384 -20.027138)
			(xy 65.940051 -20.018705) (xy 65.94004 -20.001031) (xy 65.937384 -19.992594) (xy 65.924856 -19.956411)
			(xy 65.905279 -19.88238) (xy 65.892127 -19.806942) (xy 65.885498 -19.730654) (xy 65.88506 -19.692366)
			(xy 65.885582 -19.650174) (xy 65.893576 -19.56617) (xy 65.909488 -19.483301) (xy 65.933176 -19.402311)
			(xy 65.964427 -19.323927) (xy 66.00296 -19.248856) (xy 66.048429 -19.17777) (xy 66.074036 -19.144234)
			(xy 66.079883 -19.13601) (xy 66.085128 -19.116537) (xy 66.082515 -19.096539) (xy 66.077846 -19.087592)
			(xy 66.058798 -19.053767) (xy 66.026006 -18.983399) (xy 65.999468 -18.910441) (xy 65.979384 -18.83545)
			(xy 65.965909 -18.758994) (xy 65.959144 -18.681655) (xy 65.95872 -18.642838) (xy 65.95872 -18.642584)
			(xy 65.959137 -18.60148) (xy 65.966724 -18.519622) (xy 65.981831 -18.438814) (xy 66.00433 -18.359744)
			(xy 66.034029 -18.283087) (xy 66.070674 -18.209498) (xy 66.113953 -18.139604) (xy 66.163496 -18.074001)
			(xy 66.218881 -18.01325) (xy 66.279635 -17.957868) (xy 66.34524 -17.908328) (xy 66.415137 -17.865053)
			(xy 66.488728 -17.828411) (xy 66.565386 -17.798716) (xy 66.644456 -17.776221) (xy 66.725266 -17.761118)
			(xy 66.807124 -17.753535) (xy 66.848228 -17.753076) (xy 66.889911 -17.753577) (xy 66.972911 -17.761363)
			(xy 67.054819 -17.776882) (xy 67.134915 -17.799999) (xy 67.212496 -17.830511) (xy 67.286881 -17.868149)
			(xy 67.357417 -17.912584) (xy 67.423485 -17.963425) (xy 67.484504 -18.020226) (xy 67.53994 -18.082488)
			(xy 67.565016 -18.115788) (xy 67.56527 -18.116042) (xy 67.570757 -18.122776) (xy 67.585223 -18.132372)
			(xy 67.602063 -18.136587) (xy 67.610736 -18.136108) (xy 67.697858 -18.127726) (xy 67.706567 -18.126584)
			(xy 67.722478 -18.119178) (xy 67.734922 -18.1068) (xy 67.739006 -18.099024) (xy 67.739006 -18.098516)
			(xy 67.757258 -18.060702) (xy 67.799884 -17.988356) (xy 67.849141 -17.920351) (xy 67.90459 -17.857291)
			(xy 67.965736 -17.79974) (xy 68.032035 -17.748209) (xy 68.102897 -17.703158) (xy 68.17769 -17.664987)
			(xy 68.255748 -17.634037) (xy 68.336377 -17.610583) (xy 68.418857 -17.594835) (xy 68.502455 -17.586933)
			(xy 68.54444 -17.586452) (xy 68.5868 -17.58693) (xy 68.671136 -17.594986) (xy 68.754325 -17.611023)
			(xy 68.835612 -17.634895) (xy 68.914262 -17.666384) (xy 68.989563 -17.705208) (xy 69.060833 -17.751013)
			(xy 69.127426 -17.803385) (xy 69.18874 -17.86185) (xy 69.244218 -17.925878) (xy 69.293359 -17.99489)
			(xy 69.335718 -18.068261) (xy 69.370911 -18.145325) (xy 69.39862 -18.225386) (xy 69.401856 -18.238724)
			(xy 79.0321 -18.238724) (xy 79.032651 -18.193954) (xy 79.041664 -18.104869) (xy 79.059573 -18.017137)
			(xy 79.086195 -17.931647) (xy 79.10322 -17.890236) (xy 79.106772 -17.880641) (xy 79.106781 -17.860202)
			(xy 79.10322 -17.850612) (xy 79.086184 -17.809205) (xy 79.059551 -17.723717) (xy 79.041646 -17.635983)
			(xy 79.032653 -17.546895) (xy 79.0321 -17.502124) (xy 79.032604 -17.459763) (xy 79.040657 -17.375426)
			(xy 79.056691 -17.292236) (xy 79.080559 -17.210946) (xy 79.112047 -17.132294) (xy 79.150869 -17.056991)
			(xy 79.196672 -16.985719) (xy 79.249043 -16.919123) (xy 79.307508 -16.857808) (xy 79.371536 -16.802327)
			(xy 79.440548 -16.753184) (xy 79.513918 -16.710824) (xy 79.590983 -16.675629) (xy 79.671045 -16.64792)
			(xy 79.753378 -16.627946) (xy 79.837237 -16.615889) (xy 79.921862 -16.611858) (xy 80.006487 -16.615889)
			(xy 80.090346 -16.627946) (xy 80.172679 -16.64792) (xy 80.252741 -16.675629) (xy 80.329806 -16.710824)
			(xy 80.403176 -16.753184) (xy 80.472188 -16.802327) (xy 80.536216 -16.857808) (xy 80.594681 -16.919123)
			(xy 80.647052 -16.985719) (xy 80.692855 -17.056991) (xy 80.731677 -17.132294) (xy 80.763165 -17.210946)
			(xy 80.787033 -17.292236) (xy 80.803067 -17.375426) (xy 80.81112 -17.459763) (xy 80.811624 -17.502124)
			(xy 80.811054 -17.546893) (xy 80.802046 -17.635978) (xy 80.784143 -17.723709) (xy 80.757526 -17.809201)
			(xy 80.740504 -17.850612) (xy 80.736924 -17.860198) (xy 80.736933 -17.880645) (xy 80.740504 -17.890236)
			(xy 80.757551 -17.931638) (xy 80.784182 -18.017129) (xy 80.802084 -18.104863) (xy 80.808854 -18.171951)
			(xy 131.633699 -18.171951) (xy 131.633699 -18.117449) (xy 131.641456 -18.063503) (xy 131.656811 -18.011209)
			(xy 131.679453 -17.961633) (xy 131.708919 -17.915784) (xy 131.744611 -17.874596) (xy 131.785802 -17.838906)
			(xy 131.831653 -17.809442) (xy 131.88123 -17.786804) (xy 131.933524 -17.771451) (xy 131.987471 -17.763698)
			(xy 132.014722 -17.763236) (xy 132.878322 -17.763236) (xy 132.905575 -17.763635) (xy 132.959527 -17.771395)
			(xy 133.011825 -17.786754) (xy 133.061405 -17.809399) (xy 133.107258 -17.838869) (xy 133.148451 -17.874565)
			(xy 133.184144 -17.915759) (xy 133.213611 -17.961614) (xy 133.236254 -18.011196) (xy 133.251609 -18.063495)
			(xy 133.259366 -18.117447) (xy 133.259366 -18.171946) (xy 137.033822 -18.171946) (xy 137.033822 -18.117454)
			(xy 137.041577 -18.063516) (xy 137.056928 -18.01123) (xy 137.079564 -17.961661) (xy 137.109023 -17.915818)
			(xy 137.144706 -17.874633) (xy 137.185887 -17.838946) (xy 137.231728 -17.809482) (xy 137.281294 -17.786841)
			(xy 137.333578 -17.771485) (xy 137.387516 -17.763725) (xy 137.414762 -17.763236) (xy 138.278362 -17.763236)
			(xy 138.30562 -17.763608) (xy 138.359581 -17.771362) (xy 138.41189 -17.786716) (xy 138.46148 -17.809359)
			(xy 138.507344 -17.83883) (xy 138.548546 -17.874528) (xy 138.584247 -17.915726) (xy 138.613722 -17.961586)
			(xy 138.63637 -18.011175) (xy 138.65173 -18.063482) (xy 138.659489 -18.117442) (xy 138.659489 -18.17195)
			(xy 140.633699 -18.17195) (xy 140.633699 -18.11745) (xy 140.641455 -18.063505) (xy 140.65681 -18.011213)
			(xy 140.67945 -17.961638) (xy 140.708915 -17.91579) (xy 140.744605 -17.874602) (xy 140.785793 -17.838913)
			(xy 140.831642 -17.809448) (xy 140.881217 -17.786808) (xy 140.933509 -17.771455) (xy 140.987454 -17.763699)
			(xy 141.014704 -17.763236) (xy 141.878304 -17.763236) (xy 141.905558 -17.763634) (xy 141.959512 -17.771392)
			(xy 142.011812 -17.786749) (xy 142.061394 -17.809393) (xy 142.10725 -17.838863) (xy 142.148444 -17.874559)
			(xy 142.184139 -17.915754) (xy 142.213609 -17.961609) (xy 142.236252 -18.011192) (xy 142.251609 -18.063492)
			(xy 142.259366 -18.117446) (xy 142.259366 -18.171954) (xy 142.251609 -18.225908) (xy 142.236252 -18.278208)
			(xy 142.213609 -18.327791) (xy 142.184139 -18.373646) (xy 142.148444 -18.414841) (xy 142.10725 -18.450537)
			(xy 142.061394 -18.480007) (xy 142.011812 -18.502651) (xy 141.959512 -18.518008) (xy 141.905558 -18.525766)
			(xy 141.878304 -18.526252) (xy 141.014704 -18.526252) (xy 140.987454 -18.525701) (xy 140.933509 -18.517945)
			(xy 140.881217 -18.502592) (xy 140.831642 -18.479952) (xy 140.785793 -18.450487) (xy 140.744605 -18.414798)
			(xy 140.708915 -18.37361) (xy 140.67945 -18.327762) (xy 140.65681 -18.278187) (xy 140.641455 -18.225895)
			(xy 140.633699 -18.17195) (xy 138.659489 -18.17195) (xy 138.659489 -18.171958) (xy 138.65173 -18.225918)
			(xy 138.63637 -18.278225) (xy 138.613722 -18.327814) (xy 138.584247 -18.373674) (xy 138.548546 -18.414872)
			(xy 138.507344 -18.45057) (xy 138.46148 -18.480041) (xy 138.41189 -18.502684) (xy 138.359581 -18.518038)
			(xy 138.30562 -18.525792) (xy 138.278362 -18.526252) (xy 137.414762 -18.526252) (xy 137.387516 -18.525675)
			(xy 137.333578 -18.517915) (xy 137.281294 -18.502559) (xy 137.231728 -18.479918) (xy 137.185887 -18.450454)
			(xy 137.144706 -18.414767) (xy 137.109023 -18.373582) (xy 137.079564 -18.327739) (xy 137.056928 -18.27817)
			(xy 137.041577 -18.225884) (xy 137.033822 -18.171946) (xy 133.259366 -18.171946) (xy 133.259366 -18.171953)
			(xy 133.251609 -18.225905) (xy 133.236254 -18.278204) (xy 133.213611 -18.327786) (xy 133.184144 -18.373641)
			(xy 133.148451 -18.414835) (xy 133.107258 -18.450531) (xy 133.061405 -18.480001) (xy 133.011825 -18.502646)
			(xy 132.959527 -18.518005) (xy 132.905575 -18.525765) (xy 132.878322 -18.526252) (xy 132.014722 -18.526252)
			(xy 131.987471 -18.525702) (xy 131.933524 -18.517949) (xy 131.88123 -18.502596) (xy 131.831653 -18.479958)
			(xy 131.785802 -18.450494) (xy 131.744611 -18.414804) (xy 131.708919 -18.373616) (xy 131.679453 -18.327767)
			(xy 131.656811 -18.278191) (xy 131.641456 -18.225897) (xy 131.633699 -18.171951) (xy 80.808854 -18.171951)
			(xy 80.811074 -18.193953) (xy 80.811624 -18.238724) (xy 80.81112 -18.281085) (xy 80.803067 -18.365422)
			(xy 80.787033 -18.448612) (xy 80.763165 -18.529902) (xy 80.731677 -18.608554) (xy 80.692855 -18.683857)
			(xy 80.647052 -18.755129) (xy 80.594681 -18.821725) (xy 80.536216 -18.88304) (xy 80.472188 -18.938521)
			(xy 80.403176 -18.987664) (xy 80.329806 -19.030024) (xy 80.252741 -19.065219) (xy 80.172679 -19.092928)
			(xy 80.090346 -19.112902) (xy 80.006487 -19.124959) (xy 79.921862 -19.128991) (xy 79.837237 -19.124959)
			(xy 79.753378 -19.112902) (xy 79.671045 -19.092928) (xy 79.590983 -19.065219) (xy 79.513918 -19.030024)
			(xy 79.440548 -18.987664) (xy 79.371536 -18.938521) (xy 79.307508 -18.88304) (xy 79.249043 -18.821725)
			(xy 79.196672 -18.755129) (xy 79.150869 -18.683857) (xy 79.112047 -18.608554) (xy 79.080559 -18.529902)
			(xy 79.056691 -18.448612) (xy 79.040657 -18.365422) (xy 79.032604 -18.281085) (xy 79.0321 -18.238724)
			(xy 69.401856 -18.238724) (xy 69.418593 -18.307718) (xy 69.430649 -18.391576) (xy 69.434681 -18.4762)
			(xy 69.430649 -18.560824) (xy 69.418593 -18.644682) (xy 69.39862 -18.727014) (xy 69.370911 -18.807075)
			(xy 69.335718 -18.884139) (xy 69.293359 -18.95751) (xy 69.244218 -19.026522) (xy 69.18874 -19.09055)
			(xy 69.127426 -19.149015) (xy 69.060833 -19.201387) (xy 68.989563 -19.247192) (xy 68.914262 -19.286016)
			(xy 68.835612 -19.317505) (xy 68.754325 -19.341377) (xy 68.671136 -19.357414) (xy 68.5868 -19.36547)
			(xy 68.54444 -19.365976) (xy 68.502753 -19.365468) (xy 68.419745 -19.357644) (xy 68.337834 -19.342089)
			(xy 68.257737 -19.31894) (xy 68.180157 -19.288398) (xy 68.105774 -19.250734) (xy 68.035242 -19.206275)
			(xy 67.969177 -19.155414) (xy 67.90816 -19.098595) (xy 67.852727 -19.036317) (xy 67.827652 -19.00301)
			(xy 67.827398 -19.002756) (xy 67.821873 -18.996058) (xy 67.807425 -18.986454) (xy 67.790601 -18.982223)
			(xy 67.781932 -18.98269) (xy 67.69481 -18.991072) (xy 67.686098 -18.992195) (xy 67.670187 -18.999611)
			(xy 67.657745 -19.011995) (xy 67.653662 -19.019774) (xy 67.653662 -19.020282) (xy 67.63179 -19.065383)
			(xy 67.579339 -19.150805) (xy 67.549014 -19.190716) (xy 67.543272 -19.198996) (xy 67.538026 -19.218428)
			(xy 67.540615 -19.238388) (xy 67.545204 -19.247358) (xy 67.564269 -19.281203) (xy 67.597117 -19.351604)
			(xy 67.623706 -19.424598) (xy 67.643834 -19.499632) (xy 67.657349 -19.576134) (xy 67.664146 -19.653523)
			(xy 67.664584 -19.692366) (xy 67.664167 -19.730656) (xy 67.657563 -19.806949) (xy 67.644416 -19.882392)
			(xy 67.624826 -19.956423) (xy 67.61226 -19.992594) (xy 67.609626 -20.001035) (xy 67.609615 -20.018702)
			(xy 67.61226 -20.027138) (xy 67.624799 -20.063317) (xy 67.644373 -20.13735) (xy 67.653158 -20.187755)
			(xy 138.765443 -20.187755) (xy 138.765443 -20.133245) (xy 138.773201 -20.079289) (xy 138.788559 -20.026987)
			(xy 138.811205 -19.977403) (xy 138.840677 -19.931547) (xy 138.876376 -19.890352) (xy 138.917574 -19.854657)
			(xy 138.963433 -19.825189) (xy 139.013019 -19.802547) (xy 139.065322 -19.787194) (xy 139.119279 -19.779441)
			(xy 139.146534 -19.77898) (xy 140.137134 -19.77898) (xy 140.164383 -19.779493) (xy 140.218325 -19.787253)
			(xy 140.270614 -19.80261) (xy 140.320185 -19.825253) (xy 140.36603 -19.854719) (xy 140.407215 -19.890409)
			(xy 140.442901 -19.931597) (xy 140.449617 -19.942048) (xy 175.988472 -19.942048) (xy 175.988976 -19.899687)
			(xy 175.997029 -19.81535) (xy 176.013063 -19.73216) (xy 176.036931 -19.65087) (xy 176.068419 -19.572218)
			(xy 176.107241 -19.496915) (xy 176.153044 -19.425643) (xy 176.205415 -19.359047) (xy 176.26388 -19.297732)
			(xy 176.327908 -19.242251) (xy 176.39692 -19.193108) (xy 176.47029 -19.150748) (xy 176.547355 -19.115553)
			(xy 176.627417 -19.087844) (xy 176.70975 -19.06787) (xy 176.793609 -19.055813) (xy 176.878234 -19.051782)
			(xy 176.962859 -19.055813) (xy 177.046718 -19.06787) (xy 177.129051 -19.087844) (xy 177.209113 -19.115553)
			(xy 177.286178 -19.150748) (xy 177.359548 -19.193108) (xy 177.42856 -19.242251) (xy 177.492588 -19.297732)
			(xy 177.551053 -19.359047) (xy 177.603424 -19.425643) (xy 177.649227 -19.496915) (xy 177.688049 -19.572218)
			(xy 177.719537 -19.65087) (xy 177.743405 -19.73216) (xy 177.759439 -19.81535) (xy 177.767492 -19.899687)
			(xy 177.767996 -19.942048) (xy 177.767398 -19.98792) (xy 177.757891 -20.079169) (xy 177.739034 -20.168954)
			(xy 177.725578 -20.212812) (xy 177.722752 -20.223379) (xy 177.72523 -20.245087) (xy 177.730404 -20.254722)
			(xy 177.750836 -20.289402) (xy 177.786035 -20.361795) (xy 177.814552 -20.437071) (xy 177.836153 -20.514616)
			(xy 177.850661 -20.593794) (xy 177.857958 -20.67396) (xy 177.85842 -20.714208) (xy 177.85842 -20.715224)
			(xy 177.857839 -20.760561) (xy 177.84856 -20.850758) (xy 177.830152 -20.939544) (xy 177.817018 -20.98294)
			(xy 177.81462 -20.991841) (xy 177.815621 -21.010233) (xy 177.823067 -21.02708) (xy 177.835994 -21.040201)
			(xy 177.844196 -21.044408) (xy 177.8824 -21.062505) (xy 177.955518 -21.104946) (xy 178.024281 -21.15413)
			(xy 178.088069 -21.209614) (xy 178.146306 -21.270898) (xy 178.198469 -21.337429) (xy 178.244087 -21.408608)
			(xy 178.282748 -21.483792) (xy 178.314103 -21.562305) (xy 178.337871 -21.643437) (xy 178.353837 -21.726458)
			(xy 178.361856 -21.810619) (xy 178.362356 -21.85289) (xy 178.361892 -21.894005) (xy 178.354306 -21.975884)
			(xy 178.339197 -22.056714) (xy 178.316694 -22.135805) (xy 178.28699 -22.212482) (xy 178.250337 -22.286091)
			(xy 178.207049 -22.356005) (xy 178.157495 -22.421626) (xy 178.102097 -22.482394) (xy 178.041329 -22.537792)
			(xy 177.975708 -22.587347) (xy 177.905795 -22.630635) (xy 177.832186 -22.667288) (xy 177.755509 -22.696993)
			(xy 177.676418 -22.719496) (xy 177.595588 -22.734605) (xy 177.513709 -22.742192) (xy 177.472594 -22.742652)
			(xy 177.429071 -22.742084) (xy 177.34244 -22.73358) (xy 177.257055 -22.716655) (xy 177.173731 -22.69147)
			(xy 177.093266 -22.658267) (xy 177.016429 -22.617362) (xy 176.943956 -22.569146) (xy 176.876538 -22.514083)
			(xy 176.814822 -22.452697) (xy 176.759398 -22.385575) (xy 176.710795 -22.313361) (xy 176.669479 -22.236745)
			(xy 176.652174 -22.196806) (xy 176.647921 -22.187866) (xy 176.633936 -22.17388) (xy 176.624996 -22.169628)
			(xy 176.585068 -22.152314) (xy 176.508472 -22.110985) (xy 176.436278 -22.062372) (xy 176.369178 -22.006941)
			(xy 176.307813 -21.945221) (xy 176.252769 -21.877802) (xy 176.204574 -21.80533) (xy 176.163687 -21.728496)
			(xy 176.1305 -21.648037) (xy 176.105331 -21.564721) (xy 176.088419 -21.479345) (xy 176.079928 -21.392725)
			(xy 176.079404 -21.349208) (xy 176.079404 -21.348446) (xy 176.079814 -21.310226) (xy 176.086378 -21.234067)
			(xy 176.099462 -21.158755) (xy 176.118968 -21.084845) (xy 176.131474 -21.048726) (xy 176.134055 -21.040409)
			(xy 176.134058 -21.023006) (xy 176.131474 -21.01469) (xy 176.118957 -20.978475) (xy 176.099434 -20.904375)
			(xy 176.086349 -20.828871) (xy 176.079799 -20.752523) (xy 176.079404 -20.714208) (xy 176.07999 -20.668344)
			(xy 176.089425 -20.577104) (xy 176.108186 -20.487316) (xy 176.121568 -20.443444) (xy 176.124428 -20.432883)
			(xy 176.121929 -20.411168) (xy 176.116742 -20.401534) (xy 176.096312 -20.366847) (xy 176.06107 -20.294464)
			(xy 176.032509 -20.219194) (xy 176.010862 -20.141652) (xy 175.996306 -20.062472) (xy 175.988959 -19.982301)
			(xy 175.988472 -19.942048) (xy 140.449617 -19.942048) (xy 140.472364 -19.977445) (xy 140.495002 -20.027018)
			(xy 140.510354 -20.079308) (xy 140.51811 -20.133251) (xy 140.51811 -20.187749) (xy 140.510354 -20.241692)
			(xy 140.495002 -20.293982) (xy 140.472364 -20.343555) (xy 140.442901 -20.389403) (xy 140.407215 -20.430591)
			(xy 140.36603 -20.466281) (xy 140.320185 -20.495747) (xy 140.270614 -20.51839) (xy 140.218325 -20.533747)
			(xy 140.164383 -20.541507) (xy 140.137134 -20.541996) (xy 139.146534 -20.541996) (xy 139.119279 -20.541559)
			(xy 139.065322 -20.533806) (xy 139.013019 -20.518453) (xy 138.963433 -20.495811) (xy 138.917574 -20.466343)
			(xy 138.876376 -20.430648) (xy 138.840677 -20.389453) (xy 138.811205 -20.343597) (xy 138.788559 -20.294013)
			(xy 138.773201 -20.241711) (xy 138.765443 -20.187755) (xy 67.653158 -20.187755) (xy 67.657521 -20.212789)
			(xy 67.664147 -20.289078) (xy 67.664584 -20.327366) (xy 67.66408 -20.369727) (xy 67.656027 -20.454064)
			(xy 67.639993 -20.537254) (xy 67.616125 -20.618544) (xy 67.584637 -20.697196) (xy 67.545815 -20.772499)
			(xy 67.500012 -20.843771) (xy 67.447641 -20.910367) (xy 67.389176 -20.971682) (xy 67.325148 -21.027163)
			(xy 67.256136 -21.076306) (xy 67.182766 -21.118666) (xy 67.105701 -21.153861) (xy 67.025639 -21.18157)
			(xy 66.943306 -21.201544) (xy 66.859447 -21.213601) (xy 66.774822 -21.217633) (xy 66.690197 -21.213601)
			(xy 66.606338 -21.201544) (xy 66.524005 -21.18157) (xy 66.443943 -21.153861) (xy 66.366878 -21.118666)
			(xy 66.293508 -21.076306) (xy 66.224496 -21.027163) (xy 66.160468 -20.971682) (xy 66.102003 -20.910367)
			(xy 66.049632 -20.843771) (xy 66.003829 -20.772499) (xy 65.965007 -20.697196) (xy 65.933519 -20.618544)
			(xy 65.909651 -20.537254) (xy 65.893617 -20.454064) (xy 65.885564 -20.369727) (xy 65.88506 -20.327366)
			(xy 0.509016 -20.327366) (xy 0.509016 -22.309271) (xy 65.993006 -22.309271) (xy 65.993006 -22.224549)
			(xy 66.001059 -22.140212) (xy 66.017093 -22.057022) (xy 66.040961 -21.975732) (xy 66.072449 -21.89708)
			(xy 66.111271 -21.821777) (xy 66.157074 -21.750505) (xy 66.209445 -21.683909) (xy 66.26791 -21.622594)
			(xy 66.331938 -21.567113) (xy 66.40095 -21.51797) (xy 66.47432 -21.47561) (xy 66.551385 -21.440415)
			(xy 66.631447 -21.412706) (xy 66.71378 -21.392732) (xy 66.797639 -21.380675) (xy 66.882264 -21.376644)
			(xy 66.966889 -21.380675) (xy 67.050748 -21.392732) (xy 67.133081 -21.412706) (xy 67.213143 -21.440415)
			(xy 67.290208 -21.47561) (xy 67.363578 -21.51797) (xy 67.43259 -21.567113) (xy 67.496618 -21.622594)
			(xy 67.555083 -21.683909) (xy 67.607454 -21.750505) (xy 67.653257 -21.821777) (xy 67.692079 -21.89708)
			(xy 67.723567 -21.975732) (xy 67.747435 -22.057022) (xy 67.763469 -22.140212) (xy 67.771522 -22.224549)
			(xy 67.772026 -22.26691) (xy 67.771522 -22.309271) (xy 67.763469 -22.393608) (xy 67.747435 -22.476798)
			(xy 67.723567 -22.558088) (xy 67.722853 -22.559872) (xy 114.452596 -22.559872) (xy 114.452596 -22.505328)
			(xy 114.460358 -22.45134) (xy 114.475725 -22.399006) (xy 114.498383 -22.349391) (xy 114.527872 -22.303506)
			(xy 114.563591 -22.262285) (xy 114.604813 -22.226567) (xy 114.650698 -22.19708) (xy 114.700313 -22.174422)
			(xy 114.752648 -22.159056) (xy 114.806636 -22.151295) (xy 114.833908 -22.150832) (xy 115.697508 -22.150832)
			(xy 115.724777 -22.151331) (xy 115.778758 -22.159093) (xy 115.831086 -22.174459) (xy 115.880695 -22.197116)
			(xy 115.926574 -22.226601) (xy 115.96779 -22.262316) (xy 116.003504 -22.303533) (xy 116.032988 -22.349412)
			(xy 116.055644 -22.399021) (xy 116.071008 -22.451349) (xy 116.07877 -22.505331) (xy 116.07877 -22.559869)
			(xy 116.071008 -22.613851) (xy 116.055644 -22.666179) (xy 116.032988 -22.715788) (xy 116.003504 -22.761667)
			(xy 115.96779 -22.802884) (xy 115.926574 -22.838599) (xy 115.880695 -22.868084) (xy 115.831086 -22.890741)
			(xy 115.778758 -22.906107) (xy 115.724777 -22.913869) (xy 115.697508 -22.914356) (xy 114.833908 -22.914356)
			(xy 114.806636 -22.913905) (xy 114.752648 -22.906144) (xy 114.700313 -22.890778) (xy 114.650698 -22.86812)
			(xy 114.604813 -22.838633) (xy 114.563591 -22.802915) (xy 114.527872 -22.761694) (xy 114.498383 -22.715809)
			(xy 114.475725 -22.666194) (xy 114.460358 -22.61386) (xy 114.452596 -22.559872) (xy 67.722853 -22.559872)
			(xy 67.692079 -22.63674) (xy 67.653257 -22.712043) (xy 67.607454 -22.783315) (xy 67.555083 -22.849911)
			(xy 67.496618 -22.911226) (xy 67.43259 -22.966707) (xy 67.363578 -23.01585) (xy 67.361784 -23.016886)
			(xy 136.323137 -23.016886) (xy 136.327046 -22.962479) (xy 136.338661 -22.909183) (xy 136.357746 -22.858084)
			(xy 136.383911 -22.810221) (xy 136.416623 -22.766572) (xy 136.435592 -22.74697) (xy 137.046208 -22.1361)
			(xy 137.06783 -22.115331) (xy 137.116345 -22.080114) (xy 137.169764 -22.052902) (xy 137.226775 -22.034363)
			(xy 137.285982 -22.024951) (xy 137.315956 -22.02434) (xy 137.31621 -22.02434) (xy 137.34348 -22.024815)
			(xy 137.397464 -22.032578) (xy 137.449794 -22.047945) (xy 137.499404 -22.070602) (xy 137.545285 -22.10009)
			(xy 137.586503 -22.135806) (xy 137.622218 -22.177025) (xy 137.651703 -22.222907) (xy 137.674359 -22.272518)
			(xy 137.689724 -22.324848) (xy 137.697486 -22.378832) (xy 137.697972 -22.406102) (xy 137.697972 -22.406356)
			(xy 137.6974 -22.436336) (xy 137.688023 -22.495559) (xy 137.669494 -22.552585) (xy 137.64227 -22.606009)
			(xy 137.60702 -22.654514) (xy 137.586212 -22.676104) (xy 136.975342 -23.28672) (xy 136.955728 -23.305677)
			(xy 136.912079 -23.338389) (xy 136.864216 -23.364554) (xy 136.813117 -23.383639) (xy 136.759821 -23.395254)
			(xy 136.705414 -23.399163) (xy 136.651005 -23.395286) (xy 136.597702 -23.383703) (xy 136.546591 -23.364649)
			(xy 136.498713 -23.338513) (xy 136.455044 -23.305826) (xy 136.416474 -23.267256) (xy 136.383787 -23.223587)
			(xy 136.357651 -23.175709) (xy 136.338597 -23.124598) (xy 136.327014 -23.071295) (xy 136.323137 -23.016886)
			(xy 67.361784 -23.016886) (xy 67.290208 -23.05821) (xy 67.213143 -23.093405) (xy 67.133081 -23.121114)
			(xy 67.050748 -23.141088) (xy 66.966889 -23.153145) (xy 66.882264 -23.157177) (xy 66.797639 -23.153145)
			(xy 66.71378 -23.141088) (xy 66.631447 -23.121114) (xy 66.551385 -23.093405) (xy 66.47432 -23.05821)
			(xy 66.40095 -23.01585) (xy 66.331938 -22.966707) (xy 66.26791 -22.911226) (xy 66.209445 -22.849911)
			(xy 66.157074 -22.783315) (xy 66.111271 -22.712043) (xy 66.072449 -22.63674) (xy 66.040961 -22.558088)
			(xy 66.017093 -22.476798) (xy 66.001059 -22.393608) (xy 65.993006 -22.309271) (xy 0.509016 -22.309271)
			(xy 0.509016 -23.593552) (xy 189.619128 -23.593552) (xy 189.619128 -23.593298) (xy 189.619711 -23.54856)
			(xy 189.628722 -23.459539) (xy 189.646623 -23.371871) (xy 189.673232 -23.286444) (xy 189.690248 -23.245064)
			(xy 189.69384 -23.235481) (xy 189.693822 -23.215031) (xy 189.690248 -23.20544) (xy 189.673222 -23.164064)
			(xy 189.646604 -23.078637) (xy 189.6287 -22.990968) (xy 189.619692 -22.901945) (xy 189.619128 -22.857206)
			(xy 189.619128 -22.856952) (xy 189.619632 -22.814604) (xy 189.627683 -22.73029) (xy 189.643712 -22.647124)
			(xy 189.667573 -22.565857) (xy 189.699052 -22.487227) (xy 189.737863 -22.411946) (xy 189.783653 -22.340694)
			(xy 189.836009 -22.274118) (xy 189.894457 -22.21282) (xy 189.958467 -22.157355) (xy 190.027459 -22.108226)
			(xy 190.100809 -22.065877) (xy 190.177852 -22.030693) (xy 190.257891 -22.002991) (xy 190.3402 -21.983023)
			(xy 190.424035 -21.97097) (xy 190.508636 -21.96694) (xy 190.593237 -21.97097) (xy 190.677072 -21.983023)
			(xy 190.759381 -22.002991) (xy 190.83942 -22.030693) (xy 190.916463 -22.065877) (xy 190.989813 -22.108226)
			(xy 191.058805 -22.157355) (xy 191.122815 -22.21282) (xy 191.181263 -22.274118) (xy 191.233619 -22.340694)
			(xy 191.279409 -22.411946) (xy 191.31822 -22.487227) (xy 191.349699 -22.565857) (xy 191.37356 -22.647124)
			(xy 191.389589 -22.73029) (xy 191.39764 -22.814604) (xy 191.398144 -22.856952) (xy 191.398144 -22.857206)
			(xy 191.397557 -22.901944) (xy 191.388547 -22.990965) (xy 191.370647 -23.078632) (xy 191.344039 -23.16406)
			(xy 191.327024 -23.20544) (xy 191.323489 -23.215039) (xy 191.323471 -23.235473) (xy 191.327024 -23.245064)
			(xy 191.344055 -23.286438) (xy 191.370671 -23.371866) (xy 191.388573 -23.459535) (xy 191.39758 -23.548559)
			(xy 191.398144 -23.593298) (xy 191.398144 -23.593552) (xy 191.39764 -23.6359) (xy 191.389589 -23.720214)
			(xy 191.37356 -23.80338) (xy 191.349699 -23.884647) (xy 191.31822 -23.963277) (xy 191.279409 -24.038558)
			(xy 191.233619 -24.10981) (xy 191.181263 -24.176386) (xy 191.122815 -24.237684) (xy 191.058805 -24.293149)
			(xy 190.989813 -24.342278) (xy 190.916463 -24.384627) (xy 190.83942 -24.419811) (xy 190.759381 -24.447513)
			(xy 190.677072 -24.467481) (xy 190.593237 -24.479534) (xy 190.508636 -24.483565) (xy 190.424035 -24.479534)
			(xy 190.3402 -24.467481) (xy 190.257891 -24.447513) (xy 190.177852 -24.419811) (xy 190.100809 -24.384627)
			(xy 190.027459 -24.342278) (xy 189.958467 -24.293149) (xy 189.894457 -24.237684) (xy 189.836009 -24.176386)
			(xy 189.783653 -24.10981) (xy 189.737863 -24.038558) (xy 189.699052 -23.963277) (xy 189.667573 -23.884647)
			(xy 189.643712 -23.80338) (xy 189.627683 -23.720214) (xy 189.619632 -23.6359) (xy 189.619128 -23.593552)
			(xy 0.509016 -23.593552) (xy 0.509016 -25.56891) (xy 65.510156 -25.56891) (xy 65.510621 -25.527206)
			(xy 65.518403 -25.444163) (xy 65.533928 -25.362214) (xy 65.557059 -25.282079) (xy 65.587593 -25.204462)
			(xy 65.625262 -25.130046) (xy 65.669734 -25.059485) (xy 65.720619 -24.993398) (xy 65.777469 -24.932368)
			(xy 65.839786 -24.876929) (xy 65.873122 -24.851868) (xy 65.88167 -24.844931) (xy 65.892346 -24.825708)
			(xy 65.893696 -24.814784) (xy 65.897332 -24.773398) (xy 65.911399 -24.69151) (xy 65.933041 -24.611291)
			(xy 65.962067 -24.53344) (xy 65.998226 -24.458634) (xy 66.041203 -24.387525) (xy 66.090622 -24.320733)
			(xy 66.146054 -24.25884) (xy 66.207015 -24.202385) (xy 66.272974 -24.15186) (xy 66.343357 -24.107705)
			(xy 66.41755 -24.070304) (xy 66.494907 -24.039985) (xy 66.574755 -24.01701) (xy 66.656396 -24.00158)
			(xy 66.739121 -23.99383) (xy 66.780664 -23.993348) (xy 66.824459 -23.993873) (xy 66.911625 -24.002491)
			(xy 66.997521 -24.019637) (xy 67.081315 -24.045145) (xy 67.162195 -24.078768) (xy 67.201034 -24.099012)
			(xy 67.2125 -24.10443) (xy 67.237828 -24.10443) (xy 67.249294 -24.099012) (xy 67.288138 -24.078781)
			(xy 67.369023 -24.045174) (xy 67.452816 -24.019672) (xy 67.538709 -24.002521) (xy 67.62587 -23.993888)
			(xy 67.669664 -23.993348) (xy 67.713459 -23.993873) (xy 67.800625 -24.002491) (xy 67.886521 -24.019637)
			(xy 67.970315 -24.045145) (xy 68.051195 -24.078768) (xy 68.090034 -24.099012) (xy 68.1015 -24.10443)
			(xy 68.126828 -24.10443) (xy 68.138294 -24.099012) (xy 68.177138 -24.078781) (xy 68.258023 -24.045174)
			(xy 68.341816 -24.019672) (xy 68.427709 -24.002521) (xy 68.51487 -23.993888) (xy 68.558664 -23.993348)
			(xy 68.607651 -23.994055) (xy 68.705028 -24.00487) (xy 68.752974 -24.014938) (xy 68.762324 -24.016604)
			(xy 68.781086 -24.013776) (xy 68.797533 -24.004314) (xy 68.803774 -23.997158) (xy 68.831851 -23.962886)
			(xy 68.893786 -23.899527) (xy 68.961714 -23.842641) (xy 69.034963 -23.792791) (xy 69.112805 -23.750472)
			(xy 69.19447 -23.716104) (xy 69.279148 -23.690027) (xy 69.365999 -23.672499) (xy 69.454163 -23.663695)
			(xy 69.498464 -23.663148) (xy 69.540827 -23.663615) (xy 69.625169 -23.671665) (xy 69.708365 -23.687697)
			(xy 69.789659 -23.711564) (xy 69.868317 -23.743051) (xy 69.943625 -23.781873) (xy 70.014902 -23.827677)
			(xy 70.081502 -23.880049) (xy 70.142823 -23.938516) (xy 70.198307 -24.002546) (xy 70.247454 -24.071561)
			(xy 70.250564 -24.076947) (xy 112.652614 -24.076947) (xy 112.652614 -24.022453) (xy 112.660369 -23.968515)
			(xy 112.67572 -23.916228) (xy 112.698356 -23.866659) (xy 112.727815 -23.820815) (xy 112.763499 -23.77963)
			(xy 112.80468 -23.743942) (xy 112.85052 -23.714477) (xy 112.900087 -23.691836) (xy 112.952372 -23.676478)
			(xy 113.006309 -23.668717) (xy 113.033556 -23.668228) (xy 113.897156 -23.668228) (xy 113.924413 -23.668616)
			(xy 113.978374 -23.676369) (xy 114.030682 -23.691722) (xy 114.080273 -23.714364) (xy 114.126136 -23.743834)
			(xy 114.167338 -23.779531) (xy 114.20304 -23.820729) (xy 114.232514 -23.866588) (xy 114.255162 -23.916176)
			(xy 114.270522 -23.968483) (xy 114.278281 -24.022443) (xy 114.278281 -24.076957) (xy 114.270522 -24.130917)
			(xy 114.255235 -24.182975) (xy 116.218856 -24.182975) (xy 116.218856 -24.128425) (xy 116.226619 -24.074429)
			(xy 116.241989 -24.022088) (xy 116.264651 -23.972468) (xy 116.294144 -23.926577) (xy 116.329868 -23.885352)
			(xy 116.371096 -23.84963) (xy 116.416989 -23.820139) (xy 116.466611 -23.79748) (xy 116.518953 -23.782114)
			(xy 116.572949 -23.774354) (xy 116.600224 -23.773892) (xy 117.463824 -23.773892) (xy 117.491089 -23.774472)
			(xy 117.545063 -23.782235) (xy 117.597384 -23.797601) (xy 117.646985 -23.820256) (xy 117.692857 -23.849739)
			(xy 117.734067 -23.88545) (xy 117.769776 -23.926662) (xy 117.799256 -23.972536) (xy 117.821907 -24.022139)
			(xy 117.83727 -24.07446) (xy 117.84503 -24.128435) (xy 117.84503 -24.182965) (xy 117.83727 -24.23694)
			(xy 117.821907 -24.289261) (xy 117.799256 -24.338864) (xy 117.769776 -24.384738) (xy 117.734067 -24.42595)
			(xy 117.692857 -24.461661) (xy 117.646985 -24.491144) (xy 117.597384 -24.513799) (xy 117.545063 -24.529165)
			(xy 117.491089 -24.536928) (xy 117.463824 -24.537416) (xy 116.600224 -24.537416) (xy 116.572949 -24.537046)
			(xy 116.518953 -24.529286) (xy 116.466611 -24.51392) (xy 116.416989 -24.491261) (xy 116.371096 -24.46177)
			(xy 116.329868 -24.426049) (xy 116.294144 -24.384823) (xy 116.264651 -24.338932) (xy 116.241989 -24.289312)
			(xy 116.226619 -24.236971) (xy 116.218856 -24.182975) (xy 114.255235 -24.182975) (xy 114.255162 -24.183224)
			(xy 114.232514 -24.232812) (xy 114.20304 -24.278671) (xy 114.167338 -24.319869) (xy 114.126136 -24.355566)
			(xy 114.080273 -24.385036) (xy 114.030682 -24.407678) (xy 113.978374 -24.423031) (xy 113.924414 -24.430784)
			(xy 113.897156 -24.431244) (xy 113.033556 -24.431244) (xy 113.006309 -24.430683) (xy 112.952372 -24.422922)
			(xy 112.900087 -24.407564) (xy 112.85052 -24.384923) (xy 112.80468 -24.355458) (xy 112.763499 -24.31977)
			(xy 112.727815 -24.278585) (xy 112.698356 -24.232741) (xy 112.67572 -24.183172) (xy 112.660369 -24.130885)
			(xy 112.652614 -24.076947) (xy 70.250564 -24.076947) (xy 70.289818 -24.144935) (xy 70.325015 -24.222004)
			(xy 70.352727 -24.302069) (xy 70.372702 -24.384407) (xy 70.38476 -24.46827) (xy 70.388792 -24.5529)
			(xy 70.38476 -24.63753) (xy 70.37544 -24.702351) (xy 130.235962 -24.702351) (xy 130.235962 -24.647849)
			(xy 130.243717 -24.593903) (xy 130.259071 -24.541609) (xy 130.28171 -24.492033) (xy 130.311174 -24.446182)
			(xy 130.346863 -24.404991) (xy 130.38805 -24.369298) (xy 130.433897 -24.33983) (xy 130.483472 -24.317185)
			(xy 130.535764 -24.301826) (xy 130.589709 -24.294065) (xy 130.61696 -24.293576) (xy 131.48056 -24.293576)
			(xy 131.507814 -24.294069) (xy 131.561767 -24.301821) (xy 131.614067 -24.317173) (xy 131.66365 -24.339812)
			(xy 131.709506 -24.369277) (xy 131.750702 -24.40497) (xy 131.786399 -24.446162) (xy 131.815869 -24.492015)
			(xy 131.838513 -24.541595) (xy 131.853871 -24.593894) (xy 131.861629 -24.647846) (xy 131.861629 -24.702354)
			(xy 131.853871 -24.756306) (xy 131.838513 -24.808605) (xy 131.815869 -24.858185) (xy 131.786399 -24.904038)
			(xy 131.750702 -24.94523) (xy 131.709506 -24.980923) (xy 131.66365 -25.010388) (xy 131.614067 -25.033027)
			(xy 131.561767 -25.048379) (xy 131.507814 -25.056131) (xy 131.48056 -25.056592) (xy 130.61696 -25.056592)
			(xy 130.589709 -25.056135) (xy 130.535764 -25.048374) (xy 130.483472 -25.033015) (xy 130.433897 -25.01037)
			(xy 130.38805 -24.980902) (xy 130.346863 -24.945209) (xy 130.311174 -24.904018) (xy 130.28171 -24.858167)
			(xy 130.259071 -24.808591) (xy 130.243717 -24.756297) (xy 130.235962 -24.702351) (xy 70.37544 -24.702351)
			(xy 70.372702 -24.721393) (xy 70.352727 -24.803731) (xy 70.325015 -24.883796) (xy 70.289818 -24.960865)
			(xy 70.247454 -25.034239) (xy 70.198307 -25.103254) (xy 70.142823 -25.167284) (xy 70.081502 -25.225751)
			(xy 70.014902 -25.278123) (xy 69.943625 -25.323927) (xy 69.868317 -25.362749) (xy 69.789659 -25.394236)
			(xy 69.708365 -25.418103) (xy 69.625169 -25.434135) (xy 69.540827 -25.442185) (xy 69.498464 -25.442672)
			(xy 69.449476 -25.441976) (xy 69.3521 -25.431154) (xy 69.304154 -25.421082) (xy 69.294812 -25.41935)
			(xy 69.276039 -25.422204) (xy 69.259591 -25.431693) (xy 69.253354 -25.438862) (xy 69.228687 -25.46901)
			(xy 69.174875 -25.52534) (xy 69.116354 -25.57676) (xy 69.085206 -25.600152) (xy 69.076637 -25.607067)
			(xy 69.065975 -25.626306) (xy 69.065849 -25.62733) (xy 133.339332 -25.62733) (xy 133.339332 -24.76373)
			(xy 133.339818 -24.736479) (xy 133.347574 -24.682531) (xy 133.362929 -24.630236) (xy 133.385571 -24.580659)
			(xy 133.415037 -24.534809) (xy 133.450728 -24.493618) (xy 133.491919 -24.457927) (xy 133.537769 -24.428461)
			(xy 133.587346 -24.405819) (xy 133.639641 -24.390464) (xy 133.693589 -24.382708) (xy 133.748091 -24.382708)
			(xy 133.802039 -24.390464) (xy 133.854334 -24.405819) (xy 133.903911 -24.428461) (xy 133.949761 -24.457927)
			(xy 133.990952 -24.493618) (xy 134.026643 -24.534809) (xy 134.056109 -24.580659) (xy 134.078751 -24.630236)
			(xy 134.094106 -24.682531) (xy 134.101862 -24.736479) (xy 134.102348 -24.76373) (xy 134.102348 -25.62733)
			(xy 134.101862 -25.654581) (xy 134.094106 -25.708529) (xy 134.078751 -25.760824) (xy 134.056109 -25.810401)
			(xy 134.026643 -25.856251) (xy 133.990952 -25.897442) (xy 133.949761 -25.933133) (xy 133.903911 -25.962599)
			(xy 133.854334 -25.985241) (xy 133.802039 -26.000596) (xy 133.748091 -26.008352) (xy 133.693589 -26.008352)
			(xy 133.639641 -26.000596) (xy 133.587346 -25.985241) (xy 133.537769 -25.962599) (xy 133.491919 -25.933133)
			(xy 133.450728 -25.897442) (xy 133.415037 -25.856251) (xy 133.385571 -25.810401) (xy 133.362929 -25.760824)
			(xy 133.347574 -25.708529) (xy 133.339818 -25.654581) (xy 133.339332 -25.62733) (xy 69.065849 -25.62733)
			(xy 69.064632 -25.637236) (xy 69.060986 -25.678621) (xy 69.046917 -25.760507) (xy 69.025275 -25.840725)
			(xy 68.996248 -25.918575) (xy 68.960089 -25.99338) (xy 68.917113 -26.064488) (xy 68.867694 -26.131279)
			(xy 68.812263 -26.193171) (xy 68.751303 -26.249626) (xy 68.685345 -26.300151) (xy 68.614964 -26.344307)
			(xy 68.540772 -26.381708) (xy 68.463416 -26.412028) (xy 68.38357 -26.435004) (xy 68.30193 -26.450436)
			(xy 68.219207 -26.458189) (xy 68.177664 -26.458672) (xy 68.133869 -26.458133) (xy 68.046704 -26.449518)
			(xy 67.960808 -26.432375) (xy 67.877014 -26.40687) (xy 67.796134 -26.37325) (xy 67.757294 -26.353008)
			(xy 67.745828 -26.34759) (xy 67.7205 -26.34759) (xy 67.709034 -26.353008) (xy 67.670181 -26.373222)
			(xy 67.589299 -26.406833) (xy 67.505508 -26.43234) (xy 67.419618 -26.449494) (xy 67.332457 -26.458131)
			(xy 67.288664 -26.458672) (xy 67.244869 -26.458133) (xy 67.157704 -26.449518) (xy 67.071808 -26.432375)
			(xy 66.988014 -26.40687) (xy 66.907134 -26.37325) (xy 66.868294 -26.353008) (xy 66.856828 -26.34759)
			(xy 66.8315 -26.34759) (xy 66.820034 -26.353008) (xy 66.781181 -26.373222) (xy 66.700299 -26.406833)
			(xy 66.616508 -26.43234) (xy 66.530618 -26.449494) (xy 66.443457 -26.458131) (xy 66.399664 -26.458672)
			(xy 66.358552 -26.458282) (xy 66.276678 -26.45069) (xy 66.195855 -26.435576) (xy 66.116771 -26.413067)
			(xy 66.040102 -26.383356) (xy 65.966502 -26.346696) (xy 65.8966 -26.3034) (xy 65.830991 -26.253838)
			(xy 65.770236 -26.198433) (xy 65.714853 -26.137658) (xy 65.665316 -26.072031) (xy 65.622046 -26.002113)
			(xy 65.585413 -25.928499) (xy 65.55573 -25.85182) (xy 65.53325 -25.772728) (xy 65.518165 -25.691899)
			(xy 65.510603 -25.610022) (xy 65.510156 -25.56891) (xy 0.509016 -25.56891) (xy 0.509016 -29.026161)
			(xy 11.140205 -29.026161) (xy 11.147539 -28.866724) (xy 11.162812 -28.70785) (xy 11.185984 -28.549934)
			(xy 11.216999 -28.39337) (xy 11.255779 -28.238547) (xy 11.302228 -28.085849) (xy 11.35623 -27.935656)
			(xy 11.417652 -27.788341) (xy 11.48634 -27.644271) (xy 11.562123 -27.503804) (xy 11.644814 -27.367289)
			(xy 11.734207 -27.235065) (xy 11.830079 -27.107461) (xy 11.932193 -26.984794) (xy 12.040293 -26.86737)
			(xy 12.154112 -26.75548) (xy 12.273367 -26.649402) (xy 12.397761 -26.5494) (xy 12.526985 -26.455723)
			(xy 12.660717 -26.368604) (xy 12.798626 -26.288258) (xy 12.940368 -26.214886) (xy 13.085591 -26.148671)
			(xy 13.233934 -26.089776) (xy 13.385028 -26.038349) (xy 13.538498 -25.994517) (xy 13.693962 -25.958388)
			(xy 13.851033 -25.930054) (xy 14.009321 -25.909584) (xy 14.168433 -25.897029) (xy 14.327973 -25.892421)
			(xy 14.487544 -25.895771) (xy 14.64675 -25.90707) (xy 14.805195 -25.92629) (xy 14.962485 -25.953385)
			(xy 15.118229 -25.988285) (xy 15.272039 -26.030905) (xy 15.423535 -26.081139) (xy 15.572338 -26.138862)
			(xy 15.718078 -26.203929) (xy 15.860395 -26.27618) (xy 15.998933 -26.355436) (xy 16.133349 -26.441497)
			(xy 16.263308 -26.534152) (xy 16.388487 -26.633169) (xy 16.508575 -26.738303) (xy 16.623273 -26.849292)
			(xy 16.678148 -26.907236) (xy 17.470427 -27.75458) (xy 130.687572 -27.75458) (xy 130.687572 -26.76398)
			(xy 130.688058 -26.736729) (xy 130.695814 -26.682781) (xy 130.711169 -26.630486) (xy 130.733811 -26.580909)
			(xy 130.763277 -26.535059) (xy 130.798968 -26.493868) (xy 130.840159 -26.458177) (xy 130.886009 -26.428711)
			(xy 130.935586 -26.406069) (xy 130.987881 -26.390714) (xy 131.041829 -26.382958) (xy 131.096331 -26.382958)
			(xy 131.150279 -26.390714) (xy 131.202574 -26.406069) (xy 131.252151 -26.428711) (xy 131.298001 -26.458177)
			(xy 131.339192 -26.493868) (xy 131.374883 -26.535059) (xy 131.404349 -26.580909) (xy 131.426991 -26.630486)
			(xy 131.442346 -26.682781) (xy 131.450102 -26.736729) (xy 131.450588 -26.76398) (xy 131.450588 -26.76779)
			(xy 141.621764 -26.76779) (xy 141.621764 -25.90419) (xy 141.62225 -25.876921) (xy 141.630012 -25.822937)
			(xy 141.645377 -25.770607) (xy 141.668034 -25.720997) (xy 141.69752 -25.675116) (xy 141.733235 -25.633899)
			(xy 141.774452 -25.598184) (xy 141.820333 -25.568698) (xy 141.869943 -25.546041) (xy 141.922273 -25.530676)
			(xy 141.976257 -25.522914) (xy 142.030795 -25.522914) (xy 142.084779 -25.530676) (xy 142.137109 -25.546041)
			(xy 142.186719 -25.568698) (xy 142.2326 -25.598184) (xy 142.273817 -25.633899) (xy 142.309532 -25.675116)
			(xy 142.339018 -25.720997) (xy 142.361675 -25.770607) (xy 142.37704 -25.822937) (xy 142.384802 -25.876921)
			(xy 142.385288 -25.90419) (xy 142.385288 -26.634948) (xy 175.442372 -26.634948) (xy 175.442817 -26.593237)
			(xy 175.450618 -26.510181) (xy 175.466165 -26.428221) (xy 175.489321 -26.348077) (xy 175.519883 -26.270455)
			(xy 175.557582 -26.196038) (xy 175.602086 -26.125479) (xy 175.653004 -26.059399) (xy 175.709888 -25.99838)
			(xy 175.772239 -25.942957) (xy 175.805592 -25.917906) (xy 175.814178 -25.911009) (xy 175.82483 -25.891756)
			(xy 175.826166 -25.880822) (xy 175.829855 -25.839448) (xy 175.843941 -25.757582) (xy 175.865598 -25.677385)
			(xy 175.894637 -25.599556) (xy 175.930804 -25.524774) (xy 175.973785 -25.453688) (xy 176.023205 -25.386918)
			(xy 176.078634 -25.325046) (xy 176.13959 -25.268611) (xy 176.205541 -25.218103) (xy 176.275913 -25.173964)
			(xy 176.350094 -25.136576) (xy 176.427436 -25.106267) (xy 176.507267 -25.083299) (xy 176.588892 -25.067873)
			(xy 176.671599 -25.060123) (xy 176.713134 -25.05964) (xy 176.713642 -25.05964) (xy 176.757406 -25.060139)
			(xy 176.844513 -25.068717) (xy 176.930355 -25.085818) (xy 177.0141 -25.111273) (xy 177.094937 -25.144838)
			(xy 177.133758 -25.16505) (xy 177.145111 -25.170377) (xy 177.170157 -25.170377) (xy 177.18151 -25.16505)
			(xy 177.22038 -25.144826) (xy 177.301322 -25.111257) (xy 177.38517 -25.085803) (xy 177.471113 -25.068709)
			(xy 177.55832 -25.060143) (xy 177.602134 -25.05964) (xy 177.645949 -25.060116) (xy 177.733161 -25.068665)
			(xy 177.819109 -25.085756) (xy 177.902957 -25.111222) (xy 177.983891 -25.144816) (xy 178.022758 -25.16505)
			(xy 178.034111 -25.170377) (xy 178.059157 -25.170377) (xy 178.07051 -25.16505) (xy 178.10938 -25.144826)
			(xy 178.190322 -25.111257) (xy 178.27417 -25.085803) (xy 178.360113 -25.068709) (xy 178.44732 -25.060143)
			(xy 178.491134 -25.05964) (xy 178.541288 -25.060291) (xy 178.640969 -25.071493) (xy 178.690016 -25.081992)
			(xy 178.700529 -25.083816) (xy 178.72144 -25.079687) (xy 178.7389 -25.067462) (xy 178.74488 -25.058624)
			(xy 178.766746 -25.023211) (xy 178.816155 -24.956227) (xy 178.871604 -24.894151) (xy 178.932608 -24.837525)
			(xy 178.998633 -24.786843) (xy 179.069104 -24.742549) (xy 179.143403 -24.705031) (xy 179.220882 -24.674615)
			(xy 179.300862 -24.651569) (xy 179.382645 -24.636093) (xy 179.465517 -24.628322) (xy 179.507134 -24.62784)
			(xy 179.549484 -24.628249) (xy 179.633799 -24.636303) (xy 179.716968 -24.652336) (xy 179.798236 -24.676201)
			(xy 179.876867 -24.707683) (xy 179.95215 -24.746496) (xy 180.023403 -24.79229) (xy 180.08998 -24.844649)
			(xy 180.151278 -24.9031) (xy 180.206744 -24.967112) (xy 180.255873 -25.036107) (xy 180.298222 -25.10946)
			(xy 180.333407 -25.186506) (xy 180.361109 -25.266547) (xy 180.381077 -25.348859) (xy 180.39313 -25.432696)
			(xy 180.397161 -25.5173) (xy 180.39313 -25.601904) (xy 180.381077 -25.685741) (xy 180.361109 -25.768053)
			(xy 180.333407 -25.848094) (xy 180.298222 -25.92514) (xy 180.255873 -25.998493) (xy 180.206744 -26.067488)
			(xy 180.151278 -26.1315) (xy 180.08998 -26.189951) (xy 180.023403 -26.24231) (xy 179.95215 -26.288104)
			(xy 179.876867 -26.326917) (xy 179.798236 -26.358399) (xy 179.716968 -26.382264) (xy 179.633799 -26.398297)
			(xy 179.549484 -26.406351) (xy 179.507134 -26.406856) (xy 179.505864 -26.406856) (xy 179.456029 -26.406131)
			(xy 179.35699 -26.394927) (xy 179.308252 -26.384504) (xy 179.297742 -26.382653) (xy 179.276827 -26.386794)
			(xy 179.259367 -26.39903) (xy 179.253388 -26.407872) (xy 179.230217 -26.445289) (xy 179.177598 -26.515842)
			(xy 179.118275 -26.58086) (xy 179.052827 -26.639708) (xy 179.017676 -26.66619) (xy 179.009104 -26.673102)
			(xy 178.998441 -26.692343) (xy 178.997102 -26.703274) (xy 178.993441 -26.744651) (xy 178.979354 -26.826519)
			(xy 178.957697 -26.906717) (xy 178.928657 -26.984547) (xy 178.892489 -27.059331) (xy 178.849506 -27.130418)
			(xy 178.835198 -27.149749) (xy 180.032656 -27.149749) (xy 180.032656 -27.065027) (xy 180.040709 -26.98069)
			(xy 180.056743 -26.8975) (xy 180.080611 -26.81621) (xy 180.112099 -26.737558) (xy 180.150921 -26.662255)
			(xy 180.196724 -26.590983) (xy 180.249095 -26.524387) (xy 180.30756 -26.463072) (xy 180.371588 -26.407591)
			(xy 180.4406 -26.358448) (xy 180.51397 -26.316088) (xy 180.591035 -26.280893) (xy 180.671097 -26.253184)
			(xy 180.75343 -26.23321) (xy 180.837289 -26.221153) (xy 180.921914 -26.217122) (xy 181.006539 -26.221153)
			(xy 181.090398 -26.23321) (xy 181.172731 -26.253184) (xy 181.252793 -26.280893) (xy 181.329858 -26.316088)
			(xy 181.403228 -26.358448) (xy 181.47224 -26.407591) (xy 181.536268 -26.463072) (xy 181.594733 -26.524387)
			(xy 181.647104 -26.590983) (xy 181.692907 -26.662255) (xy 181.731729 -26.737558) (xy 181.763217 -26.81621)
			(xy 181.787085 -26.8975) (xy 181.803119 -26.98069) (xy 181.811172 -27.065027) (xy 181.811676 -27.107388)
			(xy 181.811172 -27.149749) (xy 181.803119 -27.234086) (xy 181.787085 -27.317276) (xy 181.763217 -27.398566)
			(xy 181.731729 -27.477218) (xy 181.692907 -27.552521) (xy 181.647104 -27.623793) (xy 181.594733 -27.690389)
			(xy 181.536268 -27.751704) (xy 181.47224 -27.807185) (xy 181.403228 -27.856328) (xy 181.329858 -27.898688)
			(xy 181.252793 -27.933883) (xy 181.172731 -27.961592) (xy 181.090398 -27.981566) (xy 181.006539 -27.993623)
			(xy 180.921914 -27.997655) (xy 180.837289 -27.993623) (xy 180.75343 -27.981566) (xy 180.671097 -27.961592)
			(xy 180.591035 -27.933883) (xy 180.51397 -27.898688) (xy 180.4406 -27.856328) (xy 180.371588 -27.807185)
			(xy 180.30756 -27.751704) (xy 180.249095 -27.690389) (xy 180.196724 -27.623793) (xy 180.150921 -27.552521)
			(xy 180.112099 -27.477218) (xy 180.080611 -27.398566) (xy 180.056743 -27.317276) (xy 180.040709 -27.234086)
			(xy 180.032656 -27.149749) (xy 178.835198 -27.149749) (xy 178.800084 -27.197189) (xy 178.744653 -27.259061)
			(xy 178.683695 -27.315497) (xy 178.617742 -27.366004) (xy 178.547367 -27.410143) (xy 178.473184 -27.447529)
			(xy 178.395839 -27.477837) (xy 178.316006 -27.500803) (xy 178.234379 -27.516227) (xy 178.15167 -27.523974)
			(xy 178.110134 -27.524456) (xy 178.109626 -27.524456) (xy 178.065862 -27.523929) (xy 177.978756 -27.515357)
			(xy 177.892915 -27.498263) (xy 177.809169 -27.472814) (xy 177.728331 -27.439255) (xy 177.68951 -27.419046)
			(xy 177.678157 -27.413719) (xy 177.653111 -27.413719) (xy 177.641758 -27.419046) (xy 177.602894 -27.439282)
			(xy 177.521951 -27.472849) (xy 177.438101 -27.498301) (xy 177.352156 -27.515391) (xy 177.264948 -27.523955)
			(xy 177.221134 -27.524456) (xy 177.177318 -27.523994) (xy 177.090106 -27.515442) (xy 177.004158 -27.498348)
			(xy 176.920311 -27.472879) (xy 176.839376 -27.439281) (xy 176.80051 -27.419046) (xy 176.789157 -27.413719)
			(xy 176.764111 -27.413719) (xy 176.752758 -27.419046) (xy 176.713921 -27.439222) (xy 176.633081 -27.472767)
			(xy 176.549339 -27.498216) (xy 176.463504 -27.515325) (xy 176.376404 -27.523927) (xy 176.332642 -27.524456)
			(xy 176.332134 -27.524456) (xy 176.291028 -27.523955) (xy 176.209165 -27.516374) (xy 176.128351 -27.501273)
			(xy 176.049275 -27.47878) (xy 175.972611 -27.449089) (xy 175.899013 -27.412452) (xy 175.829109 -27.369181)
			(xy 175.763495 -27.319646) (xy 175.702731 -27.264268) (xy 175.647335 -27.203522) (xy 175.597779 -27.137923)
			(xy 175.554486 -27.068033) (xy 175.517825 -26.994447) (xy 175.488109 -26.917792) (xy 175.465592 -26.838723)
			(xy 175.450465 -26.757914) (xy 175.442858 -26.676054) (xy 175.442372 -26.634948) (xy 142.385288 -26.634948)
			(xy 142.385288 -26.76779) (xy 142.384802 -26.795059) (xy 142.37704 -26.849043) (xy 142.361675 -26.901373)
			(xy 142.339018 -26.950983) (xy 142.309532 -26.996864) (xy 142.273817 -27.038081) (xy 142.2326 -27.073796)
			(xy 142.186719 -27.103282) (xy 142.137109 -27.125939) (xy 142.084779 -27.141304) (xy 142.030795 -27.149066)
			(xy 141.976257 -27.149066) (xy 141.922273 -27.141304) (xy 141.869943 -27.125939) (xy 141.820333 -27.103282)
			(xy 141.774452 -27.073796) (xy 141.733235 -27.038081) (xy 141.69752 -26.996864) (xy 141.668034 -26.950983)
			(xy 141.645377 -26.901373) (xy 141.630012 -26.849043) (xy 141.62225 -26.795059) (xy 141.621764 -26.76779)
			(xy 131.450588 -26.76779) (xy 131.450588 -27.75458) (xy 131.450102 -27.781831) (xy 131.442346 -27.835779)
			(xy 131.426991 -27.888074) (xy 131.404349 -27.937651) (xy 131.374883 -27.983501) (xy 131.339192 -28.024692)
			(xy 131.298001 -28.060383) (xy 131.252151 -28.089849) (xy 131.202574 -28.112491) (xy 131.150279 -28.127846)
			(xy 131.096331 -28.135602) (xy 131.041829 -28.135602) (xy 130.987881 -28.127846) (xy 130.935586 -28.112491)
			(xy 130.886009 -28.089849) (xy 130.840159 -28.060383) (xy 130.798968 -28.024692) (xy 130.763277 -27.983501)
			(xy 130.733811 -27.937651) (xy 130.711169 -27.888074) (xy 130.695814 -27.835779) (xy 130.688058 -27.781831)
			(xy 130.687572 -27.75458) (xy 17.470427 -27.75458) (xy 17.770856 -28.07589) (xy 17.824996 -28.134528)
			(xy 17.928078 -28.256394) (xy 18.024957 -28.383247) (xy 18.115392 -28.514772) (xy 18.199158 -28.650641)
			(xy 18.276047 -28.790516) (xy 18.345869 -28.934051) (xy 18.408448 -29.080887) (xy 18.463631 -29.230661)
			(xy 18.511279 -29.382999) (xy 18.546379 -29.51861) (xy 101.326696 -29.51861) (xy 101.326696 -28.65501)
			(xy 101.327182 -28.627759) (xy 101.334938 -28.573811) (xy 101.350293 -28.521516) (xy 101.372935 -28.471939)
			(xy 101.402401 -28.426089) (xy 101.438092 -28.384898) (xy 101.479283 -28.349207) (xy 101.525133 -28.319741)
			(xy 101.57471 -28.297099) (xy 101.627005 -28.281744) (xy 101.680953 -28.273988) (xy 101.735455 -28.273988)
			(xy 101.789403 -28.281744) (xy 101.841698 -28.297099) (xy 101.891275 -28.319741) (xy 101.937125 -28.349207)
			(xy 101.978316 -28.384898) (xy 102.014007 -28.426089) (xy 102.043473 -28.471939) (xy 102.066115 -28.521516)
			(xy 102.08147 -28.573811) (xy 102.089226 -28.627759) (xy 102.089712 -28.65501) (xy 102.089712 -29.24302)
			(xy 135.551672 -29.24302) (xy 135.551672 -28.25242) (xy 135.552158 -28.225169) (xy 135.559914 -28.171221)
			(xy 135.575269 -28.118926) (xy 135.597911 -28.069349) (xy 135.627377 -28.023499) (xy 135.663068 -27.982308)
			(xy 135.704259 -27.946617) (xy 135.750109 -27.917151) (xy 135.799686 -27.894509) (xy 135.851981 -27.879154)
			(xy 135.905929 -27.871398) (xy 135.960431 -27.871398) (xy 136.014379 -27.879154) (xy 136.066674 -27.894509)
			(xy 136.116251 -27.917151) (xy 136.162101 -27.946617) (xy 136.203292 -27.982308) (xy 136.238983 -28.023499)
			(xy 136.268449 -28.069349) (xy 136.291091 -28.118926) (xy 136.306446 -28.171221) (xy 136.314202 -28.225169)
			(xy 136.314688 -28.25242) (xy 136.314688 -28.526871) (xy 139.853386 -28.526871) (xy 139.853386 -28.472329)
			(xy 139.861148 -28.418343) (xy 139.876513 -28.366011) (xy 139.89917 -28.316397) (xy 139.928656 -28.270513)
			(xy 139.964371 -28.229293) (xy 140.005589 -28.193574) (xy 140.051471 -28.164084) (xy 140.101082 -28.141424)
			(xy 140.153414 -28.126054) (xy 140.207399 -28.118289) (xy 140.23467 -28.1178) (xy 141.09827 -28.1178)
			(xy 141.12554 -28.118337) (xy 141.179524 -28.126095) (xy 141.231856 -28.141457) (xy 141.281468 -28.164111)
			(xy 141.32735 -28.193595) (xy 141.36857 -28.229309) (xy 141.404287 -28.270526) (xy 141.433775 -28.316406)
			(xy 141.456432 -28.366016) (xy 141.471798 -28.418346) (xy 141.479561 -28.47233) (xy 141.479561 -28.52687)
			(xy 141.471798 -28.580854) (xy 141.456432 -28.633184) (xy 141.433775 -28.682794) (xy 141.404287 -28.728674)
			(xy 141.36857 -28.769891) (xy 141.32735 -28.805605) (xy 141.281468 -28.835089) (xy 141.231856 -28.857743)
			(xy 141.179524 -28.873105) (xy 141.12554 -28.880863) (xy 141.09827 -28.881324) (xy 140.23467 -28.881324)
			(xy 140.207399 -28.880911) (xy 140.153414 -28.873146) (xy 140.101082 -28.857776) (xy 140.051471 -28.835116)
			(xy 140.005589 -28.805626) (xy 139.964371 -28.769907) (xy 139.928656 -28.728687) (xy 139.89917 -28.682803)
			(xy 139.876513 -28.633189) (xy 139.861148 -28.580857) (xy 139.853386 -28.526871) (xy 136.314688 -28.526871)
			(xy 136.314688 -29.24302) (xy 136.314202 -29.270271) (xy 136.306446 -29.324219) (xy 136.291091 -29.376514)
			(xy 136.268449 -29.426091) (xy 136.238983 -29.471941) (xy 136.203292 -29.513132) (xy 136.162101 -29.548823)
			(xy 136.116251 -29.578289) (xy 136.066674 -29.600931) (xy 136.014379 -29.616286) (xy 135.960431 -29.624042)
			(xy 135.905929 -29.624042) (xy 135.851981 -29.616286) (xy 135.799686 -29.600931) (xy 135.750109 -29.578289)
			(xy 135.704259 -29.548823) (xy 135.663068 -29.513132) (xy 135.627377 -29.471941) (xy 135.597911 -29.426091)
			(xy 135.575269 -29.376514) (xy 135.559914 -29.324219) (xy 135.552158 -29.270271) (xy 135.551672 -29.24302)
			(xy 102.089712 -29.24302) (xy 102.089712 -29.51861) (xy 102.089226 -29.545861) (xy 102.08147 -29.599809)
			(xy 102.066115 -29.652104) (xy 102.043473 -29.701681) (xy 102.014007 -29.747531) (xy 101.978316 -29.788722)
			(xy 101.937125 -29.824413) (xy 101.891275 -29.853879) (xy 101.841698 -29.876521) (xy 101.789403 -29.891876)
			(xy 101.735455 -29.899632) (xy 101.680953 -29.899632) (xy 101.627005 -29.891876) (xy 101.57471 -29.876521)
			(xy 101.525133 -29.853879) (xy 101.479283 -29.824413) (xy 101.438092 -29.788722) (xy 101.402401 -29.747531)
			(xy 101.372935 -29.701681) (xy 101.350293 -29.652104) (xy 101.334938 -29.599809) (xy 101.327182 -29.545861)
			(xy 101.326696 -29.51861) (xy 18.546379 -29.51861) (xy 18.551274 -29.537523) (xy 18.583516 -29.693848)
			(xy 18.607926 -29.851586) (xy 18.624443 -30.010345) (xy 18.63109 -30.1338) (xy 197.595716 -30.1338)
			(xy 197.599747 -30.049172) (xy 197.611805 -29.965311) (xy 197.631779 -29.882976) (xy 197.65949 -29.802912)
			(xy 197.694686 -29.725844) (xy 197.737048 -29.652472) (xy 197.786193 -29.583458) (xy 197.841676 -29.519429)
			(xy 197.902994 -29.460963) (xy 197.969592 -29.408591) (xy 198.040866 -29.362787) (xy 198.116172 -29.323965)
			(xy 198.194827 -29.292477) (xy 198.276119 -29.268609) (xy 198.359312 -29.252576) (xy 198.443652 -29.244524)
			(xy 198.486014 -29.244036) (xy 198.524304 -29.244437) (xy 198.600598 -29.251046) (xy 198.676041 -29.264197)
			(xy 198.750071 -29.283791) (xy 198.786242 -29.29636) (xy 198.794679 -29.299011) (xy 198.812349 -29.299011)
			(xy 198.820786 -29.29636) (xy 198.856961 -29.283808) (xy 198.930995 -29.264238) (xy 199.006435 -29.251093)
			(xy 199.082726 -29.244471) (xy 199.121014 -29.244036) (xy 199.159304 -29.244437) (xy 199.235598 -29.251046)
			(xy 199.311041 -29.264197) (xy 199.385071 -29.283791) (xy 199.421242 -29.29636) (xy 199.429679 -29.299011)
			(xy 199.447349 -29.299011) (xy 199.455786 -29.29636) (xy 199.491961 -29.283808) (xy 199.565995 -29.264238)
			(xy 199.641435 -29.251093) (xy 199.717726 -29.244471) (xy 199.756014 -29.244036) (xy 199.794304 -29.244437)
			(xy 199.870598 -29.251046) (xy 199.946041 -29.264197) (xy 200.020071 -29.283791) (xy 200.056242 -29.29636)
			(xy 200.064679 -29.299011) (xy 200.082349 -29.299011) (xy 200.090786 -29.29636) (xy 200.126961 -29.283808)
			(xy 200.200995 -29.264238) (xy 200.276435 -29.251093) (xy 200.352726 -29.244471) (xy 200.391014 -29.244036)
			(xy 200.431702 -29.244422) (xy 200.512738 -29.251848) (xy 200.592757 -29.266645) (xy 200.67109 -29.288689)
			(xy 200.747082 -29.317797) (xy 200.820096 -29.353725) (xy 200.889524 -29.396173) (xy 200.954784 -29.444785)
			(xy 201.015331 -29.499155) (xy 201.070657 -29.558829) (xy 201.120302 -29.623307) (xy 201.163849 -29.69205)
			(xy 201.200934 -29.764484) (xy 201.216514 -29.802074) (xy 201.22098 -29.811942) (xy 201.236608 -29.826918)
			(xy 201.256995 -29.83419) (xy 201.267822 -29.833824) (xy 201.286077 -29.832403) (xy 201.322664 -29.83088)
			(xy 201.340974 -29.830776) (xy 201.383338 -29.831187) (xy 201.467682 -29.839239) (xy 201.550879 -29.855272)
			(xy 201.632176 -29.87914) (xy 201.710835 -29.910629) (xy 201.786145 -29.949452) (xy 201.857423 -29.995258)
			(xy 201.924025 -30.047632) (xy 201.985346 -30.1061) (xy 202.040832 -30.170132) (xy 202.08998 -30.239149)
			(xy 202.132344 -30.312525) (xy 202.167542 -30.389596) (xy 202.195254 -30.469663) (xy 202.21523 -30.552003)
			(xy 202.227288 -30.635868) (xy 202.23132 -30.7205) (xy 202.227288 -30.805132) (xy 202.21523 -30.888997)
			(xy 202.195254 -30.971337) (xy 202.167542 -31.051404) (xy 202.132344 -31.128475) (xy 202.08998 -31.201851)
			(xy 202.040832 -31.270868) (xy 201.985346 -31.3349) (xy 201.924025 -31.393368) (xy 201.857423 -31.445742)
			(xy 201.786145 -31.491548) (xy 201.710835 -31.530371) (xy 201.632176 -31.56186) (xy 201.550879 -31.585728)
			(xy 201.467682 -31.601761) (xy 201.383338 -31.609813) (xy 201.340974 -31.6103) (xy 201.302684 -31.609905)
			(xy 201.226389 -31.603295) (xy 201.150947 -31.590142) (xy 201.076917 -31.570546) (xy 201.040746 -31.557976)
			(xy 201.032309 -31.555325) (xy 201.014639 -31.555325) (xy 201.006202 -31.557976) (xy 200.970027 -31.570528)
			(xy 200.895993 -31.590099) (xy 200.820553 -31.603244) (xy 200.744262 -31.609866) (xy 200.705974 -31.6103)
			(xy 200.667684 -31.609905) (xy 200.591389 -31.603295) (xy 200.515947 -31.590142) (xy 200.441917 -31.570546)
			(xy 200.405746 -31.557976) (xy 200.397309 -31.555325) (xy 200.379639 -31.555325) (xy 200.371202 -31.557976)
			(xy 200.335027 -31.570528) (xy 200.260993 -31.590099) (xy 200.185553 -31.603244) (xy 200.109262 -31.609866)
			(xy 200.070974 -31.6103) (xy 200.032684 -31.609905) (xy 199.956389 -31.603295) (xy 199.880947 -31.590142)
			(xy 199.806917 -31.570546) (xy 199.770746 -31.557976) (xy 199.762309 -31.555325) (xy 199.744639 -31.555325)
			(xy 199.736202 -31.557976) (xy 199.700027 -31.570528) (xy 199.625993 -31.590099) (xy 199.550553 -31.603244)
			(xy 199.474262 -31.609866) (xy 199.435974 -31.6103) (xy 199.395288 -31.609814) (xy 199.314256 -31.602396)
			(xy 199.23424 -31.587608) (xy 199.15591 -31.565572) (xy 199.07992 -31.536472) (xy 199.006906 -31.500553)
			(xy 198.937478 -31.458114) (xy 198.872217 -31.40951) (xy 198.81167 -31.355148) (xy 198.756341 -31.295482)
			(xy 198.706694 -31.231012) (xy 198.663144 -31.162275) (xy 198.626056 -31.089848) (xy 198.610474 -31.052262)
			(xy 198.605924 -31.042441) (xy 198.590335 -31.027459) (xy 198.569982 -31.020164) (xy 198.559166 -31.020512)
			(xy 198.540911 -31.021927) (xy 198.504324 -31.023454) (xy 198.486014 -31.02356) (xy 198.443652 -31.023076)
			(xy 198.359312 -31.015024) (xy 198.276119 -30.998991) (xy 198.194827 -30.975123) (xy 198.116172 -30.943635)
			(xy 198.040866 -30.904813) (xy 197.969592 -30.859009) (xy 197.902994 -30.806637) (xy 197.841676 -30.748171)
			(xy 197.786193 -30.684142) (xy 197.737048 -30.615128) (xy 197.694686 -30.541756) (xy 197.65949 -30.464688)
			(xy 197.631779 -30.384624) (xy 197.611805 -30.302289) (xy 197.599747 -30.218428) (xy 197.595716 -30.1338)
			(xy 18.63109 -30.1338) (xy 18.633025 -30.16973) (xy 18.633652 -30.329344) (xy 18.626321 -30.488792)
			(xy 18.611051 -30.647675) (xy 18.587881 -30.8056) (xy 18.556867 -30.962174) (xy 18.518086 -31.117007)
			(xy 18.471636 -31.269714) (xy 18.417631 -31.419917) (xy 18.356206 -31.56724) (xy 18.287514 -31.711318)
			(xy 18.211725 -31.851793) (xy 18.129028 -31.988316) (xy 18.039629 -32.120546) (xy 17.943749 -32.248156)
			(xy 17.841627 -32.370828) (xy 17.733517 -32.488256) (xy 17.619688 -32.60015) (xy 17.500423 -32.70623)
			(xy 17.376019 -32.806234) (xy 17.246784 -32.899911) (xy 17.173557 -32.94761) (xy 102.642416 -32.94761)
			(xy 102.642416 -31.95701) (xy 102.642902 -31.929759) (xy 102.650658 -31.875811) (xy 102.666013 -31.823516)
			(xy 102.688655 -31.773939) (xy 102.718121 -31.728089) (xy 102.753812 -31.686898) (xy 102.795003 -31.651207)
			(xy 102.840853 -31.621741) (xy 102.89043 -31.599099) (xy 102.942725 -31.583744) (xy 102.996673 -31.575988)
			(xy 103.051175 -31.575988) (xy 103.105123 -31.583744) (xy 103.157418 -31.599099) (xy 103.206995 -31.621741)
			(xy 103.252845 -31.651207) (xy 103.294036 -31.686898) (xy 103.329727 -31.728089) (xy 103.359193 -31.773939)
			(xy 103.381835 -31.823516) (xy 103.39719 -31.875811) (xy 103.404946 -31.929759) (xy 103.405432 -31.95701)
			(xy 103.405432 -32.405066) (xy 105.659936 -32.405066) (xy 105.659936 -31.541466) (xy 105.660422 -31.514215)
			(xy 105.668178 -31.460267) (xy 105.683533 -31.407972) (xy 105.706175 -31.358395) (xy 105.735641 -31.312545)
			(xy 105.771332 -31.271354) (xy 105.812523 -31.235663) (xy 105.858373 -31.206197) (xy 105.90795 -31.183555)
			(xy 105.960245 -31.1682) (xy 106.014193 -31.160444) (xy 106.068695 -31.160444) (xy 106.122643 -31.1682)
			(xy 106.174938 -31.183555) (xy 106.224515 -31.206197) (xy 106.270365 -31.235663) (xy 106.311556 -31.271354)
			(xy 106.347247 -31.312545) (xy 106.376713 -31.358395) (xy 106.399355 -31.407972) (xy 106.41471 -31.460267)
			(xy 106.422466 -31.514215) (xy 106.422952 -31.541466) (xy 106.422952 -31.65856) (xy 140.278612 -31.65856)
			(xy 140.278612 -30.79496) (xy 140.279098 -30.767709) (xy 140.286854 -30.713761) (xy 140.302209 -30.661466)
			(xy 140.324851 -30.611889) (xy 140.354317 -30.566039) (xy 140.390008 -30.524848) (xy 140.431199 -30.489157)
			(xy 140.477049 -30.459691) (xy 140.526626 -30.437049) (xy 140.578921 -30.421694) (xy 140.632869 -30.413938)
			(xy 140.687371 -30.413938) (xy 140.741319 -30.421694) (xy 140.793614 -30.437049) (xy 140.843191 -30.459691)
			(xy 140.889041 -30.489157) (xy 140.930232 -30.524848) (xy 140.965923 -30.566039) (xy 140.995389 -30.611889)
			(xy 141.018031 -30.661466) (xy 141.033386 -30.713761) (xy 141.041142 -30.767709) (xy 141.041628 -30.79496)
			(xy 141.041628 -31.65856) (xy 141.041311 -31.67634) (xy 144.616932 -31.67634) (xy 144.616932 -30.81274)
			(xy 144.617418 -30.785489) (xy 144.625174 -30.731541) (xy 144.640529 -30.679246) (xy 144.663171 -30.629669)
			(xy 144.692637 -30.583819) (xy 144.728328 -30.542628) (xy 144.769519 -30.506937) (xy 144.815369 -30.477471)
			(xy 144.864946 -30.454829) (xy 144.917241 -30.439474) (xy 144.971189 -30.431718) (xy 145.025691 -30.431718)
			(xy 145.079639 -30.439474) (xy 145.131934 -30.454829) (xy 145.181511 -30.477471) (xy 145.227361 -30.506937)
			(xy 145.268552 -30.542628) (xy 145.304243 -30.583819) (xy 145.333709 -30.629669) (xy 145.356351 -30.679246)
			(xy 145.371706 -30.731541) (xy 145.379462 -30.785489) (xy 145.379948 -30.81274) (xy 145.379948 -31.67634)
			(xy 145.379462 -31.703591) (xy 145.371706 -31.757539) (xy 145.356351 -31.809834) (xy 145.333709 -31.859411)
			(xy 145.304243 -31.905261) (xy 145.268552 -31.946452) (xy 145.227361 -31.982143) (xy 145.181511 -32.011609)
			(xy 145.131934 -32.034251) (xy 145.079639 -32.049606) (xy 145.025691 -32.057362) (xy 144.971189 -32.057362)
			(xy 144.917241 -32.049606) (xy 144.864946 -32.034251) (xy 144.815369 -32.011609) (xy 144.769519 -31.982143)
			(xy 144.728328 -31.946452) (xy 144.692637 -31.905261) (xy 144.663171 -31.859411) (xy 144.640529 -31.809834)
			(xy 144.625174 -31.757539) (xy 144.617418 -31.703591) (xy 144.616932 -31.67634) (xy 141.041311 -31.67634)
			(xy 141.041142 -31.685811) (xy 141.033386 -31.739759) (xy 141.018031 -31.792054) (xy 140.995389 -31.841631)
			(xy 140.965923 -31.887481) (xy 140.930232 -31.928672) (xy 140.889041 -31.964363) (xy 140.843191 -31.993829)
			(xy 140.793614 -32.016471) (xy 140.741319 -32.031826) (xy 140.687371 -32.039582) (xy 140.632869 -32.039582)
			(xy 140.578921 -32.031826) (xy 140.526626 -32.016471) (xy 140.477049 -31.993829) (xy 140.431199 -31.964363)
			(xy 140.390008 -31.928672) (xy 140.354317 -31.887481) (xy 140.324851 -31.841631) (xy 140.302209 -31.792054)
			(xy 140.286854 -31.739759) (xy 140.279098 -31.685811) (xy 140.278612 -31.65856) (xy 106.422952 -31.65856)
			(xy 106.422952 -32.405066) (xy 106.422466 -32.432317) (xy 106.41471 -32.486265) (xy 106.399355 -32.53856)
			(xy 106.376713 -32.588137) (xy 106.347247 -32.633987) (xy 106.311556 -32.675178) (xy 106.270365 -32.710869)
			(xy 106.224515 -32.740335) (xy 106.174938 -32.762977) (xy 106.122643 -32.778332) (xy 106.068695 -32.786088)
			(xy 106.014193 -32.786088) (xy 105.960245 -32.778332) (xy 105.90795 -32.762977) (xy 105.858373 -32.740335)
			(xy 105.812523 -32.710869) (xy 105.771332 -32.675178) (xy 105.735641 -32.633987) (xy 105.706175 -32.588137)
			(xy 105.683533 -32.53856) (xy 105.668178 -32.486265) (xy 105.660422 -32.432317) (xy 105.659936 -32.405066)
			(xy 103.405432 -32.405066) (xy 103.405432 -32.94761) (xy 103.404946 -32.974861) (xy 103.39719 -33.028809)
			(xy 103.390276 -33.052356) (xy 119.734235 -33.052356) (xy 119.734235 -32.997844) (xy 119.741993 -32.943888)
			(xy 119.757352 -32.891585) (xy 119.779997 -32.842) (xy 119.80947 -32.796143) (xy 119.845169 -32.754947)
			(xy 119.886367 -32.719252) (xy 119.932226 -32.689783) (xy 119.981813 -32.667141) (xy 120.034117 -32.651787)
			(xy 120.088074 -32.644033) (xy 120.11533 -32.643572) (xy 120.97893 -32.643572) (xy 121.006178 -32.6441)
			(xy 121.06012 -32.65186) (xy 121.112408 -32.667217) (xy 121.161979 -32.689858) (xy 121.207823 -32.719324)
			(xy 121.249008 -32.755014) (xy 121.284694 -32.796201) (xy 121.314156 -32.842047) (xy 121.336794 -32.89162)
			(xy 121.352147 -32.943909) (xy 121.359902 -32.997852) (xy 121.359902 -33.052348) (xy 121.352147 -33.106291)
			(xy 121.336794 -33.15858) (xy 121.314156 -33.208153) (xy 121.284694 -33.253999) (xy 121.249008 -33.295186)
			(xy 121.207823 -33.330876) (xy 121.161979 -33.360342) (xy 121.112408 -33.382983) (xy 121.06012 -33.39834)
			(xy 121.006178 -33.4061) (xy 120.97893 -33.406588) (xy 120.11533 -33.406588) (xy 120.088074 -33.406167)
			(xy 120.034117 -33.398413) (xy 119.981813 -33.383059) (xy 119.932226 -33.360417) (xy 119.886367 -33.330948)
			(xy 119.845169 -33.295253) (xy 119.80947 -33.254057) (xy 119.779997 -33.2082) (xy 119.757352 -33.158615)
			(xy 119.741993 -33.106312) (xy 119.734235 -33.052356) (xy 103.390276 -33.052356) (xy 103.381835 -33.081104)
			(xy 103.359193 -33.130681) (xy 103.329727 -33.176531) (xy 103.294036 -33.217722) (xy 103.252845 -33.253413)
			(xy 103.206995 -33.282879) (xy 103.157418 -33.305521) (xy 103.105123 -33.320876) (xy 103.051175 -33.328632)
			(xy 102.996673 -33.328632) (xy 102.942725 -33.320876) (xy 102.89043 -33.305521) (xy 102.840853 -33.282879)
			(xy 102.795003 -33.253413) (xy 102.753812 -33.217722) (xy 102.718121 -33.176531) (xy 102.688655 -33.130681)
			(xy 102.666013 -33.081104) (xy 102.650658 -33.028809) (xy 102.642902 -32.974861) (xy 102.642416 -32.94761)
			(xy 17.173557 -32.94761) (xy 17.11304 -32.98703) (xy 16.975119 -33.067374) (xy 16.833366 -33.140743)
			(xy 16.688131 -33.206955) (xy 16.539776 -33.265845) (xy 16.38867 -33.317266) (xy 16.235188 -33.361091)
			(xy 16.079713 -33.397211) (xy 15.922631 -33.425536) (xy 15.764332 -33.445995) (xy 15.605209 -33.458538)
			(xy 15.44566 -33.463134) (xy 15.286079 -33.459771) (xy 15.126865 -33.448457) (xy 14.968413 -33.42922)
			(xy 14.811116 -33.402109) (xy 14.655367 -33.367191) (xy 14.501552 -33.324553) (xy 14.350053 -33.2743)
			(xy 14.201248 -33.216557) (xy 14.055506 -33.151469) (xy 13.91319 -33.079197) (xy 13.774653 -32.999921)
			(xy 13.64024 -32.913837) (xy 13.510286 -32.82116) (xy 13.385112 -32.72212) (xy 13.265032 -32.616964)
			(xy 13.150342 -32.505953) (xy 13.095478 -32.447992) (xy 12.00277 -31.279592) (xy 11.948692 -31.220903)
			(xy 11.845626 -31.099035) (xy 11.748763 -30.972182) (xy 11.658343 -30.840658) (xy 11.574591 -30.704792)
			(xy 11.497716 -30.564919) (xy 11.427907 -30.421388) (xy 11.36534 -30.274557) (xy 11.310169 -30.124789)
			(xy 11.262532 -29.972457) (xy 11.222547 -29.81794) (xy 11.190314 -29.661623) (xy 11.165912 -29.503893)
			(xy 11.149402 -29.345143) (xy 11.140826 -29.185767) (xy 11.140205 -29.026161) (xy 0.509016 -29.026161)
			(xy 0.509016 -33.838388) (xy 122.111008 -33.838388) (xy 122.111008 -32.974788) (xy 122.111494 -32.947519)
			(xy 122.119256 -32.893535) (xy 122.134621 -32.841205) (xy 122.157278 -32.791595) (xy 122.186764 -32.745714)
			(xy 122.222479 -32.704497) (xy 122.263696 -32.668782) (xy 122.309577 -32.639296) (xy 122.359187 -32.616639)
			(xy 122.411517 -32.601274) (xy 122.465501 -32.593512) (xy 122.520039 -32.593512) (xy 122.574023 -32.601274)
			(xy 122.626353 -32.616639) (xy 122.675963 -32.639296) (xy 122.721844 -32.668782) (xy 122.763061 -32.704497)
			(xy 122.798776 -32.745714) (xy 122.828262 -32.791595) (xy 122.850919 -32.841205) (xy 122.866284 -32.893535)
			(xy 122.874046 -32.947519) (xy 122.874532 -32.974788) (xy 122.874532 -33.413556) (xy 124.175423 -33.413556)
			(xy 124.175423 -33.359044) (xy 124.183181 -33.305087) (xy 124.198539 -33.252783) (xy 124.221185 -33.203197)
			(xy 124.250658 -33.157339) (xy 124.286357 -33.116142) (xy 124.327555 -33.080446) (xy 124.373415 -33.050976)
			(xy 124.423002 -33.028332) (xy 124.475306 -33.012977) (xy 124.529264 -33.005222) (xy 124.55652 -33.00476)
			(xy 125.42012 -33.00476) (xy 125.447368 -33.005312) (xy 125.501309 -33.01307) (xy 125.553597 -33.028425)
			(xy 125.603167 -33.051066) (xy 125.649011 -33.08053) (xy 125.690196 -33.116218) (xy 125.725882 -33.157405)
			(xy 125.755344 -33.20325) (xy 125.777982 -33.252822) (xy 125.793335 -33.305111) (xy 125.80109 -33.359052)
			(xy 125.80109 -33.413548) (xy 125.793335 -33.467489) (xy 125.777982 -33.519778) (xy 125.755344 -33.56935)
			(xy 125.725882 -33.615195) (xy 125.690196 -33.656382) (xy 125.649011 -33.69207) (xy 125.603167 -33.721534)
			(xy 125.553597 -33.744175) (xy 125.501309 -33.75953) (xy 125.447368 -33.767288) (xy 125.42012 -33.767776)
			(xy 124.55652 -33.767776) (xy 124.529264 -33.767378) (xy 124.475306 -33.759623) (xy 124.423002 -33.744268)
			(xy 124.373415 -33.721624) (xy 124.327555 -33.692154) (xy 124.286357 -33.656458) (xy 124.250658 -33.615261)
			(xy 124.221185 -33.569403) (xy 124.198539 -33.519817) (xy 124.183181 -33.467513) (xy 124.175423 -33.413556)
			(xy 122.874532 -33.413556) (xy 122.874532 -33.838388) (xy 122.874046 -33.865657) (xy 122.866284 -33.919641)
			(xy 122.850919 -33.971971) (xy 122.828262 -34.021581) (xy 122.798776 -34.067462) (xy 122.763061 -34.108679)
			(xy 122.721844 -34.144394) (xy 122.675963 -34.17388) (xy 122.626353 -34.196537) (xy 122.574023 -34.211902)
			(xy 122.520039 -34.219664) (xy 122.465501 -34.219664) (xy 122.411517 -34.211902) (xy 122.359187 -34.196537)
			(xy 122.309577 -34.17388) (xy 122.263696 -34.144394) (xy 122.222479 -34.108679) (xy 122.186764 -34.067462)
			(xy 122.157278 -34.021581) (xy 122.134621 -33.971971) (xy 122.119256 -33.919641) (xy 122.111494 -33.865657)
			(xy 122.111008 -33.838388) (xy 0.509016 -33.838388) (xy 0.509016 -36.080556) (xy 122.143423 -36.080556)
			(xy 122.143423 -36.026044) (xy 122.151181 -35.972087) (xy 122.166539 -35.919783) (xy 122.189185 -35.870197)
			(xy 122.218658 -35.824339) (xy 122.254357 -35.783142) (xy 122.295555 -35.747446) (xy 122.341415 -35.717976)
			(xy 122.391002 -35.695332) (xy 122.443306 -35.679977) (xy 122.497264 -35.672222) (xy 122.52452 -35.67176)
			(xy 123.38812 -35.67176) (xy 123.415368 -35.672312) (xy 123.469309 -35.68007) (xy 123.521597 -35.695425)
			(xy 123.571167 -35.718066) (xy 123.617011 -35.74753) (xy 123.658196 -35.783218) (xy 123.693882 -35.824405)
			(xy 123.723344 -35.87025) (xy 123.745982 -35.919822) (xy 123.761335 -35.972111) (xy 123.76909 -36.026052)
			(xy 123.76909 -36.080548) (xy 123.761335 -36.134489) (xy 123.745982 -36.186778) (xy 123.723344 -36.23635)
			(xy 123.693882 -36.282195) (xy 123.658196 -36.323382) (xy 123.617011 -36.35907) (xy 123.571167 -36.388534)
			(xy 123.521597 -36.411175) (xy 123.469309 -36.42653) (xy 123.415368 -36.434288) (xy 123.38812 -36.434776)
			(xy 122.52452 -36.434776) (xy 122.497264 -36.434378) (xy 122.443306 -36.426623) (xy 122.391002 -36.411268)
			(xy 122.341415 -36.388624) (xy 122.295555 -36.359154) (xy 122.254357 -36.323458) (xy 122.218658 -36.282261)
			(xy 122.189185 -36.236403) (xy 122.166539 -36.186817) (xy 122.151181 -36.134513) (xy 122.143423 -36.080556)
			(xy 0.509016 -36.080556) (xy 0.509016 -39.23137) (xy 9.080235 -39.23137) (xy 9.080235 -39.10223)
			(xy 9.088185 -38.973335) (xy 9.104055 -38.845175) (xy 9.127784 -38.718234) (xy 9.159283 -38.592995)
			(xy 9.198432 -38.469932) (xy 9.245083 -38.349513) (xy 9.299058 -38.232194) (xy 9.360153 -38.11842)
			(xy 9.428136 -38.008623) (xy 9.50275 -37.90322) (xy 9.583711 -37.80261) (xy 9.670711 -37.707175)
			(xy 9.763422 -37.617276) (xy 9.861492 -37.533255) (xy 9.964547 -37.455431) (xy 10.072198 -37.384099)
			(xy 10.184037 -37.319529) (xy 10.299638 -37.261967) (xy 10.418563 -37.21163) (xy 10.540362 -37.16871)
			(xy 10.664572 -37.133369) (xy 10.790721 -37.105742) (xy 10.918333 -37.085933) (xy 11.046922 -37.074017)
			(xy 11.176 -37.070041) (xy 11.305078 -37.074017) (xy 11.433667 -37.085933) (xy 11.521898 -37.099629)
			(xy 170.60087 -37.099629) (xy 170.60087 -37.000299) (xy 170.608862 -36.901292) (xy 170.624796 -36.803249)
			(xy 170.648567 -36.706806) (xy 170.680022 -36.612588) (xy 170.718955 -36.521208) (xy 170.765116 -36.433256)
			(xy 170.818204 -36.349304) (xy 170.877875 -36.269895) (xy 170.943743 -36.195546) (xy 171.01538 -36.126738)
			(xy 171.092321 -36.063918) (xy 171.174067 -36.007493) (xy 171.260089 -35.957828) (xy 171.349828 -35.915246)
			(xy 171.442702 -35.880024) (xy 171.53811 -35.852388) (xy 171.635432 -35.83252) (xy 171.734037 -35.820547)
			(xy 171.833286 -35.816548) (xy 171.932535 -35.820547) (xy 172.03114 -35.83252) (xy 172.128462 -35.852388)
			(xy 172.22387 -35.880024) (xy 172.316744 -35.915246) (xy 172.406483 -35.957828) (xy 172.492505 -36.007493)
			(xy 172.574251 -36.063918) (xy 172.651192 -36.126738) (xy 172.722829 -36.195546) (xy 172.788697 -36.269895)
			(xy 172.848368 -36.349304) (xy 172.901456 -36.433256) (xy 172.947617 -36.521208) (xy 172.98655 -36.612588)
			(xy 173.018005 -36.706806) (xy 173.041776 -36.803249) (xy 173.05771 -36.901292) (xy 173.065702 -37.000299)
			(xy 173.066202 -37.049964) (xy 173.065702 -37.099629) (xy 173.05771 -37.198636) (xy 173.041776 -37.296679)
			(xy 173.034033 -37.328094) (xy 197.270624 -37.328094) (xy 197.271107 -37.28698) (xy 197.278695 -37.205103)
			(xy 197.293804 -37.124275) (xy 197.316307 -37.045187) (xy 197.346011 -36.968512) (xy 197.382664 -36.894904)
			(xy 197.425951 -36.824993) (xy 197.475504 -36.759373) (xy 197.5309 -36.698606) (xy 197.591667 -36.643209)
			(xy 197.657286 -36.593655) (xy 197.727197 -36.550367) (xy 197.800804 -36.513715) (xy 197.877479 -36.48401)
			(xy 197.956568 -36.461506) (xy 198.037395 -36.446396) (xy 198.119272 -36.438808) (xy 198.160386 -36.438332)
			(xy 198.203952 -36.438853) (xy 198.290667 -36.447372) (xy 198.376134 -36.464329) (xy 198.459533 -36.489562)
			(xy 198.540065 -36.522829) (xy 198.616958 -36.563811) (xy 198.689475 -36.612116) (xy 198.756921 -36.66728)
			(xy 198.81865 -36.728775) (xy 198.87407 -36.796011) (xy 198.922649 -36.868345) (xy 198.963923 -36.945081)
			(xy 198.997496 -37.025486) (xy 199.010778 -37.066982) (xy 199.013703 -37.075249) (xy 199.024271 -37.089233)
			(xy 199.038923 -37.098854) (xy 199.047354 -37.101272) (xy 199.088321 -37.111837) (xy 199.168226 -37.13965)
			(xy 199.24513 -37.174922) (xy 199.318339 -37.217334) (xy 199.387193 -37.266504) (xy 199.451068 -37.321986)
			(xy 199.509389 -37.383281) (xy 199.529427 -37.408809) (xy 207.619596 -37.408809) (xy 207.619596 -37.324087)
			(xy 207.627649 -37.23975) (xy 207.643683 -37.15656) (xy 207.667551 -37.07527) (xy 207.699039 -36.996618)
			(xy 207.737861 -36.921315) (xy 207.783664 -36.850043) (xy 207.836035 -36.783447) (xy 207.8945 -36.722132)
			(xy 207.958528 -36.666651) (xy 208.02754 -36.617508) (xy 208.10091 -36.575148) (xy 208.177975 -36.539953)
			(xy 208.258037 -36.512244) (xy 208.34037 -36.49227) (xy 208.424229 -36.480213) (xy 208.508854 -36.476182)
			(xy 208.593479 -36.480213) (xy 208.677338 -36.49227) (xy 208.759671 -36.512244) (xy 208.839733 -36.539953)
			(xy 208.916798 -36.575148) (xy 208.990168 -36.617508) (xy 209.05918 -36.666651) (xy 209.123208 -36.722132)
			(xy 209.181673 -36.783447) (xy 209.234044 -36.850043) (xy 209.279847 -36.921315) (xy 209.318669 -36.996618)
			(xy 209.350157 -37.07527) (xy 209.374025 -37.15656) (xy 209.390059 -37.23975) (xy 209.398112 -37.324087)
			(xy 209.398616 -37.366448) (xy 209.398112 -37.408809) (xy 209.390059 -37.493146) (xy 209.374025 -37.576336)
			(xy 209.350157 -37.657626) (xy 209.318669 -37.736278) (xy 209.279847 -37.811581) (xy 209.234044 -37.882853)
			(xy 209.181673 -37.949449) (xy 209.123208 -38.010764) (xy 209.05918 -38.066245) (xy 208.990168 -38.115388)
			(xy 208.916798 -38.157748) (xy 208.839733 -38.192943) (xy 208.759671 -38.220652) (xy 208.677338 -38.240626)
			(xy 208.593479 -38.252683) (xy 208.508854 -38.256715) (xy 208.424229 -38.252683) (xy 208.34037 -38.240626)
			(xy 208.258037 -38.220652) (xy 208.177975 -38.192943) (xy 208.10091 -38.157748) (xy 208.02754 -38.115388)
			(xy 207.958528 -38.066245) (xy 207.8945 -38.010764) (xy 207.836035 -37.949449) (xy 207.783664 -37.882853)
			(xy 207.737861 -37.811581) (xy 207.699039 -37.736278) (xy 207.667551 -37.657626) (xy 207.643683 -37.576336)
			(xy 207.627649 -37.493146) (xy 207.619596 -37.408809) (xy 199.529427 -37.408809) (xy 199.561629 -37.449835)
			(xy 199.607316 -37.521047) (xy 199.646037 -37.596273) (xy 199.677444 -37.674835) (xy 199.701252 -37.756024)
			(xy 199.717247 -37.839106) (xy 199.725284 -37.92333) (xy 199.725788 -37.965634) (xy 199.72532 -38.006748)
			(xy 199.71773 -38.088625) (xy 199.702618 -38.169453) (xy 199.680113 -38.248541) (xy 199.650407 -38.325216)
			(xy 199.613754 -38.398823) (xy 199.570465 -38.468734) (xy 199.520911 -38.534353) (xy 199.465514 -38.595119)
			(xy 199.404746 -38.650516) (xy 199.339127 -38.70007) (xy 199.269216 -38.743357) (xy 199.195608 -38.78001)
			(xy 199.118933 -38.809716) (xy 199.039845 -38.83222) (xy 198.959017 -38.847331) (xy 198.87714 -38.85492)
			(xy 198.836026 -38.855396) (xy 198.792461 -38.854844) (xy 198.705747 -38.846327) (xy 198.620282 -38.829372)
			(xy 198.536884 -38.804141) (xy 198.456353 -38.770876) (xy 198.379461 -38.729896) (xy 198.306944 -38.681594)
			(xy 198.239498 -38.626432) (xy 198.177769 -38.56494) (xy 198.122348 -38.497707) (xy 198.073767 -38.425377)
			(xy 198.032492 -38.348643) (xy 197.998917 -38.26824) (xy 197.985634 -38.226746) (xy 197.982688 -38.218487)
			(xy 197.97213 -38.204501) (xy 197.957486 -38.194877) (xy 197.949058 -38.192456) (xy 197.908101 -38.181857)
			(xy 197.828197 -38.154046) (xy 197.751293 -38.118776) (xy 197.678085 -38.076367) (xy 197.609232 -38.0272)
			(xy 197.545356 -37.97172) (xy 197.487035 -37.910428) (xy 197.434795 -37.843877) (xy 197.389107 -37.772668)
			(xy 197.350384 -37.697444) (xy 197.318976 -37.618885) (xy 197.295165 -37.537699) (xy 197.279169 -37.454619)
			(xy 197.271129 -37.370397) (xy 197.270624 -37.328094) (xy 173.034033 -37.328094) (xy 173.018005 -37.393122)
			(xy 172.98655 -37.48734) (xy 172.947617 -37.57872) (xy 172.901456 -37.666672) (xy 172.848368 -37.750624)
			(xy 172.788697 -37.830033) (xy 172.722829 -37.904382) (xy 172.651192 -37.97319) (xy 172.574251 -38.03601)
			(xy 172.492505 -38.092435) (xy 172.406483 -38.1421) (xy 172.316744 -38.184682) (xy 172.22387 -38.219904)
			(xy 172.128462 -38.24754) (xy 172.03114 -38.267408) (xy 171.932535 -38.279381) (xy 171.833286 -38.283381)
			(xy 171.734037 -38.279381) (xy 171.635432 -38.267408) (xy 171.53811 -38.24754) (xy 171.442702 -38.219904)
			(xy 171.349828 -38.184682) (xy 171.260089 -38.1421) (xy 171.174067 -38.092435) (xy 171.092321 -38.03601)
			(xy 171.01538 -37.97319) (xy 170.943743 -37.904382) (xy 170.877875 -37.830033) (xy 170.818204 -37.750624)
			(xy 170.765116 -37.666672) (xy 170.718955 -37.57872) (xy 170.680022 -37.48734) (xy 170.648567 -37.393122)
			(xy 170.624796 -37.296679) (xy 170.608862 -37.198636) (xy 170.60087 -37.099629) (xy 11.521898 -37.099629)
			(xy 11.561279 -37.105742) (xy 11.687428 -37.133369) (xy 11.811638 -37.16871) (xy 11.933437 -37.21163)
			(xy 12.052362 -37.261967) (xy 12.167963 -37.319529) (xy 12.279802 -37.384099) (xy 12.387453 -37.455431)
			(xy 12.490508 -37.533255) (xy 12.588578 -37.617276) (xy 12.681289 -37.707175) (xy 12.768289 -37.80261)
			(xy 12.84925 -37.90322) (xy 12.923864 -38.008623) (xy 12.991847 -38.11842) (xy 13.052942 -38.232194)
			(xy 13.106917 -38.349513) (xy 13.153568 -38.469932) (xy 13.192717 -38.592995) (xy 13.224216 -38.718234)
			(xy 13.247945 -38.845175) (xy 13.263815 -38.973335) (xy 13.271765 -39.10223) (xy 13.272262 -39.1668)
			(xy 13.271765 -39.23137) (xy 13.263815 -39.360265) (xy 13.256012 -39.423283) (xy 254.45872 -39.423283)
			(xy 254.45872 -39.338561) (xy 254.466773 -39.254224) (xy 254.482807 -39.171034) (xy 254.506675 -39.089744)
			(xy 254.538163 -39.011092) (xy 254.576985 -38.935789) (xy 254.622788 -38.864517) (xy 254.675159 -38.797921)
			(xy 254.733624 -38.736606) (xy 254.797652 -38.681125) (xy 254.866664 -38.631982) (xy 254.940034 -38.589622)
			(xy 255.017099 -38.554427) (xy 255.097161 -38.526718) (xy 255.179494 -38.506744) (xy 255.263353 -38.494687)
			(xy 255.347978 -38.490656) (xy 255.432603 -38.494687) (xy 255.516462 -38.506744) (xy 255.598795 -38.526718)
			(xy 255.678857 -38.554427) (xy 255.755922 -38.589622) (xy 255.829292 -38.631982) (xy 255.898304 -38.681125)
			(xy 255.962332 -38.736606) (xy 256.020797 -38.797921) (xy 256.073168 -38.864517) (xy 256.118971 -38.935789)
			(xy 256.157793 -39.011092) (xy 256.189281 -39.089744) (xy 256.213149 -39.171034) (xy 256.229183 -39.254224)
			(xy 256.237236 -39.338561) (xy 256.23774 -39.380922) (xy 256.237236 -39.423283) (xy 256.229183 -39.50762)
			(xy 256.213149 -39.59081) (xy 256.189281 -39.6721) (xy 256.157793 -39.750752) (xy 256.118971 -39.826055)
			(xy 256.073168 -39.897327) (xy 256.020797 -39.963923) (xy 255.962332 -40.025238) (xy 255.898304 -40.080719)
			(xy 255.829292 -40.129862) (xy 255.755922 -40.172222) (xy 255.678857 -40.207417) (xy 255.598795 -40.235126)
			(xy 255.516462 -40.2551) (xy 255.432603 -40.267157) (xy 255.347978 -40.271189) (xy 255.263353 -40.267157)
			(xy 255.179494 -40.2551) (xy 255.097161 -40.235126) (xy 255.017099 -40.207417) (xy 254.940034 -40.172222)
			(xy 254.866664 -40.129862) (xy 254.797652 -40.080719) (xy 254.733624 -40.025238) (xy 254.675159 -39.963923)
			(xy 254.622788 -39.897327) (xy 254.576985 -39.826055) (xy 254.538163 -39.750752) (xy 254.506675 -39.6721)
			(xy 254.482807 -39.59081) (xy 254.466773 -39.50762) (xy 254.45872 -39.423283) (xy 13.256012 -39.423283)
			(xy 13.247945 -39.488425) (xy 13.224216 -39.615366) (xy 13.192717 -39.740605) (xy 13.153568 -39.863668)
			(xy 13.106917 -39.984087) (xy 13.052942 -40.101406) (xy 12.991847 -40.21518) (xy 12.923864 -40.324977)
			(xy 12.84925 -40.43038) (xy 12.768289 -40.53099) (xy 12.681289 -40.626425) (xy 12.588578 -40.716324)
			(xy 12.490508 -40.800345) (xy 12.413317 -40.858637) (xy 24.936192 -40.858637) (xy 24.936192 -40.773915)
			(xy 24.944245 -40.689578) (xy 24.960279 -40.606388) (xy 24.984147 -40.525098) (xy 25.015635 -40.446446)
			(xy 25.054457 -40.371143) (xy 25.10026 -40.299871) (xy 25.152631 -40.233275) (xy 25.211096 -40.17196)
			(xy 25.275124 -40.116479) (xy 25.344136 -40.067336) (xy 25.417506 -40.024976) (xy 25.494571 -39.989781)
			(xy 25.574633 -39.962072) (xy 25.656966 -39.942098) (xy 25.740825 -39.930041) (xy 25.82545 -39.92601)
			(xy 25.910075 -39.930041) (xy 25.993934 -39.942098) (xy 26.076267 -39.962072) (xy 26.156329 -39.989781)
			(xy 26.233394 -40.024976) (xy 26.306764 -40.067336) (xy 26.375776 -40.116479) (xy 26.439804 -40.17196)
			(xy 26.498269 -40.233275) (xy 26.55064 -40.299871) (xy 26.596443 -40.371143) (xy 26.635265 -40.446446)
			(xy 26.666753 -40.525098) (xy 26.690621 -40.606388) (xy 26.706655 -40.689578) (xy 26.711938 -40.744902)
			(xy 235.083357 -40.744902) (xy 235.087362 -40.656994) (xy 235.099345 -40.569814) (xy 235.119205 -40.484085)
			(xy 235.14678 -40.400517) (xy 235.181839 -40.319803) (xy 235.224092 -40.242611) (xy 235.27319 -40.169582)
			(xy 235.328726 -40.10132) (xy 235.390238 -40.03839) (xy 235.457219 -39.981316) (xy 235.529112 -39.930568)
			(xy 235.605321 -39.886568) (xy 235.685216 -39.849681) (xy 235.768135 -39.820212) (xy 235.85339 -39.798405)
			(xy 235.940274 -39.784441) (xy 236.028068 -39.778435) (xy 236.116045 -39.780439) (xy 236.203475 -39.790434)
			(xy 236.289634 -39.808338) (xy 236.373808 -39.834002) (xy 236.455299 -39.867215) (xy 236.533433 -39.907701)
			(xy 236.607561 -39.955123) (xy 236.677069 -40.00909) (xy 236.741383 -40.069155) (xy 236.799967 -40.134819)
			(xy 236.852338 -40.205538) (xy 236.898061 -40.280726) (xy 236.936758 -40.359761) (xy 236.968107 -40.441987)
			(xy 236.991849 -40.526723) (xy 237.007787 -40.613267) (xy 237.015789 -40.700902) (xy 237.01629 -40.744902)
			(xy 237.015789 -40.788902) (xy 237.007787 -40.876537) (xy 236.994276 -40.9499) (xy 246.935452 -40.9499)
			(xy 246.939482 -40.865295) (xy 246.951537 -40.781456) (xy 246.971506 -40.699142) (xy 246.999209 -40.619099)
			(xy 247.034396 -40.542053) (xy 247.076747 -40.468699) (xy 247.125879 -40.399704) (xy 247.181347 -40.335692)
			(xy 247.242648 -40.277242) (xy 247.309228 -40.224883) (xy 247.380484 -40.179091) (xy 247.45577 -40.14028)
			(xy 247.534404 -40.1088) (xy 247.615675 -40.084938) (xy 247.698846 -40.06891) (xy 247.783163 -40.060859)
			(xy 247.825514 -40.060372) (xy 247.868043 -40.060872) (xy 247.952713 -40.068982) (xy 248.036223 -40.085137)
			(xy 248.11781 -40.109189) (xy 248.196728 -40.140918) (xy 248.272258 -40.180035) (xy 248.343709 -40.226182)
			(xy 248.41043 -40.278938) (xy 248.441464 -40.308022) (xy 248.441718 -40.308276) (xy 248.44904 -40.314652)
			(xy 248.467069 -40.321822) (xy 248.47677 -40.322246) (xy 248.557288 -40.321992) (xy 248.575576 -40.314626)
			(xy 248.582688 -40.307514) (xy 248.613778 -40.278057) (xy 248.680689 -40.224588) (xy 248.752429 -40.177798)
			(xy 248.828335 -40.13812) (xy 248.907704 -40.105923) (xy 248.9898 -40.081504) (xy 249.073863 -40.065089)
			(xy 249.159115 -40.056831) (xy 249.20194 -40.056308) (xy 249.202448 -40.056308) (xy 249.244796 -40.056782)
			(xy 249.329107 -40.064837) (xy 249.412272 -40.08087) (xy 249.493536 -40.104735) (xy 249.572163 -40.136216)
			(xy 249.647442 -40.175029) (xy 249.718691 -40.220821) (xy 249.785265 -40.273178) (xy 249.84656 -40.331627)
			(xy 249.902022 -40.395637) (xy 249.951149 -40.464629) (xy 249.993496 -40.537978) (xy 250.028678 -40.615021)
			(xy 250.056379 -40.695058) (xy 250.076346 -40.777367) (xy 250.088399 -40.8612) (xy 250.092429 -40.9458)
			(xy 250.088399 -41.0304) (xy 250.076346 -41.114233) (xy 250.056379 -41.196542) (xy 250.028678 -41.276579)
			(xy 249.993496 -41.353622) (xy 249.951149 -41.426971) (xy 249.902022 -41.495963) (xy 249.84656 -41.559973)
			(xy 249.785265 -41.618422) (xy 249.718691 -41.670779) (xy 249.647442 -41.716571) (xy 249.572163 -41.755384)
			(xy 249.493536 -41.786865) (xy 249.412272 -41.81073) (xy 249.329107 -41.826763) (xy 249.244796 -41.834818)
			(xy 249.202448 -41.835324) (xy 249.159919 -41.834822) (xy 249.07525 -41.826709) (xy 248.991741 -41.810552)
			(xy 248.910155 -41.7865) (xy 248.831237 -41.754771) (xy 248.755707 -41.715655) (xy 248.684255 -41.66951)
			(xy 248.617533 -41.616756) (xy 248.586498 -41.587674) (xy 248.586244 -41.58742) (xy 248.578903 -41.58107)
			(xy 248.560888 -41.573885) (xy 248.551192 -41.57345) (xy 248.470674 -41.573704) (xy 248.452386 -41.58107)
			(xy 248.445274 -41.588182) (xy 248.414201 -41.617657) (xy 248.347287 -41.671125) (xy 248.275544 -41.717913)
			(xy 248.199635 -41.757589) (xy 248.120264 -41.789784) (xy 248.038166 -41.8142) (xy 247.954101 -41.830612)
			(xy 247.868848 -41.838866) (xy 247.826022 -41.839388) (xy 247.825514 -41.839388) (xy 247.783163 -41.838941)
			(xy 247.698846 -41.83089) (xy 247.615675 -41.814862) (xy 247.534404 -41.791) (xy 247.45577 -41.75952)
			(xy 247.380484 -41.720709) (xy 247.309228 -41.674917) (xy 247.242648 -41.622558) (xy 247.181347 -41.564108)
			(xy 247.125879 -41.500096) (xy 247.076747 -41.431101) (xy 247.034396 -41.357747) (xy 246.999209 -41.280701)
			(xy 246.971506 -41.200658) (xy 246.951537 -41.118344) (xy 246.939482 -41.034505) (xy 246.935452 -40.9499)
			(xy 236.994276 -40.9499) (xy 236.991849 -40.963081) (xy 236.968107 -41.047817) (xy 236.936758 -41.130043)
			(xy 236.898061 -41.209078) (xy 236.852338 -41.284266) (xy 236.799967 -41.354985) (xy 236.741383 -41.420649)
			(xy 236.677069 -41.480714) (xy 236.607561 -41.534681) (xy 236.533433 -41.582103) (xy 236.455299 -41.622589)
			(xy 236.373808 -41.655802) (xy 236.289634 -41.681466) (xy 236.203475 -41.69937) (xy 236.116045 -41.709365)
			(xy 236.028068 -41.711369) (xy 235.940274 -41.705363) (xy 235.85339 -41.691399) (xy 235.768135 -41.669592)
			(xy 235.685216 -41.640123) (xy 235.605321 -41.603236) (xy 235.529112 -41.559236) (xy 235.457219 -41.508488)
			(xy 235.390238 -41.451414) (xy 235.328726 -41.388484) (xy 235.27319 -41.320222) (xy 235.224092 -41.247193)
			(xy 235.181839 -41.170001) (xy 235.14678 -41.089287) (xy 235.119205 -41.005719) (xy 235.099345 -40.91999)
			(xy 235.087362 -40.83281) (xy 235.083357 -40.744902) (xy 26.711938 -40.744902) (xy 26.714708 -40.773915)
			(xy 26.715212 -40.816276) (xy 26.714708 -40.858637) (xy 26.706655 -40.942974) (xy 26.690621 -41.026164)
			(xy 26.666753 -41.107454) (xy 26.635265 -41.186106) (xy 26.596443 -41.261409) (xy 26.55064 -41.332681)
			(xy 26.498269 -41.399277) (xy 26.439804 -41.460592) (xy 26.375776 -41.516073) (xy 26.306764 -41.565216)
			(xy 26.233394 -41.607576) (xy 26.156329 -41.642771) (xy 26.076267 -41.67048) (xy 25.993934 -41.690454)
			(xy 25.910075 -41.702511) (xy 25.82545 -41.706543) (xy 25.740825 -41.702511) (xy 25.656966 -41.690454)
			(xy 25.574633 -41.67048) (xy 25.494571 -41.642771) (xy 25.417506 -41.607576) (xy 25.344136 -41.565216)
			(xy 25.275124 -41.516073) (xy 25.211096 -41.460592) (xy 25.152631 -41.399277) (xy 25.10026 -41.332681)
			(xy 25.054457 -41.261409) (xy 25.015635 -41.186106) (xy 24.984147 -41.107454) (xy 24.960279 -41.026164)
			(xy 24.944245 -40.942974) (xy 24.936192 -40.858637) (xy 12.413317 -40.858637) (xy 12.387453 -40.878169)
			(xy 12.279802 -40.949501) (xy 12.167963 -41.014071) (xy 12.052362 -41.071633) (xy 11.933437 -41.12197)
			(xy 11.811638 -41.16489) (xy 11.687428 -41.200231) (xy 11.561279 -41.227858) (xy 11.433667 -41.247667)
			(xy 11.305078 -41.259583) (xy 11.176 -41.26356) (xy 11.046922 -41.259583) (xy 10.918333 -41.247667)
			(xy 10.790721 -41.227858) (xy 10.664572 -41.200231) (xy 10.540362 -41.16489) (xy 10.418563 -41.12197)
			(xy 10.299638 -41.071633) (xy 10.184037 -41.014071) (xy 10.072198 -40.949501) (xy 9.964547 -40.878169)
			(xy 9.861492 -40.800345) (xy 9.763422 -40.716324) (xy 9.670711 -40.626425) (xy 9.583711 -40.53099)
			(xy 9.50275 -40.43038) (xy 9.428136 -40.324977) (xy 9.360153 -40.21518) (xy 9.299058 -40.101406)
			(xy 9.245083 -39.984087) (xy 9.198432 -39.863668) (xy 9.159283 -39.740605) (xy 9.127784 -39.615366)
			(xy 9.104055 -39.488425) (xy 9.088185 -39.360265) (xy 9.080235 -39.23137) (xy 0.509016 -39.23137)
			(xy 0.509016 -43.481752) (xy 178.630072 -43.481752) (xy 178.630072 -42.618152) (xy 178.630558 -42.590883)
			(xy 178.63832 -42.536899) (xy 178.653685 -42.484569) (xy 178.676342 -42.434959) (xy 178.705828 -42.389078)
			(xy 178.741543 -42.347861) (xy 178.78276 -42.312146) (xy 178.828641 -42.28266) (xy 178.878251 -42.260003)
			(xy 178.930581 -42.244638) (xy 178.984565 -42.236876) (xy 179.039103 -42.236876) (xy 179.093087 -42.244638)
			(xy 179.145417 -42.260003) (xy 179.195027 -42.28266) (xy 179.240908 -42.312146) (xy 179.282125 -42.347861)
			(xy 179.31784 -42.389078) (xy 179.347326 -42.434959) (xy 179.369983 -42.484569) (xy 179.385348 -42.536899)
			(xy 179.39311 -42.590883) (xy 179.393596 -42.618152) (xy 179.393596 -43.481752) (xy 179.39311 -43.509021)
			(xy 179.385348 -43.563005) (xy 179.369983 -43.615335) (xy 179.347326 -43.664945) (xy 179.31784 -43.710826)
			(xy 179.282125 -43.752043) (xy 179.240908 -43.787758) (xy 179.195027 -43.817244) (xy 179.145417 -43.839901)
			(xy 179.093087 -43.855266) (xy 179.039103 -43.863028) (xy 178.984565 -43.863028) (xy 178.930581 -43.855266)
			(xy 178.878251 -43.839901) (xy 178.828641 -43.817244) (xy 178.78276 -43.787758) (xy 178.741543 -43.752043)
			(xy 178.705828 -43.710826) (xy 178.676342 -43.664945) (xy 178.653685 -43.615335) (xy 178.63832 -43.563005)
			(xy 178.630558 -43.509021) (xy 178.630072 -43.481752) (xy 0.509016 -43.481752) (xy 0.509016 -47.04994)
			(xy 59.582066 -47.04994) (xy 59.586045 -46.890389) (xy 59.597972 -46.731234) (xy 59.617818 -46.572872)
			(xy 59.645532 -46.415696) (xy 59.681047 -46.260096) (xy 59.724273 -46.10646) (xy 59.775104 -45.95517)
			(xy 59.833413 -45.806602) (xy 59.899054 -45.661125) (xy 59.971866 -45.519101) (xy 60.051666 -45.380882)
			(xy 60.138257 -45.246813) (xy 60.231423 -45.117227) (xy 60.330933 -44.992446) (xy 60.436538 -44.87278)
			(xy 60.547978 -44.758527) (xy 60.664973 -44.649971) (xy 60.787235 -44.547381) (xy 60.914458 -44.451014)
			(xy 61.046326 -44.361107) (xy 61.182512 -44.277886) (xy 61.322677 -44.201556) (xy 61.466472 -44.132307)
			(xy 61.613541 -44.070313) (xy 61.763517 -44.015726) (xy 61.916027 -43.968683) (xy 62.070693 -43.9293)
			(xy 62.227129 -43.897676) (xy 62.384947 -43.873888) (xy 62.543755 -43.857997) (xy 62.703158 -43.850041)
			(xy 62.782958 -43.849544) (xy 64.382904 -43.849544) (xy 64.462705 -43.850033) (xy 64.622107 -43.857989)
			(xy 64.780916 -43.87388) (xy 64.938734 -43.897668) (xy 65.095171 -43.929293) (xy 65.249837 -43.968675)
			(xy 65.402347 -44.015719) (xy 65.552323 -44.070306) (xy 65.699392 -44.132301) (xy 65.843188 -44.201549)
			(xy 65.983353 -44.277879) (xy 66.119539 -44.361101) (xy 66.251408 -44.451008) (xy 66.378631 -44.547376)
			(xy 66.500893 -44.649966) (xy 66.617889 -44.758522) (xy 66.729328 -44.872775) (xy 66.834934 -44.992442)
			(xy 66.934444 -45.117223) (xy 67.02761 -45.246809) (xy 67.114201 -45.380878) (xy 67.194001 -45.519097)
			(xy 67.266813 -45.661122) (xy 67.332455 -45.806599) (xy 67.390764 -45.955168) (xy 67.441595 -46.106458)
			(xy 67.484821 -46.260094) (xy 67.520336 -46.415694) (xy 67.54805 -46.572871) (xy 67.567896 -46.731233)
			(xy 67.579823 -46.890388) (xy 67.583802 -47.04994) (xy 89.78165 -47.04994) (xy 89.78563 -46.895439)
			(xy 89.797557 -46.741349) (xy 89.817402 -46.588076) (xy 89.84511 -46.436028) (xy 89.880608 -46.285609)
			(xy 89.923803 -46.137216) (xy 89.97458 -45.991243) (xy 90.032804 -45.848078) (xy 90.098321 -45.708101)
			(xy 90.170957 -45.571681) (xy 90.250519 -45.439181) (xy 90.336796 -45.310953) (xy 90.42956 -45.187337)
			(xy 90.528565 -45.068659) (xy 90.633548 -44.955236) (xy 90.74423 -44.847368) (xy 90.860319 -44.74534)
			(xy 90.981506 -44.649424) (xy 91.10747 -44.559873) (xy 91.237877 -44.476926) (xy 91.372381 -44.400801)
			(xy 91.510626 -44.331702) (xy 91.652244 -44.269811) (xy 91.796861 -44.215293) (xy 91.944092 -44.168291)
			(xy 92.093548 -44.128931) (xy 92.244832 -44.097317) (xy 92.397543 -44.073533) (xy 92.551275 -44.057642)
			(xy 92.705622 -44.049686) (xy 92.782898 -44.049188) (xy 94.383098 -44.049188) (xy 94.460374 -44.049669)
			(xy 94.614722 -44.057625) (xy 94.768456 -44.073516) (xy 94.921168 -44.0973) (xy 95.072452 -44.128914)
			(xy 95.221909 -44.168274) (xy 95.369142 -44.215276) (xy 95.513759 -44.269795) (xy 95.655379 -44.331686)
			(xy 95.793624 -44.400785) (xy 95.928129 -44.47691) (xy 96.058537 -44.559858) (xy 96.184502 -44.649409)
			(xy 96.30569 -44.745326) (xy 96.421779 -44.847354) (xy 96.532463 -44.955223) (xy 96.555487 -44.980098)
			(xy 181.659784 -44.980098) (xy 181.659784 -44.116498) (xy 181.66027 -44.089229) (xy 181.668032 -44.035245)
			(xy 181.683397 -43.982915) (xy 181.706054 -43.933305) (xy 181.73554 -43.887424) (xy 181.771255 -43.846207)
			(xy 181.812472 -43.810492) (xy 181.858353 -43.781006) (xy 181.907963 -43.758349) (xy 181.960293 -43.742984)
			(xy 182.014277 -43.735222) (xy 182.068815 -43.735222) (xy 182.122799 -43.742984) (xy 182.175129 -43.758349)
			(xy 182.224739 -43.781006) (xy 182.27062 -43.810492) (xy 182.311837 -43.846207) (xy 182.347552 -43.887424)
			(xy 182.377038 -43.933305) (xy 182.399695 -43.982915) (xy 182.412218 -44.025566) (xy 236.740192 -44.025566)
			(xy 236.74068 -43.984453) (xy 236.74827 -43.902577) (xy 236.763381 -43.82175) (xy 236.785886 -43.742663)
			(xy 236.815591 -43.665989) (xy 236.852243 -43.592383) (xy 236.895531 -43.522473) (xy 236.945083 -43.456854)
			(xy 237.000479 -43.396088) (xy 237.061245 -43.340691) (xy 237.126863 -43.291137) (xy 237.196773 -43.247849)
			(xy 237.270378 -43.211196) (xy 237.347052 -43.181489) (xy 237.426139 -43.158984) (xy 237.506965 -43.143872)
			(xy 237.588841 -43.136281) (xy 237.629954 -43.135804) (xy 237.672596 -43.136331) (xy 237.757484 -43.144543)
			(xy 237.841197 -43.160838) (xy 237.922968 -43.185068) (xy 237.962694 -43.200574) (xy 237.971356 -43.203655)
			(xy 237.989722 -43.204046) (xy 237.998508 -43.201336) (xy 238.034032 -43.189272) (xy 238.106663 -43.170452)
			(xy 238.18062 -43.157817) (xy 238.25538 -43.151455) (xy 238.292894 -43.151044) (xy 238.332166 -43.151496)
			(xy 238.410399 -43.158477) (xy 238.487712 -43.172332) (xy 238.563501 -43.192954) (xy 238.600488 -43.206162)
			(xy 238.609037 -43.208926) (xy 238.626991 -43.208926) (xy 238.63554 -43.206162) (xy 238.672533 -43.192975)
			(xy 238.748323 -43.172363) (xy 238.825633 -43.158506) (xy 238.903863 -43.151512) (xy 238.943134 -43.151044)
			(xy 238.981423 -43.151469) (xy 239.057717 -43.158071) (xy 239.133159 -43.171215) (xy 239.207191 -43.190803)
			(xy 239.243362 -43.203368) (xy 239.251799 -43.206019) (xy 239.269469 -43.206019) (xy 239.277906 -43.203368)
			(xy 239.314089 -43.190839) (xy 239.38812 -43.171262) (xy 239.463558 -43.158111) (xy 239.539846 -43.151482)
			(xy 239.578134 -43.151044) (xy 239.616423 -43.151469) (xy 239.692717 -43.158071) (xy 239.768159 -43.171215)
			(xy 239.842191 -43.190803) (xy 239.878362 -43.203368) (xy 239.886799 -43.206019) (xy 239.904469 -43.206019)
			(xy 239.912906 -43.203368) (xy 239.949089 -43.190839) (xy 240.02312 -43.171262) (xy 240.098558 -43.158111)
			(xy 240.174846 -43.151482) (xy 240.213134 -43.151044) (xy 240.25606 -43.151581) (xy 240.341511 -43.159862)
			(xy 240.425768 -43.176335) (xy 240.508046 -43.200846) (xy 240.587581 -43.233168) (xy 240.613613 -43.246802)
			(xy 243.62918 -43.246802) (xy 243.629584 -43.208512) (xy 243.636192 -43.132218) (xy 243.649342 -43.056775)
			(xy 243.668936 -42.982745) (xy 243.681504 -42.946574) (xy 243.684156 -42.938137) (xy 243.684156 -42.920466)
			(xy 243.681504 -42.91203) (xy 243.668959 -42.875853) (xy 243.649386 -42.80182) (xy 243.636239 -42.72638)
			(xy 243.629616 -42.65009) (xy 243.62918 -42.611802) (xy 243.629684 -42.569441) (xy 243.637737 -42.485104)
			(xy 243.653771 -42.401914) (xy 243.677639 -42.320624) (xy 243.709127 -42.241972) (xy 243.747949 -42.166669)
			(xy 243.793752 -42.095397) (xy 243.846123 -42.028801) (xy 243.904588 -41.967486) (xy 243.968616 -41.912005)
			(xy 244.037628 -41.862862) (xy 244.110998 -41.820502) (xy 244.188063 -41.785307) (xy 244.268125 -41.757598)
			(xy 244.350458 -41.737624) (xy 244.434317 -41.725567) (xy 244.518942 -41.721536) (xy 244.603567 -41.725567)
			(xy 244.687426 -41.737624) (xy 244.769759 -41.757598) (xy 244.849821 -41.785307) (xy 244.926886 -41.820502)
			(xy 245.000256 -41.862862) (xy 245.069268 -41.912005) (xy 245.133296 -41.967486) (xy 245.191761 -42.028801)
			(xy 245.244132 -42.095397) (xy 245.289935 -42.166669) (xy 245.328757 -42.241972) (xy 245.360245 -42.320624)
			(xy 245.384113 -42.401914) (xy 245.400147 -42.485104) (xy 245.4082 -42.569441) (xy 245.408704 -42.611802)
			(xy 245.408302 -42.650092) (xy 245.401694 -42.726386) (xy 245.388543 -42.801829) (xy 245.368949 -42.875859)
			(xy 245.35638 -42.91203) (xy 245.353727 -42.920466) (xy 245.353728 -42.938137) (xy 245.35638 -42.946574)
			(xy 245.368926 -42.982751) (xy 245.388499 -43.056784) (xy 245.401645 -43.132224) (xy 245.408269 -43.208514)
			(xy 245.408704 -43.246802) (xy 245.4082 -43.289163) (xy 245.400147 -43.3735) (xy 245.384113 -43.45669)
			(xy 245.360245 -43.53798) (xy 245.328757 -43.616632) (xy 245.289935 -43.691935) (xy 245.244132 -43.763207)
			(xy 245.191761 -43.829803) (xy 245.133296 -43.891118) (xy 245.069268 -43.946599) (xy 245.000256 -43.995742)
			(xy 244.926886 -44.038102) (xy 244.849821 -44.073297) (xy 244.769759 -44.101006) (xy 244.687426 -44.12098)
			(xy 244.603567 -44.133037) (xy 244.518942 -44.137069) (xy 244.434317 -44.133037) (xy 244.350458 -44.12098)
			(xy 244.268125 -44.101006) (xy 244.188063 -44.073297) (xy 244.110998 -44.038102) (xy 244.037628 -43.995742)
			(xy 243.968616 -43.946599) (xy 243.904588 -43.891118) (xy 243.846123 -43.829803) (xy 243.793752 -43.763207)
			(xy 243.747949 -43.691935) (xy 243.709127 -43.616632) (xy 243.677639 -43.53798) (xy 243.653771 -43.45669)
			(xy 243.637737 -43.3735) (xy 243.629684 -43.289163) (xy 243.62918 -43.246802) (xy 240.613613 -43.246802)
			(xy 240.663633 -43.272999) (xy 240.735496 -43.31997) (xy 240.802501 -43.373643) (xy 240.864025 -43.433521)
			(xy 240.919496 -43.499046) (xy 240.968398 -43.569608) (xy 241.010277 -43.644552) (xy 241.044744 -43.723182)
			(xy 241.071477 -43.804765) (xy 241.090229 -43.888544) (xy 241.096038 -43.931078) (xy 241.097792 -43.94092)
			(xy 241.107661 -43.958279) (xy 241.123386 -43.970587) (xy 241.132868 -43.97375) (xy 241.172506 -43.985287)
			(xy 241.249638 -44.014728) (xy 241.32371 -44.051189) (xy 241.394086 -44.094356) (xy 241.460159 -44.143858)
			(xy 241.521362 -44.199269) (xy 241.577167 -44.260112) (xy 241.627095 -44.325864) (xy 241.670716 -44.395959)
			(xy 241.707655 -44.469795) (xy 241.737594 -44.546735) (xy 241.760276 -44.626118) (xy 241.775505 -44.707261)
			(xy 241.78315 -44.789466) (xy 241.783616 -44.830746) (xy 241.783231 -44.871862) (xy 241.775639 -44.953744)
			(xy 241.760525 -45.034576) (xy 241.738017 -45.113668) (xy 241.708307 -45.190346) (xy 241.671649 -45.263956)
			(xy 241.628355 -45.333869) (xy 241.578796 -45.39949) (xy 241.523393 -45.460258) (xy 241.462619 -45.515654)
			(xy 241.396993 -45.565207) (xy 241.327075 -45.608494) (xy 241.253462 -45.645144) (xy 241.176781 -45.674846)
			(xy 241.097686 -45.697346) (xy 241.016853 -45.712452) (xy 240.93497 -45.720035) (xy 240.893854 -45.720508)
			(xy 240.848047 -45.719908) (xy 240.756919 -45.710469) (xy 240.667241 -45.691726) (xy 240.579961 -45.663878)
			(xy 240.537746 -45.646086) (xy 240.528923 -45.642621) (xy 240.509997 -45.641842) (xy 240.500916 -45.644562)
			(xy 240.454475 -45.659757) (xy 240.359116 -45.681105) (xy 240.261993 -45.691873) (xy 240.213134 -45.692568)
			(xy 240.174844 -45.692152) (xy 240.09855 -45.685547) (xy 240.023108 -45.672401) (xy 239.949077 -45.652811)
			(xy 239.912906 -45.640244) (xy 239.904469 -45.637593) (xy 239.886799 -45.637593) (xy 239.878362 -45.640244)
			(xy 239.842183 -45.652782) (xy 239.76815 -45.672357) (xy 239.692711 -45.685505) (xy 239.616422 -45.692131)
			(xy 239.578134 -45.692568) (xy 239.539844 -45.692152) (xy 239.46355 -45.685547) (xy 239.388108 -45.672401)
			(xy 239.314077 -45.652811) (xy 239.277906 -45.640244) (xy 239.269469 -45.637593) (xy 239.251799 -45.637593)
			(xy 239.243362 -45.640244) (xy 239.207183 -45.652782) (xy 239.13315 -45.672357) (xy 239.057711 -45.685505)
			(xy 238.981422 -45.692131) (xy 238.943134 -45.692568) (xy 238.903862 -45.692107) (xy 238.825629 -45.685129)
			(xy 238.748316 -45.671276) (xy 238.672527 -45.650657) (xy 238.63554 -45.63745) (xy 238.626991 -45.634686)
			(xy 238.609037 -45.634686) (xy 238.600488 -45.63745) (xy 238.563502 -45.650659) (xy 238.48771 -45.671265)
			(xy 238.410397 -45.685115) (xy 238.332165 -45.692103) (xy 238.292894 -45.692568) (xy 238.24936 -45.692039)
			(xy 238.16271 -45.683524) (xy 238.077306 -45.666586) (xy 237.993965 -45.641387) (xy 237.913484 -45.608168)
			(xy 237.87481 -45.588174) (xy 237.86657 -45.584248) (xy 237.848476 -45.581916) (xy 237.839504 -45.583602)
			(xy 237.790399 -45.594167) (xy 237.690592 -45.6055) (xy 237.640368 -45.606208) (xy 237.640114 -45.606208)
			(xy 237.599001 -45.605674) (xy 237.517127 -45.598088) (xy 237.436301 -45.582981) (xy 237.357214 -45.560481)
			(xy 237.280541 -45.53078) (xy 237.206935 -45.494131) (xy 237.137024 -45.450847) (xy 237.071406 -45.401297)
			(xy 237.010639 -45.345904) (xy 236.955242 -45.285141) (xy 236.905687 -45.219525) (xy 236.862399 -45.149618)
			(xy 236.825745 -45.076014) (xy 236.796038 -44.999343) (xy 236.773533 -44.920257) (xy 236.75842 -44.839433)
			(xy 236.750829 -44.757559) (xy 236.750352 -44.716446) (xy 236.750814 -44.676228) (xy 236.758123 -44.596123)
			(xy 236.772622 -44.517004) (xy 236.794193 -44.439513) (xy 236.80801 -44.40174) (xy 236.811025 -44.392621)
			(xy 236.810769 -44.373433) (xy 236.807502 -44.364402) (xy 236.791394 -44.324025) (xy 236.766206 -44.240819)
			(xy 236.749266 -44.15555) (xy 236.740738 -44.069034) (xy 236.740192 -44.025566) (xy 182.412218 -44.025566)
			(xy 182.41506 -44.035245) (xy 182.422822 -44.089229) (xy 182.423308 -44.116498) (xy 182.423308 -44.980098)
			(xy 182.422822 -45.007367) (xy 182.41506 -45.061351) (xy 182.399695 -45.113681) (xy 182.377038 -45.163291)
			(xy 182.347552 -45.209172) (xy 182.311837 -45.250389) (xy 182.27062 -45.286104) (xy 182.224739 -45.31559)
			(xy 182.175129 -45.338247) (xy 182.122799 -45.353612) (xy 182.068815 -45.361374) (xy 182.014277 -45.361374)
			(xy 181.960293 -45.353612) (xy 181.907963 -45.338247) (xy 181.858353 -45.31559) (xy 181.812472 -45.286104)
			(xy 181.771255 -45.250389) (xy 181.73554 -45.209172) (xy 181.706054 -45.163291) (xy 181.683397 -45.113681)
			(xy 181.668032 -45.061351) (xy 181.66027 -45.007367) (xy 181.659784 -44.980098) (xy 96.555487 -44.980098)
			(xy 96.637446 -45.068647) (xy 96.736452 -45.187325) (xy 96.829216 -45.310943) (xy 96.915495 -45.439171)
			(xy 96.995057 -45.571672) (xy 97.067693 -45.708092) (xy 97.133211 -45.848071) (xy 97.191435 -45.991237)
			(xy 97.242212 -46.13721) (xy 97.285407 -46.285604) (xy 97.320906 -46.436025) (xy 97.329238 -46.481746)
			(xy 178.630072 -46.481746) (xy 178.630072 -45.618146) (xy 178.630558 -45.590877) (xy 178.63832 -45.536893)
			(xy 178.653685 -45.484563) (xy 178.676342 -45.434953) (xy 178.705828 -45.389072) (xy 178.741543 -45.347855)
			(xy 178.78276 -45.31214) (xy 178.828641 -45.282654) (xy 178.878251 -45.259997) (xy 178.930581 -45.244632)
			(xy 178.984565 -45.23687) (xy 179.039103 -45.23687) (xy 179.093087 -45.244632) (xy 179.145417 -45.259997)
			(xy 179.195027 -45.282654) (xy 179.240908 -45.31214) (xy 179.282125 -45.347855) (xy 179.31784 -45.389072)
			(xy 179.347326 -45.434953) (xy 179.369983 -45.484563) (xy 179.385348 -45.536893) (xy 179.39311 -45.590877)
			(xy 179.393596 -45.618146) (xy 179.393596 -46.481746) (xy 179.39311 -46.509015) (xy 179.385348 -46.562999)
			(xy 179.369983 -46.615329) (xy 179.347326 -46.664939) (xy 179.31784 -46.71082) (xy 179.282125 -46.752037)
			(xy 179.240908 -46.787752) (xy 179.195027 -46.817238) (xy 179.145417 -46.839895) (xy 179.093087 -46.85526)
			(xy 179.039103 -46.863022) (xy 178.984565 -46.863022) (xy 178.930581 -46.85526) (xy 178.878251 -46.839895)
			(xy 178.828641 -46.817238) (xy 178.78276 -46.787752) (xy 178.741543 -46.752037) (xy 178.705828 -46.71082)
			(xy 178.676342 -46.664939) (xy 178.653685 -46.615329) (xy 178.63832 -46.562999) (xy 178.630558 -46.509015)
			(xy 178.630072 -46.481746) (xy 97.329238 -46.481746) (xy 97.348615 -46.588073) (xy 97.368459 -46.741347)
			(xy 97.380387 -46.895438) (xy 97.384366 -47.04994) (xy 97.380387 -47.204442) (xy 97.368459 -47.358533)
			(xy 97.348615 -47.511807) (xy 97.320906 -47.663855) (xy 97.285407 -47.814276) (xy 97.242212 -47.96267)
			(xy 97.219453 -48.028098) (xy 181.659784 -48.028098) (xy 181.659784 -47.164498) (xy 181.66027 -47.137229)
			(xy 181.668032 -47.083245) (xy 181.683397 -47.030915) (xy 181.706054 -46.981305) (xy 181.73554 -46.935424)
			(xy 181.771255 -46.894207) (xy 181.812472 -46.858492) (xy 181.858353 -46.829006) (xy 181.907963 -46.806349)
			(xy 181.960293 -46.790984) (xy 182.014277 -46.783222) (xy 182.068815 -46.783222) (xy 182.122799 -46.790984)
			(xy 182.175129 -46.806349) (xy 182.224739 -46.829006) (xy 182.27062 -46.858492) (xy 182.311837 -46.894207)
			(xy 182.347552 -46.935424) (xy 182.377038 -46.981305) (xy 182.399695 -47.030915) (xy 182.41506 -47.083245)
			(xy 182.422822 -47.137229) (xy 182.423308 -47.164498) (xy 182.423308 -48.028098) (xy 182.422822 -48.055367)
			(xy 182.41506 -48.109351) (xy 182.399695 -48.161681) (xy 182.377038 -48.211291) (xy 182.347552 -48.257172)
			(xy 182.311837 -48.298389) (xy 182.27062 -48.334104) (xy 182.224739 -48.36359) (xy 182.175129 -48.386247)
			(xy 182.122799 -48.401612) (xy 182.068815 -48.409374) (xy 182.014277 -48.409374) (xy 181.960293 -48.401612)
			(xy 181.907963 -48.386247) (xy 181.858353 -48.36359) (xy 181.812472 -48.334104) (xy 181.771255 -48.298389)
			(xy 181.73554 -48.257172) (xy 181.706054 -48.211291) (xy 181.683397 -48.161681) (xy 181.668032 -48.109351)
			(xy 181.66027 -48.055367) (xy 181.659784 -48.028098) (xy 97.219453 -48.028098) (xy 97.191435 -48.108643)
			(xy 97.133211 -48.251809) (xy 97.067693 -48.391788) (xy 96.995057 -48.528208) (xy 96.915495 -48.660709)
			(xy 96.829216 -48.788937) (xy 96.736452 -48.912555) (xy 96.637446 -49.031233) (xy 96.532463 -49.144657)
			(xy 96.421779 -49.252526) (xy 96.30569 -49.354554) (xy 96.184502 -49.450471) (xy 96.140518 -49.48174)
			(xy 178.630072 -49.48174) (xy 178.630072 -48.61814) (xy 178.630558 -48.590871) (xy 178.63832 -48.536887)
			(xy 178.653685 -48.484557) (xy 178.676342 -48.434947) (xy 178.705828 -48.389066) (xy 178.741543 -48.347849)
			(xy 178.78276 -48.312134) (xy 178.828641 -48.282648) (xy 178.878251 -48.259991) (xy 178.930581 -48.244626)
			(xy 178.984565 -48.236864) (xy 179.039103 -48.236864) (xy 179.093087 -48.244626) (xy 179.145417 -48.259991)
			(xy 179.195027 -48.282648) (xy 179.240908 -48.312134) (xy 179.282125 -48.347849) (xy 179.31784 -48.389066)
			(xy 179.347326 -48.434947) (xy 179.369983 -48.484557) (xy 179.385348 -48.536887) (xy 179.39311 -48.590871)
			(xy 179.393596 -48.61814) (xy 179.393596 -49.48174) (xy 179.39311 -49.509009) (xy 179.385348 -49.562993)
			(xy 179.369983 -49.615323) (xy 179.347326 -49.664933) (xy 179.31784 -49.710814) (xy 179.282125 -49.752031)
			(xy 179.240908 -49.787746) (xy 179.195027 -49.817232) (xy 179.145417 -49.839889) (xy 179.093087 -49.855254)
			(xy 179.039103 -49.863016) (xy 178.984565 -49.863016) (xy 178.930581 -49.855254) (xy 178.878251 -49.839889)
			(xy 178.828641 -49.817232) (xy 178.78276 -49.787746) (xy 178.741543 -49.752031) (xy 178.705828 -49.710814)
			(xy 178.676342 -49.664933) (xy 178.653685 -49.615323) (xy 178.63832 -49.562993) (xy 178.630558 -49.509009)
			(xy 178.630072 -49.48174) (xy 96.140518 -49.48174) (xy 96.058537 -49.540022) (xy 95.928129 -49.62297)
			(xy 95.793624 -49.699095) (xy 95.655379 -49.768194) (xy 95.513759 -49.830085) (xy 95.369142 -49.884604)
			(xy 95.221909 -49.931606) (xy 95.072452 -49.970966) (xy 94.921168 -50.00258) (xy 94.768456 -50.026364)
			(xy 94.614722 -50.042255) (xy 94.460374 -50.050211) (xy 94.383098 -50.0507) (xy 92.782898 -50.0507)
			(xy 92.705622 -50.050194) (xy 92.551275 -50.042238) (xy 92.397543 -50.026347) (xy 92.244832 -50.002563)
			(xy 92.093548 -49.970949) (xy 91.944092 -49.931589) (xy 91.796861 -49.884587) (xy 91.652244 -49.830069)
			(xy 91.510626 -49.768178) (xy 91.372381 -49.699079) (xy 91.237877 -49.622954) (xy 91.10747 -49.540007)
			(xy 90.981506 -49.450456) (xy 90.860319 -49.35454) (xy 90.74423 -49.252512) (xy 90.633548 -49.144644)
			(xy 90.528565 -49.031221) (xy 90.42956 -48.912543) (xy 90.336796 -48.788927) (xy 90.250519 -48.660699)
			(xy 90.170957 -48.528199) (xy 90.098321 -48.391779) (xy 90.032804 -48.251802) (xy 89.97458 -48.108637)
			(xy 89.923803 -47.962664) (xy 89.880608 -47.814271) (xy 89.84511 -47.663852) (xy 89.817402 -47.511804)
			(xy 89.797557 -47.358531) (xy 89.78563 -47.204441) (xy 89.78165 -47.04994) (xy 67.583802 -47.04994)
			(xy 67.579823 -47.209492) (xy 67.567896 -47.368647) (xy 67.54805 -47.527009) (xy 67.520336 -47.684186)
			(xy 67.484821 -47.839786) (xy 67.441595 -47.993422) (xy 67.390764 -48.144712) (xy 67.332455 -48.293281)
			(xy 67.266813 -48.438758) (xy 67.194001 -48.580783) (xy 67.114201 -48.719002) (xy 67.02761 -48.853071)
			(xy 66.934444 -48.982657) (xy 66.834934 -49.107438) (xy 66.729328 -49.227105) (xy 66.617889 -49.341358)
			(xy 66.500893 -49.449914) (xy 66.378631 -49.552504) (xy 66.251408 -49.648872) (xy 66.119539 -49.738779)
			(xy 65.983353 -49.822001) (xy 65.843188 -49.898331) (xy 65.699392 -49.967579) (xy 65.552323 -50.029574)
			(xy 65.402347 -50.084161) (xy 65.249837 -50.131205) (xy 65.095171 -50.170587) (xy 64.938734 -50.202212)
			(xy 64.780916 -50.226) (xy 64.622107 -50.241891) (xy 64.462705 -50.249847) (xy 64.382904 -50.250344)
			(xy 62.782958 -50.250344) (xy 62.703158 -50.249839) (xy 62.543755 -50.241883) (xy 62.384947 -50.225992)
			(xy 62.227129 -50.202204) (xy 62.070693 -50.17058) (xy 61.916027 -50.131197) (xy 61.763517 -50.084154)
			(xy 61.613541 -50.029567) (xy 61.466472 -49.967573) (xy 61.322677 -49.898324) (xy 61.182512 -49.821994)
			(xy 61.046326 -49.738773) (xy 60.914458 -49.648866) (xy 60.787235 -49.552499) (xy 60.664973 -49.449909)
			(xy 60.547978 -49.341353) (xy 60.436538 -49.2271) (xy 60.330933 -49.107434) (xy 60.231423 -48.982653)
			(xy 60.138257 -48.853067) (xy 60.051666 -48.718998) (xy 59.971866 -48.580779) (xy 59.899054 -48.438755)
			(xy 59.833413 -48.293278) (xy 59.775104 -48.14471) (xy 59.724273 -47.99342) (xy 59.681047 -47.839784)
			(xy 59.645532 -47.684184) (xy 59.617818 -47.527008) (xy 59.597972 -47.368646) (xy 59.586045 -47.209491)
			(xy 59.582066 -47.04994) (xy 0.509016 -47.04994) (xy 0.509016 -50.949098) (xy 181.659784 -50.949098)
			(xy 181.659784 -50.085498) (xy 181.66027 -50.058229) (xy 181.668032 -50.004245) (xy 181.683397 -49.951915)
			(xy 181.706054 -49.902305) (xy 181.73554 -49.856424) (xy 181.771255 -49.815207) (xy 181.812472 -49.779492)
			(xy 181.858353 -49.750006) (xy 181.907963 -49.727349) (xy 181.960293 -49.711984) (xy 182.014277 -49.704222)
			(xy 182.068815 -49.704222) (xy 182.122799 -49.711984) (xy 182.175129 -49.727349) (xy 182.224739 -49.750006)
			(xy 182.27062 -49.779492) (xy 182.311837 -49.815207) (xy 182.347552 -49.856424) (xy 182.377038 -49.902305)
			(xy 182.399695 -49.951915) (xy 182.41506 -50.004245) (xy 182.422822 -50.058229) (xy 182.423308 -50.085498)
			(xy 182.423308 -50.949098) (xy 182.422822 -50.976367) (xy 182.41506 -51.030351) (xy 182.399695 -51.082681)
			(xy 182.377038 -51.132291) (xy 182.347552 -51.178172) (xy 182.311837 -51.219389) (xy 182.27062 -51.255104)
			(xy 182.224739 -51.28459) (xy 182.175129 -51.307247) (xy 182.122799 -51.322612) (xy 182.068815 -51.330374)
			(xy 182.014277 -51.330374) (xy 181.960293 -51.322612) (xy 181.907963 -51.307247) (xy 181.858353 -51.28459)
			(xy 181.812472 -51.255104) (xy 181.771255 -51.219389) (xy 181.73554 -51.178172) (xy 181.706054 -51.132291)
			(xy 181.683397 -51.082681) (xy 181.668032 -51.030351) (xy 181.66027 -50.976367) (xy 181.659784 -50.949098)
			(xy 0.509016 -50.949098) (xy 0.509016 -52.481734) (xy 178.630072 -52.481734) (xy 178.630072 -51.618134)
			(xy 178.630558 -51.590865) (xy 178.63832 -51.536881) (xy 178.653685 -51.484551) (xy 178.676342 -51.434941)
			(xy 178.705828 -51.38906) (xy 178.741543 -51.347843) (xy 178.78276 -51.312128) (xy 178.828641 -51.282642)
			(xy 178.878251 -51.259985) (xy 178.930581 -51.24462) (xy 178.984565 -51.236858) (xy 179.039103 -51.236858)
			(xy 179.093087 -51.24462) (xy 179.145417 -51.259985) (xy 179.195027 -51.282642) (xy 179.240908 -51.312128)
			(xy 179.282125 -51.347843) (xy 179.31784 -51.38906) (xy 179.347326 -51.434941) (xy 179.369983 -51.484551)
			(xy 179.385348 -51.536881) (xy 179.39311 -51.590865) (xy 179.393596 -51.618134) (xy 179.393596 -51.999896)
			(xy 201.367397 -51.999896) (xy 201.371407 -51.837793) (xy 201.38343 -51.676088) (xy 201.403434 -51.515174)
			(xy 201.431372 -51.355447) (xy 201.467175 -51.197297) (xy 201.510755 -51.041111) (xy 201.562006 -50.887271)
			(xy 201.620802 -50.736154) (xy 201.687 -50.58813) (xy 201.760436 -50.44356) (xy 201.840933 -50.302799)
			(xy 201.928292 -50.166191) (xy 202.0223 -50.034071) (xy 202.122727 -49.906761) (xy 202.229327 -49.784573)
			(xy 202.341839 -49.667807) (xy 202.459987 -49.556748) (xy 202.583484 -49.451667) (xy 202.712026 -49.352823)
			(xy 202.845299 -49.260456) (xy 202.982977 -49.174793) (xy 203.124723 -49.096044) (xy 203.27019 -49.024401)
			(xy 203.419022 -48.960039) (xy 203.570854 -48.903117) (xy 203.725316 -48.853773) (xy 203.882029 -48.812128)
			(xy 204.04061 -48.778283) (xy 204.200671 -48.752323) (xy 204.361819 -48.73431) (xy 204.523661 -48.724289)
			(xy 204.685801 -48.722283) (xy 204.847842 -48.728299) (xy 205.009386 -48.74232) (xy 205.17004 -48.764313)
			(xy 205.32941 -48.794225) (xy 205.487105 -48.831981) (xy 205.64274 -48.877489) (xy 205.795934 -48.930639)
			(xy 205.946312 -48.9913) (xy 206.093507 -49.059323) (xy 206.237157 -49.134542) (xy 206.376912 -49.216773)
			(xy 206.512428 -49.305815) (xy 206.643376 -49.40145) (xy 206.769434 -49.503444) (xy 206.890294 -49.611547)
			(xy 207.00566 -49.725494) (xy 207.115249 -49.845008) (xy 207.218794 -49.969795) (xy 207.316041 -50.09955)
			(xy 207.406753 -50.233955) (xy 207.490706 -50.372682) (xy 207.567696 -50.515391) (xy 207.637535 -50.661732)
			(xy 207.70005 -50.811349) (xy 207.755091 -50.963874) (xy 207.802521 -51.118934) (xy 207.842224 -51.27615)
			(xy 207.874105 -51.435138) (xy 207.898083 -51.595507) (xy 207.914102 -51.756866) (xy 207.922121 -51.91882)
			(xy 207.922622 -51.999896) (xy 207.922121 -52.080972) (xy 207.921092 -52.10175) (xy 244.67947 -52.10175)
			(xy 244.679975 -52.075243) (xy 244.687334 -52.022743) (xy 244.701889 -51.971767) (xy 244.723361 -51.923297)
			(xy 244.751335 -51.878265) (xy 244.785274 -51.837539) (xy 244.824523 -51.801903) (xy 244.868327 -51.772043)
			(xy 244.915843 -51.748534) (xy 244.966156 -51.731829) (xy 244.992144 -51.726592) (xy 245.000543 -51.724726)
			(xy 245.015476 -51.716197) (xy 245.026755 -51.703216) (xy 245.030244 -51.69535) (xy 245.045663 -51.657494)
			(xy 245.082559 -51.584546) (xy 245.125992 -51.515291) (xy 245.175596 -51.450313) (xy 245.230952 -51.39016)
			(xy 245.291595 -51.335341) (xy 245.357011 -51.286316) (xy 245.426649 -51.2435) (xy 245.499922 -51.207254)
			(xy 245.576211 -51.177884) (xy 245.654873 -51.155637) (xy 245.735245 -51.140701) (xy 245.816648 -51.133203)
			(xy 245.857522 -51.13274) (xy 245.899843 -51.133258) (xy 245.984099 -51.14133) (xy 246.067208 -51.157371)
			(xy 246.148416 -51.181236) (xy 246.226989 -51.212708) (xy 246.302217 -51.251503) (xy 246.33809 -51.273964)
			(xy 246.346484 -51.278827) (xy 246.365522 -51.28248) (xy 246.38456 -51.278827) (xy 246.392954 -51.273964)
			(xy 246.42883 -51.25151) (xy 246.504063 -51.212731) (xy 246.582638 -51.181268) (xy 246.663845 -51.157405)
			(xy 246.74695 -51.141356) (xy 246.831202 -51.133268) (xy 246.873522 -51.13274) (xy 246.926862 -51.134518)
			(xy 246.938638 -51.134618) (xy 246.960306 -51.125466) (xy 246.975671 -51.107657) (xy 246.979186 -51.096418)
			(xy 246.990138 -51.056039) (xy 247.018713 -50.977397) (xy 247.054545 -50.901785) (xy 247.097317 -50.829872)
			(xy 247.146653 -50.762292) (xy 247.202115 -50.699642) (xy 247.263214 -50.642477) (xy 247.329411 -50.5913)
			(xy 247.40012 -50.546564) (xy 247.474717 -50.508665) (xy 247.552542 -50.477936) (xy 247.632909 -50.45465)
			(xy 247.715107 -50.439012) (xy 247.79841 -50.431161) (xy 247.840246 -50.430684) (xy 247.883752 -50.431235)
			(xy 247.970347 -50.439729) (xy 248.055699 -50.456641) (xy 248.138991 -50.481809) (xy 248.219426 -50.514992)
			(xy 248.296235 -50.555874) (xy 248.332752 -50.579528) (xy 248.341308 -50.584744) (xy 248.360946 -50.588653)
			(xy 248.380584 -50.584744) (xy 248.38914 -50.579528) (xy 248.425663 -50.555885) (xy 248.50248 -50.515022)
			(xy 248.582916 -50.481847) (xy 248.666204 -50.456676) (xy 248.751551 -50.439749) (xy 248.838142 -50.431227)
			(xy 248.881646 -50.430684) (xy 248.926403 -50.431259) (xy 249.015462 -50.440266) (xy 249.103167 -50.458165)
			(xy 249.188634 -50.484775) (xy 249.270999 -50.519828) (xy 249.349431 -50.562968) (xy 249.386598 -50.58791)
			(xy 249.394939 -50.593062) (xy 249.414052 -50.597328) (xy 249.433374 -50.594144) (xy 249.44197 -50.589434)
			(xy 249.4758 -50.569354) (xy 249.546346 -50.534523) (xy 249.619688 -50.506051) (xy 249.695257 -50.484158)
			(xy 249.772462 -50.469016) (xy 249.850701 -50.460742) (xy 249.890026 -50.45964) (xy 249.889772 -50.4444)
			(xy 249.889772 -50.443892) (xy 249.89024 -50.405527) (xy 249.896983 -50.329093) (xy 249.903234 -50.291238)
			(xy 249.904413 -50.282319) (xy 249.901131 -50.26464) (xy 249.891952 -50.249179) (xy 249.8852 -50.243232)
			(xy 249.851748 -50.215094) (xy 249.789907 -50.153305) (xy 249.734424 -50.08575) (xy 249.685833 -50.01308)
			(xy 249.644603 -49.935995) (xy 249.61113 -49.855239) (xy 249.585738 -49.771589) (xy 249.568671 -49.685852)
			(xy 249.560094 -49.598855) (xy 249.559572 -49.555146) (xy 249.560076 -49.512785) (xy 249.568129 -49.428448)
			(xy 249.584163 -49.345258) (xy 249.608031 -49.263968) (xy 249.639519 -49.185316) (xy 249.678341 -49.110013)
			(xy 249.724144 -49.038741) (xy 249.776515 -48.972145) (xy 249.83498 -48.91083) (xy 249.899008 -48.855349)
			(xy 249.96802 -48.806206) (xy 250.04139 -48.763846) (xy 250.118455 -48.728651) (xy 250.198517 -48.700942)
			(xy 250.28085 -48.680968) (xy 250.364709 -48.668911) (xy 250.449334 -48.66488) (xy 250.533959 -48.668911)
			(xy 250.617818 -48.680968) (xy 250.700151 -48.700942) (xy 250.780213 -48.728651) (xy 250.857278 -48.763846)
			(xy 250.930648 -48.806206) (xy 250.99966 -48.855349) (xy 251.063688 -48.91083) (xy 251.122153 -48.972145)
			(xy 251.174524 -49.038741) (xy 251.220327 -49.110013) (xy 251.259149 -49.185316) (xy 251.290637 -49.263968)
			(xy 251.314505 -49.345258) (xy 251.330539 -49.428448) (xy 251.338592 -49.512785) (xy 251.339096 -49.555146)
			(xy 251.338636 -49.593574) (xy 251.331894 -49.670136) (xy 251.325634 -49.708054) (xy 251.324473 -49.716974)
			(xy 251.32775 -49.73465) (xy 251.336921 -49.750111) (xy 251.343668 -49.75606) (xy 251.362142 -49.771471)
			(xy 251.397596 -49.803999) (xy 251.414534 -49.821084) (xy 251.422676 -49.828571) (xy 251.443355 -49.836348)
			(xy 251.454412 -49.83607) (xy 251.469822 -49.835031) (xy 251.50069 -49.833886) (xy 251.516134 -49.833784)
			(xy 251.557251 -49.834166) (xy 251.639133 -49.841757) (xy 251.719966 -49.85687) (xy 251.79906 -49.879378)
			(xy 251.875739 -49.909087) (xy 251.94935 -49.945745) (xy 252.019265 -49.989039) (xy 252.084886 -50.038598)
			(xy 252.145655 -50.094001) (xy 252.201053 -50.154775) (xy 252.250607 -50.220401) (xy 252.293894 -50.29032)
			(xy 252.330545 -50.363934) (xy 252.360248 -50.440616) (xy 252.382748 -50.519712) (xy 252.397854 -50.600546)
			(xy 252.405438 -50.682429) (xy 252.405896 -50.723546) (xy 252.405358 -50.767341) (xy 252.396743 -50.854506)
			(xy 252.379599 -50.940401) (xy 252.354094 -51.024196) (xy 252.320474 -51.105076) (xy 252.300232 -51.143916)
			(xy 252.29478 -51.15537) (xy 252.2948 -51.18071) (xy 252.300232 -51.192176) (xy 252.320452 -51.231026)
			(xy 252.354062 -51.311909) (xy 252.379567 -51.3957) (xy 252.39672 -51.481592) (xy 252.405355 -51.568752)
			(xy 252.405896 -51.612546) (xy 252.405358 -51.656341) (xy 252.396743 -51.743506) (xy 252.379599 -51.829401)
			(xy 252.354094 -51.913196) (xy 252.320474 -51.994076) (xy 252.317441 -51.999896) (xy 265.367523 -51.999896)
			(xy 265.371533 -51.837793) (xy 265.383556 -51.676088) (xy 265.40356 -51.515174) (xy 265.431498 -51.355447)
			(xy 265.467301 -51.197297) (xy 265.510881 -51.041111) (xy 265.562132 -50.887271) (xy 265.620928 -50.736154)
			(xy 265.687126 -50.58813) (xy 265.760562 -50.44356) (xy 265.841059 -50.302799) (xy 265.928418 -50.166191)
			(xy 266.022426 -50.034071) (xy 266.122853 -49.906761) (xy 266.229453 -49.784573) (xy 266.341965 -49.667807)
			(xy 266.460113 -49.556748) (xy 266.58361 -49.451667) (xy 266.712152 -49.352823) (xy 266.845425 -49.260456)
			(xy 266.983103 -49.174793) (xy 267.124849 -49.096044) (xy 267.270316 -49.024401) (xy 267.419148 -48.960039)
			(xy 267.57098 -48.903117) (xy 267.725442 -48.853773) (xy 267.882155 -48.812128) (xy 268.040736 -48.778283)
			(xy 268.200797 -48.752323) (xy 268.361945 -48.73431) (xy 268.523787 -48.724289) (xy 268.685927 -48.722283)
			(xy 268.847968 -48.728299) (xy 269.009512 -48.74232) (xy 269.170166 -48.764313) (xy 269.329536 -48.794225)
			(xy 269.487231 -48.831981) (xy 269.642866 -48.877489) (xy 269.79606 -48.930639) (xy 269.946438 -48.9913)
			(xy 270.093633 -49.059323) (xy 270.237283 -49.134542) (xy 270.377038 -49.216773) (xy 270.512554 -49.305815)
			(xy 270.643502 -49.40145) (xy 270.76956 -49.503444) (xy 270.89042 -49.611547) (xy 271.005786 -49.725494)
			(xy 271.115375 -49.845008) (xy 271.21892 -49.969795) (xy 271.316167 -50.09955) (xy 271.406879 -50.233955)
			(xy 271.490832 -50.372682) (xy 271.567822 -50.515391) (xy 271.637661 -50.661732) (xy 271.700176 -50.811349)
			(xy 271.755217 -50.963874) (xy 271.802647 -51.118934) (xy 271.84235 -51.27615) (xy 271.874231 -51.435138)
			(xy 271.898209 -51.595507) (xy 271.914228 -51.756866) (xy 271.922247 -51.91882) (xy 271.922748 -51.999896)
			(xy 271.922247 -52.080972) (xy 271.914228 -52.242926) (xy 271.898209 -52.404285) (xy 271.874231 -52.564654)
			(xy 271.84235 -52.723642) (xy 271.802647 -52.880858) (xy 271.755217 -53.035918) (xy 271.700176 -53.188443)
			(xy 271.637661 -53.33806) (xy 271.567822 -53.484401) (xy 271.490832 -53.62711) (xy 271.406879 -53.765837)
			(xy 271.316167 -53.900242) (xy 271.21892 -54.029997) (xy 271.115375 -54.154784) (xy 271.005786 -54.274298)
			(xy 270.89042 -54.388245) (xy 270.76956 -54.496348) (xy 270.643502 -54.598342) (xy 270.512554 -54.693977)
			(xy 270.377038 -54.783019) (xy 270.237283 -54.86525) (xy 270.093633 -54.940469) (xy 269.946438 -55.008492)
			(xy 269.79606 -55.069153) (xy 269.642866 -55.122303) (xy 269.487231 -55.167811) (xy 269.329536 -55.205567)
			(xy 269.170166 -55.235479) (xy 269.009512 -55.257472) (xy 268.847968 -55.271493) (xy 268.685927 -55.277509)
			(xy 268.523787 -55.275503) (xy 268.361945 -55.265482) (xy 268.200797 -55.247469) (xy 268.040736 -55.221509)
			(xy 267.882155 -55.187664) (xy 267.725442 -55.146019) (xy 267.57098 -55.096675) (xy 267.419148 -55.039753)
			(xy 267.270316 -54.975391) (xy 267.124849 -54.903748) (xy 266.983103 -54.824999) (xy 266.845425 -54.739336)
			(xy 266.712152 -54.646969) (xy 266.58361 -54.548125) (xy 266.460113 -54.443044) (xy 266.341965 -54.331985)
			(xy 266.229453 -54.215219) (xy 266.122853 -54.093031) (xy 266.022426 -53.965721) (xy 265.928418 -53.833601)
			(xy 265.841059 -53.696993) (xy 265.760562 -53.556232) (xy 265.687126 -53.411662) (xy 265.620928 -53.263638)
			(xy 265.562132 -53.112521) (xy 265.510881 -52.958681) (xy 265.467301 -52.802495) (xy 265.431498 -52.644345)
			(xy 265.40356 -52.484618) (xy 265.383556 -52.323704) (xy 265.371533 -52.161999) (xy 265.367523 -51.999896)
			(xy 252.317441 -51.999896) (xy 252.300232 -52.032916) (xy 252.29478 -52.04437) (xy 252.2948 -52.06971)
			(xy 252.300232 -52.081176) (xy 252.320452 -52.120026) (xy 252.354062 -52.200909) (xy 252.379567 -52.2847)
			(xy 252.39672 -52.370592) (xy 252.405355 -52.457752) (xy 252.405896 -52.501546) (xy 252.405431 -52.54266)
			(xy 252.39784 -52.624537) (xy 252.382728 -52.705364) (xy 252.360222 -52.784452) (xy 252.330515 -52.861127)
			(xy 252.293861 -52.934733) (xy 252.250573 -53.004644) (xy 252.201018 -53.070263) (xy 252.145621 -53.131029)
			(xy 252.084853 -53.186426) (xy 252.019234 -53.235979) (xy 251.949323 -53.279267) (xy 251.875716 -53.31592)
			(xy 251.799041 -53.345626) (xy 251.719952 -53.36813) (xy 251.639125 -53.383242) (xy 251.557248 -53.390832)
			(xy 251.516134 -53.391308) (xy 251.471924 -53.390745) (xy 251.383942 -53.381965) (xy 251.297264 -53.3645)
			(xy 251.212747 -53.33852) (xy 251.131225 -53.304282) (xy 251.053503 -53.262125) (xy 250.980346 -53.212465)
			(xy 250.912478 -53.15579) (xy 250.881134 -53.124608) (xy 250.873005 -53.117104) (xy 250.852316 -53.109337)
			(xy 250.841256 -53.109622) (xy 250.825846 -53.110663) (xy 250.794978 -53.111806) (xy 250.779534 -53.111908)
			(xy 250.737779 -53.111492) (xy 250.654637 -53.103677) (xy 250.572592 -53.088104) (xy 250.492369 -53.064909)
			(xy 250.414673 -53.034297) (xy 250.340188 -52.996537) (xy 250.269571 -52.951961) (xy 250.203442 -52.900963)
			(xy 250.142385 -52.843991) (xy 250.086937 -52.781547) (xy 250.037585 -52.714181) (xy 249.994765 -52.642486)
			(xy 249.958854 -52.567092) (xy 249.930167 -52.488665) (xy 249.908958 -52.407894) (xy 249.895413 -52.32549)
			(xy 249.892058 -52.283868) (xy 249.891061 -52.274773) (xy 249.88348 -52.258135) (xy 249.870549 -52.245209)
			(xy 249.853908 -52.237634) (xy 249.844814 -52.236624) (xy 249.805225 -52.23352) (xy 249.726783 -52.221122)
			(xy 249.649759 -52.201775) (xy 249.574769 -52.175634) (xy 249.50241 -52.142907) (xy 249.433259 -52.103855)
			(xy 249.400314 -52.081684) (xy 249.392012 -52.076461) (xy 249.372875 -52.072218) (xy 249.353539 -52.075433)
			(xy 249.344942 -52.08016) (xy 249.312459 -52.099495) (xy 249.244799 -52.133223) (xy 249.174522 -52.161088)
			(xy 249.13844 -52.172362) (xy 249.128616 -52.175851) (xy 249.112727 -52.189319) (xy 249.103444 -52.207965)
			(xy 249.102372 -52.218336) (xy 249.099675 -52.260463) (xy 249.087279 -52.34397) (xy 249.067027 -52.425926)
			(xy 249.039099 -52.505595) (xy 249.003748 -52.582258) (xy 248.961291 -52.655227) (xy 248.912112 -52.723845)
			(xy 248.856651 -52.787493) (xy 248.795409 -52.8456) (xy 248.728936 -52.897642) (xy 248.657831 -52.943151)
			(xy 248.582733 -52.981717) (xy 248.504319 -53.012994) (xy 248.423294 -53.036699) (xy 248.340387 -53.052621)
			(xy 248.256345 -53.060614) (xy 248.214134 -53.061108) (xy 248.171669 -53.060607) (xy 248.087125 -53.052507)
			(xy 248.003739 -53.036385) (xy 247.922268 -53.01239) (xy 247.843456 -52.98074) (xy 247.768018 -52.941722)
			(xy 247.696643 -52.895693) (xy 247.629979 -52.84307) (xy 247.568634 -52.784334) (xy 247.540526 -52.752498)
			(xy 247.534176 -52.745132) (xy 247.517412 -52.736496) (xy 247.429274 -52.726336) (xy 247.410986 -52.731416)
			(xy 247.403112 -52.737258) (xy 247.370277 -52.761024) (xy 247.301045 -52.803187) (xy 247.228263 -52.838875)
			(xy 247.152535 -52.867791) (xy 247.07449 -52.889697) (xy 246.994775 -52.904409) (xy 246.914052 -52.911805)
			(xy 246.873522 -52.912264) (xy 246.831202 -52.911724) (xy 246.746946 -52.903656) (xy 246.663838 -52.887619)
			(xy 246.58263 -52.863758) (xy 246.504056 -52.83229) (xy 246.428827 -52.793499) (xy 246.392954 -52.77104)
			(xy 246.38456 -52.766177) (xy 246.365522 -52.762524) (xy 246.346484 -52.766177) (xy 246.33809 -52.77104)
			(xy 246.302222 -52.793507) (xy 246.226987 -52.832285) (xy 246.148411 -52.863747) (xy 246.067203 -52.887609)
			(xy 245.984096 -52.903654) (xy 245.899842 -52.911738) (xy 245.857522 -52.912264) (xy 245.813221 -52.911666)
			(xy 245.725058 -52.90285) (xy 245.638208 -52.885314) (xy 245.553531 -52.85923) (xy 245.471867 -52.824858)
			(xy 245.394025 -52.782538) (xy 245.320775 -52.732689) (xy 245.252843 -52.675806) (xy 245.190903 -52.61245)
			(xy 245.135568 -52.543252) (xy 245.111016 -52.506372) (xy 245.106055 -52.499361) (xy 245.092457 -52.488884)
			(xy 245.076169 -52.483465) (xy 245.067582 -52.483258) (xy 245.060978 -52.483258) (xy 245.033722 -52.482865)
			(xy 244.979766 -52.475104) (xy 244.927464 -52.459743) (xy 244.87788 -52.437094) (xy 244.832025 -52.407619)
			(xy 244.790831 -52.371918) (xy 244.755138 -52.330717) (xy 244.725671 -52.284856) (xy 244.703032 -52.235269)
			(xy 244.68768 -52.182963) (xy 244.679929 -52.129006) (xy 244.67947 -52.10175) (xy 207.921092 -52.10175)
			(xy 207.914102 -52.242926) (xy 207.898083 -52.404285) (xy 207.874105 -52.564654) (xy 207.842224 -52.723642)
			(xy 207.802521 -52.880858) (xy 207.755091 -53.035918) (xy 207.70005 -53.188443) (xy 207.637535 -53.33806)
			(xy 207.567696 -53.484401) (xy 207.490706 -53.62711) (xy 207.406753 -53.765837) (xy 207.316041 -53.900242)
			(xy 207.218794 -54.029997) (xy 207.115249 -54.154784) (xy 207.00566 -54.274298) (xy 206.890294 -54.388245)
			(xy 206.769434 -54.496348) (xy 206.643376 -54.598342) (xy 206.512428 -54.693977) (xy 206.376912 -54.783019)
			(xy 206.237157 -54.86525) (xy 206.093507 -54.940469) (xy 205.946312 -55.008492) (xy 205.795934 -55.069153)
			(xy 205.64274 -55.122303) (xy 205.487105 -55.167811) (xy 205.32941 -55.205567) (xy 205.17004 -55.235479)
			(xy 205.009386 -55.257472) (xy 204.847842 -55.271493) (xy 204.685801 -55.277509) (xy 204.523661 -55.275503)
			(xy 204.361819 -55.265482) (xy 204.200671 -55.247469) (xy 204.04061 -55.221509) (xy 203.882029 -55.187664)
			(xy 203.725316 -55.146019) (xy 203.570854 -55.096675) (xy 203.419022 -55.039753) (xy 203.27019 -54.975391)
			(xy 203.124723 -54.903748) (xy 202.982977 -54.824999) (xy 202.845299 -54.739336) (xy 202.712026 -54.646969)
			(xy 202.583484 -54.548125) (xy 202.459987 -54.443044) (xy 202.341839 -54.331985) (xy 202.229327 -54.215219)
			(xy 202.122727 -54.093031) (xy 202.0223 -53.965721) (xy 201.928292 -53.833601) (xy 201.840933 -53.696993)
			(xy 201.760436 -53.556232) (xy 201.687 -53.411662) (xy 201.620802 -53.263638) (xy 201.562006 -53.112521)
			(xy 201.510755 -52.958681) (xy 201.467175 -52.802495) (xy 201.431372 -52.644345) (xy 201.403434 -52.484618)
			(xy 201.38343 -52.323704) (xy 201.371407 -52.161999) (xy 201.367397 -51.999896) (xy 179.393596 -51.999896)
			(xy 179.393596 -52.481734) (xy 179.39311 -52.509003) (xy 179.385348 -52.562987) (xy 179.369983 -52.615317)
			(xy 179.347326 -52.664927) (xy 179.31784 -52.710808) (xy 179.282125 -52.752025) (xy 179.240908 -52.78774)
			(xy 179.195027 -52.817226) (xy 179.145417 -52.839883) (xy 179.093087 -52.855248) (xy 179.039103 -52.86301)
			(xy 178.984565 -52.86301) (xy 178.930581 -52.855248) (xy 178.878251 -52.839883) (xy 178.828641 -52.817226)
			(xy 178.78276 -52.78774) (xy 178.741543 -52.752025) (xy 178.705828 -52.710808) (xy 178.676342 -52.664927)
			(xy 178.653685 -52.615317) (xy 178.63832 -52.562987) (xy 178.630558 -52.509003) (xy 178.630072 -52.481734)
			(xy 0.509016 -52.481734) (xy 0.509016 -53.954934) (xy 181.659784 -53.954934) (xy 181.659784 -53.091334)
			(xy 181.66027 -53.064065) (xy 181.668032 -53.010081) (xy 181.683397 -52.957751) (xy 181.706054 -52.908141)
			(xy 181.73554 -52.86226) (xy 181.771255 -52.821043) (xy 181.812472 -52.785328) (xy 181.858353 -52.755842)
			(xy 181.907963 -52.733185) (xy 181.960293 -52.71782) (xy 182.014277 -52.710058) (xy 182.068815 -52.710058)
			(xy 182.122799 -52.71782) (xy 182.175129 -52.733185) (xy 182.224739 -52.755842) (xy 182.27062 -52.785328)
			(xy 182.311837 -52.821043) (xy 182.347552 -52.86226) (xy 182.377038 -52.908141) (xy 182.399695 -52.957751)
			(xy 182.41506 -53.010081) (xy 182.422822 -53.064065) (xy 182.423308 -53.091334) (xy 182.423308 -53.954934)
			(xy 182.422822 -53.982203) (xy 182.41506 -54.036187) (xy 182.399695 -54.088517) (xy 182.377038 -54.138127)
			(xy 182.347552 -54.184008) (xy 182.311837 -54.225225) (xy 182.27062 -54.26094) (xy 182.224739 -54.290426)
			(xy 182.175129 -54.313083) (xy 182.122799 -54.328448) (xy 182.068815 -54.33621) (xy 182.014277 -54.33621)
			(xy 181.960293 -54.328448) (xy 181.907963 -54.313083) (xy 181.858353 -54.290426) (xy 181.812472 -54.26094)
			(xy 181.771255 -54.225225) (xy 181.73554 -54.184008) (xy 181.706054 -54.138127) (xy 181.683397 -54.088517)
			(xy 181.668032 -54.036187) (xy 181.66027 -53.982203) (xy 181.659784 -53.954934) (xy 0.509016 -53.954934)
			(xy 0.509016 -55.481728) (xy 178.630072 -55.481728) (xy 178.630072 -54.618128) (xy 178.630558 -54.590859)
			(xy 178.63832 -54.536875) (xy 178.653685 -54.484545) (xy 178.676342 -54.434935) (xy 178.705828 -54.389054)
			(xy 178.741543 -54.347837) (xy 178.78276 -54.312122) (xy 178.828641 -54.282636) (xy 178.878251 -54.259979)
			(xy 178.930581 -54.244614) (xy 178.984565 -54.236852) (xy 179.039103 -54.236852) (xy 179.093087 -54.244614)
			(xy 179.145417 -54.259979) (xy 179.195027 -54.282636) (xy 179.240908 -54.312122) (xy 179.282125 -54.347837)
			(xy 179.31784 -54.389054) (xy 179.347326 -54.434935) (xy 179.369983 -54.484545) (xy 179.385348 -54.536875)
			(xy 179.39311 -54.590859) (xy 179.393596 -54.618128) (xy 179.393596 -55.481728) (xy 179.39311 -55.508997)
			(xy 179.385348 -55.562981) (xy 179.369983 -55.615311) (xy 179.347326 -55.664921) (xy 179.31784 -55.710802)
			(xy 179.282125 -55.752019) (xy 179.240908 -55.787734) (xy 179.195027 -55.81722) (xy 179.145417 -55.839877)
			(xy 179.093087 -55.855242) (xy 179.039103 -55.863004) (xy 178.984565 -55.863004) (xy 178.930581 -55.855242)
			(xy 178.878251 -55.839877) (xy 178.828641 -55.81722) (xy 178.78276 -55.787734) (xy 178.741543 -55.752019)
			(xy 178.705828 -55.710802) (xy 178.676342 -55.664921) (xy 178.653685 -55.615311) (xy 178.63832 -55.562981)
			(xy 178.630558 -55.508997) (xy 178.630072 -55.481728) (xy 0.509016 -55.481728) (xy 0.509016 -57.094435)
			(xy 170.842169 -57.094435) (xy 170.842169 -57.005413) (xy 170.850149 -56.916749) (xy 170.866045 -56.829158)
			(xy 170.889728 -56.743343) (xy 170.921008 -56.659998) (xy 170.959634 -56.579792) (xy 171.005293 -56.503371)
			(xy 171.057619 -56.43135) (xy 171.11619 -56.36431) (xy 171.180535 -56.30279) (xy 171.250135 -56.247286)
			(xy 171.324431 -56.198244) (xy 171.402823 -56.156059) (xy 171.484682 -56.121071) (xy 171.569347 -56.093562)
			(xy 171.656137 -56.073752) (xy 171.744353 -56.061802) (xy 171.833286 -56.057809) (xy 171.922219 -56.061802)
			(xy 172.010435 -56.073752) (xy 172.097225 -56.093562) (xy 172.18189 -56.121071) (xy 172.263749 -56.156059)
			(xy 172.342141 -56.198244) (xy 172.416437 -56.247286) (xy 172.486037 -56.30279) (xy 172.550382 -56.36431)
			(xy 172.608953 -56.43135) (xy 172.661279 -56.503371) (xy 172.706938 -56.579792) (xy 172.745564 -56.659998)
			(xy 172.776844 -56.743343) (xy 172.800527 -56.829158) (xy 172.816423 -56.916749) (xy 172.824403 -57.005413)
			(xy 172.824902 -57.049924) (xy 172.824403 -57.094435) (xy 172.816423 -57.183099) (xy 172.800527 -57.27069)
			(xy 172.776844 -57.356505) (xy 172.745564 -57.43985) (xy 172.706938 -57.520056) (xy 172.661279 -57.596477)
			(xy 172.608953 -57.668498) (xy 172.550382 -57.735538) (xy 172.486037 -57.797058) (xy 172.416437 -57.852562)
			(xy 172.342141 -57.901604) (xy 172.263749 -57.943789) (xy 172.18189 -57.978777) (xy 172.097225 -58.006286)
			(xy 172.010435 -58.026096) (xy 171.922219 -58.038046) (xy 171.833286 -58.04204) (xy 171.744353 -58.038046)
			(xy 171.656137 -58.026096) (xy 171.569347 -58.006286) (xy 171.484682 -57.978777) (xy 171.402823 -57.943789)
			(xy 171.324431 -57.901604) (xy 171.250135 -57.852562) (xy 171.180535 -57.797058) (xy 171.11619 -57.735538)
			(xy 171.057619 -57.668498) (xy 171.005293 -57.596477) (xy 170.959634 -57.520056) (xy 170.921008 -57.43985)
			(xy 170.889728 -57.356505) (xy 170.866045 -57.27069) (xy 170.850149 -57.183099) (xy 170.842169 -57.094435)
			(xy 0.509016 -57.094435) (xy 0.509016 -60.375038) (xy 233.333297 -60.375038) (xy 233.337302 -60.28713)
			(xy 233.349285 -60.19995) (xy 233.369145 -60.114221) (xy 233.39672 -60.030653) (xy 233.431779 -59.949939)
			(xy 233.474032 -59.872747) (xy 233.52313 -59.799718) (xy 233.578666 -59.731456) (xy 233.640178 -59.668526)
			(xy 233.707159 -59.611452) (xy 233.779052 -59.560704) (xy 233.855261 -59.516704) (xy 233.935156 -59.479817)
			(xy 234.018075 -59.450348) (xy 234.10333 -59.428541) (xy 234.190214 -59.414577) (xy 234.278008 -59.408571)
			(xy 234.365985 -59.410575) (xy 234.453415 -59.42057) (xy 234.539574 -59.438474) (xy 234.623748 -59.464138)
			(xy 234.705239 -59.497351) (xy 234.783373 -59.537837) (xy 234.857501 -59.585259) (xy 234.927009 -59.639226)
			(xy 234.991323 -59.699291) (xy 235.049907 -59.764955) (xy 235.102278 -59.835674) (xy 235.148001 -59.910862)
			(xy 235.186698 -59.989897) (xy 235.218047 -60.072123) (xy 235.241789 -60.156859) (xy 235.257727 -60.243403)
			(xy 235.265729 -60.331038) (xy 235.26623 -60.375038) (xy 235.265729 -60.419038) (xy 235.257727 -60.506673)
			(xy 235.241789 -60.593217) (xy 235.218047 -60.677953) (xy 235.186698 -60.760179) (xy 235.148001 -60.839214)
			(xy 235.102278 -60.914402) (xy 235.049907 -60.985121) (xy 234.991323 -61.050785) (xy 234.927009 -61.11085)
			(xy 234.857501 -61.164817) (xy 234.783373 -61.212239) (xy 234.705239 -61.252725) (xy 234.623748 -61.285938)
			(xy 234.539574 -61.311602) (xy 234.453415 -61.329506) (xy 234.365985 -61.339501) (xy 234.278008 -61.341505)
			(xy 234.190214 -61.335499) (xy 234.10333 -61.321535) (xy 234.018075 -61.299728) (xy 233.935156 -61.270259)
			(xy 233.855261 -61.233372) (xy 233.779052 -61.189372) (xy 233.707159 -61.138624) (xy 233.640178 -61.08155)
			(xy 233.578666 -61.01862) (xy 233.52313 -60.950358) (xy 233.474032 -60.877329) (xy 233.431779 -60.800137)
			(xy 233.39672 -60.719423) (xy 233.369145 -60.635855) (xy 233.349285 -60.550126) (xy 233.337302 -60.462946)
			(xy 233.333297 -60.375038) (xy 0.509016 -60.375038) (xy 0.509016 -74.760836) (xy 39.554404 -74.760836)
			(xy 39.554404 -66.060828) (xy 39.554909 -65.955304) (xy 39.562993 -65.74441) (xy 39.579149 -65.533981)
			(xy 39.603352 -65.324324) (xy 39.635569 -65.115749) (xy 39.675751 -64.908561) (xy 39.723839 -64.703064)
			(xy 39.779763 -64.49956) (xy 39.84344 -64.298347) (xy 39.914778 -64.09972) (xy 39.993672 -63.903972)
			(xy 40.080005 -63.71139) (xy 40.173652 -63.522255) (xy 40.274474 -63.336846) (xy 40.382324 -63.155435)
			(xy 40.497043 -62.978288) (xy 40.618463 -62.805666) (xy 40.746406 -62.63782) (xy 40.880684 -62.474998)
			(xy 41.0211 -62.317439) (xy 41.167448 -62.165374) (xy 41.319513 -62.019026) (xy 41.477072 -61.87861)
			(xy 41.639894 -61.744332) (xy 41.80774 -61.616389) (xy 41.980362 -61.494969) (xy 42.157509 -61.38025)
			(xy 42.33892 -61.2724) (xy 42.524329 -61.171578) (xy 42.713464 -61.077931) (xy 42.906046 -60.991598)
			(xy 43.101794 -60.912704) (xy 43.300421 -60.841366) (xy 43.501634 -60.777689) (xy 43.705138 -60.721765)
			(xy 43.910635 -60.673677) (xy 44.117823 -60.633495) (xy 44.326398 -60.601278) (xy 44.536055 -60.577075)
			(xy 44.746484 -60.560919) (xy 44.957378 -60.552835) (xy 45.168426 -60.552835) (xy 45.37932 -60.560919)
			(xy 45.589749 -60.577075) (xy 45.799406 -60.601278) (xy 46.007981 -60.633495) (xy 46.215169 -60.673677)
			(xy 46.420666 -60.721765) (xy 46.62417 -60.777689) (xy 46.825383 -60.841366) (xy 47.02401 -60.912704)
			(xy 47.219758 -60.991598) (xy 47.41234 -61.077931) (xy 47.601475 -61.171578) (xy 47.786884 -61.2724)
			(xy 47.968295 -61.38025) (xy 48.145442 -61.494969) (xy 48.318064 -61.616389) (xy 48.48591 -61.744332)
			(xy 48.648732 -61.87861) (xy 48.806291 -62.019026) (xy 48.958356 -62.165374) (xy 49.104704 -62.317439)
			(xy 49.24512 -62.474998) (xy 49.379398 -62.63782) (xy 49.507341 -62.805666) (xy 49.628761 -62.978288)
			(xy 49.74348 -63.155435) (xy 49.85133 -63.336846) (xy 49.952152 -63.522255) (xy 50.045799 -63.71139)
			(xy 50.132132 -63.903972) (xy 50.211026 -64.09972) (xy 50.282364 -64.298347) (xy 50.346041 -64.49956)
			(xy 50.401965 -64.703064) (xy 50.450053 -64.908561) (xy 50.490235 -65.115749) (xy 50.522452 -65.324324)
			(xy 50.546655 -65.533981) (xy 50.562811 -65.74441) (xy 50.570895 -65.955304) (xy 50.5714 -66.060828)
			(xy 50.5714 -74.760836) (xy 50.571366 -74.767948) (xy 173.354492 -74.767948) (xy 173.354492 -66.06794)
			(xy 173.354997 -65.962416) (xy 173.363081 -65.751522) (xy 173.379237 -65.541093) (xy 173.40344 -65.331436)
			(xy 173.435657 -65.122861) (xy 173.475839 -64.915673) (xy 173.523927 -64.710176) (xy 173.579851 -64.506672)
			(xy 173.643528 -64.305459) (xy 173.714866 -64.106832) (xy 173.79376 -63.911084) (xy 173.880093 -63.718502)
			(xy 173.97374 -63.529367) (xy 174.074562 -63.343958) (xy 174.182412 -63.162547) (xy 174.297131 -62.9854)
			(xy 174.418551 -62.812778) (xy 174.546494 -62.644932) (xy 174.680772 -62.48211) (xy 174.821188 -62.324551)
			(xy 174.967536 -62.172486) (xy 175.119601 -62.026138) (xy 175.27716 -61.885722) (xy 175.439982 -61.751444)
			(xy 175.607828 -61.623501) (xy 175.78045 -61.502081) (xy 175.957597 -61.387362) (xy 176.139008 -61.279512)
			(xy 176.324417 -61.17869) (xy 176.513552 -61.085043) (xy 176.706134 -60.99871) (xy 176.901882 -60.919816)
			(xy 177.100509 -60.848478) (xy 177.301722 -60.784801) (xy 177.505226 -60.728877) (xy 177.710723 -60.680789)
			(xy 177.917911 -60.640607) (xy 178.126486 -60.60839) (xy 178.336143 -60.584187) (xy 178.546572 -60.568031)
			(xy 178.757466 -60.559947) (xy 178.968514 -60.559947) (xy 179.179408 -60.568031) (xy 179.389837 -60.584187)
			(xy 179.599494 -60.60839) (xy 179.808069 -60.640607) (xy 180.015257 -60.680789) (xy 180.220754 -60.728877)
			(xy 180.424258 -60.784801) (xy 180.625471 -60.848478) (xy 180.824098 -60.919816) (xy 181.019846 -60.99871)
			(xy 181.212428 -61.085043) (xy 181.401563 -61.17869) (xy 181.586972 -61.279512) (xy 181.768383 -61.387362)
			(xy 181.94553 -61.502081) (xy 182.118152 -61.623501) (xy 182.285998 -61.751444) (xy 182.44882 -61.885722)
			(xy 182.606379 -62.026138) (xy 182.758444 -62.172486) (xy 182.904792 -62.324551) (xy 183.045208 -62.48211)
			(xy 183.179486 -62.644932) (xy 183.307429 -62.812778) (xy 183.428849 -62.9854) (xy 183.543568 -63.162547)
			(xy 183.651418 -63.343958) (xy 183.75224 -63.529367) (xy 183.845887 -63.718502) (xy 183.93222 -63.911084)
			(xy 184.011114 -64.106832) (xy 184.082452 -64.305459) (xy 184.146129 -64.506672) (xy 184.202053 -64.710176)
			(xy 184.250141 -64.915673) (xy 184.290323 -65.122861) (xy 184.32254 -65.331436) (xy 184.346743 -65.541093)
			(xy 184.362899 -65.751522) (xy 184.370983 -65.962416) (xy 184.371488 -66.06794) (xy 184.371488 -74.760836)
			(xy 287.494472 -74.760836) (xy 287.494472 -66.060828) (xy 287.494977 -65.955304) (xy 287.503061 -65.74441)
			(xy 287.519217 -65.533981) (xy 287.54342 -65.324324) (xy 287.575637 -65.115749) (xy 287.615819 -64.908561)
			(xy 287.663907 -64.703064) (xy 287.719831 -64.49956) (xy 287.783508 -64.298347) (xy 287.854846 -64.09972)
			(xy 287.93374 -63.903972) (xy 288.020073 -63.71139) (xy 288.11372 -63.522255) (xy 288.214542 -63.336846)
			(xy 288.322392 -63.155435) (xy 288.437111 -62.978288) (xy 288.558531 -62.805666) (xy 288.686474 -62.63782)
			(xy 288.820752 -62.474998) (xy 288.961168 -62.317439) (xy 289.107516 -62.165374) (xy 289.259581 -62.019026)
			(xy 289.41714 -61.87861) (xy 289.579962 -61.744332) (xy 289.747808 -61.616389) (xy 289.92043 -61.494969)
			(xy 290.097577 -61.38025) (xy 290.278988 -61.2724) (xy 290.464397 -61.171578) (xy 290.653532 -61.077931)
			(xy 290.846114 -60.991598) (xy 291.041862 -60.912704) (xy 291.240489 -60.841366) (xy 291.441702 -60.777689)
			(xy 291.645206 -60.721765) (xy 291.850703 -60.673677) (xy 292.057891 -60.633495) (xy 292.266466 -60.601278)
			(xy 292.476123 -60.577075) (xy 292.686552 -60.560919) (xy 292.897446 -60.552835) (xy 293.108494 -60.552835)
			(xy 293.319388 -60.560919) (xy 293.529817 -60.577075) (xy 293.739474 -60.601278) (xy 293.948049 -60.633495)
			(xy 294.155237 -60.673677) (xy 294.360734 -60.721765) (xy 294.564238 -60.777689) (xy 294.765451 -60.841366)
			(xy 294.964078 -60.912704) (xy 295.159826 -60.991598) (xy 295.352408 -61.077931) (xy 295.541543 -61.171578)
			(xy 295.726952 -61.2724) (xy 295.908363 -61.38025) (xy 296.08551 -61.494969) (xy 296.258132 -61.616389)
			(xy 296.425978 -61.744332) (xy 296.5888 -61.87861) (xy 296.746359 -62.019026) (xy 296.898424 -62.165374)
			(xy 297.044772 -62.317439) (xy 297.185188 -62.474998) (xy 297.319466 -62.63782) (xy 297.447409 -62.805666)
			(xy 297.568829 -62.978288) (xy 297.683548 -63.155435) (xy 297.791398 -63.336846) (xy 297.89222 -63.522255)
			(xy 297.985867 -63.71139) (xy 298.0722 -63.903972) (xy 298.151094 -64.09972) (xy 298.222432 -64.298347)
			(xy 298.286109 -64.49956) (xy 298.342033 -64.703064) (xy 298.390121 -64.908561) (xy 298.430303 -65.115749)
			(xy 298.46252 -65.324324) (xy 298.486723 -65.533981) (xy 298.502879 -65.74441) (xy 298.510963 -65.955304)
			(xy 298.511468 -66.060828) (xy 298.511468 -74.760836) (xy 298.511434 -74.767948) (xy 421.29456 -74.767948)
			(xy 421.29456 -66.06794) (xy 421.295065 -65.962416) (xy 421.303149 -65.751522) (xy 421.319305 -65.541093)
			(xy 421.343508 -65.331436) (xy 421.375725 -65.122861) (xy 421.415907 -64.915673) (xy 421.463995 -64.710176)
			(xy 421.519919 -64.506672) (xy 421.583596 -64.305459) (xy 421.654934 -64.106832) (xy 421.733828 -63.911084)
			(xy 421.820161 -63.718502) (xy 421.913808 -63.529367) (xy 422.01463 -63.343958) (xy 422.12248 -63.162547)
			(xy 422.237199 -62.9854) (xy 422.358619 -62.812778) (xy 422.486562 -62.644932) (xy 422.62084 -62.48211)
			(xy 422.761256 -62.324551) (xy 422.907604 -62.172486) (xy 423.059669 -62.026138) (xy 423.217228 -61.885722)
			(xy 423.38005 -61.751444) (xy 423.547896 -61.623501) (xy 423.720518 -61.502081) (xy 423.897665 -61.387362)
			(xy 424.079076 -61.279512) (xy 424.264485 -61.17869) (xy 424.45362 -61.085043) (xy 424.646202 -60.99871)
			(xy 424.84195 -60.919816) (xy 425.040577 -60.848478) (xy 425.24179 -60.784801) (xy 425.445294 -60.728877)
			(xy 425.650791 -60.680789) (xy 425.857979 -60.640607) (xy 426.066554 -60.60839) (xy 426.276211 -60.584187)
			(xy 426.48664 -60.568031) (xy 426.697534 -60.559947) (xy 426.908582 -60.559947) (xy 427.119476 -60.568031)
			(xy 427.329905 -60.584187) (xy 427.539562 -60.60839) (xy 427.748137 -60.640607) (xy 427.955325 -60.680789)
			(xy 428.160822 -60.728877) (xy 428.364326 -60.784801) (xy 428.565539 -60.848478) (xy 428.764166 -60.919816)
			(xy 428.959914 -60.99871) (xy 429.152496 -61.085043) (xy 429.341631 -61.17869) (xy 429.52704 -61.279512)
			(xy 429.708451 -61.387362) (xy 429.885598 -61.502081) (xy 430.05822 -61.623501) (xy 430.226066 -61.751444)
			(xy 430.388888 -61.885722) (xy 430.546447 -62.026138) (xy 430.698512 -62.172486) (xy 430.84486 -62.324551)
			(xy 430.985276 -62.48211) (xy 431.119554 -62.644932) (xy 431.247497 -62.812778) (xy 431.368917 -62.9854)
			(xy 431.483636 -63.162547) (xy 431.591486 -63.343958) (xy 431.692308 -63.529367) (xy 431.785955 -63.718502)
			(xy 431.872288 -63.911084) (xy 431.951182 -64.106832) (xy 432.02252 -64.305459) (xy 432.086197 -64.506672)
			(xy 432.142121 -64.710176) (xy 432.190209 -64.915673) (xy 432.230391 -65.122861) (xy 432.262608 -65.331436)
			(xy 432.286811 -65.541093) (xy 432.302967 -65.751522) (xy 432.311051 -65.962416) (xy 432.311556 -66.06794)
			(xy 432.311556 -74.767948) (xy 432.311051 -74.873472) (xy 432.302967 -75.084366) (xy 432.286811 -75.294795)
			(xy 432.262608 -75.504452) (xy 432.230391 -75.713027) (xy 432.190209 -75.920215) (xy 432.142121 -76.125712)
			(xy 432.086197 -76.329216) (xy 432.02252 -76.530429) (xy 431.951182 -76.729056) (xy 431.872288 -76.924804)
			(xy 431.785955 -77.117386) (xy 431.692308 -77.306521) (xy 431.591486 -77.49193) (xy 431.483636 -77.673341)
			(xy 431.368917 -77.850488) (xy 431.247497 -78.02311) (xy 431.119554 -78.190956) (xy 430.985276 -78.353778)
			(xy 430.84486 -78.511337) (xy 430.698512 -78.663402) (xy 430.546447 -78.80975) (xy 430.388888 -78.950166)
			(xy 430.226066 -79.084444) (xy 430.05822 -79.212387) (xy 429.885598 -79.333807) (xy 429.708451 -79.448526)
			(xy 429.52704 -79.556376) (xy 429.341631 -79.657198) (xy 429.152496 -79.750845) (xy 428.959914 -79.837178)
			(xy 428.764166 -79.916072) (xy 428.565539 -79.98741) (xy 428.364326 -80.051087) (xy 428.160822 -80.107011)
			(xy 427.955325 -80.155099) (xy 427.748137 -80.195281) (xy 427.539562 -80.227498) (xy 427.329905 -80.251701)
			(xy 427.119476 -80.267857) (xy 426.908582 -80.275941) (xy 426.697534 -80.275941) (xy 426.48664 -80.267857)
			(xy 426.276211 -80.251701) (xy 426.066554 -80.227498) (xy 425.857979 -80.195281) (xy 425.650791 -80.155099)
			(xy 425.445294 -80.107011) (xy 425.24179 -80.051087) (xy 425.040577 -79.98741) (xy 424.84195 -79.916072)
			(xy 424.646202 -79.837178) (xy 424.45362 -79.750845) (xy 424.264485 -79.657198) (xy 424.079076 -79.556376)
			(xy 423.897665 -79.448526) (xy 423.720518 -79.333807) (xy 423.547896 -79.212387) (xy 423.38005 -79.084444)
			(xy 423.217228 -78.950166) (xy 423.059669 -78.80975) (xy 422.907604 -78.663402) (xy 422.761256 -78.511337)
			(xy 422.62084 -78.353778) (xy 422.486562 -78.190956) (xy 422.358619 -78.02311) (xy 422.237199 -77.850488)
			(xy 422.12248 -77.673341) (xy 422.01463 -77.49193) (xy 421.913808 -77.306521) (xy 421.820161 -77.117386)
			(xy 421.733828 -76.924804) (xy 421.654934 -76.729056) (xy 421.583596 -76.530429) (xy 421.519919 -76.329216)
			(xy 421.463995 -76.125712) (xy 421.415907 -75.920215) (xy 421.375725 -75.713027) (xy 421.343508 -75.504452)
			(xy 421.319305 -75.294795) (xy 421.303149 -75.084366) (xy 421.295065 -74.873472) (xy 421.29456 -74.767948)
			(xy 298.511434 -74.767948) (xy 298.510963 -74.86636) (xy 298.502879 -75.077254) (xy 298.486723 -75.287683)
			(xy 298.46252 -75.49734) (xy 298.430303 -75.705915) (xy 298.390121 -75.913103) (xy 298.342033 -76.1186)
			(xy 298.286109 -76.322104) (xy 298.222432 -76.523317) (xy 298.151094 -76.721944) (xy 298.0722 -76.917692)
			(xy 297.985867 -77.110274) (xy 297.89222 -77.299409) (xy 297.791398 -77.484818) (xy 297.683548 -77.666229)
			(xy 297.568829 -77.843376) (xy 297.447409 -78.015998) (xy 297.319466 -78.183844) (xy 297.185188 -78.346666)
			(xy 297.044772 -78.504225) (xy 296.898424 -78.65629) (xy 296.746359 -78.802638) (xy 296.5888 -78.943054)
			(xy 296.425978 -79.077332) (xy 296.258132 -79.205275) (xy 296.08551 -79.326695) (xy 295.908363 -79.441414)
			(xy 295.726952 -79.549264) (xy 295.541543 -79.650086) (xy 295.352408 -79.743733) (xy 295.159826 -79.830066)
			(xy 294.964078 -79.90896) (xy 294.765451 -79.980298) (xy 294.564238 -80.043975) (xy 294.360734 -80.099899)
			(xy 294.155237 -80.147987) (xy 293.948049 -80.188169) (xy 293.739474 -80.220386) (xy 293.529817 -80.244589)
			(xy 293.319388 -80.260745) (xy 293.108494 -80.268829) (xy 292.897446 -80.268829) (xy 292.686552 -80.260745)
			(xy 292.476123 -80.244589) (xy 292.266466 -80.220386) (xy 292.057891 -80.188169) (xy 291.850703 -80.147987)
			(xy 291.645206 -80.099899) (xy 291.441702 -80.043975) (xy 291.240489 -79.980298) (xy 291.041862 -79.90896)
			(xy 290.846114 -79.830066) (xy 290.653532 -79.743733) (xy 290.464397 -79.650086) (xy 290.278988 -79.549264)
			(xy 290.097577 -79.441414) (xy 289.92043 -79.326695) (xy 289.747808 -79.205275) (xy 289.579962 -79.077332)
			(xy 289.41714 -78.943054) (xy 289.259581 -78.802638) (xy 289.107516 -78.65629) (xy 288.961168 -78.504225)
			(xy 288.820752 -78.346666) (xy 288.686474 -78.183844) (xy 288.558531 -78.015998) (xy 288.437111 -77.843376)
			(xy 288.322392 -77.666229) (xy 288.214542 -77.484818) (xy 288.11372 -77.299409) (xy 288.020073 -77.110274)
			(xy 287.93374 -76.917692) (xy 287.854846 -76.721944) (xy 287.783508 -76.523317) (xy 287.719831 -76.322104)
			(xy 287.663907 -76.1186) (xy 287.615819 -75.913103) (xy 287.575637 -75.705915) (xy 287.54342 -75.49734)
			(xy 287.519217 -75.287683) (xy 287.503061 -75.077254) (xy 287.494977 -74.86636) (xy 287.494472 -74.760836)
			(xy 184.371488 -74.760836) (xy 184.371488 -74.767948) (xy 184.370983 -74.873472) (xy 184.362899 -75.084366)
			(xy 184.346743 -75.294795) (xy 184.32254 -75.504452) (xy 184.290323 -75.713027) (xy 184.250141 -75.920215)
			(xy 184.202053 -76.125712) (xy 184.146129 -76.329216) (xy 184.082452 -76.530429) (xy 184.011114 -76.729056)
			(xy 183.93222 -76.924804) (xy 183.845887 -77.117386) (xy 183.75224 -77.306521) (xy 183.651418 -77.49193)
			(xy 183.543568 -77.673341) (xy 183.428849 -77.850488) (xy 183.307429 -78.02311) (xy 183.179486 -78.190956)
			(xy 183.045208 -78.353778) (xy 182.904792 -78.511337) (xy 182.758444 -78.663402) (xy 182.606379 -78.80975)
			(xy 182.44882 -78.950166) (xy 182.285998 -79.084444) (xy 182.118152 -79.212387) (xy 181.94553 -79.333807)
			(xy 181.768383 -79.448526) (xy 181.586972 -79.556376) (xy 181.401563 -79.657198) (xy 181.212428 -79.750845)
			(xy 181.019846 -79.837178) (xy 180.824098 -79.916072) (xy 180.625471 -79.98741) (xy 180.424258 -80.051087)
			(xy 180.220754 -80.107011) (xy 180.015257 -80.155099) (xy 179.808069 -80.195281) (xy 179.599494 -80.227498)
			(xy 179.389837 -80.251701) (xy 179.179408 -80.267857) (xy 178.968514 -80.275941) (xy 178.757466 -80.275941)
			(xy 178.546572 -80.267857) (xy 178.336143 -80.251701) (xy 178.126486 -80.227498) (xy 177.917911 -80.195281)
			(xy 177.710723 -80.155099) (xy 177.505226 -80.107011) (xy 177.301722 -80.051087) (xy 177.100509 -79.98741)
			(xy 176.901882 -79.916072) (xy 176.706134 -79.837178) (xy 176.513552 -79.750845) (xy 176.324417 -79.657198)
			(xy 176.139008 -79.556376) (xy 175.957597 -79.448526) (xy 175.78045 -79.333807) (xy 175.607828 -79.212387)
			(xy 175.439982 -79.084444) (xy 175.27716 -78.950166) (xy 175.119601 -78.80975) (xy 174.967536 -78.663402)
			(xy 174.821188 -78.511337) (xy 174.680772 -78.353778) (xy 174.546494 -78.190956) (xy 174.418551 -78.02311)
			(xy 174.297131 -77.850488) (xy 174.182412 -77.673341) (xy 174.074562 -77.49193) (xy 173.97374 -77.306521)
			(xy 173.880093 -77.117386) (xy 173.79376 -76.924804) (xy 173.714866 -76.729056) (xy 173.643528 -76.530429)
			(xy 173.579851 -76.329216) (xy 173.523927 -76.125712) (xy 173.475839 -75.920215) (xy 173.435657 -75.713027)
			(xy 173.40344 -75.504452) (xy 173.379237 -75.294795) (xy 173.363081 -75.084366) (xy 173.354997 -74.873472)
			(xy 173.354492 -74.767948) (xy 50.571366 -74.767948) (xy 50.570895 -74.86636) (xy 50.562811 -75.077254)
			(xy 50.546655 -75.287683) (xy 50.522452 -75.49734) (xy 50.490235 -75.705915) (xy 50.450053 -75.913103)
			(xy 50.401965 -76.1186) (xy 50.346041 -76.322104) (xy 50.282364 -76.523317) (xy 50.211026 -76.721944)
			(xy 50.132132 -76.917692) (xy 50.045799 -77.110274) (xy 49.952152 -77.299409) (xy 49.85133 -77.484818)
			(xy 49.74348 -77.666229) (xy 49.628761 -77.843376) (xy 49.507341 -78.015998) (xy 49.379398 -78.183844)
			(xy 49.24512 -78.346666) (xy 49.104704 -78.504225) (xy 48.958356 -78.65629) (xy 48.806291 -78.802638)
			(xy 48.648732 -78.943054) (xy 48.48591 -79.077332) (xy 48.318064 -79.205275) (xy 48.145442 -79.326695)
			(xy 47.968295 -79.441414) (xy 47.786884 -79.549264) (xy 47.601475 -79.650086) (xy 47.41234 -79.743733)
			(xy 47.219758 -79.830066) (xy 47.02401 -79.90896) (xy 46.825383 -79.980298) (xy 46.62417 -80.043975)
			(xy 46.420666 -80.099899) (xy 46.215169 -80.147987) (xy 46.007981 -80.188169) (xy 45.799406 -80.220386)
			(xy 45.589749 -80.244589) (xy 45.37932 -80.260745) (xy 45.168426 -80.268829) (xy 44.957378 -80.268829)
			(xy 44.746484 -80.260745) (xy 44.536055 -80.244589) (xy 44.326398 -80.220386) (xy 44.117823 -80.188169)
			(xy 43.910635 -80.147987) (xy 43.705138 -80.099899) (xy 43.501634 -80.043975) (xy 43.300421 -79.980298)
			(xy 43.101794 -79.90896) (xy 42.906046 -79.830066) (xy 42.713464 -79.743733) (xy 42.524329 -79.650086)
			(xy 42.33892 -79.549264) (xy 42.157509 -79.441414) (xy 41.980362 -79.326695) (xy 41.80774 -79.205275)
			(xy 41.639894 -79.077332) (xy 41.477072 -78.943054) (xy 41.319513 -78.802638) (xy 41.167448 -78.65629)
			(xy 41.0211 -78.504225) (xy 40.880684 -78.346666) (xy 40.746406 -78.183844) (xy 40.618463 -78.015998)
			(xy 40.497043 -77.843376) (xy 40.382324 -77.666229) (xy 40.274474 -77.484818) (xy 40.173652 -77.299409)
			(xy 40.080005 -77.110274) (xy 39.993672 -76.917692) (xy 39.914778 -76.721944) (xy 39.84344 -76.523317)
			(xy 39.779763 -76.322104) (xy 39.723839 -76.1186) (xy 39.675751 -75.913103) (xy 39.635569 -75.705915)
			(xy 39.603352 -75.49734) (xy 39.579149 -75.287683) (xy 39.562993 -75.077254) (xy 39.554909 -74.86636)
			(xy 39.554404 -74.760836) (xy 0.509016 -74.760836) (xy 0.509016 -77.67193) (xy 0.5095 -77.725143)
			(xy 0.517108 -77.831296) (xy 0.532269 -77.936637) (xy 0.554904 -78.040627) (xy 0.584899 -78.142739)
			(xy 0.622101 -78.242451) (xy 0.666319 -78.339256) (xy 0.71733 -78.43266) (xy 0.774873 -78.522188)
			(xy 0.838654 -78.607384) (xy 0.90835 -78.687813) (xy 0.945642 -78.725776) (xy 1.77419 -79.554324)
			(xy 1.823612 -79.604428) (xy 1.917404 -79.709374) (xy 2.005163 -79.819414) (xy 2.086614 -79.934202)
			(xy 2.161501 -80.053377) (xy 2.229587 -80.176563) (xy 2.290658 -80.303374) (xy 2.344523 -80.433409)
			(xy 2.391012 -80.56626) (xy 2.429978 -80.701509) (xy 2.461299 -80.83873) (xy 2.484876 -80.977491)
			(xy 2.500635 -81.117356) (xy 2.508527 -81.257885) (xy 2.509012 -81.32826) (xy 2.509012 -81.691972)
			(xy 232.140715 -81.691972) (xy 232.145114 -81.518126) (xy 232.157548 -81.34467) (xy 232.177991 -81.171975)
			(xy 232.206398 -81.00041) (xy 232.242709 -80.830342) (xy 232.286847 -80.662135) (xy 232.338717 -80.49615)
			(xy 232.398207 -80.332741) (xy 232.465191 -80.172258) (xy 232.539525 -80.015044) (xy 232.62105 -79.861437)
			(xy 232.709592 -79.711764) (xy 232.804961 -79.566346) (xy 232.906953 -79.425495) (xy 233.015351 -79.289511)
			(xy 233.129921 -79.158685) (xy 233.250418 -79.033298) (xy 233.376586 -78.913618) (xy 233.508153 -78.799901)
			(xy 233.644839 -78.69239) (xy 233.715306 -78.641448) (xy 238.084614 -78.641448) (xy 238.155081 -78.69239)
			(xy 238.291767 -78.799901) (xy 238.423334 -78.913618) (xy 238.549502 -79.033298) (xy 238.669999 -79.158685)
			(xy 238.784569 -79.289511) (xy 238.892967 -79.425495) (xy 238.994959 -79.566346) (xy 239.090328 -79.711764)
			(xy 239.17887 -79.861437) (xy 239.260395 -80.015044) (xy 239.334729 -80.172258) (xy 239.401713 -80.332741)
			(xy 239.461203 -80.49615) (xy 239.513073 -80.662135) (xy 239.557211 -80.830342) (xy 239.593522 -81.00041)
			(xy 239.608937 -81.093507) (xy 398.275806 -81.093507) (xy 398.275806 -81.008785) (xy 398.283859 -80.924448)
			(xy 398.299893 -80.841258) (xy 398.323761 -80.759968) (xy 398.355249 -80.681316) (xy 398.394071 -80.606013)
			(xy 398.439874 -80.534741) (xy 398.492245 -80.468145) (xy 398.55071 -80.40683) (xy 398.614738 -80.351349)
			(xy 398.68375 -80.302206) (xy 398.75712 -80.259846) (xy 398.834185 -80.224651) (xy 398.914247 -80.196942)
			(xy 398.99658 -80.176968) (xy 399.080439 -80.164911) (xy 399.165064 -80.16088) (xy 399.249689 -80.164911)
			(xy 399.333548 -80.176968) (xy 399.415881 -80.196942) (xy 399.495943 -80.224651) (xy 399.573008 -80.259846)
			(xy 399.646378 -80.302206) (xy 399.71539 -80.351349) (xy 399.779418 -80.40683) (xy 399.837883 -80.468145)
			(xy 399.890254 -80.534741) (xy 399.936057 -80.606013) (xy 399.974879 -80.681316) (xy 400.006367 -80.759968)
			(xy 400.030235 -80.841258) (xy 400.046269 -80.924448) (xy 400.054322 -81.008785) (xy 400.054826 -81.051146)
			(xy 400.054322 -81.093507) (xy 400.046269 -81.177844) (xy 400.030235 -81.261034) (xy 400.006367 -81.342324)
			(xy 399.974879 -81.420976) (xy 399.936057 -81.496279) (xy 399.890254 -81.567551) (xy 399.837883 -81.634147)
			(xy 399.779418 -81.695462) (xy 399.71539 -81.750943) (xy 399.646378 -81.800086) (xy 399.573008 -81.842446)
			(xy 399.495943 -81.877641) (xy 399.415881 -81.90535) (xy 399.333548 -81.925324) (xy 399.249689 -81.937381)
			(xy 399.165064 -81.941413) (xy 399.080439 -81.937381) (xy 398.99658 -81.925324) (xy 398.914247 -81.90535)
			(xy 398.834185 -81.877641) (xy 398.75712 -81.842446) (xy 398.68375 -81.800086) (xy 398.614738 -81.750943)
			(xy 398.55071 -81.695462) (xy 398.492245 -81.634147) (xy 398.439874 -81.567551) (xy 398.394071 -81.496279)
			(xy 398.355249 -81.420976) (xy 398.323761 -81.342324) (xy 398.299893 -81.261034) (xy 398.283859 -81.177844)
			(xy 398.275806 -81.093507) (xy 239.608937 -81.093507) (xy 239.621929 -81.171975) (xy 239.642372 -81.34467)
			(xy 239.654806 -81.518126) (xy 239.659205 -81.691972) (xy 239.655559 -81.865835) (xy 239.643877 -82.039343)
			(xy 239.624183 -82.212126) (xy 239.596519 -82.383812) (xy 239.560945 -82.554036) (xy 239.517536 -82.722432)
			(xy 239.466387 -82.888641) (xy 239.407605 -83.052306) (xy 239.341317 -83.213078) (xy 239.267665 -83.370612)
			(xy 239.186806 -83.524571) (xy 239.098913 -83.674626) (xy 239.004175 -83.820455) (xy 238.902794 -83.961748)
			(xy 238.794987 -84.0982) (xy 238.680985 -84.229521) (xy 238.561032 -84.355429) (xy 238.435384 -84.475655)
			(xy 238.30431 -84.589941) (xy 238.168092 -84.698043) (xy 238.027019 -84.79973) (xy 237.881395 -84.894784)
			(xy 237.731531 -84.983001) (xy 237.577747 -85.064194) (xy 237.420373 -85.138187) (xy 237.259746 -85.204823)
			(xy 237.096208 -85.263959) (xy 236.930111 -85.315469) (xy 236.761809 -85.359242) (xy 236.591663 -85.395185)
			(xy 236.420037 -85.423221) (xy 236.247297 -85.443289) (xy 236.073815 -85.455348) (xy 235.89996 -85.45937)
			(xy 235.726105 -85.455348) (xy 235.552623 -85.443289) (xy 235.379883 -85.423221) (xy 235.208257 -85.395185)
			(xy 235.038111 -85.359242) (xy 234.869809 -85.315469) (xy 234.703712 -85.263959) (xy 234.540174 -85.204823)
			(xy 234.379547 -85.138187) (xy 234.222173 -85.064194) (xy 234.068389 -84.983001) (xy 233.918525 -84.894784)
			(xy 233.772901 -84.79973) (xy 233.631828 -84.698043) (xy 233.49561 -84.589941) (xy 233.364536 -84.475655)
			(xy 233.238888 -84.355429) (xy 233.118935 -84.229521) (xy 233.004933 -84.0982) (xy 232.897126 -83.961748)
			(xy 232.795745 -83.820455) (xy 232.701007 -83.674626) (xy 232.613114 -83.524571) (xy 232.532255 -83.370612)
			(xy 232.458603 -83.213078) (xy 232.392315 -83.052306) (xy 232.333533 -82.888641) (xy 232.282384 -82.722432)
			(xy 232.238975 -82.554036) (xy 232.203401 -82.383812) (xy 232.175737 -82.212126) (xy 232.156043 -82.039343)
			(xy 232.144361 -81.865835) (xy 232.140715 -81.691972) (xy 2.509012 -81.691972) (xy 2.509012 -84.065147)
			(xy 218.29831 -84.065147) (xy 218.29831 -84.010653) (xy 218.306065 -83.956712) (xy 218.321417 -83.904424)
			(xy 218.344054 -83.854854) (xy 218.373515 -83.809009) (xy 218.4092 -83.767823) (xy 218.450383 -83.732134)
			(xy 218.496225 -83.70267) (xy 218.545794 -83.680029) (xy 218.598081 -83.664672) (xy 218.652021 -83.656912)
			(xy 218.679268 -83.656424) (xy 219.542868 -83.656424) (xy 219.570125 -83.656821) (xy 219.624084 -83.664575)
			(xy 219.67639 -83.679929) (xy 219.725978 -83.702572) (xy 219.771839 -83.732041) (xy 219.813039 -83.767738)
			(xy 219.848739 -83.808935) (xy 219.878213 -83.854794) (xy 219.90086 -83.90438) (xy 219.916219 -83.956685)
			(xy 219.923977 -84.010643) (xy 219.923977 -84.065157) (xy 219.916219 -84.119115) (xy 219.90086 -84.17142)
			(xy 219.878213 -84.221006) (xy 219.848739 -84.266865) (xy 219.813039 -84.308062) (xy 219.771839 -84.343759)
			(xy 219.725978 -84.373228) (xy 219.67639 -84.395871) (xy 219.624084 -84.411225) (xy 219.570125 -84.418979)
			(xy 219.542868 -84.41944) (xy 218.679268 -84.41944) (xy 218.652021 -84.418888) (xy 218.598081 -84.411128)
			(xy 218.545794 -84.395771) (xy 218.496225 -84.37313) (xy 218.450383 -84.343666) (xy 218.4092 -84.307977)
			(xy 218.373515 -84.266791) (xy 218.344054 -84.220946) (xy 218.321417 -84.171376) (xy 218.306065 -84.119088)
			(xy 218.29831 -84.065147) (xy 2.509012 -84.065147) (xy 2.509012 -86.948548) (xy 217.344518 -86.948548)
			(xy 217.344518 -86.894052) (xy 217.352274 -86.84011) (xy 217.367627 -86.787821) (xy 217.390266 -86.738249)
			(xy 217.419729 -86.692404) (xy 217.455416 -86.651218) (xy 217.496602 -86.61553) (xy 217.542447 -86.586067)
			(xy 217.592019 -86.563428) (xy 217.644308 -86.548074) (xy 217.69825 -86.540318) (xy 217.725498 -86.539832)
			(xy 218.589098 -86.539832) (xy 218.616354 -86.540215) (xy 218.670311 -86.547972) (xy 218.722614 -86.56333)
			(xy 218.7722 -86.585975) (xy 218.818058 -86.615446) (xy 218.859255 -86.651143) (xy 218.894953 -86.69234)
			(xy 218.924424 -86.738198) (xy 218.947069 -86.787784) (xy 218.962427 -86.840087) (xy 218.970185 -86.894044)
			(xy 218.970185 -86.948556) (xy 218.962427 -87.002513) (xy 218.947069 -87.054816) (xy 218.924424 -87.104402)
			(xy 218.894953 -87.15026) (xy 218.859255 -87.191457) (xy 218.818058 -87.227154) (xy 218.7722 -87.256625)
			(xy 218.722614 -87.27927) (xy 218.670311 -87.294628) (xy 218.616354 -87.302385) (xy 218.589098 -87.302848)
			(xy 217.725498 -87.302848) (xy 217.69825 -87.302282) (xy 217.644308 -87.294526) (xy 217.592019 -87.279172)
			(xy 217.542447 -87.256533) (xy 217.496602 -87.22707) (xy 217.455416 -87.191382) (xy 217.419729 -87.150196)
			(xy 217.390266 -87.104351) (xy 217.367627 -87.054779) (xy 217.352274 -87.00249) (xy 217.344518 -86.948548)
			(xy 2.509012 -86.948548) (xy 2.509012 -106.447336) (xy 11.713464 -106.447336) (xy 11.713464 -105.456736)
			(xy 11.71395 -105.429467) (xy 11.721712 -105.375483) (xy 11.737077 -105.323153) (xy 11.759734 -105.273543)
			(xy 11.78922 -105.227662) (xy 11.824935 -105.186445) (xy 11.866152 -105.15073) (xy 11.912033 -105.121244)
			(xy 11.961643 -105.098587) (xy 12.013973 -105.083222) (xy 12.067957 -105.07546) (xy 12.122495 -105.07546)
			(xy 12.176479 -105.083222) (xy 12.228809 -105.098587) (xy 12.278419 -105.121244) (xy 12.3243 -105.15073)
			(xy 12.365517 -105.186445) (xy 12.401232 -105.227662) (xy 12.430718 -105.273543) (xy 12.453375 -105.323153)
			(xy 12.46874 -105.375483) (xy 12.476502 -105.429467) (xy 12.476988 -105.456736) (xy 12.476988 -105.664)
			(xy 15.57274 -105.664) (xy 15.57274 -104.6734) (xy 15.573226 -104.646131) (xy 15.580988 -104.592147)
			(xy 15.596353 -104.539817) (xy 15.61901 -104.490207) (xy 15.648496 -104.444326) (xy 15.684211 -104.403109)
			(xy 15.725428 -104.367394) (xy 15.771309 -104.337908) (xy 15.820919 -104.315251) (xy 15.873249 -104.299886)
			(xy 15.927233 -104.292124) (xy 15.981771 -104.292124) (xy 16.035755 -104.299886) (xy 16.088085 -104.315251)
			(xy 16.137695 -104.337908) (xy 16.146631 -104.343651) (xy 326.803 -104.343651) (xy 326.803 -104.258929)
			(xy 326.811053 -104.174592) (xy 326.827087 -104.091402) (xy 326.850955 -104.010112) (xy 326.882443 -103.93146)
			(xy 326.921265 -103.856157) (xy 326.967068 -103.784885) (xy 327.019439 -103.718289) (xy 327.077904 -103.656974)
			(xy 327.141932 -103.601493) (xy 327.210944 -103.55235) (xy 327.284314 -103.50999) (xy 327.361379 -103.474795)
			(xy 327.441441 -103.447086) (xy 327.523774 -103.427112) (xy 327.607633 -103.415055) (xy 327.692258 -103.411024)
			(xy 327.776883 -103.415055) (xy 327.860742 -103.427112) (xy 327.943075 -103.447086) (xy 328.023137 -103.474795)
			(xy 328.100202 -103.50999) (xy 328.173572 -103.55235) (xy 328.242584 -103.601493) (xy 328.306612 -103.656974)
			(xy 328.365077 -103.718289) (xy 328.417448 -103.784885) (xy 328.463251 -103.856157) (xy 328.502073 -103.93146)
			(xy 328.533561 -104.010112) (xy 328.557429 -104.091402) (xy 328.573463 -104.174592) (xy 328.581516 -104.258929)
			(xy 328.58202 -104.30129) (xy 328.581516 -104.343651) (xy 328.573463 -104.427988) (xy 328.557429 -104.511178)
			(xy 328.533561 -104.592468) (xy 328.502073 -104.67112) (xy 328.463251 -104.746423) (xy 328.417448 -104.817695)
			(xy 328.365077 -104.884291) (xy 328.306612 -104.945606) (xy 328.242584 -105.001087) (xy 328.173572 -105.05023)
			(xy 328.100202 -105.09259) (xy 328.023137 -105.127785) (xy 327.943075 -105.155494) (xy 327.860742 -105.175468)
			(xy 327.776883 -105.187525) (xy 327.692258 -105.191557) (xy 327.607633 -105.187525) (xy 327.523774 -105.175468)
			(xy 327.441441 -105.155494) (xy 327.361379 -105.127785) (xy 327.284314 -105.09259) (xy 327.210944 -105.05023)
			(xy 327.141932 -105.001087) (xy 327.077904 -104.945606) (xy 327.019439 -104.884291) (xy 326.967068 -104.817695)
			(xy 326.921265 -104.746423) (xy 326.882443 -104.67112) (xy 326.850955 -104.592468) (xy 326.827087 -104.511178)
			(xy 326.811053 -104.427988) (xy 326.803 -104.343651) (xy 16.146631 -104.343651) (xy 16.183576 -104.367394)
			(xy 16.224793 -104.403109) (xy 16.260508 -104.444326) (xy 16.289994 -104.490207) (xy 16.312651 -104.539817)
			(xy 16.328016 -104.592147) (xy 16.335778 -104.646131) (xy 16.336264 -104.6734) (xy 16.336264 -105.664)
			(xy 16.335778 -105.691269) (xy 16.328016 -105.745253) (xy 16.312651 -105.797583) (xy 16.289994 -105.847193)
			(xy 16.260508 -105.893074) (xy 16.224793 -105.934291) (xy 16.183576 -105.970006) (xy 16.137695 -105.999492)
			(xy 16.088085 -106.022149) (xy 16.035755 -106.037514) (xy 15.981771 -106.045276) (xy 15.927233 -106.045276)
			(xy 15.873249 -106.037514) (xy 15.820919 -106.022149) (xy 15.771309 -105.999492) (xy 15.725428 -105.970006)
			(xy 15.684211 -105.934291) (xy 15.648496 -105.893074) (xy 15.61901 -105.847193) (xy 15.596353 -105.797583)
			(xy 15.580988 -105.745253) (xy 15.573226 -105.691269) (xy 15.57274 -105.664) (xy 12.476988 -105.664)
			(xy 12.476988 -106.447336) (xy 12.476502 -106.474605) (xy 12.46874 -106.528589) (xy 12.453375 -106.580919)
			(xy 12.430718 -106.630529) (xy 12.401232 -106.67641) (xy 12.365517 -106.717627) (xy 12.3243 -106.753342)
			(xy 12.278419 -106.782828) (xy 12.228809 -106.805485) (xy 12.176479 -106.82085) (xy 12.122495 -106.828612)
			(xy 12.067957 -106.828612) (xy 12.013973 -106.82085) (xy 11.961643 -106.805485) (xy 11.912033 -106.782828)
			(xy 11.866152 -106.753342) (xy 11.824935 -106.717627) (xy 11.78922 -106.67641) (xy 11.759734 -106.630529)
			(xy 11.737077 -106.580919) (xy 11.721712 -106.528589) (xy 11.71395 -106.474605) (xy 11.713464 -106.447336)
			(xy 2.509012 -106.447336) (xy 2.509012 -108.943971) (xy 11.292822 -108.943971) (xy 11.292822 -108.889469)
			(xy 11.300578 -108.835522) (xy 11.315933 -108.783228) (xy 11.338574 -108.733651) (xy 11.36804 -108.687801)
			(xy 11.403731 -108.646611) (xy 11.444921 -108.61092) (xy 11.490771 -108.581454) (xy 11.540348 -108.558813)
			(xy 11.592642 -108.543458) (xy 11.646589 -108.535702) (xy 11.67384 -108.535216) (xy 12.53744 -108.535216)
			(xy 12.564692 -108.535694) (xy 12.61864 -108.54345) (xy 12.670935 -108.558806) (xy 12.720513 -108.581447)
			(xy 12.766364 -108.610914) (xy 12.807554 -108.646606) (xy 12.843246 -108.687796) (xy 12.872713 -108.733647)
			(xy 12.895354 -108.783225) (xy 12.91071 -108.83552) (xy 12.918466 -108.889468) (xy 12.918466 -108.943972)
			(xy 12.91071 -108.99792) (xy 12.895354 -109.050215) (xy 12.872713 -109.099793) (xy 12.843246 -109.145644)
			(xy 12.807554 -109.186834) (xy 12.766364 -109.222526) (xy 12.720513 -109.251993) (xy 12.670935 -109.274634)
			(xy 12.61864 -109.28999) (xy 12.564692 -109.297746) (xy 12.53744 -109.298232) (xy 11.67384 -109.298232)
			(xy 11.646589 -109.297738) (xy 11.592642 -109.289982) (xy 11.540348 -109.274627) (xy 11.490771 -109.251986)
			(xy 11.444921 -109.22252) (xy 11.403731 -109.186829) (xy 11.36804 -109.145639) (xy 11.338574 -109.099789)
			(xy 11.315933 -109.050212) (xy 11.300578 -108.997918) (xy 11.292822 -108.943971) (xy 2.509012 -108.943971)
			(xy 2.509012 -109.451973) (xy 15.092889 -109.451973) (xy 15.092889 -109.397467) (xy 15.100646 -109.343517)
			(xy 15.116002 -109.291219) (xy 15.138645 -109.241639) (xy 15.168113 -109.195786) (xy 15.203807 -109.154594)
			(xy 15.244999 -109.118901) (xy 15.290853 -109.089433) (xy 15.340433 -109.066791) (xy 15.39273 -109.051435)
			(xy 15.446681 -109.043679) (xy 15.473934 -109.043216) (xy 16.464534 -109.043216) (xy 16.491785 -109.043694)
			(xy 16.545733 -109.051451) (xy 16.598028 -109.066807) (xy 16.647605 -109.089448) (xy 16.693456 -109.118915)
			(xy 16.734646 -109.154607) (xy 16.770337 -109.195798) (xy 16.799804 -109.241648) (xy 16.822445 -109.291226)
			(xy 16.8378 -109.343521) (xy 16.845556 -109.397469) (xy 16.845556 -109.451971) (xy 16.8378 -109.505919)
			(xy 16.822445 -109.558214) (xy 16.799804 -109.607792) (xy 16.770337 -109.653642) (xy 16.734646 -109.694833)
			(xy 16.693456 -109.730525) (xy 16.647605 -109.759992) (xy 16.598028 -109.782633) (xy 16.545733 -109.797989)
			(xy 16.491785 -109.805746) (xy 16.464534 -109.806232) (xy 15.473934 -109.806232) (xy 15.446681 -109.805761)
			(xy 15.39273 -109.798005) (xy 15.340433 -109.782649) (xy 15.290853 -109.760007) (xy 15.244999 -109.730539)
			(xy 15.203807 -109.694846) (xy 15.168113 -109.653654) (xy 15.138645 -109.607801) (xy 15.116002 -109.558221)
			(xy 15.100646 -109.505923) (xy 15.092889 -109.451973) (xy 2.509012 -109.451973) (xy 2.509012 -114.734161)
			(xy 11.255226 -114.734161) (xy 11.255226 -114.679659) (xy 11.262982 -114.625711) (xy 11.278337 -114.573416)
			(xy 11.300979 -114.523839) (xy 11.330445 -114.477988) (xy 11.366136 -114.436798) (xy 11.407326 -114.401106)
			(xy 11.453177 -114.371639) (xy 11.502754 -114.348998) (xy 11.555049 -114.333643) (xy 11.608997 -114.325886)
			(xy 11.636248 -114.3254) (xy 12.499848 -114.3254) (xy 12.527101 -114.325867) (xy 12.581052 -114.333624)
			(xy 12.633349 -114.34898) (xy 12.68293 -114.371622) (xy 12.728783 -114.40109) (xy 12.769975 -114.436783)
			(xy 12.805669 -114.477976) (xy 12.835137 -114.523829) (xy 12.85778 -114.573409) (xy 12.873136 -114.625706)
			(xy 12.880893 -114.679657) (xy 12.880893 -114.734163) (xy 12.873136 -114.788114) (xy 12.85778 -114.840411)
			(xy 12.835137 -114.889991) (xy 12.805669 -114.935844) (xy 12.769975 -114.977037) (xy 12.728783 -115.01273)
			(xy 12.68293 -115.042198) (xy 12.633349 -115.06484) (xy 12.581052 -115.080196) (xy 12.527101 -115.087953)
			(xy 12.499848 -115.088416) (xy 11.636248 -115.088416) (xy 11.608997 -115.087934) (xy 11.555049 -115.080177)
			(xy 11.502754 -115.064822) (xy 11.453177 -115.042181) (xy 11.407326 -115.012714) (xy 11.366136 -114.977022)
			(xy 11.330445 -114.935832) (xy 11.300979 -114.889981) (xy 11.278337 -114.840404) (xy 11.262982 -114.788109)
			(xy 11.255226 -114.734161) (xy 2.509012 -114.734161) (xy 2.509012 -133.480302) (xy 20.179284 -133.480302)
			(xy 20.179284 -132.489702) (xy 20.17977 -132.462451) (xy 20.187526 -132.408503) (xy 20.202881 -132.356208)
			(xy 20.225523 -132.306631) (xy 20.254989 -132.260781) (xy 20.29068 -132.21959) (xy 20.331871 -132.183899)
			(xy 20.377721 -132.154433) (xy 20.427298 -132.131791) (xy 20.479593 -132.116436) (xy 20.533541 -132.10868)
			(xy 20.588043 -132.10868) (xy 20.641991 -132.116436) (xy 20.694286 -132.131791) (xy 20.743863 -132.154433)
			(xy 20.789713 -132.183899) (xy 20.830904 -132.21959) (xy 20.866595 -132.260781) (xy 20.896061 -132.306631)
			(xy 20.918703 -132.356208) (xy 20.934058 -132.408503) (xy 20.941814 -132.462451) (xy 20.9423 -132.489702)
			(xy 20.9423 -133.480302) (xy 20.941814 -133.507553) (xy 20.934058 -133.561501) (xy 20.918703 -133.613796)
			(xy 20.896061 -133.663373) (xy 20.866595 -133.709223) (xy 20.830904 -133.750414) (xy 20.789713 -133.786105)
			(xy 20.743863 -133.815571) (xy 20.694286 -133.838213) (xy 20.641991 -133.853568) (xy 20.588043 -133.861324)
			(xy 20.533541 -133.861324) (xy 20.479593 -133.853568) (xy 20.427298 -133.838213) (xy 20.377721 -133.815571)
			(xy 20.331871 -133.786105) (xy 20.29068 -133.750414) (xy 20.254989 -133.709223) (xy 20.225523 -133.663373)
			(xy 20.202881 -133.613796) (xy 20.187526 -133.561501) (xy 20.17977 -133.507553) (xy 20.179284 -133.480302)
			(xy 2.509012 -133.480302) (xy 2.509012 -138.001502) (xy 20.019264 -138.001502) (xy 20.019264 -137.010902)
			(xy 20.01975 -136.983651) (xy 20.027506 -136.929703) (xy 20.042861 -136.877408) (xy 20.065503 -136.827831)
			(xy 20.094969 -136.781981) (xy 20.13066 -136.74079) (xy 20.171851 -136.705099) (xy 20.217701 -136.675633)
			(xy 20.267278 -136.652991) (xy 20.319573 -136.637636) (xy 20.373521 -136.62988) (xy 20.428023 -136.62988)
			(xy 20.481971 -136.637636) (xy 20.534266 -136.652991) (xy 20.583843 -136.675633) (xy 20.629693 -136.705099)
			(xy 20.670884 -136.74079) (xy 20.706575 -136.781981) (xy 20.736041 -136.827831) (xy 20.758683 -136.877408)
			(xy 20.774038 -136.929703) (xy 20.781794 -136.983651) (xy 20.78228 -137.010902) (xy 20.78228 -138.001502)
			(xy 20.781794 -138.028753) (xy 20.774038 -138.082701) (xy 20.758683 -138.134996) (xy 20.736041 -138.184573)
			(xy 20.706575 -138.230423) (xy 20.670884 -138.271614) (xy 20.629693 -138.307305) (xy 20.583843 -138.336771)
			(xy 20.534266 -138.359413) (xy 20.481971 -138.374768) (xy 20.428023 -138.382524) (xy 20.373521 -138.382524)
			(xy 20.319573 -138.374768) (xy 20.267278 -138.359413) (xy 20.217701 -138.336771) (xy 20.171851 -138.307305)
			(xy 20.13066 -138.271614) (xy 20.094969 -138.230423) (xy 20.065503 -138.184573) (xy 20.042861 -138.134996)
			(xy 20.027506 -138.082701) (xy 20.01975 -138.028753) (xy 20.019264 -138.001502) (xy 2.509012 -138.001502)
			(xy 2.509012 -145.104166) (xy 163.29995 -145.104166) (xy 163.29995 -145.049634) (xy 163.30771 -144.995658)
			(xy 163.323072 -144.943336) (xy 163.345724 -144.893732) (xy 163.375204 -144.847856) (xy 163.410912 -144.806643)
			(xy 163.452121 -144.77093) (xy 163.497993 -144.741445) (xy 163.547595 -144.718788) (xy 163.599915 -144.70342)
			(xy 163.653891 -144.695653) (xy 163.681156 -144.695164) (xy 164.671756 -144.695164) (xy 164.699031 -144.695573)
			(xy 164.753026 -144.70333) (xy 164.805368 -144.718694) (xy 164.85499 -144.74135) (xy 164.900882 -144.770839)
			(xy 164.94211 -144.806559) (xy 164.977835 -144.847783) (xy 165.007329 -144.893672) (xy 165.029991 -144.943291)
			(xy 165.045361 -144.995631) (xy 165.053124 -145.049625) (xy 165.053124 -145.104175) (xy 165.045361 -145.158169)
			(xy 165.029991 -145.210509) (xy 165.007329 -145.260128) (xy 164.977835 -145.306017) (xy 164.94211 -145.347241)
			(xy 164.900882 -145.382961) (xy 164.85499 -145.41245) (xy 164.805368 -145.435106) (xy 164.753026 -145.45047)
			(xy 164.699031 -145.458227) (xy 164.671756 -145.458688) (xy 163.681156 -145.458688) (xy 163.653891 -145.458147)
			(xy 163.599915 -145.45038) (xy 163.547595 -145.435012) (xy 163.497993 -145.412355) (xy 163.452121 -145.38287)
			(xy 163.410912 -145.347157) (xy 163.375204 -145.305944) (xy 163.345724 -145.260068) (xy 163.323072 -145.210464)
			(xy 163.30771 -145.158142) (xy 163.29995 -145.104166) (xy 2.509012 -145.104166) (xy 2.509012 -153.765504)
			(xy 24.441921 -153.765504) (xy 24.445917 -153.555618) (xy 24.457902 -153.346036) (xy 24.477856 -153.137062)
			(xy 24.505752 -152.929) (xy 24.541549 -152.72215) (xy 24.585194 -152.516813) (xy 24.636626 -152.313287)
			(xy 24.695768 -152.111866) (xy 24.762536 -151.912843) (xy 24.836832 -151.716506) (xy 24.91855 -151.52314)
			(xy 25.007569 -151.333025) (xy 25.103762 -151.146437) (xy 25.206989 -150.963646) (xy 25.3171 -150.784918)
			(xy 25.433935 -150.610511) (xy 25.557325 -150.440679) (xy 25.687092 -150.275667) (xy 25.823046 -150.115716)
			(xy 25.964992 -149.961056) (xy 26.112722 -149.811912) (xy 26.266024 -149.668501) (xy 26.424674 -149.53103)
			(xy 26.588443 -149.399698) (xy 26.757093 -149.274697) (xy 26.930379 -149.156206) (xy 27.108051 -149.044399)
			(xy 27.289851 -148.939437) (xy 27.475515 -148.841472) (xy 27.664773 -148.750647) (xy 27.857353 -148.667093)
			(xy 28.052974 -148.59093) (xy 28.251352 -148.522271) (xy 28.452201 -148.461214) (xy 28.655228 -148.407847)
			(xy 28.860141 -148.362249) (xy 29.06664 -148.324484) (xy 29.274427 -148.294609) (xy 29.483202 -148.272666)
			(xy 29.69266 -148.258687) (xy 29.902499 -148.252692) (xy 30.112413 -148.254691) (xy 30.3221 -148.264679)
			(xy 30.531254 -148.282644) (xy 30.739572 -148.308558) (xy 30.946753 -148.342383) (xy 31.152497 -148.384072)
			(xy 31.356503 -148.433564) (xy 31.558478 -148.490786) (xy 31.758128 -148.555656) (xy 31.955163 -148.62808)
			(xy 32.149299 -148.707953) (xy 32.340252 -148.795159) (xy 32.527748 -148.889571) (xy 32.711513 -148.991053)
			(xy 32.891281 -149.099457) (xy 33.066792 -149.214627) (xy 33.237791 -149.336395) (xy 33.404031 -149.464584)
			(xy 33.56527 -149.59901) (xy 33.721274 -149.739477) (xy 33.871817 -149.885781) (xy 34.016681 -150.03771)
			(xy 34.155656 -150.195044) (xy 34.288541 -150.357555) (xy 34.415142 -150.525008) (xy 34.535277 -150.697158)
			(xy 34.648771 -150.873758) (xy 34.688915 -150.941786) (xy 108.742233 -150.941786) (xy 108.746238 -150.836037)
			(xy 108.758228 -150.730894) (xy 108.778137 -150.626959) (xy 108.805848 -150.524827) (xy 108.841205 -150.425083)
			(xy 108.884003 -150.328299) (xy 108.933999 -150.235029) (xy 108.990906 -150.145808) (xy 109.054397 -150.061145)
			(xy 109.124109 -149.981527) (xy 109.199643 -149.907409) (xy 109.280566 -149.839216) (xy 109.366415 -149.777338)
			(xy 109.456698 -149.722131) (xy 109.550897 -149.673909) (xy 109.648474 -149.632949) (xy 109.748869 -149.599487)
			(xy 109.851507 -149.573713) (xy 109.9558 -149.555775) (xy 110.061151 -149.545776) (xy 110.166957 -149.543773)
			(xy 110.272611 -149.549778) (xy 110.377508 -149.563757) (xy 110.481048 -149.585628) (xy 110.582637 -149.615268)
			(xy 110.681694 -149.652506) (xy 110.777651 -149.697128) (xy 110.869958 -149.74888) (xy 110.958087 -149.807465)
			(xy 111.041533 -149.872547) (xy 111.119817 -149.943753) (xy 111.187365 -150.015249) (xy 160.856694 -150.015249)
			(xy 160.856694 -149.960751) (xy 160.86445 -149.906808) (xy 160.879803 -149.854517) (xy 160.902441 -149.804944)
			(xy 160.931904 -149.759096) (xy 160.967592 -149.717909) (xy 161.008777 -149.682219) (xy 161.054623 -149.652753)
			(xy 161.104195 -149.630111) (xy 161.156484 -149.614755) (xy 161.210427 -149.606996) (xy 161.237676 -149.606508)
			(xy 162.228276 -149.606508) (xy 162.255531 -149.606937) (xy 162.309487 -149.614692) (xy 162.36179 -149.630046)
			(xy 162.411375 -149.652688) (xy 162.457233 -149.682157) (xy 162.498431 -149.717852) (xy 162.534128 -149.759047)
			(xy 162.5636 -149.804904) (xy 162.586245 -149.854488) (xy 162.601603 -149.90679) (xy 162.609361 -149.960745)
			(xy 162.609361 -149.967557) (xy 163.793819 -149.967557) (xy 163.793819 -149.913043) (xy 163.801578 -149.859084)
			(xy 163.816937 -149.806779) (xy 163.839584 -149.757192) (xy 163.869057 -149.711333) (xy 163.904758 -149.670135)
			(xy 163.945958 -149.634438) (xy 163.99182 -149.604968) (xy 164.041409 -149.582325) (xy 164.093716 -149.566971)
			(xy 164.147675 -149.559217) (xy 164.174932 -149.558756) (xy 165.165532 -149.558756) (xy 165.192779 -149.559316)
			(xy 165.246718 -149.567076) (xy 165.299004 -149.582432) (xy 165.348573 -149.605073) (xy 165.394415 -149.634537)
			(xy 165.435597 -149.670226) (xy 165.471282 -149.711411) (xy 165.500742 -149.757255) (xy 165.523379 -149.806826)
			(xy 165.538731 -149.859113) (xy 165.546486 -149.913053) (xy 165.546486 -149.967547) (xy 165.538731 -150.021487)
			(xy 165.523379 -150.073774) (xy 165.500742 -150.123345) (xy 165.471282 -150.169189) (xy 165.435597 -150.210374)
			(xy 165.394415 -150.246063) (xy 165.348573 -150.275527) (xy 165.299004 -150.298168) (xy 165.246718 -150.313524)
			(xy 165.192779 -150.321284) (xy 165.165532 -150.321772) (xy 164.174932 -150.321772) (xy 164.147675 -150.321383)
			(xy 164.093716 -150.313629) (xy 164.041409 -150.298275) (xy 163.99182 -150.275632) (xy 163.945958 -150.246162)
			(xy 163.904758 -150.210465) (xy 163.869057 -150.169267) (xy 163.839584 -150.123408) (xy 163.816937 -150.073821)
			(xy 163.801578 -150.021516) (xy 163.793819 -149.967557) (xy 162.609361 -149.967557) (xy 162.609361 -150.015255)
			(xy 162.601603 -150.06921) (xy 162.586245 -150.121512) (xy 162.5636 -150.171096) (xy 162.534128 -150.216953)
			(xy 162.498431 -150.258148) (xy 162.457233 -150.293843) (xy 162.411375 -150.323312) (xy 162.36179 -150.345954)
			(xy 162.309487 -150.361308) (xy 162.255531 -150.369063) (xy 162.228276 -150.369524) (xy 161.237676 -150.369524)
			(xy 161.210427 -150.369004) (xy 161.156484 -150.361245) (xy 161.104195 -150.345889) (xy 161.054623 -150.323247)
			(xy 161.008777 -150.293781) (xy 160.967592 -150.258091) (xy 160.931904 -150.216904) (xy 160.902441 -150.171056)
			(xy 160.879803 -150.121483) (xy 160.86445 -150.069192) (xy 160.856694 -150.015249) (xy 111.187365 -150.015249)
			(xy 111.192492 -150.020676) (xy 111.259142 -150.102876) (xy 111.319384 -150.18988) (xy 111.372873 -150.281191)
			(xy 111.419304 -150.376286) (xy 111.458409 -150.47462) (xy 111.489966 -150.575631) (xy 111.513793 -150.678738)
			(xy 111.529754 -150.783352) (xy 111.537758 -150.888874) (xy 111.538258 -150.941786) (xy 111.537758 -150.994698)
			(xy 111.529754 -151.10022) (xy 111.513793 -151.204834) (xy 111.489966 -151.307941) (xy 111.458409 -151.408952)
			(xy 111.419304 -151.507286) (xy 111.372873 -151.602381) (xy 111.319384 -151.693692) (xy 111.259142 -151.780696)
			(xy 111.192492 -151.862896) (xy 111.119817 -151.939819) (xy 111.041533 -152.011025) (xy 110.958087 -152.076107)
			(xy 110.869958 -152.134692) (xy 110.777651 -152.186444) (xy 110.681694 -152.231066) (xy 110.582637 -152.268304)
			(xy 110.481048 -152.297944) (xy 110.377508 -152.319815) (xy 110.272611 -152.333794) (xy 110.166957 -152.339799)
			(xy 110.061151 -152.337796) (xy 109.9558 -152.327797) (xy 109.851507 -152.309859) (xy 109.748869 -152.284085)
			(xy 109.648474 -152.250623) (xy 109.550897 -152.209663) (xy 109.456698 -152.161441) (xy 109.366415 -152.106234)
			(xy 109.280566 -152.044356) (xy 109.199643 -151.976163) (xy 109.124109 -151.902045) (xy 109.054397 -151.822427)
			(xy 108.990906 -151.737764) (xy 108.933999 -151.648543) (xy 108.884003 -151.555273) (xy 108.841205 -151.458489)
			(xy 108.805848 -151.358745) (xy 108.778137 -151.256613) (xy 108.758228 -151.152678) (xy 108.746238 -151.047535)
			(xy 108.742233 -150.941786) (xy 34.688915 -150.941786) (xy 34.755459 -151.05455) (xy 34.855186 -151.239273)
			(xy 34.947809 -151.427659) (xy 35.033193 -151.619434) (xy 35.111214 -151.814321) (xy 35.181759 -152.012037)
			(xy 35.244726 -152.212295) (xy 35.300023 -152.414805) (xy 35.34757 -152.619274) (xy 35.354948 -152.657556)
			(xy 115.368832 -152.657556) (xy 115.369254 -152.619267) (xy 115.375857 -152.542973) (xy 115.389002 -152.46753)
			(xy 115.40859 -152.393499) (xy 115.421156 -152.357328) (xy 115.423829 -152.348897) (xy 115.423815 -152.331221)
			(xy 115.421156 -152.322784) (xy 115.408624 -152.286603) (xy 115.389048 -152.212571) (xy 115.375898 -152.137132)
			(xy 115.36927 -152.060844) (xy 115.368832 -152.022556) (xy 115.369211 -151.981443) (xy 115.376803 -151.89957)
			(xy 115.391918 -151.818746) (xy 115.414428 -151.739662) (xy 115.44414 -151.662993) (xy 115.480801 -151.589393)
			(xy 115.524097 -151.51949) (xy 115.573659 -151.453881) (xy 115.629065 -151.393126) (xy 115.689841 -151.337743)
			(xy 115.755469 -151.288206) (xy 115.825388 -151.244936) (xy 115.899002 -151.208303) (xy 115.975683 -151.178621)
			(xy 116.054775 -151.156141) (xy 116.135605 -151.141056) (xy 116.217481 -151.133495) (xy 116.258594 -151.133048)
			(xy 116.29691 -151.133415) (xy 116.373264 -151.139947) (xy 116.448771 -151.153032) (xy 116.52287 -151.172572)
			(xy 116.559076 -151.185118) (xy 116.567392 -151.187704) (xy 116.584796 -151.187704) (xy 116.593112 -151.185118)
			(xy 116.629327 -151.172602) (xy 116.703427 -151.153078) (xy 116.778931 -151.139993) (xy 116.855279 -151.133443)
			(xy 116.893594 -151.133048) (xy 116.933808 -151.133478) (xy 117.01391 -151.140701) (xy 117.093031 -151.155132)
			(xy 117.170525 -151.176654) (xy 117.2083 -151.190452) (xy 117.217087 -151.193359) (xy 117.235581 -151.193359)
			(xy 117.244368 -151.190452) (xy 117.282145 -151.176662) (xy 117.359642 -151.155155) (xy 117.438762 -151.140723)
			(xy 117.518861 -151.133486) (xy 117.559074 -151.133048) (xy 117.59739 -151.133421) (xy 117.673744 -151.139951)
			(xy 117.74925 -151.153034) (xy 117.82335 -151.172573) (xy 117.859556 -151.185118) (xy 117.867872 -151.187704)
			(xy 117.885276 -151.187704) (xy 117.893592 -151.185118) (xy 117.929809 -151.172608) (xy 118.003908 -151.153082)
			(xy 118.079411 -151.139995) (xy 118.155759 -151.133444) (xy 118.194074 -151.133048) (xy 118.23239 -151.133421)
			(xy 118.308744 -151.139951) (xy 118.38425 -151.153034) (xy 118.45835 -151.172573) (xy 118.494556 -151.185118)
			(xy 118.502872 -151.187704) (xy 118.520276 -151.187704) (xy 118.528592 -151.185118) (xy 118.564809 -151.172608)
			(xy 118.638908 -151.153082) (xy 118.714411 -151.139995) (xy 118.790759 -151.133444) (xy 118.829074 -151.133048)
			(xy 118.86739 -151.133421) (xy 118.943744 -151.139951) (xy 119.01925 -151.153034) (xy 119.09335 -151.172573)
			(xy 119.129556 -151.185118) (xy 119.137872 -151.187704) (xy 119.155276 -151.187704) (xy 119.163592 -151.185118)
			(xy 119.199718 -151.172636) (xy 119.273629 -151.153143) (xy 119.348939 -151.140056) (xy 119.425093 -151.133472)
			(xy 119.463312 -151.133048) (xy 119.464074 -151.133048) (xy 119.505181 -151.133537) (xy 119.587043 -151.141119)
			(xy 119.667858 -151.156221) (xy 119.746934 -151.178714) (xy 119.823598 -151.208407) (xy 119.897196 -151.245045)
			(xy 119.9671 -151.288316) (xy 120.032714 -151.337852) (xy 120.093479 -151.39323) (xy 120.148875 -151.453978)
			(xy 120.198431 -151.519577) (xy 120.241724 -151.589468) (xy 120.278384 -151.663055) (xy 120.3081 -151.73971)
			(xy 120.330617 -151.818779) (xy 120.345743 -151.899589) (xy 120.35335 -151.98145) (xy 120.353836 -152.022556)
			(xy 120.353419 -152.060846) (xy 120.346814 -152.137139) (xy 120.333668 -152.212582) (xy 120.314078 -152.286613)
			(xy 120.301512 -152.322784) (xy 120.298884 -152.331226) (xy 120.29887 -152.348891) (xy 120.301512 -152.357328)
			(xy 120.314046 -152.393509) (xy 120.333622 -152.467541) (xy 120.346772 -152.542979) (xy 120.353399 -152.619268)
			(xy 120.353836 -152.657556) (xy 120.353306 -152.698665) (xy 120.345722 -152.780533) (xy 120.330616 -152.861351)
			(xy 120.308115 -152.940431) (xy 120.278413 -153.017096) (xy 120.241762 -153.090693) (xy 120.198476 -153.160594)
			(xy 120.148923 -153.226202) (xy 120.093528 -153.286957) (xy 120.032762 -153.34234) (xy 119.967144 -153.391879)
			(xy 119.897234 -153.435151) (xy 119.823629 -153.471786) (xy 119.746958 -153.501473) (xy 119.667874 -153.523957)
			(xy 119.587052 -153.539047) (xy 119.505183 -153.546614) (xy 119.464074 -153.547064) (xy 119.425757 -153.546706)
			(xy 119.349404 -153.540171) (xy 119.273897 -153.527084) (xy 119.199798 -153.507541) (xy 119.163592 -153.494994)
			(xy 119.155276 -153.492408) (xy 119.137872 -153.492408) (xy 119.129556 -153.494994) (xy 119.093344 -153.507519)
			(xy 119.019243 -153.527041) (xy 118.943738 -153.540123) (xy 118.867389 -153.546671) (xy 118.829074 -153.547064)
			(xy 118.790757 -153.546706) (xy 118.714404 -153.540171) (xy 118.638897 -153.527084) (xy 118.564798 -153.507541)
			(xy 118.528592 -153.494994) (xy 118.520276 -153.492408) (xy 118.502872 -153.492408) (xy 118.494556 -153.494994)
			(xy 118.458344 -153.507519) (xy 118.384243 -153.527041) (xy 118.308738 -153.540123) (xy 118.232389 -153.546671)
			(xy 118.194074 -153.547064) (xy 118.155757 -153.546706) (xy 118.079404 -153.540171) (xy 118.003897 -153.527084)
			(xy 117.929798 -153.507541) (xy 117.893592 -153.494994) (xy 117.885276 -153.492408) (xy 117.867872 -153.492408)
			(xy 117.859556 -153.494994) (xy 117.823344 -153.507519) (xy 117.749243 -153.527041) (xy 117.673738 -153.540123)
			(xy 117.597389 -153.546671) (xy 117.559074 -153.547064) (xy 117.51886 -153.546643) (xy 117.438758 -153.539418)
			(xy 117.359636 -153.524984) (xy 117.282143 -153.50346) (xy 117.244368 -153.48966) (xy 117.235581 -153.486753)
			(xy 117.217087 -153.486753) (xy 117.2083 -153.48966) (xy 117.170526 -153.50346) (xy 117.093029 -153.524965)
			(xy 117.013907 -153.539393) (xy 116.933807 -153.546627) (xy 116.893594 -153.547064) (xy 116.855277 -153.5467)
			(xy 116.778924 -153.540167) (xy 116.703417 -153.527082) (xy 116.629318 -153.50754) (xy 116.593112 -153.494994)
			(xy 116.584796 -153.492408) (xy 116.567392 -153.492408) (xy 116.559076 -153.494994) (xy 116.522953 -153.507485)
			(xy 116.449041 -153.526976) (xy 116.37373 -153.54006) (xy 116.297575 -153.546641) (xy 116.259356 -153.547064)
			(xy 116.258594 -153.547064) (xy 116.217487 -153.546593) (xy 116.135624 -153.539008) (xy 116.05481 -153.523904)
			(xy 115.975734 -153.501409) (xy 115.89907 -153.471714) (xy 115.825473 -153.435075) (xy 115.755569 -153.391802)
			(xy 115.689955 -153.342264) (xy 115.629192 -153.286885) (xy 115.573796 -153.226137) (xy 115.52424 -153.160537)
			(xy 115.480947 -153.090646) (xy 115.444287 -153.017059) (xy 115.414571 -152.940403) (xy 115.392053 -152.861333)
			(xy 115.376926 -152.780524) (xy 115.369318 -152.698663) (xy 115.368832 -152.657556) (xy 35.354948 -152.657556)
			(xy 35.387298 -152.825405) (xy 35.41915 -153.032898) (xy 35.44308 -153.241454) (xy 35.459052 -153.45077)
			(xy 35.467044 -153.660542) (xy 35.467544 -153.765504) (xy 35.467044 -153.870466) (xy 35.459052 -154.080238)
			(xy 35.44308 -154.289554) (xy 35.422918 -154.465274) (xy 127.823468 -154.465274) (xy 127.824038 -154.420505)
			(xy 127.833047 -154.33142) (xy 127.850949 -154.243689) (xy 127.877566 -154.158197) (xy 127.894588 -154.116786)
			(xy 127.89817 -154.1072) (xy 127.89816 -154.086753) (xy 127.894588 -154.077162) (xy 127.87754 -154.03576)
			(xy 127.850909 -153.95027) (xy 127.833008 -153.862535) (xy 127.824018 -153.773445) (xy 127.823468 -153.728674)
			(xy 127.824038 -153.683905) (xy 127.833047 -153.59482) (xy 127.850949 -153.507089) (xy 127.877566 -153.421597)
			(xy 127.894588 -153.380186) (xy 127.89817 -153.3706) (xy 127.89816 -153.350153) (xy 127.894588 -153.340562)
			(xy 127.87754 -153.29916) (xy 127.850909 -153.21367) (xy 127.833008 -153.125935) (xy 127.824018 -153.036845)
			(xy 127.823468 -152.992074) (xy 127.823874 -152.950958) (xy 127.831464 -152.869076) (xy 127.846576 -152.788245)
			(xy 127.869082 -152.709152) (xy 127.898791 -152.632473) (xy 127.935447 -152.558863) (xy 127.978739 -152.488949)
			(xy 128.028297 -152.423328) (xy 128.083699 -152.362559) (xy 128.144471 -152.307161) (xy 128.210095 -152.257607)
			(xy 128.280012 -152.21432) (xy 128.353625 -152.177668) (xy 128.430305 -152.147965) (xy 128.509399 -152.125463)
			(xy 128.590232 -152.110356) (xy 128.672114 -152.102771) (xy 128.71323 -152.102312) (xy 128.754841 -152.102773)
			(xy 128.837698 -152.110553) (xy 128.919467 -152.126031) (xy 128.999435 -152.149074) (xy 129.076903 -152.179479)
			(xy 129.151195 -152.216982) (xy 129.186686 -152.23871) (xy 129.195829 -152.243863) (xy 129.216542 -152.24708)
			(xy 129.236814 -152.241752) (xy 129.24536 -152.235662) (xy 129.278989 -152.209671) (xy 129.350383 -152.163546)
			(xy 129.425854 -152.124445) (xy 129.504712 -152.092724) (xy 129.586237 -152.068675) (xy 129.669685 -152.052515)
			(xy 129.754295 -152.044393) (xy 129.796794 -152.043892) (xy 129.837907 -152.044419) (xy 129.919782 -152.052005)
			(xy 130.000607 -152.067113) (xy 130.079694 -152.089613) (xy 130.156368 -152.119315) (xy 130.229974 -152.155965)
			(xy 130.299884 -152.19925) (xy 130.365503 -152.2488) (xy 130.42627 -152.304193) (xy 130.481667 -152.364957)
			(xy 130.531221 -152.430573) (xy 130.57451 -152.500481) (xy 130.611164 -152.574085) (xy 130.64087 -152.650756)
			(xy 130.663376 -152.729842) (xy 130.678488 -152.810667) (xy 130.686079 -152.892541) (xy 130.686556 -152.933654)
			(xy 130.685993 -152.978424) (xy 130.676983 -153.067509) (xy 130.659077 -153.15524) (xy 130.632459 -153.240731)
			(xy 130.615436 -153.282142) (xy 130.611899 -153.291741) (xy 130.611882 -153.312176) (xy 130.615436 -153.321766)
			(xy 130.63244 -153.363117) (xy 130.659051 -153.448479) (xy 130.676958 -153.536082) (xy 130.68598 -153.625039)
			(xy 130.686556 -153.669746) (xy 130.686556 -153.670762) (xy 130.686302 -153.682192) (xy 130.712781 -153.688138)
			(xy 130.765016 -153.702881) (xy 130.790696 -153.711656) (xy 130.798893 -153.71417) (xy 130.816027 -153.71417)
			(xy 130.824224 -153.711656) (xy 130.85944 -153.699695) (xy 130.931444 -153.681041) (xy 131.004765 -153.668532)
			(xy 131.07888 -153.662259) (xy 131.11607 -153.661872) (xy 131.153259 -153.662271) (xy 131.227372 -153.668558)
			(xy 131.300692 -153.681065) (xy 131.372698 -153.699703) (xy 131.407916 -153.711656) (xy 131.416113 -153.71417)
			(xy 131.433247 -153.71417) (xy 131.441444 -153.711656) (xy 131.476659 -153.699689) (xy 131.548662 -153.681037)
			(xy 131.621984 -153.66853) (xy 131.6961 -153.662258) (xy 131.73329 -153.661872) (xy 131.77523 -153.662267)
			(xy 131.858732 -153.670239) (xy 131.941097 -153.686113) (xy 132.02158 -153.709744) (xy 132.099453 -153.740919)
			(xy 132.165372 -153.774902) (xy 188.441847 -153.774902) (xy 188.445843 -153.565016) (xy 188.457828 -153.355434)
			(xy 188.477782 -153.14646) (xy 188.505678 -152.938398) (xy 188.541475 -152.731548) (xy 188.58512 -152.526211)
			(xy 188.636552 -152.322685) (xy 188.695694 -152.121264) (xy 188.762462 -151.922241) (xy 188.836758 -151.725904)
			(xy 188.918476 -151.532538) (xy 189.007495 -151.342423) (xy 189.103688 -151.155835) (xy 189.206915 -150.973044)
			(xy 189.317026 -150.794316) (xy 189.433861 -150.619909) (xy 189.557251 -150.450077) (xy 189.687018 -150.285065)
			(xy 189.822972 -150.125114) (xy 189.964918 -149.970454) (xy 190.112648 -149.82131) (xy 190.26595 -149.677899)
			(xy 190.4246 -149.540428) (xy 190.588369 -149.409096) (xy 190.757019 -149.284095) (xy 190.930305 -149.165604)
			(xy 191.107977 -149.053797) (xy 191.289777 -148.948835) (xy 191.475441 -148.85087) (xy 191.664699 -148.760045)
			(xy 191.857279 -148.676491) (xy 192.0529 -148.600328) (xy 192.251278 -148.531669) (xy 192.452127 -148.470612)
			(xy 192.655154 -148.417245) (xy 192.860067 -148.371647) (xy 193.066566 -148.333882) (xy 193.274353 -148.304007)
			(xy 193.483128 -148.282064) (xy 193.692586 -148.268085) (xy 193.902425 -148.26209) (xy 194.112339 -148.264089)
			(xy 194.322026 -148.274077) (xy 194.53118 -148.292042) (xy 194.739498 -148.317956) (xy 194.946679 -148.351781)
			(xy 195.152423 -148.39347) (xy 195.356429 -148.442962) (xy 195.558404 -148.500184) (xy 195.758054 -148.565054)
			(xy 195.955089 -148.637478) (xy 196.149225 -148.717351) (xy 196.340178 -148.804557) (xy 196.527674 -148.898969)
			(xy 196.711439 -149.000451) (xy 196.891207 -149.108855) (xy 197.066718 -149.224025) (xy 197.237717 -149.345793)
			(xy 197.403957 -149.473982) (xy 197.565196 -149.608408) (xy 197.7212 -149.748875) (xy 197.871743 -149.895179)
			(xy 198.016607 -150.047108) (xy 198.155582 -150.204442) (xy 198.288467 -150.366953) (xy 198.415068 -150.534406)
			(xy 198.535203 -150.706556) (xy 198.648697 -150.883156) (xy 198.755385 -151.063948) (xy 198.855112 -151.248671)
			(xy 198.947735 -151.437057) (xy 199.033119 -151.628832) (xy 199.11114 -151.823719) (xy 199.181685 -152.021435)
			(xy 199.244652 -152.221693) (xy 199.299949 -152.424203) (xy 199.347496 -152.628672) (xy 199.387224 -152.834803)
			(xy 199.419076 -153.042296) (xy 199.443006 -153.250852) (xy 199.458978 -153.460168) (xy 199.46697 -153.66994)
			(xy 199.467428 -153.766012) (xy 272.382243 -153.766012) (xy 272.386239 -153.556126) (xy 272.398224 -153.346544)
			(xy 272.418178 -153.13757) (xy 272.446074 -152.929508) (xy 272.481871 -152.722658) (xy 272.525516 -152.517321)
			(xy 272.576948 -152.313795) (xy 272.63609 -152.112374) (xy 272.702858 -151.913351) (xy 272.777154 -151.717014)
			(xy 272.858872 -151.523648) (xy 272.947891 -151.333533) (xy 273.044084 -151.146945) (xy 273.147311 -150.964154)
			(xy 273.257422 -150.785426) (xy 273.374257 -150.611019) (xy 273.497647 -150.441187) (xy 273.627414 -150.276175)
			(xy 273.763368 -150.116224) (xy 273.905314 -149.961564) (xy 274.053044 -149.81242) (xy 274.206346 -149.669009)
			(xy 274.364996 -149.531538) (xy 274.528765 -149.400206) (xy 274.697415 -149.275205) (xy 274.870701 -149.156714)
			(xy 275.048373 -149.044907) (xy 275.230173 -148.939945) (xy 275.415837 -148.84198) (xy 275.605095 -148.751155)
			(xy 275.797675 -148.667601) (xy 275.993296 -148.591438) (xy 276.191674 -148.522779) (xy 276.392523 -148.461722)
			(xy 276.59555 -148.408355) (xy 276.800463 -148.362757) (xy 277.006962 -148.324992) (xy 277.214749 -148.295117)
			(xy 277.423524 -148.273174) (xy 277.632982 -148.259195) (xy 277.842821 -148.2532) (xy 278.052735 -148.255199)
			(xy 278.262422 -148.265187) (xy 278.471576 -148.283152) (xy 278.679894 -148.309066) (xy 278.887075 -148.342891)
			(xy 279.092819 -148.38458) (xy 279.296825 -148.434072) (xy 279.4988 -148.491294) (xy 279.69845 -148.556164)
			(xy 279.895485 -148.628588) (xy 280.089621 -148.708461) (xy 280.280574 -148.795667) (xy 280.46807 -148.890079)
			(xy 280.651835 -148.991561) (xy 280.831603 -149.099965) (xy 281.007114 -149.215135) (xy 281.178113 -149.336903)
			(xy 281.344353 -149.465092) (xy 281.505592 -149.599518) (xy 281.661596 -149.739985) (xy 281.812139 -149.886289)
			(xy 281.957003 -150.038218) (xy 282.095978 -150.195552) (xy 282.228863 -150.358063) (xy 282.355464 -150.525516)
			(xy 282.475599 -150.697666) (xy 282.589093 -150.874266) (xy 282.695781 -151.055058) (xy 282.795508 -151.239781)
			(xy 282.888131 -151.428167) (xy 282.973515 -151.619942) (xy 283.051536 -151.814829) (xy 283.122081 -152.012545)
			(xy 283.185048 -152.212803) (xy 283.240345 -152.415313) (xy 283.287892 -152.619782) (xy 283.305746 -152.71242)
			(xy 358.186997 -152.71242) (xy 358.191002 -152.606671) (xy 358.202992 -152.501528) (xy 358.222901 -152.397593)
			(xy 358.250612 -152.295461) (xy 358.285969 -152.195717) (xy 358.328767 -152.098933) (xy 358.378763 -152.005663)
			(xy 358.43567 -151.916442) (xy 358.499161 -151.831779) (xy 358.568873 -151.752161) (xy 358.644407 -151.678043)
			(xy 358.72533 -151.60985) (xy 358.811179 -151.547972) (xy 358.901462 -151.492765) (xy 358.995661 -151.444543)
			(xy 359.093238 -151.403583) (xy 359.193633 -151.370121) (xy 359.296271 -151.344347) (xy 359.400564 -151.326409)
			(xy 359.505915 -151.31641) (xy 359.611721 -151.314407) (xy 359.717375 -151.320412) (xy 359.822272 -151.334391)
			(xy 359.925812 -151.356262) (xy 360.027401 -151.385902) (xy 360.126458 -151.42314) (xy 360.222415 -151.467762)
			(xy 360.314722 -151.519514) (xy 360.402851 -151.578099) (xy 360.486297 -151.643181) (xy 360.564581 -151.714387)
			(xy 360.637256 -151.79131) (xy 360.703906 -151.87351) (xy 360.764148 -151.960514) (xy 360.817637 -152.051825)
			(xy 360.864068 -152.14692) (xy 360.903173 -152.245254) (xy 360.93473 -152.346265) (xy 360.958557 -152.449372)
			(xy 360.974518 -152.553986) (xy 360.982522 -152.659508) (xy 360.983022 -152.71242) (xy 360.982522 -152.765332)
			(xy 360.974518 -152.870854) (xy 360.958557 -152.975468) (xy 360.93473 -153.078575) (xy 360.903173 -153.179586)
			(xy 360.864068 -153.27792) (xy 360.817637 -153.373015) (xy 360.764148 -153.464326) (xy 360.703906 -153.55133)
			(xy 360.637256 -153.63353) (xy 360.564581 -153.710453) (xy 360.486297 -153.781659) (xy 360.402851 -153.846741)
			(xy 360.314722 -153.905326) (xy 360.222415 -153.957078) (xy 360.126458 -154.0017) (xy 360.027401 -154.038938)
			(xy 359.925812 -154.068578) (xy 359.822272 -154.090449) (xy 359.717375 -154.104428) (xy 359.611721 -154.110433)
			(xy 359.505915 -154.10843) (xy 359.400564 -154.098431) (xy 359.296271 -154.080493) (xy 359.193633 -154.054719)
			(xy 359.093238 -154.021257) (xy 358.995661 -153.980297) (xy 358.901462 -153.932075) (xy 358.811179 -153.876868)
			(xy 358.72533 -153.81499) (xy 358.644407 -153.746797) (xy 358.568873 -153.672679) (xy 358.499161 -153.593061)
			(xy 358.43567 -153.508398) (xy 358.378763 -153.419177) (xy 358.328767 -153.325907) (xy 358.285969 -153.229123)
			(xy 358.250612 -153.129379) (xy 358.222901 -153.027247) (xy 358.202992 -152.923312) (xy 358.191002 -152.818169)
			(xy 358.186997 -152.71242) (xy 283.305746 -152.71242) (xy 283.32762 -152.825913) (xy 283.359472 -153.033406)
			(xy 283.383402 -153.241962) (xy 283.399374 -153.451278) (xy 283.407366 -153.66105) (xy 283.407866 -153.766012)
			(xy 283.407366 -153.870974) (xy 283.399374 -154.080746) (xy 283.383402 -154.290062) (xy 283.359472 -154.498618)
			(xy 283.32762 -154.706111) (xy 283.287892 -154.912242) (xy 283.240345 -155.116711) (xy 283.185048 -155.319221)
			(xy 283.122081 -155.519479) (xy 283.051536 -155.717195) (xy 282.973515 -155.912082) (xy 282.888131 -156.103857)
			(xy 282.795508 -156.292243) (xy 282.695781 -156.476966) (xy 282.589093 -156.657758) (xy 282.475599 -156.834358)
			(xy 282.355464 -157.006508) (xy 282.228863 -157.173961) (xy 282.095978 -157.336472) (xy 281.957003 -157.493806)
			(xy 281.812139 -157.645735) (xy 281.661596 -157.792039) (xy 281.505592 -157.932506) (xy 281.344353 -158.066932)
			(xy 281.178113 -158.195121) (xy 281.007114 -158.316889) (xy 280.831603 -158.432059) (xy 280.651835 -158.540463)
			(xy 280.46807 -158.641945) (xy 280.280574 -158.736357) (xy 280.089621 -158.823563) (xy 279.895485 -158.903436)
			(xy 279.69845 -158.97586) (xy 279.4988 -159.04073) (xy 279.382794 -159.073596) (xy 343.127076 -159.073596)
			(xy 343.127653 -159.028827) (xy 343.136659 -158.939742) (xy 343.15456 -158.852011) (xy 343.181175 -158.766519)
			(xy 343.198196 -158.725108) (xy 343.201765 -158.715518) (xy 343.201764 -158.695074) (xy 343.198196 -158.685484)
			(xy 343.181156 -158.644079) (xy 343.154522 -158.55859) (xy 343.136619 -158.470856) (xy 343.127627 -158.381767)
			(xy 343.127076 -158.336996) (xy 343.127653 -158.292227) (xy 343.136659 -158.203142) (xy 343.15456 -158.115411)
			(xy 343.181175 -158.029919) (xy 343.198196 -157.988508) (xy 343.201765 -157.978918) (xy 343.201764 -157.958474)
			(xy 343.198196 -157.948884) (xy 343.181156 -157.907479) (xy 343.154522 -157.82199) (xy 343.136619 -157.734256)
			(xy 343.127627 -157.645167) (xy 343.127076 -157.600396) (xy 343.127549 -157.559286) (xy 343.135137 -157.477416)
			(xy 343.150247 -157.396596) (xy 343.172752 -157.317516) (xy 343.202459 -157.240849) (xy 343.239114 -157.167252)
			(xy 343.282404 -157.097351) (xy 343.33196 -157.031743) (xy 343.387359 -156.970988) (xy 343.448129 -156.915605)
			(xy 343.51375 -156.866067) (xy 343.583663 -156.822796) (xy 343.657271 -156.786161) (xy 343.733945 -156.756475)
			(xy 343.813032 -156.733992) (xy 343.893856 -156.718903) (xy 343.975728 -156.711337) (xy 344.016838 -156.710888)
			(xy 344.058442 -156.711362) (xy 344.14129 -156.719094) (xy 344.223055 -156.734524) (xy 344.303022 -156.757517)
			(xy 344.380495 -156.787874) (xy 344.454797 -156.825328) (xy 344.490294 -156.847032) (xy 344.499434 -156.852189)
			(xy 344.520149 -156.855402) (xy 344.540422 -156.850073) (xy 344.548968 -156.843984) (xy 344.582592 -156.818029)
			(xy 344.653971 -156.771973) (xy 344.729414 -156.73293) (xy 344.808235 -156.701255) (xy 344.889716 -156.677237)
			(xy 344.973116 -156.661094) (xy 345.057674 -156.652974) (xy 345.100148 -156.652468) (xy 345.100402 -156.652468)
			(xy 345.14151 -156.652911) (xy 345.223374 -156.660496) (xy 345.30419 -156.6756) (xy 345.383268 -156.698096)
			(xy 345.459933 -156.727791) (xy 345.533532 -156.764433) (xy 345.603437 -156.807707) (xy 345.669051 -156.857246)
			(xy 345.729816 -156.912627) (xy 345.785212 -156.973378) (xy 345.806812 -157.001972) (xy 386.403596 -157.001972)
			(xy 386.40399 -156.963682) (xy 386.410601 -156.887387) (xy 386.423753 -156.811945) (xy 386.44335 -156.737915)
			(xy 386.45592 -156.701744) (xy 386.458586 -156.693311) (xy 386.458577 -156.675637) (xy 386.45592 -156.6672)
			(xy 386.443367 -156.631026) (xy 386.423796 -156.556991) (xy 386.410652 -156.481551) (xy 386.40403 -156.40526)
			(xy 386.403596 -156.366972) (xy 386.404015 -156.328179) (xy 386.410791 -156.25089) (xy 386.424264 -156.174482)
			(xy 386.44433 -156.099536) (xy 386.45719 -156.062934) (xy 386.459858 -156.054502) (xy 386.459846 -156.036827)
			(xy 386.45719 -156.02839) (xy 386.444324 -155.991789) (xy 386.424239 -155.916847) (xy 386.410766 -155.840438)
			(xy 386.404005 -155.763146) (xy 386.403596 -155.724352) (xy 386.404014 -155.686062) (xy 386.410618 -155.609769)
			(xy 386.423763 -155.534326) (xy 386.443354 -155.460295) (xy 386.45592 -155.424124) (xy 386.458596 -155.415693)
			(xy 386.45858 -155.398017) (xy 386.45592 -155.38958) (xy 386.443389 -155.353398) (xy 386.423812 -155.279367)
			(xy 386.410662 -155.203928) (xy 386.404034 -155.12764) (xy 386.403596 -155.089352) (xy 386.40407 -155.049438)
			(xy 386.411294 -154.969935) (xy 386.425601 -154.891398) (xy 386.446874 -154.814455) (xy 386.460492 -154.776932)
			(xy 386.463345 -154.768269) (xy 386.463329 -154.750041) (xy 386.460492 -154.741372) (xy 386.44684 -154.70386)
			(xy 386.425547 -154.626919) (xy 386.411244 -154.548377) (xy 386.404048 -154.468869) (xy 386.403596 -154.428952)
			(xy 386.404014 -154.390662) (xy 386.410618 -154.314369) (xy 386.423763 -154.238926) (xy 386.443354 -154.164895)
			(xy 386.45592 -154.128724) (xy 386.458596 -154.120293) (xy 386.45858 -154.102617) (xy 386.45592 -154.09418)
			(xy 386.443389 -154.057998) (xy 386.423812 -153.983967) (xy 386.410662 -153.908528) (xy 386.404034 -153.83224)
			(xy 386.403596 -153.793952) (xy 386.404007 -153.75284) (xy 386.411599 -153.670969) (xy 386.426714 -153.590147)
			(xy 386.449223 -153.511065) (xy 386.478934 -153.434397) (xy 386.515593 -153.360799) (xy 386.558887 -153.290897)
			(xy 386.608448 -153.225289) (xy 386.663851 -153.164535) (xy 386.724625 -153.109152) (xy 386.79025 -153.059614)
			(xy 386.860166 -153.016344) (xy 386.933777 -152.97971) (xy 387.010455 -152.950026) (xy 387.089545 -152.927544)
			(xy 387.170372 -152.912457) (xy 387.252246 -152.904893) (xy 387.293358 -152.904444) (xy 387.331674 -152.904822)
			(xy 387.408027 -152.91135) (xy 387.483534 -152.924432) (xy 387.557634 -152.94397) (xy 387.59384 -152.956514)
			(xy 387.602156 -152.9591) (xy 387.61956 -152.9591) (xy 387.627876 -152.956514) (xy 387.663994 -152.944008)
			(xy 387.737908 -152.924522) (xy 387.81322 -152.911442) (xy 387.889376 -152.904865) (xy 387.927596 -152.904444)
			(xy 387.928358 -152.904444) (xy 387.969464 -152.904953) (xy 388.051326 -152.912533) (xy 388.13214 -152.927634)
			(xy 388.211216 -152.950125) (xy 388.28788 -152.979816) (xy 388.361478 -153.016453) (xy 388.431382 -153.059723)
			(xy 388.496996 -153.109258) (xy 388.55776 -153.164634) (xy 388.613157 -153.225381) (xy 388.662713 -153.290979)
			(xy 388.706006 -153.360869) (xy 388.742667 -153.434454) (xy 388.772383 -153.511109) (xy 388.7949 -153.590177)
			(xy 388.810027 -153.670986) (xy 388.817634 -153.752846) (xy 388.817889 -153.774394) (xy 436.382169 -153.774394)
			(xy 436.386165 -153.564508) (xy 436.39815 -153.354926) (xy 436.418104 -153.145952) (xy 436.446 -152.93789)
			(xy 436.481797 -152.73104) (xy 436.525442 -152.525703) (xy 436.576874 -152.322177) (xy 436.636016 -152.120756)
			(xy 436.702784 -151.921733) (xy 436.77708 -151.725396) (xy 436.858798 -151.53203) (xy 436.947817 -151.341915)
			(xy 437.04401 -151.155327) (xy 437.147237 -150.972536) (xy 437.257348 -150.793808) (xy 437.374183 -150.619401)
			(xy 437.497573 -150.449569) (xy 437.62734 -150.284557) (xy 437.763294 -150.124606) (xy 437.90524 -149.969946)
			(xy 438.05297 -149.820802) (xy 438.206272 -149.677391) (xy 438.364922 -149.53992) (xy 438.528691 -149.408588)
			(xy 438.697341 -149.283587) (xy 438.870627 -149.165096) (xy 439.048299 -149.053289) (xy 439.230099 -148.948327)
			(xy 439.415763 -148.850362) (xy 439.605021 -148.759537) (xy 439.797601 -148.675983) (xy 439.993222 -148.59982)
			(xy 440.1916 -148.531161) (xy 440.392449 -148.470104) (xy 440.595476 -148.416737) (xy 440.800389 -148.371139)
			(xy 441.006888 -148.333374) (xy 441.214675 -148.303499) (xy 441.42345 -148.281556) (xy 441.632908 -148.267577)
			(xy 441.842747 -148.261582) (xy 442.052661 -148.263581) (xy 442.262348 -148.273569) (xy 442.471502 -148.291534)
			(xy 442.67982 -148.317448) (xy 442.887001 -148.351273) (xy 443.092745 -148.392962) (xy 443.296751 -148.442454)
			(xy 443.498726 -148.499676) (xy 443.698376 -148.564546) (xy 443.895411 -148.63697) (xy 444.089547 -148.716843)
			(xy 444.2805 -148.804049) (xy 444.467996 -148.898461) (xy 444.651761 -148.999943) (xy 444.831529 -149.108347)
			(xy 445.00704 -149.223517) (xy 445.178039 -149.345285) (xy 445.344279 -149.473474) (xy 445.505518 -149.6079)
			(xy 445.661522 -149.748367) (xy 445.812065 -149.894671) (xy 445.956929 -150.0466) (xy 446.095904 -150.203934)
			(xy 446.228789 -150.366445) (xy 446.35539 -150.533898) (xy 446.475525 -150.706048) (xy 446.589019 -150.882648)
			(xy 446.695707 -151.06344) (xy 446.795434 -151.248163) (xy 446.888057 -151.436549) (xy 446.973441 -151.628324)
			(xy 447.051462 -151.823211) (xy 447.122007 -152.020927) (xy 447.184974 -152.221185) (xy 447.240271 -152.423695)
			(xy 447.287818 -152.628164) (xy 447.327546 -152.834295) (xy 447.359398 -153.041788) (xy 447.383328 -153.250344)
			(xy 447.3993 -153.45966) (xy 447.407292 -153.669432) (xy 447.407792 -153.774394) (xy 447.407292 -153.879356)
			(xy 447.3993 -154.089128) (xy 447.383328 -154.298444) (xy 447.359398 -154.507) (xy 447.327546 -154.714493)
			(xy 447.287818 -154.920624) (xy 447.240271 -155.125093) (xy 447.184974 -155.327603) (xy 447.122007 -155.527861)
			(xy 447.051462 -155.725577) (xy 446.973441 -155.920464) (xy 446.888057 -156.112239) (xy 446.795434 -156.300625)
			(xy 446.695707 -156.485348) (xy 446.589019 -156.66614) (xy 446.475525 -156.84274) (xy 446.35539 -157.01489)
			(xy 446.228789 -157.182343) (xy 446.095904 -157.344854) (xy 445.956929 -157.502188) (xy 445.812065 -157.654117)
			(xy 445.661522 -157.800421) (xy 445.505518 -157.940888) (xy 445.344279 -158.075314) (xy 445.178039 -158.203503)
			(xy 445.00704 -158.325271) (xy 444.831529 -158.440441) (xy 444.651761 -158.548845) (xy 444.467996 -158.650327)
			(xy 444.2805 -158.744739) (xy 444.089547 -158.831945) (xy 443.895411 -158.911818) (xy 443.698376 -158.984242)
			(xy 443.498726 -159.049112) (xy 443.296751 -159.106334) (xy 443.092745 -159.155826) (xy 442.887001 -159.197515)
			(xy 442.67982 -159.23134) (xy 442.471502 -159.257254) (xy 442.262348 -159.275219) (xy 442.052661 -159.285207)
			(xy 441.842747 -159.287206) (xy 441.632908 -159.281211) (xy 441.42345 -159.267232) (xy 441.214675 -159.245289)
			(xy 441.006888 -159.215414) (xy 440.800389 -159.177649) (xy 440.595476 -159.132051) (xy 440.392449 -159.078684)
			(xy 440.1916 -159.017627) (xy 439.993222 -158.948968) (xy 439.797601 -158.872805) (xy 439.605021 -158.789251)
			(xy 439.415763 -158.698426) (xy 439.230099 -158.600461) (xy 439.048299 -158.495499) (xy 438.870627 -158.383692)
			(xy 438.697341 -158.265201) (xy 438.528691 -158.1402) (xy 438.364922 -158.008868) (xy 438.206272 -157.871397)
			(xy 438.05297 -157.727986) (xy 437.90524 -157.578842) (xy 437.763294 -157.424182) (xy 437.62734 -157.264231)
			(xy 437.497573 -157.099219) (xy 437.374183 -156.929387) (xy 437.257348 -156.75498) (xy 437.147237 -156.576252)
			(xy 437.04401 -156.393461) (xy 436.947817 -156.206873) (xy 436.858798 -156.016758) (xy 436.77708 -155.823392)
			(xy 436.702784 -155.627055) (xy 436.636016 -155.428032) (xy 436.576874 -155.226611) (xy 436.525442 -155.023085)
			(xy 436.481797 -154.817748) (xy 436.446 -154.610898) (xy 436.418104 -154.402836) (xy 436.39815 -154.193862)
			(xy 436.386165 -153.98428) (xy 436.382169 -153.774394) (xy 388.817889 -153.774394) (xy 388.81812 -153.793952)
			(xy 388.817702 -153.832242) (xy 388.811098 -153.908535) (xy 388.797953 -153.983978) (xy 388.778362 -154.058009)
			(xy 388.765796 -154.09418) (xy 388.763168 -154.102623) (xy 388.763152 -154.120288) (xy 388.765796 -154.128724)
			(xy 388.778328 -154.164905) (xy 388.797905 -154.238937) (xy 388.811055 -154.314375) (xy 388.817683 -154.390664)
			(xy 388.81812 -154.428952) (xy 388.817646 -154.468866) (xy 388.810422 -154.548369) (xy 388.796115 -154.626906)
			(xy 388.774842 -154.703849) (xy 388.761224 -154.741372) (xy 388.758419 -154.750047) (xy 388.758403 -154.768264)
			(xy 388.761224 -154.776932) (xy 388.774878 -154.814443) (xy 388.79617 -154.891385) (xy 388.810472 -154.969927)
			(xy 388.817668 -155.049435) (xy 388.81812 -155.089352) (xy 388.817702 -155.127642) (xy 388.811098 -155.203935)
			(xy 388.797953 -155.279378) (xy 388.778362 -155.353409) (xy 388.765796 -155.38958) (xy 388.763168 -155.398023)
			(xy 388.763152 -155.415688) (xy 388.765796 -155.424124) (xy 388.778328 -155.460305) (xy 388.797905 -155.534337)
			(xy 388.811055 -155.609775) (xy 388.817683 -155.686064) (xy 388.81812 -155.724352) (xy 388.817677 -155.763144)
			(xy 388.810908 -155.840433) (xy 388.797442 -155.916841) (xy 388.777382 -155.991787) (xy 388.764526 -156.02839)
			(xy 388.761895 -156.036832) (xy 388.761883 -156.054497) (xy 388.764526 -156.062934) (xy 388.7774 -156.099532)
			(xy 388.797482 -156.174476) (xy 388.810953 -156.250885) (xy 388.817712 -156.328178) (xy 388.81812 -156.366972)
			(xy 388.817708 -156.405262) (xy 388.811103 -156.481556) (xy 388.797955 -156.556998) (xy 388.778363 -156.631029)
			(xy 388.765796 -156.6672) (xy 388.763157 -156.67564) (xy 388.763148 -156.693308) (xy 388.765796 -156.701744)
			(xy 388.778334 -156.737923) (xy 388.797909 -156.811956) (xy 388.811058 -156.887395) (xy 388.817683 -156.963684)
			(xy 388.81812 -157.001972) (xy 388.817621 -157.043082) (xy 388.810036 -157.124951) (xy 388.794928 -157.20577)
			(xy 388.772425 -157.284851) (xy 388.742721 -157.361517) (xy 388.706068 -157.435115) (xy 388.66278 -157.505016)
			(xy 388.613226 -157.570624) (xy 388.557828 -157.631379) (xy 388.49706 -157.686762) (xy 388.43144 -157.736301)
			(xy 388.361528 -157.779573) (xy 388.287921 -157.816208) (xy 388.211248 -157.845893) (xy 388.132162 -157.868377)
			(xy 388.051339 -157.883465) (xy 387.969468 -157.891031) (xy 387.928358 -157.89148) (xy 387.890041 -157.891126)
			(xy 387.813688 -157.88459) (xy 387.738181 -157.871501) (xy 387.664082 -157.851957) (xy 387.627876 -157.83941)
			(xy 387.61956 -157.836824) (xy 387.602156 -157.836824) (xy 387.59384 -157.83941) (xy 387.557721 -157.851912)
			(xy 387.483807 -157.871399) (xy 387.408495 -157.88448) (xy 387.33234 -157.891059) (xy 387.29412 -157.89148)
			(xy 387.293358 -157.89148) (xy 387.252251 -157.891028) (xy 387.170388 -157.88344) (xy 387.089574 -157.868332)
			(xy 387.010498 -157.845835) (xy 386.933835 -157.816138) (xy 386.860238 -157.779497) (xy 386.790335 -157.736222)
			(xy 386.724722 -157.686684) (xy 386.663959 -157.631304) (xy 386.608563 -157.570555) (xy 386.559008 -157.504955)
			(xy 386.515715 -157.435063) (xy 386.479055 -157.361475) (xy 386.449338 -157.28482) (xy 386.42682 -157.20575)
			(xy 386.411692 -157.12494) (xy 386.404083 -157.043079) (xy 386.403596 -157.001972) (xy 345.806812 -157.001972)
			(xy 345.834767 -157.03898) (xy 345.878059 -157.108874) (xy 345.914719 -157.182463) (xy 345.944433 -157.259121)
			(xy 345.966949 -157.338193) (xy 345.982074 -157.419006) (xy 345.989679 -157.500868) (xy 345.990164 -157.541976)
			(xy 345.989609 -157.586746) (xy 345.980596 -157.675831) (xy 345.962689 -157.763562) (xy 345.936068 -157.849053)
			(xy 345.919044 -157.890464) (xy 345.915494 -157.900059) (xy 345.915485 -157.920497) (xy 345.919044 -157.930088)
			(xy 345.936056 -157.971436) (xy 345.962665 -158.056799) (xy 345.980569 -158.144403) (xy 345.989589 -158.233361)
			(xy 345.990164 -158.278068) (xy 345.990164 -158.279084) (xy 345.98991 -158.290514) (xy 346.016389 -158.296459)
			(xy 346.068624 -158.311202) (xy 346.094304 -158.319978) (xy 346.102501 -158.322492) (xy 346.119635 -158.322492)
			(xy 346.127832 -158.319978) (xy 346.163048 -158.308033) (xy 346.235059 -158.289446) (xy 346.308381 -158.277006)
			(xy 346.382492 -158.2708) (xy 346.419678 -158.270448) (xy 346.456862 -158.27082) (xy 346.53097 -158.277041)
			(xy 346.60429 -158.289483) (xy 346.676301 -158.308056) (xy 346.711524 -158.319978) (xy 346.719721 -158.322492)
			(xy 346.736855 -158.322492) (xy 346.745052 -158.319978) (xy 346.780146 -158.308069) (xy 346.851906 -158.289524)
			(xy 346.924971 -158.277084) (xy 346.998824 -158.270837) (xy 347.035882 -158.270448) (xy 347.036898 -158.270448)
			(xy 347.078822 -158.270999) (xy 347.162292 -158.278969) (xy 347.244625 -158.294837) (xy 347.325078 -158.31846)
			(xy 347.40292 -158.349624) (xy 347.477448 -158.388045) (xy 347.547987 -158.433377) (xy 347.613896 -158.485209)
			(xy 347.674581 -158.543071) (xy 347.72949 -158.60644) (xy 347.778127 -158.674741) (xy 347.820052 -158.747357)
			(xy 347.854884 -158.823628) (xy 347.882308 -158.902865) (xy 347.902076 -158.984351) (xy 347.914009 -159.067346)
			(xy 347.917999 -159.1511) (xy 347.914009 -159.234854) (xy 347.902076 -159.317849) (xy 347.882308 -159.399335)
			(xy 347.854884 -159.478572) (xy 347.820052 -159.554843) (xy 347.778127 -159.627459) (xy 347.72949 -159.69576)
			(xy 347.674581 -159.759129) (xy 347.613896 -159.816991) (xy 347.547987 -159.868823) (xy 347.477448 -159.914155)
			(xy 347.40292 -159.952576) (xy 347.325078 -159.98374) (xy 347.244625 -160.007363) (xy 347.162292 -160.023231)
			(xy 347.078822 -160.031201) (xy 347.036898 -160.031684) (xy 347.035882 -160.031684) (xy 346.998825 -160.031285)
			(xy 346.924976 -160.025019) (xy 346.851913 -160.012575) (xy 346.780153 -159.994041) (xy 346.745052 -159.982154)
			(xy 346.736855 -159.97964) (xy 346.719721 -159.97964) (xy 346.711524 -159.982154) (xy 346.684116 -159.991499)
			(xy 346.628318 -160.007008) (xy 346.600018 -160.013142) (xy 346.590235 -160.015622) (xy 346.573598 -160.027019)
			(xy 346.562626 -160.04394) (xy 346.560394 -160.053782) (xy 346.550929 -160.102889) (xy 346.522417 -160.19875)
			(xy 346.503498 -160.245044) (xy 346.499892 -160.254619) (xy 346.499745 -160.275056) (xy 346.503244 -160.284668)
			(xy 346.520278 -160.326041) (xy 346.546893 -160.41147) (xy 346.564794 -160.499139) (xy 346.5738 -160.588163)
			(xy 346.574364 -160.632902) (xy 346.574364 -160.633156) (xy 346.57386 -160.675504) (xy 346.565809 -160.759818)
			(xy 346.54978 -160.842984) (xy 346.525919 -160.924251) (xy 346.49444 -161.002881) (xy 346.455629 -161.078162)
			(xy 346.409839 -161.149414) (xy 346.357483 -161.21599) (xy 346.299035 -161.277288) (xy 346.235025 -161.332753)
			(xy 346.166033 -161.381882) (xy 346.092683 -161.424231) (xy 346.01564 -161.459415) (xy 345.935601 -161.487117)
			(xy 345.853292 -161.507085) (xy 345.769457 -161.519138) (xy 345.684856 -161.523169) (xy 345.600255 -161.519138)
			(xy 345.51642 -161.507085) (xy 345.434111 -161.487117) (xy 345.354072 -161.459415) (xy 345.277029 -161.424231)
			(xy 345.203679 -161.381882) (xy 345.134687 -161.332753) (xy 345.070677 -161.277288) (xy 345.012229 -161.21599)
			(xy 344.959873 -161.149414) (xy 344.914083 -161.078162) (xy 344.875272 -161.002881) (xy 344.843793 -160.924251)
			(xy 344.819932 -160.842984) (xy 344.803903 -160.759818) (xy 344.795852 -160.675504) (xy 344.795348 -160.633156)
			(xy 344.795348 -160.632902) (xy 344.795938 -160.588164) (xy 344.804948 -160.499143) (xy 344.822847 -160.411476)
			(xy 344.849453 -160.326048) (xy 344.866468 -160.284668) (xy 344.870056 -160.275084) (xy 344.87004 -160.254635)
			(xy 344.866468 -160.245044) (xy 344.849433 -160.203637) (xy 344.822801 -160.118148) (xy 344.804897 -160.030415)
			(xy 344.795901 -159.941327) (xy 344.795348 -159.896556) (xy 344.795678 -159.859467) (xy 344.801776 -159.78554)
			(xy 344.814009 -159.712377) (xy 344.82278 -159.676338) (xy 344.824538 -159.668008) (xy 344.823098 -159.651057)
			(xy 344.816174 -159.635517) (xy 344.810588 -159.629094) (xy 344.770202 -159.586168) (xy 344.758264 -159.588708)
			(xy 344.749364 -159.591023) (xy 344.733871 -159.600904) (xy 344.728038 -159.608012) (xy 344.702891 -159.640664)
			(xy 344.647483 -159.701681) (xy 344.586669 -159.757312) (xy 344.520971 -159.807081) (xy 344.450952 -159.850561)
			(xy 344.377213 -159.887379) (xy 344.300384 -159.917221) (xy 344.221125 -159.93983) (xy 344.140115 -159.955012)
			(xy 344.058048 -159.962637) (xy 344.016838 -159.963104) (xy 343.975733 -159.962551) (xy 343.893874 -159.954971)
			(xy 343.813062 -159.939871) (xy 343.733989 -159.917381) (xy 343.657327 -159.887692) (xy 343.583731 -159.851057)
			(xy 343.513829 -159.807789) (xy 343.448216 -159.758257) (xy 343.387452 -159.702884) (xy 343.332056 -159.642141)
			(xy 343.2825 -159.576547) (xy 343.239206 -159.506661) (xy 343.202543 -159.433078) (xy 343.172826 -159.356428)
			(xy 343.150306 -159.277363) (xy 343.135175 -159.196557) (xy 343.127564 -159.114701) (xy 343.127076 -159.073596)
			(xy 279.382794 -159.073596) (xy 279.296825 -159.097952) (xy 279.092819 -159.147444) (xy 278.887075 -159.189133)
			(xy 278.679894 -159.222958) (xy 278.471576 -159.248872) (xy 278.262422 -159.266837) (xy 278.052735 -159.276825)
			(xy 277.842821 -159.278824) (xy 277.632982 -159.272829) (xy 277.423524 -159.25885) (xy 277.214749 -159.236907)
			(xy 277.006962 -159.207032) (xy 276.800463 -159.169267) (xy 276.59555 -159.123669) (xy 276.392523 -159.070302)
			(xy 276.191674 -159.009245) (xy 275.993296 -158.940586) (xy 275.797675 -158.864423) (xy 275.605095 -158.780869)
			(xy 275.415837 -158.690044) (xy 275.230173 -158.592079) (xy 275.048373 -158.487117) (xy 274.870701 -158.37531)
			(xy 274.697415 -158.256819) (xy 274.528765 -158.131818) (xy 274.364996 -158.000486) (xy 274.206346 -157.863015)
			(xy 274.053044 -157.719604) (xy 273.905314 -157.57046) (xy 273.763368 -157.4158) (xy 273.627414 -157.255849)
			(xy 273.497647 -157.090837) (xy 273.374257 -156.921005) (xy 273.257422 -156.746598) (xy 273.147311 -156.56787)
			(xy 273.044084 -156.385079) (xy 272.947891 -156.198491) (xy 272.858872 -156.008376) (xy 272.777154 -155.81501)
			(xy 272.702858 -155.618673) (xy 272.63609 -155.41965) (xy 272.576948 -155.218229) (xy 272.525516 -155.014703)
			(xy 272.481871 -154.809366) (xy 272.446074 -154.602516) (xy 272.418178 -154.394454) (xy 272.398224 -154.18548)
			(xy 272.386239 -153.975898) (xy 272.382243 -153.766012) (xy 199.467428 -153.766012) (xy 199.46747 -153.774902)
			(xy 199.46697 -153.879864) (xy 199.458978 -154.089636) (xy 199.443006 -154.298952) (xy 199.419076 -154.507508)
			(xy 199.387224 -154.715001) (xy 199.347496 -154.921132) (xy 199.299949 -155.125601) (xy 199.244652 -155.328111)
			(xy 199.181685 -155.528369) (xy 199.11114 -155.726085) (xy 199.033119 -155.920972) (xy 198.947735 -156.112747)
			(xy 198.855112 -156.301133) (xy 198.755385 -156.485856) (xy 198.648697 -156.666648) (xy 198.535203 -156.843248)
			(xy 198.415068 -157.015398) (xy 198.288467 -157.182851) (xy 198.155582 -157.345362) (xy 198.016607 -157.502696)
			(xy 197.871743 -157.654625) (xy 197.7212 -157.800929) (xy 197.565196 -157.941396) (xy 197.403957 -158.075822)
			(xy 197.237717 -158.204011) (xy 197.066718 -158.325779) (xy 196.891207 -158.440949) (xy 196.711439 -158.549353)
			(xy 196.527674 -158.650835) (xy 196.340178 -158.745247) (xy 196.149225 -158.832453) (xy 195.955089 -158.912326)
			(xy 195.758054 -158.98475) (xy 195.558404 -159.04962) (xy 195.356429 -159.106842) (xy 195.152423 -159.156334)
			(xy 194.946679 -159.198023) (xy 194.739498 -159.231848) (xy 194.53118 -159.257762) (xy 194.322026 -159.275727)
			(xy 194.112339 -159.285715) (xy 193.902425 -159.287714) (xy 193.692586 -159.281719) (xy 193.483128 -159.26774)
			(xy 193.274353 -159.245797) (xy 193.066566 -159.215922) (xy 192.860067 -159.178157) (xy 192.655154 -159.132559)
			(xy 192.452127 -159.079192) (xy 192.251278 -159.018135) (xy 192.0529 -158.949476) (xy 191.857279 -158.873313)
			(xy 191.664699 -158.789759) (xy 191.475441 -158.698934) (xy 191.289777 -158.600969) (xy 191.107977 -158.496007)
			(xy 190.930305 -158.3842) (xy 190.757019 -158.265709) (xy 190.588369 -158.140708) (xy 190.4246 -158.009376)
			(xy 190.26595 -157.871905) (xy 190.112648 -157.728494) (xy 189.964918 -157.57935) (xy 189.822972 -157.42469)
			(xy 189.687018 -157.264739) (xy 189.557251 -157.099727) (xy 189.433861 -156.929895) (xy 189.317026 -156.755488)
			(xy 189.206915 -156.57676) (xy 189.103688 -156.393969) (xy 189.007495 -156.207381) (xy 188.918476 -156.017266)
			(xy 188.836758 -155.8239) (xy 188.762462 -155.627563) (xy 188.695694 -155.42854) (xy 188.636552 -155.227119)
			(xy 188.58512 -155.023593) (xy 188.541475 -154.818256) (xy 188.505678 -154.611406) (xy 188.477782 -154.403344)
			(xy 188.457828 -154.19437) (xy 188.445843 -153.984788) (xy 188.441847 -153.774902) (xy 132.165372 -153.774902)
			(xy 132.17401 -153.779355) (xy 132.244575 -153.824704) (xy 132.31051 -153.876555) (xy 132.371218 -153.934439)
			(xy 132.426149 -153.997832) (xy 132.474805 -154.066159) (xy 132.516746 -154.138802) (xy 132.551591 -154.215103)
			(xy 132.579026 -154.29437) (xy 132.598802 -154.375887) (xy 132.61074 -154.458914) (xy 132.614731 -154.5427)
			(xy 132.61074 -154.626486) (xy 132.598802 -154.709513) (xy 132.579026 -154.79103) (xy 132.551591 -154.870297)
			(xy 132.516746 -154.946598) (xy 132.474805 -155.019241) (xy 132.426149 -155.087568) (xy 132.371218 -155.150961)
			(xy 132.31051 -155.208845) (xy 132.244575 -155.260696) (xy 132.17401 -155.306045) (xy 132.099453 -155.344481)
			(xy 132.02158 -155.375656) (xy 131.941097 -155.399287) (xy 131.858732 -155.415161) (xy 131.77523 -155.423133)
			(xy 131.73329 -155.423616) (xy 131.6961 -155.423229) (xy 131.621987 -155.416939) (xy 131.548668 -155.404428)
			(xy 131.476662 -155.385787) (xy 131.441444 -155.373832) (xy 131.433247 -155.371318) (xy 131.416113 -155.371318)
			(xy 131.407916 -155.373832) (xy 131.374578 -155.385154) (xy 131.306486 -155.403082) (xy 131.237181 -155.41552)
			(xy 131.202176 -155.419298) (xy 131.192163 -155.420682) (xy 131.174401 -155.43031) (xy 131.161723 -155.446041)
			(xy 131.158488 -155.45562) (xy 131.151035 -155.480306) (xy 131.133624 -155.528851) (xy 131.12369 -155.552648)
			(xy 131.120082 -155.562222) (xy 131.119936 -155.58266) (xy 131.123436 -155.592272) (xy 131.140471 -155.633645)
			(xy 131.167086 -155.719073) (xy 131.184987 -155.806743) (xy 131.193992 -155.895767) (xy 131.194556 -155.940506)
			(xy 131.194556 -155.94076) (xy 131.194052 -155.983108) (xy 131.186001 -156.067422) (xy 131.169972 -156.150588)
			(xy 131.146111 -156.231855) (xy 131.114632 -156.310485) (xy 131.075821 -156.385766) (xy 131.030031 -156.457018)
			(xy 130.977675 -156.523594) (xy 130.919227 -156.584892) (xy 130.855217 -156.640357) (xy 130.786225 -156.689486)
			(xy 130.712875 -156.731835) (xy 130.635832 -156.767019) (xy 130.555793 -156.794721) (xy 130.473484 -156.814689)
			(xy 130.389649 -156.826742) (xy 130.305048 -156.830773) (xy 130.220447 -156.826742) (xy 130.136612 -156.814689)
			(xy 130.054303 -156.794721) (xy 129.974264 -156.767019) (xy 129.897221 -156.731835) (xy 129.823871 -156.689486)
			(xy 129.754879 -156.640357) (xy 129.690869 -156.584892) (xy 129.632421 -156.523594) (xy 129.580065 -156.457018)
			(xy 129.534275 -156.385766) (xy 129.495464 -156.310485) (xy 129.463985 -156.231855) (xy 129.440124 -156.150588)
			(xy 129.424095 -156.067422) (xy 129.416044 -155.983108) (xy 129.41554 -155.94076) (xy 129.41554 -155.940506)
			(xy 129.416091 -155.895767) (xy 129.425111 -155.806745) (xy 129.443021 -155.719078) (xy 129.46964 -155.633651)
			(xy 129.48666 -155.592272) (xy 129.490247 -155.582688) (xy 129.490232 -155.562239) (xy 129.48666 -155.552648)
			(xy 129.471663 -155.516314) (xy 129.447353 -155.441557) (xy 129.429731 -155.364948) (xy 129.418932 -155.287083)
			(xy 129.416556 -155.247848) (xy 129.415794 -155.233878) (xy 129.400046 -155.21051) (xy 129.29235 -155.160472)
			(xy 129.264664 -155.16352) (xy 129.253234 -155.172156) (xy 129.220015 -155.196974) (xy 129.149739 -155.241)
			(xy 129.075668 -155.27829) (xy 128.998447 -155.308521) (xy 128.918747 -155.33143) (xy 128.83726 -155.346818)
			(xy 128.754694 -155.354552) (xy 128.71323 -155.355036) (xy 128.672115 -155.354573) (xy 128.590235 -155.346988)
			(xy 128.509404 -155.33188) (xy 128.430313 -155.309379) (xy 128.353635 -155.279675) (xy 128.280025 -155.243023)
			(xy 128.210111 -155.199735) (xy 128.144489 -155.150181) (xy 128.08372 -155.094783) (xy 128.028322 -155.034014)
			(xy 127.978767 -154.968393) (xy 127.935479 -154.898479) (xy 127.898826 -154.824869) (xy 127.869122 -154.748191)
			(xy 127.84662 -154.669099) (xy 127.831512 -154.588269) (xy 127.823927 -154.506389) (xy 127.823468 -154.465274)
			(xy 35.422918 -154.465274) (xy 35.41915 -154.49811) (xy 35.387298 -154.705603) (xy 35.34757 -154.911734)
			(xy 35.300023 -155.116203) (xy 35.244726 -155.318713) (xy 35.181759 -155.518971) (xy 35.111214 -155.716687)
			(xy 35.033193 -155.911574) (xy 34.947809 -156.103349) (xy 34.855186 -156.291735) (xy 34.755459 -156.476458)
			(xy 34.648771 -156.65725) (xy 34.535277 -156.83385) (xy 34.415142 -157.006) (xy 34.288541 -157.173453)
			(xy 34.155656 -157.335964) (xy 34.016681 -157.493298) (xy 33.871817 -157.645227) (xy 33.721274 -157.791531)
			(xy 33.56527 -157.931998) (xy 33.404031 -158.066424) (xy 33.237791 -158.194613) (xy 33.066792 -158.316381)
			(xy 32.891281 -158.431551) (xy 32.711513 -158.539955) (xy 32.527748 -158.641437) (xy 32.340252 -158.735849)
			(xy 32.149299 -158.823055) (xy 31.955163 -158.902928) (xy 31.758128 -158.975352) (xy 31.558478 -159.040222)
			(xy 31.356503 -159.097444) (xy 31.152497 -159.146936) (xy 30.946753 -159.188625) (xy 30.739572 -159.22245)
			(xy 30.531254 -159.248364) (xy 30.3221 -159.266329) (xy 30.112413 -159.276317) (xy 29.902499 -159.278316)
			(xy 29.69266 -159.272321) (xy 29.483202 -159.258342) (xy 29.274427 -159.236399) (xy 29.06664 -159.206524)
			(xy 28.860141 -159.168759) (xy 28.655228 -159.123161) (xy 28.452201 -159.069794) (xy 28.251352 -159.008737)
			(xy 28.052974 -158.940078) (xy 27.857353 -158.863915) (xy 27.664773 -158.780361) (xy 27.475515 -158.689536)
			(xy 27.289851 -158.591571) (xy 27.108051 -158.486609) (xy 26.930379 -158.374802) (xy 26.757093 -158.256311)
			(xy 26.588443 -158.13131) (xy 26.424674 -157.999978) (xy 26.266024 -157.862507) (xy 26.112722 -157.719096)
			(xy 25.964992 -157.569952) (xy 25.823046 -157.415292) (xy 25.687092 -157.255341) (xy 25.557325 -157.090329)
			(xy 25.433935 -156.920497) (xy 25.3171 -156.74609) (xy 25.206989 -156.567362) (xy 25.103762 -156.384571)
			(xy 25.007569 -156.197983) (xy 24.91855 -156.007868) (xy 24.836832 -155.814502) (xy 24.762536 -155.618165)
			(xy 24.695768 -155.419142) (xy 24.636626 -155.217721) (xy 24.585194 -155.014195) (xy 24.541549 -154.808858)
			(xy 24.505752 -154.602008) (xy 24.477856 -154.393946) (xy 24.457902 -154.184972) (xy 24.445917 -153.97539)
			(xy 24.441921 -153.765504) (xy 2.509012 -153.765504) (xy 2.509012 -164.097716) (xy 86.129368 -164.097716)
			(xy 86.129877 -164.05494) (xy 86.138089 -163.969783) (xy 86.154448 -163.88581) (xy 86.178803 -163.803797)
			(xy 86.194392 -163.76396) (xy 86.19746 -163.755511) (xy 86.19811 -163.737557) (xy 86.195662 -163.728908)
			(xy 86.181097 -163.683434) (xy 86.160666 -163.590154) (xy 86.150355 -163.495221) (xy 86.149688 -163.447476)
			(xy 86.150084 -163.409186) (xy 86.156694 -163.332892) (xy 86.169846 -163.257449) (xy 86.189443 -163.183419)
			(xy 86.202012 -163.147248) (xy 86.204676 -163.138815) (xy 86.204669 -163.121141) (xy 86.202012 -163.112704)
			(xy 86.18946 -163.076529) (xy 86.169889 -163.002495) (xy 86.156744 -162.927055) (xy 86.150122 -162.850764)
			(xy 86.149688 -162.812476) (xy 86.15013 -162.771365) (xy 86.157719 -162.689494) (xy 86.172832 -162.608673)
			(xy 86.195339 -162.529592) (xy 86.225048 -162.452925) (xy 86.261705 -162.379327) (xy 86.304997 -162.309425)
			(xy 86.354555 -162.243817) (xy 86.409957 -162.183063) (xy 86.470728 -162.12768) (xy 86.536351 -162.078142)
			(xy 86.606266 -162.034871) (xy 86.679876 -161.998237) (xy 86.756552 -161.968552) (xy 86.83564 -161.94607)
			(xy 86.916466 -161.930982) (xy 86.998339 -161.923417) (xy 87.03945 -161.922968) (xy 87.077766 -161.923352)
			(xy 87.154119 -161.92988) (xy 87.229626 -161.94296) (xy 87.303725 -161.962495) (xy 87.339932 -161.975038)
			(xy 87.348248 -161.977624) (xy 87.365652 -161.977624) (xy 87.373968 -161.975038) (xy 87.410177 -161.962503)
			(xy 87.484279 -161.942985) (xy 87.559785 -161.929905) (xy 87.636135 -161.92336) (xy 87.67445 -161.922968)
			(xy 87.712766 -161.923352) (xy 87.789119 -161.92988) (xy 87.864626 -161.94296) (xy 87.938725 -161.962495)
			(xy 87.974932 -161.975038) (xy 87.983248 -161.977624) (xy 88.000652 -161.977624) (xy 88.008968 -161.975038)
			(xy 88.045177 -161.962503) (xy 88.119279 -161.942985) (xy 88.194785 -161.929905) (xy 88.271135 -161.92336)
			(xy 88.30945 -161.922968) (xy 88.347766 -161.923352) (xy 88.424119 -161.92988) (xy 88.499626 -161.94296)
			(xy 88.573725 -161.962495) (xy 88.609932 -161.975038) (xy 88.618248 -161.977624) (xy 88.635652 -161.977624)
			(xy 88.643968 -161.975038) (xy 88.680177 -161.962503) (xy 88.754279 -161.942985) (xy 88.829785 -161.929905)
			(xy 88.906135 -161.92336) (xy 88.94445 -161.922968) (xy 88.982766 -161.923352) (xy 89.059119 -161.92988)
			(xy 89.134626 -161.94296) (xy 89.208725 -161.962495) (xy 89.244932 -161.975038) (xy 89.253248 -161.977624)
			(xy 89.270652 -161.977624) (xy 89.278968 -161.975038) (xy 89.315177 -161.962503) (xy 89.389279 -161.942985)
			(xy 89.464785 -161.929905) (xy 89.541135 -161.92336) (xy 89.57945 -161.922968) (xy 89.62106 -161.923438)
			(xy 89.703917 -161.931201) (xy 89.785687 -161.946663) (xy 89.865658 -161.96969) (xy 89.90457 -161.984436)
			(xy 89.913248 -161.987466) (xy 89.931617 -161.98771) (xy 89.940384 -161.984944) (xy 89.976385 -161.972506)
			(xy 90.050053 -161.953122) (xy 90.125108 -161.940106) (xy 90.201001 -161.933552) (xy 90.239088 -161.933128)
			(xy 90.23985 -161.933128) (xy 90.280956 -161.93366) (xy 90.362817 -161.94124) (xy 90.443629 -161.956339)
			(xy 90.522705 -161.97883) (xy 90.599368 -162.008519) (xy 90.672965 -162.045155) (xy 90.742868 -162.088423)
			(xy 90.808482 -162.137957) (xy 90.869246 -162.193332) (xy 90.924643 -162.254076) (xy 90.974199 -162.319673)
			(xy 91.017492 -162.389561) (xy 91.054154 -162.463145) (xy 91.08387 -162.539798) (xy 91.106389 -162.618865)
			(xy 91.121517 -162.699672) (xy 91.129125 -162.781531) (xy 91.129612 -162.822636) (xy 91.12919 -162.860925)
			(xy 91.122588 -162.937219) (xy 91.109443 -163.012662) (xy 91.089854 -163.086693) (xy 91.077288 -163.122864)
			(xy 91.076082 -163.126674) (xy 119.365268 -163.126674) (xy 119.365838 -163.081905) (xy 119.374847 -162.99282)
			(xy 119.392749 -162.905089) (xy 119.419366 -162.819597) (xy 119.436388 -162.778186) (xy 119.43997 -162.7686)
			(xy 119.43996 -162.748153) (xy 119.436388 -162.738562) (xy 119.41934 -162.69716) (xy 119.392709 -162.61167)
			(xy 119.374808 -162.523935) (xy 119.365818 -162.434845) (xy 119.365268 -162.390074) (xy 119.365838 -162.345305)
			(xy 119.374847 -162.25622) (xy 119.392749 -162.168489) (xy 119.419366 -162.082997) (xy 119.436388 -162.041586)
			(xy 119.43997 -162.032) (xy 119.43996 -162.011553) (xy 119.436388 -162.001962) (xy 119.41934 -161.96056)
			(xy 119.392709 -161.87507) (xy 119.374808 -161.787335) (xy 119.365818 -161.698245) (xy 119.365268 -161.653474)
			(xy 119.365674 -161.612358) (xy 119.373264 -161.530476) (xy 119.388376 -161.449645) (xy 119.410882 -161.370552)
			(xy 119.440591 -161.293873) (xy 119.477247 -161.220263) (xy 119.520539 -161.150349) (xy 119.570097 -161.084728)
			(xy 119.625499 -161.023959) (xy 119.686271 -160.968561) (xy 119.751895 -160.919007) (xy 119.821812 -160.87572)
			(xy 119.895425 -160.839068) (xy 119.972105 -160.809365) (xy 120.051199 -160.786863) (xy 120.132032 -160.771756)
			(xy 120.213914 -160.764171) (xy 120.25503 -160.763712) (xy 120.296641 -160.764173) (xy 120.379498 -160.771953)
			(xy 120.461267 -160.787431) (xy 120.541235 -160.810474) (xy 120.618703 -160.840879) (xy 120.692995 -160.878382)
			(xy 120.728486 -160.90011) (xy 120.737629 -160.905263) (xy 120.758342 -160.90848) (xy 120.778614 -160.903152)
			(xy 120.78716 -160.897062) (xy 120.820789 -160.871071) (xy 120.892183 -160.824946) (xy 120.967654 -160.785845)
			(xy 121.046512 -160.754124) (xy 121.128037 -160.730075) (xy 121.211485 -160.713915) (xy 121.296095 -160.705793)
			(xy 121.338594 -160.705292) (xy 121.379707 -160.705819) (xy 121.461582 -160.713405) (xy 121.542407 -160.728513)
			(xy 121.621494 -160.751013) (xy 121.698168 -160.780715) (xy 121.771774 -160.817365) (xy 121.841684 -160.86065)
			(xy 121.907303 -160.9102) (xy 121.96807 -160.965593) (xy 122.023467 -161.026357) (xy 122.073021 -161.091973)
			(xy 122.11631 -161.161881) (xy 122.152964 -161.235485) (xy 122.18267 -161.312156) (xy 122.205176 -161.391242)
			(xy 122.220288 -161.472067) (xy 122.227879 -161.553941) (xy 122.228356 -161.595054) (xy 122.227793 -161.639824)
			(xy 122.218783 -161.728909) (xy 122.200877 -161.81664) (xy 122.174259 -161.902131) (xy 122.157236 -161.943542)
			(xy 122.153699 -161.953141) (xy 122.153682 -161.973576) (xy 122.157236 -161.983166) (xy 122.17424 -162.024517)
			(xy 122.200851 -162.109879) (xy 122.218758 -162.197482) (xy 122.22778 -162.286439) (xy 122.228356 -162.331146)
			(xy 122.228356 -162.332162) (xy 122.228102 -162.343592) (xy 122.254581 -162.349538) (xy 122.306816 -162.364281)
			(xy 122.332496 -162.373056) (xy 122.340693 -162.37557) (xy 122.357827 -162.37557) (xy 122.366024 -162.373056)
			(xy 122.40124 -162.361095) (xy 122.473244 -162.342441) (xy 122.546565 -162.329932) (xy 122.62068 -162.323659)
			(xy 122.65787 -162.323272) (xy 122.695059 -162.323671) (xy 122.769172 -162.329958) (xy 122.842492 -162.342465)
			(xy 122.914498 -162.361103) (xy 122.949716 -162.373056) (xy 122.957913 -162.37557) (xy 122.975047 -162.37557)
			(xy 122.983244 -162.373056) (xy 123.018459 -162.361089) (xy 123.090462 -162.342437) (xy 123.163784 -162.32993)
			(xy 123.2379 -162.323658) (xy 123.27509 -162.323272) (xy 123.31703 -162.323667) (xy 123.400532 -162.331639)
			(xy 123.482897 -162.347513) (xy 123.56338 -162.371144) (xy 123.641253 -162.402319) (xy 123.71581 -162.440755)
			(xy 123.786375 -162.486104) (xy 123.85231 -162.537955) (xy 123.913018 -162.595839) (xy 123.913877 -162.59683)
			(xy 376.471695 -162.59683) (xy 376.4757 -162.491081) (xy 376.48769 -162.385938) (xy 376.507599 -162.282003)
			(xy 376.53531 -162.179871) (xy 376.570667 -162.080127) (xy 376.613465 -161.983343) (xy 376.663461 -161.890073)
			(xy 376.720368 -161.800852) (xy 376.783859 -161.716189) (xy 376.853571 -161.636571) (xy 376.929105 -161.562453)
			(xy 377.010028 -161.49426) (xy 377.095877 -161.432382) (xy 377.18616 -161.377175) (xy 377.280359 -161.328953)
			(xy 377.377936 -161.287993) (xy 377.478331 -161.254531) (xy 377.580969 -161.228757) (xy 377.685262 -161.210819)
			(xy 377.790613 -161.20082) (xy 377.896419 -161.198817) (xy 378.002073 -161.204822) (xy 378.10697 -161.218801)
			(xy 378.21051 -161.240672) (xy 378.312099 -161.270312) (xy 378.411156 -161.30755) (xy 378.507113 -161.352172)
			(xy 378.59942 -161.403924) (xy 378.687549 -161.462509) (xy 378.770995 -161.527591) (xy 378.849279 -161.598797)
			(xy 378.921954 -161.67572) (xy 378.988604 -161.75792) (xy 379.048846 -161.844924) (xy 379.102335 -161.936235)
			(xy 379.148766 -162.03133) (xy 379.187871 -162.129664) (xy 379.219428 -162.230675) (xy 379.243255 -162.333782)
			(xy 379.259216 -162.438396) (xy 379.26722 -162.543918) (xy 379.26772 -162.59683) (xy 379.26722 -162.649742)
			(xy 379.266995 -162.65271) (xy 385.808735 -162.65271) (xy 385.81274 -162.546961) (xy 385.82473 -162.441818)
			(xy 385.844639 -162.337883) (xy 385.87235 -162.235751) (xy 385.907707 -162.136007) (xy 385.950505 -162.039223)
			(xy 386.000501 -161.945953) (xy 386.057408 -161.856732) (xy 386.120899 -161.772069) (xy 386.190611 -161.692451)
			(xy 386.266145 -161.618333) (xy 386.347068 -161.55014) (xy 386.432917 -161.488262) (xy 386.5232 -161.433055)
			(xy 386.617399 -161.384833) (xy 386.714976 -161.343873) (xy 386.815371 -161.310411) (xy 386.918009 -161.284637)
			(xy 387.022302 -161.266699) (xy 387.127653 -161.2567) (xy 387.233459 -161.254697) (xy 387.339113 -161.260702)
			(xy 387.44401 -161.274681) (xy 387.54755 -161.296552) (xy 387.649139 -161.326192) (xy 387.748196 -161.36343)
			(xy 387.844153 -161.408052) (xy 387.93646 -161.459804) (xy 388.024589 -161.518389) (xy 388.108035 -161.583471)
			(xy 388.186319 -161.654677) (xy 388.231017 -161.701988) (xy 409.929076 -161.701988) (xy 409.92965 -161.657219)
			(xy 409.938657 -161.568134) (xy 409.956559 -161.480403) (xy 409.983175 -161.394911) (xy 410.000196 -161.3535)
			(xy 410.00377 -161.343912) (xy 410.003765 -161.323466) (xy 410.000196 -161.313876) (xy 409.983153 -161.272472)
			(xy 409.956521 -161.186983) (xy 409.938618 -161.099248) (xy 409.929627 -161.010159) (xy 409.929076 -160.965388)
			(xy 409.92965 -160.920619) (xy 409.938657 -160.831534) (xy 409.956559 -160.743803) (xy 409.983175 -160.658311)
			(xy 410.000196 -160.6169) (xy 410.00377 -160.607312) (xy 410.003765 -160.586866) (xy 410.000196 -160.577276)
			(xy 409.983153 -160.535872) (xy 409.956521 -160.450383) (xy 409.938618 -160.362648) (xy 409.929627 -160.273559)
			(xy 409.929076 -160.228788) (xy 409.929541 -160.187678) (xy 409.93713 -160.105808) (xy 409.952241 -160.024988)
			(xy 409.974747 -159.945907) (xy 410.004454 -159.869241) (xy 410.041109 -159.795643) (xy 410.0844 -159.725742)
			(xy 410.133957 -159.660134) (xy 410.189357 -159.59938) (xy 410.250127 -159.543997) (xy 410.315748 -159.494459)
			(xy 410.385662 -159.451187) (xy 410.45927 -159.414553) (xy 410.535944 -159.384867) (xy 410.615031 -159.362384)
			(xy 410.695856 -159.347295) (xy 410.777728 -159.339729) (xy 410.818838 -159.33928) (xy 410.860442 -159.339755)
			(xy 410.94329 -159.347487) (xy 411.025054 -159.362917) (xy 411.105022 -159.38591) (xy 411.182495 -159.416266)
			(xy 411.256796 -159.45372) (xy 411.292294 -159.475424) (xy 411.301434 -159.480582) (xy 411.322149 -159.483796)
			(xy 411.342422 -159.478466) (xy 411.350968 -159.472376) (xy 411.384591 -159.44642) (xy 411.45597 -159.400364)
			(xy 411.531414 -159.361321) (xy 411.610235 -159.329647) (xy 411.691716 -159.305629) (xy 411.775116 -159.289486)
			(xy 411.859674 -159.281366) (xy 411.902148 -159.28086) (xy 411.902402 -159.28086) (xy 411.943509 -159.281311)
			(xy 412.025374 -159.288895) (xy 412.106189 -159.304) (xy 412.185267 -159.326496) (xy 412.261931 -159.356191)
			(xy 412.33553 -159.392831) (xy 412.405434 -159.436106) (xy 412.471048 -159.485644) (xy 412.531813 -159.541025)
			(xy 412.587209 -159.601775) (xy 412.636764 -159.667376) (xy 412.680057 -159.737269) (xy 412.716716 -159.810858)
			(xy 412.746431 -159.887515) (xy 412.768947 -159.966587) (xy 412.784073 -160.047398) (xy 412.791679 -160.129261)
			(xy 412.792164 -160.170368) (xy 412.791606 -160.215138) (xy 412.782594 -160.304223) (xy 412.764688 -160.391954)
			(xy 412.738068 -160.477445) (xy 412.721044 -160.518856) (xy 412.717498 -160.528452) (xy 412.717487 -160.548889)
			(xy 412.721044 -160.55848) (xy 412.738053 -160.599829) (xy 412.764663 -160.685192) (xy 412.782568 -160.772795)
			(xy 412.791589 -160.861753) (xy 412.792164 -160.90646) (xy 412.792164 -160.907476) (xy 412.79191 -160.918906)
			(xy 412.818389 -160.924851) (xy 412.870624 -160.939594) (xy 412.896304 -160.94837) (xy 412.904501 -160.950884)
			(xy 412.921635 -160.950884) (xy 412.929832 -160.94837) (xy 412.96505 -160.936429) (xy 413.037059 -160.91784)
			(xy 413.110382 -160.905398) (xy 413.184492 -160.899192) (xy 413.221678 -160.89884) (xy 413.258862 -160.899213)
			(xy 413.33297 -160.905434) (xy 413.40629 -160.917875) (xy 413.478301 -160.936448) (xy 413.513524 -160.94837)
			(xy 413.521721 -160.950884) (xy 413.538855 -160.950884) (xy 413.547052 -160.94837) (xy 413.582146 -160.93646)
			(xy 413.653906 -160.917916) (xy 413.726971 -160.905476) (xy 413.800824 -160.899229) (xy 413.837882 -160.89884)
			(xy 413.838898 -160.89884) (xy 413.880822 -160.899407) (xy 413.964291 -160.907377) (xy 414.046623 -160.923245)
			(xy 414.127075 -160.946868) (xy 414.204917 -160.978031) (xy 414.279444 -161.016452) (xy 414.349982 -161.061784)
			(xy 414.415891 -161.113615) (xy 414.476575 -161.171477) (xy 414.531484 -161.234845) (xy 414.580121 -161.303146)
			(xy 414.622045 -161.37576) (xy 414.656876 -161.452031) (xy 414.684301 -161.531268) (xy 414.704068 -161.612752)
			(xy 414.716001 -161.695747) (xy 414.719991 -161.7795) (xy 414.716001 -161.863253) (xy 414.704068 -161.946248)
			(xy 414.684301 -162.027732) (xy 414.656876 -162.106969) (xy 414.622045 -162.18324) (xy 414.580121 -162.255854)
			(xy 414.531484 -162.324155) (xy 414.476575 -162.387523) (xy 414.415891 -162.445385) (xy 414.349982 -162.497216)
			(xy 414.279444 -162.542548) (xy 414.204917 -162.580969) (xy 414.127075 -162.612132) (xy 414.046623 -162.635755)
			(xy 413.964291 -162.651623) (xy 413.880822 -162.659593) (xy 413.838898 -162.660076) (xy 413.837882 -162.660076)
			(xy 413.800825 -162.659672) (xy 413.726976 -162.653407) (xy 413.653913 -162.640964) (xy 413.582153 -162.622432)
			(xy 413.547052 -162.610546) (xy 413.538855 -162.608032) (xy 413.521721 -162.608032) (xy 413.513524 -162.610546)
			(xy 413.484638 -162.620383) (xy 413.425785 -162.636529) (xy 413.395922 -162.642804) (xy 413.386334 -162.645159)
			(xy 413.369889 -162.656054) (xy 413.358796 -162.672367) (xy 413.356298 -162.68192) (xy 413.34617 -162.726275)
			(xy 413.318046 -162.812805) (xy 413.300164 -162.85464) (xy 413.296347 -162.864579) (xy 413.296353 -162.885846)
			(xy 413.300164 -162.895788) (xy 413.318394 -162.938388) (xy 413.346909 -163.026556) (xy 413.366099 -163.117213)
			(xy 413.375757 -163.209373) (xy 413.376364 -163.255706) (xy 413.376364 -163.256214) (xy 413.37586 -163.298562)
			(xy 413.367809 -163.382876) (xy 413.35178 -163.466042) (xy 413.327919 -163.547309) (xy 413.29644 -163.625939)
			(xy 413.257629 -163.70122) (xy 413.230169 -163.74395) (xy 431.840894 -163.74395) (xy 431.840894 -163.68945)
			(xy 431.84865 -163.635505) (xy 431.864004 -163.583213) (xy 431.886644 -163.533639) (xy 431.916109 -163.48779)
			(xy 431.951798 -163.446602) (xy 431.992986 -163.410912) (xy 432.038833 -163.381447) (xy 432.088408 -163.358807)
			(xy 432.140699 -163.343452) (xy 432.194644 -163.335695) (xy 432.221894 -163.335208) (xy 433.212494 -163.335208)
			(xy 433.239748 -163.335638) (xy 433.293702 -163.343395) (xy 433.346003 -163.358751) (xy 433.395586 -163.381394)
			(xy 433.441442 -163.410863) (xy 433.482637 -163.446559) (xy 433.518333 -163.487753) (xy 433.547803 -163.533609)
			(xy 433.570447 -163.583191) (xy 433.585804 -163.635492) (xy 433.593561 -163.689446) (xy 433.593561 -163.743954)
			(xy 433.585804 -163.797908) (xy 433.570447 -163.850209) (xy 433.547803 -163.899791) (xy 433.518333 -163.945647)
			(xy 433.482637 -163.986841) (xy 433.441442 -164.022537) (xy 433.395586 -164.052006) (xy 433.346003 -164.074649)
			(xy 433.293702 -164.090005) (xy 433.239748 -164.097762) (xy 433.212494 -164.098224) (xy 432.221894 -164.098224)
			(xy 432.194644 -164.097705) (xy 432.140699 -164.089948) (xy 432.088408 -164.074593) (xy 432.038833 -164.051953)
			(xy 431.992986 -164.022488) (xy 431.951798 -163.986798) (xy 431.916109 -163.94561) (xy 431.886644 -163.899761)
			(xy 431.864004 -163.850187) (xy 431.84865 -163.797895) (xy 431.840894 -163.74395) (xy 413.230169 -163.74395)
			(xy 413.211839 -163.772472) (xy 413.159483 -163.839048) (xy 413.101035 -163.900346) (xy 413.037025 -163.955811)
			(xy 412.968033 -164.00494) (xy 412.894683 -164.047289) (xy 412.81764 -164.082473) (xy 412.737601 -164.110175)
			(xy 412.655292 -164.130143) (xy 412.571457 -164.142196) (xy 412.486856 -164.146227) (xy 412.402255 -164.142196)
			(xy 412.31842 -164.130143) (xy 412.236111 -164.110175) (xy 412.156072 -164.082473) (xy 412.079029 -164.047289)
			(xy 412.005679 -164.00494) (xy 411.936687 -163.955811) (xy 411.872677 -163.900346) (xy 411.814229 -163.839048)
			(xy 411.761873 -163.772472) (xy 411.716083 -163.70122) (xy 411.677272 -163.625939) (xy 411.645793 -163.547309)
			(xy 411.621932 -163.466042) (xy 411.605903 -163.382876) (xy 411.597852 -163.298562) (xy 411.597348 -163.256214)
			(xy 411.597348 -163.255706) (xy 411.597963 -163.209374) (xy 411.607632 -163.117217) (xy 411.626825 -163.026563)
			(xy 411.655334 -162.938394) (xy 411.673548 -162.895788) (xy 411.677348 -162.885844) (xy 411.677353 -162.864582)
			(xy 411.673548 -162.85464) (xy 411.655311 -162.811974) (xy 411.626764 -162.723684) (xy 411.607569 -162.632899)
			(xy 411.597934 -162.54061) (xy 411.597348 -162.494214) (xy 411.597953 -162.446404) (xy 411.608131 -162.351329)
			(xy 411.617668 -162.304476) (xy 411.61964 -162.292071) (xy 411.612727 -162.267957) (xy 411.60446 -162.258502)
			(xy 411.56382 -162.216338) (xy 411.560264 -162.2171) (xy 411.551416 -162.219411) (xy 411.536053 -162.229303)
			(xy 411.530292 -162.236404) (xy 411.505145 -162.269057) (xy 411.449744 -162.330083) (xy 411.388935 -162.385722)
			(xy 411.323239 -162.435497) (xy 411.253221 -162.478981) (xy 411.17948 -162.515801) (xy 411.102649 -162.545642)
			(xy 411.023387 -162.568246) (xy 410.942373 -162.583421) (xy 410.860303 -162.591036) (xy 410.819092 -162.591496)
			(xy 410.818838 -162.591496) (xy 410.777733 -162.590951) (xy 410.695873 -162.583371) (xy 410.615061 -162.568271)
			(xy 410.535987 -162.54578) (xy 410.459325 -162.516091) (xy 410.385729 -162.479456) (xy 410.315826 -162.436187)
			(xy 410.250213 -162.386655) (xy 410.18945 -162.331281) (xy 410.134053 -162.270538) (xy 410.084497 -162.204943)
			(xy 410.041203 -162.135056) (xy 410.004541 -162.061473) (xy 409.974824 -161.984822) (xy 409.952304 -161.905756)
			(xy 409.937174 -161.82495) (xy 409.929564 -161.743093) (xy 409.929076 -161.701988) (xy 388.231017 -161.701988)
			(xy 388.258994 -161.7316) (xy 388.325644 -161.8138) (xy 388.385886 -161.900804) (xy 388.439375 -161.992115)
			(xy 388.485806 -162.08721) (xy 388.524911 -162.185544) (xy 388.556468 -162.286555) (xy 388.580295 -162.389662)
			(xy 388.596256 -162.494276) (xy 388.60426 -162.599798) (xy 388.60476 -162.65271) (xy 388.60426 -162.705622)
			(xy 388.596256 -162.811144) (xy 388.580295 -162.915758) (xy 388.556468 -163.018865) (xy 388.524911 -163.119876)
			(xy 388.485806 -163.21821) (xy 388.439375 -163.313305) (xy 388.385886 -163.404616) (xy 388.325644 -163.49162)
			(xy 388.258994 -163.57382) (xy 388.186319 -163.650743) (xy 388.108035 -163.721949) (xy 388.024589 -163.787031)
			(xy 387.93646 -163.845616) (xy 387.844153 -163.897368) (xy 387.748196 -163.94199) (xy 387.649139 -163.979228)
			(xy 387.54755 -164.008868) (xy 387.44401 -164.030739) (xy 387.339113 -164.044718) (xy 387.233459 -164.050723)
			(xy 387.127653 -164.04872) (xy 387.022302 -164.038721) (xy 386.918009 -164.020783) (xy 386.815371 -163.995009)
			(xy 386.714976 -163.961547) (xy 386.617399 -163.920587) (xy 386.5232 -163.872365) (xy 386.432917 -163.817158)
			(xy 386.347068 -163.75528) (xy 386.266145 -163.687087) (xy 386.190611 -163.612969) (xy 386.120899 -163.533351)
			(xy 386.057408 -163.448688) (xy 386.000501 -163.359467) (xy 385.950505 -163.266197) (xy 385.907707 -163.169413)
			(xy 385.87235 -163.069669) (xy 385.844639 -162.967537) (xy 385.82473 -162.863602) (xy 385.81274 -162.758459)
			(xy 385.808735 -162.65271) (xy 379.266995 -162.65271) (xy 379.259216 -162.755264) (xy 379.243255 -162.859878)
			(xy 379.219428 -162.962985) (xy 379.187871 -163.063996) (xy 379.148766 -163.16233) (xy 379.102335 -163.257425)
			(xy 379.048846 -163.348736) (xy 378.988604 -163.43574) (xy 378.921954 -163.51794) (xy 378.849279 -163.594863)
			(xy 378.770995 -163.666069) (xy 378.687549 -163.731151) (xy 378.59942 -163.789736) (xy 378.507113 -163.841488)
			(xy 378.411156 -163.88611) (xy 378.312099 -163.923348) (xy 378.21051 -163.952988) (xy 378.10697 -163.974859)
			(xy 378.002073 -163.988838) (xy 377.896419 -163.994843) (xy 377.790613 -163.99284) (xy 377.685262 -163.982841)
			(xy 377.580969 -163.964903) (xy 377.478331 -163.939129) (xy 377.377936 -163.905667) (xy 377.280359 -163.864707)
			(xy 377.18616 -163.816485) (xy 377.095877 -163.761278) (xy 377.010028 -163.6994) (xy 376.929105 -163.631207)
			(xy 376.853571 -163.557089) (xy 376.783859 -163.477471) (xy 376.720368 -163.392808) (xy 376.663461 -163.303587)
			(xy 376.613465 -163.210317) (xy 376.570667 -163.113533) (xy 376.53531 -163.013789) (xy 376.507599 -162.911657)
			(xy 376.48769 -162.807722) (xy 376.4757 -162.702579) (xy 376.471695 -162.59683) (xy 123.913877 -162.59683)
			(xy 123.967949 -162.659232) (xy 124.016605 -162.727559) (xy 124.058546 -162.800202) (xy 124.093391 -162.876503)
			(xy 124.120826 -162.95577) (xy 124.140602 -163.037287) (xy 124.15254 -163.120314) (xy 124.156531 -163.2041)
			(xy 124.15254 -163.287886) (xy 124.140602 -163.370913) (xy 124.120826 -163.45243) (xy 124.093391 -163.531697)
			(xy 124.058546 -163.607998) (xy 124.016605 -163.680641) (xy 123.967949 -163.748968) (xy 123.913018 -163.812361)
			(xy 123.85231 -163.870245) (xy 123.786375 -163.922096) (xy 123.71581 -163.967445) (xy 123.641253 -164.005881)
			(xy 123.56338 -164.037056) (xy 123.482897 -164.060687) (xy 123.400532 -164.076561) (xy 123.31703 -164.084533)
			(xy 123.27509 -164.085016) (xy 123.2379 -164.084629) (xy 123.163787 -164.078339) (xy 123.090468 -164.065828)
			(xy 123.018462 -164.047187) (xy 122.983244 -164.035232) (xy 122.975047 -164.032718) (xy 122.957913 -164.032718)
			(xy 122.949716 -164.035232) (xy 122.907233 -164.049509) (xy 122.820068 -164.070379) (xy 122.775726 -164.076888)
			(xy 122.765804 -164.078672) (xy 122.748385 -164.088778) (xy 122.736231 -164.104835) (xy 122.733308 -164.11448)
			(xy 122.724748 -164.14638) (xy 122.70352 -164.20893) (xy 122.69089 -164.239448) (xy 122.687282 -164.249022)
			(xy 122.687136 -164.26946) (xy 122.690636 -164.279072) (xy 122.707671 -164.320445) (xy 122.734286 -164.405873)
			(xy 122.752187 -164.493543) (xy 122.756237 -164.53358) (xy 365.854996 -164.53358) (xy 365.855358 -164.495263)
			(xy 365.861892 -164.41891) (xy 365.874978 -164.343403) (xy 365.89452 -164.269304) (xy 365.907066 -164.233098)
			(xy 365.909662 -164.224784) (xy 365.909655 -164.207378) (xy 365.907066 -164.199062) (xy 365.894569 -164.162941)
			(xy 365.875081 -164.089028) (xy 365.861998 -164.013717) (xy 365.855418 -163.937561) (xy 365.854996 -163.899342)
			(xy 365.854996 -163.89858) (xy 365.855448 -163.857477) (xy 365.863034 -163.775622) (xy 365.878141 -163.694816)
			(xy 365.900639 -163.615749) (xy 365.930337 -163.539095) (xy 365.966981 -163.465508) (xy 366.010258 -163.395615)
			(xy 366.059799 -163.330014) (xy 366.115181 -163.269264) (xy 366.175933 -163.213883) (xy 366.241535 -163.164344)
			(xy 366.311429 -163.121069) (xy 366.385017 -163.084427) (xy 366.461672 -163.054732) (xy 366.54074 -163.032236)
			(xy 366.621546 -163.017131) (xy 366.703401 -163.009546) (xy 366.744504 -163.009072) (xy 366.745266 -163.009072)
			(xy 366.783487 -163.009474) (xy 366.859645 -163.01604) (xy 366.934958 -163.029126) (xy 367.008868 -163.048635)
			(xy 367.044986 -163.061142) (xy 367.053302 -163.063728) (xy 367.070706 -163.063728) (xy 367.079022 -163.061142)
			(xy 367.115235 -163.04862) (xy 367.189336 -163.029098) (xy 367.26484 -163.016015) (xy 367.341189 -163.009466)
			(xy 367.379504 -163.009072) (xy 367.419718 -163.009498) (xy 367.49982 -163.016721) (xy 367.578942 -163.031153)
			(xy 367.656435 -163.052677) (xy 367.69421 -163.066476) (xy 367.702997 -163.069383) (xy 367.721491 -163.069383)
			(xy 367.730278 -163.066476) (xy 367.768054 -163.052684) (xy 367.845551 -163.031177) (xy 367.924672 -163.016746)
			(xy 368.004771 -163.00951) (xy 368.044984 -163.009072) (xy 368.0833 -163.009446) (xy 368.159653 -163.015977)
			(xy 368.23516 -163.029059) (xy 368.309259 -163.048598) (xy 368.345466 -163.061142) (xy 368.353782 -163.063728)
			(xy 368.371186 -163.063728) (xy 368.379502 -163.061142) (xy 368.415717 -163.048626) (xy 368.489817 -163.029103)
			(xy 368.565321 -163.016017) (xy 368.641669 -163.009467) (xy 368.679984 -163.009072) (xy 368.7183 -163.009446)
			(xy 368.794653 -163.015977) (xy 368.87016 -163.029059) (xy 368.944259 -163.048598) (xy 368.980466 -163.061142)
			(xy 368.988782 -163.063728) (xy 369.006186 -163.063728) (xy 369.014502 -163.061142) (xy 369.050717 -163.048626)
			(xy 369.124817 -163.029103) (xy 369.200321 -163.016017) (xy 369.276669 -163.009467) (xy 369.314984 -163.009072)
			(xy 369.3533 -163.009446) (xy 369.429653 -163.015977) (xy 369.50516 -163.029059) (xy 369.579259 -163.048598)
			(xy 369.615466 -163.061142) (xy 369.623782 -163.063728) (xy 369.641186 -163.063728) (xy 369.649502 -163.061142)
			(xy 369.685565 -163.048673) (xy 369.759352 -163.029204) (xy 369.834533 -163.016119) (xy 369.910559 -163.009515)
			(xy 369.948714 -163.009072) (xy 369.949984 -163.009072) (xy 369.994754 -163.009635) (xy 370.083841 -163.018637)
			(xy 370.171573 -163.03654) (xy 370.257063 -163.063164) (xy 370.298472 -163.080192) (xy 370.308063 -163.083757)
			(xy 370.328505 -163.083757) (xy 370.338096 -163.080192) (xy 370.379479 -163.063183) (xy 370.464904 -163.036561)
			(xy 370.55257 -163.018653) (xy 370.641592 -163.00964) (xy 370.68633 -163.009072) (xy 370.686584 -163.009072)
			(xy 370.727686 -163.009582) (xy 370.809538 -163.017165) (xy 370.890342 -163.032268) (xy 370.969408 -163.054763)
			(xy 371.046061 -163.084457) (xy 371.119647 -163.121096) (xy 371.189538 -163.16437) (xy 371.255139 -163.213907)
			(xy 371.315889 -163.269286) (xy 371.37127 -163.330033) (xy 371.42081 -163.395632) (xy 371.464086 -163.465522)
			(xy 371.500729 -163.539106) (xy 371.530426 -163.615758) (xy 371.552923 -163.694823) (xy 371.56803 -163.775626)
			(xy 371.575616 -163.857478) (xy 371.576092 -163.89858) (xy 371.576092 -163.899342) (xy 371.575679 -163.937562)
			(xy 371.569116 -164.013721) (xy 371.556033 -164.089033) (xy 371.536527 -164.162943) (xy 371.524022 -164.199062)
			(xy 371.521447 -164.207381) (xy 371.52144 -164.224782) (xy 371.524022 -164.233098) (xy 371.536535 -164.269314)
			(xy 371.55606 -164.343414) (xy 371.569146 -164.418917) (xy 371.575697 -164.495265) (xy 371.576092 -164.53358)
			(xy 371.575734 -164.571323) (xy 371.569392 -164.646543) (xy 371.556692 -164.720953) (xy 371.537726 -164.794018)
			(xy 371.525546 -164.829744) (xy 371.522818 -164.838516) (xy 371.52307 -164.85687) (xy 371.526054 -164.865558)
			(xy 371.541045 -164.904681) (xy 371.564495 -164.985121) (xy 371.58028 -165.067409) (xy 371.588259 -165.150817)
			(xy 371.588792 -165.19271) (xy 371.588792 -165.19398) (xy 371.588329 -165.235083) (xy 371.580745 -165.316939)
			(xy 371.565641 -165.397747) (xy 371.543146 -165.476815) (xy 371.51345 -165.553471) (xy 371.476808 -165.62706)
			(xy 371.433533 -165.696954) (xy 371.383993 -165.762556) (xy 371.328611 -165.823308) (xy 371.267859 -165.87869)
			(xy 371.202257 -165.92823) (xy 371.132363 -165.971506) (xy 371.058775 -166.008149) (xy 370.982119 -166.037844)
			(xy 370.90305 -166.06034) (xy 370.822243 -166.075445) (xy 370.740387 -166.083029) (xy 370.699284 -166.083488)
			(xy 370.69903 -166.083488) (xy 370.654291 -166.082927) (xy 370.56527 -166.07391) (xy 370.477602 -166.056003)
			(xy 370.392175 -166.029387) (xy 370.350796 -166.012368) (xy 370.341205 -166.008803) (xy 370.320763 -166.008803)
			(xy 370.311172 -166.012368) (xy 370.269762 -166.029396) (xy 370.184274 -166.056029) (xy 370.096542 -166.073935)
			(xy 370.007454 -166.082933) (xy 369.962684 -166.083488) (xy 369.961414 -166.083488) (xy 369.923257 -166.083067)
			(xy 369.847228 -166.076479) (xy 369.772044 -166.063393) (xy 369.69826 -166.043906) (xy 369.662202 -166.031418)
			(xy 369.653886 -166.028832) (xy 369.636482 -166.028832) (xy 369.628166 -166.031418) (xy 369.591953 -166.043941)
			(xy 369.517852 -166.063463) (xy 369.442348 -166.076546) (xy 369.365999 -166.083094) (xy 369.327684 -166.083488)
			(xy 369.289367 -166.083126) (xy 369.213014 -166.076592) (xy 369.137507 -166.063506) (xy 369.063408 -166.043964)
			(xy 369.027202 -166.031418) (xy 369.018886 -166.028832) (xy 369.001482 -166.028832) (xy 368.993166 -166.031418)
			(xy 368.956953 -166.043941) (xy 368.882852 -166.063463) (xy 368.807348 -166.076546) (xy 368.730999 -166.083094)
			(xy 368.692684 -166.083488) (xy 368.654367 -166.083126) (xy 368.578014 -166.076592) (xy 368.502507 -166.063506)
			(xy 368.428408 -166.043964) (xy 368.392202 -166.031418) (xy 368.383886 -166.028832) (xy 368.366482 -166.028832)
			(xy 368.358166 -166.031418) (xy 368.321953 -166.043941) (xy 368.247852 -166.063463) (xy 368.172348 -166.076546)
			(xy 368.095999 -166.083094) (xy 368.057684 -166.083488) (xy 368.01747 -166.083062) (xy 367.937368 -166.075838)
			(xy 367.858246 -166.061406) (xy 367.780753 -166.039883) (xy 367.742978 -166.026084) (xy 367.734191 -166.023177)
			(xy 367.715697 -166.023177) (xy 367.70691 -166.026084) (xy 367.669134 -166.039877) (xy 367.591637 -166.061385)
			(xy 367.512517 -166.075815) (xy 367.432417 -166.083051) (xy 367.392204 -166.083488) (xy 367.353888 -166.08312)
			(xy 367.277534 -166.076588) (xy 367.202027 -166.063503) (xy 367.127928 -166.043963) (xy 367.091722 -166.031418)
			(xy 367.083406 -166.028832) (xy 367.066002 -166.028832) (xy 367.057686 -166.031418) (xy 367.021563 -166.043908)
			(xy 366.947651 -166.063398) (xy 366.87234 -166.076483) (xy 366.796185 -166.083065) (xy 366.757966 -166.083488)
			(xy 366.757204 -166.083488) (xy 366.7161 -166.083044) (xy 366.634244 -166.075459) (xy 366.553436 -166.060354)
			(xy 366.474367 -166.037857) (xy 366.397711 -166.00816) (xy 366.324122 -165.971516) (xy 366.254228 -165.928239)
			(xy 366.188625 -165.878698) (xy 366.127874 -165.823315) (xy 366.072492 -165.762562) (xy 366.022951 -165.696959)
			(xy 365.979676 -165.627064) (xy 365.943034 -165.553475) (xy 365.913338 -165.476818) (xy 365.890843 -165.397748)
			(xy 365.875739 -165.316941) (xy 365.868155 -165.235084) (xy 365.867696 -165.19398) (xy 365.867696 -165.192964)
			(xy 365.868115 -165.155349) (xy 365.874496 -165.080389) (xy 365.887191 -165.006237) (xy 365.906111 -164.933424)
			(xy 365.918242 -164.897816) (xy 365.920992 -164.889049) (xy 365.920727 -164.87069) (xy 365.917734 -164.862002)
			(xy 365.902679 -164.822733) (xy 365.879172 -164.741978) (xy 365.863391 -164.659366) (xy 365.855475 -164.575633)
			(xy 365.854996 -164.53358) (xy 122.756237 -164.53358) (xy 122.761192 -164.582567) (xy 122.761756 -164.627306)
			(xy 122.761756 -164.62756) (xy 122.761252 -164.669908) (xy 122.753201 -164.754222) (xy 122.737172 -164.837388)
			(xy 122.713311 -164.918655) (xy 122.681832 -164.997285) (xy 122.643021 -165.072566) (xy 122.597231 -165.143818)
			(xy 122.544875 -165.210394) (xy 122.486427 -165.271692) (xy 122.422417 -165.327157) (xy 122.353425 -165.376286)
			(xy 122.280075 -165.418635) (xy 122.203032 -165.453819) (xy 122.122993 -165.481521) (xy 122.040684 -165.501489)
			(xy 121.956849 -165.513542) (xy 121.872248 -165.517573) (xy 121.787647 -165.513542) (xy 121.703812 -165.501489)
			(xy 121.621503 -165.481521) (xy 121.541464 -165.453819) (xy 121.464421 -165.418635) (xy 121.391071 -165.376286)
			(xy 121.322079 -165.327157) (xy 121.258069 -165.271692) (xy 121.199621 -165.210394) (xy 121.147265 -165.143818)
			(xy 121.101475 -165.072566) (xy 121.062664 -164.997285) (xy 121.031185 -164.918655) (xy 121.007324 -164.837388)
			(xy 120.991295 -164.754222) (xy 120.983244 -164.669908) (xy 120.98274 -164.62756) (xy 120.98274 -164.627306)
			(xy 120.983291 -164.582567) (xy 120.992311 -164.493545) (xy 121.010221 -164.405878) (xy 121.03684 -164.320451)
			(xy 121.05386 -164.279072) (xy 121.057447 -164.269488) (xy 121.057432 -164.249039) (xy 121.05386 -164.239448)
			(xy 121.037012 -164.19848) (xy 121.010567 -164.113931) (xy 120.992664 -164.027171) (xy 120.983478 -163.939061)
			(xy 120.98274 -163.89477) (xy 120.982373 -163.885212) (xy 120.975335 -163.867438) (xy 120.962255 -163.853496)
			(xy 120.953784 -163.84905) (xy 120.870726 -163.809934) (xy 120.861899 -163.806187) (xy 120.842781 -163.804911)
			(xy 120.824539 -163.810771) (xy 120.816878 -163.816538) (xy 120.782853 -163.843559) (xy 120.710459 -163.891613)
			(xy 120.633724 -163.93238) (xy 120.55338 -163.965469) (xy 120.470192 -163.990568) (xy 120.384953 -164.007435)
			(xy 120.298476 -164.01591) (xy 120.25503 -164.016436) (xy 120.213915 -164.015973) (xy 120.132035 -164.008388)
			(xy 120.051204 -163.99328) (xy 119.972113 -163.970779) (xy 119.895435 -163.941075) (xy 119.821825 -163.904423)
			(xy 119.751911 -163.861135) (xy 119.686289 -163.811581) (xy 119.62552 -163.756183) (xy 119.570122 -163.695414)
			(xy 119.520567 -163.629793) (xy 119.477279 -163.559879) (xy 119.440626 -163.486269) (xy 119.410922 -163.409591)
			(xy 119.38842 -163.330499) (xy 119.373312 -163.249669) (xy 119.365727 -163.167789) (xy 119.365268 -163.126674)
			(xy 91.076082 -163.126674) (xy 91.074618 -163.131296) (xy 91.074629 -163.148971) (xy 91.077288 -163.157408)
			(xy 91.089816 -163.193591) (xy 91.109393 -163.267622) (xy 91.122545 -163.34306) (xy 91.129174 -163.419348)
			(xy 91.129612 -163.457636) (xy 91.129114 -163.500412) (xy 91.120898 -163.585569) (xy 91.104536 -163.669543)
			(xy 91.080178 -163.751555) (xy 91.064588 -163.791392) (xy 91.061544 -163.799848) (xy 91.060879 -163.817795)
			(xy 91.063318 -163.826444) (xy 91.07787 -163.871922) (xy 91.098306 -163.9652) (xy 91.108623 -164.060131)
			(xy 91.109292 -164.107876) (xy 91.108825 -164.148987) (xy 91.101239 -164.230857) (xy 91.08613 -164.311679)
			(xy 91.063626 -164.390761) (xy 91.033921 -164.467428) (xy 90.997266 -164.541027) (xy 90.953976 -164.610929)
			(xy 90.904419 -164.676538) (xy 90.849019 -164.737293) (xy 90.788249 -164.792677) (xy 90.722626 -164.842215)
			(xy 90.652712 -164.885486) (xy 90.579103 -164.92212) (xy 90.502427 -164.951804) (xy 90.423339 -164.974286)
			(xy 90.342514 -164.989373) (xy 90.260641 -164.996936) (xy 90.21953 -164.997384) (xy 90.177921 -164.996892)
			(xy 90.095064 -164.989136) (xy 90.013294 -164.97368) (xy 89.933323 -164.950659) (xy 89.89441 -164.935916)
			(xy 89.88572 -164.932926) (xy 89.867362 -164.932654) (xy 89.858596 -164.935408) (xy 89.822497 -164.947854)
			(xy 89.748643 -164.967275) (xy 89.673397 -164.980297) (xy 89.597312 -164.986825) (xy 89.55913 -164.987224)
			(xy 89.520814 -164.986846) (xy 89.444461 -164.980317) (xy 89.368954 -164.967235) (xy 89.294855 -164.947698)
			(xy 89.258648 -164.935154) (xy 89.250332 -164.932568) (xy 89.232928 -164.932568) (xy 89.224612 -164.935154)
			(xy 89.188396 -164.947666) (xy 89.114296 -164.96719) (xy 89.038793 -164.980277) (xy 88.962445 -164.986828)
			(xy 88.92413 -164.987224) (xy 88.885814 -164.986846) (xy 88.809461 -164.980317) (xy 88.733954 -164.967235)
			(xy 88.659855 -164.947698) (xy 88.623648 -164.935154) (xy 88.615332 -164.932568) (xy 88.597928 -164.932568)
			(xy 88.589612 -164.935154) (xy 88.553396 -164.947666) (xy 88.479296 -164.96719) (xy 88.403793 -164.980277)
			(xy 88.327445 -164.986828) (xy 88.28913 -164.987224) (xy 88.250814 -164.986846) (xy 88.174461 -164.980317)
			(xy 88.098954 -164.967235) (xy 88.024855 -164.947698) (xy 87.988648 -164.935154) (xy 87.980332 -164.932568)
			(xy 87.962928 -164.932568) (xy 87.954612 -164.935154) (xy 87.918396 -164.947666) (xy 87.844296 -164.96719)
			(xy 87.768793 -164.980277) (xy 87.692445 -164.986828) (xy 87.65413 -164.987224) (xy 87.615814 -164.986846)
			(xy 87.539461 -164.980317) (xy 87.463954 -164.967235) (xy 87.389855 -164.947698) (xy 87.353648 -164.935154)
			(xy 87.345332 -164.932568) (xy 87.327928 -164.932568) (xy 87.319612 -164.935154) (xy 87.283487 -164.947638)
			(xy 87.209575 -164.96713) (xy 87.134265 -164.980216) (xy 87.058111 -164.9868) (xy 87.019892 -164.987224)
			(xy 87.01913 -164.987224) (xy 86.978023 -164.986759) (xy 86.896158 -164.979177) (xy 86.815342 -164.964075)
			(xy 86.736265 -164.941581) (xy 86.659599 -164.911888) (xy 86.586 -164.875249) (xy 86.516095 -164.831976)
			(xy 86.45048 -164.782438) (xy 86.389716 -164.727058) (xy 86.334319 -164.666309) (xy 86.284763 -164.600708)
			(xy 86.241471 -164.530815) (xy 86.204811 -164.457226) (xy 86.175097 -164.380569) (xy 86.152582 -164.301497)
			(xy 86.137457 -164.220686) (xy 86.129853 -164.138823) (xy 86.129368 -164.097716) (xy 2.509012 -164.097716)
			(xy 2.509012 -166.86276) (xy 61.046868 -166.86276) (xy 61.047433 -166.81799) (xy 61.056443 -166.728905)
			(xy 61.074347 -166.641174) (xy 61.100966 -166.555683) (xy 61.117988 -166.514272) (xy 61.121578 -166.504688)
			(xy 61.121563 -166.484239) (xy 61.117988 -166.474648) (xy 61.100968 -166.433235) (xy 61.074329 -166.347749)
			(xy 61.05642 -166.260018) (xy 61.047422 -166.17093) (xy 61.046868 -166.12616) (xy 61.047433 -166.08139)
			(xy 61.056443 -165.992305) (xy 61.074347 -165.904574) (xy 61.100966 -165.819083) (xy 61.117988 -165.777672)
			(xy 61.121578 -165.768088) (xy 61.121563 -165.747639) (xy 61.117988 -165.738048) (xy 61.100968 -165.696635)
			(xy 61.074329 -165.611149) (xy 61.05642 -165.523418) (xy 61.047422 -165.43433) (xy 61.046868 -165.38956)
			(xy 61.047314 -165.348449) (xy 61.054905 -165.266579) (xy 61.070019 -165.185759) (xy 61.092527 -165.106679)
			(xy 61.122236 -165.030013) (xy 61.158893 -164.956415) (xy 61.202185 -164.886514) (xy 61.251743 -164.820907)
			(xy 61.307144 -164.760153) (xy 61.367915 -164.70477) (xy 61.433537 -164.655232) (xy 61.503451 -164.611961)
			(xy 61.57706 -164.575327) (xy 61.653735 -164.545641) (xy 61.732822 -164.523157) (xy 61.813647 -164.508068)
			(xy 61.895519 -164.500502) (xy 61.93663 -164.500052) (xy 61.978234 -164.500535) (xy 62.061081 -164.508266)
			(xy 62.142846 -164.523695) (xy 62.222813 -164.546687) (xy 62.300286 -164.577041) (xy 62.374588 -164.614493)
			(xy 62.410086 -164.636196) (xy 62.419228 -164.641351) (xy 62.439942 -164.644569) (xy 62.460215 -164.639239)
			(xy 62.46876 -164.633148) (xy 62.502383 -164.607191) (xy 62.573762 -164.561136) (xy 62.649206 -164.522094)
			(xy 62.728027 -164.49042) (xy 62.809509 -164.466402) (xy 62.892908 -164.450259) (xy 62.977466 -164.442138)
			(xy 63.01994 -164.441632) (xy 63.020194 -164.441632) (xy 63.0613 -164.442118) (xy 63.143163 -164.449702)
			(xy 63.223977 -164.464805) (xy 63.303052 -164.487299) (xy 63.379716 -164.516993) (xy 63.453313 -164.553631)
			(xy 63.523217 -164.596903) (xy 63.58883 -164.64644) (xy 63.649594 -164.701818) (xy 63.70499 -164.762565)
			(xy 63.754546 -164.828164) (xy 63.797839 -164.898054) (xy 63.8345 -164.971641) (xy 63.864216 -165.048295)
			(xy 63.886734 -165.127364) (xy 63.901861 -165.208173) (xy 63.909469 -165.290034) (xy 63.909956 -165.33114)
			(xy 63.909389 -165.375909) (xy 63.900379 -165.464994) (xy 63.882475 -165.552725) (xy 63.855858 -165.638217)
			(xy 63.838836 -165.679628) (xy 63.83525 -165.689212) (xy 63.835264 -165.709661) (xy 63.838836 -165.719252)
			(xy 63.855836 -165.760605) (xy 63.882448 -165.845966) (xy 63.900356 -165.933568) (xy 63.903248 -165.962076)
			(xy 81.591411 -165.962076) (xy 81.595416 -165.856327) (xy 81.607406 -165.751184) (xy 81.627315 -165.647249)
			(xy 81.655026 -165.545117) (xy 81.690383 -165.445373) (xy 81.733181 -165.348589) (xy 81.783177 -165.255319)
			(xy 81.840084 -165.166098) (xy 81.903575 -165.081435) (xy 81.973287 -165.001817) (xy 82.048821 -164.927699)
			(xy 82.129744 -164.859506) (xy 82.215593 -164.797628) (xy 82.305876 -164.742421) (xy 82.400075 -164.694199)
			(xy 82.497652 -164.653239) (xy 82.598047 -164.619777) (xy 82.700685 -164.594003) (xy 82.804978 -164.576065)
			(xy 82.910329 -164.566066) (xy 83.016135 -164.564063) (xy 83.121789 -164.570068) (xy 83.226686 -164.584047)
			(xy 83.330226 -164.605918) (xy 83.431815 -164.635558) (xy 83.530872 -164.672796) (xy 83.626829 -164.717418)
			(xy 83.719136 -164.76917) (xy 83.807265 -164.827755) (xy 83.890711 -164.892837) (xy 83.968995 -164.964043)
			(xy 84.04167 -165.040966) (xy 84.10832 -165.123166) (xy 84.168562 -165.21017) (xy 84.222051 -165.301481)
			(xy 84.268482 -165.396576) (xy 84.307587 -165.49491) (xy 84.339144 -165.595921) (xy 84.362971 -165.699028)
			(xy 84.378932 -165.803642) (xy 84.386936 -165.909164) (xy 84.387436 -165.962076) (xy 90.989411 -165.962076)
			(xy 90.993416 -165.856327) (xy 91.005406 -165.751184) (xy 91.025315 -165.647249) (xy 91.053026 -165.545117)
			(xy 91.088383 -165.445373) (xy 91.131181 -165.348589) (xy 91.181177 -165.255319) (xy 91.238084 -165.166098)
			(xy 91.301575 -165.081435) (xy 91.371287 -165.001817) (xy 91.446821 -164.927699) (xy 91.527744 -164.859506)
			(xy 91.613593 -164.797628) (xy 91.703876 -164.742421) (xy 91.798075 -164.694199) (xy 91.895652 -164.653239)
			(xy 91.996047 -164.619777) (xy 92.098685 -164.594003) (xy 92.202978 -164.576065) (xy 92.308329 -164.566066)
			(xy 92.414135 -164.564063) (xy 92.519789 -164.570068) (xy 92.624686 -164.584047) (xy 92.728226 -164.605918)
			(xy 92.829815 -164.635558) (xy 92.928872 -164.672796) (xy 93.024829 -164.717418) (xy 93.117136 -164.76917)
			(xy 93.205265 -164.827755) (xy 93.288711 -164.892837) (xy 93.366995 -164.964043) (xy 93.43967 -165.040966)
			(xy 93.50632 -165.123166) (xy 93.566562 -165.21017) (xy 93.620051 -165.301481) (xy 93.666482 -165.396576)
			(xy 93.705587 -165.49491) (xy 93.737144 -165.595921) (xy 93.760971 -165.699028) (xy 93.776932 -165.803642)
			(xy 93.784936 -165.909164) (xy 93.785436 -165.962076) (xy 93.784936 -166.014988) (xy 93.776932 -166.12051)
			(xy 93.760971 -166.225124) (xy 93.737144 -166.328231) (xy 93.705587 -166.429242) (xy 93.666482 -166.527576)
			(xy 93.620051 -166.622671) (xy 93.566562 -166.713982) (xy 93.50632 -166.800986) (xy 93.43967 -166.883186)
			(xy 93.366995 -166.960109) (xy 93.288711 -167.031315) (xy 93.205265 -167.096397) (xy 93.117136 -167.154982)
			(xy 93.024829 -167.206734) (xy 92.928872 -167.251356) (xy 92.829815 -167.288594) (xy 92.728226 -167.318234)
			(xy 92.624686 -167.340105) (xy 92.519789 -167.354084) (xy 92.414135 -167.360089) (xy 92.308329 -167.358086)
			(xy 92.202978 -167.348087) (xy 92.098685 -167.330149) (xy 91.996047 -167.304375) (xy 91.895652 -167.270913)
			(xy 91.798075 -167.229953) (xy 91.703876 -167.181731) (xy 91.613593 -167.126524) (xy 91.527744 -167.064646)
			(xy 91.446821 -166.996453) (xy 91.371287 -166.922335) (xy 91.301575 -166.842717) (xy 91.238084 -166.758054)
			(xy 91.181177 -166.668833) (xy 91.131181 -166.575563) (xy 91.088383 -166.478779) (xy 91.053026 -166.379035)
			(xy 91.025315 -166.276903) (xy 91.005406 -166.172968) (xy 90.993416 -166.067825) (xy 90.989411 -165.962076)
			(xy 84.387436 -165.962076) (xy 84.386936 -166.014988) (xy 84.378932 -166.12051) (xy 84.362971 -166.225124)
			(xy 84.339144 -166.328231) (xy 84.307587 -166.429242) (xy 84.268482 -166.527576) (xy 84.222051 -166.622671)
			(xy 84.168562 -166.713982) (xy 84.10832 -166.800986) (xy 84.04167 -166.883186) (xy 83.968995 -166.960109)
			(xy 83.890711 -167.031315) (xy 83.807265 -167.096397) (xy 83.719136 -167.154982) (xy 83.626829 -167.206734)
			(xy 83.530872 -167.251356) (xy 83.431815 -167.288594) (xy 83.330226 -167.318234) (xy 83.226686 -167.340105)
			(xy 83.121789 -167.354084) (xy 83.016135 -167.360089) (xy 82.910329 -167.358086) (xy 82.804978 -167.348087)
			(xy 82.700685 -167.330149) (xy 82.598047 -167.304375) (xy 82.497652 -167.270913) (xy 82.400075 -167.229953)
			(xy 82.305876 -167.181731) (xy 82.215593 -167.126524) (xy 82.129744 -167.064646) (xy 82.048821 -166.996453)
			(xy 81.973287 -166.922335) (xy 81.903575 -166.842717) (xy 81.840084 -166.758054) (xy 81.783177 -166.668833)
			(xy 81.733181 -166.575563) (xy 81.690383 -166.478779) (xy 81.655026 -166.379035) (xy 81.627315 -166.276903)
			(xy 81.607406 -166.172968) (xy 81.595416 -166.067825) (xy 81.591411 -165.962076) (xy 63.903248 -165.962076)
			(xy 63.909379 -166.022525) (xy 63.909956 -166.067232) (xy 63.909956 -166.068248) (xy 63.909702 -166.079678)
			(xy 63.936181 -166.085625) (xy 63.988416 -166.100367) (xy 64.014096 -166.109142) (xy 64.022293 -166.111656)
			(xy 64.039427 -166.111656) (xy 64.047624 -166.109142) (xy 64.082842 -166.097202) (xy 64.154852 -166.078613)
			(xy 64.228174 -166.066171) (xy 64.302285 -166.059965) (xy 64.33947 -166.059612) (xy 64.376654 -166.059989)
			(xy 64.450761 -166.066209) (xy 64.524081 -166.078649) (xy 64.596093 -166.097221) (xy 64.631316 -166.109142)
			(xy 64.639513 -166.111656) (xy 64.656647 -166.111656) (xy 64.664844 -166.109142) (xy 64.699939 -166.097233)
			(xy 64.771698 -166.078689) (xy 64.844763 -166.066249) (xy 64.918616 -166.060001) (xy 64.955674 -166.059612)
			(xy 64.95669 -166.059612) (xy 64.998618 -166.060035) (xy 65.082094 -166.068005) (xy 65.164434 -166.083874)
			(xy 65.244893 -166.107498) (xy 65.322742 -166.138663) (xy 65.397276 -166.177087) (xy 65.46782 -166.222422)
			(xy 65.533735 -166.274258) (xy 65.594424 -166.332124) (xy 65.649338 -166.395498) (xy 65.69798 -166.463804)
			(xy 65.739908 -166.536425) (xy 65.774743 -166.612703) (xy 65.802169 -166.691946) (xy 65.821939 -166.773438)
			(xy 65.833873 -166.85644) (xy 65.837863 -166.9402) (xy 65.833873 -167.02396) (xy 65.821939 -167.106962)
			(xy 65.802169 -167.188454) (xy 65.774743 -167.267697) (xy 65.739908 -167.343975) (xy 65.69798 -167.416596)
			(xy 65.688295 -167.430196) (xy 351.432876 -167.430196) (xy 351.433453 -167.385427) (xy 351.442459 -167.296342)
			(xy 351.46036 -167.208611) (xy 351.486975 -167.123119) (xy 351.503996 -167.081708) (xy 351.507565 -167.072118)
			(xy 351.507564 -167.051674) (xy 351.503996 -167.042084) (xy 351.486956 -167.000679) (xy 351.460322 -166.91519)
			(xy 351.442419 -166.827456) (xy 351.433427 -166.738367) (xy 351.432876 -166.693596) (xy 351.433453 -166.648827)
			(xy 351.442459 -166.559742) (xy 351.46036 -166.472011) (xy 351.486975 -166.386519) (xy 351.503996 -166.345108)
			(xy 351.507565 -166.335518) (xy 351.507564 -166.315074) (xy 351.503996 -166.305484) (xy 351.486956 -166.264079)
			(xy 351.460322 -166.17859) (xy 351.442419 -166.090856) (xy 351.433427 -166.001767) (xy 351.432876 -165.956996)
			(xy 351.433349 -165.915886) (xy 351.440937 -165.834016) (xy 351.456047 -165.753196) (xy 351.478552 -165.674116)
			(xy 351.508259 -165.597449) (xy 351.544914 -165.523852) (xy 351.588204 -165.453951) (xy 351.63776 -165.388343)
			(xy 351.693159 -165.327588) (xy 351.753929 -165.272205) (xy 351.81955 -165.222667) (xy 351.889463 -165.179396)
			(xy 351.963071 -165.142761) (xy 352.039745 -165.113075) (xy 352.118832 -165.090592) (xy 352.199656 -165.075503)
			(xy 352.281528 -165.067937) (xy 352.322638 -165.067488) (xy 352.364242 -165.067962) (xy 352.44709 -165.075694)
			(xy 352.528855 -165.091124) (xy 352.608822 -165.114117) (xy 352.686295 -165.144474) (xy 352.760597 -165.181928)
			(xy 352.796094 -165.203632) (xy 352.805234 -165.208789) (xy 352.825949 -165.212002) (xy 352.846222 -165.206673)
			(xy 352.854768 -165.200584) (xy 352.888392 -165.174629) (xy 352.959771 -165.128573) (xy 353.035214 -165.08953)
			(xy 353.114035 -165.057855) (xy 353.195516 -165.033837) (xy 353.278916 -165.017694) (xy 353.363474 -165.009574)
			(xy 353.405948 -165.009068) (xy 353.406202 -165.009068) (xy 353.44731 -165.009511) (xy 353.529174 -165.017096)
			(xy 353.60999 -165.0322) (xy 353.689068 -165.054696) (xy 353.765733 -165.084391) (xy 353.839332 -165.121033)
			(xy 353.909237 -165.164307) (xy 353.974851 -165.213846) (xy 354.035616 -165.269227) (xy 354.091012 -165.329978)
			(xy 354.140567 -165.39558) (xy 354.183859 -165.465474) (xy 354.220519 -165.539063) (xy 354.250233 -165.615721)
			(xy 354.272749 -165.694793) (xy 354.287874 -165.775606) (xy 354.295479 -165.857468) (xy 354.295964 -165.898576)
			(xy 354.295409 -165.943346) (xy 354.286396 -166.032431) (xy 354.268489 -166.120162) (xy 354.241868 -166.205653)
			(xy 354.224844 -166.247064) (xy 354.221294 -166.256659) (xy 354.221285 -166.277097) (xy 354.224844 -166.286688)
			(xy 354.241856 -166.328036) (xy 354.268465 -166.413399) (xy 354.286369 -166.501003) (xy 354.289105 -166.527988)
			(xy 401.547076 -166.527988) (xy 401.54765 -166.483219) (xy 401.556657 -166.394134) (xy 401.574559 -166.306403)
			(xy 401.601175 -166.220911) (xy 401.618196 -166.1795) (xy 401.62177 -166.169912) (xy 401.621765 -166.149466)
			(xy 401.618196 -166.139876) (xy 401.601153 -166.098472) (xy 401.574521 -166.012983) (xy 401.556618 -165.925248)
			(xy 401.547627 -165.836159) (xy 401.547076 -165.791388) (xy 401.54765 -165.746619) (xy 401.556657 -165.657534)
			(xy 401.574559 -165.569803) (xy 401.601175 -165.484311) (xy 401.618196 -165.4429) (xy 401.62177 -165.433312)
			(xy 401.621765 -165.412866) (xy 401.618196 -165.403276) (xy 401.601153 -165.361872) (xy 401.574521 -165.276383)
			(xy 401.556618 -165.188648) (xy 401.547627 -165.099559) (xy 401.547076 -165.054788) (xy 401.547541 -165.013678)
			(xy 401.55513 -164.931808) (xy 401.570241 -164.850988) (xy 401.592747 -164.771907) (xy 401.622454 -164.695241)
			(xy 401.659109 -164.621643) (xy 401.7024 -164.551742) (xy 401.751957 -164.486134) (xy 401.807357 -164.42538)
			(xy 401.868127 -164.369997) (xy 401.933748 -164.320459) (xy 402.003662 -164.277187) (xy 402.07727 -164.240553)
			(xy 402.153944 -164.210867) (xy 402.233031 -164.188384) (xy 402.313856 -164.173295) (xy 402.395728 -164.165729)
			(xy 402.436838 -164.16528) (xy 402.478442 -164.165755) (xy 402.56129 -164.173487) (xy 402.643054 -164.188917)
			(xy 402.723022 -164.21191) (xy 402.800495 -164.242266) (xy 402.874796 -164.27972) (xy 402.910294 -164.301424)
			(xy 402.919434 -164.306582) (xy 402.940149 -164.309796) (xy 402.960422 -164.304466) (xy 402.968968 -164.298376)
			(xy 403.002591 -164.27242) (xy 403.07397 -164.226364) (xy 403.149414 -164.187321) (xy 403.228235 -164.155647)
			(xy 403.309716 -164.131629) (xy 403.393116 -164.115486) (xy 403.477674 -164.107366) (xy 403.520148 -164.10686)
			(xy 403.520402 -164.10686) (xy 403.561509 -164.107311) (xy 403.643374 -164.114895) (xy 403.724189 -164.13)
			(xy 403.803267 -164.152496) (xy 403.879931 -164.182191) (xy 403.95353 -164.218831) (xy 404.023434 -164.262106)
			(xy 404.089048 -164.311644) (xy 404.149813 -164.367025) (xy 404.205209 -164.427775) (xy 404.254764 -164.493376)
			(xy 404.298057 -164.563269) (xy 404.334716 -164.636858) (xy 404.364431 -164.713515) (xy 404.386947 -164.792587)
			(xy 404.402073 -164.873398) (xy 404.409679 -164.955261) (xy 404.410164 -164.996368) (xy 404.409606 -165.041138)
			(xy 404.400594 -165.130223) (xy 404.382688 -165.217954) (xy 404.356068 -165.303445) (xy 404.339044 -165.344856)
			(xy 404.335498 -165.354452) (xy 404.335487 -165.374889) (xy 404.339044 -165.38448) (xy 404.356053 -165.425829)
			(xy 404.382663 -165.511192) (xy 404.400568 -165.598795) (xy 404.409589 -165.687753) (xy 404.410164 -165.73246)
			(xy 404.410164 -165.733476) (xy 404.40991 -165.744906) (xy 404.436389 -165.750851) (xy 404.488624 -165.765594)
			(xy 404.514304 -165.77437) (xy 404.522501 -165.776884) (xy 404.539635 -165.776884) (xy 404.547832 -165.77437)
			(xy 404.58305 -165.762429) (xy 404.655059 -165.74384) (xy 404.728382 -165.731398) (xy 404.802492 -165.725192)
			(xy 404.839678 -165.72484) (xy 404.876862 -165.725213) (xy 404.95097 -165.731434) (xy 405.02429 -165.743875)
			(xy 405.096301 -165.762448) (xy 405.131524 -165.77437) (xy 405.139721 -165.776884) (xy 405.156855 -165.776884)
			(xy 405.165052 -165.77437) (xy 405.200146 -165.76246) (xy 405.271906 -165.743916) (xy 405.344971 -165.731476)
			(xy 405.418824 -165.725229) (xy 405.455882 -165.72484) (xy 405.456898 -165.72484) (xy 405.498822 -165.725407)
			(xy 405.582291 -165.733377) (xy 405.664623 -165.749245) (xy 405.745075 -165.772868) (xy 405.822917 -165.804031)
			(xy 405.897444 -165.842452) (xy 405.967982 -165.887784) (xy 406.033891 -165.939615) (xy 406.094575 -165.997477)
			(xy 406.149484 -166.060845) (xy 406.198121 -166.129146) (xy 406.240045 -166.20176) (xy 406.274876 -166.278031)
			(xy 406.302301 -166.357268) (xy 406.322068 -166.438752) (xy 406.334001 -166.521747) (xy 406.337991 -166.6055)
			(xy 406.334001 -166.689253) (xy 406.322068 -166.772248) (xy 406.302301 -166.853732) (xy 406.274876 -166.932969)
			(xy 406.240045 -167.00924) (xy 406.198121 -167.081854) (xy 406.149484 -167.150155) (xy 406.094575 -167.213523)
			(xy 406.033891 -167.271385) (xy 405.967982 -167.323216) (xy 405.897444 -167.368548) (xy 405.822917 -167.406969)
			(xy 405.745075 -167.438132) (xy 405.664623 -167.461755) (xy 405.582291 -167.477623) (xy 405.498822 -167.485593)
			(xy 405.456898 -167.486076) (xy 405.455882 -167.486076) (xy 405.418825 -167.485672) (xy 405.344976 -167.479407)
			(xy 405.271913 -167.466964) (xy 405.200153 -167.448432) (xy 405.165052 -167.436546) (xy 405.156855 -167.434032)
			(xy 405.139721 -167.434032) (xy 405.131524 -167.436546) (xy 405.102638 -167.446383) (xy 405.043785 -167.462529)
			(xy 405.013922 -167.468804) (xy 405.004334 -167.471159) (xy 404.987889 -167.482054) (xy 404.976796 -167.498367)
			(xy 404.974298 -167.50792) (xy 404.96417 -167.552275) (xy 404.936046 -167.638805) (xy 404.918164 -167.68064)
			(xy 404.914347 -167.690579) (xy 404.914353 -167.711846) (xy 404.918164 -167.721788) (xy 404.936394 -167.764388)
			(xy 404.964909 -167.852556) (xy 404.984099 -167.943213) (xy 404.993757 -168.035373) (xy 404.994364 -168.081706)
			(xy 404.994364 -168.082214) (xy 404.99386 -168.124562) (xy 404.985809 -168.208876) (xy 404.96978 -168.292042)
			(xy 404.945919 -168.373309) (xy 404.91444 -168.451939) (xy 404.875629 -168.52722) (xy 404.829839 -168.598472)
			(xy 404.777483 -168.665048) (xy 404.719035 -168.726346) (xy 404.655025 -168.781811) (xy 404.586033 -168.83094)
			(xy 404.512683 -168.873289) (xy 404.43564 -168.908473) (xy 404.355601 -168.936175) (xy 404.273292 -168.956143)
			(xy 404.189457 -168.968196) (xy 404.104856 -168.972227) (xy 404.020255 -168.968196) (xy 403.93642 -168.956143)
			(xy 403.854111 -168.936175) (xy 403.774072 -168.908473) (xy 403.697029 -168.873289) (xy 403.623679 -168.83094)
			(xy 403.554687 -168.781811) (xy 403.490677 -168.726346) (xy 403.432229 -168.665048) (xy 403.379873 -168.598472)
			(xy 403.334083 -168.52722) (xy 403.295272 -168.451939) (xy 403.263793 -168.373309) (xy 403.239932 -168.292042)
			(xy 403.223903 -168.208876) (xy 403.215852 -168.124562) (xy 403.215348 -168.082214) (xy 403.215348 -168.081706)
			(xy 403.215963 -168.035374) (xy 403.225632 -167.943217) (xy 403.244825 -167.852563) (xy 403.273334 -167.764394)
			(xy 403.291548 -167.721788) (xy 403.295348 -167.711844) (xy 403.295353 -167.690582) (xy 403.291548 -167.68064)
			(xy 403.273311 -167.637974) (xy 403.244764 -167.549684) (xy 403.225569 -167.458899) (xy 403.215934 -167.36661)
			(xy 403.215348 -167.320214) (xy 403.215953 -167.272404) (xy 403.226131 -167.177329) (xy 403.235668 -167.130476)
			(xy 403.23764 -167.118071) (xy 403.230727 -167.093957) (xy 403.22246 -167.084502) (xy 403.18182 -167.042338)
			(xy 403.178264 -167.0431) (xy 403.169416 -167.045411) (xy 403.154053 -167.055303) (xy 403.148292 -167.062404)
			(xy 403.123145 -167.095057) (xy 403.067744 -167.156083) (xy 403.006935 -167.211722) (xy 402.941239 -167.261497)
			(xy 402.871221 -167.304981) (xy 402.79748 -167.341801) (xy 402.720649 -167.371642) (xy 402.641387 -167.394246)
			(xy 402.560373 -167.409421) (xy 402.478303 -167.417036) (xy 402.437092 -167.417496) (xy 402.436838 -167.417496)
			(xy 402.395733 -167.416951) (xy 402.313873 -167.409371) (xy 402.233061 -167.394271) (xy 402.153987 -167.37178)
			(xy 402.077325 -167.342091) (xy 402.003729 -167.305456) (xy 401.933826 -167.262187) (xy 401.868213 -167.212655)
			(xy 401.80745 -167.157281) (xy 401.752053 -167.096538) (xy 401.702497 -167.030943) (xy 401.659203 -166.961056)
			(xy 401.622541 -166.887473) (xy 401.592824 -166.810822) (xy 401.570304 -166.731756) (xy 401.555174 -166.65095)
			(xy 401.547564 -166.569093) (xy 401.547076 -166.527988) (xy 354.289105 -166.527988) (xy 354.295389 -166.589961)
			(xy 354.295964 -166.634668) (xy 354.295964 -166.635684) (xy 354.29571 -166.647114) (xy 354.322189 -166.653059)
			(xy 354.374424 -166.667802) (xy 354.400104 -166.676578) (xy 354.408301 -166.679092) (xy 354.425435 -166.679092)
			(xy 354.433632 -166.676578) (xy 354.468848 -166.664633) (xy 354.540859 -166.646046) (xy 354.614181 -166.633606)
			(xy 354.688292 -166.6274) (xy 354.725478 -166.627048) (xy 354.762662 -166.62742) (xy 354.83677 -166.633641)
			(xy 354.91009 -166.646083) (xy 354.982101 -166.664656) (xy 355.017324 -166.676578) (xy 355.025521 -166.679092)
			(xy 355.042655 -166.679092) (xy 355.050852 -166.676578) (xy 355.085946 -166.664669) (xy 355.157706 -166.646124)
			(xy 355.230771 -166.633684) (xy 355.304624 -166.627437) (xy 355.341682 -166.627048) (xy 355.342698 -166.627048)
			(xy 355.384622 -166.627599) (xy 355.468092 -166.635569) (xy 355.550425 -166.651437) (xy 355.630878 -166.67506)
			(xy 355.70872 -166.706224) (xy 355.783248 -166.744645) (xy 355.853787 -166.789977) (xy 355.919696 -166.841809)
			(xy 355.980381 -166.899671) (xy 356.03529 -166.96304) (xy 356.083927 -167.031341) (xy 356.125852 -167.103957)
			(xy 356.160684 -167.180228) (xy 356.188108 -167.259465) (xy 356.207876 -167.340951) (xy 356.219809 -167.423946)
			(xy 356.223799 -167.5077) (xy 356.219809 -167.591454) (xy 356.207876 -167.674449) (xy 356.188108 -167.755935)
			(xy 356.160684 -167.835172) (xy 356.125852 -167.911443) (xy 356.083927 -167.984059) (xy 356.03529 -168.05236)
			(xy 355.980381 -168.115729) (xy 355.919696 -168.173591) (xy 355.853787 -168.225423) (xy 355.783248 -168.270755)
			(xy 355.70872 -168.309176) (xy 355.630878 -168.34034) (xy 355.550425 -168.363963) (xy 355.468092 -168.379831)
			(xy 355.384622 -168.387801) (xy 355.342698 -168.388284) (xy 355.341682 -168.388284) (xy 355.304625 -168.387885)
			(xy 355.230776 -168.381619) (xy 355.157713 -168.369175) (xy 355.085953 -168.350641) (xy 355.050852 -168.338754)
			(xy 355.042655 -168.33624) (xy 355.025521 -168.33624) (xy 355.017324 -168.338754) (xy 354.989546 -168.348208)
			(xy 354.932984 -168.363843) (xy 354.904294 -168.369996) (xy 354.894532 -168.372423) (xy 354.877923 -168.383747)
			(xy 354.866932 -168.400579) (xy 354.86467 -168.410382) (xy 354.855142 -168.457509) (xy 354.827269 -168.549532)
			(xy 354.809044 -168.594024) (xy 354.805459 -168.603609) (xy 354.805473 -168.624057) (xy 354.809044 -168.633648)
			(xy 354.826071 -168.675024) (xy 354.852688 -168.760451) (xy 354.870591 -168.84812) (xy 354.879599 -168.937143)
			(xy 354.880164 -168.981882) (xy 354.880164 -168.982136) (xy 354.87966 -169.024484) (xy 354.871609 -169.108798)
			(xy 354.85558 -169.191964) (xy 354.831719 -169.273231) (xy 354.80024 -169.351861) (xy 354.761429 -169.427142)
			(xy 354.715639 -169.498394) (xy 354.663283 -169.56497) (xy 354.604835 -169.626268) (xy 354.540825 -169.681733)
			(xy 354.471833 -169.730862) (xy 354.398483 -169.773211) (xy 354.32144 -169.808395) (xy 354.241401 -169.836097)
			(xy 354.159092 -169.856065) (xy 354.075257 -169.868118) (xy 353.990656 -169.872149) (xy 353.906055 -169.868118)
			(xy 353.82222 -169.856065) (xy 353.739911 -169.836097) (xy 353.659872 -169.808395) (xy 353.582829 -169.773211)
			(xy 353.509479 -169.730862) (xy 353.440487 -169.681733) (xy 353.376477 -169.626268) (xy 353.318029 -169.56497)
			(xy 353.265673 -169.498394) (xy 353.219883 -169.427142) (xy 353.181072 -169.351861) (xy 353.149593 -169.273231)
			(xy 353.125732 -169.191964) (xy 353.109703 -169.108798) (xy 353.101652 -169.024484) (xy 353.101148 -168.982136)
			(xy 353.101148 -168.981882) (xy 353.101731 -168.937144) (xy 353.110743 -168.848123) (xy 353.128644 -168.760456)
			(xy 353.155252 -168.675028) (xy 353.172268 -168.633648) (xy 353.175811 -168.624051) (xy 353.175824 -168.603615)
			(xy 353.172268 -168.594024) (xy 353.155227 -168.55262) (xy 353.128597 -168.46713) (xy 353.110694 -168.379396)
			(xy 353.1017 -168.290307) (xy 353.101148 -168.245536) (xy 353.101148 -168.24452) (xy 353.101526 -168.208908)
			(xy 353.107261 -168.137915) (xy 353.118654 -168.067607) (xy 353.126802 -168.032938) (xy 353.128529 -168.024629)
			(xy 353.126997 -168.007741) (xy 353.119979 -167.992303) (xy 353.114356 -167.985948) (xy 353.07397 -167.943276)
			(xy 353.064064 -167.945308) (xy 353.055164 -167.947623) (xy 353.039671 -167.957504) (xy 353.033838 -167.964612)
			(xy 353.008691 -167.997264) (xy 352.953283 -168.058281) (xy 352.892469 -168.113912) (xy 352.826771 -168.163681)
			(xy 352.756752 -168.207161) (xy 352.683013 -168.243979) (xy 352.606184 -168.273821) (xy 352.526925 -168.29643)
			(xy 352.445915 -168.311612) (xy 352.363848 -168.319237) (xy 352.322638 -168.319704) (xy 352.281533 -168.319151)
			(xy 352.199674 -168.311571) (xy 352.118862 -168.296471) (xy 352.039789 -168.273981) (xy 351.963127 -168.244292)
			(xy 351.889531 -168.207657) (xy 351.819629 -168.164389) (xy 351.754016 -168.114857) (xy 351.693252 -168.059484)
			(xy 351.637856 -167.998741) (xy 351.5883 -167.933147) (xy 351.545006 -167.863261) (xy 351.508343 -167.789678)
			(xy 351.478626 -167.713028) (xy 351.456106 -167.633963) (xy 351.440975 -167.553157) (xy 351.433364 -167.471301)
			(xy 351.432876 -167.430196) (xy 65.688295 -167.430196) (xy 65.649338 -167.484902) (xy 65.594424 -167.548276)
			(xy 65.533735 -167.606142) (xy 65.46782 -167.657978) (xy 65.397276 -167.703313) (xy 65.322742 -167.741737)
			(xy 65.244893 -167.772902) (xy 65.164434 -167.796526) (xy 65.082094 -167.812395) (xy 64.998618 -167.820365)
			(xy 64.95669 -167.820848) (xy 64.955674 -167.820848) (xy 64.918617 -167.820448) (xy 64.844768 -167.814181)
			(xy 64.771705 -167.801738) (xy 64.699945 -167.783204) (xy 64.664844 -167.771318) (xy 64.656647 -167.768804)
			(xy 64.639513 -167.768804) (xy 64.631316 -167.771318) (xy 64.597889 -167.782662) (xy 64.529607 -167.80059)
			(xy 64.494918 -167.807132) (xy 64.484907 -167.809437) (xy 64.467748 -167.820693) (xy 64.456372 -167.837772)
			(xy 64.454024 -167.847772) (xy 64.44452 -167.895628) (xy 64.416383 -167.989057) (xy 64.39789 -168.034208)
			(xy 64.394248 -168.043772) (xy 64.394124 -168.064219) (xy 64.397636 -168.073832) (xy 64.414658 -168.11521)
			(xy 64.441276 -168.200636) (xy 64.459181 -168.288304) (xy 64.46819 -168.377327) (xy 64.468756 -168.422066)
			(xy 64.468756 -168.42232) (xy 64.468252 -168.464668) (xy 64.460201 -168.548982) (xy 64.444172 -168.632148)
			(xy 64.420311 -168.713415) (xy 64.388832 -168.792045) (xy 64.350021 -168.867326) (xy 64.304231 -168.938578)
			(xy 64.251875 -169.005154) (xy 64.193427 -169.066452) (xy 64.129417 -169.121917) (xy 64.060425 -169.171046)
			(xy 63.987075 -169.213395) (xy 63.910032 -169.248579) (xy 63.829993 -169.276281) (xy 63.747684 -169.296249)
			(xy 63.663849 -169.308302) (xy 63.579248 -169.312333) (xy 63.494647 -169.308302) (xy 63.410812 -169.296249)
			(xy 63.328503 -169.276281) (xy 63.248464 -169.248579) (xy 63.171421 -169.213395) (xy 63.098071 -169.171046)
			(xy 63.029079 -169.121917) (xy 62.965069 -169.066452) (xy 62.906621 -169.005154) (xy 62.854265 -168.938578)
			(xy 62.808475 -168.867326) (xy 62.769664 -168.792045) (xy 62.738185 -168.713415) (xy 62.714324 -168.632148)
			(xy 62.698295 -168.548982) (xy 62.690244 -168.464668) (xy 62.68974 -168.42232) (xy 62.68974 -168.422066)
			(xy 62.690311 -168.377328) (xy 62.699325 -168.288306) (xy 62.71723 -168.200639) (xy 62.743842 -168.115211)
			(xy 62.76086 -168.073832) (xy 62.764412 -168.064238) (xy 62.76442 -168.043799) (xy 62.76086 -168.034208)
			(xy 62.743813 -167.992806) (xy 62.717185 -167.907315) (xy 62.699284 -167.81958) (xy 62.690292 -167.730491)
			(xy 62.68974 -167.68572) (xy 62.68974 -167.685466) (xy 62.689833 -167.667858) (xy 62.691229 -167.632668)
			(xy 62.692534 -167.615108) (xy 62.692907 -167.605036) (xy 62.68662 -167.585904) (xy 62.673425 -167.57069)
			(xy 62.664594 -167.565832) (xy 62.566296 -167.516556) (xy 62.535816 -167.520366) (xy 62.524132 -167.53078)
			(xy 62.493735 -167.556935) (xy 62.428993 -167.604263) (xy 62.360251 -167.645567) (xy 62.288069 -167.680512)
			(xy 62.213032 -167.708812) (xy 62.135751 -167.730238) (xy 62.056854 -167.744617) (xy 61.976982 -167.75183)
			(xy 61.936884 -167.752268) (xy 61.93663 -167.752268) (xy 61.895524 -167.751759) (xy 61.813662 -167.744177)
			(xy 61.732849 -167.729076) (xy 61.653773 -167.706584) (xy 61.57711 -167.676893) (xy 61.503513 -167.640256)
			(xy 61.433609 -167.596985) (xy 61.367995 -167.547451) (xy 61.307231 -167.492074) (xy 61.251835 -167.431328)
			(xy 61.202279 -167.36573) (xy 61.158986 -167.295841) (xy 61.122325 -167.222256) (xy 61.092608 -167.145602)
			(xy 61.07009 -167.066534) (xy 61.054963 -166.985725) (xy 61.047355 -166.903866) (xy 61.046868 -166.86276)
			(xy 2.509012 -166.86276) (xy 2.509012 -170.29303) (xy 8.7249 -170.29303) (xy 8.7249 -169.42943) (xy 8.725386 -169.402179)
			(xy 8.733142 -169.348231) (xy 8.748497 -169.295936) (xy 8.771139 -169.246359) (xy 8.800605 -169.200509)
			(xy 8.836296 -169.159318) (xy 8.877487 -169.123627) (xy 8.923337 -169.094161) (xy 8.972914 -169.071519)
			(xy 9.025209 -169.056164) (xy 9.079157 -169.048408) (xy 9.133659 -169.048408) (xy 9.187607 -169.056164)
			(xy 9.239902 -169.071519) (xy 9.289479 -169.094161) (xy 9.335329 -169.123627) (xy 9.37652 -169.159318)
			(xy 9.412211 -169.200509) (xy 9.441677 -169.246359) (xy 9.464319 -169.295936) (xy 9.479674 -169.348231)
			(xy 9.48743 -169.402179) (xy 9.487916 -169.42943) (xy 9.487916 -169.857674) (xy 111.084868 -169.857674)
			(xy 111.085438 -169.812905) (xy 111.094447 -169.72382) (xy 111.112349 -169.636089) (xy 111.138966 -169.550597)
			(xy 111.155988 -169.509186) (xy 111.15957 -169.4996) (xy 111.15956 -169.479153) (xy 111.155988 -169.469562)
			(xy 111.13894 -169.42816) (xy 111.112309 -169.34267) (xy 111.094408 -169.254935) (xy 111.085418 -169.165845)
			(xy 111.084868 -169.121074) (xy 111.085438 -169.076305) (xy 111.094447 -168.98722) (xy 111.112349 -168.899489)
			(xy 111.138966 -168.813997) (xy 111.155988 -168.772586) (xy 111.15957 -168.763) (xy 111.15956 -168.742553)
			(xy 111.155988 -168.732962) (xy 111.13894 -168.69156) (xy 111.112309 -168.60607) (xy 111.094408 -168.518335)
			(xy 111.085418 -168.429245) (xy 111.084868 -168.384474) (xy 111.085274 -168.343358) (xy 111.092864 -168.261476)
			(xy 111.107976 -168.180645) (xy 111.130482 -168.101552) (xy 111.160191 -168.024873) (xy 111.196847 -167.951263)
			(xy 111.240139 -167.881349) (xy 111.289697 -167.815728) (xy 111.345099 -167.754959) (xy 111.405871 -167.699561)
			(xy 111.471495 -167.650007) (xy 111.541412 -167.60672) (xy 111.615025 -167.570068) (xy 111.691705 -167.540365)
			(xy 111.770799 -167.517863) (xy 111.851632 -167.502756) (xy 111.933514 -167.495171) (xy 111.97463 -167.494712)
			(xy 112.016241 -167.495173) (xy 112.099098 -167.502953) (xy 112.180867 -167.518431) (xy 112.260835 -167.541474)
			(xy 112.338303 -167.571879) (xy 112.412595 -167.609382) (xy 112.448086 -167.63111) (xy 112.457229 -167.636263)
			(xy 112.477942 -167.63948) (xy 112.498214 -167.634152) (xy 112.50676 -167.628062) (xy 112.540389 -167.602071)
			(xy 112.611783 -167.555946) (xy 112.687254 -167.516845) (xy 112.766112 -167.485124) (xy 112.847637 -167.461075)
			(xy 112.931085 -167.444915) (xy 113.015695 -167.436793) (xy 113.058194 -167.436292) (xy 113.099307 -167.436819)
			(xy 113.181182 -167.444405) (xy 113.262007 -167.459513) (xy 113.341094 -167.482013) (xy 113.417768 -167.511715)
			(xy 113.491374 -167.548365) (xy 113.561284 -167.59165) (xy 113.626903 -167.6412) (xy 113.68767 -167.696593)
			(xy 113.743067 -167.757357) (xy 113.792621 -167.822973) (xy 113.83591 -167.892881) (xy 113.872564 -167.966485)
			(xy 113.90227 -168.043156) (xy 113.924776 -168.122242) (xy 113.939888 -168.203067) (xy 113.947479 -168.284941)
			(xy 113.947956 -168.326054) (xy 113.947393 -168.370824) (xy 113.938383 -168.459909) (xy 113.920477 -168.54764)
			(xy 113.893859 -168.633131) (xy 113.876836 -168.674542) (xy 113.873299 -168.684141) (xy 113.873282 -168.704576)
			(xy 113.876836 -168.714166) (xy 113.89384 -168.755517) (xy 113.920451 -168.840879) (xy 113.938358 -168.928482)
			(xy 113.94738 -169.017439) (xy 113.947956 -169.062146) (xy 113.947956 -169.063162) (xy 113.947702 -169.074592)
			(xy 113.974181 -169.080538) (xy 114.026416 -169.095281) (xy 114.052096 -169.104056) (xy 114.060293 -169.10657)
			(xy 114.077427 -169.10657) (xy 114.085624 -169.104056) (xy 114.12084 -169.092095) (xy 114.192844 -169.073441)
			(xy 114.266165 -169.060932) (xy 114.34028 -169.054659) (xy 114.37747 -169.054272) (xy 114.414659 -169.054671)
			(xy 114.488772 -169.060958) (xy 114.562092 -169.073465) (xy 114.634098 -169.092103) (xy 114.669316 -169.104056)
			(xy 114.677513 -169.10657) (xy 114.694647 -169.10657) (xy 114.702844 -169.104056) (xy 114.738059 -169.092089)
			(xy 114.810062 -169.073437) (xy 114.883384 -169.06093) (xy 114.9575 -169.054658) (xy 114.99469 -169.054272)
			(xy 115.03663 -169.054667) (xy 115.120132 -169.062639) (xy 115.202497 -169.078513) (xy 115.28298 -169.102144)
			(xy 115.360853 -169.133319) (xy 115.43541 -169.171755) (xy 115.505975 -169.217104) (xy 115.57191 -169.268955)
			(xy 115.632618 -169.326839) (xy 115.687549 -169.390232) (xy 115.736205 -169.458559) (xy 115.778146 -169.531202)
			(xy 115.812991 -169.607503) (xy 115.840426 -169.68677) (xy 115.860202 -169.768287) (xy 115.87214 -169.851314)
			(xy 115.876131 -169.9351) (xy 115.87214 -170.018886) (xy 115.860202 -170.101913) (xy 115.840426 -170.18343)
			(xy 115.812991 -170.262697) (xy 115.778146 -170.338998) (xy 115.736205 -170.411641) (xy 115.687549 -170.479968)
			(xy 115.632618 -170.543361) (xy 115.57191 -170.601245) (xy 115.505975 -170.653096) (xy 115.498571 -170.657854)
			(xy 161.052951 -170.657854) (xy 161.052951 -170.603346) (xy 161.060709 -170.549393) (xy 161.076066 -170.497093)
			(xy 161.09871 -170.447511) (xy 161.12818 -170.401657) (xy 161.163876 -170.360463) (xy 161.205071 -170.324769)
			(xy 161.250927 -170.295301) (xy 161.30051 -170.27266) (xy 161.352811 -170.257305) (xy 161.406764 -170.24955)
			(xy 161.434018 -170.249088) (xy 162.297618 -170.249088) (xy 162.324868 -170.249583) (xy 162.378813 -170.257342)
			(xy 162.431105 -170.272698) (xy 162.48068 -170.29534) (xy 162.526528 -170.324806) (xy 162.567715 -170.360498)
			(xy 162.603404 -170.401687) (xy 162.632869 -170.447536) (xy 162.655508 -170.497111) (xy 162.670862 -170.549404)
			(xy 162.678618 -170.60335) (xy 162.678618 -170.65785) (xy 162.670862 -170.711796) (xy 162.655508 -170.764089)
			(xy 162.632869 -170.813664) (xy 162.603404 -170.859513) (xy 162.567715 -170.900702) (xy 162.526528 -170.936394)
			(xy 162.48068 -170.96586) (xy 162.431105 -170.988502) (xy 162.378813 -171.003858) (xy 162.324868 -171.011617)
			(xy 162.297618 -171.012104) (xy 161.434018 -171.012104) (xy 161.406764 -171.01165) (xy 161.352811 -171.003895)
			(xy 161.30051 -170.98854) (xy 161.250927 -170.965899) (xy 161.205071 -170.936431) (xy 161.163876 -170.900737)
			(xy 161.12818 -170.859543) (xy 161.09871 -170.813689) (xy 161.076066 -170.764107) (xy 161.060709 -170.711807)
			(xy 161.052951 -170.657854) (xy 115.498571 -170.657854) (xy 115.43541 -170.698445) (xy 115.360853 -170.736881)
			(xy 115.28298 -170.768056) (xy 115.202497 -170.791687) (xy 115.120132 -170.807561) (xy 115.03663 -170.815533)
			(xy 114.99469 -170.816016) (xy 114.9575 -170.815629) (xy 114.883387 -170.809339) (xy 114.810068 -170.796828)
			(xy 114.738062 -170.778187) (xy 114.702844 -170.766232) (xy 114.694647 -170.763718) (xy 114.677513 -170.763718)
			(xy 114.669316 -170.766232) (xy 114.625188 -170.781068) (xy 114.534574 -170.80245) (xy 114.488468 -170.808904)
			(xy 114.478735 -170.810567) (xy 114.461516 -170.820188) (xy 114.449244 -170.83563) (xy 114.44605 -170.844972)
			(xy 114.43848 -170.870441) (xy 114.420685 -170.920512) (xy 114.41049 -170.945048) (xy 114.406882 -170.954622)
			(xy 114.406736 -170.97506) (xy 114.410236 -170.984672) (xy 114.427271 -171.026045) (xy 114.453886 -171.111473)
			(xy 114.471787 -171.199143) (xy 114.480792 -171.288167) (xy 114.481356 -171.332906) (xy 114.481356 -171.33316)
			(xy 114.480852 -171.375508) (xy 114.472801 -171.459822) (xy 114.456772 -171.542988) (xy 114.432911 -171.624255)
			(xy 114.401432 -171.702885) (xy 114.362621 -171.778166) (xy 114.316831 -171.849418) (xy 114.264475 -171.915994)
			(xy 114.206027 -171.977292) (xy 114.142017 -172.032757) (xy 114.073025 -172.081886) (xy 113.999675 -172.124235)
			(xy 113.922632 -172.159419) (xy 113.842593 -172.187121) (xy 113.760284 -172.207089) (xy 113.676449 -172.219142)
			(xy 113.591848 -172.223173) (xy 113.507247 -172.219142) (xy 113.423412 -172.207089) (xy 113.341103 -172.187121)
			(xy 113.261064 -172.159419) (xy 113.184021 -172.124235) (xy 113.110671 -172.081886) (xy 113.041679 -172.032757)
			(xy 112.977669 -171.977292) (xy 112.919221 -171.915994) (xy 112.866865 -171.849418) (xy 112.821075 -171.778166)
			(xy 112.782264 -171.702885) (xy 112.750785 -171.624255) (xy 112.726924 -171.542988) (xy 112.710895 -171.459822)
			(xy 112.702844 -171.375508) (xy 112.70234 -171.33316) (xy 112.70234 -171.332906) (xy 112.702891 -171.288167)
			(xy 112.711911 -171.199145) (xy 112.729821 -171.111478) (xy 112.75644 -171.026051) (xy 112.77346 -170.984672)
			(xy 112.777047 -170.975088) (xy 112.777032 -170.954639) (xy 112.77346 -170.945048) (xy 112.757652 -170.906707)
			(xy 112.732373 -170.827716) (xy 112.714548 -170.746717) (xy 112.70433 -170.664411) (xy 112.702594 -170.622976)
			(xy 112.702594 -170.622722) (xy 112.701955 -170.613271) (xy 112.694549 -170.595846) (xy 112.681333 -170.582289)
			(xy 112.672876 -170.578018) (xy 112.589818 -170.540172) (xy 112.581121 -170.536666) (xy 112.562416 -170.535564)
			(xy 112.544562 -170.541248) (xy 112.536986 -170.546776) (xy 112.536986 -170.54703) (xy 112.536478 -170.54703)
			(xy 112.502475 -170.574102) (xy 112.430107 -170.622247) (xy 112.353386 -170.663099) (xy 112.273043 -170.696267)
			(xy 112.189846 -170.721435) (xy 112.104591 -170.738363) (xy 112.01809 -170.746889) (xy 111.97463 -170.747436)
			(xy 111.933515 -170.746973) (xy 111.851635 -170.739388) (xy 111.770804 -170.72428) (xy 111.691713 -170.701779)
			(xy 111.615035 -170.672075) (xy 111.541425 -170.635423) (xy 111.471511 -170.592135) (xy 111.405889 -170.542581)
			(xy 111.34512 -170.487183) (xy 111.289722 -170.426414) (xy 111.240167 -170.360793) (xy 111.196879 -170.290879)
			(xy 111.160226 -170.217269) (xy 111.130522 -170.140591) (xy 111.10802 -170.061499) (xy 111.092912 -169.980669)
			(xy 111.085327 -169.898789) (xy 111.084868 -169.857674) (xy 9.487916 -169.857674) (xy 9.487916 -170.29303)
			(xy 9.48743 -170.320281) (xy 9.479674 -170.374229) (xy 9.464319 -170.426524) (xy 9.441677 -170.476101)
			(xy 9.412211 -170.521951) (xy 9.37652 -170.563142) (xy 9.335329 -170.598833) (xy 9.289479 -170.628299)
			(xy 9.239902 -170.650941) (xy 9.187607 -170.666296) (xy 9.133659 -170.674052) (xy 9.079157 -170.674052)
			(xy 9.025209 -170.666296) (xy 8.972914 -170.650941) (xy 8.923337 -170.628299) (xy 8.877487 -170.598833)
			(xy 8.836296 -170.563142) (xy 8.800605 -170.521951) (xy 8.771139 -170.476101) (xy 8.748497 -170.426524)
			(xy 8.733142 -170.374229) (xy 8.725386 -170.320281) (xy 8.7249 -170.29303) (xy 2.509012 -170.29303)
			(xy 2.509012 -173.07814) (xy 8.7249 -173.07814) (xy 8.7249 -172.21454) (xy 8.725386 -172.187289)
			(xy 8.733142 -172.133341) (xy 8.748497 -172.081046) (xy 8.771139 -172.031469) (xy 8.800605 -171.985619)
			(xy 8.836296 -171.944428) (xy 8.877487 -171.908737) (xy 8.923337 -171.879271) (xy 8.972914 -171.856629)
			(xy 9.025209 -171.841274) (xy 9.079157 -171.833518) (xy 9.133659 -171.833518) (xy 9.187607 -171.841274)
			(xy 9.239902 -171.856629) (xy 9.289479 -171.879271) (xy 9.335329 -171.908737) (xy 9.37652 -171.944428)
			(xy 9.412211 -171.985619) (xy 9.441677 -172.031469) (xy 9.464319 -172.081046) (xy 9.479674 -172.133341)
			(xy 9.48743 -172.187289) (xy 9.487916 -172.21454) (xy 9.487916 -173.07814) (xy 9.48743 -173.105391)
			(xy 9.479674 -173.159339) (xy 9.464319 -173.211634) (xy 9.441677 -173.261211) (xy 9.412211 -173.307061)
			(xy 9.37652 -173.348252) (xy 9.335329 -173.383943) (xy 9.289479 -173.413409) (xy 9.239902 -173.436051)
			(xy 9.187607 -173.451406) (xy 9.133659 -173.459162) (xy 9.079157 -173.459162) (xy 9.025209 -173.451406)
			(xy 8.972914 -173.436051) (xy 8.923337 -173.413409) (xy 8.877487 -173.383943) (xy 8.836296 -173.348252)
			(xy 8.800605 -173.307061) (xy 8.771139 -173.261211) (xy 8.748497 -173.211634) (xy 8.733142 -173.159339)
			(xy 8.725386 -173.105391) (xy 8.7249 -173.07814) (xy 2.509012 -173.07814) (xy 2.509012 -175.848264)
			(xy 8.7249 -175.848264) (xy 8.7249 -174.984664) (xy 8.725386 -174.957413) (xy 8.733142 -174.903465)
			(xy 8.748497 -174.85117) (xy 8.771139 -174.801593) (xy 8.800605 -174.755743) (xy 8.836296 -174.714552)
			(xy 8.877487 -174.678861) (xy 8.923337 -174.649395) (xy 8.972914 -174.626753) (xy 9.025209 -174.611398)
			(xy 9.079157 -174.603642) (xy 9.133659 -174.603642) (xy 9.187607 -174.611398) (xy 9.239902 -174.626753)
			(xy 9.289479 -174.649395) (xy 9.335329 -174.678861) (xy 9.37652 -174.714552) (xy 9.412211 -174.755743)
			(xy 9.441677 -174.801593) (xy 9.464319 -174.85117) (xy 9.479674 -174.903465) (xy 9.48743 -174.957413)
			(xy 9.487916 -174.984664) (xy 9.487916 -175.559974) (xy 69.360288 -175.559974) (xy 69.360857 -175.515205)
			(xy 69.369865 -175.42612) (xy 69.387768 -175.338388) (xy 69.414386 -175.252897) (xy 69.431408 -175.211486)
			(xy 69.434989 -175.2019) (xy 69.43498 -175.181453) (xy 69.431408 -175.171862) (xy 69.414355 -175.130462)
			(xy 69.387726 -175.044971) (xy 69.369827 -174.957236) (xy 69.360838 -174.868145) (xy 69.360288 -174.823374)
			(xy 69.360857 -174.778605) (xy 69.369865 -174.68952) (xy 69.387768 -174.601788) (xy 69.414386 -174.516297)
			(xy 69.431408 -174.474886) (xy 69.434989 -174.4653) (xy 69.43498 -174.444853) (xy 69.431408 -174.435262)
			(xy 69.414355 -174.393862) (xy 69.387726 -174.308371) (xy 69.369827 -174.220636) (xy 69.360838 -174.131545)
			(xy 69.360288 -174.086774) (xy 69.360674 -174.045657) (xy 69.368264 -173.963775) (xy 69.383377 -173.882942)
			(xy 69.405884 -173.803848) (xy 69.435593 -173.727169) (xy 69.47225 -173.653557) (xy 69.515543 -173.583643)
			(xy 69.565103 -173.518021) (xy 69.620506 -173.457252) (xy 69.681279 -173.401854) (xy 69.746905 -173.3523)
			(xy 69.816824 -173.309013) (xy 69.890438 -173.272362) (xy 69.96712 -173.24266) (xy 70.046216 -173.220159)
			(xy 70.12705 -173.205053) (xy 70.208933 -173.19747) (xy 70.25005 -173.197012) (xy 70.29166 -173.197513)
			(xy 70.374516 -173.205285) (xy 70.456284 -173.220756) (xy 70.536252 -173.243791) (xy 70.613721 -173.274189)
			(xy 70.688014 -173.311686) (xy 70.723506 -173.33341) (xy 70.73264 -173.338581) (xy 70.753359 -173.341792)
			(xy 70.773635 -173.336456) (xy 70.78218 -173.330362) (xy 70.815836 -173.304408) (xy 70.887226 -173.258279)
			(xy 70.962691 -173.219173) (xy 71.041544 -173.187448) (xy 71.123065 -173.163392) (xy 71.20651 -173.147226)
			(xy 71.291116 -173.139097) (xy 71.333614 -173.138592) (xy 71.374727 -173.139099) (xy 71.456602 -173.146687)
			(xy 71.537428 -173.161797) (xy 71.616516 -173.1843) (xy 71.693189 -173.214003) (xy 71.703445 -173.21911)
			(xy 393.739116 -173.21911) (xy 393.739743 -173.172708) (xy 393.749432 -173.08041) (xy 393.768686 -172.989625)
			(xy 393.797294 -172.90134) (xy 393.81557 -172.858684) (xy 393.819371 -172.84874) (xy 393.819374 -172.827478)
			(xy 393.81557 -172.817536) (xy 393.797307 -172.774875) (xy 393.768715 -172.686587) (xy 393.749458 -172.595804)
			(xy 393.739745 -172.503511) (xy 393.739116 -172.45711) (xy 393.739622 -172.415997) (xy 393.747208 -172.33412)
			(xy 393.762316 -172.253293) (xy 393.784818 -172.174205) (xy 393.81452 -172.097531) (xy 393.851171 -172.023924)
			(xy 393.894457 -171.954012) (xy 393.944008 -171.888393) (xy 393.999403 -171.827626) (xy 394.060168 -171.772229)
			(xy 394.125786 -171.722675) (xy 394.195696 -171.679387) (xy 394.269301 -171.642733) (xy 394.345975 -171.613028)
			(xy 394.425062 -171.590524) (xy 394.505889 -171.575413) (xy 394.587765 -171.567824) (xy 394.628878 -171.567348)
			(xy 394.670013 -171.567796) (xy 394.75193 -171.575416) (xy 394.832794 -171.590566) (xy 394.911913 -171.613115)
			(xy 394.988614 -171.642872) (xy 395.06224 -171.679583) (xy 395.132163 -171.722933) (xy 395.197785 -171.772553)
			(xy 395.258547 -171.828019) (xy 395.313929 -171.888856) (xy 395.339062 -171.921424) (xy 395.345281 -171.928954)
			(xy 395.36201 -171.939002) (xy 395.371574 -171.940982) (xy 395.41286 -171.948033) (xy 395.493962 -171.968978)
			(xy 395.572736 -171.997455) (xy 395.648484 -172.033212) (xy 395.720535 -172.075931) (xy 395.78825 -172.125234)
			(xy 395.851031 -172.180685) (xy 395.908321 -172.241793) (xy 395.959613 -172.308015) (xy 396.004452 -172.378766)
			(xy 396.042441 -172.453419) (xy 396.073244 -172.531313) (xy 396.096588 -172.611757) (xy 396.112266 -172.69404)
			(xy 396.120139 -172.777432) (xy 396.12062 -172.819314) (xy 396.120152 -172.860082) (xy 396.112652 -172.941273)
			(xy 396.097752 -173.021436) (xy 396.075577 -173.099899) (xy 396.046313 -173.176003) (xy 396.028672 -173.21276)
			(xy 396.024359 -173.222451) (xy 396.023438 -173.243625) (xy 396.026894 -173.253654) (xy 396.041217 -173.292003)
			(xy 396.063564 -173.370761) (xy 396.07857 -173.451241) (xy 396.086111 -173.53276) (xy 396.086584 -173.573694)
			(xy 396.086007 -173.618463) (xy 396.077001 -173.707548) (xy 396.0591 -173.795279) (xy 396.032485 -173.880771)
			(xy 396.015464 -173.922182) (xy 396.011903 -173.931774) (xy 396.0119 -173.952215) (xy 396.015464 -173.961806)
			(xy 396.032477 -174.003153) (xy 396.059087 -174.088517) (xy 396.076991 -174.17612) (xy 396.08601 -174.265079)
			(xy 396.086584 -174.309786) (xy 396.086584 -174.310802) (xy 396.08633 -174.322232) (xy 396.112809 -174.328178)
			(xy 396.165044 -174.342921) (xy 396.190724 -174.351696) (xy 396.198921 -174.35421) (xy 396.216055 -174.35421)
			(xy 396.224252 -174.351696) (xy 396.259466 -174.339729) (xy 396.33147 -174.321076) (xy 396.404792 -174.308569)
			(xy 396.478908 -174.302297) (xy 396.516098 -174.301912) (xy 396.553288 -174.302301) (xy 396.627401 -174.30859)
			(xy 396.70072 -174.3211) (xy 396.772726 -174.339741) (xy 396.807944 -174.351696) (xy 396.816141 -174.35421)
			(xy 396.833275 -174.35421) (xy 396.841472 -174.351696) (xy 396.876685 -174.339723) (xy 396.948689 -174.321072)
			(xy 397.022011 -174.308567) (xy 397.096127 -174.302297) (xy 397.133318 -174.301912) (xy 397.175254 -174.302444)
			(xy 397.258746 -174.310418) (xy 397.341102 -174.326292) (xy 397.421577 -174.349923) (xy 397.49944 -174.381096)
			(xy 397.573988 -174.41953) (xy 397.644545 -174.464875) (xy 397.710473 -174.516722) (xy 397.771173 -174.574601)
			(xy 397.826097 -174.637988) (xy 397.874747 -174.706309) (xy 397.916683 -174.778944) (xy 397.951524 -174.855237)
			(xy 397.978955 -174.934497) (xy 397.998729 -175.016005) (xy 398.010665 -175.099023) (xy 398.014656 -175.1828)
			(xy 398.010665 -175.266577) (xy 397.998729 -175.349595) (xy 397.978955 -175.431103) (xy 397.951524 -175.510363)
			(xy 397.916683 -175.586656) (xy 397.874747 -175.659291) (xy 397.826097 -175.727612) (xy 397.771173 -175.790999)
			(xy 397.710473 -175.848878) (xy 397.644545 -175.900725) (xy 397.573988 -175.94607) (xy 397.49944 -175.984504)
			(xy 397.421577 -176.015677) (xy 397.341102 -176.039308) (xy 397.258746 -176.055182) (xy 397.175254 -176.063156)
			(xy 397.133318 -176.063656) (xy 397.096129 -176.063259) (xy 397.022016 -176.056971) (xy 396.948696 -176.044464)
			(xy 396.87669 -176.025825) (xy 396.841472 -176.013872) (xy 396.833275 -176.011358) (xy 396.816141 -176.011358)
			(xy 396.807944 -176.013872) (xy 396.778999 -176.023726) (xy 396.720017 -176.039869) (xy 396.690088 -176.04613)
			(xy 396.680511 -176.048515) (xy 396.664071 -176.059402) (xy 396.652972 -176.0757) (xy 396.650464 -176.085246)
			(xy 396.640294 -176.12901) (xy 396.612299 -176.21439) (xy 396.594584 -176.25568) (xy 396.590807 -176.265631)
			(xy 396.590789 -176.286886) (xy 396.594584 -176.296828) (xy 396.612789 -176.339438) (xy 396.641312 -176.427603)
			(xy 396.660509 -176.518256) (xy 396.670174 -176.610414) (xy 396.670784 -176.656746) (xy 396.670784 -176.657254)
			(xy 396.67028 -176.699602) (xy 396.662229 -176.783916) (xy 396.6462 -176.867082) (xy 396.622339 -176.948349)
			(xy 396.59086 -177.026979) (xy 396.552049 -177.10226) (xy 396.506259 -177.173512) (xy 396.453903 -177.240088)
			(xy 396.395455 -177.301386) (xy 396.331445 -177.356851) (xy 396.262453 -177.40598) (xy 396.189103 -177.448329)
			(xy 396.11206 -177.483513) (xy 396.032021 -177.511215) (xy 395.949712 -177.531183) (xy 395.865877 -177.543236)
			(xy 395.781276 -177.547267) (xy 395.696675 -177.543236) (xy 395.61284 -177.531183) (xy 395.530531 -177.511215)
			(xy 395.450492 -177.483513) (xy 395.373449 -177.448329) (xy 395.300099 -177.40598) (xy 395.231107 -177.356851)
			(xy 395.167097 -177.301386) (xy 395.108649 -177.240088) (xy 395.056293 -177.173512) (xy 395.010503 -177.10226)
			(xy 394.971692 -177.026979) (xy 394.940213 -176.948349) (xy 394.916352 -176.867082) (xy 394.900323 -176.783916)
			(xy 394.892272 -176.699602) (xy 394.891768 -176.657254) (xy 394.891768 -176.656746) (xy 394.892395 -176.610415)
			(xy 394.902061 -176.518257) (xy 394.92125 -176.427603) (xy 394.949756 -176.339434) (xy 394.967968 -176.296828)
			(xy 394.971802 -176.286894) (xy 394.971784 -176.265622) (xy 394.967968 -176.25568) (xy 394.949707 -176.213025)
			(xy 394.921167 -176.12473) (xy 394.901979 -176.033943) (xy 394.89235 -175.941651) (xy 394.891768 -175.895254)
			(xy 394.89209 -175.858508) (xy 394.898067 -175.785262) (xy 394.903706 -175.74895) (xy 394.905149 -175.737024)
			(xy 394.898112 -175.714088) (xy 394.890244 -175.705008) (xy 394.824966 -175.637698) (xy 394.80236 -175.629824)
			(xy 394.790168 -175.631602) (xy 394.760779 -175.635286) (xy 394.701676 -175.63923) (xy 394.672058 -175.639476)
			(xy 394.630944 -175.639027) (xy 394.549066 -175.631436) (xy 394.468237 -175.616324) (xy 394.389148 -175.593818)
			(xy 394.312473 -175.564111) (xy 394.238865 -175.527456) (xy 394.168954 -175.484166) (xy 394.103335 -175.434611)
			(xy 394.042568 -175.379212) (xy 393.987171 -175.318444) (xy 393.937618 -175.252823) (xy 393.89433 -175.18291)
			(xy 393.857678 -175.109302) (xy 393.827973 -175.032625) (xy 393.80547 -174.953535) (xy 393.79036 -174.872707)
			(xy 393.782772 -174.790829) (xy 393.782296 -174.749714) (xy 393.782296 -174.749206) (xy 393.782815 -174.706532)
			(xy 393.791014 -174.621579) (xy 393.807309 -174.537801) (xy 393.83155 -174.455968) (xy 393.847066 -174.416212)
			(xy 393.850705 -174.406179) (xy 393.85003 -174.384863) (xy 393.845796 -174.375064) (xy 393.828734 -174.338786)
			(xy 393.800425 -174.263775) (xy 393.778984 -174.18652) (xy 393.764586 -174.107649) (xy 393.757348 -174.027801)
			(xy 393.756896 -173.987714) (xy 393.757452 -173.943459) (xy 393.766275 -173.855391) (xy 393.783795 -173.768633)
			(xy 393.809839 -173.684042) (xy 393.826492 -173.643036) (xy 393.830085 -173.632871) (xy 393.829579 -173.611348)
			(xy 393.825476 -173.60138) (xy 393.808875 -173.565511) (xy 393.781358 -173.491412) (xy 393.760529 -173.415162)
			(xy 393.746554 -173.337364) (xy 393.739543 -173.258632) (xy 393.739116 -173.21911) (xy 71.703445 -173.21911)
			(xy 71.766795 -173.250654) (xy 71.836706 -173.29394) (xy 71.902324 -173.343492) (xy 71.963091 -173.398886)
			(xy 72.018488 -173.459651) (xy 72.068042 -173.525268) (xy 72.11133 -173.595177) (xy 72.147984 -173.668781)
			(xy 72.17769 -173.745454) (xy 72.200196 -173.82454) (xy 72.215308 -173.905366) (xy 72.222899 -173.987241)
			(xy 72.223376 -174.028354) (xy 72.22282 -174.073124) (xy 72.213808 -174.162209) (xy 72.195901 -174.24994)
			(xy 72.16928 -174.335431) (xy 72.152256 -174.376842) (xy 72.148718 -174.38644) (xy 72.148701 -174.406876)
			(xy 72.152256 -174.416466) (xy 72.169272 -174.457846) (xy 72.195896 -174.543271) (xy 72.213802 -174.630939)
			(xy 72.222811 -174.719961) (xy 72.223376 -174.7647) (xy 72.223376 -174.765208) (xy 72.223122 -174.77867)
			(xy 72.249601 -174.784615) (xy 72.301836 -174.799358) (xy 72.327516 -174.808134) (xy 72.335713 -174.810648)
			(xy 72.352847 -174.810648) (xy 72.361044 -174.808134) (xy 72.39626 -174.796188) (xy 72.46827 -174.777601)
			(xy 72.541593 -174.765161) (xy 72.615704 -174.758956) (xy 72.65289 -174.758604) (xy 72.690074 -174.75897)
			(xy 72.764182 -174.765192) (xy 72.837502 -174.777635) (xy 72.909513 -174.796211) (xy 72.944736 -174.808134)
			(xy 72.952933 -174.810648) (xy 72.970067 -174.810648) (xy 72.978264 -174.808134) (xy 73.013366 -174.796247)
			(xy 73.085122 -174.777697) (xy 73.158185 -174.765251) (xy 73.232036 -174.758997) (xy 73.269094 -174.758604)
			(xy 73.27011 -174.758604) (xy 73.312036 -174.759059) (xy 73.395508 -174.767031) (xy 73.477845 -174.7829)
			(xy 73.5583 -174.806525) (xy 73.636145 -174.83769) (xy 73.710676 -174.876114) (xy 73.781216 -174.921448)
			(xy 73.847128 -174.973283) (xy 73.907814 -175.031148) (xy 73.962725 -175.094519) (xy 74.011364 -175.162823)
			(xy 74.053289 -175.235441) (xy 74.088123 -175.311716) (xy 74.115548 -175.390956) (xy 74.135316 -175.472444)
			(xy 74.14725 -175.555443) (xy 74.15124 -175.6392) (xy 74.14725 -175.722957) (xy 74.135316 -175.805956)
			(xy 74.115548 -175.887444) (xy 74.088123 -175.966684) (xy 74.053289 -176.042959) (xy 74.01685 -176.106074)
			(xy 102.855268 -176.106074) (xy 102.855838 -176.061305) (xy 102.864847 -175.97222) (xy 102.882749 -175.884489)
			(xy 102.909366 -175.798997) (xy 102.926388 -175.757586) (xy 102.92997 -175.748) (xy 102.92996 -175.727553)
			(xy 102.926388 -175.717962) (xy 102.90934 -175.67656) (xy 102.882709 -175.59107) (xy 102.864808 -175.503335)
			(xy 102.855818 -175.414245) (xy 102.855268 -175.369474) (xy 102.855838 -175.324705) (xy 102.864847 -175.23562)
			(xy 102.882749 -175.147889) (xy 102.909366 -175.062397) (xy 102.926388 -175.020986) (xy 102.92997 -175.0114)
			(xy 102.92996 -174.990953) (xy 102.926388 -174.981362) (xy 102.90934 -174.93996) (xy 102.882709 -174.85447)
			(xy 102.864808 -174.766735) (xy 102.855818 -174.677645) (xy 102.855268 -174.632874) (xy 102.855674 -174.591758)
			(xy 102.863264 -174.509876) (xy 102.878376 -174.429045) (xy 102.900882 -174.349952) (xy 102.930591 -174.273273)
			(xy 102.967247 -174.199663) (xy 103.010539 -174.129749) (xy 103.060097 -174.064128) (xy 103.115499 -174.003359)
			(xy 103.176271 -173.947961) (xy 103.241895 -173.898407) (xy 103.311812 -173.85512) (xy 103.385425 -173.818468)
			(xy 103.462105 -173.788765) (xy 103.541199 -173.766263) (xy 103.622032 -173.751156) (xy 103.703914 -173.743571)
			(xy 103.74503 -173.743112) (xy 103.786641 -173.743573) (xy 103.869498 -173.751353) (xy 103.951267 -173.766831)
			(xy 104.031235 -173.789874) (xy 104.108703 -173.820279) (xy 104.182995 -173.857782) (xy 104.218486 -173.87951)
			(xy 104.227629 -173.884663) (xy 104.248342 -173.88788) (xy 104.268614 -173.882552) (xy 104.27716 -173.876462)
			(xy 104.310789 -173.850471) (xy 104.382183 -173.804346) (xy 104.457654 -173.765245) (xy 104.536512 -173.733524)
			(xy 104.618037 -173.709475) (xy 104.701485 -173.693315) (xy 104.786095 -173.685193) (xy 104.828594 -173.684692)
			(xy 104.869707 -173.685219) (xy 104.951582 -173.692805) (xy 105.032407 -173.707913) (xy 105.111494 -173.730413)
			(xy 105.188168 -173.760115) (xy 105.261774 -173.796765) (xy 105.331684 -173.84005) (xy 105.397303 -173.8896)
			(xy 105.45807 -173.944993) (xy 105.513467 -174.005757) (xy 105.563021 -174.071373) (xy 105.60631 -174.141281)
			(xy 105.642964 -174.214885) (xy 105.67267 -174.291556) (xy 105.695176 -174.370642) (xy 105.710288 -174.451467)
			(xy 105.717879 -174.533341) (xy 105.718356 -174.574454) (xy 105.717793 -174.619224) (xy 105.708783 -174.708309)
			(xy 105.690877 -174.79604) (xy 105.664259 -174.881531) (xy 105.647236 -174.922942) (xy 105.643699 -174.932541)
			(xy 105.643682 -174.952976) (xy 105.647236 -174.962566) (xy 105.66424 -175.003917) (xy 105.690851 -175.089279)
			(xy 105.708758 -175.176882) (xy 105.71778 -175.265839) (xy 105.718356 -175.310546) (xy 105.718356 -175.311562)
			(xy 105.718102 -175.322992) (xy 105.744581 -175.328938) (xy 105.796816 -175.343681) (xy 105.822496 -175.352456)
			(xy 105.830693 -175.35497) (xy 105.847827 -175.35497) (xy 105.856024 -175.352456) (xy 105.89124 -175.340495)
			(xy 105.963244 -175.321841) (xy 106.036565 -175.309332) (xy 106.11068 -175.303059) (xy 106.14787 -175.302672)
			(xy 106.185059 -175.303071) (xy 106.259172 -175.309358) (xy 106.332492 -175.321865) (xy 106.404498 -175.340503)
			(xy 106.439716 -175.352456) (xy 106.447913 -175.35497) (xy 106.465047 -175.35497) (xy 106.473244 -175.352456)
			(xy 106.508459 -175.340489) (xy 106.580462 -175.321837) (xy 106.653784 -175.30933) (xy 106.7279 -175.303058)
			(xy 106.76509 -175.302672) (xy 106.80703 -175.303067) (xy 106.890532 -175.311039) (xy 106.972897 -175.326913)
			(xy 107.05338 -175.350544) (xy 107.131253 -175.381719) (xy 107.20581 -175.420155) (xy 107.276375 -175.465504)
			(xy 107.34231 -175.517355) (xy 107.403018 -175.575239) (xy 107.457949 -175.638632) (xy 107.505577 -175.705516)
			(xy 359.713276 -175.705516) (xy 359.713826 -175.660746) (xy 359.72284 -175.571661) (xy 359.740749 -175.48393)
			(xy 359.767371 -175.398439) (xy 359.784396 -175.357028) (xy 359.787954 -175.347435) (xy 359.78796 -175.326994)
			(xy 359.784396 -175.317404) (xy 359.767362 -175.275997) (xy 359.740727 -175.190508) (xy 359.722822 -175.102775)
			(xy 359.713828 -175.013687) (xy 359.713276 -174.968916) (xy 359.713826 -174.924146) (xy 359.72284 -174.835061)
			(xy 359.740749 -174.74733) (xy 359.767371 -174.661839) (xy 359.784396 -174.620428) (xy 359.787954 -174.610835)
			(xy 359.78796 -174.590394) (xy 359.784396 -174.580804) (xy 359.767362 -174.539397) (xy 359.740727 -174.453908)
			(xy 359.722822 -174.366175) (xy 359.713828 -174.277087) (xy 359.713276 -174.232316) (xy 359.713768 -174.191206)
			(xy 359.721354 -174.109337) (xy 359.736463 -174.028517) (xy 359.758966 -173.949437) (xy 359.788671 -173.872771)
			(xy 359.825324 -173.799173) (xy 359.868613 -173.729272) (xy 359.918168 -173.663664) (xy 359.973567 -173.602909)
			(xy 360.034335 -173.547526) (xy 360.099955 -173.497988) (xy 360.169867 -173.454716) (xy 360.243474 -173.418081)
			(xy 360.320148 -173.388396) (xy 360.399234 -173.365912) (xy 360.480057 -173.350823) (xy 360.561928 -173.343257)
			(xy 360.603038 -173.342808) (xy 360.644642 -173.343279) (xy 360.72749 -173.351011) (xy 360.809255 -173.366441)
			(xy 360.889223 -173.389435) (xy 360.966695 -173.419793) (xy 361.040997 -173.457248) (xy 361.076494 -173.478952)
			(xy 361.08563 -173.48412) (xy 361.106349 -173.487339) (xy 361.126625 -173.482001) (xy 361.135168 -173.475904)
			(xy 361.168794 -173.449952) (xy 361.240172 -173.403895) (xy 361.315615 -173.364851) (xy 361.394436 -173.333176)
			(xy 361.475917 -173.309157) (xy 361.559316 -173.293014) (xy 361.643874 -173.284894) (xy 361.686348 -173.284388)
			(xy 361.686602 -173.284388) (xy 361.72771 -173.284811) (xy 361.809576 -173.292396) (xy 361.890393 -173.307501)
			(xy 361.969472 -173.329998) (xy 362.046138 -173.359694) (xy 362.119738 -173.396336) (xy 362.189643 -173.439612)
			(xy 362.255258 -173.489152) (xy 362.316023 -173.544534) (xy 362.371419 -173.605287) (xy 362.420974 -173.67089)
			(xy 362.464266 -173.740786) (xy 362.500925 -173.814377) (xy 362.530638 -173.891036) (xy 362.553153 -173.97011)
			(xy 362.568276 -174.050924) (xy 362.57588 -174.132788) (xy 362.576364 -174.173896) (xy 362.575781 -174.218665)
			(xy 362.566776 -174.307749) (xy 362.548877 -174.395481) (xy 362.522264 -174.480972) (xy 362.505244 -174.522384)
			(xy 362.501683 -174.531976) (xy 362.501681 -174.552417) (xy 362.505244 -174.562008) (xy 362.522284 -174.603413)
			(xy 362.548917 -174.688902) (xy 362.56682 -174.776636) (xy 362.575812 -174.865725) (xy 362.576364 -174.910496)
			(xy 362.575094 -174.953676) (xy 362.575044 -174.965402) (xy 362.584373 -174.986895) (xy 362.602231 -175.002063)
			(xy 362.613448 -175.005492) (xy 362.632331 -175.010413) (xy 362.669682 -175.021721) (xy 362.688124 -175.028098)
			(xy 362.696321 -175.030612) (xy 362.713455 -175.030612) (xy 362.721652 -175.028098) (xy 362.756876 -175.016176)
			(xy 362.828883 -174.997583) (xy 362.902204 -174.985136) (xy 362.976313 -174.978924) (xy 363.013498 -174.978568)
			(xy 363.050682 -174.978934) (xy 363.12479 -174.985156) (xy 363.19811 -174.997599) (xy 363.270121 -175.016175)
			(xy 363.305344 -175.028098) (xy 363.313541 -175.030612) (xy 363.330675 -175.030612) (xy 363.338872 -175.028098)
			(xy 363.373974 -175.016212) (xy 363.44573 -174.997661) (xy 363.518793 -174.985214) (xy 363.592644 -174.978961)
			(xy 363.629702 -174.978568) (xy 363.630718 -174.978568) (xy 363.672642 -174.979095) (xy 363.75611 -174.987067)
			(xy 363.838443 -175.002937) (xy 363.918894 -175.026561) (xy 363.996736 -175.057726) (xy 364.071262 -175.096148)
			(xy 364.141799 -175.141481) (xy 364.207708 -175.193313) (xy 364.268391 -175.251175) (xy 364.323299 -175.314544)
			(xy 364.371935 -175.382845) (xy 364.413859 -175.45546) (xy 364.44869 -175.531731) (xy 364.476114 -175.610968)
			(xy 364.495881 -175.692452) (xy 364.507814 -175.775447) (xy 364.511804 -175.8592) (xy 364.507814 -175.942953)
			(xy 364.495881 -176.025948) (xy 364.476114 -176.107432) (xy 364.44869 -176.186669) (xy 364.413859 -176.26294)
			(xy 364.371935 -176.335555) (xy 364.323299 -176.403856) (xy 364.268391 -176.467225) (xy 364.207708 -176.525087)
			(xy 364.141799 -176.576919) (xy 364.071262 -176.622252) (xy 363.996736 -176.660674) (xy 363.918894 -176.691839)
			(xy 363.838443 -176.715463) (xy 363.75611 -176.731333) (xy 363.672642 -176.739305) (xy 363.630718 -176.739804)
			(xy 363.629702 -176.739804) (xy 363.592645 -176.739398) (xy 363.518796 -176.733134) (xy 363.445733 -176.720692)
			(xy 363.373973 -176.70216) (xy 363.338872 -176.690274) (xy 363.330675 -176.68776) (xy 363.313541 -176.68776)
			(xy 363.305344 -176.690274) (xy 363.271298 -176.701763) (xy 363.201741 -176.719817) (xy 363.166406 -176.726342)
			(xy 363.157048 -176.728326) (xy 363.140733 -176.738296) (xy 363.129218 -176.75356) (xy 363.126274 -176.762664)
			(xy 363.118487 -176.78918) (xy 363.100057 -176.841287) (xy 363.089444 -176.866804) (xy 363.085871 -176.876392)
			(xy 363.085877 -176.896837) (xy 363.089444 -176.906428) (xy 363.106465 -176.947806) (xy 363.133084 -177.033233)
			(xy 363.150988 -177.120901) (xy 363.159998 -177.209923) (xy 363.160564 -177.254662) (xy 363.160564 -177.254916)
			(xy 363.16006 -177.297264) (xy 363.152009 -177.381578) (xy 363.13598 -177.464744) (xy 363.112119 -177.546011)
			(xy 363.08064 -177.624641) (xy 363.041829 -177.699922) (xy 362.996039 -177.771174) (xy 362.943683 -177.83775)
			(xy 362.885235 -177.899048) (xy 362.821225 -177.954513) (xy 362.752233 -178.003642) (xy 362.678883 -178.045991)
			(xy 362.60184 -178.081175) (xy 362.521801 -178.108877) (xy 362.439492 -178.128845) (xy 362.355657 -178.140898)
			(xy 362.271056 -178.144929) (xy 362.186455 -178.140898) (xy 362.10262 -178.128845) (xy 362.020311 -178.108877)
			(xy 361.940272 -178.081175) (xy 361.863229 -178.045991) (xy 361.789879 -178.003642) (xy 361.720887 -177.954513)
			(xy 361.656877 -177.899048) (xy 361.598429 -177.83775) (xy 361.546073 -177.771174) (xy 361.500283 -177.699922)
			(xy 361.461472 -177.624641) (xy 361.429993 -177.546011) (xy 361.406132 -177.464744) (xy 361.390103 -177.381578)
			(xy 361.382052 -177.297264) (xy 361.381548 -177.254916) (xy 361.381548 -177.254662) (xy 361.382124 -177.209924)
			(xy 361.391138 -177.120903) (xy 361.409041 -177.033235) (xy 361.435651 -176.947807) (xy 361.452668 -176.906428)
			(xy 361.456222 -176.896834) (xy 361.456228 -176.876395) (xy 361.452668 -176.866804) (xy 361.435658 -176.825422)
			(xy 361.409036 -176.739997) (xy 361.391129 -176.65233) (xy 361.382115 -176.563308) (xy 361.381548 -176.51857)
			(xy 361.381548 -176.518316) (xy 361.38189 -176.482968) (xy 361.387504 -176.412495) (xy 361.39869 -176.34269)
			(xy 361.406694 -176.308258) (xy 361.409002 -176.295757) (xy 361.402463 -176.271224) (xy 361.394248 -176.261522)
			(xy 361.353608 -176.218596) (xy 361.34421 -176.220628) (xy 361.335443 -176.222892) (xy 361.32021 -176.232657)
			(xy 361.314492 -176.239678) (xy 361.289344 -176.272353) (xy 361.233931 -176.333418) (xy 361.173106 -176.389094)
			(xy 361.10739 -176.438902) (xy 361.037347 -176.482416) (xy 360.963578 -176.519263) (xy 360.886716 -176.549126)
			(xy 360.807421 -176.571748) (xy 360.726373 -176.586937) (xy 360.644268 -176.594561) (xy 360.603038 -176.595024)
			(xy 360.561931 -176.594551) (xy 360.480067 -176.58697) (xy 360.399251 -176.571868) (xy 360.320173 -176.549375)
			(xy 360.243508 -176.519683) (xy 360.169909 -176.483044) (xy 360.100004 -176.439772) (xy 360.034389 -176.390235)
			(xy 359.973624 -176.334856) (xy 359.918228 -176.274107) (xy 359.868672 -176.208506) (xy 359.825379 -176.138613)
			(xy 359.78872 -176.065025) (xy 359.759005 -175.988368) (xy 359.73649 -175.909296) (xy 359.721365 -175.828485)
			(xy 359.713761 -175.746623) (xy 359.713276 -175.705516) (xy 107.505577 -175.705516) (xy 107.506605 -175.706959)
			(xy 107.548546 -175.779602) (xy 107.583391 -175.855903) (xy 107.610826 -175.93517) (xy 107.630602 -176.016687)
			(xy 107.64254 -176.099714) (xy 107.646531 -176.1835) (xy 107.64254 -176.267286) (xy 107.630602 -176.350313)
			(xy 107.610826 -176.43183) (xy 107.583391 -176.511097) (xy 107.548546 -176.587398) (xy 107.506605 -176.660041)
			(xy 107.457949 -176.728368) (xy 107.403018 -176.791761) (xy 107.34231 -176.849645) (xy 107.276375 -176.901496)
			(xy 107.20581 -176.946845) (xy 107.131253 -176.985281) (xy 107.05338 -177.016456) (xy 106.972897 -177.040087)
			(xy 106.890532 -177.055961) (xy 106.80703 -177.063933) (xy 106.76509 -177.064416) (xy 106.7279 -177.064029)
			(xy 106.653787 -177.057739) (xy 106.580468 -177.045228) (xy 106.508462 -177.026587) (xy 106.473244 -177.014632)
			(xy 106.465047 -177.012118) (xy 106.447913 -177.012118) (xy 106.439716 -177.014632) (xy 106.394061 -177.029945)
			(xy 106.300252 -177.051713) (xy 106.252518 -177.058066) (xy 106.242041 -177.059824) (xy 106.223772 -177.070618)
			(xy 106.211473 -177.087908) (xy 106.20883 -177.098198) (xy 106.199325 -177.142161) (xy 106.1726 -177.22805)
			(xy 106.15549 -177.269648) (xy 106.151882 -177.279222) (xy 106.151736 -177.29966) (xy 106.155236 -177.309272)
			(xy 106.172271 -177.350645) (xy 106.198886 -177.436073) (xy 106.216787 -177.523743) (xy 106.225792 -177.612767)
			(xy 106.226356 -177.657506) (xy 106.226356 -177.65776) (xy 106.225852 -177.700108) (xy 106.217801 -177.784422)
			(xy 106.201772 -177.867588) (xy 106.177911 -177.948855) (xy 106.146432 -178.027485) (xy 106.107621 -178.102766)
			(xy 106.061831 -178.174018) (xy 106.009475 -178.240594) (xy 105.951027 -178.301892) (xy 105.887017 -178.357357)
			(xy 105.818025 -178.406486) (xy 105.744675 -178.448835) (xy 105.667632 -178.484019) (xy 105.587593 -178.511721)
			(xy 105.505284 -178.531689) (xy 105.421449 -178.543742) (xy 105.336848 -178.547773) (xy 105.252247 -178.543742)
			(xy 105.168412 -178.531689) (xy 105.086103 -178.511721) (xy 105.006064 -178.484019) (xy 104.929021 -178.448835)
			(xy 104.855671 -178.406486) (xy 104.786679 -178.357357) (xy 104.722669 -178.301892) (xy 104.664221 -178.240594)
			(xy 104.611865 -178.174018) (xy 104.566075 -178.102766) (xy 104.527264 -178.027485) (xy 104.495785 -177.948855)
			(xy 104.471924 -177.867588) (xy 104.455895 -177.784422) (xy 104.447844 -177.700108) (xy 104.44734 -177.65776)
			(xy 104.44734 -177.657506) (xy 104.447891 -177.612767) (xy 104.456911 -177.523745) (xy 104.474821 -177.436078)
			(xy 104.50144 -177.350651) (xy 104.51846 -177.309272) (xy 104.522047 -177.299688) (xy 104.522032 -177.279239)
			(xy 104.51846 -177.269648) (xy 104.501426 -177.228241) (xy 104.474794 -177.142752) (xy 104.456889 -177.055019)
			(xy 104.447894 -176.965931) (xy 104.44734 -176.92116) (xy 104.447594 -176.89703) (xy 104.44745 -176.887477)
			(xy 104.440882 -176.869548) (xy 104.428227 -176.855249) (xy 104.419908 -176.850548) (xy 104.33812 -176.808638)
			(xy 104.329507 -176.804642) (xy 104.310627 -176.802733) (xy 104.292347 -176.807824) (xy 104.284526 -176.81321)
			(xy 104.284526 -176.813464) (xy 104.284018 -176.813464) (xy 104.250823 -176.838169) (xy 104.180649 -176.882028)
			(xy 104.106709 -176.919187) (xy 104.029639 -176.949324) (xy 103.950105 -176.97218) (xy 103.868793 -176.987556)
			(xy 103.786406 -176.995321) (xy 103.74503 -176.995836) (xy 103.703915 -176.995373) (xy 103.622035 -176.987788)
			(xy 103.541204 -176.97268) (xy 103.462113 -176.950179) (xy 103.385435 -176.920475) (xy 103.311825 -176.883823)
			(xy 103.241911 -176.840535) (xy 103.176289 -176.790981) (xy 103.11552 -176.735583) (xy 103.060122 -176.674814)
			(xy 103.010567 -176.609193) (xy 102.967279 -176.539279) (xy 102.930626 -176.465669) (xy 102.900922 -176.388991)
			(xy 102.87842 -176.309899) (xy 102.863312 -176.229069) (xy 102.855727 -176.147189) (xy 102.855268 -176.106074)
			(xy 74.01685 -176.106074) (xy 74.011364 -176.115577) (xy 73.962725 -176.183881) (xy 73.907814 -176.247252)
			(xy 73.847128 -176.305117) (xy 73.781216 -176.356952) (xy 73.710676 -176.402286) (xy 73.636145 -176.44071)
			(xy 73.5583 -176.471875) (xy 73.477845 -176.4955) (xy 73.395508 -176.511369) (xy 73.312036 -176.519341)
			(xy 73.27011 -176.51984) (xy 73.269094 -176.51984) (xy 73.232037 -176.519434) (xy 73.158188 -176.51317)
			(xy 73.085125 -176.500728) (xy 73.013365 -176.482196) (xy 72.978264 -176.47031) (xy 72.970067 -176.467796)
			(xy 72.952933 -176.467796) (xy 72.944736 -176.47031) (xy 72.910756 -176.481853) (xy 72.841327 -176.500034)
			(xy 72.806052 -176.506632) (xy 72.796116 -176.508916) (xy 72.779041 -176.520017) (xy 72.767603 -176.536869)
			(xy 72.765158 -176.546764) (xy 72.755578 -176.591455) (xy 72.728473 -176.67875) (xy 72.711056 -176.721008)
			(xy 72.70748 -176.730595) (xy 72.707488 -176.751041) (xy 72.711056 -176.760632) (xy 72.728073 -176.802012)
			(xy 72.754694 -176.887437) (xy 72.7726 -176.975105) (xy 72.78161 -177.064127) (xy 72.782176 -177.108866)
			(xy 72.782176 -177.10912) (xy 72.781672 -177.151468) (xy 72.773621 -177.235782) (xy 72.757592 -177.318948)
			(xy 72.733731 -177.400215) (xy 72.702252 -177.478845) (xy 72.663441 -177.554126) (xy 72.617651 -177.625378)
			(xy 72.565295 -177.691954) (xy 72.506847 -177.753252) (xy 72.442837 -177.808717) (xy 72.373845 -177.857846)
			(xy 72.300495 -177.900195) (xy 72.223452 -177.935379) (xy 72.143413 -177.963081) (xy 72.061104 -177.983049)
			(xy 71.977269 -177.995102) (xy 71.892668 -177.999133) (xy 71.808067 -177.995102) (xy 71.724232 -177.983049)
			(xy 71.641923 -177.963081) (xy 71.561884 -177.935379) (xy 71.484841 -177.900195) (xy 71.411491 -177.857846)
			(xy 71.342499 -177.808717) (xy 71.278489 -177.753252) (xy 71.220041 -177.691954) (xy 71.167685 -177.625378)
			(xy 71.121895 -177.554126) (xy 71.083084 -177.478845) (xy 71.051605 -177.400215) (xy 71.027744 -177.318948)
			(xy 71.011715 -177.235782) (xy 71.003664 -177.151468) (xy 71.00316 -177.10912) (xy 71.00316 -177.108866)
			(xy 71.003737 -177.064128) (xy 71.01275 -176.975107) (xy 71.030653 -176.887439) (xy 71.057263 -176.802011)
			(xy 71.07428 -176.760632) (xy 71.077831 -176.751038) (xy 71.077839 -176.730599) (xy 71.07428 -176.721008)
			(xy 71.057235 -176.679605) (xy 71.030605 -176.594115) (xy 71.012704 -176.50638) (xy 71.003712 -176.417291)
			(xy 71.00316 -176.37252) (xy 71.00316 -176.371758) (xy 71.003227 -176.356824) (xy 71.004242 -176.326972)
			(xy 71.005192 -176.312068) (xy 71.005427 -176.302019) (xy 70.999034 -176.282984) (xy 70.985815 -176.267867)
			(xy 70.976998 -176.263046) (xy 70.8787 -176.214532) (xy 70.84822 -176.218596) (xy 70.83679 -176.228756)
			(xy 70.806403 -176.254854) (xy 70.741691 -176.302073) (xy 70.672994 -176.343279) (xy 70.60087 -176.378141)
			(xy 70.525902 -176.406374) (xy 70.4487 -176.427751) (xy 70.369887 -176.442098) (xy 70.290104 -176.449298)
			(xy 70.25005 -176.449736) (xy 70.208935 -176.449254) (xy 70.127056 -176.441671) (xy 70.046226 -176.426565)
			(xy 69.967134 -176.404065) (xy 69.890456 -176.374363) (xy 69.816846 -176.337712) (xy 69.746932 -176.294426)
			(xy 69.68131 -176.244873) (xy 69.620541 -176.189476) (xy 69.565143 -176.128708) (xy 69.515588 -176.063088)
			(xy 69.472299 -175.993175) (xy 69.435647 -175.919566) (xy 69.405943 -175.842889) (xy 69.383441 -175.763798)
			(xy 69.368332 -175.682968) (xy 69.360747 -175.601089) (xy 69.360288 -175.559974) (xy 9.487916 -175.559974)
			(xy 9.487916 -175.848264) (xy 9.48743 -175.875515) (xy 9.479674 -175.929463) (xy 9.464319 -175.981758)
			(xy 9.441677 -176.031335) (xy 9.412211 -176.077185) (xy 9.37652 -176.118376) (xy 9.335329 -176.154067)
			(xy 9.289479 -176.183533) (xy 9.239902 -176.206175) (xy 9.187607 -176.22153) (xy 9.133659 -176.229286)
			(xy 9.079157 -176.229286) (xy 9.025209 -176.22153) (xy 8.972914 -176.206175) (xy 8.923337 -176.183533)
			(xy 8.877487 -176.154067) (xy 8.836296 -176.118376) (xy 8.800605 -176.077185) (xy 8.771139 -176.031335)
			(xy 8.748497 -175.981758) (xy 8.733142 -175.929463) (xy 8.725386 -175.875515) (xy 8.7249 -175.848264)
			(xy 2.509012 -175.848264) (xy 2.509012 -178.618388) (xy 8.7249 -178.618388) (xy 8.7249 -177.754788)
			(xy 8.725386 -177.727537) (xy 8.733142 -177.673589) (xy 8.748497 -177.621294) (xy 8.771139 -177.571717)
			(xy 8.800605 -177.525867) (xy 8.836296 -177.484676) (xy 8.877487 -177.448985) (xy 8.923337 -177.419519)
			(xy 8.972914 -177.396877) (xy 9.025209 -177.381522) (xy 9.079157 -177.373766) (xy 9.133659 -177.373766)
			(xy 9.187607 -177.381522) (xy 9.239902 -177.396877) (xy 9.289479 -177.419519) (xy 9.335329 -177.448985)
			(xy 9.37652 -177.484676) (xy 9.412211 -177.525867) (xy 9.441677 -177.571717) (xy 9.464319 -177.621294)
			(xy 9.479674 -177.673589) (xy 9.48743 -177.727537) (xy 9.487916 -177.754788) (xy 9.487916 -178.618388)
			(xy 9.48743 -178.645639) (xy 9.479674 -178.699587) (xy 9.464319 -178.751882) (xy 9.44304 -178.798474)
			(xy 77.963268 -178.798474) (xy 77.963886 -178.752072) (xy 77.973579 -178.659774) (xy 77.992835 -178.568989)
			(xy 78.021445 -178.480704) (xy 78.039722 -178.438048) (xy 78.043541 -178.42811) (xy 78.043531 -178.406843)
			(xy 78.039722 -178.3969) (xy 78.021451 -178.354243) (xy 77.99286 -178.265953) (xy 77.973605 -178.175169)
			(xy 77.963896 -178.082875) (xy 77.963268 -178.036474) (xy 77.963674 -177.995358) (xy 77.971264 -177.913476)
			(xy 77.986376 -177.832645) (xy 78.008882 -177.753552) (xy 78.038591 -177.676873) (xy 78.075247 -177.603263)
			(xy 78.118539 -177.533349) (xy 78.168097 -177.467728) (xy 78.223499 -177.406959) (xy 78.284271 -177.351561)
			(xy 78.349895 -177.302007) (xy 78.419812 -177.25872) (xy 78.493425 -177.222068) (xy 78.570105 -177.192365)
			(xy 78.649199 -177.169863) (xy 78.730032 -177.154756) (xy 78.811914 -177.147171) (xy 78.85303 -177.146712)
			(xy 78.893848 -177.147168) (xy 78.975141 -177.154659) (xy 79.055405 -177.169568) (xy 79.133966 -177.191768)
			(xy 79.210162 -177.221072) (xy 79.283352 -177.257234) (xy 79.352922 -177.29995) (xy 79.418285 -177.348861)
			(xy 79.478892 -177.403555) (xy 79.534233 -177.463571) (xy 79.559404 -177.495708) (xy 79.565179 -177.502627)
			(xy 79.580393 -177.512264) (xy 79.589122 -177.514504) (xy 79.631283 -177.524073) (xy 79.713687 -177.550242)
			(xy 79.793163 -177.584282) (xy 79.868962 -177.625872) (xy 79.940368 -177.67462) (xy 80.006708 -177.730066)
			(xy 80.067355 -177.791686) (xy 80.121738 -177.8589) (xy 80.169343 -177.931073) (xy 80.209721 -178.007525)
			(xy 80.242492 -178.087533) (xy 80.267345 -178.170343) (xy 80.284047 -178.255173) (xy 80.29244 -178.341224)
			(xy 80.292956 -178.384454) (xy 80.292766 -178.411062) (xy 80.289588 -178.464184) (xy 80.286606 -178.490626)
			(xy 80.285833 -178.501873) (xy 80.292962 -178.523233) (xy 80.300322 -178.531774) (xy 80.329261 -178.562798)
			(xy 80.381784 -178.629432) (xy 80.427728 -178.700761) (xy 80.466676 -178.776139) (xy 80.498274 -178.854881)
			(xy 80.522235 -178.936272) (xy 80.538342 -179.019574) (xy 80.546449 -179.104032) (xy 80.546956 -179.146454)
			(xy 80.546393 -179.191224) (xy 80.537383 -179.280309) (xy 80.519477 -179.36804) (xy 80.492859 -179.453531)
			(xy 80.475836 -179.494942) (xy 80.472299 -179.504541) (xy 80.472282 -179.524976) (xy 80.475836 -179.534566)
			(xy 80.49284 -179.575917) (xy 80.519451 -179.661279) (xy 80.537358 -179.748882) (xy 80.54638 -179.837839)
			(xy 80.546956 -179.882546) (xy 80.546956 -179.883562) (xy 80.546702 -179.894992) (xy 80.573181 -179.900938)
			(xy 80.625416 -179.915681) (xy 80.651096 -179.924456) (xy 80.659293 -179.92697) (xy 80.676427 -179.92697)
			(xy 80.684624 -179.924456) (xy 80.71984 -179.912495) (xy 80.791844 -179.893841) (xy 80.865165 -179.881332)
			(xy 80.93928 -179.875059) (xy 80.97647 -179.874672) (xy 81.013659 -179.875071) (xy 81.087772 -179.881358)
			(xy 81.161092 -179.893865) (xy 81.233098 -179.912503) (xy 81.268316 -179.924456) (xy 81.276513 -179.92697)
			(xy 81.293647 -179.92697) (xy 81.301844 -179.924456) (xy 81.337059 -179.912489) (xy 81.409062 -179.893837)
			(xy 81.482384 -179.88133) (xy 81.5565 -179.875058) (xy 81.59369 -179.874672) (xy 81.63563 -179.875067)
			(xy 81.719132 -179.883039) (xy 81.801497 -179.898913) (xy 81.88198 -179.922544) (xy 81.959853 -179.953719)
			(xy 82.03441 -179.992155) (xy 82.104975 -180.037504) (xy 82.17091 -180.089355) (xy 82.231618 -180.147239)
			(xy 82.286549 -180.210632) (xy 82.335205 -180.278959) (xy 82.377146 -180.351602) (xy 82.411991 -180.427903)
			(xy 82.439426 -180.50717) (xy 82.459202 -180.588687) (xy 82.462267 -180.610002) (xy 86.081108 -180.610002)
			(xy 86.081685 -180.565233) (xy 86.090691 -180.476148) (xy 86.108592 -180.388417) (xy 86.135207 -180.302925)
			(xy 86.152228 -180.261514) (xy 86.155792 -180.251923) (xy 86.155793 -180.231481) (xy 86.152228 -180.22189)
			(xy 86.135186 -180.180486) (xy 86.108554 -180.094996) (xy 86.090651 -180.007262) (xy 86.081659 -179.918173)
			(xy 86.081108 -179.873402) (xy 86.081685 -179.828633) (xy 86.090691 -179.739548) (xy 86.108592 -179.651817)
			(xy 86.135207 -179.566325) (xy 86.152228 -179.524914) (xy 86.155792 -179.515323) (xy 86.155793 -179.494881)
			(xy 86.152228 -179.48529) (xy 86.135186 -179.443886) (xy 86.108554 -179.358396) (xy 86.090651 -179.270662)
			(xy 86.081659 -179.181573) (xy 86.081108 -179.136802) (xy 86.081615 -179.095689) (xy 86.089201 -179.013813)
			(xy 86.10431 -178.932986) (xy 86.126812 -178.853898) (xy 86.156515 -178.777224) (xy 86.193165 -178.703617)
			(xy 86.236451 -178.633706) (xy 86.286003 -178.568087) (xy 86.341397 -178.50732) (xy 86.402163 -178.451923)
			(xy 86.46778 -178.402369) (xy 86.537689 -178.359081) (xy 86.611295 -178.322428) (xy 86.687968 -178.292722)
			(xy 86.767055 -178.270217) (xy 86.847881 -178.255106) (xy 86.929757 -178.247516) (xy 86.97087 -178.24704)
			(xy 87.01248 -178.247527) (xy 87.095336 -178.255301) (xy 87.177105 -178.270774) (xy 87.257073 -178.293812)
			(xy 87.334542 -178.324213) (xy 87.408835 -178.361712) (xy 87.444326 -178.383438) (xy 87.453453 -178.388623)
			(xy 87.474176 -178.391826) (xy 87.494454 -178.386485) (xy 87.503 -178.38039) (xy 87.536641 -178.354416)
			(xy 87.608034 -178.30829) (xy 87.683503 -178.269188) (xy 87.762359 -178.237466) (xy 87.843882 -178.213414)
			(xy 87.927328 -178.19725) (xy 88.011936 -178.189124) (xy 88.054434 -178.18862) (xy 88.095548 -178.18908)
			(xy 88.177426 -178.19667) (xy 88.258254 -178.211782) (xy 88.337343 -178.234287) (xy 88.414018 -178.263994)
			(xy 88.487625 -178.300648) (xy 88.557536 -178.343937) (xy 88.623155 -178.393491) (xy 88.683922 -178.448889)
			(xy 88.739319 -178.509657) (xy 88.788872 -178.575277) (xy 88.83216 -178.645189) (xy 88.868813 -178.718797)
			(xy 88.898518 -178.795473) (xy 88.921021 -178.874562) (xy 88.936132 -178.95539) (xy 88.94372 -179.037268)
			(xy 88.944196 -179.078382) (xy 88.943648 -179.123152) (xy 88.934633 -179.212238) (xy 88.916724 -179.299969)
			(xy 88.890101 -179.38546) (xy 88.873076 -179.42687) (xy 88.869521 -179.436464) (xy 88.869514 -179.456904)
			(xy 88.873076 -179.466494) (xy 88.890086 -179.507843) (xy 88.916696 -179.593206) (xy 88.934602 -179.680809)
			(xy 88.943621 -179.769767) (xy 88.944196 -179.814474) (xy 88.944196 -179.81549) (xy 88.943942 -179.82692)
			(xy 88.970422 -179.832862) (xy 89.022656 -179.847607) (xy 89.048336 -179.856384) (xy 89.056533 -179.858898)
			(xy 89.073667 -179.858898) (xy 89.081864 -179.856384) (xy 89.117077 -179.844413) (xy 89.189082 -179.825761)
			(xy 89.262404 -179.813256) (xy 89.33652 -179.806985) (xy 89.37371 -179.8066) (xy 89.4109 -179.806986)
			(xy 89.485013 -179.813277) (xy 89.558333 -179.825787) (xy 89.630338 -179.844429) (xy 89.665556 -179.856384)
			(xy 89.673753 -179.858898) (xy 89.690887 -179.858898) (xy 89.699084 -179.856384) (xy 89.734295 -179.844408)
			(xy 89.8063 -179.825757) (xy 89.879623 -179.813253) (xy 89.953739 -179.806984) (xy 89.99093 -179.8066)
			(xy 90.032865 -179.807156) (xy 90.116355 -179.815131) (xy 90.198709 -179.831006) (xy 90.279182 -179.854637)
			(xy 90.357043 -179.885811) (xy 90.431589 -179.924244) (xy 90.502144 -179.969589) (xy 90.56807 -180.021436)
			(xy 90.628768 -180.079314) (xy 90.683691 -180.1427) (xy 90.732339 -180.211019) (xy 90.774274 -180.283653)
			(xy 90.809114 -180.359944) (xy 90.836544 -180.439202) (xy 90.856317 -180.520708) (xy 90.868253 -180.603725)
			(xy 90.869375 -180.627274) (xy 94.473268 -180.627274) (xy 94.473838 -180.582505) (xy 94.482847 -180.49342)
			(xy 94.500749 -180.405689) (xy 94.527366 -180.320197) (xy 94.544388 -180.278786) (xy 94.54797 -180.2692)
			(xy 94.54796 -180.248753) (xy 94.544388 -180.239162) (xy 94.52734 -180.19776) (xy 94.500709 -180.11227)
			(xy 94.482808 -180.024535) (xy 94.473818 -179.935445) (xy 94.473268 -179.890674) (xy 94.473838 -179.845905)
			(xy 94.482847 -179.75682) (xy 94.500749 -179.669089) (xy 94.527366 -179.583597) (xy 94.544388 -179.542186)
			(xy 94.54797 -179.5326) (xy 94.54796 -179.512153) (xy 94.544388 -179.502562) (xy 94.52734 -179.46116)
			(xy 94.500709 -179.37567) (xy 94.482808 -179.287935) (xy 94.473818 -179.198845) (xy 94.473268 -179.154074)
			(xy 94.473674 -179.112958) (xy 94.481264 -179.031076) (xy 94.496376 -178.950245) (xy 94.518882 -178.871152)
			(xy 94.548591 -178.794473) (xy 94.585247 -178.720863) (xy 94.628539 -178.650949) (xy 94.678097 -178.585328)
			(xy 94.733499 -178.524559) (xy 94.794271 -178.469161) (xy 94.859895 -178.419607) (xy 94.929812 -178.37632)
			(xy 95.003425 -178.339668) (xy 95.080105 -178.309965) (xy 95.159199 -178.287463) (xy 95.240032 -178.272356)
			(xy 95.321914 -178.264771) (xy 95.36303 -178.264312) (xy 95.404641 -178.264773) (xy 95.487498 -178.272553)
			(xy 95.569267 -178.288031) (xy 95.649235 -178.311074) (xy 95.726703 -178.341479) (xy 95.800995 -178.378982)
			(xy 95.836486 -178.40071) (xy 95.845629 -178.405863) (xy 95.866342 -178.40908) (xy 95.886614 -178.403752)
			(xy 95.89516 -178.397662) (xy 95.928789 -178.371671) (xy 96.000183 -178.325546) (xy 96.075654 -178.286445)
			(xy 96.154512 -178.254724) (xy 96.236037 -178.230675) (xy 96.319485 -178.214515) (xy 96.404095 -178.206393)
			(xy 96.446594 -178.205892) (xy 96.487707 -178.206419) (xy 96.569582 -178.214005) (xy 96.650407 -178.229113)
			(xy 96.729494 -178.251613) (xy 96.806168 -178.281315) (xy 96.879774 -178.317965) (xy 96.949684 -178.36125)
			(xy 97.015303 -178.4108) (xy 97.07607 -178.466193) (xy 97.131467 -178.526957) (xy 97.181021 -178.592573)
			(xy 97.22431 -178.662481) (xy 97.260964 -178.736085) (xy 97.29067 -178.812756) (xy 97.313176 -178.891842)
			(xy 97.328288 -178.972667) (xy 97.335879 -179.054541) (xy 97.336356 -179.095654) (xy 97.335793 -179.140424)
			(xy 97.329275 -179.204874) (xy 368.074448 -179.204874) (xy 368.075006 -179.161932) (xy 368.083288 -179.076448)
			(xy 368.099773 -178.99216) (xy 368.124306 -178.909855) (xy 368.15666 -178.830297) (xy 368.196533 -178.75423)
			(xy 368.243554 -178.682361) (xy 368.297284 -178.615359) (xy 368.357224 -178.55385) (xy 368.422813 -178.498405)
			(xy 368.493443 -178.449542) (xy 368.568454 -178.407716) (xy 368.607594 -178.390042) (xy 368.615999 -178.385919)
			(xy 368.629281 -178.372745) (xy 368.633502 -178.364388) (xy 368.645948 -178.33721) (xy 368.64947 -178.328554)
			(xy 368.650638 -178.309919) (xy 368.648234 -178.300888) (xy 368.635415 -178.257999) (xy 368.617464 -178.170297)
			(xy 368.608423 -178.081234) (xy 368.607848 -178.036474) (xy 368.608352 -177.994113) (xy 368.616405 -177.909776)
			(xy 368.632439 -177.826586) (xy 368.656307 -177.745296) (xy 368.687795 -177.666644) (xy 368.726617 -177.591341)
			(xy 368.77242 -177.520069) (xy 368.824791 -177.453473) (xy 368.883256 -177.392158) (xy 368.947284 -177.336677)
			(xy 369.016296 -177.287534) (xy 369.089666 -177.245174) (xy 369.166731 -177.209979) (xy 369.246793 -177.18227)
			(xy 369.329126 -177.162296) (xy 369.412985 -177.150239) (xy 369.49761 -177.146208) (xy 369.582235 -177.150239)
			(xy 369.666094 -177.162296) (xy 369.748427 -177.18227) (xy 369.828489 -177.209979) (xy 369.905554 -177.245174)
			(xy 369.978924 -177.287534) (xy 370.047936 -177.336677) (xy 370.111964 -177.392158) (xy 370.170429 -177.453473)
			(xy 370.2228 -177.520069) (xy 370.268603 -177.591341) (xy 370.307425 -177.666644) (xy 370.338913 -177.745296)
			(xy 370.362781 -177.826586) (xy 370.378815 -177.909776) (xy 370.386868 -177.994113) (xy 370.387372 -178.036474)
			(xy 370.387372 -178.036728) (xy 370.386948 -178.075094) (xy 370.380306 -178.151538) (xy 370.367099 -178.227125)
			(xy 370.357654 -178.264312) (xy 370.35562 -178.273261) (xy 370.357441 -178.291512) (xy 370.365595 -178.307941)
			(xy 370.37903 -178.320427) (xy 370.387372 -178.324256) (xy 370.427603 -178.341379) (xy 370.50477 -178.382506)
			(xy 370.577528 -178.431007) (xy 370.645175 -178.486413) (xy 370.707059 -178.548191) (xy 370.762582 -178.615743)
			(xy 370.811207 -178.688417) (xy 370.852467 -178.765513) (xy 370.885962 -178.846285) (xy 370.911369 -178.929954)
			(xy 370.928442 -179.015713) (xy 370.937018 -179.102733) (xy 370.937536 -179.146454) (xy 370.936975 -179.191224)
			(xy 370.927964 -179.280309) (xy 370.910058 -179.36804) (xy 370.883439 -179.453531) (xy 370.866416 -179.494942)
			(xy 370.86288 -179.504541) (xy 370.862862 -179.524975) (xy 370.866416 -179.534566) (xy 370.883441 -179.575977)
			(xy 370.910078 -179.661464) (xy 370.927986 -179.749196) (xy 370.936982 -179.838284) (xy 370.937536 -179.883054)
			(xy 370.937282 -179.903882) (xy 370.937631 -179.91519) (xy 370.946776 -179.935848) (xy 370.963889 -179.950596)
			(xy 370.97462 -179.954174) (xy 370.989618 -179.95835) (xy 371.019344 -179.967623) (xy 371.034056 -179.972716)
			(xy 371.042253 -179.97523) (xy 371.059387 -179.97523) (xy 371.067584 -179.972716) (xy 371.102796 -179.960741)
			(xy 371.174801 -179.94209) (xy 371.248123 -179.929585) (xy 371.322239 -179.923316) (xy 371.35943 -179.922932)
			(xy 371.396619 -179.923339) (xy 371.470732 -179.929623) (xy 371.544052 -179.942128) (xy 371.616058 -179.960764)
			(xy 371.651276 -179.972716) (xy 371.659473 -179.97523) (xy 371.676607 -179.97523) (xy 371.684804 -179.972716)
			(xy 371.720023 -179.960763) (xy 371.792025 -179.942106) (xy 371.865345 -179.929595) (xy 371.93946 -179.923319)
			(xy 371.97665 -179.922932) (xy 372.01859 -179.923405) (xy 372.10209 -179.931374) (xy 372.184455 -179.947244)
			(xy 372.264938 -179.970872) (xy 372.34281 -180.002043) (xy 372.417367 -180.040476) (xy 372.487932 -180.085822)
			(xy 372.553868 -180.137671) (xy 372.614576 -180.195553) (xy 372.669507 -180.258944) (xy 372.718163 -180.327269)
			(xy 372.760105 -180.39991) (xy 372.794951 -180.476209) (xy 372.822386 -180.555475) (xy 372.842162 -180.63699)
			(xy 372.848069 -180.678074) (xy 376.477276 -180.678074) (xy 376.477846 -180.633305) (xy 376.486854 -180.54422)
			(xy 376.504757 -180.456489) (xy 376.531374 -180.370997) (xy 376.548396 -180.329586) (xy 376.551978 -180.32)
			(xy 376.551968 -180.299553) (xy 376.548396 -180.289962) (xy 376.531349 -180.24856) (xy 376.504717 -180.16307)
			(xy 376.486816 -180.075335) (xy 376.477826 -179.986245) (xy 376.477276 -179.941474) (xy 376.477846 -179.896705)
			(xy 376.486854 -179.80762) (xy 376.504757 -179.719889) (xy 376.531374 -179.634397) (xy 376.548396 -179.592986)
			(xy 376.551978 -179.5834) (xy 376.551968 -179.562953) (xy 376.548396 -179.553362) (xy 376.531349 -179.51196)
			(xy 376.504717 -179.42647) (xy 376.486816 -179.338735) (xy 376.477826 -179.249645) (xy 376.477276 -179.204874)
			(xy 376.477674 -179.163758) (xy 376.485264 -179.081876) (xy 376.500376 -179.001043) (xy 376.522883 -178.92195)
			(xy 376.552591 -178.845272) (xy 376.589248 -178.771661) (xy 376.632541 -178.701747) (xy 376.682099 -178.636125)
			(xy 376.737501 -178.575356) (xy 376.798274 -178.519958) (xy 376.863899 -178.470404) (xy 376.933817 -178.427117)
			(xy 377.00743 -178.390466) (xy 377.084111 -178.360763) (xy 377.163206 -178.338262) (xy 377.244039 -178.323155)
			(xy 377.325922 -178.315571) (xy 377.367038 -178.315112) (xy 377.408648 -178.315619) (xy 377.491503 -178.323389)
			(xy 377.573272 -178.338859) (xy 377.65324 -178.361894) (xy 377.730709 -178.392291) (xy 377.805002 -178.429786)
			(xy 377.840494 -178.45151) (xy 377.849633 -178.45667) (xy 377.870349 -178.459885) (xy 377.890623 -178.454554)
			(xy 377.899168 -178.448462) (xy 377.932829 -178.422514) (xy 378.004217 -178.376384) (xy 378.079682 -178.337278)
			(xy 378.158534 -178.305551) (xy 378.240054 -178.281495) (xy 378.323498 -178.265328) (xy 378.408104 -178.257198)
			(xy 378.450602 -178.256692) (xy 378.491715 -178.257211) (xy 378.57359 -178.264798) (xy 378.654416 -178.279906)
			(xy 378.733503 -178.302408) (xy 378.810176 -178.33211) (xy 378.883782 -178.368761) (xy 378.953693 -178.412046)
			(xy 379.019312 -178.461597) (xy 379.080078 -178.51699) (xy 379.135475 -178.577755) (xy 379.185029 -178.643371)
			(xy 379.228318 -178.713279) (xy 379.264972 -178.786883) (xy 379.294678 -178.863555) (xy 379.317184 -178.942641)
			(xy 379.332296 -179.023466) (xy 379.339887 -179.105341) (xy 379.340364 -179.146454) (xy 379.339801 -179.191224)
			(xy 379.330791 -179.280309) (xy 379.312886 -179.36804) (xy 379.286267 -179.453531) (xy 379.269244 -179.494942)
			(xy 379.265706 -179.50454) (xy 379.265689 -179.524976) (xy 379.269244 -179.534566) (xy 379.286249 -179.575917)
			(xy 379.31286 -179.661279) (xy 379.330766 -179.748882) (xy 379.339788 -179.837839) (xy 379.340364 -179.882546)
			(xy 379.340364 -179.883562) (xy 379.34011 -179.894992) (xy 379.366589 -179.900938) (xy 379.418824 -179.915681)
			(xy 379.444504 -179.924456) (xy 379.452701 -179.92697) (xy 379.469835 -179.92697) (xy 379.478032 -179.924456)
			(xy 379.513248 -179.912493) (xy 379.585251 -179.893839) (xy 379.658572 -179.881331) (xy 379.732688 -179.875058)
			(xy 379.769878 -179.874672) (xy 379.807067 -179.875069) (xy 379.88118 -179.881356) (xy 379.9545 -179.893864)
			(xy 380.026506 -179.912502) (xy 380.061724 -179.924456) (xy 380.069921 -179.92697) (xy 380.087055 -179.92697)
			(xy 380.095252 -179.924456) (xy 380.130466 -179.912487) (xy 380.20247 -179.893835) (xy 380.275792 -179.881329)
			(xy 380.349908 -179.875057) (xy 380.387098 -179.874672) (xy 380.429038 -179.875067) (xy 380.512539 -179.88304)
			(xy 380.594904 -179.898915) (xy 380.675386 -179.922546) (xy 380.753258 -179.953722) (xy 380.827814 -179.992158)
			(xy 380.898379 -180.037507) (xy 380.964314 -180.089358) (xy 381.025021 -180.147242) (xy 381.079951 -180.210635)
			(xy 381.128607 -180.278962) (xy 381.170547 -180.351604) (xy 381.205392 -180.427905) (xy 381.232827 -180.507172)
			(xy 381.252602 -180.588688) (xy 381.26454 -180.671715) (xy 381.264843 -180.678074) (xy 384.808476 -180.678074)
			(xy 384.809046 -180.633305) (xy 384.818054 -180.54422) (xy 384.835957 -180.456489) (xy 384.862574 -180.370997)
			(xy 384.879596 -180.329586) (xy 384.883178 -180.32) (xy 384.883168 -180.299553) (xy 384.879596 -180.289962)
			(xy 384.862549 -180.24856) (xy 384.835917 -180.16307) (xy 384.818016 -180.075335) (xy 384.809026 -179.986245)
			(xy 384.808476 -179.941474) (xy 384.809046 -179.896705) (xy 384.818054 -179.80762) (xy 384.835957 -179.719889)
			(xy 384.862574 -179.634397) (xy 384.879596 -179.592986) (xy 384.883178 -179.5834) (xy 384.883168 -179.562953)
			(xy 384.879596 -179.553362) (xy 384.862549 -179.51196) (xy 384.835917 -179.42647) (xy 384.818016 -179.338735)
			(xy 384.809026 -179.249645) (xy 384.808476 -179.204874) (xy 384.808874 -179.163758) (xy 384.816464 -179.081876)
			(xy 384.831576 -179.001043) (xy 384.854083 -178.92195) (xy 384.883791 -178.845272) (xy 384.920448 -178.771661)
			(xy 384.963741 -178.701747) (xy 385.013299 -178.636125) (xy 385.068701 -178.575356) (xy 385.129474 -178.519958)
			(xy 385.195099 -178.470404) (xy 385.265017 -178.427117) (xy 385.33863 -178.390466) (xy 385.415311 -178.360763)
			(xy 385.494406 -178.338262) (xy 385.575239 -178.323155) (xy 385.657122 -178.315571) (xy 385.698238 -178.315112)
			(xy 385.739848 -178.315619) (xy 385.822703 -178.323389) (xy 385.904472 -178.338859) (xy 385.98444 -178.361894)
			(xy 386.061909 -178.392291) (xy 386.136202 -178.429786) (xy 386.171694 -178.45151) (xy 386.180833 -178.45667)
			(xy 386.201549 -178.459885) (xy 386.221823 -178.454554) (xy 386.230368 -178.448462) (xy 386.264029 -178.422514)
			(xy 386.335417 -178.376384) (xy 386.410882 -178.337278) (xy 386.489734 -178.305551) (xy 386.571254 -178.281495)
			(xy 386.654698 -178.265328) (xy 386.739304 -178.257198) (xy 386.781802 -178.256692) (xy 386.822915 -178.257211)
			(xy 386.90479 -178.264798) (xy 386.985616 -178.279906) (xy 387.064703 -178.302408) (xy 387.141376 -178.33211)
			(xy 387.214982 -178.368761) (xy 387.284893 -178.412046) (xy 387.350512 -178.461597) (xy 387.411278 -178.51699)
			(xy 387.466675 -178.577755) (xy 387.516229 -178.643371) (xy 387.559518 -178.713279) (xy 387.596172 -178.786883)
			(xy 387.625878 -178.863555) (xy 387.648384 -178.942641) (xy 387.663496 -179.023466) (xy 387.671087 -179.105341)
			(xy 387.671564 -179.146454) (xy 387.671001 -179.191224) (xy 387.661991 -179.280309) (xy 387.644086 -179.36804)
			(xy 387.617467 -179.453531) (xy 387.600444 -179.494942) (xy 387.596906 -179.50454) (xy 387.596889 -179.524976)
			(xy 387.600444 -179.534566) (xy 387.617449 -179.575917) (xy 387.64406 -179.661279) (xy 387.661966 -179.748882)
			(xy 387.670988 -179.837839) (xy 387.671564 -179.882546) (xy 387.671564 -179.883562) (xy 387.67131 -179.894992)
			(xy 387.697789 -179.900938) (xy 387.750024 -179.915681) (xy 387.775704 -179.924456) (xy 387.783901 -179.92697)
			(xy 387.801035 -179.92697) (xy 387.809232 -179.924456) (xy 387.844448 -179.912493) (xy 387.916451 -179.893839)
			(xy 387.989772 -179.881331) (xy 388.063888 -179.875058) (xy 388.101078 -179.874672) (xy 388.138267 -179.875069)
			(xy 388.21238 -179.881356) (xy 388.2857 -179.893864) (xy 388.357706 -179.912502) (xy 388.392924 -179.924456)
			(xy 388.401121 -179.92697) (xy 388.418255 -179.92697) (xy 388.426452 -179.924456) (xy 388.461666 -179.912487)
			(xy 388.53367 -179.893835) (xy 388.606992 -179.881329) (xy 388.681108 -179.875057) (xy 388.718298 -179.874672)
			(xy 388.760238 -179.875067) (xy 388.843739 -179.88304) (xy 388.926104 -179.898915) (xy 389.006586 -179.922546)
			(xy 389.084458 -179.953722) (xy 389.159014 -179.992158) (xy 389.229579 -180.037507) (xy 389.295514 -180.089358)
			(xy 389.356221 -180.147242) (xy 389.411151 -180.210635) (xy 389.459807 -180.278962) (xy 389.501747 -180.351604)
			(xy 389.536592 -180.427905) (xy 389.564027 -180.507172) (xy 389.583802 -180.588688) (xy 389.59574 -180.671715)
			(xy 389.599731 -180.7555) (xy 389.59574 -180.839285) (xy 389.583802 -180.922312) (xy 389.564027 -181.003828)
			(xy 389.536592 -181.083095) (xy 389.501747 -181.159396) (xy 389.459807 -181.232038) (xy 389.411151 -181.300365)
			(xy 389.356221 -181.363758) (xy 389.295514 -181.421642) (xy 389.229579 -181.473493) (xy 389.159014 -181.518842)
			(xy 389.084458 -181.557278) (xy 389.006586 -181.588454) (xy 388.926104 -181.612085) (xy 388.843739 -181.62796)
			(xy 388.760238 -181.635933) (xy 388.718298 -181.636416) (xy 388.681108 -181.636027) (xy 388.606996 -181.629737)
			(xy 388.533676 -181.617227) (xy 388.46167 -181.598587) (xy 388.426452 -181.586632) (xy 388.418255 -181.584118)
			(xy 388.401121 -181.584118) (xy 388.392924 -181.586632) (xy 388.365208 -181.596078) (xy 388.308773 -181.611711)
			(xy 388.280148 -181.617874) (xy 388.270401 -181.620348) (xy 388.25379 -181.63165) (xy 388.242792 -181.648464)
			(xy 388.240524 -181.65826) (xy 388.231054 -181.705587) (xy 388.203179 -181.797995) (xy 388.184898 -181.842664)
			(xy 388.181281 -181.852235) (xy 388.18114 -181.872676) (xy 388.184644 -181.882288) (xy 388.201684 -181.923659)
			(xy 388.228298 -182.009088) (xy 388.246197 -182.096758) (xy 388.255201 -182.185783) (xy 388.255764 -182.230522)
			(xy 388.255764 -182.230776) (xy 388.25526 -182.273124) (xy 388.247209 -182.357438) (xy 388.23118 -182.440604)
			(xy 388.207319 -182.521871) (xy 388.17584 -182.600501) (xy 388.137029 -182.675782) (xy 388.091239 -182.747034)
			(xy 388.038883 -182.81361) (xy 387.980435 -182.874908) (xy 387.916425 -182.930373) (xy 387.847433 -182.979502)
			(xy 387.774083 -183.021851) (xy 387.69704 -183.057035) (xy 387.617001 -183.084737) (xy 387.534692 -183.104705)
			(xy 387.450857 -183.116758) (xy 387.366256 -183.120789) (xy 387.281655 -183.116758) (xy 387.19782 -183.104705)
			(xy 387.115511 -183.084737) (xy 387.035472 -183.057035) (xy 386.958429 -183.021851) (xy 386.885079 -182.979502)
			(xy 386.816087 -182.930373) (xy 386.752077 -182.874908) (xy 386.693629 -182.81361) (xy 386.641273 -182.747034)
			(xy 386.595483 -182.675782) (xy 386.556672 -182.600501) (xy 386.525193 -182.521871) (xy 386.501332 -182.440604)
			(xy 386.485303 -182.357438) (xy 386.477252 -182.273124) (xy 386.476748 -182.230776) (xy 386.476748 -182.230522)
			(xy 386.477311 -182.185784) (xy 386.486329 -182.096762) (xy 386.504235 -182.009095) (xy 386.53085 -181.923667)
			(xy 386.547868 -181.882288) (xy 386.551445 -181.872701) (xy 386.551436 -181.852255) (xy 386.547868 -181.842664)
			(xy 386.53084 -181.801254) (xy 386.504206 -181.715766) (xy 386.4863 -181.628034) (xy 386.477302 -181.538946)
			(xy 386.476748 -181.494176) (xy 386.476748 -181.493668) (xy 386.47711 -181.457839) (xy 386.482902 -181.386415)
			(xy 386.49442 -181.315688) (xy 386.502656 -181.280816) (xy 386.504356 -181.272508) (xy 386.502799 -181.255633)
			(xy 386.495808 -181.240195) (xy 386.49021 -181.233826) (xy 386.44957 -181.1909) (xy 386.43941 -181.193186)
			(xy 386.430637 -181.195432) (xy 386.415405 -181.205208) (xy 386.409692 -181.212236) (xy 386.384552 -181.244927)
			(xy 386.329156 -181.306026) (xy 386.268343 -181.361734) (xy 386.202634 -181.411575) (xy 386.132593 -181.455119)
			(xy 386.058822 -181.491993) (xy 385.981955 -181.521881) (xy 385.902652 -181.544524) (xy 385.821593 -181.55973)
			(xy 385.739474 -181.567368) (xy 385.698238 -181.567836) (xy 385.657123 -181.567365) (xy 385.575243 -181.559781)
			(xy 385.494413 -181.544674) (xy 385.415321 -181.522173) (xy 385.338643 -181.49247) (xy 385.265033 -181.455819)
			(xy 385.195119 -181.412532) (xy 385.129497 -181.362978) (xy 385.068728 -181.30758) (xy 385.01333 -181.246812)
			(xy 384.963775 -181.181191) (xy 384.920487 -181.111277) (xy 384.883834 -181.037668) (xy 384.854131 -180.96099)
			(xy 384.831629 -180.881899) (xy 384.81652 -180.801068) (xy 384.808935 -180.719189) (xy 384.808476 -180.678074)
			(xy 381.264843 -180.678074) (xy 381.268531 -180.7555) (xy 381.26454 -180.839285) (xy 381.252602 -180.922312)
			(xy 381.232827 -181.003828) (xy 381.205392 -181.083095) (xy 381.170547 -181.159396) (xy 381.128607 -181.232038)
			(xy 381.079951 -181.300365) (xy 381.025021 -181.363758) (xy 380.964314 -181.421642) (xy 380.898379 -181.473493)
			(xy 380.827814 -181.518842) (xy 380.753258 -181.557278) (xy 380.675386 -181.588454) (xy 380.594904 -181.612085)
			(xy 380.512539 -181.62796) (xy 380.429038 -181.635933) (xy 380.387098 -181.636416) (xy 380.349908 -181.636027)
			(xy 380.275796 -181.629737) (xy 380.202476 -181.617227) (xy 380.13047 -181.598587) (xy 380.095252 -181.586632)
			(xy 380.087055 -181.584118) (xy 380.069921 -181.584118) (xy 380.061724 -181.586632) (xy 380.034008 -181.596078)
			(xy 379.977573 -181.611711) (xy 379.948948 -181.617874) (xy 379.939201 -181.620348) (xy 379.92259 -181.63165)
			(xy 379.911592 -181.648464) (xy 379.909324 -181.65826) (xy 379.899854 -181.705587) (xy 379.871979 -181.797995)
			(xy 379.853698 -181.842664) (xy 379.850081 -181.852235) (xy 379.84994 -181.872676) (xy 379.853444 -181.882288)
			(xy 379.870484 -181.923659) (xy 379.897098 -182.009088) (xy 379.914997 -182.096758) (xy 379.924001 -182.185783)
			(xy 379.924564 -182.230522) (xy 379.924564 -182.230776) (xy 379.92406 -182.273124) (xy 379.916009 -182.357438)
			(xy 379.89998 -182.440604) (xy 379.876119 -182.521871) (xy 379.84464 -182.600501) (xy 379.805829 -182.675782)
			(xy 379.760039 -182.747034) (xy 379.707683 -182.81361) (xy 379.649235 -182.874908) (xy 379.585225 -182.930373)
			(xy 379.516233 -182.979502) (xy 379.442883 -183.021851) (xy 379.36584 -183.057035) (xy 379.285801 -183.084737)
			(xy 379.203492 -183.104705) (xy 379.119657 -183.116758) (xy 379.035056 -183.120789) (xy 378.950455 -183.116758)
			(xy 378.86662 -183.104705) (xy 378.784311 -183.084737) (xy 378.704272 -183.057035) (xy 378.627229 -183.021851)
			(xy 378.553879 -182.979502) (xy 378.484887 -182.930373) (xy 378.420877 -182.874908) (xy 378.362429 -182.81361)
			(xy 378.310073 -182.747034) (xy 378.264283 -182.675782) (xy 378.225472 -182.600501) (xy 378.193993 -182.521871)
			(xy 378.170132 -182.440604) (xy 378.154103 -182.357438) (xy 378.146052 -182.273124) (xy 378.145548 -182.230776)
			(xy 378.145548 -182.230522) (xy 378.146111 -182.185784) (xy 378.155129 -182.096762) (xy 378.173035 -182.009095)
			(xy 378.19965 -181.923667) (xy 378.216668 -181.882288) (xy 378.220245 -181.872701) (xy 378.220236 -181.852255)
			(xy 378.216668 -181.842664) (xy 378.19964 -181.801254) (xy 378.173006 -181.715766) (xy 378.1551 -181.628034)
			(xy 378.146102 -181.538946) (xy 378.145548 -181.494176) (xy 378.145548 -181.493668) (xy 378.14591 -181.457839)
			(xy 378.151702 -181.386415) (xy 378.16322 -181.315688) (xy 378.171456 -181.280816) (xy 378.173156 -181.272508)
			(xy 378.171599 -181.255633) (xy 378.164608 -181.240195) (xy 378.15901 -181.233826) (xy 378.11837 -181.1909)
			(xy 378.10821 -181.193186) (xy 378.099437 -181.195432) (xy 378.084205 -181.205208) (xy 378.078492 -181.212236)
			(xy 378.053352 -181.244927) (xy 377.997956 -181.306026) (xy 377.937143 -181.361734) (xy 377.871434 -181.411575)
			(xy 377.801393 -181.455119) (xy 377.727622 -181.491993) (xy 377.650755 -181.521881) (xy 377.571452 -181.544524)
			(xy 377.490393 -181.55973) (xy 377.408274 -181.567368) (xy 377.367038 -181.567836) (xy 377.325923 -181.567365)
			(xy 377.244043 -181.559781) (xy 377.163213 -181.544674) (xy 377.084121 -181.522173) (xy 377.007443 -181.49247)
			(xy 376.933833 -181.455819) (xy 376.863919 -181.412532) (xy 376.798297 -181.362978) (xy 376.737528 -181.30758)
			(xy 376.68213 -181.246812) (xy 376.632575 -181.181191) (xy 376.589287 -181.111277) (xy 376.552634 -181.037668)
			(xy 376.522931 -180.96099) (xy 376.500429 -180.881899) (xy 376.48532 -180.801068) (xy 376.477735 -180.719189)
			(xy 376.477276 -180.678074) (xy 372.848069 -180.678074) (xy 372.8541 -180.720015) (xy 372.858091 -180.8038)
			(xy 372.8541 -180.887585) (xy 372.842162 -180.97061) (xy 372.822386 -181.052125) (xy 372.794951 -181.131391)
			(xy 372.760105 -181.20769) (xy 372.718163 -181.280331) (xy 372.669507 -181.348656) (xy 372.614576 -181.412047)
			(xy 372.553868 -181.469929) (xy 372.487932 -181.521778) (xy 372.417367 -181.567124) (xy 372.34281 -181.605557)
			(xy 372.264938 -181.636728) (xy 372.184455 -181.660356) (xy 372.10209 -181.676226) (xy 372.01859 -181.684195)
			(xy 371.97665 -181.684676) (xy 371.939461 -181.684274) (xy 371.865348 -181.677988) (xy 371.792028 -181.665482)
			(xy 371.720022 -181.646845) (xy 371.684804 -181.634892) (xy 371.676607 -181.632378) (xy 371.659473 -181.632378)
			(xy 371.651276 -181.634892) (xy 371.611916 -181.648156) (xy 371.531285 -181.66812) (xy 371.449135 -181.680416)
			(xy 371.40769 -181.683152) (xy 371.397889 -181.684131) (xy 371.380113 -181.692579) (xy 371.36683 -181.707102)
			(xy 371.362986 -181.716172) (xy 371.348 -181.753764) (xy 371.344428 -181.763418) (xy 371.344429 -181.783987)
			(xy 371.348 -181.793642) (xy 371.365038 -181.835014) (xy 371.391656 -181.920442) (xy 371.409557 -182.008112)
			(xy 371.418559 -182.097137) (xy 371.41912 -182.141876) (xy 371.418616 -182.184237) (xy 371.410563 -182.268574)
			(xy 371.394529 -182.351764) (xy 371.370661 -182.433054) (xy 371.339173 -182.511706) (xy 371.300351 -182.587009)
			(xy 371.254548 -182.658281) (xy 371.202177 -182.724877) (xy 371.143712 -182.786192) (xy 371.079684 -182.841673)
			(xy 371.010672 -182.890816) (xy 370.937302 -182.933176) (xy 370.860237 -182.968371) (xy 370.780175 -182.99608)
			(xy 370.697842 -183.016054) (xy 370.613983 -183.028111) (xy 370.529358 -183.032143) (xy 370.444733 -183.028111)
			(xy 370.360874 -183.016054) (xy 370.278541 -182.99608) (xy 370.198479 -182.968371) (xy 370.121414 -182.933176)
			(xy 370.048044 -182.890816) (xy 369.979032 -182.841673) (xy 369.915004 -182.786192) (xy 369.856539 -182.724877)
			(xy 369.804168 -182.658281) (xy 369.758365 -182.587009) (xy 369.719543 -182.511706) (xy 369.688055 -182.433054)
			(xy 369.664187 -182.351764) (xy 369.648153 -182.268574) (xy 369.6401 -182.184237) (xy 369.639596 -182.141876)
			(xy 369.640165 -182.097107) (xy 369.649173 -182.008022) (xy 369.667076 -181.92029) (xy 369.693694 -181.834799)
			(xy 369.710716 -181.793388) (xy 369.714296 -181.783802) (xy 369.714287 -181.763355) (xy 369.710716 -181.753764)
			(xy 369.693665 -181.712364) (xy 369.667035 -181.626872) (xy 369.649135 -181.539137) (xy 369.640146 -181.450047)
			(xy 369.639596 -181.405276) (xy 369.639771 -181.384669) (xy 369.641804 -181.343504) (xy 369.64366 -181.32298)
			(xy 369.644023 -181.312283) (xy 369.63707 -181.292069) (xy 369.630198 -181.283864) (xy 369.57127 -181.22011)
			(xy 369.551204 -181.211728) (xy 369.540282 -181.211982) (xy 369.523264 -181.212236) (xy 369.522756 -181.212236)
			(xy 369.481649 -181.211766) (xy 369.399787 -181.204159) (xy 369.318976 -181.189032) (xy 369.239905 -181.166515)
			(xy 369.163248 -181.136799) (xy 369.08966 -181.100138) (xy 369.019768 -181.056844) (xy 368.954168 -181.007287)
			(xy 368.893419 -180.95189) (xy 368.83804 -180.891125) (xy 368.788503 -180.825509) (xy 368.745231 -180.755604)
			(xy 368.708592 -180.682005) (xy 368.678899 -180.605339) (xy 368.656406 -180.526261) (xy 368.641304 -180.445446)
			(xy 368.633721 -180.363581) (xy 368.633248 -180.322474) (xy 368.6337 -180.283493) (xy 368.640575 -180.205835)
			(xy 368.654226 -180.129077) (xy 368.663982 -180.091334) (xy 368.666037 -180.082278) (xy 368.664208 -180.063813)
			(xy 368.655908 -180.047218) (xy 368.642231 -180.034679) (xy 368.633756 -180.030882) (xy 368.596114 -180.015301)
			(xy 368.523548 -179.97826) (xy 368.454673 -179.934739) (xy 368.390066 -179.885102) (xy 368.330268 -179.829767)
			(xy 368.27578 -179.769195) (xy 368.227059 -179.703896) (xy 368.184512 -179.634415) (xy 368.148496 -179.561335)
			(xy 368.119314 -179.485268) (xy 368.097208 -179.406851) (xy 368.082365 -179.326741) (xy 368.074909 -179.24561)
			(xy 368.074448 -179.204874) (xy 97.329275 -179.204874) (xy 97.326783 -179.229509) (xy 97.308877 -179.31724)
			(xy 97.282259 -179.402731) (xy 97.265236 -179.444142) (xy 97.261699 -179.453741) (xy 97.261682 -179.474176)
			(xy 97.265236 -179.483766) (xy 97.28224 -179.525117) (xy 97.308851 -179.610479) (xy 97.326758 -179.698082)
			(xy 97.33578 -179.787039) (xy 97.336356 -179.831746) (xy 97.336356 -179.832762) (xy 97.336102 -179.844192)
			(xy 97.362581 -179.850138) (xy 97.414816 -179.864881) (xy 97.440496 -179.873656) (xy 97.448693 -179.87617)
			(xy 97.465827 -179.87617) (xy 97.474024 -179.873656) (xy 97.50924 -179.861695) (xy 97.581244 -179.843041)
			(xy 97.654565 -179.830532) (xy 97.72868 -179.824259) (xy 97.76587 -179.823872) (xy 97.803059 -179.824271)
			(xy 97.877172 -179.830558) (xy 97.950492 -179.843065) (xy 98.022498 -179.861703) (xy 98.057716 -179.873656)
			(xy 98.065913 -179.87617) (xy 98.083047 -179.87617) (xy 98.091244 -179.873656) (xy 98.126459 -179.861689)
			(xy 98.198462 -179.843037) (xy 98.271784 -179.83053) (xy 98.3459 -179.824258) (xy 98.38309 -179.823872)
			(xy 98.42503 -179.824267) (xy 98.508532 -179.832239) (xy 98.590897 -179.848113) (xy 98.67138 -179.871744)
			(xy 98.749253 -179.902919) (xy 98.82381 -179.941355) (xy 98.894375 -179.986704) (xy 98.96031 -180.038555)
			(xy 99.021018 -180.096439) (xy 99.075949 -180.159832) (xy 99.124605 -180.228159) (xy 99.166546 -180.300802)
			(xy 99.201391 -180.377103) (xy 99.228826 -180.45637) (xy 99.248602 -180.537887) (xy 99.26054 -180.620914)
			(xy 99.264531 -180.7047) (xy 99.26054 -180.788486) (xy 99.248602 -180.871513) (xy 99.228826 -180.95303)
			(xy 99.201391 -181.032297) (xy 99.166546 -181.108598) (xy 99.124605 -181.181241) (xy 99.075949 -181.249568)
			(xy 99.021018 -181.312961) (xy 98.96031 -181.370845) (xy 98.894375 -181.422696) (xy 98.82381 -181.468045)
			(xy 98.749253 -181.506481) (xy 98.67138 -181.537656) (xy 98.590897 -181.561287) (xy 98.508532 -181.577161)
			(xy 98.42503 -181.585133) (xy 98.38309 -181.585616) (xy 98.3459 -181.585229) (xy 98.271787 -181.578939)
			(xy 98.198468 -181.566428) (xy 98.126462 -181.547787) (xy 98.091244 -181.535832) (xy 98.083047 -181.533318)
			(xy 98.065913 -181.533318) (xy 98.057716 -181.535832) (xy 98.015534 -181.549982) (xy 97.929009 -181.570726)
			(xy 97.884996 -181.577234) (xy 97.875031 -181.57898) (xy 97.85759 -181.589205) (xy 97.845466 -181.605383)
			(xy 97.842578 -181.61508) (xy 97.833805 -181.648299) (xy 97.811813 -181.713397) (xy 97.798636 -181.745128)
			(xy 97.79505 -181.754712) (xy 97.795064 -181.775161) (xy 97.798636 -181.784752) (xy 97.815664 -181.826127)
			(xy 97.842281 -181.911555) (xy 97.860184 -181.999224) (xy 97.869191 -182.088247) (xy 97.869756 -182.132986)
			(xy 97.869756 -182.13324) (xy 97.869252 -182.175588) (xy 97.861201 -182.259902) (xy 97.845172 -182.343068)
			(xy 97.821311 -182.424335) (xy 97.789832 -182.502965) (xy 97.751021 -182.578246) (xy 97.705231 -182.649498)
			(xy 97.652875 -182.716074) (xy 97.594427 -182.777372) (xy 97.530417 -182.832837) (xy 97.461425 -182.881966)
			(xy 97.388075 -182.924315) (xy 97.311032 -182.959499) (xy 97.230993 -182.987201) (xy 97.148684 -183.007169)
			(xy 97.064849 -183.019222) (xy 96.980248 -183.023253) (xy 96.895647 -183.019222) (xy 96.811812 -183.007169)
			(xy 96.729503 -182.987201) (xy 96.649464 -182.959499) (xy 96.572421 -182.924315) (xy 96.499071 -182.881966)
			(xy 96.430079 -182.832837) (xy 96.366069 -182.777372) (xy 96.307621 -182.716074) (xy 96.255265 -182.649498)
			(xy 96.209475 -182.578246) (xy 96.170664 -182.502965) (xy 96.139185 -182.424335) (xy 96.115324 -182.343068)
			(xy 96.099295 -182.259902) (xy 96.091244 -182.175588) (xy 96.09074 -182.13324) (xy 96.09074 -182.132986)
			(xy 96.091318 -182.088248) (xy 96.10033 -181.999226) (xy 96.118232 -181.911559) (xy 96.144843 -181.826131)
			(xy 96.16186 -181.784752) (xy 96.165401 -181.775154) (xy 96.165416 -181.754718) (xy 96.16186 -181.745128)
			(xy 96.144825 -181.703755) (xy 96.11821 -181.618327) (xy 96.100309 -181.530657) (xy 96.091304 -181.441633)
			(xy 96.09074 -181.396894) (xy 96.09074 -181.395878) (xy 96.090368 -181.38632) (xy 96.083332 -181.368547)
			(xy 96.070254 -181.354605) (xy 96.061784 -181.350158) (xy 95.965264 -181.304184) (xy 95.936308 -181.30774)
			(xy 95.924878 -181.317138) (xy 95.890853 -181.344159) (xy 95.818459 -181.392213) (xy 95.741724 -181.43298)
			(xy 95.66138 -181.466069) (xy 95.578192 -181.491168) (xy 95.492953 -181.508035) (xy 95.406476 -181.51651)
			(xy 95.36303 -181.517036) (xy 95.321915 -181.516573) (xy 95.240035 -181.508988) (xy 95.159204 -181.49388)
			(xy 95.080113 -181.471379) (xy 95.003435 -181.441675) (xy 94.929825 -181.405023) (xy 94.859911 -181.361735)
			(xy 94.794289 -181.312181) (xy 94.73352 -181.256783) (xy 94.678122 -181.196014) (xy 94.628567 -181.130393)
			(xy 94.585279 -181.060479) (xy 94.548626 -180.986869) (xy 94.518922 -180.910191) (xy 94.49642 -180.831099)
			(xy 94.481312 -180.750269) (xy 94.473727 -180.668389) (xy 94.473268 -180.627274) (xy 90.869375 -180.627274)
			(xy 90.872244 -180.6875) (xy 90.868253 -180.771275) (xy 90.856317 -180.854292) (xy 90.836544 -180.935798)
			(xy 90.809114 -181.015056) (xy 90.774274 -181.091347) (xy 90.732339 -181.163981) (xy 90.683691 -181.2323)
			(xy 90.628768 -181.295686) (xy 90.56807 -181.353564) (xy 90.502144 -181.405411) (xy 90.431589 -181.450756)
			(xy 90.357043 -181.489189) (xy 90.279182 -181.520363) (xy 90.198709 -181.543994) (xy 90.116355 -181.559869)
			(xy 90.032865 -181.567844) (xy 89.99093 -181.568344) (xy 89.953741 -181.567944) (xy 89.879628 -181.561657)
			(xy 89.806308 -181.54915) (xy 89.734302 -181.530513) (xy 89.699084 -181.51856) (xy 89.690887 -181.516046)
			(xy 89.673753 -181.516046) (xy 89.665556 -181.51856) (xy 89.630433 -181.5305) (xy 89.558617 -181.54912)
			(xy 89.485489 -181.561626) (xy 89.411567 -181.56793) (xy 89.374472 -181.568344) (xy 89.372948 -181.568344)
			(xy 89.365328 -181.56809) (xy 89.355809 -181.6135) (xy 89.328579 -181.702202) (xy 89.310972 -181.745128)
			(xy 89.307384 -181.754712) (xy 89.307399 -181.775161) (xy 89.310972 -181.784752) (xy 89.327996 -181.826163)
			(xy 89.354632 -181.91165) (xy 89.37254 -181.999382) (xy 89.381538 -182.08847) (xy 89.382092 -182.13324)
			(xy 89.381588 -182.175601) (xy 89.373535 -182.259938) (xy 89.357501 -182.343128) (xy 89.333633 -182.424418)
			(xy 89.302145 -182.50307) (xy 89.263323 -182.578373) (xy 89.21752 -182.649645) (xy 89.165149 -182.716241)
			(xy 89.106684 -182.777556) (xy 89.042656 -182.833037) (xy 88.973644 -182.88218) (xy 88.900274 -182.92454)
			(xy 88.823209 -182.959735) (xy 88.743147 -182.987444) (xy 88.660814 -183.007418) (xy 88.576955 -183.019475)
			(xy 88.49233 -183.023507) (xy 88.407705 -183.019475) (xy 88.323846 -183.007418) (xy 88.241513 -182.987444)
			(xy 88.161451 -182.959735) (xy 88.084386 -182.92454) (xy 88.011016 -182.88218) (xy 87.942004 -182.833037)
			(xy 87.877976 -182.777556) (xy 87.819511 -182.716241) (xy 87.76714 -182.649645) (xy 87.721337 -182.578373)
			(xy 87.682515 -182.50307) (xy 87.651027 -182.424418) (xy 87.627159 -182.343128) (xy 87.611125 -182.259938)
			(xy 87.603072 -182.175601) (xy 87.602568 -182.13324) (xy 87.603127 -182.08847) (xy 87.612138 -181.999385)
			(xy 87.630045 -181.911654) (xy 87.656665 -181.826163) (xy 87.673688 -181.784752) (xy 87.677232 -181.775155)
			(xy 87.677247 -181.754718) (xy 87.673688 -181.745128) (xy 87.65877 -181.708939) (xy 87.634581 -181.634489)
			(xy 87.617023 -181.558202) (xy 87.606232 -181.480668) (xy 87.603838 -181.441598) (xy 87.602983 -181.432757)
			(xy 87.596138 -181.416387) (xy 87.58411 -181.403342) (xy 87.576406 -181.398926) (xy 87.486236 -181.352444)
			(xy 87.459312 -181.35346) (xy 87.447882 -181.360826) (xy 87.412209 -181.38294) (xy 87.337447 -181.421096)
			(xy 87.259425 -181.452047) (xy 87.178837 -181.475518) (xy 87.096397 -181.4913) (xy 87.012838 -181.499253)
			(xy 86.97087 -181.499764) (xy 86.929755 -181.499316) (xy 86.847877 -181.491726) (xy 86.767048 -181.476614)
			(xy 86.687959 -181.454109) (xy 86.611283 -181.424402) (xy 86.537675 -181.387748) (xy 86.467763 -181.344458)
			(xy 86.402144 -181.294902) (xy 86.341376 -181.239504) (xy 86.28598 -181.178735) (xy 86.236426 -181.113114)
			(xy 86.193139 -181.043201) (xy 86.156487 -180.969592) (xy 86.126782 -180.892915) (xy 86.10428 -180.813824)
			(xy 86.08917 -180.732995) (xy 86.081583 -180.651117) (xy 86.081108 -180.610002) (xy 82.462267 -180.610002)
			(xy 82.47114 -180.671714) (xy 82.475131 -180.7555) (xy 82.47114 -180.839286) (xy 82.459202 -180.922313)
			(xy 82.439426 -181.00383) (xy 82.411991 -181.083097) (xy 82.377146 -181.159398) (xy 82.335205 -181.232041)
			(xy 82.286549 -181.300368) (xy 82.231618 -181.363761) (xy 82.17091 -181.421645) (xy 82.104975 -181.473496)
			(xy 82.03441 -181.518845) (xy 81.959853 -181.557281) (xy 81.88198 -181.588456) (xy 81.801497 -181.612087)
			(xy 81.719132 -181.627961) (xy 81.63563 -181.635933) (xy 81.59369 -181.636416) (xy 81.5565 -181.636029)
			(xy 81.482387 -181.629739) (xy 81.409068 -181.617228) (xy 81.337062 -181.598587) (xy 81.301844 -181.586632)
			(xy 81.293647 -181.584118) (xy 81.276513 -181.584118) (xy 81.268316 -181.586632) (xy 81.24011 -181.596266)
			(xy 81.182657 -181.612157) (xy 81.153508 -181.618382) (xy 81.143879 -181.620834) (xy 81.127394 -181.631892)
			(xy 81.116335 -181.648377) (xy 81.113884 -181.658006) (xy 81.104396 -181.702491) (xy 81.07755 -181.789404)
			(xy 81.06029 -181.831488) (xy 81.056659 -181.841055) (xy 81.056528 -181.861499) (xy 81.060036 -181.871112)
			(xy 81.077051 -181.912492) (xy 81.103672 -181.997918) (xy 81.121578 -182.085585) (xy 81.130589 -182.174608)
			(xy 81.131156 -182.219346) (xy 81.131156 -182.2196) (xy 81.130652 -182.261948) (xy 81.122601 -182.346262)
			(xy 81.106572 -182.429428) (xy 81.082711 -182.510695) (xy 81.051232 -182.589325) (xy 81.012421 -182.664606)
			(xy 80.966631 -182.735858) (xy 80.914275 -182.802434) (xy 80.855827 -182.863732) (xy 80.791817 -182.919197)
			(xy 80.722825 -182.968326) (xy 80.649475 -183.010675) (xy 80.572432 -183.045859) (xy 80.492393 -183.073561)
			(xy 80.410084 -183.093529) (xy 80.326249 -183.105582) (xy 80.241648 -183.109613) (xy 80.157047 -183.105582)
			(xy 80.073212 -183.093529) (xy 79.990903 -183.073561) (xy 79.910864 -183.045859) (xy 79.833821 -183.010675)
			(xy 79.760471 -182.968326) (xy 79.691479 -182.919197) (xy 79.627469 -182.863732) (xy 79.569021 -182.802434)
			(xy 79.516665 -182.735858) (xy 79.470875 -182.664606) (xy 79.432064 -182.589325) (xy 79.400585 -182.510695)
			(xy 79.376724 -182.429428) (xy 79.360695 -182.346262) (xy 79.352644 -182.261948) (xy 79.35214 -182.2196)
			(xy 79.35214 -182.219346) (xy 79.352704 -182.174608) (xy 79.361721 -182.085586) (xy 79.379627 -181.997918)
			(xy 79.406242 -181.912491) (xy 79.42326 -181.871112) (xy 79.426824 -181.861521) (xy 79.426824 -181.841079)
			(xy 79.42326 -181.831488) (xy 79.406239 -181.790076) (xy 79.379604 -181.704589) (xy 79.361695 -181.616857)
			(xy 79.352696 -181.52777) (xy 79.35214 -181.483) (xy 79.35214 -181.482746) (xy 79.352599 -181.44258)
			(xy 79.359845 -181.362574) (xy 79.366618 -181.32298) (xy 79.366618 -181.322726) (xy 79.368105 -181.310829)
			(xy 79.361202 -181.287898) (xy 79.35341 -181.278784) (xy 79.287878 -181.210204) (xy 79.265018 -181.202076)
			(xy 79.252826 -181.203854) (xy 79.222877 -181.207733) (xy 79.162627 -181.21193) (xy 79.13243 -181.212236)
			(xy 79.091315 -181.211773) (xy 79.009435 -181.204188) (xy 78.928604 -181.18908) (xy 78.849513 -181.166579)
			(xy 78.772835 -181.136875) (xy 78.699225 -181.100223) (xy 78.629311 -181.056935) (xy 78.563689 -181.007381)
			(xy 78.50292 -180.951983) (xy 78.447522 -180.891214) (xy 78.397967 -180.825593) (xy 78.354679 -180.755679)
			(xy 78.318026 -180.682069) (xy 78.288322 -180.605391) (xy 78.26582 -180.526299) (xy 78.250712 -180.445469)
			(xy 78.243127 -180.363589) (xy 78.242668 -180.322474) (xy 78.242668 -180.321966) (xy 78.243175 -180.279292)
			(xy 78.251378 -180.194339) (xy 78.267677 -180.110561) (xy 78.291921 -180.028728) (xy 78.307438 -179.988972)
			(xy 78.311043 -179.978929) (xy 78.310391 -179.957622) (xy 78.306168 -179.947824) (xy 78.289089 -179.911553)
			(xy 78.260784 -179.836541) (xy 78.239347 -179.759284) (xy 78.224953 -179.680411) (xy 78.217719 -179.600562)
			(xy 78.217268 -179.560474) (xy 78.21746 -179.533866) (xy 78.220637 -179.480744) (xy 78.223618 -179.454302)
			(xy 78.224368 -179.443055) (xy 78.217254 -179.421697) (xy 78.209902 -179.413154) (xy 78.180933 -179.382157)
			(xy 78.128411 -179.31552) (xy 78.082469 -179.244186) (xy 78.043525 -179.168805) (xy 78.011931 -179.090059)
			(xy 77.987974 -179.008663) (xy 77.971872 -178.925358) (xy 77.963772 -178.840898) (xy 77.963268 -178.798474)
			(xy 9.44304 -178.798474) (xy 9.441677 -178.801459) (xy 9.412211 -178.847309) (xy 9.37652 -178.8885)
			(xy 9.335329 -178.924191) (xy 9.289479 -178.953657) (xy 9.239902 -178.976299) (xy 9.187607 -178.991654)
			(xy 9.133659 -178.99941) (xy 9.079157 -178.99941) (xy 9.025209 -178.991654) (xy 8.972914 -178.976299)
			(xy 8.923337 -178.953657) (xy 8.877487 -178.924191) (xy 8.836296 -178.8885) (xy 8.800605 -178.847309)
			(xy 8.771139 -178.801459) (xy 8.748497 -178.751882) (xy 8.733142 -178.699587) (xy 8.725386 -178.645639)
			(xy 8.7249 -178.618388) (xy 2.509012 -178.618388) (xy 2.509012 -190.64715) (xy 220.414866 -190.64715)
			(xy 220.414866 -190.59265) (xy 220.422621 -190.538705) (xy 220.437974 -190.486413) (xy 220.460612 -190.436837)
			(xy 220.490075 -190.390988) (xy 220.525762 -190.349798) (xy 220.566948 -190.314105) (xy 220.612793 -190.284636)
			(xy 220.662366 -190.261992) (xy 220.714656 -190.246632) (xy 220.7686 -190.238869) (xy 220.79585 -190.23838)
			(xy 221.78645 -190.23838) (xy 221.813704 -190.238864) (xy 221.867659 -190.246615) (xy 221.919961 -190.261966)
			(xy 221.969546 -190.284605) (xy 222.015404 -190.314071) (xy 222.056601 -190.349763) (xy 222.092299 -190.390956)
			(xy 222.121771 -190.43681) (xy 222.144416 -190.486392) (xy 222.159775 -190.538692) (xy 222.167533 -190.592646)
			(xy 222.167533 -190.647154) (xy 222.159775 -190.701108) (xy 222.144416 -190.753408) (xy 222.121771 -190.80299)
			(xy 222.092299 -190.848844) (xy 222.056601 -190.890037) (xy 222.015404 -190.925729) (xy 221.969546 -190.955195)
			(xy 221.919961 -190.977834) (xy 221.867659 -190.993185) (xy 221.813704 -191.000936) (xy 221.78645 -191.001396)
			(xy 220.79585 -191.001396) (xy 220.7686 -191.000931) (xy 220.714656 -190.993168) (xy 220.662366 -190.977808)
			(xy 220.612793 -190.955164) (xy 220.566948 -190.925695) (xy 220.525762 -190.890002) (xy 220.490075 -190.848812)
			(xy 220.460612 -190.802963) (xy 220.437974 -190.753387) (xy 220.422621 -190.701095) (xy 220.414866 -190.64715)
			(xy 2.509012 -190.64715) (xy 2.509012 -194.296284) (xy 255.545336 -194.296284) (xy 255.545336 -193.432684)
			(xy 255.545822 -193.405415) (xy 255.553584 -193.351431) (xy 255.568949 -193.299101) (xy 255.591606 -193.249491)
			(xy 255.621092 -193.20361) (xy 255.656807 -193.162393) (xy 255.698024 -193.126678) (xy 255.743905 -193.097192)
			(xy 255.793515 -193.074535) (xy 255.845845 -193.05917) (xy 255.899829 -193.051408) (xy 255.954367 -193.051408)
			(xy 256.008351 -193.05917) (xy 256.060681 -193.074535) (xy 256.110291 -193.097192) (xy 256.156172 -193.126678)
			(xy 256.197389 -193.162393) (xy 256.233104 -193.20361) (xy 256.26259 -193.249491) (xy 256.285247 -193.299101)
			(xy 256.300612 -193.351431) (xy 256.308374 -193.405415) (xy 256.30886 -193.432684) (xy 256.30886 -194.296284)
			(xy 256.308374 -194.323553) (xy 256.300612 -194.377537) (xy 256.285247 -194.429867) (xy 256.26259 -194.479477)
			(xy 256.25414 -194.492626) (xy 260.09346 -194.492626) (xy 260.09346 -193.502026) (xy 260.093946 -193.474757)
			(xy 260.101708 -193.420773) (xy 260.117073 -193.368443) (xy 260.13973 -193.318833) (xy 260.169216 -193.272952)
			(xy 260.204931 -193.231735) (xy 260.246148 -193.19602) (xy 260.292029 -193.166534) (xy 260.341639 -193.143877)
			(xy 260.393969 -193.128512) (xy 260.447953 -193.12075) (xy 260.502491 -193.12075) (xy 260.556475 -193.128512)
			(xy 260.608805 -193.143877) (xy 260.658415 -193.166534) (xy 260.704296 -193.19602) (xy 260.745513 -193.231735)
			(xy 260.781228 -193.272952) (xy 260.810714 -193.318833) (xy 260.833371 -193.368443) (xy 260.848736 -193.420773)
			(xy 260.856498 -193.474757) (xy 260.856984 -193.502026) (xy 260.856984 -194.492626) (xy 260.856498 -194.519895)
			(xy 260.848736 -194.573879) (xy 260.833371 -194.626209) (xy 260.810714 -194.675819) (xy 260.781228 -194.7217)
			(xy 260.745513 -194.762917) (xy 260.704296 -194.798632) (xy 260.658415 -194.828118) (xy 260.608805 -194.850775)
			(xy 260.556475 -194.86614) (xy 260.502491 -194.873902) (xy 260.447953 -194.873902) (xy 260.393969 -194.86614)
			(xy 260.341639 -194.850775) (xy 260.292029 -194.828118) (xy 260.246148 -194.798632) (xy 260.204931 -194.762917)
			(xy 260.169216 -194.7217) (xy 260.13973 -194.675819) (xy 260.117073 -194.626209) (xy 260.101708 -194.573879)
			(xy 260.093946 -194.519895) (xy 260.09346 -194.492626) (xy 256.25414 -194.492626) (xy 256.233104 -194.525358)
			(xy 256.197389 -194.566575) (xy 256.156172 -194.60229) (xy 256.110291 -194.631776) (xy 256.060681 -194.654433)
			(xy 256.008351 -194.669798) (xy 255.954367 -194.67756) (xy 255.899829 -194.67756) (xy 255.845845 -194.669798)
			(xy 255.793515 -194.654433) (xy 255.743905 -194.631776) (xy 255.698024 -194.60229) (xy 255.656807 -194.566575)
			(xy 255.621092 -194.525358) (xy 255.591606 -194.479477) (xy 255.568949 -194.429867) (xy 255.553584 -194.377537)
			(xy 255.545822 -194.323553) (xy 255.545336 -194.296284) (xy 2.509012 -194.296284) (xy 2.509012 -197.07352)
			(xy 255.545336 -197.07352) (xy 255.545336 -196.20992) (xy 255.545822 -196.182651) (xy 255.553584 -196.128667)
			(xy 255.568949 -196.076337) (xy 255.591606 -196.026727) (xy 255.621092 -195.980846) (xy 255.656807 -195.939629)
			(xy 255.698024 -195.903914) (xy 255.743905 -195.874428) (xy 255.793515 -195.851771) (xy 255.845845 -195.836406)
			(xy 255.899829 -195.828644) (xy 255.954367 -195.828644) (xy 256.008351 -195.836406) (xy 256.060681 -195.851771)
			(xy 256.110291 -195.874428) (xy 256.156172 -195.903914) (xy 256.197389 -195.939629) (xy 256.233104 -195.980846)
			(xy 256.26259 -196.026727) (xy 256.285247 -196.076337) (xy 256.300612 -196.128667) (xy 256.308374 -196.182651)
			(xy 256.30886 -196.20992) (xy 256.30886 -197.07352) (xy 256.308374 -197.100789) (xy 256.300612 -197.154773)
			(xy 256.285247 -197.207103) (xy 256.26259 -197.256713) (xy 256.233104 -197.302594) (xy 256.197389 -197.343811)
			(xy 256.156172 -197.379526) (xy 256.110291 -197.409012) (xy 256.060681 -197.431669) (xy 256.008351 -197.447034)
			(xy 255.954367 -197.454796) (xy 255.899829 -197.454796) (xy 255.845845 -197.447034) (xy 255.793515 -197.431669)
			(xy 255.743905 -197.409012) (xy 255.698024 -197.379526) (xy 255.656807 -197.343811) (xy 255.621092 -197.302594)
			(xy 255.591606 -197.256713) (xy 255.568949 -197.207103) (xy 255.553584 -197.154773) (xy 255.545822 -197.100789)
			(xy 255.545336 -197.07352) (xy 2.509012 -197.07352) (xy 2.509012 -199.868028) (xy 255.545336 -199.868028)
			(xy 255.545336 -199.004428) (xy 255.545822 -198.977159) (xy 255.553584 -198.923175) (xy 255.568949 -198.870845)
			(xy 255.591606 -198.821235) (xy 255.621092 -198.775354) (xy 255.656807 -198.734137) (xy 255.698024 -198.698422)
			(xy 255.743905 -198.668936) (xy 255.793515 -198.646279) (xy 255.845845 -198.630914) (xy 255.899829 -198.623152)
			(xy 255.954367 -198.623152) (xy 256.008351 -198.630914) (xy 256.060681 -198.646279) (xy 256.110291 -198.668936)
			(xy 256.156172 -198.698422) (xy 256.197389 -198.734137) (xy 256.233104 -198.775354) (xy 256.26259 -198.821235)
			(xy 256.285247 -198.870845) (xy 256.300612 -198.923175) (xy 256.308374 -198.977159) (xy 256.30886 -199.004428)
			(xy 256.30886 -199.868028) (xy 256.308374 -199.895297) (xy 256.300612 -199.949281) (xy 256.285247 -200.001611)
			(xy 256.26259 -200.051221) (xy 256.233104 -200.097102) (xy 256.197389 -200.138319) (xy 256.156172 -200.174034)
			(xy 256.110291 -200.20352) (xy 256.060681 -200.226177) (xy 256.008351 -200.241542) (xy 255.954367 -200.249304)
			(xy 255.899829 -200.249304) (xy 255.845845 -200.241542) (xy 255.793515 -200.226177) (xy 255.743905 -200.20352)
			(xy 255.698024 -200.174034) (xy 255.656807 -200.138319) (xy 255.621092 -200.097102) (xy 255.591606 -200.051221)
			(xy 255.568949 -200.001611) (xy 255.553584 -199.949281) (xy 255.545822 -199.895297) (xy 255.545336 -199.868028)
			(xy 2.509012 -199.868028) (xy 2.509012 -202.662536) (xy 255.545336 -202.662536) (xy 255.545336 -201.798936)
			(xy 255.545822 -201.771667) (xy 255.553584 -201.717683) (xy 255.568949 -201.665353) (xy 255.591606 -201.615743)
			(xy 255.621092 -201.569862) (xy 255.656807 -201.528645) (xy 255.698024 -201.49293) (xy 255.743905 -201.463444)
			(xy 255.793515 -201.440787) (xy 255.845845 -201.425422) (xy 255.899829 -201.41766) (xy 255.954367 -201.41766)
			(xy 256.008351 -201.425422) (xy 256.060681 -201.440787) (xy 256.110291 -201.463444) (xy 256.156172 -201.49293)
			(xy 256.197389 -201.528645) (xy 256.233104 -201.569862) (xy 256.26259 -201.615743) (xy 256.285247 -201.665353)
			(xy 256.300612 -201.717683) (xy 256.308374 -201.771667) (xy 256.30886 -201.798936) (xy 256.30886 -202.662536)
			(xy 256.308374 -202.689805) (xy 256.300612 -202.743789) (xy 256.285247 -202.796119) (xy 256.26259 -202.845729)
			(xy 256.233104 -202.89161) (xy 256.197389 -202.932827) (xy 256.156172 -202.968542) (xy 256.110291 -202.998028)
			(xy 256.060681 -203.020685) (xy 256.008351 -203.03605) (xy 255.954367 -203.043812) (xy 255.899829 -203.043812)
			(xy 255.845845 -203.03605) (xy 255.793515 -203.020685) (xy 255.743905 -202.998028) (xy 255.698024 -202.968542)
			(xy 255.656807 -202.932827) (xy 255.621092 -202.89161) (xy 255.591606 -202.845729) (xy 255.568949 -202.796119)
			(xy 255.553584 -202.743789) (xy 255.545822 -202.689805) (xy 255.545336 -202.662536) (xy 2.509012 -202.662536)
			(xy 2.509012 -205.439772) (xy 255.545336 -205.439772) (xy 255.545336 -204.576172) (xy 255.545822 -204.548903)
			(xy 255.553584 -204.494919) (xy 255.568949 -204.442589) (xy 255.591606 -204.392979) (xy 255.621092 -204.347098)
			(xy 255.656807 -204.305881) (xy 255.698024 -204.270166) (xy 255.743905 -204.24068) (xy 255.793515 -204.218023)
			(xy 255.845845 -204.202658) (xy 255.899829 -204.194896) (xy 255.954367 -204.194896) (xy 256.008351 -204.202658)
			(xy 256.060681 -204.218023) (xy 256.110291 -204.24068) (xy 256.156172 -204.270166) (xy 256.197389 -204.305881)
			(xy 256.233104 -204.347098) (xy 256.26259 -204.392979) (xy 256.285247 -204.442589) (xy 256.300612 -204.494919)
			(xy 256.308374 -204.548903) (xy 256.30886 -204.576172) (xy 256.30886 -205.439772) (xy 256.308374 -205.467041)
			(xy 256.300612 -205.521025) (xy 256.285247 -205.573355) (xy 256.26259 -205.622965) (xy 256.233104 -205.668846)
			(xy 256.197389 -205.710063) (xy 256.156172 -205.745778) (xy 256.110291 -205.775264) (xy 256.060681 -205.797921)
			(xy 256.008351 -205.813286) (xy 255.954367 -205.821048) (xy 255.899829 -205.821048) (xy 255.845845 -205.813286)
			(xy 255.793515 -205.797921) (xy 255.743905 -205.775264) (xy 255.698024 -205.745778) (xy 255.656807 -205.710063)
			(xy 255.621092 -205.668846) (xy 255.591606 -205.622965) (xy 255.568949 -205.573355) (xy 255.553584 -205.521025)
			(xy 255.545822 -205.467041) (xy 255.545336 -205.439772) (xy 2.509012 -205.439772) (xy 2.509012 -207.499458)
			(xy 97.408492 -207.499458) (xy 97.408492 -206.635858) (xy 97.408978 -206.608589) (xy 97.41674 -206.554605)
			(xy 97.432105 -206.502275) (xy 97.454762 -206.452665) (xy 97.484248 -206.406784) (xy 97.519963 -206.365567)
			(xy 97.56118 -206.329852) (xy 97.607061 -206.300366) (xy 97.656671 -206.277709) (xy 97.709001 -206.262344)
			(xy 97.762985 -206.254582) (xy 97.817523 -206.254582) (xy 97.871507 -206.262344) (xy 97.923837 -206.277709)
			(xy 97.973447 -206.300366) (xy 98.019328 -206.329852) (xy 98.060545 -206.365567) (xy 98.09626 -206.406784)
			(xy 98.125746 -206.452665) (xy 98.148403 -206.502275) (xy 98.163768 -206.554605) (xy 98.17153 -206.608589)
			(xy 98.172016 -206.635858) (xy 98.172016 -207.499458) (xy 98.17153 -207.526727) (xy 98.163768 -207.580711)
			(xy 98.148403 -207.633041) (xy 98.125746 -207.682651) (xy 98.09626 -207.728532) (xy 98.060545 -207.769749)
			(xy 98.019328 -207.805464) (xy 97.973447 -207.83495) (xy 97.923837 -207.857607) (xy 97.871507 -207.872972)
			(xy 97.817523 -207.880734) (xy 97.762985 -207.880734) (xy 97.709001 -207.872972) (xy 97.656671 -207.857607)
			(xy 97.607061 -207.83495) (xy 97.56118 -207.805464) (xy 97.519963 -207.769749) (xy 97.484248 -207.728532)
			(xy 97.454762 -207.682651) (xy 97.432105 -207.633041) (xy 97.41674 -207.580711) (xy 97.408978 -207.526727)
			(xy 97.408492 -207.499458) (xy 2.509012 -207.499458) (xy 2.509012 -209.023458) (xy 94.105984 -209.023458)
			(xy 94.105984 -208.159858) (xy 94.10647 -208.132589) (xy 94.114232 -208.078605) (xy 94.129597 -208.026275)
			(xy 94.152254 -207.976665) (xy 94.18174 -207.930784) (xy 94.217455 -207.889567) (xy 94.258672 -207.853852)
			(xy 94.304553 -207.824366) (xy 94.354163 -207.801709) (xy 94.406493 -207.786344) (xy 94.460477 -207.778582)
			(xy 94.515015 -207.778582) (xy 94.568999 -207.786344) (xy 94.621329 -207.801709) (xy 94.670939 -207.824366)
			(xy 94.71682 -207.853852) (xy 94.758037 -207.889567) (xy 94.793752 -207.930784) (xy 94.823238 -207.976665)
			(xy 94.845895 -208.026275) (xy 94.86126 -208.078605) (xy 94.869022 -208.132589) (xy 94.869508 -208.159858)
			(xy 94.869508 -208.217008) (xy 255.545336 -208.217008) (xy 255.545336 -207.353408) (xy 255.545822 -207.326139)
			(xy 255.553584 -207.272155) (xy 255.568949 -207.219825) (xy 255.591606 -207.170215) (xy 255.621092 -207.124334)
			(xy 255.656807 -207.083117) (xy 255.698024 -207.047402) (xy 255.743905 -207.017916) (xy 255.793515 -206.995259)
			(xy 255.845845 -206.979894) (xy 255.899829 -206.972132) (xy 255.954367 -206.972132) (xy 256.008351 -206.979894)
			(xy 256.060681 -206.995259) (xy 256.110291 -207.017916) (xy 256.156172 -207.047402) (xy 256.197389 -207.083117)
			(xy 256.233104 -207.124334) (xy 256.26259 -207.170215) (xy 256.285247 -207.219825) (xy 256.300612 -207.272155)
			(xy 256.308374 -207.326139) (xy 256.30886 -207.353408) (xy 256.30886 -208.217008) (xy 256.308374 -208.244277)
			(xy 256.300612 -208.298261) (xy 256.285247 -208.350591) (xy 256.26259 -208.400201) (xy 256.233104 -208.446082)
			(xy 256.197389 -208.487299) (xy 256.156172 -208.523014) (xy 256.110291 -208.5525) (xy 256.060681 -208.575157)
			(xy 256.008351 -208.590522) (xy 255.954367 -208.598284) (xy 255.899829 -208.598284) (xy 255.845845 -208.590522)
			(xy 255.793515 -208.575157) (xy 255.743905 -208.5525) (xy 255.698024 -208.523014) (xy 255.656807 -208.487299)
			(xy 255.621092 -208.446082) (xy 255.591606 -208.400201) (xy 255.568949 -208.350591) (xy 255.553584 -208.298261)
			(xy 255.545822 -208.244277) (xy 255.545336 -208.217008) (xy 94.869508 -208.217008) (xy 94.869508 -209.023458)
			(xy 94.869022 -209.050727) (xy 94.86126 -209.104711) (xy 94.845895 -209.157041) (xy 94.823238 -209.206651)
			(xy 94.793752 -209.252532) (xy 94.758037 -209.293749) (xy 94.71682 -209.329464) (xy 94.670939 -209.35895)
			(xy 94.621329 -209.381607) (xy 94.568999 -209.396972) (xy 94.515015 -209.404734) (xy 94.460477 -209.404734)
			(xy 94.406493 -209.396972) (xy 94.354163 -209.381607) (xy 94.304553 -209.35895) (xy 94.258672 -209.329464)
			(xy 94.217455 -209.293749) (xy 94.18174 -209.252532) (xy 94.152254 -209.206651) (xy 94.129597 -209.157041)
			(xy 94.114232 -209.104711) (xy 94.10647 -209.050727) (xy 94.105984 -209.023458) (xy 2.509012 -209.023458)
			(xy 2.509012 -212.98027) (xy 78.81214 -212.98027) (xy 78.81617 -212.837935) (xy 78.828245 -212.696055)
			(xy 78.848328 -212.555087) (xy 78.876355 -212.41548) (xy 78.912235 -212.277682) (xy 78.955853 -212.142135)
			(xy 79.00707 -212.009273) (xy 79.065721 -211.879521) (xy 79.131619 -211.753295) (xy 79.204553 -211.630999)
			(xy 79.28429 -211.513026) (xy 79.370572 -211.399753) (xy 79.463125 -211.291542) (xy 79.561652 -211.188741)
			(xy 79.665837 -211.091679) (xy 79.775346 -211.000667) (xy 79.889829 -210.915995) (xy 80.008919 -210.837937)
			(xy 80.132234 -210.766741) (xy 80.25938 -210.702635) (xy 80.389949 -210.645826) (xy 80.523523 -210.596494)
			(xy 80.659674 -210.554798) (xy 80.797965 -210.520872) (xy 80.937955 -210.494824) (xy 81.079194 -210.476738)
			(xy 81.22123 -210.466671) (xy 81.363608 -210.464656) (xy 81.505872 -210.470699) (xy 81.647566 -210.484781)
			(xy 81.788236 -210.506857) (xy 81.927433 -210.536857) (xy 82.064709 -210.574683) (xy 82.199625 -210.620215)
			(xy 82.331749 -210.673306) (xy 82.460658 -210.733788) (xy 82.585939 -210.801466) (xy 82.70719 -210.876123)
			(xy 82.824023 -210.957521) (xy 82.936064 -211.045398) (xy 83.042954 -211.139473) (xy 83.144351 -211.239445)
			(xy 83.239929 -211.344993) (xy 83.329383 -211.455779) (xy 83.412425 -211.571448) (xy 83.488791 -211.691631)
			(xy 83.558235 -211.815941) (xy 83.620535 -211.943982) (xy 83.675491 -212.075341) (xy 83.69835 -212.140038)
			(xy 94.106492 -212.140038) (xy 94.106492 -211.276438) (xy 94.106978 -211.249187) (xy 94.114734 -211.195239)
			(xy 94.130089 -211.142944) (xy 94.152731 -211.093367) (xy 94.182197 -211.047517) (xy 94.217888 -211.006326)
			(xy 94.259079 -210.970635) (xy 94.304929 -210.941169) (xy 94.354506 -210.918527) (xy 94.406801 -210.903172)
			(xy 94.460749 -210.895416) (xy 94.515251 -210.895416) (xy 94.569199 -210.903172) (xy 94.621494 -210.918527)
			(xy 94.671071 -210.941169) (xy 94.716921 -210.970635) (xy 94.758112 -211.006326) (xy 94.793803 -211.047517)
			(xy 94.823269 -211.093367) (xy 94.845911 -211.142944) (xy 94.861266 -211.195239) (xy 94.869022 -211.249187)
			(xy 94.869508 -211.276438) (xy 94.869508 -212.140038) (xy 94.869022 -212.167289) (xy 94.861266 -212.221237)
			(xy 94.845911 -212.273532) (xy 94.823269 -212.323109) (xy 94.793803 -212.368959) (xy 94.758112 -212.41015)
			(xy 94.716921 -212.445841) (xy 94.671071 -212.475307) (xy 94.621494 -212.497949) (xy 94.569199 -212.513304)
			(xy 94.515251 -212.52106) (xy 94.460749 -212.52106) (xy 94.406801 -212.513304) (xy 94.354506 -212.497949)
			(xy 94.304929 -212.475307) (xy 94.259079 -212.445841) (xy 94.217888 -212.41015) (xy 94.182197 -212.368959)
			(xy 94.152731 -212.323109) (xy 94.130089 -212.273532) (xy 94.114734 -212.221237) (xy 94.106978 -212.167289)
			(xy 94.106492 -212.140038) (xy 83.69835 -212.140038) (xy 83.722928 -212.2096) (xy 83.762692 -212.346327)
			(xy 83.794658 -212.485085) (xy 83.818723 -212.625429) (xy 83.834809 -212.76691) (xy 83.842864 -212.909074)
			(xy 83.843368 -212.98027) (xy 140.011408 -212.98027) (xy 140.015438 -212.837906) (xy 140.027516 -212.695998)
			(xy 140.047604 -212.555001) (xy 140.075636 -212.415366) (xy 140.111523 -212.27754) (xy 140.15515 -212.141966)
			(xy 140.206377 -212.009077) (xy 140.26504 -211.879298) (xy 140.330952 -211.753047) (xy 140.403901 -211.630727)
			(xy 140.483653 -211.51273) (xy 140.569953 -211.399434) (xy 140.662525 -211.291201) (xy 140.761071 -211.188379)
			(xy 140.865277 -211.091298) (xy 140.974809 -211.000267) (xy 141.089315 -210.915579) (xy 141.208429 -210.837504)
			(xy 141.331769 -210.766294) (xy 141.45894 -210.702175) (xy 141.589536 -210.645354) (xy 141.723136 -210.596013)
			(xy 141.859315 -210.554308) (xy 141.997634 -210.520375) (xy 142.137652 -210.494322) (xy 142.278919 -210.476232)
			(xy 142.420984 -210.466163) (xy 142.563391 -210.464148) (xy 142.705684 -210.470192) (xy 142.847406 -210.484278)
			(xy 142.988105 -210.506358) (xy 143.12733 -210.536363) (xy 143.264634 -210.574197) (xy 143.399577 -210.619738)
			(xy 143.531728 -210.672841) (xy 143.660663 -210.733335) (xy 143.785969 -210.801026) (xy 143.907245 -210.875699)
			(xy 144.024101 -210.957113) (xy 144.093464 -211.011516) (xy 255.545336 -211.011516) (xy 255.545336 -210.147916)
			(xy 255.545822 -210.120647) (xy 255.553584 -210.066663) (xy 255.568949 -210.014333) (xy 255.591606 -209.964723)
			(xy 255.621092 -209.918842) (xy 255.656807 -209.877625) (xy 255.698024 -209.84191) (xy 255.743905 -209.812424)
			(xy 255.793515 -209.789767) (xy 255.845845 -209.774402) (xy 255.899829 -209.76664) (xy 255.954367 -209.76664)
			(xy 256.008351 -209.774402) (xy 256.060681 -209.789767) (xy 256.110291 -209.812424) (xy 256.156172 -209.84191)
			(xy 256.197389 -209.877625) (xy 256.233104 -209.918842) (xy 256.26259 -209.964723) (xy 256.285247 -210.014333)
			(xy 256.300612 -210.066663) (xy 256.308374 -210.120647) (xy 256.30886 -210.147916) (xy 256.30886 -211.011516)
			(xy 256.308374 -211.038785) (xy 256.300612 -211.092769) (xy 256.285247 -211.145099) (xy 256.26259 -211.194709)
			(xy 256.233104 -211.24059) (xy 256.197389 -211.281807) (xy 256.156172 -211.317522) (xy 256.110291 -211.347008)
			(xy 256.060681 -211.369665) (xy 256.008351 -211.38503) (xy 255.954367 -211.392792) (xy 255.899829 -211.392792)
			(xy 255.845845 -211.38503) (xy 255.793515 -211.369665) (xy 255.743905 -211.347008) (xy 255.698024 -211.317522)
			(xy 255.656807 -211.281807) (xy 255.621092 -211.24059) (xy 255.591606 -211.194709) (xy 255.568949 -211.145099)
			(xy 255.553584 -211.092769) (xy 255.545822 -211.038785) (xy 255.545336 -211.011516) (xy 144.093464 -211.011516)
			(xy 144.136165 -211.045007) (xy 144.243077 -211.139101) (xy 144.344494 -211.239093) (xy 144.440091 -211.344662)
			(xy 144.529563 -211.455471) (xy 144.612622 -211.571164) (xy 144.689003 -211.691371) (xy 144.758461 -211.815706)
			(xy 144.820774 -211.943772) (xy 144.875741 -212.075159) (xy 144.923187 -212.209444) (xy 144.96296 -212.346199)
			(xy 144.994932 -212.484985) (xy 145.019002 -212.625357) (xy 145.035091 -212.766867) (xy 145.043148 -212.909059)
			(xy 145.043652 -212.98027) (xy 145.043148 -213.051481) (xy 145.035091 -213.193673) (xy 145.019002 -213.335183)
			(xy 144.994932 -213.475555) (xy 144.96296 -213.614341) (xy 144.923187 -213.751096) (xy 144.90378 -213.806024)
			(xy 255.545336 -213.806024) (xy 255.545336 -212.942424) (xy 255.545822 -212.915155) (xy 255.553584 -212.861171)
			(xy 255.568949 -212.808841) (xy 255.591606 -212.759231) (xy 255.621092 -212.71335) (xy 255.656807 -212.672133)
			(xy 255.698024 -212.636418) (xy 255.743905 -212.606932) (xy 255.793515 -212.584275) (xy 255.845845 -212.56891)
			(xy 255.899829 -212.561148) (xy 255.954367 -212.561148) (xy 256.008351 -212.56891) (xy 256.060681 -212.584275)
			(xy 256.110291 -212.606932) (xy 256.156172 -212.636418) (xy 256.197389 -212.672133) (xy 256.233104 -212.71335)
			(xy 256.26259 -212.759231) (xy 256.285247 -212.808841) (xy 256.300612 -212.861171) (xy 256.308374 -212.915155)
			(xy 256.30886 -212.942424) (xy 256.30886 -212.980016) (xy 326.752208 -212.980016) (xy 326.756238 -212.837681)
			(xy 326.768313 -212.695801) (xy 326.788396 -212.554833) (xy 326.816423 -212.415226) (xy 326.852303 -212.277428)
			(xy 326.895921 -212.141881) (xy 326.947138 -212.009019) (xy 327.005789 -211.879267) (xy 327.071687 -211.753041)
			(xy 327.144621 -211.630745) (xy 327.224358 -211.512772) (xy 327.31064 -211.399499) (xy 327.403193 -211.291288)
			(xy 327.50172 -211.188487) (xy 327.605905 -211.091425) (xy 327.715414 -211.000413) (xy 327.829897 -210.915741)
			(xy 327.948987 -210.837683) (xy 328.072302 -210.766487) (xy 328.199448 -210.702381) (xy 328.330017 -210.645572)
			(xy 328.463591 -210.59624) (xy 328.599742 -210.554544) (xy 328.738033 -210.520618) (xy 328.878023 -210.49457)
			(xy 329.019262 -210.476484) (xy 329.161298 -210.466417) (xy 329.303676 -210.464402) (xy 329.44594 -210.470445)
			(xy 329.587634 -210.484527) (xy 329.728304 -210.506603) (xy 329.867501 -210.536603) (xy 330.004777 -210.574429)
			(xy 330.139693 -210.619961) (xy 330.271817 -210.673052) (xy 330.400726 -210.733534) (xy 330.526007 -210.801212)
			(xy 330.647258 -210.875869) (xy 330.764091 -210.957267) (xy 330.876132 -211.045144) (xy 330.983022 -211.139219)
			(xy 331.084419 -211.239191) (xy 331.179997 -211.344739) (xy 331.269451 -211.455525) (xy 331.352493 -211.571194)
			(xy 331.428859 -211.691377) (xy 331.498303 -211.815687) (xy 331.560603 -211.943728) (xy 331.615559 -212.075087)
			(xy 331.662996 -212.209346) (xy 331.70276 -212.346073) (xy 331.734726 -212.484831) (xy 331.758791 -212.625175)
			(xy 331.774877 -212.766656) (xy 331.782932 -212.90882) (xy 331.783436 -212.980016) (xy 387.951476 -212.980016)
			(xy 387.955506 -212.837652) (xy 387.967584 -212.695744) (xy 387.987672 -212.554747) (xy 388.015704 -212.415112)
			(xy 388.051591 -212.277286) (xy 388.095218 -212.141712) (xy 388.146445 -212.008823) (xy 388.205108 -211.879044)
			(xy 388.27102 -211.752793) (xy 388.343969 -211.630473) (xy 388.423721 -211.512476) (xy 388.510021 -211.39918)
			(xy 388.602593 -211.290947) (xy 388.701139 -211.188125) (xy 388.805345 -211.091044) (xy 388.914877 -211.000013)
			(xy 389.029383 -210.915325) (xy 389.148497 -210.83725) (xy 389.271837 -210.76604) (xy 389.399008 -210.701921)
			(xy 389.529604 -210.6451) (xy 389.663204 -210.595759) (xy 389.799383 -210.554054) (xy 389.937702 -210.520121)
			(xy 390.07772 -210.494068) (xy 390.218987 -210.475978) (xy 390.361052 -210.465909) (xy 390.503459 -210.463894)
			(xy 390.645752 -210.469938) (xy 390.787474 -210.484024) (xy 390.928173 -210.506104) (xy 391.067398 -210.536109)
			(xy 391.204702 -210.573943) (xy 391.339645 -210.619484) (xy 391.471796 -210.672587) (xy 391.600731 -210.733081)
			(xy 391.726037 -210.800772) (xy 391.847313 -210.875445) (xy 391.964169 -210.956859) (xy 392.076233 -211.044753)
			(xy 392.183145 -211.138847) (xy 392.284562 -211.238839) (xy 392.380159 -211.344408) (xy 392.469631 -211.455217)
			(xy 392.55269 -211.57091) (xy 392.629071 -211.691117) (xy 392.698529 -211.815452) (xy 392.760842 -211.943518)
			(xy 392.815809 -212.074905) (xy 392.863255 -212.20919) (xy 392.903028 -212.345945) (xy 392.935 -212.484731)
			(xy 392.95907 -212.625103) (xy 392.975159 -212.766613) (xy 392.983216 -212.908805) (xy 392.98372 -212.980016)
			(xy 392.983216 -213.051227) (xy 392.975159 -213.193419) (xy 392.95907 -213.334929) (xy 392.935 -213.475301)
			(xy 392.903028 -213.614087) (xy 392.863255 -213.750842) (xy 392.815809 -213.885127) (xy 392.760842 -214.016514)
			(xy 392.698529 -214.14458) (xy 392.629071 -214.268915) (xy 392.55269 -214.389122) (xy 392.469631 -214.504815)
			(xy 392.380159 -214.615624) (xy 392.284562 -214.721193) (xy 392.183145 -214.821185) (xy 392.076233 -214.915279)
			(xy 391.964169 -215.003173) (xy 391.847313 -215.084587) (xy 391.726037 -215.15926) (xy 391.600731 -215.226951)
			(xy 391.471796 -215.287445) (xy 391.339645 -215.340548) (xy 391.204702 -215.386089) (xy 391.067398 -215.423923)
			(xy 390.928173 -215.453928) (xy 390.787474 -215.476008) (xy 390.645752 -215.490094) (xy 390.503459 -215.496138)
			(xy 390.361052 -215.494123) (xy 390.218987 -215.484054) (xy 390.07772 -215.465964) (xy 389.937702 -215.439911)
			(xy 389.799383 -215.405978) (xy 389.663204 -215.364273) (xy 389.529604 -215.314932) (xy 389.399008 -215.258111)
			(xy 389.271837 -215.193992) (xy 389.148497 -215.122782) (xy 389.029383 -215.044707) (xy 388.914877 -214.960019)
			(xy 388.805345 -214.868988) (xy 388.701139 -214.771907) (xy 388.602593 -214.669085) (xy 388.510021 -214.560852)
			(xy 388.423721 -214.447556) (xy 388.343969 -214.329559) (xy 388.27102 -214.207239) (xy 388.205108 -214.080988)
			(xy 388.146445 -213.951209) (xy 388.095218 -213.81832) (xy 388.051591 -213.682746) (xy 388.015704 -213.54492)
			(xy 387.987672 -213.405285) (xy 387.967584 -213.264288) (xy 387.955506 -213.12238) (xy 387.951476 -212.980016)
			(xy 331.783436 -212.980016) (xy 331.782932 -213.051212) (xy 331.774877 -213.193376) (xy 331.758791 -213.334857)
			(xy 331.734726 -213.475201) (xy 331.70276 -213.613959) (xy 331.662996 -213.750686) (xy 331.615559 -213.884945)
			(xy 331.560603 -214.016304) (xy 331.498303 -214.144345) (xy 331.428859 -214.268655) (xy 331.352493 -214.388838)
			(xy 331.269451 -214.504507) (xy 331.179997 -214.615293) (xy 331.084419 -214.720841) (xy 330.983022 -214.820813)
			(xy 330.876132 -214.914888) (xy 330.764091 -215.002765) (xy 330.647258 -215.084163) (xy 330.526007 -215.15882)
			(xy 330.400726 -215.226498) (xy 330.271817 -215.28698) (xy 330.139693 -215.340071) (xy 330.004777 -215.385603)
			(xy 329.867501 -215.423429) (xy 329.728304 -215.453429) (xy 329.587634 -215.475505) (xy 329.44594 -215.489587)
			(xy 329.303676 -215.49563) (xy 329.161298 -215.493615) (xy 329.019262 -215.483548) (xy 328.878023 -215.465462)
			(xy 328.738033 -215.439414) (xy 328.599742 -215.405488) (xy 328.463591 -215.363792) (xy 328.330017 -215.31446)
			(xy 328.199448 -215.257651) (xy 328.072302 -215.193545) (xy 327.948987 -215.122349) (xy 327.829897 -215.044291)
			(xy 327.715414 -214.959619) (xy 327.605905 -214.868607) (xy 327.50172 -214.771545) (xy 327.403193 -214.668744)
			(xy 327.31064 -214.560533) (xy 327.224358 -214.44726) (xy 327.144621 -214.329287) (xy 327.071687 -214.206991)
			(xy 327.005789 -214.080765) (xy 326.947138 -213.951013) (xy 326.895921 -213.818151) (xy 326.852303 -213.682604)
			(xy 326.816423 -213.544806) (xy 326.788396 -213.405199) (xy 326.768313 -213.264231) (xy 326.756238 -213.122351)
			(xy 326.752208 -212.980016) (xy 256.30886 -212.980016) (xy 256.30886 -213.806024) (xy 256.308374 -213.833293)
			(xy 256.300612 -213.887277) (xy 256.285247 -213.939607) (xy 256.26259 -213.989217) (xy 256.233104 -214.035098)
			(xy 256.197389 -214.076315) (xy 256.156172 -214.11203) (xy 256.110291 -214.141516) (xy 256.060681 -214.164173)
			(xy 256.008351 -214.179538) (xy 255.954367 -214.1873) (xy 255.899829 -214.1873) (xy 255.845845 -214.179538)
			(xy 255.793515 -214.164173) (xy 255.743905 -214.141516) (xy 255.698024 -214.11203) (xy 255.656807 -214.076315)
			(xy 255.621092 -214.035098) (xy 255.591606 -213.989217) (xy 255.568949 -213.939607) (xy 255.553584 -213.887277)
			(xy 255.545822 -213.833293) (xy 255.545336 -213.806024) (xy 144.90378 -213.806024) (xy 144.875741 -213.885381)
			(xy 144.820774 -214.016768) (xy 144.758461 -214.144834) (xy 144.689003 -214.269169) (xy 144.612622 -214.389376)
			(xy 144.529563 -214.505069) (xy 144.440091 -214.615878) (xy 144.344494 -214.721447) (xy 144.243077 -214.821439)
			(xy 144.136165 -214.915533) (xy 144.024101 -215.003427) (xy 143.907245 -215.084841) (xy 143.785969 -215.159514)
			(xy 143.660663 -215.227205) (xy 143.531728 -215.287699) (xy 143.399577 -215.340802) (xy 143.264634 -215.386343)
			(xy 143.12733 -215.424177) (xy 142.988105 -215.454182) (xy 142.847406 -215.476262) (xy 142.705684 -215.490348)
			(xy 142.563391 -215.496392) (xy 142.420984 -215.494377) (xy 142.278919 -215.484308) (xy 142.137652 -215.466218)
			(xy 141.997634 -215.440165) (xy 141.859315 -215.406232) (xy 141.723136 -215.364527) (xy 141.589536 -215.315186)
			(xy 141.45894 -215.258365) (xy 141.331769 -215.194246) (xy 141.208429 -215.123036) (xy 141.089315 -215.044961)
			(xy 140.974809 -214.960273) (xy 140.865277 -214.869242) (xy 140.761071 -214.772161) (xy 140.662525 -214.669339)
			(xy 140.569953 -214.561106) (xy 140.483653 -214.44781) (xy 140.403901 -214.329813) (xy 140.330952 -214.207493)
			(xy 140.26504 -214.081242) (xy 140.206377 -213.951463) (xy 140.15515 -213.818574) (xy 140.111523 -213.683)
			(xy 140.075636 -213.545174) (xy 140.047604 -213.405539) (xy 140.027516 -213.264542) (xy 140.015438 -213.122634)
			(xy 140.011408 -212.98027) (xy 83.843368 -212.98027) (xy 83.842864 -213.051466) (xy 83.834809 -213.19363)
			(xy 83.818723 -213.335111) (xy 83.794658 -213.475455) (xy 83.762692 -213.614213) (xy 83.722928 -213.75094)
			(xy 83.675491 -213.885199) (xy 83.620535 -214.016558) (xy 83.558235 -214.144599) (xy 83.488791 -214.268909)
			(xy 83.412425 -214.389092) (xy 83.329383 -214.504761) (xy 83.239929 -214.615547) (xy 83.144351 -214.721095)
			(xy 83.042954 -214.821067) (xy 82.936064 -214.915142) (xy 82.837488 -214.992458) (xy 94.106492 -214.992458)
			(xy 94.106492 -214.128858) (xy 94.106978 -214.101607) (xy 94.114734 -214.047659) (xy 94.130089 -213.995364)
			(xy 94.152731 -213.945787) (xy 94.182197 -213.899937) (xy 94.217888 -213.858746) (xy 94.259079 -213.823055)
			(xy 94.304929 -213.793589) (xy 94.354506 -213.770947) (xy 94.406801 -213.755592) (xy 94.460749 -213.747836)
			(xy 94.515251 -213.747836) (xy 94.569199 -213.755592) (xy 94.621494 -213.770947) (xy 94.671071 -213.793589)
			(xy 94.716921 -213.823055) (xy 94.758112 -213.858746) (xy 94.793803 -213.899937) (xy 94.823269 -213.945787)
			(xy 94.845911 -213.995364) (xy 94.861266 -214.047659) (xy 94.869022 -214.101607) (xy 94.869508 -214.128858)
			(xy 94.869508 -214.992458) (xy 94.869022 -215.019709) (xy 94.861266 -215.073657) (xy 94.845911 -215.125952)
			(xy 94.823269 -215.175529) (xy 94.793803 -215.221379) (xy 94.758112 -215.26257) (xy 94.716921 -215.298261)
			(xy 94.671071 -215.327727) (xy 94.621494 -215.350369) (xy 94.569199 -215.365724) (xy 94.515251 -215.37348)
			(xy 94.460749 -215.37348) (xy 94.406801 -215.365724) (xy 94.354506 -215.350369) (xy 94.304929 -215.327727)
			(xy 94.259079 -215.298261) (xy 94.217888 -215.26257) (xy 94.182197 -215.221379) (xy 94.152731 -215.175529)
			(xy 94.130089 -215.125952) (xy 94.114734 -215.073657) (xy 94.106978 -215.019709) (xy 94.106492 -214.992458)
			(xy 82.837488 -214.992458) (xy 82.824023 -215.003019) (xy 82.70719 -215.084417) (xy 82.585939 -215.159074)
			(xy 82.460658 -215.226752) (xy 82.331749 -215.287234) (xy 82.199625 -215.340325) (xy 82.064709 -215.385857)
			(xy 81.927433 -215.423683) (xy 81.788236 -215.453683) (xy 81.647566 -215.475759) (xy 81.505872 -215.489841)
			(xy 81.363608 -215.495884) (xy 81.22123 -215.493869) (xy 81.079194 -215.483802) (xy 80.937955 -215.465716)
			(xy 80.797965 -215.439668) (xy 80.659674 -215.405742) (xy 80.523523 -215.364046) (xy 80.389949 -215.314714)
			(xy 80.25938 -215.257905) (xy 80.132234 -215.193799) (xy 80.008919 -215.122603) (xy 79.889829 -215.044545)
			(xy 79.775346 -214.959873) (xy 79.665837 -214.868861) (xy 79.561652 -214.771799) (xy 79.463125 -214.668998)
			(xy 79.370572 -214.560787) (xy 79.28429 -214.447514) (xy 79.204553 -214.329541) (xy 79.131619 -214.207245)
			(xy 79.065721 -214.081019) (xy 79.00707 -213.951267) (xy 78.955853 -213.818405) (xy 78.912235 -213.682858)
			(xy 78.876355 -213.54506) (xy 78.848328 -213.405453) (xy 78.828245 -213.264485) (xy 78.81617 -213.122605)
			(xy 78.81214 -212.98027) (xy 2.509012 -212.98027) (xy 2.509012 -217.548574) (xy 338.152884 -217.548574)
			(xy 338.152884 -217.494026) (xy 338.160647 -217.440032) (xy 338.176017 -217.387693) (xy 338.198679 -217.338074)
			(xy 338.228172 -217.292186) (xy 338.263897 -217.250963) (xy 338.305125 -217.215244) (xy 338.351016 -217.185756)
			(xy 338.400638 -217.1631) (xy 338.452979 -217.147737) (xy 338.506973 -217.13998) (xy 338.534248 -217.13952)
			(xy 339.550248 -217.13952) (xy 339.577514 -217.140046) (xy 339.63149 -217.147813) (xy 339.683811 -217.163181)
			(xy 339.733413 -217.185839) (xy 339.779286 -217.215325) (xy 339.820495 -217.251039) (xy 339.856204 -217.292253)
			(xy 339.885684 -217.338129) (xy 339.908336 -217.387734) (xy 339.923698 -217.440057) (xy 339.931458 -217.494034)
			(xy 339.931458 -217.548566) (xy 339.923698 -217.602543) (xy 339.908336 -217.654866) (xy 339.885684 -217.704471)
			(xy 339.856204 -217.750347) (xy 339.820495 -217.791561) (xy 339.779286 -217.827275) (xy 339.733413 -217.856761)
			(xy 339.683811 -217.879419) (xy 339.63149 -217.894787) (xy 339.577514 -217.902554) (xy 339.550248 -217.903044)
			(xy 338.534248 -217.903044) (xy 338.506973 -217.90262) (xy 338.452979 -217.894863) (xy 338.400638 -217.8795)
			(xy 338.351016 -217.856844) (xy 338.305125 -217.827356) (xy 338.263897 -217.791637) (xy 338.228172 -217.750414)
			(xy 338.198679 -217.704526) (xy 338.176017 -217.654907) (xy 338.160647 -217.602568) (xy 338.152884 -217.548574)
			(xy 2.509012 -217.548574) (xy 2.509012 -219.820372) (xy 129.049982 -219.820372) (xy 129.049982 -219.765828)
			(xy 129.057745 -219.71184) (xy 129.073111 -219.659505) (xy 129.095769 -219.609891) (xy 129.125257 -219.564005)
			(xy 129.160975 -219.522783) (xy 129.202196 -219.487064) (xy 129.24808 -219.457575) (xy 129.297694 -219.434915)
			(xy 129.350028 -219.419547) (xy 129.404016 -219.411783) (xy 129.431288 -219.411296) (xy 130.447288 -219.411296)
			(xy 130.474557 -219.411843) (xy 130.528539 -219.419602) (xy 130.580867 -219.434966) (xy 130.630476 -219.45762)
			(xy 130.676357 -219.487104) (xy 130.717574 -219.522818) (xy 130.753288 -219.564034) (xy 130.782774 -219.609913)
			(xy 130.80543 -219.659522) (xy 130.820795 -219.711849) (xy 130.828557 -219.765831) (xy 130.828557 -219.820369)
			(xy 130.820795 -219.874351) (xy 130.80543 -219.926678) (xy 130.782774 -219.976287) (xy 130.753288 -220.022166)
			(xy 130.717574 -220.063382) (xy 130.676357 -220.099096) (xy 130.630476 -220.12858) (xy 130.580867 -220.151234)
			(xy 130.528539 -220.166598) (xy 130.474557 -220.174357) (xy 130.447288 -220.17482) (xy 129.431288 -220.17482)
			(xy 129.404016 -220.174417) (xy 129.350028 -220.166653) (xy 129.297694 -220.151285) (xy 129.24808 -220.128625)
			(xy 129.202196 -220.099136) (xy 129.160975 -220.063417) (xy 129.125257 -220.022195) (xy 129.095769 -219.976309)
			(xy 129.073111 -219.926695) (xy 129.057745 -219.87436) (xy 129.049982 -219.820372) (xy 2.509012 -219.820372)
			(xy 2.509012 -243.6744) (xy 108.185132 -243.6744) (xy 108.189304 -243.624054) (xy 108.201706 -243.575081)
			(xy 108.222 -243.528817) (xy 108.249632 -243.486525) (xy 108.283849 -243.449358) (xy 108.323717 -243.418331)
			(xy 108.368148 -243.394288) (xy 108.41593 -243.377887) (xy 108.465761 -243.369575) (xy 108.49102 -243.369084)
			(xy 109.431074 -243.369084) (xy 109.456332 -243.369591) (xy 109.506161 -243.377902) (xy 109.553942 -243.394301)
			(xy 109.598371 -243.418342) (xy 109.638238 -243.449368) (xy 109.672453 -243.486533) (xy 109.700085 -243.528823)
			(xy 109.720378 -243.575085) (xy 109.73278 -243.624056) (xy 109.736927 -243.6741) (xy 361.758723 -243.6741)
			(xy 361.762898 -243.623721) (xy 361.775308 -243.574716) (xy 361.795615 -243.528421) (xy 361.823265 -243.486101)
			(xy 361.857503 -243.448909) (xy 361.897396 -243.41786) (xy 361.941856 -243.393801) (xy 361.989669 -243.377388)
			(xy 362.039532 -243.369068) (xy 362.064808 -243.368576) (xy 363.004862 -243.368576) (xy 363.030146 -243.36899)
			(xy 363.080025 -243.377308) (xy 363.127854 -243.393722) (xy 363.172329 -243.417786) (xy 363.212237 -243.448843)
			(xy 363.246487 -243.486045) (xy 363.274147 -243.528377) (xy 363.294462 -243.574685) (xy 363.306876 -243.623705)
			(xy 363.311053 -243.6741) (xy 363.306876 -243.724495) (xy 363.294462 -243.773515) (xy 363.274147 -243.819823)
			(xy 363.246487 -243.862155) (xy 363.212237 -243.899357) (xy 363.172329 -243.930414) (xy 363.127854 -243.954478)
			(xy 363.080025 -243.970892) (xy 363.030146 -243.97921) (xy 363.004862 -243.9797) (xy 362.064808 -243.9797)
			(xy 362.039532 -243.979132) (xy 361.989669 -243.970812) (xy 361.941856 -243.954399) (xy 361.897396 -243.93034)
			(xy 361.857503 -243.899291) (xy 361.823265 -243.862099) (xy 361.795615 -243.819779) (xy 361.775308 -243.773484)
			(xy 361.762898 -243.724479) (xy 361.758723 -243.6741) (xy 109.736927 -243.6741) (xy 109.736952 -243.6744)
			(xy 109.73278 -243.724744) (xy 109.720378 -243.773715) (xy 109.700085 -243.819977) (xy 109.672453 -243.862267)
			(xy 109.638238 -243.899432) (xy 109.598371 -243.930458) (xy 109.553942 -243.954499) (xy 109.506161 -243.970898)
			(xy 109.456332 -243.979209) (xy 109.431074 -243.9797) (xy 108.49102 -243.9797) (xy 108.465761 -243.979225)
			(xy 108.41593 -243.970913) (xy 108.368148 -243.954512) (xy 108.323717 -243.930469) (xy 108.283849 -243.899442)
			(xy 108.249632 -243.862275) (xy 108.222 -243.819983) (xy 108.201706 -243.773719) (xy 108.189304 -243.724746)
			(xy 108.185132 -243.6744) (xy 2.509012 -243.6744) (xy 2.509012 -244.4844) (xy 97.374883 -244.4844)
			(xy 97.379059 -244.434011) (xy 97.391472 -244.384997) (xy 97.411784 -244.338695) (xy 97.43944 -244.296368)
			(xy 97.473686 -244.259171) (xy 97.513588 -244.228118) (xy 97.558057 -244.204057) (xy 97.605881 -244.187644)
			(xy 97.655753 -244.179326) (xy 97.681034 -244.178836) (xy 98.621088 -244.178836) (xy 98.646367 -244.179332)
			(xy 98.696236 -244.187652) (xy 98.744056 -244.204067) (xy 98.788521 -244.228129) (xy 98.82842 -244.259181)
			(xy 98.862663 -244.296378) (xy 98.890316 -244.338703) (xy 98.910626 -244.385003) (xy 98.923037 -244.434014)
			(xy 98.927213 -244.4844) (xy 100.194783 -244.4844) (xy 100.198959 -244.434011) (xy 100.211373 -244.384996)
			(xy 100.231685 -244.338693) (xy 100.259342 -244.296365) (xy 100.293589 -244.259168) (xy 100.333492 -244.228115)
			(xy 100.377963 -244.204054) (xy 100.425787 -244.187642) (xy 100.475661 -244.179326) (xy 100.500942 -244.178836)
			(xy 101.440996 -244.178836) (xy 101.466275 -244.179333) (xy 101.516143 -244.187654) (xy 101.563961 -244.204069)
			(xy 101.608426 -244.228131) (xy 101.648323 -244.259184) (xy 101.682565 -244.29638) (xy 101.710217 -244.338705)
			(xy 101.730526 -244.385005) (xy 101.742937 -244.434015) (xy 101.747113 -244.4844) (xy 103.014983 -244.4844)
			(xy 103.019159 -244.434014) (xy 103.03157 -244.385003) (xy 103.051879 -244.338704) (xy 103.079532 -244.296378)
			(xy 103.113774 -244.259181) (xy 103.153672 -244.228128) (xy 103.198137 -244.204065) (xy 103.245956 -244.18765)
			(xy 103.295825 -244.179329) (xy 103.321104 -244.178836) (xy 104.261158 -244.178836) (xy 104.286439 -244.17933)
			(xy 104.336312 -244.187646) (xy 104.384136 -244.204058) (xy 104.428605 -244.228118) (xy 104.468508 -244.259171)
			(xy 104.502755 -244.296368) (xy 104.530412 -244.338695) (xy 104.550724 -244.384997) (xy 104.563137 -244.434011)
			(xy 104.567313 -244.4844) (xy 105.834883 -244.4844) (xy 105.839059 -244.434014) (xy 105.851471 -244.385002)
			(xy 105.87178 -244.338701) (xy 105.899434 -244.296375) (xy 105.933678 -244.259178) (xy 105.973577 -244.228125)
			(xy 106.018043 -244.204063) (xy 106.065863 -244.187648) (xy 106.115732 -244.179328) (xy 106.141012 -244.178836)
			(xy 107.081066 -244.178836) (xy 107.106346 -244.17933) (xy 107.156218 -244.187647) (xy 107.204041 -244.20406)
			(xy 107.24851 -244.228121) (xy 107.288411 -244.259174) (xy 107.322657 -244.29637) (xy 107.350313 -244.338697)
			(xy 107.370624 -244.384999) (xy 107.383037 -244.434012) (xy 107.387188 -244.4841) (xy 364.108984 -244.4841)
			(xy 364.113155 -244.433763) (xy 364.125555 -244.384799) (xy 364.145845 -244.338543) (xy 364.173472 -244.296259)
			(xy 364.207683 -244.259098) (xy 364.247543 -244.228076) (xy 364.291966 -244.204037) (xy 364.33974 -244.187639)
			(xy 364.389561 -244.179327) (xy 364.414816 -244.178836) (xy 365.35487 -244.178836) (xy 365.380133 -244.179238)
			(xy 365.42997 -244.18755) (xy 365.47776 -244.203952) (xy 365.522198 -244.227997) (xy 365.562072 -244.259028)
			(xy 365.596293 -244.2962) (xy 365.62393 -244.338497) (xy 365.644227 -244.384767) (xy 365.656631 -244.433747)
			(xy 365.660804 -244.4841) (xy 366.928884 -244.4841) (xy 366.933055 -244.433762) (xy 366.945456 -244.384797)
			(xy 366.965746 -244.338541) (xy 366.993374 -244.296256) (xy 367.027586 -244.259095) (xy 367.067447 -244.228073)
			(xy 367.111871 -244.204035) (xy 367.159646 -244.187637) (xy 367.209469 -244.179327) (xy 367.234724 -244.178836)
			(xy 368.174778 -244.178836) (xy 368.200041 -244.179239) (xy 368.249877 -244.187552) (xy 368.297665 -244.203955)
			(xy 368.342102 -244.228) (xy 368.381975 -244.259031) (xy 368.416196 -244.296203) (xy 368.443831 -244.3385)
			(xy 368.464128 -244.384769) (xy 368.476531 -244.433748) (xy 368.480704 -244.4841) (xy 369.749113 -244.4841)
			(xy 369.753283 -244.433771) (xy 369.76568 -244.384814) (xy 369.785966 -244.338565) (xy 369.813587 -244.296286)
			(xy 369.847791 -244.25913) (xy 369.887643 -244.22811) (xy 369.932057 -244.204073) (xy 369.979822 -244.187673)
			(xy 370.029635 -244.179359) (xy 370.054886 -244.178836) (xy 370.99494 -244.178836) (xy 371.020197 -244.179272)
			(xy 371.070021 -244.187592) (xy 371.117796 -244.203999) (xy 371.162219 -244.228045) (xy 371.202079 -244.259074)
			(xy 371.236289 -244.296241) (xy 371.263916 -244.33853) (xy 371.284205 -244.38479) (xy 371.296604 -244.433759)
			(xy 371.300776 -244.4841) (xy 372.569013 -244.4841) (xy 372.573183 -244.43377) (xy 372.585581 -244.384812)
			(xy 372.605867 -244.338563) (xy 372.63349 -244.296284) (xy 372.667694 -244.259127) (xy 372.707547 -244.228107)
			(xy 372.751963 -244.20407) (xy 372.799729 -244.187671) (xy 372.849543 -244.179358) (xy 372.874794 -244.178836)
			(xy 373.814848 -244.178836) (xy 373.840104 -244.179273) (xy 373.889927 -244.187594) (xy 373.937701 -244.204002)
			(xy 373.982123 -244.228048) (xy 374.021982 -244.259077) (xy 374.056191 -244.296243) (xy 374.083817 -244.338533)
			(xy 374.104106 -244.384792) (xy 374.116505 -244.43376) (xy 374.120676 -244.4841) (xy 374.116505 -244.53444)
			(xy 374.104106 -244.583408) (xy 374.083817 -244.629667) (xy 374.056191 -244.671957) (xy 374.021982 -244.709123)
			(xy 373.982123 -244.740152) (xy 373.937701 -244.764198) (xy 373.889927 -244.780606) (xy 373.840104 -244.788927)
			(xy 373.814848 -244.789452) (xy 372.874794 -244.789452) (xy 372.849543 -244.788842) (xy 372.799729 -244.780529)
			(xy 372.751963 -244.76413) (xy 372.707547 -244.740093) (xy 372.667694 -244.709073) (xy 372.63349 -244.671916)
			(xy 372.605867 -244.629637) (xy 372.585581 -244.583388) (xy 372.573183 -244.53443) (xy 372.569013 -244.4841)
			(xy 371.300776 -244.4841) (xy 371.296604 -244.534441) (xy 371.284205 -244.58341) (xy 371.263915 -244.62967)
			(xy 371.236289 -244.671959) (xy 371.202079 -244.709126) (xy 371.162219 -244.740155) (xy 371.117796 -244.764201)
			(xy 371.070021 -244.780608) (xy 371.020197 -244.788928) (xy 370.99494 -244.789452) (xy 370.054886 -244.789452)
			(xy 370.029635 -244.788841) (xy 369.979822 -244.780527) (xy 369.932057 -244.764127) (xy 369.887643 -244.74009)
			(xy 369.847791 -244.70907) (xy 369.813587 -244.671914) (xy 369.785966 -244.629635) (xy 369.76568 -244.583386)
			(xy 369.753283 -244.534429) (xy 369.749113 -244.4841) (xy 368.480704 -244.4841) (xy 368.476531 -244.534452)
			(xy 368.464128 -244.583431) (xy 368.443831 -244.6297) (xy 368.416196 -244.671997) (xy 368.381975 -244.709169)
			(xy 368.342102 -244.7402) (xy 368.297665 -244.764245) (xy 368.249877 -244.780648) (xy 368.200041 -244.788961)
			(xy 368.174778 -244.789452) (xy 367.234724 -244.789452) (xy 367.209469 -244.788873) (xy 367.159646 -244.780563)
			(xy 367.111871 -244.764165) (xy 367.067447 -244.740127) (xy 367.027586 -244.709105) (xy 366.993374 -244.671944)
			(xy 366.965746 -244.629659) (xy 366.945456 -244.583403) (xy 366.933055 -244.534438) (xy 366.928884 -244.4841)
			(xy 365.660804 -244.4841) (xy 365.656631 -244.534453) (xy 365.644227 -244.583433) (xy 365.62393 -244.629703)
			(xy 365.596293 -244.672) (xy 365.562072 -244.709172) (xy 365.522198 -244.740203) (xy 365.47776 -244.764248)
			(xy 365.42997 -244.78065) (xy 365.380133 -244.788962) (xy 365.35487 -244.789452) (xy 364.414816 -244.789452)
			(xy 364.389561 -244.788873) (xy 364.33974 -244.780561) (xy 364.291966 -244.764163) (xy 364.247543 -244.740124)
			(xy 364.207683 -244.709102) (xy 364.173472 -244.671941) (xy 364.145845 -244.629657) (xy 364.125555 -244.583401)
			(xy 364.113155 -244.534437) (xy 364.108984 -244.4841) (xy 107.387188 -244.4841) (xy 107.387213 -244.4844)
			(xy 107.383037 -244.534788) (xy 107.370624 -244.583801) (xy 107.350313 -244.630103) (xy 107.322657 -244.67243)
			(xy 107.288411 -244.709626) (xy 107.24851 -244.740679) (xy 107.204041 -244.76474) (xy 107.156218 -244.781153)
			(xy 107.106346 -244.78947) (xy 107.081066 -244.78996) (xy 106.141012 -244.78996) (xy 106.115732 -244.789472)
			(xy 106.065863 -244.781152) (xy 106.018043 -244.764737) (xy 105.973577 -244.740675) (xy 105.933678 -244.709622)
			(xy 105.899434 -244.672425) (xy 105.87178 -244.630099) (xy 105.851471 -244.583798) (xy 105.839059 -244.534786)
			(xy 105.834883 -244.4844) (xy 104.567313 -244.4844) (xy 104.563137 -244.534789) (xy 104.550724 -244.583803)
			(xy 104.530412 -244.630105) (xy 104.502755 -244.672432) (xy 104.468508 -244.709629) (xy 104.428605 -244.740682)
			(xy 104.384136 -244.764742) (xy 104.336312 -244.781154) (xy 104.286439 -244.78947) (xy 104.261158 -244.78996)
			(xy 103.321104 -244.78996) (xy 103.295825 -244.789471) (xy 103.245956 -244.78115) (xy 103.198137 -244.764735)
			(xy 103.153672 -244.740672) (xy 103.113774 -244.709619) (xy 103.079532 -244.672422) (xy 103.051879 -244.630096)
			(xy 103.03157 -244.583797) (xy 103.019159 -244.534786) (xy 103.014983 -244.4844) (xy 101.747113 -244.4844)
			(xy 101.742937 -244.534785) (xy 101.730526 -244.583795) (xy 101.710217 -244.630095) (xy 101.682565 -244.67242)
			(xy 101.648323 -244.709616) (xy 101.608426 -244.740669) (xy 101.563961 -244.764731) (xy 101.516143 -244.781146)
			(xy 101.466275 -244.789467) (xy 101.440996 -244.78996) (xy 100.500942 -244.78996) (xy 100.475661 -244.789474)
			(xy 100.425787 -244.781158) (xy 100.377963 -244.764746) (xy 100.333492 -244.740685) (xy 100.293589 -244.709632)
			(xy 100.259342 -244.672435) (xy 100.231685 -244.630107) (xy 100.211373 -244.583804) (xy 100.198959 -244.534789)
			(xy 100.194783 -244.4844) (xy 98.927213 -244.4844) (xy 98.923037 -244.534786) (xy 98.910626 -244.583797)
			(xy 98.890316 -244.630097) (xy 98.862663 -244.672422) (xy 98.82842 -244.709619) (xy 98.788521 -244.740671)
			(xy 98.744056 -244.764733) (xy 98.696236 -244.781148) (xy 98.646367 -244.789468) (xy 98.621088 -244.78996)
			(xy 97.681034 -244.78996) (xy 97.655753 -244.789474) (xy 97.605881 -244.781156) (xy 97.558057 -244.764743)
			(xy 97.513588 -244.740682) (xy 97.473686 -244.709629) (xy 97.43944 -244.672432) (xy 97.411784 -244.630105)
			(xy 97.391472 -244.583803) (xy 97.379059 -244.534789) (xy 97.374883 -244.4844) (xy 2.509012 -244.4844)
			(xy 2.509012 -245.2944) (xy 108.185144 -245.2944) (xy 108.189316 -245.244056) (xy 108.201717 -245.195085)
			(xy 108.222011 -245.148823) (xy 108.249642 -245.106533) (xy 108.283857 -245.069367) (xy 108.323723 -245.038341)
			(xy 108.368153 -245.014299) (xy 108.415933 -244.997899) (xy 108.465762 -244.989587) (xy 108.49102 -244.989096)
			(xy 109.431074 -244.989096) (xy 109.456333 -244.989579) (xy 109.506164 -244.99789) (xy 109.553947 -245.01429)
			(xy 109.598378 -245.038332) (xy 109.638246 -245.069359) (xy 109.672463 -245.106526) (xy 109.700095 -245.148818)
			(xy 109.72039 -245.195081) (xy 109.732792 -245.244054) (xy 109.736939 -245.2941) (xy 361.758735 -245.2941)
			(xy 361.76291 -245.243723) (xy 361.775319 -245.194719) (xy 361.795626 -245.148427) (xy 361.823274 -245.106109)
			(xy 361.857511 -245.068918) (xy 361.897403 -245.03787) (xy 361.941861 -245.013812) (xy 361.989672 -244.997399)
			(xy 362.039533 -244.98908) (xy 362.064808 -244.988588) (xy 363.004862 -244.988588) (xy 363.030147 -244.988978)
			(xy 363.080028 -244.997296) (xy 363.127859 -245.013711) (xy 363.172336 -245.037776) (xy 363.212245 -245.068834)
			(xy 363.246497 -245.106037) (xy 363.274158 -245.148371) (xy 363.294473 -245.194681) (xy 363.306888 -245.243703)
			(xy 363.311065 -245.2941) (xy 363.306888 -245.344497) (xy 363.294473 -245.393519) (xy 363.274158 -245.439829)
			(xy 363.246497 -245.482163) (xy 363.212245 -245.519366) (xy 363.172336 -245.550424) (xy 363.127859 -245.574489)
			(xy 363.080028 -245.590904) (xy 363.030147 -245.599222) (xy 363.004862 -245.599712) (xy 362.064808 -245.599712)
			(xy 362.039533 -245.59912) (xy 361.989672 -245.590801) (xy 361.941861 -245.574388) (xy 361.897403 -245.55033)
			(xy 361.857511 -245.519282) (xy 361.823274 -245.482091) (xy 361.795626 -245.439773) (xy 361.775319 -245.393481)
			(xy 361.76291 -245.344477) (xy 361.758735 -245.2941) (xy 109.736939 -245.2941) (xy 109.736964 -245.2944)
			(xy 109.732792 -245.344746) (xy 109.72039 -245.393719) (xy 109.700095 -245.439982) (xy 109.672463 -245.482274)
			(xy 109.638246 -245.519441) (xy 109.598378 -245.550468) (xy 109.553947 -245.57451) (xy 109.506164 -245.59091)
			(xy 109.456333 -245.599221) (xy 109.431074 -245.599712) (xy 108.49102 -245.599712) (xy 108.465762 -245.599213)
			(xy 108.415933 -245.590901) (xy 108.368153 -245.574501) (xy 108.323723 -245.550459) (xy 108.283857 -245.519433)
			(xy 108.249642 -245.482267) (xy 108.222011 -245.439977) (xy 108.201717 -245.393715) (xy 108.189316 -245.344744)
			(xy 108.185144 -245.2944) (xy 2.509012 -245.2944) (xy 2.509012 -246.1044) (xy 97.374895 -246.1044)
			(xy 97.379071 -246.054013) (xy 97.391483 -246.005001) (xy 97.411794 -245.958701) (xy 97.439449 -245.916375)
			(xy 97.473694 -245.879179) (xy 97.513595 -245.848128) (xy 97.558062 -245.824068) (xy 97.605884 -245.807655)
			(xy 97.655754 -245.799338) (xy 97.681034 -245.798848) (xy 98.621088 -245.798848) (xy 98.646368 -245.79932)
			(xy 98.696239 -245.80764) (xy 98.744061 -245.824056) (xy 98.788528 -245.848119) (xy 98.828428 -245.879173)
			(xy 98.862672 -245.91637) (xy 98.890327 -245.958698) (xy 98.910637 -246.004999) (xy 98.923049 -246.054012)
			(xy 98.927225 -246.1044) (xy 100.194795 -246.1044) (xy 100.198971 -246.054012) (xy 100.211384 -246.005)
			(xy 100.231695 -245.958699) (xy 100.259351 -245.916373) (xy 100.293597 -245.879177) (xy 100.333499 -245.848125)
			(xy 100.377968 -245.824065) (xy 100.42579 -245.807654) (xy 100.475662 -245.799338) (xy 100.500942 -245.798848)
			(xy 101.440996 -245.798848) (xy 101.466276 -245.799321) (xy 101.516146 -245.807642) (xy 101.563966 -245.824058)
			(xy 101.608432 -245.848121) (xy 101.648331 -245.879175) (xy 101.682574 -245.916373) (xy 101.710228 -245.9587)
			(xy 101.730538 -246.005001) (xy 101.742949 -246.054013) (xy 101.747125 -246.1044) (xy 103.014995 -246.1044)
			(xy 103.01917 -246.054016) (xy 103.031581 -246.005007) (xy 103.05189 -245.958709) (xy 103.079542 -245.916385)
			(xy 103.113783 -245.87919) (xy 103.153679 -245.848138) (xy 103.198142 -245.824076) (xy 103.245959 -245.807661)
			(xy 103.295826 -245.799341) (xy 103.321104 -245.798848) (xy 104.261158 -245.798848) (xy 104.28644 -245.799318)
			(xy 104.336315 -245.807634) (xy 104.38414 -245.824047) (xy 104.428612 -245.848108) (xy 104.468516 -245.879162)
			(xy 104.502764 -245.91636) (xy 104.530422 -245.958689) (xy 104.550735 -246.004993) (xy 104.563149 -246.054009)
			(xy 104.567325 -246.1044) (xy 105.834895 -246.1044) (xy 105.839071 -246.054016) (xy 105.851482 -246.005006)
			(xy 105.871791 -245.958707) (xy 105.899444 -245.916383) (xy 105.933686 -245.879187) (xy 105.973583 -245.848135)
			(xy 106.018047 -245.824074) (xy 106.065866 -245.80766) (xy 106.115733 -245.79934) (xy 106.141012 -245.798848)
			(xy 107.081066 -245.798848) (xy 107.106347 -245.799318) (xy 107.156221 -245.807636) (xy 107.204046 -245.824049)
			(xy 107.248516 -245.848111) (xy 107.288419 -245.879165) (xy 107.322666 -245.916363) (xy 107.350323 -245.958691)
			(xy 107.370636 -246.004995) (xy 107.383049 -246.05401) (xy 107.387208 -246.1042) (xy 364.108896 -246.1042)
			(xy 364.113068 -246.053848) (xy 364.125472 -246.00487) (xy 364.145768 -245.958601) (xy 364.173403 -245.916305)
			(xy 364.207623 -245.879133) (xy 364.247495 -245.848102) (xy 364.291931 -245.824057) (xy 364.339718 -245.807653)
			(xy 364.389554 -245.79934) (xy 364.414816 -245.798848) (xy 365.35487 -245.798848) (xy 365.380126 -245.799426)
			(xy 365.429949 -245.807736) (xy 365.477725 -245.824133) (xy 365.52215 -245.848171) (xy 365.562012 -245.879193)
			(xy 365.596224 -245.916354) (xy 365.623853 -245.958639) (xy 365.644144 -246.004896) (xy 365.656545 -246.053861)
			(xy 365.660716 -246.1042) (xy 366.928796 -246.1042) (xy 366.932969 -246.053847) (xy 366.945372 -246.004868)
			(xy 366.965669 -245.958599) (xy 366.993305 -245.916302) (xy 367.027526 -245.879131) (xy 367.067399 -245.848099)
			(xy 367.111836 -245.824054) (xy 367.159625 -245.807652) (xy 367.209461 -245.799339) (xy 367.234724 -245.798848)
			(xy 368.174778 -245.798848) (xy 368.200033 -245.799427) (xy 368.249855 -245.807737) (xy 368.29763 -245.824135)
			(xy 368.342054 -245.848173) (xy 368.381915 -245.879196) (xy 368.416126 -245.916357) (xy 368.443754 -245.958642)
			(xy 368.464045 -246.004897) (xy 368.476445 -246.053862) (xy 368.480616 -246.1042) (xy 369.749024 -246.1042)
			(xy 369.753196 -246.053856) (xy 369.765597 -246.004885) (xy 369.785888 -245.958623) (xy 369.813518 -245.916332)
			(xy 369.847731 -245.879165) (xy 369.887595 -245.848136) (xy 369.932022 -245.824092) (xy 369.979801 -245.807687)
			(xy 370.029628 -245.79937) (xy 370.054886 -245.798848) (xy 370.99494 -245.798848) (xy 371.02019 -245.799461)
			(xy 371.069999 -245.807778) (xy 371.11776 -245.82418) (xy 371.162171 -245.848219) (xy 371.202019 -245.879239)
			(xy 371.236219 -245.916395) (xy 371.263838 -245.958673) (xy 371.284121 -246.004919) (xy 371.296517 -246.053873)
			(xy 371.300687 -246.1042) (xy 372.568924 -246.1042) (xy 372.573096 -246.053855) (xy 372.585497 -246.004884)
			(xy 372.60579 -245.958621) (xy 372.63342 -245.916329) (xy 372.667634 -245.879162) (xy 372.707499 -245.848133)
			(xy 372.751927 -245.824089) (xy 372.799707 -245.807685) (xy 372.849535 -245.79937) (xy 372.874794 -245.798848)
			(xy 373.814848 -245.798848) (xy 373.840097 -245.799461) (xy 373.889906 -245.80778) (xy 373.937666 -245.824183)
			(xy 373.982075 -245.848222) (xy 374.021923 -245.879242) (xy 374.056121 -245.916398) (xy 374.083739 -245.958675)
			(xy 374.104022 -246.004921) (xy 374.116417 -246.053874) (xy 374.120587 -246.1042) (xy 374.116417 -246.154526)
			(xy 374.104022 -246.203479) (xy 374.083739 -246.249725) (xy 374.056121 -246.292002) (xy 374.021923 -246.329158)
			(xy 373.982075 -246.360178) (xy 373.937666 -246.384217) (xy 373.889906 -246.40062) (xy 373.840097 -246.408939)
			(xy 373.814848 -246.409464) (xy 372.874794 -246.409464) (xy 372.849535 -246.40903) (xy 372.799707 -246.400715)
			(xy 372.751927 -246.384311) (xy 372.707499 -246.360267) (xy 372.667634 -246.329238) (xy 372.63342 -246.292071)
			(xy 372.60579 -246.249779) (xy 372.585497 -246.203516) (xy 372.573096 -246.154545) (xy 372.568924 -246.1042)
			(xy 371.300687 -246.1042) (xy 371.296517 -246.154527) (xy 371.284121 -246.203481) (xy 371.263838 -246.249727)
			(xy 371.236219 -246.292005) (xy 371.202019 -246.329161) (xy 371.162171 -246.360181) (xy 371.11776 -246.38422)
			(xy 371.069999 -246.400622) (xy 371.02019 -246.408939) (xy 370.99494 -246.409464) (xy 370.054886 -246.409464)
			(xy 370.029628 -246.40903) (xy 369.979801 -246.400713) (xy 369.932022 -246.384308) (xy 369.887595 -246.360264)
			(xy 369.847731 -246.329235) (xy 369.813518 -246.292068) (xy 369.785888 -246.249777) (xy 369.765597 -246.203515)
			(xy 369.753196 -246.154544) (xy 369.749024 -246.1042) (xy 368.480616 -246.1042) (xy 368.476445 -246.154538)
			(xy 368.464045 -246.203503) (xy 368.443754 -246.249758) (xy 368.416126 -246.292043) (xy 368.381915 -246.329204)
			(xy 368.342054 -246.360227) (xy 368.29763 -246.384265) (xy 368.249855 -246.400663) (xy 368.200033 -246.408973)
			(xy 368.174778 -246.409464) (xy 367.234724 -246.409464) (xy 367.209461 -246.409061) (xy 367.159625 -246.400748)
			(xy 367.111836 -246.384346) (xy 367.067399 -246.360301) (xy 367.027526 -246.329269) (xy 366.993305 -246.292098)
			(xy 366.965669 -246.249801) (xy 366.945372 -246.203532) (xy 366.932969 -246.154553) (xy 366.928796 -246.1042)
			(xy 365.660716 -246.1042) (xy 365.656545 -246.154539) (xy 365.644144 -246.203504) (xy 365.623853 -246.249761)
			(xy 365.596224 -246.292046) (xy 365.562012 -246.329207) (xy 365.52215 -246.360229) (xy 365.477725 -246.384267)
			(xy 365.429949 -246.400664) (xy 365.380126 -246.408974) (xy 365.35487 -246.409464) (xy 364.414816 -246.409464)
			(xy 364.389554 -246.40906) (xy 364.339718 -246.400747) (xy 364.291931 -246.384343) (xy 364.247495 -246.360298)
			(xy 364.207623 -246.329267) (xy 364.173403 -246.292095) (xy 364.145768 -246.249799) (xy 364.125472 -246.20353)
			(xy 364.113068 -246.154552) (xy 364.108896 -246.1042) (xy 107.387208 -246.1042) (xy 107.387225 -246.1044)
			(xy 107.383049 -246.15479) (xy 107.370636 -246.203805) (xy 107.350323 -246.250109) (xy 107.322666 -246.292437)
			(xy 107.288419 -246.329635) (xy 107.248516 -246.360689) (xy 107.204046 -246.384751) (xy 107.156221 -246.401164)
			(xy 107.106347 -246.409482) (xy 107.081066 -246.409972) (xy 106.141012 -246.409972) (xy 106.115733 -246.40946)
			(xy 106.065866 -246.40114) (xy 106.018047 -246.384726) (xy 105.973583 -246.360665) (xy 105.933686 -246.329613)
			(xy 105.899444 -246.292417) (xy 105.871791 -246.250093) (xy 105.851482 -246.203794) (xy 105.839071 -246.154784)
			(xy 105.834895 -246.1044) (xy 104.567325 -246.1044) (xy 104.563149 -246.154791) (xy 104.550735 -246.203807)
			(xy 104.530422 -246.250111) (xy 104.502764 -246.29244) (xy 104.468516 -246.329638) (xy 104.428612 -246.360692)
			(xy 104.38414 -246.384753) (xy 104.336315 -246.401166) (xy 104.28644 -246.409482) (xy 104.261158 -246.409972)
			(xy 103.321104 -246.409972) (xy 103.295826 -246.409459) (xy 103.245959 -246.401139) (xy 103.198142 -246.384724)
			(xy 103.153679 -246.360662) (xy 103.113783 -246.32961) (xy 103.079542 -246.292415) (xy 103.05189 -246.250091)
			(xy 103.031581 -246.203793) (xy 103.01917 -246.154784) (xy 103.014995 -246.1044) (xy 101.747125 -246.1044)
			(xy 101.742949 -246.154787) (xy 101.730538 -246.203799) (xy 101.710228 -246.2501) (xy 101.682574 -246.292427)
			(xy 101.648331 -246.329625) (xy 101.608432 -246.360679) (xy 101.563966 -246.384742) (xy 101.516146 -246.401158)
			(xy 101.466276 -246.409479) (xy 101.440996 -246.409972) (xy 100.500942 -246.409972) (xy 100.475662 -246.409462)
			(xy 100.42579 -246.401146) (xy 100.377968 -246.384735) (xy 100.333499 -246.360675) (xy 100.293597 -246.329623)
			(xy 100.259351 -246.292427) (xy 100.231695 -246.250101) (xy 100.211384 -246.2038) (xy 100.198971 -246.154788)
			(xy 100.194795 -246.1044) (xy 98.927225 -246.1044) (xy 98.923049 -246.154788) (xy 98.910637 -246.203801)
			(xy 98.890327 -246.250102) (xy 98.862672 -246.29243) (xy 98.828428 -246.329627) (xy 98.788528 -246.360681)
			(xy 98.744061 -246.384744) (xy 98.696239 -246.40116) (xy 98.646368 -246.40948) (xy 98.621088 -246.409972)
			(xy 97.681034 -246.409972) (xy 97.655754 -246.409462) (xy 97.605884 -246.401145) (xy 97.558062 -246.384732)
			(xy 97.513595 -246.360672) (xy 97.473694 -246.329621) (xy 97.439449 -246.292425) (xy 97.411794 -246.250099)
			(xy 97.391483 -246.203799) (xy 97.379071 -246.154787) (xy 97.374895 -246.1044) (xy 2.509012 -246.1044)
			(xy 2.509012 -246.9144) (xy 108.185156 -246.9144) (xy 108.189328 -246.864058) (xy 108.201729 -246.815089)
			(xy 108.222021 -246.768829) (xy 108.249651 -246.72654) (xy 108.283865 -246.689376) (xy 108.32373 -246.658351)
			(xy 108.368157 -246.63431) (xy 108.415936 -246.617911) (xy 108.465763 -246.609599) (xy 108.49102 -246.609108)
			(xy 109.431074 -246.609108) (xy 109.456334 -246.609567) (xy 109.506167 -246.617878) (xy 109.553951 -246.634279)
			(xy 109.598385 -246.658322) (xy 109.638254 -246.68935) (xy 109.672472 -246.726518) (xy 109.700106 -246.768812)
			(xy 109.720401 -246.815077) (xy 109.732804 -246.864052) (xy 109.736959 -246.9142) (xy 361.758647 -246.9142)
			(xy 361.762823 -246.863808) (xy 361.775236 -246.814791) (xy 361.795548 -246.768485) (xy 361.823205 -246.726155)
			(xy 361.857452 -246.688953) (xy 361.897355 -246.657897) (xy 361.941825 -246.633831) (xy 361.989651 -246.617414)
			(xy 362.039526 -246.609093) (xy 362.064808 -246.6086) (xy 363.004862 -246.6086) (xy 363.03014 -246.609166)
			(xy 363.080006 -246.617481) (xy 363.127824 -246.633892) (xy 363.172288 -246.65795) (xy 363.212185 -246.688999)
			(xy 363.246428 -246.726191) (xy 363.274081 -246.768513) (xy 363.29439 -246.81481) (xy 363.306801 -246.863818)
			(xy 363.310977 -246.9142) (xy 363.306801 -246.964582) (xy 363.29439 -247.01359) (xy 363.274081 -247.059887)
			(xy 363.246428 -247.102209) (xy 363.212185 -247.139401) (xy 363.172288 -247.17045) (xy 363.127824 -247.194508)
			(xy 363.080006 -247.210919) (xy 363.03014 -247.219234) (xy 363.004862 -247.219724) (xy 362.064808 -247.219724)
			(xy 362.039526 -247.219307) (xy 361.989651 -247.210986) (xy 361.941825 -247.194569) (xy 361.897355 -247.170503)
			(xy 361.857452 -247.139447) (xy 361.823205 -247.102245) (xy 361.795548 -247.059915) (xy 361.775236 -247.013609)
			(xy 361.762823 -246.964592) (xy 361.758647 -246.9142) (xy 109.736959 -246.9142) (xy 109.736976 -246.9144)
			(xy 109.732804 -246.964748) (xy 109.720401 -247.013723) (xy 109.700106 -247.059988) (xy 109.672472 -247.102282)
			(xy 109.638254 -247.13945) (xy 109.598385 -247.170478) (xy 109.553951 -247.194521) (xy 109.506167 -247.210922)
			(xy 109.456334 -247.219233) (xy 109.431074 -247.219724) (xy 108.49102 -247.219724) (xy 108.465763 -247.219201)
			(xy 108.415936 -247.210889) (xy 108.368157 -247.19449) (xy 108.32373 -247.170449) (xy 108.283865 -247.139424)
			(xy 108.249651 -247.10226) (xy 108.222021 -247.059971) (xy 108.201729 -247.013711) (xy 108.189328 -246.964742)
			(xy 108.185156 -246.9144) (xy 2.509012 -246.9144) (xy 2.509012 -247.7244) (xy 97.374907 -247.7244)
			(xy 97.379083 -247.674015) (xy 97.391495 -247.625005) (xy 97.411805 -247.578707) (xy 97.439459 -247.536383)
			(xy 97.473702 -247.499188) (xy 97.513601 -247.468138) (xy 97.558067 -247.444079) (xy 97.605887 -247.427667)
			(xy 97.655755 -247.41935) (xy 97.681034 -247.41886) (xy 98.621088 -247.41886) (xy 98.646369 -247.419308)
			(xy 98.696242 -247.427629) (xy 98.744066 -247.444045) (xy 98.788534 -247.468109) (xy 98.828436 -247.499164)
			(xy 98.862682 -247.536363) (xy 98.890337 -247.578692) (xy 98.910648 -247.624995) (xy 98.923061 -247.67401)
			(xy 98.927237 -247.7244) (xy 100.194807 -247.7244) (xy 100.198983 -247.674014) (xy 100.211395 -247.625004)
			(xy 100.231706 -247.578704) (xy 100.259361 -247.53638) (xy 100.293605 -247.499185) (xy 100.333506 -247.468135)
			(xy 100.377972 -247.444076) (xy 100.425793 -247.427665) (xy 100.475663 -247.41935) (xy 100.500942 -247.41886)
			(xy 101.440996 -247.41886) (xy 101.466277 -247.419309) (xy 101.516149 -247.42763) (xy 101.563971 -247.444047)
			(xy 101.608439 -247.468111) (xy 101.648339 -247.499167) (xy 101.682584 -247.536366) (xy 101.710238 -247.578694)
			(xy 101.730549 -247.624997) (xy 101.742961 -247.674011) (xy 101.747137 -247.7244) (xy 103.015007 -247.7244)
			(xy 103.019182 -247.674018) (xy 103.031593 -247.625011) (xy 103.0519 -247.578715) (xy 103.079551 -247.536393)
			(xy 103.113791 -247.499199) (xy 103.153685 -247.468148) (xy 103.198147 -247.444087) (xy 103.245962 -247.427673)
			(xy 103.295827 -247.419353) (xy 103.321104 -247.41886) (xy 104.261158 -247.41886) (xy 104.286441 -247.419306)
			(xy 104.336318 -247.427622) (xy 104.384145 -247.444036) (xy 104.428619 -247.468098) (xy 104.468524 -247.499153)
			(xy 104.502774 -247.536353) (xy 104.530433 -247.578683) (xy 104.550746 -247.624989) (xy 104.56316 -247.674007)
			(xy 104.567337 -247.7244) (xy 105.834907 -247.7244) (xy 105.839082 -247.674018) (xy 105.851493 -247.62501)
			(xy 105.871801 -247.578713) (xy 105.899453 -247.53639) (xy 105.933694 -247.499196) (xy 105.97359 -247.468145)
			(xy 106.018052 -247.444085) (xy 106.065869 -247.427671) (xy 106.115734 -247.419352) (xy 106.141012 -247.41886)
			(xy 107.081066 -247.41886) (xy 107.106348 -247.419306) (xy 107.156224 -247.427624) (xy 107.204051 -247.444038)
			(xy 107.248523 -247.468101) (xy 107.288427 -247.499156) (xy 107.322676 -247.536356) (xy 107.350334 -247.578686)
			(xy 107.370647 -247.624991) (xy 107.383061 -247.674008) (xy 107.38722 -247.7242) (xy 364.108908 -247.7242)
			(xy 364.11308 -247.67385) (xy 364.125483 -247.624874) (xy 364.145778 -247.578607) (xy 364.173412 -247.536312)
			(xy 364.207631 -247.499142) (xy 364.247501 -247.468112) (xy 364.291935 -247.444068) (xy 364.339721 -247.427665)
			(xy 364.389555 -247.419352) (xy 364.414816 -247.41886) (xy 365.35487 -247.41886) (xy 365.380127 -247.419414)
			(xy 365.429952 -247.427724) (xy 365.477729 -247.444122) (xy 365.522156 -247.468161) (xy 365.56202 -247.499184)
			(xy 365.596233 -247.536347) (xy 365.623863 -247.578634) (xy 365.644155 -247.624892) (xy 365.656556 -247.673859)
			(xy 365.660728 -247.7242) (xy 366.928808 -247.7242) (xy 366.93298 -247.673849) (xy 366.945384 -247.624872)
			(xy 366.96568 -247.578605) (xy 366.993314 -247.536309) (xy 367.027534 -247.499139) (xy 367.067406 -247.468109)
			(xy 367.111841 -247.444065) (xy 367.159628 -247.427663) (xy 367.209462 -247.419351) (xy 367.234724 -247.41886)
			(xy 368.174778 -247.41886) (xy 368.200034 -247.419415) (xy 368.249858 -247.427726) (xy 368.297635 -247.444124)
			(xy 368.34206 -247.468163) (xy 368.381923 -247.499187) (xy 368.416136 -247.536349) (xy 368.443764 -247.578636)
			(xy 368.464056 -247.624893) (xy 368.476457 -247.67386) (xy 368.480628 -247.7242) (xy 369.749037 -247.7242)
			(xy 369.753208 -247.673858) (xy 369.765609 -247.624889) (xy 369.785899 -247.578629) (xy 369.813527 -247.53634)
			(xy 369.847739 -247.499174) (xy 369.887601 -247.468147) (xy 369.932027 -247.444103) (xy 369.979804 -247.427699)
			(xy 370.029629 -247.419383) (xy 370.054886 -247.41886) (xy 370.99494 -247.41886) (xy 371.020191 -247.419449)
			(xy 371.070002 -247.427767) (xy 371.117765 -247.444169) (xy 371.162177 -247.468209) (xy 371.202028 -247.499231)
			(xy 371.236229 -247.536388) (xy 371.263848 -247.578667) (xy 371.284133 -247.624915) (xy 371.296529 -247.673871)
			(xy 371.300699 -247.7242) (xy 372.568937 -247.7242) (xy 372.573108 -247.673857) (xy 372.585509 -247.624888)
			(xy 372.605801 -247.578627) (xy 372.63343 -247.536337) (xy 372.667642 -247.499171) (xy 372.707506 -247.468144)
			(xy 372.751932 -247.444101) (xy 372.79971 -247.427698) (xy 372.849536 -247.419382) (xy 372.874794 -247.41886)
			(xy 373.814848 -247.41886) (xy 373.840098 -247.419449) (xy 373.889908 -247.427768) (xy 373.93767 -247.444172)
			(xy 373.982082 -247.468212) (xy 374.021931 -247.499233) (xy 374.056131 -247.53639) (xy 374.083749 -247.578669)
			(xy 374.104033 -247.624917) (xy 374.116429 -247.673872) (xy 374.120599 -247.7242) (xy 374.116429 -247.774528)
			(xy 374.104033 -247.823483) (xy 374.083749 -247.869731) (xy 374.056131 -247.91201) (xy 374.021931 -247.949166)
			(xy 373.982082 -247.980188) (xy 373.937671 -248.004228) (xy 373.889908 -248.020632) (xy 373.840098 -248.028951)
			(xy 373.814848 -248.029476) (xy 372.874794 -248.029476) (xy 372.849536 -248.029018) (xy 372.79971 -248.020702)
			(xy 372.751932 -248.004299) (xy 372.707506 -247.980256) (xy 372.667642 -247.949229) (xy 372.63343 -247.912063)
			(xy 372.605801 -247.869773) (xy 372.585509 -247.823512) (xy 372.573108 -247.774543) (xy 372.568937 -247.7242)
			(xy 371.300699 -247.7242) (xy 371.296529 -247.774529) (xy 371.284133 -247.823485) (xy 371.263848 -247.869733)
			(xy 371.236229 -247.912012) (xy 371.202028 -247.949169) (xy 371.162177 -247.980191) (xy 371.117765 -248.004231)
			(xy 371.070002 -248.020633) (xy 371.020191 -248.028951) (xy 370.99494 -248.029476) (xy 370.054886 -248.029476)
			(xy 370.029629 -248.029017) (xy 369.979804 -248.020701) (xy 369.932027 -248.004297) (xy 369.887601 -247.980253)
			(xy 369.847739 -247.949226) (xy 369.813527 -247.91206) (xy 369.785899 -247.869771) (xy 369.765609 -247.823511)
			(xy 369.753208 -247.774542) (xy 369.749037 -247.7242) (xy 368.480628 -247.7242) (xy 368.476457 -247.77454)
			(xy 368.464056 -247.823507) (xy 368.443764 -247.869764) (xy 368.416136 -247.912051) (xy 368.381923 -247.949213)
			(xy 368.34206 -247.980237) (xy 368.297635 -248.004276) (xy 368.249858 -248.020674) (xy 368.200034 -248.028985)
			(xy 368.174778 -248.029476) (xy 367.234724 -248.029476) (xy 367.209462 -248.029049) (xy 367.159628 -248.020737)
			(xy 367.111841 -248.004335) (xy 367.067406 -247.980291) (xy 367.027534 -247.949261) (xy 366.993314 -247.912091)
			(xy 366.96568 -247.869795) (xy 366.945384 -247.823528) (xy 366.93298 -247.774551) (xy 366.928808 -247.7242)
			(xy 365.660728 -247.7242) (xy 365.656556 -247.774541) (xy 365.644155 -247.823508) (xy 365.623863 -247.869766)
			(xy 365.596233 -247.912053) (xy 365.56202 -247.949216) (xy 365.522156 -247.980239) (xy 365.477729 -248.004278)
			(xy 365.429952 -248.020676) (xy 365.380127 -248.028986) (xy 365.35487 -248.029476) (xy 364.414816 -248.029476)
			(xy 364.389555 -248.029048) (xy 364.339721 -248.020735) (xy 364.291935 -248.004332) (xy 364.247501 -247.980288)
			(xy 364.207631 -247.949258) (xy 364.173412 -247.912088) (xy 364.145778 -247.869793) (xy 364.125483 -247.823526)
			(xy 364.11308 -247.77455) (xy 364.108908 -247.7242) (xy 107.38722 -247.7242) (xy 107.387237 -247.7244)
			(xy 107.383061 -247.774792) (xy 107.370647 -247.823809) (xy 107.350334 -247.870114) (xy 107.322676 -247.912444)
			(xy 107.288427 -247.949644) (xy 107.248523 -247.980699) (xy 107.204051 -248.004762) (xy 107.156224 -248.021176)
			(xy 107.106348 -248.029494) (xy 107.081066 -248.029984) (xy 106.141012 -248.029984) (xy 106.115734 -248.029448)
			(xy 106.065869 -248.021129) (xy 106.018052 -248.004715) (xy 105.97359 -247.980655) (xy 105.933694 -247.949604)
			(xy 105.899453 -247.91241) (xy 105.871801 -247.870087) (xy 105.851493 -247.82379) (xy 105.839082 -247.774782)
			(xy 105.834907 -247.7244) (xy 104.567337 -247.7244) (xy 104.56316 -247.774793) (xy 104.550746 -247.823811)
			(xy 104.530433 -247.870117) (xy 104.502774 -247.912447) (xy 104.468524 -247.949647) (xy 104.428619 -247.980702)
			(xy 104.384145 -248.004764) (xy 104.336318 -248.021178) (xy 104.286441 -248.029494) (xy 104.261158 -248.029984)
			(xy 103.321104 -248.029984) (xy 103.295827 -248.029447) (xy 103.245962 -248.021127) (xy 103.198147 -248.004713)
			(xy 103.153685 -247.980652) (xy 103.113791 -247.949601) (xy 103.079551 -247.912407) (xy 103.0519 -247.870085)
			(xy 103.031593 -247.823789) (xy 103.019182 -247.774782) (xy 103.015007 -247.7244) (xy 101.747137 -247.7244)
			(xy 101.742961 -247.774789) (xy 101.730549 -247.823803) (xy 101.710238 -247.870106) (xy 101.682584 -247.912434)
			(xy 101.648339 -247.949633) (xy 101.608439 -247.980689) (xy 101.563971 -248.004753) (xy 101.516149 -248.02117)
			(xy 101.466277 -248.029491) (xy 101.440996 -248.029984) (xy 100.500942 -248.029984) (xy 100.475663 -248.02945)
			(xy 100.425793 -248.021135) (xy 100.377972 -248.004724) (xy 100.333506 -247.980665) (xy 100.293605 -247.949615)
			(xy 100.259361 -247.91242) (xy 100.231706 -247.870096) (xy 100.211395 -247.823796) (xy 100.198983 -247.774786)
			(xy 100.194807 -247.7244) (xy 98.927237 -247.7244) (xy 98.923061 -247.77479) (xy 98.910648 -247.823805)
			(xy 98.890337 -247.870108) (xy 98.862682 -247.912437) (xy 98.828436 -247.949636) (xy 98.788534 -247.980691)
			(xy 98.744066 -248.004755) (xy 98.696242 -248.021171) (xy 98.646369 -248.029492) (xy 98.621088 -248.029984)
			(xy 97.681034 -248.029984) (xy 97.655755 -248.02945) (xy 97.605887 -248.021133) (xy 97.558067 -248.004721)
			(xy 97.513601 -247.980662) (xy 97.473702 -247.949612) (xy 97.439459 -247.912417) (xy 97.411805 -247.870093)
			(xy 97.391495 -247.823795) (xy 97.379083 -247.774785) (xy 97.374907 -247.7244) (xy 2.509012 -247.7244)
			(xy 2.509012 -248.5344) (xy 108.185168 -248.5344) (xy 108.189339 -248.48406) (xy 108.20174 -248.435093)
			(xy 108.222032 -248.388834) (xy 108.249661 -248.346547) (xy 108.283873 -248.309385) (xy 108.323736 -248.278361)
			(xy 108.368162 -248.254321) (xy 108.415939 -248.237922) (xy 108.465764 -248.229611) (xy 108.49102 -248.22912)
			(xy 109.431074 -248.22912) (xy 109.456335 -248.229555) (xy 109.50617 -248.237867) (xy 109.553956 -248.254268)
			(xy 109.598391 -248.278312) (xy 109.638262 -248.309342) (xy 109.672482 -248.346511) (xy 109.700117 -248.388806)
			(xy 109.720412 -248.435073) (xy 109.732816 -248.48405) (xy 109.736971 -248.5342) (xy 361.758659 -248.5342)
			(xy 361.762835 -248.48381) (xy 361.775248 -248.434795) (xy 361.795559 -248.388491) (xy 361.823214 -248.346162)
			(xy 361.85746 -248.308962) (xy 361.897361 -248.277907) (xy 361.94183 -248.253842) (xy 361.989653 -248.237426)
			(xy 362.039527 -248.229104) (xy 362.064808 -248.228612) (xy 363.004862 -248.228612) (xy 363.030141 -248.229154)
			(xy 363.080009 -248.23747) (xy 363.127829 -248.253881) (xy 363.172294 -248.27794) (xy 363.212193 -248.30899)
			(xy 363.246437 -248.346184) (xy 363.274091 -248.388507) (xy 363.294401 -248.434806) (xy 363.306813 -248.483816)
			(xy 363.310989 -248.5342) (xy 363.306813 -248.584584) (xy 363.294401 -248.633594) (xy 363.274091 -248.679893)
			(xy 363.246437 -248.722216) (xy 363.212193 -248.75941) (xy 363.172294 -248.79046) (xy 363.127829 -248.814519)
			(xy 363.080009 -248.83093) (xy 363.030141 -248.839246) (xy 363.004862 -248.839736) (xy 362.064808 -248.839736)
			(xy 362.039527 -248.839296) (xy 361.989653 -248.830974) (xy 361.94183 -248.814558) (xy 361.897361 -248.790493)
			(xy 361.85746 -248.759438) (xy 361.823214 -248.722238) (xy 361.795559 -248.679909) (xy 361.775248 -248.633605)
			(xy 361.762835 -248.58459) (xy 361.758659 -248.5342) (xy 109.736971 -248.5342) (xy 109.736988 -248.5344)
			(xy 109.732816 -248.58475) (xy 109.720412 -248.633727) (xy 109.700117 -248.679994) (xy 109.672482 -248.722289)
			(xy 109.638262 -248.759458) (xy 109.598391 -248.790488) (xy 109.553956 -248.814532) (xy 109.50617 -248.830933)
			(xy 109.456335 -248.839245) (xy 109.431074 -248.839736) (xy 108.49102 -248.839736) (xy 108.465764 -248.839189)
			(xy 108.415939 -248.830878) (xy 108.368162 -248.814479) (xy 108.323736 -248.790439) (xy 108.283873 -248.759415)
			(xy 108.249661 -248.722253) (xy 108.222032 -248.679966) (xy 108.20174 -248.633707) (xy 108.189339 -248.58474)
			(xy 108.185168 -248.5344) (xy 2.509012 -248.5344) (xy 2.509012 -258.880356) (xy 67.312036 -258.880356)
			(xy 67.316066 -258.738021) (xy 67.328141 -258.596141) (xy 67.348224 -258.455173) (xy 67.376251 -258.315566)
			(xy 67.412131 -258.177768) (xy 67.455749 -258.042221) (xy 67.506966 -257.909359) (xy 67.565617 -257.779607)
			(xy 67.631515 -257.653381) (xy 67.704449 -257.531085) (xy 67.784186 -257.413112) (xy 67.870468 -257.299839)
			(xy 67.963021 -257.191628) (xy 68.061548 -257.088827) (xy 68.165733 -256.991765) (xy 68.275242 -256.900753)
			(xy 68.389725 -256.816081) (xy 68.508815 -256.738023) (xy 68.63213 -256.666827) (xy 68.759276 -256.602721)
			(xy 68.889845 -256.545912) (xy 69.023419 -256.49658) (xy 69.15957 -256.454884) (xy 69.297861 -256.420958)
			(xy 69.437851 -256.39491) (xy 69.57909 -256.376824) (xy 69.721126 -256.366757) (xy 69.863504 -256.364742)
			(xy 70.005768 -256.370785) (xy 70.147462 -256.384867) (xy 70.288132 -256.406943) (xy 70.427329 -256.436943)
			(xy 70.564605 -256.474769) (xy 70.699521 -256.520301) (xy 70.831645 -256.573392) (xy 70.960554 -256.633874)
			(xy 71.085835 -256.701552) (xy 71.207086 -256.776209) (xy 71.323919 -256.857607) (xy 71.43596 -256.945484)
			(xy 71.54285 -257.039559) (xy 71.644247 -257.139531) (xy 71.739825 -257.245079) (xy 71.829279 -257.355865)
			(xy 71.912321 -257.471534) (xy 71.988687 -257.591717) (xy 72.058131 -257.716027) (xy 72.120431 -257.844068)
			(xy 72.175387 -257.975427) (xy 72.222824 -258.109686) (xy 72.262588 -258.246413) (xy 72.294554 -258.385171)
			(xy 72.318619 -258.525515) (xy 72.334705 -258.666996) (xy 72.34276 -258.80916) (xy 72.343264 -258.880356)
			(xy 151.51202 -258.880356) (xy 151.51605 -258.738021) (xy 151.528125 -258.596141) (xy 151.548208 -258.455173)
			(xy 151.576235 -258.315566) (xy 151.612115 -258.177768) (xy 151.655733 -258.042221) (xy 151.70695 -257.909359)
			(xy 151.765601 -257.779607) (xy 151.831499 -257.653381) (xy 151.904433 -257.531085) (xy 151.98417 -257.413112)
			(xy 152.070452 -257.299839) (xy 152.163005 -257.191628) (xy 152.261532 -257.088827) (xy 152.365717 -256.991765)
			(xy 152.475226 -256.900753) (xy 152.589709 -256.816081) (xy 152.708799 -256.738023) (xy 152.832114 -256.666827)
			(xy 152.95926 -256.602721) (xy 153.089829 -256.545912) (xy 153.223403 -256.49658) (xy 153.359554 -256.454884)
			(xy 153.497845 -256.420958) (xy 153.637835 -256.39491) (xy 153.779074 -256.376824) (xy 153.92111 -256.366757)
			(xy 154.063488 -256.364742) (xy 154.205752 -256.370785) (xy 154.347446 -256.384867) (xy 154.488116 -256.406943)
			(xy 154.627313 -256.436943) (xy 154.764589 -256.474769) (xy 154.899505 -256.520301) (xy 155.031629 -256.573392)
			(xy 155.160538 -256.633874) (xy 155.285819 -256.701552) (xy 155.40707 -256.776209) (xy 155.523903 -256.857607)
			(xy 155.635944 -256.945484) (xy 155.742834 -257.039559) (xy 155.844231 -257.139531) (xy 155.939809 -257.245079)
			(xy 156.029263 -257.355865) (xy 156.112305 -257.471534) (xy 156.188671 -257.591717) (xy 156.258115 -257.716027)
			(xy 156.320415 -257.844068) (xy 156.375371 -257.975427) (xy 156.422808 -258.109686) (xy 156.462572 -258.246413)
			(xy 156.494538 -258.385171) (xy 156.518603 -258.525515) (xy 156.534689 -258.666996) (xy 156.542744 -258.80916)
			(xy 156.543246 -258.880102) (xy 315.252104 -258.880102) (xy 315.256134 -258.737767) (xy 315.268209 -258.595887)
			(xy 315.288292 -258.454919) (xy 315.316319 -258.315312) (xy 315.352199 -258.177514) (xy 315.395817 -258.041967)
			(xy 315.447034 -257.909105) (xy 315.505685 -257.779353) (xy 315.571583 -257.653127) (xy 315.644517 -257.530831)
			(xy 315.724254 -257.412858) (xy 315.810536 -257.299585) (xy 315.903089 -257.191374) (xy 316.001616 -257.088573)
			(xy 316.105801 -256.991511) (xy 316.21531 -256.900499) (xy 316.329793 -256.815827) (xy 316.448883 -256.737769)
			(xy 316.572198 -256.666573) (xy 316.699344 -256.602467) (xy 316.829913 -256.545658) (xy 316.963487 -256.496326)
			(xy 317.099638 -256.45463) (xy 317.237929 -256.420704) (xy 317.377919 -256.394656) (xy 317.519158 -256.37657)
			(xy 317.661194 -256.366503) (xy 317.803572 -256.364488) (xy 317.945836 -256.370531) (xy 318.08753 -256.384613)
			(xy 318.2282 -256.406689) (xy 318.367397 -256.436689) (xy 318.504673 -256.474515) (xy 318.639589 -256.520047)
			(xy 318.771713 -256.573138) (xy 318.900622 -256.63362) (xy 319.025903 -256.701298) (xy 319.147154 -256.775955)
			(xy 319.263987 -256.857353) (xy 319.376028 -256.94523) (xy 319.482918 -257.039305) (xy 319.584315 -257.139277)
			(xy 319.679893 -257.244825) (xy 319.769347 -257.355611) (xy 319.852389 -257.47128) (xy 319.928755 -257.591463)
			(xy 319.998199 -257.715773) (xy 320.060499 -257.843814) (xy 320.115455 -257.975173) (xy 320.162892 -258.109432)
			(xy 320.202656 -258.246159) (xy 320.234622 -258.384917) (xy 320.258687 -258.525261) (xy 320.274773 -258.666742)
			(xy 320.282828 -258.808906) (xy 320.283332 -258.880102) (xy 399.452088 -258.880102) (xy 399.456118 -258.737767)
			(xy 399.468193 -258.595887) (xy 399.488276 -258.454919) (xy 399.516303 -258.315312) (xy 399.552183 -258.177514)
			(xy 399.595801 -258.041967) (xy 399.647018 -257.909105) (xy 399.705669 -257.779353) (xy 399.771567 -257.653127)
			(xy 399.844501 -257.530831) (xy 399.924238 -257.412858) (xy 400.01052 -257.299585) (xy 400.103073 -257.191374)
			(xy 400.2016 -257.088573) (xy 400.305785 -256.991511) (xy 400.415294 -256.900499) (xy 400.529777 -256.815827)
			(xy 400.648867 -256.737769) (xy 400.772182 -256.666573) (xy 400.899328 -256.602467) (xy 401.029897 -256.545658)
			(xy 401.163471 -256.496326) (xy 401.299622 -256.45463) (xy 401.437913 -256.420704) (xy 401.577903 -256.394656)
			(xy 401.719142 -256.37657) (xy 401.861178 -256.366503) (xy 402.003556 -256.364488) (xy 402.14582 -256.370531)
			(xy 402.287514 -256.384613) (xy 402.428184 -256.406689) (xy 402.567381 -256.436689) (xy 402.704657 -256.474515)
			(xy 402.839573 -256.520047) (xy 402.971697 -256.573138) (xy 403.100606 -256.63362) (xy 403.225887 -256.701298)
			(xy 403.347138 -256.775955) (xy 403.463971 -256.857353) (xy 403.576012 -256.94523) (xy 403.682902 -257.039305)
			(xy 403.784299 -257.139277) (xy 403.879877 -257.244825) (xy 403.969331 -257.355611) (xy 404.052373 -257.47128)
			(xy 404.128739 -257.591463) (xy 404.198183 -257.715773) (xy 404.260483 -257.843814) (xy 404.315439 -257.975173)
			(xy 404.362876 -258.109432) (xy 404.40264 -258.246159) (xy 404.434606 -258.384917) (xy 404.458671 -258.525261)
			(xy 404.474757 -258.666742) (xy 404.482812 -258.808906) (xy 404.483316 -258.880102) (xy 404.482812 -258.951298)
			(xy 404.474757 -259.093462) (xy 404.458671 -259.234943) (xy 404.434606 -259.375287) (xy 404.40264 -259.514045)
			(xy 404.362876 -259.650772) (xy 404.315439 -259.785031) (xy 404.260483 -259.91639) (xy 404.198183 -260.044431)
			(xy 404.128739 -260.168741) (xy 404.052373 -260.288924) (xy 403.969331 -260.404593) (xy 403.879877 -260.515379)
			(xy 403.784299 -260.620927) (xy 403.682902 -260.720899) (xy 403.576012 -260.814974) (xy 403.463971 -260.902851)
			(xy 403.347138 -260.984249) (xy 403.225887 -261.058906) (xy 403.100606 -261.126584) (xy 402.971697 -261.187066)
			(xy 402.839573 -261.240157) (xy 402.704657 -261.285689) (xy 402.567381 -261.323515) (xy 402.428184 -261.353515)
			(xy 402.287514 -261.375591) (xy 402.14582 -261.389673) (xy 402.003556 -261.395716) (xy 401.861178 -261.393701)
			(xy 401.719142 -261.383634) (xy 401.577903 -261.365548) (xy 401.437913 -261.3395) (xy 401.299622 -261.305574)
			(xy 401.163471 -261.263878) (xy 401.029897 -261.214546) (xy 400.899328 -261.157737) (xy 400.772182 -261.093631)
			(xy 400.648867 -261.022435) (xy 400.529777 -260.944377) (xy 400.415294 -260.859705) (xy 400.305785 -260.768693)
			(xy 400.2016 -260.671631) (xy 400.103073 -260.56883) (xy 400.01052 -260.460619) (xy 399.924238 -260.347346)
			(xy 399.844501 -260.229373) (xy 399.771567 -260.107077) (xy 399.705669 -259.980851) (xy 399.647018 -259.851099)
			(xy 399.595801 -259.718237) (xy 399.552183 -259.58269) (xy 399.516303 -259.444892) (xy 399.488276 -259.305285)
			(xy 399.468193 -259.164317) (xy 399.456118 -259.022437) (xy 399.452088 -258.880102) (xy 320.283332 -258.880102)
			(xy 320.282828 -258.951298) (xy 320.274773 -259.093462) (xy 320.258687 -259.234943) (xy 320.234622 -259.375287)
			(xy 320.202656 -259.514045) (xy 320.162892 -259.650772) (xy 320.115455 -259.785031) (xy 320.060499 -259.91639)
			(xy 319.998199 -260.044431) (xy 319.928755 -260.168741) (xy 319.852389 -260.288924) (xy 319.769347 -260.404593)
			(xy 319.679893 -260.515379) (xy 319.584315 -260.620927) (xy 319.482918 -260.720899) (xy 319.376028 -260.814974)
			(xy 319.263987 -260.902851) (xy 319.147154 -260.984249) (xy 319.025903 -261.058906) (xy 318.900622 -261.126584)
			(xy 318.771713 -261.187066) (xy 318.639589 -261.240157) (xy 318.504673 -261.285689) (xy 318.367397 -261.323515)
			(xy 318.2282 -261.353515) (xy 318.08753 -261.375591) (xy 317.945836 -261.389673) (xy 317.803572 -261.395716)
			(xy 317.661194 -261.393701) (xy 317.519158 -261.383634) (xy 317.377919 -261.365548) (xy 317.237929 -261.3395)
			(xy 317.099638 -261.305574) (xy 316.963487 -261.263878) (xy 316.829913 -261.214546) (xy 316.699344 -261.157737)
			(xy 316.572198 -261.093631) (xy 316.448883 -261.022435) (xy 316.329793 -260.944377) (xy 316.21531 -260.859705)
			(xy 316.105801 -260.768693) (xy 316.001616 -260.671631) (xy 315.903089 -260.56883) (xy 315.810536 -260.460619)
			(xy 315.724254 -260.347346) (xy 315.644517 -260.229373) (xy 315.571583 -260.107077) (xy 315.505685 -259.980851)
			(xy 315.447034 -259.851099) (xy 315.395817 -259.718237) (xy 315.352199 -259.58269) (xy 315.316319 -259.444892)
			(xy 315.288292 -259.305285) (xy 315.268209 -259.164317) (xy 315.256134 -259.022437) (xy 315.252104 -258.880102)
			(xy 156.543246 -258.880102) (xy 156.543248 -258.880356) (xy 156.542744 -258.951552) (xy 156.534689 -259.093716)
			(xy 156.518603 -259.235197) (xy 156.494538 -259.375541) (xy 156.462572 -259.514299) (xy 156.422808 -259.651026)
			(xy 156.375371 -259.785285) (xy 156.320415 -259.916644) (xy 156.258115 -260.044685) (xy 156.188671 -260.168995)
			(xy 156.112305 -260.289178) (xy 156.029263 -260.404847) (xy 155.939809 -260.515633) (xy 155.844231 -260.621181)
			(xy 155.742834 -260.721153) (xy 155.635944 -260.815228) (xy 155.523903 -260.903105) (xy 155.40707 -260.984503)
			(xy 155.285819 -261.05916) (xy 155.160538 -261.126838) (xy 155.031629 -261.18732) (xy 154.899505 -261.240411)
			(xy 154.764589 -261.285943) (xy 154.627313 -261.323769) (xy 154.488116 -261.353769) (xy 154.347446 -261.375845)
			(xy 154.205752 -261.389927) (xy 154.063488 -261.39597) (xy 153.92111 -261.393955) (xy 153.779074 -261.383888)
			(xy 153.637835 -261.365802) (xy 153.497845 -261.339754) (xy 153.359554 -261.305828) (xy 153.223403 -261.264132)
			(xy 153.089829 -261.2148) (xy 152.95926 -261.157991) (xy 152.832114 -261.093885) (xy 152.708799 -261.022689)
			(xy 152.589709 -260.944631) (xy 152.475226 -260.859959) (xy 152.365717 -260.768947) (xy 152.261532 -260.671885)
			(xy 152.163005 -260.569084) (xy 152.070452 -260.460873) (xy 151.98417 -260.3476) (xy 151.904433 -260.229627)
			(xy 151.831499 -260.107331) (xy 151.765601 -259.981105) (xy 151.70695 -259.851353) (xy 151.655733 -259.718491)
			(xy 151.612115 -259.582944) (xy 151.576235 -259.445146) (xy 151.548208 -259.305539) (xy 151.528125 -259.164571)
			(xy 151.51605 -259.022691) (xy 151.51202 -258.880356) (xy 72.343264 -258.880356) (xy 72.34276 -258.951552)
			(xy 72.334705 -259.093716) (xy 72.318619 -259.235197) (xy 72.294554 -259.375541) (xy 72.262588 -259.514299)
			(xy 72.222824 -259.651026) (xy 72.175387 -259.785285) (xy 72.120431 -259.916644) (xy 72.058131 -260.044685)
			(xy 71.988687 -260.168995) (xy 71.912321 -260.289178) (xy 71.829279 -260.404847) (xy 71.739825 -260.515633)
			(xy 71.644247 -260.621181) (xy 71.54285 -260.721153) (xy 71.43596 -260.815228) (xy 71.323919 -260.903105)
			(xy 71.207086 -260.984503) (xy 71.085835 -261.05916) (xy 70.960554 -261.126838) (xy 70.831645 -261.18732)
			(xy 70.699521 -261.240411) (xy 70.564605 -261.285943) (xy 70.427329 -261.323769) (xy 70.288132 -261.353769)
			(xy 70.147462 -261.375845) (xy 70.005768 -261.389927) (xy 69.863504 -261.39597) (xy 69.721126 -261.393955)
			(xy 69.57909 -261.383888) (xy 69.437851 -261.365802) (xy 69.297861 -261.339754) (xy 69.15957 -261.305828)
			(xy 69.023419 -261.264132) (xy 68.889845 -261.2148) (xy 68.759276 -261.157991) (xy 68.63213 -261.093885)
			(xy 68.508815 -261.022689) (xy 68.389725 -260.944631) (xy 68.275242 -260.859959) (xy 68.165733 -260.768947)
			(xy 68.061548 -260.671885) (xy 67.963021 -260.569084) (xy 67.870468 -260.460873) (xy 67.784186 -260.3476)
			(xy 67.704449 -260.229627) (xy 67.631515 -260.107331) (xy 67.565617 -259.981105) (xy 67.506966 -259.851353)
			(xy 67.455749 -259.718491) (xy 67.412131 -259.582944) (xy 67.376251 -259.445146) (xy 67.348224 -259.305539)
			(xy 67.328141 -259.164571) (xy 67.316066 -259.022691) (xy 67.312036 -258.880356) (xy 2.509012 -258.880356)
			(xy 2.509012 -269.226284) (xy 108.48519 -269.226284) (xy 108.48915 -269.17723) (xy 108.500927 -269.129446)
			(xy 108.520218 -269.08417) (xy 108.546521 -269.042574) (xy 108.579156 -269.005737) (xy 108.617277 -268.974612)
			(xy 108.659898 -268.950005) (xy 108.705914 -268.932553) (xy 108.754133 -268.922709) (xy 108.803308 -268.920728)
			(xy 108.852163 -268.92666) (xy 108.899434 -268.940352) (xy 108.943896 -268.96145) (xy 108.984399 -268.989406)
			(xy 109.019892 -269.023498) (xy 109.049457 -269.062842) (xy 109.072328 -269.106419) (xy 109.087912 -269.1531)
			(xy 109.095807 -269.201677) (xy 109.096302 -269.226284) (xy 109.425752 -269.226284) (xy 109.429706 -269.177311)
			(xy 109.441464 -269.129607) (xy 109.460722 -269.084406) (xy 109.486981 -269.04288) (xy 109.519562 -269.006104)
			(xy 109.55762 -268.97503) (xy 109.60017 -268.950464) (xy 109.646109 -268.933042) (xy 109.694249 -268.923214)
			(xy 109.743341 -268.921236) (xy 109.792115 -268.927158) (xy 109.839307 -268.940827) (xy 109.883696 -268.96189)
			(xy 109.924131 -268.9898) (xy 109.959565 -269.023835) (xy 109.989081 -269.063114) (xy 110.011914 -269.106618)
			(xy 110.027473 -269.153222) (xy 110.035354 -269.201718) (xy 110.035848 -269.226284) (xy 114.11891 -269.226284)
			(xy 114.12287 -269.17723) (xy 114.134647 -269.129446) (xy 114.153938 -269.08417) (xy 114.180241 -269.042574)
			(xy 114.212876 -269.005737) (xy 114.250997 -268.974612) (xy 114.293618 -268.950005) (xy 114.339634 -268.932553)
			(xy 114.387853 -268.922709) (xy 114.437028 -268.920728) (xy 114.485883 -268.92666) (xy 114.533154 -268.940352)
			(xy 114.577616 -268.96145) (xy 114.618119 -268.989406) (xy 114.653612 -269.023498) (xy 114.683177 -269.062842)
			(xy 114.706048 -269.106419) (xy 114.721632 -269.1531) (xy 114.729527 -269.201677) (xy 114.730022 -269.226284)
			(xy 115.059472 -269.226284) (xy 115.063426 -269.177311) (xy 115.075184 -269.129607) (xy 115.094442 -269.084406)
			(xy 115.120701 -269.04288) (xy 115.153282 -269.006104) (xy 115.19134 -268.97503) (xy 115.23389 -268.950464)
			(xy 115.279829 -268.933042) (xy 115.327969 -268.923214) (xy 115.377061 -268.921236) (xy 115.425835 -268.927158)
			(xy 115.473027 -268.940827) (xy 115.517416 -268.96189) (xy 115.557851 -268.9898) (xy 115.593285 -269.023835)
			(xy 115.622801 -269.063114) (xy 115.645634 -269.106618) (xy 115.661193 -269.153222) (xy 115.669074 -269.201718)
			(xy 115.669563 -269.22603) (xy 356.425258 -269.22603) (xy 356.429218 -269.176976) (xy 356.440995 -269.129192)
			(xy 356.460286 -269.083916) (xy 356.486589 -269.04232) (xy 356.519224 -269.005483) (xy 356.557345 -268.974358)
			(xy 356.599966 -268.949751) (xy 356.645982 -268.932299) (xy 356.694201 -268.922455) (xy 356.743376 -268.920474)
			(xy 356.792231 -268.926406) (xy 356.839502 -268.940098) (xy 356.883964 -268.961196) (xy 356.924467 -268.989152)
			(xy 356.95996 -269.023244) (xy 356.989525 -269.062588) (xy 357.012396 -269.106165) (xy 357.02798 -269.152846)
			(xy 357.035875 -269.201423) (xy 357.03637 -269.22603) (xy 357.36582 -269.22603) (xy 357.369774 -269.177057)
			(xy 357.381532 -269.129353) (xy 357.40079 -269.084152) (xy 357.427049 -269.042626) (xy 357.45963 -269.00585)
			(xy 357.497688 -268.974776) (xy 357.540238 -268.95021) (xy 357.586177 -268.932788) (xy 357.634317 -268.92296)
			(xy 357.683409 -268.920982) (xy 357.732183 -268.926904) (xy 357.779375 -268.940573) (xy 357.823764 -268.961636)
			(xy 357.864199 -268.989546) (xy 357.899633 -269.023581) (xy 357.929149 -269.06286) (xy 357.951982 -269.106364)
			(xy 357.967541 -269.152968) (xy 357.975422 -269.201464) (xy 357.975916 -269.22603) (xy 362.058978 -269.22603)
			(xy 362.062938 -269.176976) (xy 362.074715 -269.129192) (xy 362.094006 -269.083916) (xy 362.120309 -269.04232)
			(xy 362.152944 -269.005483) (xy 362.191065 -268.974358) (xy 362.233686 -268.949751) (xy 362.279702 -268.932299)
			(xy 362.327921 -268.922455) (xy 362.377096 -268.920474) (xy 362.425951 -268.926406) (xy 362.473222 -268.940098)
			(xy 362.517684 -268.961196) (xy 362.558187 -268.989152) (xy 362.59368 -269.023244) (xy 362.623245 -269.062588)
			(xy 362.646116 -269.106165) (xy 362.6617 -269.152846) (xy 362.669595 -269.201423) (xy 362.67009 -269.22603)
			(xy 362.99954 -269.22603) (xy 363.003494 -269.177057) (xy 363.015252 -269.129353) (xy 363.03451 -269.084152)
			(xy 363.060769 -269.042626) (xy 363.09335 -269.00585) (xy 363.131408 -268.974776) (xy 363.173958 -268.95021)
			(xy 363.219897 -268.932788) (xy 363.268037 -268.92296) (xy 363.317129 -268.920982) (xy 363.365903 -268.926904)
			(xy 363.413095 -268.940573) (xy 363.457484 -268.961636) (xy 363.497919 -268.989546) (xy 363.533353 -269.023581)
			(xy 363.562869 -269.06286) (xy 363.585702 -269.106364) (xy 363.601261 -269.152968) (xy 363.609142 -269.201464)
			(xy 363.609636 -269.22603) (xy 363.609142 -269.250596) (xy 363.601261 -269.299092) (xy 363.585702 -269.345696)
			(xy 363.562869 -269.3892) (xy 363.533353 -269.428479) (xy 363.497919 -269.462514) (xy 363.457484 -269.490424)
			(xy 363.413095 -269.511487) (xy 363.365903 -269.525156) (xy 363.317129 -269.531078) (xy 363.268037 -269.5291)
			(xy 363.219897 -269.519272) (xy 363.173958 -269.50185) (xy 363.131408 -269.477284) (xy 363.09335 -269.44621)
			(xy 363.060769 -269.409434) (xy 363.03451 -269.367908) (xy 363.015252 -269.322707) (xy 363.003494 -269.275003)
			(xy 362.99954 -269.22603) (xy 362.67009 -269.22603) (xy 362.669595 -269.250637) (xy 362.6617 -269.299214)
			(xy 362.646116 -269.345895) (xy 362.623245 -269.389472) (xy 362.59368 -269.428816) (xy 362.558187 -269.462908)
			(xy 362.517684 -269.490864) (xy 362.473222 -269.511962) (xy 362.425951 -269.525654) (xy 362.377096 -269.531586)
			(xy 362.327921 -269.529605) (xy 362.279702 -269.519761) (xy 362.233686 -269.502309) (xy 362.191065 -269.477702)
			(xy 362.152944 -269.446577) (xy 362.120309 -269.40974) (xy 362.094006 -269.368144) (xy 362.074715 -269.322868)
			(xy 362.062938 -269.275084) (xy 362.058978 -269.22603) (xy 357.975916 -269.22603) (xy 357.975422 -269.250596)
			(xy 357.967541 -269.299092) (xy 357.951982 -269.345696) (xy 357.929149 -269.3892) (xy 357.899633 -269.428479)
			(xy 357.864199 -269.462514) (xy 357.823764 -269.490424) (xy 357.779375 -269.511487) (xy 357.732183 -269.525156)
			(xy 357.683409 -269.531078) (xy 357.634317 -269.5291) (xy 357.586177 -269.519272) (xy 357.540238 -269.50185)
			(xy 357.497688 -269.477284) (xy 357.45963 -269.44621) (xy 357.427049 -269.409434) (xy 357.40079 -269.367908)
			(xy 357.381532 -269.322707) (xy 357.369774 -269.275003) (xy 357.36582 -269.22603) (xy 357.03637 -269.22603)
			(xy 357.035875 -269.250637) (xy 357.02798 -269.299214) (xy 357.012396 -269.345895) (xy 356.989525 -269.389472)
			(xy 356.95996 -269.428816) (xy 356.924467 -269.462908) (xy 356.883964 -269.490864) (xy 356.839502 -269.511962)
			(xy 356.792231 -269.525654) (xy 356.743376 -269.531586) (xy 356.694201 -269.529605) (xy 356.645982 -269.519761)
			(xy 356.599966 -269.502309) (xy 356.557345 -269.477702) (xy 356.519224 -269.446577) (xy 356.486589 -269.40974)
			(xy 356.460286 -269.368144) (xy 356.440995 -269.322868) (xy 356.429218 -269.275084) (xy 356.425258 -269.22603)
			(xy 115.669563 -269.22603) (xy 115.669568 -269.226284) (xy 115.669074 -269.25085) (xy 115.661193 -269.299346)
			(xy 115.645634 -269.34595) (xy 115.622801 -269.389454) (xy 115.593285 -269.428733) (xy 115.557851 -269.462768)
			(xy 115.517416 -269.490678) (xy 115.473027 -269.511741) (xy 115.425835 -269.52541) (xy 115.377061 -269.531332)
			(xy 115.327969 -269.529354) (xy 115.279829 -269.519526) (xy 115.23389 -269.502104) (xy 115.19134 -269.477538)
			(xy 115.153282 -269.446464) (xy 115.120701 -269.409688) (xy 115.094442 -269.368162) (xy 115.075184 -269.322961)
			(xy 115.063426 -269.275257) (xy 115.059472 -269.226284) (xy 114.730022 -269.226284) (xy 114.729527 -269.250891)
			(xy 114.721632 -269.299468) (xy 114.706048 -269.346149) (xy 114.683177 -269.389726) (xy 114.653612 -269.42907)
			(xy 114.618119 -269.463162) (xy 114.577616 -269.491118) (xy 114.533154 -269.512216) (xy 114.485883 -269.525908)
			(xy 114.437028 -269.53184) (xy 114.387853 -269.529859) (xy 114.339634 -269.520015) (xy 114.293618 -269.502563)
			(xy 114.250997 -269.477956) (xy 114.212876 -269.446831) (xy 114.180241 -269.409994) (xy 114.153938 -269.368398)
			(xy 114.134647 -269.323122) (xy 114.12287 -269.275338) (xy 114.11891 -269.226284) (xy 110.035848 -269.226284)
			(xy 110.035354 -269.25085) (xy 110.027473 -269.299346) (xy 110.011914 -269.34595) (xy 109.989081 -269.389454)
			(xy 109.959565 -269.428733) (xy 109.924131 -269.462768) (xy 109.883696 -269.490678) (xy 109.839307 -269.511741)
			(xy 109.792115 -269.52541) (xy 109.743341 -269.531332) (xy 109.694249 -269.529354) (xy 109.646109 -269.519526)
			(xy 109.60017 -269.502104) (xy 109.55762 -269.477538) (xy 109.519562 -269.446464) (xy 109.486981 -269.409688)
			(xy 109.460722 -269.368162) (xy 109.441464 -269.322961) (xy 109.429706 -269.275257) (xy 109.425752 -269.226284)
			(xy 109.096302 -269.226284) (xy 109.095807 -269.250891) (xy 109.087912 -269.299468) (xy 109.072328 -269.346149)
			(xy 109.049457 -269.389726) (xy 109.019892 -269.42907) (xy 108.984399 -269.463162) (xy 108.943896 -269.491118)
			(xy 108.899434 -269.512216) (xy 108.852163 -269.525908) (xy 108.803308 -269.53184) (xy 108.754133 -269.529859)
			(xy 108.705914 -269.520015) (xy 108.659898 -269.502563) (xy 108.617277 -269.477956) (xy 108.579156 -269.446831)
			(xy 108.546521 -269.409994) (xy 108.520218 -269.368398) (xy 108.500927 -269.323122) (xy 108.48915 -269.275338)
			(xy 108.48519 -269.226284) (xy 2.509012 -269.226284) (xy 2.509012 -270.03629) (xy 97.675204 -270.03629)
			(xy 97.679164 -269.987236) (xy 97.690941 -269.939452) (xy 97.710232 -269.894176) (xy 97.736535 -269.85258)
			(xy 97.76917 -269.815743) (xy 97.807291 -269.784618) (xy 97.849912 -269.760011) (xy 97.895928 -269.742559)
			(xy 97.944147 -269.732715) (xy 97.993322 -269.730734) (xy 98.042177 -269.736666) (xy 98.089448 -269.750358)
			(xy 98.13391 -269.771456) (xy 98.174413 -269.799412) (xy 98.209906 -269.833504) (xy 98.239471 -269.872848)
			(xy 98.262342 -269.916425) (xy 98.277926 -269.963106) (xy 98.285821 -270.011683) (xy 98.286316 -270.03629)
			(xy 98.615766 -270.03629) (xy 98.61972 -269.987317) (xy 98.631478 -269.939613) (xy 98.650736 -269.894412)
			(xy 98.676995 -269.852886) (xy 98.709576 -269.81611) (xy 98.747634 -269.785036) (xy 98.790184 -269.76047)
			(xy 98.836123 -269.743048) (xy 98.884263 -269.73322) (xy 98.933355 -269.731242) (xy 98.982129 -269.737164)
			(xy 99.029321 -269.750833) (xy 99.07371 -269.771896) (xy 99.114145 -269.799806) (xy 99.149579 -269.833841)
			(xy 99.179095 -269.87312) (xy 99.201928 -269.916624) (xy 99.217487 -269.963228) (xy 99.225368 -270.011724)
			(xy 99.225862 -270.03629) (xy 100.495112 -270.03629) (xy 100.499072 -269.987236) (xy 100.510849 -269.939452)
			(xy 100.53014 -269.894176) (xy 100.556443 -269.85258) (xy 100.589078 -269.815743) (xy 100.627199 -269.784618)
			(xy 100.66982 -269.760011) (xy 100.715836 -269.742559) (xy 100.764055 -269.732715) (xy 100.81323 -269.730734)
			(xy 100.862085 -269.736666) (xy 100.909356 -269.750358) (xy 100.953818 -269.771456) (xy 100.994321 -269.799412)
			(xy 101.029814 -269.833504) (xy 101.059379 -269.872848) (xy 101.08225 -269.916425) (xy 101.097834 -269.963106)
			(xy 101.105729 -270.011683) (xy 101.106224 -270.03629) (xy 101.435674 -270.03629) (xy 101.439628 -269.987317)
			(xy 101.451386 -269.939613) (xy 101.470644 -269.894412) (xy 101.496903 -269.852886) (xy 101.529484 -269.81611)
			(xy 101.567542 -269.785036) (xy 101.610092 -269.76047) (xy 101.656031 -269.743048) (xy 101.704171 -269.73322)
			(xy 101.753263 -269.731242) (xy 101.802037 -269.737164) (xy 101.849229 -269.750833) (xy 101.893618 -269.771896)
			(xy 101.934053 -269.799806) (xy 101.969487 -269.833841) (xy 101.999003 -269.87312) (xy 102.021836 -269.916624)
			(xy 102.037395 -269.963228) (xy 102.045276 -270.011724) (xy 102.04577 -270.03629) (xy 103.315274 -270.03629)
			(xy 103.319234 -269.987236) (xy 103.331011 -269.939452) (xy 103.350302 -269.894176) (xy 103.376605 -269.85258)
			(xy 103.40924 -269.815743) (xy 103.447361 -269.784618) (xy 103.489982 -269.760011) (xy 103.535998 -269.742559)
			(xy 103.584217 -269.732715) (xy 103.633392 -269.730734) (xy 103.682247 -269.736666) (xy 103.729518 -269.750358)
			(xy 103.77398 -269.771456) (xy 103.814483 -269.799412) (xy 103.849976 -269.833504) (xy 103.879541 -269.872848)
			(xy 103.902412 -269.916425) (xy 103.917996 -269.963106) (xy 103.925891 -270.011683) (xy 103.926386 -270.03629)
			(xy 104.255836 -270.03629) (xy 104.25979 -269.987317) (xy 104.271548 -269.939613) (xy 104.290806 -269.894412)
			(xy 104.317065 -269.852886) (xy 104.349646 -269.81611) (xy 104.387704 -269.785036) (xy 104.430254 -269.76047)
			(xy 104.476193 -269.743048) (xy 104.524333 -269.73322) (xy 104.573425 -269.731242) (xy 104.622199 -269.737164)
			(xy 104.669391 -269.750833) (xy 104.71378 -269.771896) (xy 104.754215 -269.799806) (xy 104.789649 -269.833841)
			(xy 104.819165 -269.87312) (xy 104.841998 -269.916624) (xy 104.857557 -269.963228) (xy 104.865438 -270.011724)
			(xy 104.865932 -270.03629) (xy 106.135182 -270.03629) (xy 106.139142 -269.987236) (xy 106.150919 -269.939452)
			(xy 106.17021 -269.894176) (xy 106.196513 -269.85258) (xy 106.229148 -269.815743) (xy 106.267269 -269.784618)
			(xy 106.30989 -269.760011) (xy 106.355906 -269.742559) (xy 106.404125 -269.732715) (xy 106.4533 -269.730734)
			(xy 106.502155 -269.736666) (xy 106.549426 -269.750358) (xy 106.593888 -269.771456) (xy 106.634391 -269.799412)
			(xy 106.669884 -269.833504) (xy 106.699449 -269.872848) (xy 106.72232 -269.916425) (xy 106.737904 -269.963106)
			(xy 106.745799 -270.011683) (xy 106.746294 -270.03629) (xy 107.075744 -270.03629) (xy 107.079698 -269.987317)
			(xy 107.091456 -269.939613) (xy 107.110714 -269.894412) (xy 107.136973 -269.852886) (xy 107.169554 -269.81611)
			(xy 107.207612 -269.785036) (xy 107.250162 -269.76047) (xy 107.296101 -269.743048) (xy 107.344241 -269.73322)
			(xy 107.393333 -269.731242) (xy 107.442107 -269.737164) (xy 107.489299 -269.750833) (xy 107.533688 -269.771896)
			(xy 107.574123 -269.799806) (xy 107.609557 -269.833841) (xy 107.639073 -269.87312) (xy 107.661906 -269.916624)
			(xy 107.677465 -269.963228) (xy 107.685346 -270.011724) (xy 107.68584 -270.03629) (xy 116.468918 -270.03629)
			(xy 116.472878 -269.987236) (xy 116.484655 -269.939452) (xy 116.503946 -269.894176) (xy 116.530249 -269.85258)
			(xy 116.562884 -269.815743) (xy 116.601005 -269.784618) (xy 116.643626 -269.760011) (xy 116.689642 -269.742559)
			(xy 116.737861 -269.732715) (xy 116.787036 -269.730734) (xy 116.835891 -269.736666) (xy 116.883162 -269.750358)
			(xy 116.927624 -269.771456) (xy 116.968127 -269.799412) (xy 117.00362 -269.833504) (xy 117.033185 -269.872848)
			(xy 117.056056 -269.916425) (xy 117.07164 -269.963106) (xy 117.079535 -270.011683) (xy 117.08003 -270.03629)
			(xy 117.40948 -270.03629) (xy 117.413434 -269.987317) (xy 117.425192 -269.939613) (xy 117.44445 -269.894412)
			(xy 117.470709 -269.852886) (xy 117.50329 -269.81611) (xy 117.541348 -269.785036) (xy 117.583898 -269.76047)
			(xy 117.629837 -269.743048) (xy 117.677977 -269.73322) (xy 117.727069 -269.731242) (xy 117.775843 -269.737164)
			(xy 117.823035 -269.750833) (xy 117.867424 -269.771896) (xy 117.907859 -269.799806) (xy 117.943293 -269.833841)
			(xy 117.972809 -269.87312) (xy 117.995642 -269.916624) (xy 118.011201 -269.963228) (xy 118.019082 -270.011724)
			(xy 118.019576 -270.03629) (xy 119.288826 -270.03629) (xy 119.292786 -269.987236) (xy 119.304563 -269.939452)
			(xy 119.323854 -269.894176) (xy 119.350157 -269.85258) (xy 119.382792 -269.815743) (xy 119.420913 -269.784618)
			(xy 119.463534 -269.760011) (xy 119.50955 -269.742559) (xy 119.557769 -269.732715) (xy 119.606944 -269.730734)
			(xy 119.655799 -269.736666) (xy 119.70307 -269.750358) (xy 119.747532 -269.771456) (xy 119.788035 -269.799412)
			(xy 119.823528 -269.833504) (xy 119.853093 -269.872848) (xy 119.875964 -269.916425) (xy 119.891548 -269.963106)
			(xy 119.899443 -270.011683) (xy 119.899938 -270.03629) (xy 120.229388 -270.03629) (xy 120.233342 -269.987317)
			(xy 120.2451 -269.939613) (xy 120.264358 -269.894412) (xy 120.290617 -269.852886) (xy 120.323198 -269.81611)
			(xy 120.361256 -269.785036) (xy 120.403806 -269.76047) (xy 120.449745 -269.743048) (xy 120.497885 -269.73322)
			(xy 120.546977 -269.731242) (xy 120.595751 -269.737164) (xy 120.642943 -269.750833) (xy 120.687332 -269.771896)
			(xy 120.727767 -269.799806) (xy 120.763201 -269.833841) (xy 120.792717 -269.87312) (xy 120.81555 -269.916624)
			(xy 120.831109 -269.963228) (xy 120.83899 -270.011724) (xy 120.839484 -270.03629) (xy 122.108988 -270.03629)
			(xy 122.112948 -269.987236) (xy 122.124725 -269.939452) (xy 122.144016 -269.894176) (xy 122.170319 -269.85258)
			(xy 122.202954 -269.815743) (xy 122.241075 -269.784618) (xy 122.283696 -269.760011) (xy 122.329712 -269.742559)
			(xy 122.377931 -269.732715) (xy 122.427106 -269.730734) (xy 122.475961 -269.736666) (xy 122.523232 -269.750358)
			(xy 122.567694 -269.771456) (xy 122.608197 -269.799412) (xy 122.64369 -269.833504) (xy 122.673255 -269.872848)
			(xy 122.696126 -269.916425) (xy 122.71171 -269.963106) (xy 122.719605 -270.011683) (xy 122.7201 -270.03629)
			(xy 123.04955 -270.03629) (xy 123.053504 -269.987317) (xy 123.065262 -269.939613) (xy 123.08452 -269.894412)
			(xy 123.110779 -269.852886) (xy 123.14336 -269.81611) (xy 123.181418 -269.785036) (xy 123.223968 -269.76047)
			(xy 123.269907 -269.743048) (xy 123.318047 -269.73322) (xy 123.367139 -269.731242) (xy 123.415913 -269.737164)
			(xy 123.463105 -269.750833) (xy 123.507494 -269.771896) (xy 123.547929 -269.799806) (xy 123.583363 -269.833841)
			(xy 123.612879 -269.87312) (xy 123.635712 -269.916624) (xy 123.651271 -269.963228) (xy 123.659152 -270.011724)
			(xy 123.659646 -270.03629) (xy 124.928896 -270.03629) (xy 124.932856 -269.987236) (xy 124.944633 -269.939452)
			(xy 124.963924 -269.894176) (xy 124.990227 -269.85258) (xy 125.022862 -269.815743) (xy 125.060983 -269.784618)
			(xy 125.103604 -269.760011) (xy 125.14962 -269.742559) (xy 125.197839 -269.732715) (xy 125.247014 -269.730734)
			(xy 125.295869 -269.736666) (xy 125.34314 -269.750358) (xy 125.387602 -269.771456) (xy 125.428105 -269.799412)
			(xy 125.463598 -269.833504) (xy 125.493163 -269.872848) (xy 125.516034 -269.916425) (xy 125.531618 -269.963106)
			(xy 125.539513 -270.011683) (xy 125.540008 -270.03629) (xy 125.869458 -270.03629) (xy 125.873412 -269.987317)
			(xy 125.88517 -269.939613) (xy 125.904428 -269.894412) (xy 125.930687 -269.852886) (xy 125.963268 -269.81611)
			(xy 126.001326 -269.785036) (xy 126.043876 -269.76047) (xy 126.089815 -269.743048) (xy 126.137955 -269.73322)
			(xy 126.187047 -269.731242) (xy 126.235821 -269.737164) (xy 126.283013 -269.750833) (xy 126.327402 -269.771896)
			(xy 126.367837 -269.799806) (xy 126.403271 -269.833841) (xy 126.432787 -269.87312) (xy 126.45562 -269.916624)
			(xy 126.471179 -269.963228) (xy 126.47906 -270.011724) (xy 126.479549 -270.036036) (xy 345.615272 -270.036036)
			(xy 345.619232 -269.986982) (xy 345.631009 -269.939198) (xy 345.6503 -269.893922) (xy 345.676603 -269.852326)
			(xy 345.709238 -269.815489) (xy 345.747359 -269.784364) (xy 345.78998 -269.759757) (xy 345.835996 -269.742305)
			(xy 345.884215 -269.732461) (xy 345.93339 -269.73048) (xy 345.982245 -269.736412) (xy 346.029516 -269.750104)
			(xy 346.073978 -269.771202) (xy 346.114481 -269.799158) (xy 346.149974 -269.83325) (xy 346.179539 -269.872594)
			(xy 346.20241 -269.916171) (xy 346.217994 -269.962852) (xy 346.225889 -270.011429) (xy 346.226384 -270.036036)
			(xy 346.555834 -270.036036) (xy 346.559788 -269.987063) (xy 346.571546 -269.939359) (xy 346.590804 -269.894158)
			(xy 346.617063 -269.852632) (xy 346.649644 -269.815856) (xy 346.687702 -269.784782) (xy 346.730252 -269.760216)
			(xy 346.776191 -269.742794) (xy 346.824331 -269.732966) (xy 346.873423 -269.730988) (xy 346.922197 -269.73691)
			(xy 346.969389 -269.750579) (xy 347.013778 -269.771642) (xy 347.054213 -269.799552) (xy 347.089647 -269.833587)
			(xy 347.119163 -269.872866) (xy 347.141996 -269.91637) (xy 347.157555 -269.962974) (xy 347.165436 -270.01147)
			(xy 347.16593 -270.036036) (xy 348.43518 -270.036036) (xy 348.43914 -269.986982) (xy 348.450917 -269.939198)
			(xy 348.470208 -269.893922) (xy 348.496511 -269.852326) (xy 348.529146 -269.815489) (xy 348.567267 -269.784364)
			(xy 348.609888 -269.759757) (xy 348.655904 -269.742305) (xy 348.704123 -269.732461) (xy 348.753298 -269.73048)
			(xy 348.802153 -269.736412) (xy 348.849424 -269.750104) (xy 348.893886 -269.771202) (xy 348.934389 -269.799158)
			(xy 348.969882 -269.83325) (xy 348.999447 -269.872594) (xy 349.022318 -269.916171) (xy 349.037902 -269.962852)
			(xy 349.045797 -270.011429) (xy 349.046292 -270.036036) (xy 349.375742 -270.036036) (xy 349.379696 -269.987063)
			(xy 349.391454 -269.939359) (xy 349.410712 -269.894158) (xy 349.436971 -269.852632) (xy 349.469552 -269.815856)
			(xy 349.50761 -269.784782) (xy 349.55016 -269.760216) (xy 349.596099 -269.742794) (xy 349.644239 -269.732966)
			(xy 349.693331 -269.730988) (xy 349.742105 -269.73691) (xy 349.789297 -269.750579) (xy 349.833686 -269.771642)
			(xy 349.874121 -269.799552) (xy 349.909555 -269.833587) (xy 349.939071 -269.872866) (xy 349.961904 -269.91637)
			(xy 349.977463 -269.962974) (xy 349.985344 -270.01147) (xy 349.985838 -270.036036) (xy 351.255342 -270.036036)
			(xy 351.259302 -269.986982) (xy 351.271079 -269.939198) (xy 351.29037 -269.893922) (xy 351.316673 -269.852326)
			(xy 351.349308 -269.815489) (xy 351.387429 -269.784364) (xy 351.43005 -269.759757) (xy 351.476066 -269.742305)
			(xy 351.524285 -269.732461) (xy 351.57346 -269.73048) (xy 351.622315 -269.736412) (xy 351.669586 -269.750104)
			(xy 351.714048 -269.771202) (xy 351.754551 -269.799158) (xy 351.790044 -269.83325) (xy 351.819609 -269.872594)
			(xy 351.84248 -269.916171) (xy 351.858064 -269.962852) (xy 351.865959 -270.011429) (xy 351.866454 -270.036036)
			(xy 352.195904 -270.036036) (xy 352.199858 -269.987063) (xy 352.211616 -269.939359) (xy 352.230874 -269.894158)
			(xy 352.257133 -269.852632) (xy 352.289714 -269.815856) (xy 352.327772 -269.784782) (xy 352.370322 -269.760216)
			(xy 352.416261 -269.742794) (xy 352.464401 -269.732966) (xy 352.513493 -269.730988) (xy 352.562267 -269.73691)
			(xy 352.609459 -269.750579) (xy 352.653848 -269.771642) (xy 352.694283 -269.799552) (xy 352.729717 -269.833587)
			(xy 352.759233 -269.872866) (xy 352.782066 -269.91637) (xy 352.797625 -269.962974) (xy 352.805506 -270.01147)
			(xy 352.806 -270.036036) (xy 354.07525 -270.036036) (xy 354.07921 -269.986982) (xy 354.090987 -269.939198)
			(xy 354.110278 -269.893922) (xy 354.136581 -269.852326) (xy 354.169216 -269.815489) (xy 354.207337 -269.784364)
			(xy 354.249958 -269.759757) (xy 354.295974 -269.742305) (xy 354.344193 -269.732461) (xy 354.393368 -269.73048)
			(xy 354.442223 -269.736412) (xy 354.489494 -269.750104) (xy 354.533956 -269.771202) (xy 354.574459 -269.799158)
			(xy 354.609952 -269.83325) (xy 354.639517 -269.872594) (xy 354.662388 -269.916171) (xy 354.677972 -269.962852)
			(xy 354.685867 -270.011429) (xy 354.686362 -270.036036) (xy 355.015812 -270.036036) (xy 355.019766 -269.987063)
			(xy 355.031524 -269.939359) (xy 355.050782 -269.894158) (xy 355.077041 -269.852632) (xy 355.109622 -269.815856)
			(xy 355.14768 -269.784782) (xy 355.19023 -269.760216) (xy 355.236169 -269.742794) (xy 355.284309 -269.732966)
			(xy 355.333401 -269.730988) (xy 355.382175 -269.73691) (xy 355.429367 -269.750579) (xy 355.473756 -269.771642)
			(xy 355.514191 -269.799552) (xy 355.549625 -269.833587) (xy 355.579141 -269.872866) (xy 355.601974 -269.91637)
			(xy 355.617533 -269.962974) (xy 355.625414 -270.01147) (xy 355.625908 -270.036036) (xy 364.408986 -270.036036)
			(xy 364.412946 -269.986982) (xy 364.424723 -269.939198) (xy 364.444014 -269.893922) (xy 364.470317 -269.852326)
			(xy 364.502952 -269.815489) (xy 364.541073 -269.784364) (xy 364.583694 -269.759757) (xy 364.62971 -269.742305)
			(xy 364.677929 -269.732461) (xy 364.727104 -269.73048) (xy 364.775959 -269.736412) (xy 364.82323 -269.750104)
			(xy 364.867692 -269.771202) (xy 364.908195 -269.799158) (xy 364.943688 -269.83325) (xy 364.973253 -269.872594)
			(xy 364.996124 -269.916171) (xy 365.011708 -269.962852) (xy 365.019603 -270.011429) (xy 365.020098 -270.036036)
			(xy 365.349548 -270.036036) (xy 365.353502 -269.987063) (xy 365.36526 -269.939359) (xy 365.384518 -269.894158)
			(xy 365.410777 -269.852632) (xy 365.443358 -269.815856) (xy 365.481416 -269.784782) (xy 365.523966 -269.760216)
			(xy 365.569905 -269.742794) (xy 365.618045 -269.732966) (xy 365.667137 -269.730988) (xy 365.715911 -269.73691)
			(xy 365.763103 -269.750579) (xy 365.807492 -269.771642) (xy 365.847927 -269.799552) (xy 365.883361 -269.833587)
			(xy 365.912877 -269.872866) (xy 365.93571 -269.91637) (xy 365.951269 -269.962974) (xy 365.95915 -270.01147)
			(xy 365.959644 -270.036036) (xy 367.228894 -270.036036) (xy 367.232854 -269.986982) (xy 367.244631 -269.939198)
			(xy 367.263922 -269.893922) (xy 367.290225 -269.852326) (xy 367.32286 -269.815489) (xy 367.360981 -269.784364)
			(xy 367.403602 -269.759757) (xy 367.449618 -269.742305) (xy 367.497837 -269.732461) (xy 367.547012 -269.73048)
			(xy 367.595867 -269.736412) (xy 367.643138 -269.750104) (xy 367.6876 -269.771202) (xy 367.728103 -269.799158)
			(xy 367.763596 -269.83325) (xy 367.793161 -269.872594) (xy 367.816032 -269.916171) (xy 367.831616 -269.962852)
			(xy 367.839511 -270.011429) (xy 367.840006 -270.036036) (xy 368.169456 -270.036036) (xy 368.17341 -269.987063)
			(xy 368.185168 -269.939359) (xy 368.204426 -269.894158) (xy 368.230685 -269.852632) (xy 368.263266 -269.815856)
			(xy 368.301324 -269.784782) (xy 368.343874 -269.760216) (xy 368.389813 -269.742794) (xy 368.437953 -269.732966)
			(xy 368.487045 -269.730988) (xy 368.535819 -269.73691) (xy 368.583011 -269.750579) (xy 368.6274 -269.771642)
			(xy 368.667835 -269.799552) (xy 368.703269 -269.833587) (xy 368.732785 -269.872866) (xy 368.755618 -269.91637)
			(xy 368.771177 -269.962974) (xy 368.779058 -270.01147) (xy 368.779552 -270.036036) (xy 370.049056 -270.036036)
			(xy 370.053016 -269.986982) (xy 370.064793 -269.939198) (xy 370.084084 -269.893922) (xy 370.110387 -269.852326)
			(xy 370.143022 -269.815489) (xy 370.181143 -269.784364) (xy 370.223764 -269.759757) (xy 370.26978 -269.742305)
			(xy 370.317999 -269.732461) (xy 370.367174 -269.73048) (xy 370.416029 -269.736412) (xy 370.4633 -269.750104)
			(xy 370.507762 -269.771202) (xy 370.548265 -269.799158) (xy 370.583758 -269.83325) (xy 370.613323 -269.872594)
			(xy 370.636194 -269.916171) (xy 370.651778 -269.962852) (xy 370.659673 -270.011429) (xy 370.660168 -270.036036)
			(xy 370.989618 -270.036036) (xy 370.993572 -269.987063) (xy 371.00533 -269.939359) (xy 371.024588 -269.894158)
			(xy 371.050847 -269.852632) (xy 371.083428 -269.815856) (xy 371.121486 -269.784782) (xy 371.164036 -269.760216)
			(xy 371.209975 -269.742794) (xy 371.258115 -269.732966) (xy 371.307207 -269.730988) (xy 371.355981 -269.73691)
			(xy 371.403173 -269.750579) (xy 371.447562 -269.771642) (xy 371.487997 -269.799552) (xy 371.523431 -269.833587)
			(xy 371.552947 -269.872866) (xy 371.57578 -269.91637) (xy 371.591339 -269.962974) (xy 371.59922 -270.01147)
			(xy 371.599714 -270.036036) (xy 372.868964 -270.036036) (xy 372.872924 -269.986982) (xy 372.884701 -269.939198)
			(xy 372.903992 -269.893922) (xy 372.930295 -269.852326) (xy 372.96293 -269.815489) (xy 373.001051 -269.784364)
			(xy 373.043672 -269.759757) (xy 373.089688 -269.742305) (xy 373.137907 -269.732461) (xy 373.187082 -269.73048)
			(xy 373.235937 -269.736412) (xy 373.283208 -269.750104) (xy 373.32767 -269.771202) (xy 373.368173 -269.799158)
			(xy 373.403666 -269.83325) (xy 373.433231 -269.872594) (xy 373.456102 -269.916171) (xy 373.471686 -269.962852)
			(xy 373.479581 -270.011429) (xy 373.480076 -270.036036) (xy 373.809526 -270.036036) (xy 373.81348 -269.987063)
			(xy 373.825238 -269.939359) (xy 373.844496 -269.894158) (xy 373.870755 -269.852632) (xy 373.903336 -269.815856)
			(xy 373.941394 -269.784782) (xy 373.983944 -269.760216) (xy 374.029883 -269.742794) (xy 374.078023 -269.732966)
			(xy 374.127115 -269.730988) (xy 374.175889 -269.73691) (xy 374.223081 -269.750579) (xy 374.26747 -269.771642)
			(xy 374.307905 -269.799552) (xy 374.343339 -269.833587) (xy 374.372855 -269.872866) (xy 374.395688 -269.91637)
			(xy 374.411247 -269.962974) (xy 374.419128 -270.01147) (xy 374.419622 -270.036036) (xy 374.419128 -270.060602)
			(xy 374.411247 -270.109098) (xy 374.395688 -270.155702) (xy 374.372855 -270.199206) (xy 374.343339 -270.238485)
			(xy 374.307905 -270.27252) (xy 374.26747 -270.30043) (xy 374.223081 -270.321493) (xy 374.175889 -270.335162)
			(xy 374.127115 -270.341084) (xy 374.078023 -270.339106) (xy 374.029883 -270.329278) (xy 373.983944 -270.311856)
			(xy 373.941394 -270.28729) (xy 373.903336 -270.256216) (xy 373.870755 -270.21944) (xy 373.844496 -270.177914)
			(xy 373.825238 -270.132713) (xy 373.81348 -270.085009) (xy 373.809526 -270.036036) (xy 373.480076 -270.036036)
			(xy 373.479581 -270.060643) (xy 373.471686 -270.10922) (xy 373.456102 -270.155901) (xy 373.433231 -270.199478)
			(xy 373.403666 -270.238822) (xy 373.368173 -270.272914) (xy 373.32767 -270.30087) (xy 373.283208 -270.321968)
			(xy 373.235937 -270.33566) (xy 373.187082 -270.341592) (xy 373.137907 -270.339611) (xy 373.089688 -270.329767)
			(xy 373.043672 -270.312315) (xy 373.001051 -270.287708) (xy 372.96293 -270.256583) (xy 372.930295 -270.219746)
			(xy 372.903992 -270.17815) (xy 372.884701 -270.132874) (xy 372.872924 -270.08509) (xy 372.868964 -270.036036)
			(xy 371.599714 -270.036036) (xy 371.59922 -270.060602) (xy 371.591339 -270.109098) (xy 371.57578 -270.155702)
			(xy 371.552947 -270.199206) (xy 371.523431 -270.238485) (xy 371.487997 -270.27252) (xy 371.447562 -270.30043)
			(xy 371.403173 -270.321493) (xy 371.355981 -270.335162) (xy 371.307207 -270.341084) (xy 371.258115 -270.339106)
			(xy 371.209975 -270.329278) (xy 371.164036 -270.311856) (xy 371.121486 -270.28729) (xy 371.083428 -270.256216)
			(xy 371.050847 -270.21944) (xy 371.024588 -270.177914) (xy 371.00533 -270.132713) (xy 370.993572 -270.085009)
			(xy 370.989618 -270.036036) (xy 370.660168 -270.036036) (xy 370.659673 -270.060643) (xy 370.651778 -270.10922)
			(xy 370.636194 -270.155901) (xy 370.613323 -270.199478) (xy 370.583758 -270.238822) (xy 370.548265 -270.272914)
			(xy 370.507762 -270.30087) (xy 370.4633 -270.321968) (xy 370.416029 -270.33566) (xy 370.367174 -270.341592)
			(xy 370.317999 -270.339611) (xy 370.26978 -270.329767) (xy 370.223764 -270.312315) (xy 370.181143 -270.287708)
			(xy 370.143022 -270.256583) (xy 370.110387 -270.219746) (xy 370.084084 -270.17815) (xy 370.064793 -270.132874)
			(xy 370.053016 -270.08509) (xy 370.049056 -270.036036) (xy 368.779552 -270.036036) (xy 368.779058 -270.060602)
			(xy 368.771177 -270.109098) (xy 368.755618 -270.155702) (xy 368.732785 -270.199206) (xy 368.703269 -270.238485)
			(xy 368.667835 -270.27252) (xy 368.6274 -270.30043) (xy 368.583011 -270.321493) (xy 368.535819 -270.335162)
			(xy 368.487045 -270.341084) (xy 368.437953 -270.339106) (xy 368.389813 -270.329278) (xy 368.343874 -270.311856)
			(xy 368.301324 -270.28729) (xy 368.263266 -270.256216) (xy 368.230685 -270.21944) (xy 368.204426 -270.177914)
			(xy 368.185168 -270.132713) (xy 368.17341 -270.085009) (xy 368.169456 -270.036036) (xy 367.840006 -270.036036)
			(xy 367.839511 -270.060643) (xy 367.831616 -270.10922) (xy 367.816032 -270.155901) (xy 367.793161 -270.199478)
			(xy 367.763596 -270.238822) (xy 367.728103 -270.272914) (xy 367.6876 -270.30087) (xy 367.643138 -270.321968)
			(xy 367.595867 -270.33566) (xy 367.547012 -270.341592) (xy 367.497837 -270.339611) (xy 367.449618 -270.329767)
			(xy 367.403602 -270.312315) (xy 367.360981 -270.287708) (xy 367.32286 -270.256583) (xy 367.290225 -270.219746)
			(xy 367.263922 -270.17815) (xy 367.244631 -270.132874) (xy 367.232854 -270.08509) (xy 367.228894 -270.036036)
			(xy 365.959644 -270.036036) (xy 365.95915 -270.060602) (xy 365.951269 -270.109098) (xy 365.93571 -270.155702)
			(xy 365.912877 -270.199206) (xy 365.883361 -270.238485) (xy 365.847927 -270.27252) (xy 365.807492 -270.30043)
			(xy 365.763103 -270.321493) (xy 365.715911 -270.335162) (xy 365.667137 -270.341084) (xy 365.618045 -270.339106)
			(xy 365.569905 -270.329278) (xy 365.523966 -270.311856) (xy 365.481416 -270.28729) (xy 365.443358 -270.256216)
			(xy 365.410777 -270.21944) (xy 365.384518 -270.177914) (xy 365.36526 -270.132713) (xy 365.353502 -270.085009)
			(xy 365.349548 -270.036036) (xy 365.020098 -270.036036) (xy 365.019603 -270.060643) (xy 365.011708 -270.10922)
			(xy 364.996124 -270.155901) (xy 364.973253 -270.199478) (xy 364.943688 -270.238822) (xy 364.908195 -270.272914)
			(xy 364.867692 -270.30087) (xy 364.82323 -270.321968) (xy 364.775959 -270.33566) (xy 364.727104 -270.341592)
			(xy 364.677929 -270.339611) (xy 364.62971 -270.329767) (xy 364.583694 -270.312315) (xy 364.541073 -270.287708)
			(xy 364.502952 -270.256583) (xy 364.470317 -270.219746) (xy 364.444014 -270.17815) (xy 364.424723 -270.132874)
			(xy 364.412946 -270.08509) (xy 364.408986 -270.036036) (xy 355.625908 -270.036036) (xy 355.625414 -270.060602)
			(xy 355.617533 -270.109098) (xy 355.601974 -270.155702) (xy 355.579141 -270.199206) (xy 355.549625 -270.238485)
			(xy 355.514191 -270.27252) (xy 355.473756 -270.30043) (xy 355.429367 -270.321493) (xy 355.382175 -270.335162)
			(xy 355.333401 -270.341084) (xy 355.284309 -270.339106) (xy 355.236169 -270.329278) (xy 355.19023 -270.311856)
			(xy 355.14768 -270.28729) (xy 355.109622 -270.256216) (xy 355.077041 -270.21944) (xy 355.050782 -270.177914)
			(xy 355.031524 -270.132713) (xy 355.019766 -270.085009) (xy 355.015812 -270.036036) (xy 354.686362 -270.036036)
			(xy 354.685867 -270.060643) (xy 354.677972 -270.10922) (xy 354.662388 -270.155901) (xy 354.639517 -270.199478)
			(xy 354.609952 -270.238822) (xy 354.574459 -270.272914) (xy 354.533956 -270.30087) (xy 354.489494 -270.321968)
			(xy 354.442223 -270.33566) (xy 354.393368 -270.341592) (xy 354.344193 -270.339611) (xy 354.295974 -270.329767)
			(xy 354.249958 -270.312315) (xy 354.207337 -270.287708) (xy 354.169216 -270.256583) (xy 354.136581 -270.219746)
			(xy 354.110278 -270.17815) (xy 354.090987 -270.132874) (xy 354.07921 -270.08509) (xy 354.07525 -270.036036)
			(xy 352.806 -270.036036) (xy 352.805506 -270.060602) (xy 352.797625 -270.109098) (xy 352.782066 -270.155702)
			(xy 352.759233 -270.199206) (xy 352.729717 -270.238485) (xy 352.694283 -270.27252) (xy 352.653848 -270.30043)
			(xy 352.609459 -270.321493) (xy 352.562267 -270.335162) (xy 352.513493 -270.341084) (xy 352.464401 -270.339106)
			(xy 352.416261 -270.329278) (xy 352.370322 -270.311856) (xy 352.327772 -270.28729) (xy 352.289714 -270.256216)
			(xy 352.257133 -270.21944) (xy 352.230874 -270.177914) (xy 352.211616 -270.132713) (xy 352.199858 -270.085009)
			(xy 352.195904 -270.036036) (xy 351.866454 -270.036036) (xy 351.865959 -270.060643) (xy 351.858064 -270.10922)
			(xy 351.84248 -270.155901) (xy 351.819609 -270.199478) (xy 351.790044 -270.238822) (xy 351.754551 -270.272914)
			(xy 351.714048 -270.30087) (xy 351.669586 -270.321968) (xy 351.622315 -270.33566) (xy 351.57346 -270.341592)
			(xy 351.524285 -270.339611) (xy 351.476066 -270.329767) (xy 351.43005 -270.312315) (xy 351.387429 -270.287708)
			(xy 351.349308 -270.256583) (xy 351.316673 -270.219746) (xy 351.29037 -270.17815) (xy 351.271079 -270.132874)
			(xy 351.259302 -270.08509) (xy 351.255342 -270.036036) (xy 349.985838 -270.036036) (xy 349.985344 -270.060602)
			(xy 349.977463 -270.109098) (xy 349.961904 -270.155702) (xy 349.939071 -270.199206) (xy 349.909555 -270.238485)
			(xy 349.874121 -270.27252) (xy 349.833686 -270.30043) (xy 349.789297 -270.321493) (xy 349.742105 -270.335162)
			(xy 349.693331 -270.341084) (xy 349.644239 -270.339106) (xy 349.596099 -270.329278) (xy 349.55016 -270.311856)
			(xy 349.50761 -270.28729) (xy 349.469552 -270.256216) (xy 349.436971 -270.21944) (xy 349.410712 -270.177914)
			(xy 349.391454 -270.132713) (xy 349.379696 -270.085009) (xy 349.375742 -270.036036) (xy 349.046292 -270.036036)
			(xy 349.045797 -270.060643) (xy 349.037902 -270.10922) (xy 349.022318 -270.155901) (xy 348.999447 -270.199478)
			(xy 348.969882 -270.238822) (xy 348.934389 -270.272914) (xy 348.893886 -270.30087) (xy 348.849424 -270.321968)
			(xy 348.802153 -270.33566) (xy 348.753298 -270.341592) (xy 348.704123 -270.339611) (xy 348.655904 -270.329767)
			(xy 348.609888 -270.312315) (xy 348.567267 -270.287708) (xy 348.529146 -270.256583) (xy 348.496511 -270.219746)
			(xy 348.470208 -270.17815) (xy 348.450917 -270.132874) (xy 348.43914 -270.08509) (xy 348.43518 -270.036036)
			(xy 347.16593 -270.036036) (xy 347.165436 -270.060602) (xy 347.157555 -270.109098) (xy 347.141996 -270.155702)
			(xy 347.119163 -270.199206) (xy 347.089647 -270.238485) (xy 347.054213 -270.27252) (xy 347.013778 -270.30043)
			(xy 346.969389 -270.321493) (xy 346.922197 -270.335162) (xy 346.873423 -270.341084) (xy 346.824331 -270.339106)
			(xy 346.776191 -270.329278) (xy 346.730252 -270.311856) (xy 346.687702 -270.28729) (xy 346.649644 -270.256216)
			(xy 346.617063 -270.21944) (xy 346.590804 -270.177914) (xy 346.571546 -270.132713) (xy 346.559788 -270.085009)
			(xy 346.555834 -270.036036) (xy 346.226384 -270.036036) (xy 346.225889 -270.060643) (xy 346.217994 -270.10922)
			(xy 346.20241 -270.155901) (xy 346.179539 -270.199478) (xy 346.149974 -270.238822) (xy 346.114481 -270.272914)
			(xy 346.073978 -270.30087) (xy 346.029516 -270.321968) (xy 345.982245 -270.33566) (xy 345.93339 -270.341592)
			(xy 345.884215 -270.339611) (xy 345.835996 -270.329767) (xy 345.78998 -270.312315) (xy 345.747359 -270.287708)
			(xy 345.709238 -270.256583) (xy 345.676603 -270.219746) (xy 345.6503 -270.17815) (xy 345.631009 -270.132874)
			(xy 345.619232 -270.08509) (xy 345.615272 -270.036036) (xy 126.479549 -270.036036) (xy 126.479554 -270.03629)
			(xy 126.47906 -270.060856) (xy 126.471179 -270.109352) (xy 126.45562 -270.155956) (xy 126.432787 -270.19946)
			(xy 126.403271 -270.238739) (xy 126.367837 -270.272774) (xy 126.327402 -270.300684) (xy 126.283013 -270.321747)
			(xy 126.235821 -270.335416) (xy 126.187047 -270.341338) (xy 126.137955 -270.33936) (xy 126.089815 -270.329532)
			(xy 126.043876 -270.31211) (xy 126.001326 -270.287544) (xy 125.963268 -270.25647) (xy 125.930687 -270.219694)
			(xy 125.904428 -270.178168) (xy 125.88517 -270.132967) (xy 125.873412 -270.085263) (xy 125.869458 -270.03629)
			(xy 125.540008 -270.03629) (xy 125.539513 -270.060897) (xy 125.531618 -270.109474) (xy 125.516034 -270.156155)
			(xy 125.493163 -270.199732) (xy 125.463598 -270.239076) (xy 125.428105 -270.273168) (xy 125.387602 -270.301124)
			(xy 125.34314 -270.322222) (xy 125.295869 -270.335914) (xy 125.247014 -270.341846) (xy 125.197839 -270.339865)
			(xy 125.14962 -270.330021) (xy 125.103604 -270.312569) (xy 125.060983 -270.287962) (xy 125.022862 -270.256837)
			(xy 124.990227 -270.22) (xy 124.963924 -270.178404) (xy 124.944633 -270.133128) (xy 124.932856 -270.085344)
			(xy 124.928896 -270.03629) (xy 123.659646 -270.03629) (xy 123.659152 -270.060856) (xy 123.651271 -270.109352)
			(xy 123.635712 -270.155956) (xy 123.612879 -270.19946) (xy 123.583363 -270.238739) (xy 123.547929 -270.272774)
			(xy 123.507494 -270.300684) (xy 123.463105 -270.321747) (xy 123.415913 -270.335416) (xy 123.367139 -270.341338)
			(xy 123.318047 -270.33936) (xy 123.269907 -270.329532) (xy 123.223968 -270.31211) (xy 123.181418 -270.287544)
			(xy 123.14336 -270.25647) (xy 123.110779 -270.219694) (xy 123.08452 -270.178168) (xy 123.065262 -270.132967)
			(xy 123.053504 -270.085263) (xy 123.04955 -270.03629) (xy 122.7201 -270.03629) (xy 122.719605 -270.060897)
			(xy 122.71171 -270.109474) (xy 122.696126 -270.156155) (xy 122.673255 -270.199732) (xy 122.64369 -270.239076)
			(xy 122.608197 -270.273168) (xy 122.567694 -270.301124) (xy 122.523232 -270.322222) (xy 122.475961 -270.335914)
			(xy 122.427106 -270.341846) (xy 122.377931 -270.339865) (xy 122.329712 -270.330021) (xy 122.283696 -270.312569)
			(xy 122.241075 -270.287962) (xy 122.202954 -270.256837) (xy 122.170319 -270.22) (xy 122.144016 -270.178404)
			(xy 122.124725 -270.133128) (xy 122.112948 -270.085344) (xy 122.108988 -270.03629) (xy 120.839484 -270.03629)
			(xy 120.83899 -270.060856) (xy 120.831109 -270.109352) (xy 120.81555 -270.155956) (xy 120.792717 -270.19946)
			(xy 120.763201 -270.238739) (xy 120.727767 -270.272774) (xy 120.687332 -270.300684) (xy 120.642943 -270.321747)
			(xy 120.595751 -270.335416) (xy 120.546977 -270.341338) (xy 120.497885 -270.33936) (xy 120.449745 -270.329532)
			(xy 120.403806 -270.31211) (xy 120.361256 -270.287544) (xy 120.323198 -270.25647) (xy 120.290617 -270.219694)
			(xy 120.264358 -270.178168) (xy 120.2451 -270.132967) (xy 120.233342 -270.085263) (xy 120.229388 -270.03629)
			(xy 119.899938 -270.03629) (xy 119.899443 -270.060897) (xy 119.891548 -270.109474) (xy 119.875964 -270.156155)
			(xy 119.853093 -270.199732) (xy 119.823528 -270.239076) (xy 119.788035 -270.273168) (xy 119.747532 -270.301124)
			(xy 119.70307 -270.322222) (xy 119.655799 -270.335914) (xy 119.606944 -270.341846) (xy 119.557769 -270.339865)
			(xy 119.50955 -270.330021) (xy 119.463534 -270.312569) (xy 119.420913 -270.287962) (xy 119.382792 -270.256837)
			(xy 119.350157 -270.22) (xy 119.323854 -270.178404) (xy 119.304563 -270.133128) (xy 119.292786 -270.085344)
			(xy 119.288826 -270.03629) (xy 118.019576 -270.03629) (xy 118.019082 -270.060856) (xy 118.011201 -270.109352)
			(xy 117.995642 -270.155956) (xy 117.972809 -270.19946) (xy 117.943293 -270.238739) (xy 117.907859 -270.272774)
			(xy 117.867424 -270.300684) (xy 117.823035 -270.321747) (xy 117.775843 -270.335416) (xy 117.727069 -270.341338)
			(xy 117.677977 -270.33936) (xy 117.629837 -270.329532) (xy 117.583898 -270.31211) (xy 117.541348 -270.287544)
			(xy 117.50329 -270.25647) (xy 117.470709 -270.219694) (xy 117.44445 -270.178168) (xy 117.425192 -270.132967)
			(xy 117.413434 -270.085263) (xy 117.40948 -270.03629) (xy 117.08003 -270.03629) (xy 117.079535 -270.060897)
			(xy 117.07164 -270.109474) (xy 117.056056 -270.156155) (xy 117.033185 -270.199732) (xy 117.00362 -270.239076)
			(xy 116.968127 -270.273168) (xy 116.927624 -270.301124) (xy 116.883162 -270.322222) (xy 116.835891 -270.335914)
			(xy 116.787036 -270.341846) (xy 116.737861 -270.339865) (xy 116.689642 -270.330021) (xy 116.643626 -270.312569)
			(xy 116.601005 -270.287962) (xy 116.562884 -270.256837) (xy 116.530249 -270.22) (xy 116.503946 -270.178404)
			(xy 116.484655 -270.133128) (xy 116.472878 -270.085344) (xy 116.468918 -270.03629) (xy 107.68584 -270.03629)
			(xy 107.685346 -270.060856) (xy 107.677465 -270.109352) (xy 107.661906 -270.155956) (xy 107.639073 -270.19946)
			(xy 107.609557 -270.238739) (xy 107.574123 -270.272774) (xy 107.533688 -270.300684) (xy 107.489299 -270.321747)
			(xy 107.442107 -270.335416) (xy 107.393333 -270.341338) (xy 107.344241 -270.33936) (xy 107.296101 -270.329532)
			(xy 107.250162 -270.31211) (xy 107.207612 -270.287544) (xy 107.169554 -270.25647) (xy 107.136973 -270.219694)
			(xy 107.110714 -270.178168) (xy 107.091456 -270.132967) (xy 107.079698 -270.085263) (xy 107.075744 -270.03629)
			(xy 106.746294 -270.03629) (xy 106.745799 -270.060897) (xy 106.737904 -270.109474) (xy 106.72232 -270.156155)
			(xy 106.699449 -270.199732) (xy 106.669884 -270.239076) (xy 106.634391 -270.273168) (xy 106.593888 -270.301124)
			(xy 106.549426 -270.322222) (xy 106.502155 -270.335914) (xy 106.4533 -270.341846) (xy 106.404125 -270.339865)
			(xy 106.355906 -270.330021) (xy 106.30989 -270.312569) (xy 106.267269 -270.287962) (xy 106.229148 -270.256837)
			(xy 106.196513 -270.22) (xy 106.17021 -270.178404) (xy 106.150919 -270.133128) (xy 106.139142 -270.085344)
			(xy 106.135182 -270.03629) (xy 104.865932 -270.03629) (xy 104.865438 -270.060856) (xy 104.857557 -270.109352)
			(xy 104.841998 -270.155956) (xy 104.819165 -270.19946) (xy 104.789649 -270.238739) (xy 104.754215 -270.272774)
			(xy 104.71378 -270.300684) (xy 104.669391 -270.321747) (xy 104.622199 -270.335416) (xy 104.573425 -270.341338)
			(xy 104.524333 -270.33936) (xy 104.476193 -270.329532) (xy 104.430254 -270.31211) (xy 104.387704 -270.287544)
			(xy 104.349646 -270.25647) (xy 104.317065 -270.219694) (xy 104.290806 -270.178168) (xy 104.271548 -270.132967)
			(xy 104.25979 -270.085263) (xy 104.255836 -270.03629) (xy 103.926386 -270.03629) (xy 103.925891 -270.060897)
			(xy 103.917996 -270.109474) (xy 103.902412 -270.156155) (xy 103.879541 -270.199732) (xy 103.849976 -270.239076)
			(xy 103.814483 -270.273168) (xy 103.77398 -270.301124) (xy 103.729518 -270.322222) (xy 103.682247 -270.335914)
			(xy 103.633392 -270.341846) (xy 103.584217 -270.339865) (xy 103.535998 -270.330021) (xy 103.489982 -270.312569)
			(xy 103.447361 -270.287962) (xy 103.40924 -270.256837) (xy 103.376605 -270.22) (xy 103.350302 -270.178404)
			(xy 103.331011 -270.133128) (xy 103.319234 -270.085344) (xy 103.315274 -270.03629) (xy 102.04577 -270.03629)
			(xy 102.045276 -270.060856) (xy 102.037395 -270.109352) (xy 102.021836 -270.155956) (xy 101.999003 -270.19946)
			(xy 101.969487 -270.238739) (xy 101.934053 -270.272774) (xy 101.893618 -270.300684) (xy 101.849229 -270.321747)
			(xy 101.802037 -270.335416) (xy 101.753263 -270.341338) (xy 101.704171 -270.33936) (xy 101.656031 -270.329532)
			(xy 101.610092 -270.31211) (xy 101.567542 -270.287544) (xy 101.529484 -270.25647) (xy 101.496903 -270.219694)
			(xy 101.470644 -270.178168) (xy 101.451386 -270.132967) (xy 101.439628 -270.085263) (xy 101.435674 -270.03629)
			(xy 101.106224 -270.03629) (xy 101.105729 -270.060897) (xy 101.097834 -270.109474) (xy 101.08225 -270.156155)
			(xy 101.059379 -270.199732) (xy 101.029814 -270.239076) (xy 100.994321 -270.273168) (xy 100.953818 -270.301124)
			(xy 100.909356 -270.322222) (xy 100.862085 -270.335914) (xy 100.81323 -270.341846) (xy 100.764055 -270.339865)
			(xy 100.715836 -270.330021) (xy 100.66982 -270.312569) (xy 100.627199 -270.287962) (xy 100.589078 -270.256837)
			(xy 100.556443 -270.22) (xy 100.53014 -270.178404) (xy 100.510849 -270.133128) (xy 100.499072 -270.085344)
			(xy 100.495112 -270.03629) (xy 99.225862 -270.03629) (xy 99.225368 -270.060856) (xy 99.217487 -270.109352)
			(xy 99.201928 -270.155956) (xy 99.179095 -270.19946) (xy 99.149579 -270.238739) (xy 99.114145 -270.272774)
			(xy 99.07371 -270.300684) (xy 99.029321 -270.321747) (xy 98.982129 -270.335416) (xy 98.933355 -270.341338)
			(xy 98.884263 -270.33936) (xy 98.836123 -270.329532) (xy 98.790184 -270.31211) (xy 98.747634 -270.287544)
			(xy 98.709576 -270.25647) (xy 98.676995 -270.219694) (xy 98.650736 -270.178168) (xy 98.631478 -270.132967)
			(xy 98.61972 -270.085263) (xy 98.615766 -270.03629) (xy 98.286316 -270.03629) (xy 98.285821 -270.060897)
			(xy 98.277926 -270.109474) (xy 98.262342 -270.156155) (xy 98.239471 -270.199732) (xy 98.209906 -270.239076)
			(xy 98.174413 -270.273168) (xy 98.13391 -270.301124) (xy 98.089448 -270.322222) (xy 98.042177 -270.335914)
			(xy 97.993322 -270.341846) (xy 97.944147 -270.339865) (xy 97.895928 -270.330021) (xy 97.849912 -270.312569)
			(xy 97.807291 -270.287962) (xy 97.76917 -270.256837) (xy 97.736535 -270.22) (xy 97.710232 -270.178404)
			(xy 97.690941 -270.133128) (xy 97.679164 -270.085344) (xy 97.675204 -270.03629) (xy 2.509012 -270.03629)
			(xy 2.509012 -270.846296) (xy 108.48519 -270.846296) (xy 108.48915 -270.797242) (xy 108.500927 -270.749458)
			(xy 108.520218 -270.704182) (xy 108.546521 -270.662586) (xy 108.579156 -270.625749) (xy 108.617277 -270.594624)
			(xy 108.659898 -270.570017) (xy 108.705914 -270.552565) (xy 108.754133 -270.542721) (xy 108.803308 -270.54074)
			(xy 108.852163 -270.546672) (xy 108.899434 -270.560364) (xy 108.943896 -270.581462) (xy 108.984399 -270.609418)
			(xy 109.019892 -270.64351) (xy 109.049457 -270.682854) (xy 109.072328 -270.726431) (xy 109.087912 -270.773112)
			(xy 109.095807 -270.821689) (xy 109.096302 -270.846296) (xy 109.425752 -270.846296) (xy 109.429706 -270.797323)
			(xy 109.441464 -270.749619) (xy 109.460722 -270.704418) (xy 109.486981 -270.662892) (xy 109.519562 -270.626116)
			(xy 109.55762 -270.595042) (xy 109.60017 -270.570476) (xy 109.646109 -270.553054) (xy 109.694249 -270.543226)
			(xy 109.743341 -270.541248) (xy 109.792115 -270.54717) (xy 109.839307 -270.560839) (xy 109.883696 -270.581902)
			(xy 109.924131 -270.609812) (xy 109.959565 -270.643847) (xy 109.989081 -270.683126) (xy 110.011914 -270.72663)
			(xy 110.027473 -270.773234) (xy 110.035354 -270.82173) (xy 110.035848 -270.846296) (xy 114.11891 -270.846296)
			(xy 114.12287 -270.797242) (xy 114.134647 -270.749458) (xy 114.153938 -270.704182) (xy 114.180241 -270.662586)
			(xy 114.212876 -270.625749) (xy 114.250997 -270.594624) (xy 114.293618 -270.570017) (xy 114.339634 -270.552565)
			(xy 114.387853 -270.542721) (xy 114.437028 -270.54074) (xy 114.485883 -270.546672) (xy 114.533154 -270.560364)
			(xy 114.577616 -270.581462) (xy 114.618119 -270.609418) (xy 114.653612 -270.64351) (xy 114.683177 -270.682854)
			(xy 114.706048 -270.726431) (xy 114.721632 -270.773112) (xy 114.729527 -270.821689) (xy 114.730022 -270.846296)
			(xy 115.059472 -270.846296) (xy 115.063426 -270.797323) (xy 115.075184 -270.749619) (xy 115.094442 -270.704418)
			(xy 115.120701 -270.662892) (xy 115.153282 -270.626116) (xy 115.19134 -270.595042) (xy 115.23389 -270.570476)
			(xy 115.279829 -270.553054) (xy 115.327969 -270.543226) (xy 115.377061 -270.541248) (xy 115.425835 -270.54717)
			(xy 115.473027 -270.560839) (xy 115.517416 -270.581902) (xy 115.557851 -270.609812) (xy 115.593285 -270.643847)
			(xy 115.622801 -270.683126) (xy 115.645634 -270.72663) (xy 115.661193 -270.773234) (xy 115.669074 -270.82173)
			(xy 115.669563 -270.846042) (xy 356.425258 -270.846042) (xy 356.429218 -270.796988) (xy 356.440995 -270.749204)
			(xy 356.460286 -270.703928) (xy 356.486589 -270.662332) (xy 356.519224 -270.625495) (xy 356.557345 -270.59437)
			(xy 356.599966 -270.569763) (xy 356.645982 -270.552311) (xy 356.694201 -270.542467) (xy 356.743376 -270.540486)
			(xy 356.792231 -270.546418) (xy 356.839502 -270.56011) (xy 356.883964 -270.581208) (xy 356.924467 -270.609164)
			(xy 356.95996 -270.643256) (xy 356.989525 -270.6826) (xy 357.012396 -270.726177) (xy 357.02798 -270.772858)
			(xy 357.035875 -270.821435) (xy 357.03637 -270.846042) (xy 357.36582 -270.846042) (xy 357.369774 -270.797069)
			(xy 357.381532 -270.749365) (xy 357.40079 -270.704164) (xy 357.427049 -270.662638) (xy 357.45963 -270.625862)
			(xy 357.497688 -270.594788) (xy 357.540238 -270.570222) (xy 357.586177 -270.5528) (xy 357.634317 -270.542972)
			(xy 357.683409 -270.540994) (xy 357.732183 -270.546916) (xy 357.779375 -270.560585) (xy 357.823764 -270.581648)
			(xy 357.864199 -270.609558) (xy 357.899633 -270.643593) (xy 357.929149 -270.682872) (xy 357.951982 -270.726376)
			(xy 357.967541 -270.77298) (xy 357.975422 -270.821476) (xy 357.975916 -270.846042) (xy 362.058978 -270.846042)
			(xy 362.062938 -270.796988) (xy 362.074715 -270.749204) (xy 362.094006 -270.703928) (xy 362.120309 -270.662332)
			(xy 362.152944 -270.625495) (xy 362.191065 -270.59437) (xy 362.233686 -270.569763) (xy 362.279702 -270.552311)
			(xy 362.327921 -270.542467) (xy 362.377096 -270.540486) (xy 362.425951 -270.546418) (xy 362.473222 -270.56011)
			(xy 362.517684 -270.581208) (xy 362.558187 -270.609164) (xy 362.59368 -270.643256) (xy 362.623245 -270.6826)
			(xy 362.646116 -270.726177) (xy 362.6617 -270.772858) (xy 362.669595 -270.821435) (xy 362.67009 -270.846042)
			(xy 362.99954 -270.846042) (xy 363.003494 -270.797069) (xy 363.015252 -270.749365) (xy 363.03451 -270.704164)
			(xy 363.060769 -270.662638) (xy 363.09335 -270.625862) (xy 363.131408 -270.594788) (xy 363.173958 -270.570222)
			(xy 363.219897 -270.5528) (xy 363.268037 -270.542972) (xy 363.317129 -270.540994) (xy 363.365903 -270.546916)
			(xy 363.413095 -270.560585) (xy 363.457484 -270.581648) (xy 363.497919 -270.609558) (xy 363.533353 -270.643593)
			(xy 363.562869 -270.682872) (xy 363.585702 -270.726376) (xy 363.601261 -270.77298) (xy 363.609142 -270.821476)
			(xy 363.609636 -270.846042) (xy 363.609142 -270.870608) (xy 363.601261 -270.919104) (xy 363.585702 -270.965708)
			(xy 363.562869 -271.009212) (xy 363.533353 -271.048491) (xy 363.497919 -271.082526) (xy 363.457484 -271.110436)
			(xy 363.413095 -271.131499) (xy 363.365903 -271.145168) (xy 363.317129 -271.15109) (xy 363.268037 -271.149112)
			(xy 363.219897 -271.139284) (xy 363.173958 -271.121862) (xy 363.131408 -271.097296) (xy 363.09335 -271.066222)
			(xy 363.060769 -271.029446) (xy 363.03451 -270.98792) (xy 363.015252 -270.942719) (xy 363.003494 -270.895015)
			(xy 362.99954 -270.846042) (xy 362.67009 -270.846042) (xy 362.669595 -270.870649) (xy 362.6617 -270.919226)
			(xy 362.646116 -270.965907) (xy 362.623245 -271.009484) (xy 362.59368 -271.048828) (xy 362.558187 -271.08292)
			(xy 362.517684 -271.110876) (xy 362.473222 -271.131974) (xy 362.425951 -271.145666) (xy 362.377096 -271.151598)
			(xy 362.327921 -271.149617) (xy 362.279702 -271.139773) (xy 362.233686 -271.122321) (xy 362.191065 -271.097714)
			(xy 362.152944 -271.066589) (xy 362.120309 -271.029752) (xy 362.094006 -270.988156) (xy 362.074715 -270.94288)
			(xy 362.062938 -270.895096) (xy 362.058978 -270.846042) (xy 357.975916 -270.846042) (xy 357.975422 -270.870608)
			(xy 357.967541 -270.919104) (xy 357.951982 -270.965708) (xy 357.929149 -271.009212) (xy 357.899633 -271.048491)
			(xy 357.864199 -271.082526) (xy 357.823764 -271.110436) (xy 357.779375 -271.131499) (xy 357.732183 -271.145168)
			(xy 357.683409 -271.15109) (xy 357.634317 -271.149112) (xy 357.586177 -271.139284) (xy 357.540238 -271.121862)
			(xy 357.497688 -271.097296) (xy 357.45963 -271.066222) (xy 357.427049 -271.029446) (xy 357.40079 -270.98792)
			(xy 357.381532 -270.942719) (xy 357.369774 -270.895015) (xy 357.36582 -270.846042) (xy 357.03637 -270.846042)
			(xy 357.035875 -270.870649) (xy 357.02798 -270.919226) (xy 357.012396 -270.965907) (xy 356.989525 -271.009484)
			(xy 356.95996 -271.048828) (xy 356.924467 -271.08292) (xy 356.883964 -271.110876) (xy 356.839502 -271.131974)
			(xy 356.792231 -271.145666) (xy 356.743376 -271.151598) (xy 356.694201 -271.149617) (xy 356.645982 -271.139773)
			(xy 356.599966 -271.122321) (xy 356.557345 -271.097714) (xy 356.519224 -271.066589) (xy 356.486589 -271.029752)
			(xy 356.460286 -270.988156) (xy 356.440995 -270.94288) (xy 356.429218 -270.895096) (xy 356.425258 -270.846042)
			(xy 115.669563 -270.846042) (xy 115.669568 -270.846296) (xy 115.669074 -270.870862) (xy 115.661193 -270.919358)
			(xy 115.645634 -270.965962) (xy 115.622801 -271.009466) (xy 115.593285 -271.048745) (xy 115.557851 -271.08278)
			(xy 115.517416 -271.11069) (xy 115.473027 -271.131753) (xy 115.425835 -271.145422) (xy 115.377061 -271.151344)
			(xy 115.327969 -271.149366) (xy 115.279829 -271.139538) (xy 115.23389 -271.122116) (xy 115.19134 -271.09755)
			(xy 115.153282 -271.066476) (xy 115.120701 -271.0297) (xy 115.094442 -270.988174) (xy 115.075184 -270.942973)
			(xy 115.063426 -270.895269) (xy 115.059472 -270.846296) (xy 114.730022 -270.846296) (xy 114.729527 -270.870903)
			(xy 114.721632 -270.91948) (xy 114.706048 -270.966161) (xy 114.683177 -271.009738) (xy 114.653612 -271.049082)
			(xy 114.618119 -271.083174) (xy 114.577616 -271.11113) (xy 114.533154 -271.132228) (xy 114.485883 -271.14592)
			(xy 114.437028 -271.151852) (xy 114.387853 -271.149871) (xy 114.339634 -271.140027) (xy 114.293618 -271.122575)
			(xy 114.250997 -271.097968) (xy 114.212876 -271.066843) (xy 114.180241 -271.030006) (xy 114.153938 -270.98841)
			(xy 114.134647 -270.943134) (xy 114.12287 -270.89535) (xy 114.11891 -270.846296) (xy 110.035848 -270.846296)
			(xy 110.035354 -270.870862) (xy 110.027473 -270.919358) (xy 110.011914 -270.965962) (xy 109.989081 -271.009466)
			(xy 109.959565 -271.048745) (xy 109.924131 -271.08278) (xy 109.883696 -271.11069) (xy 109.839307 -271.131753)
			(xy 109.792115 -271.145422) (xy 109.743341 -271.151344) (xy 109.694249 -271.149366) (xy 109.646109 -271.139538)
			(xy 109.60017 -271.122116) (xy 109.55762 -271.09755) (xy 109.519562 -271.066476) (xy 109.486981 -271.0297)
			(xy 109.460722 -270.988174) (xy 109.441464 -270.942973) (xy 109.429706 -270.895269) (xy 109.425752 -270.846296)
			(xy 109.096302 -270.846296) (xy 109.095807 -270.870903) (xy 109.087912 -270.91948) (xy 109.072328 -270.966161)
			(xy 109.049457 -271.009738) (xy 109.019892 -271.049082) (xy 108.984399 -271.083174) (xy 108.943896 -271.11113)
			(xy 108.899434 -271.132228) (xy 108.852163 -271.14592) (xy 108.803308 -271.151852) (xy 108.754133 -271.149871)
			(xy 108.705914 -271.140027) (xy 108.659898 -271.122575) (xy 108.617277 -271.097968) (xy 108.579156 -271.066843)
			(xy 108.546521 -271.030006) (xy 108.520218 -270.98841) (xy 108.500927 -270.943134) (xy 108.48915 -270.89535)
			(xy 108.48519 -270.846296) (xy 2.509012 -270.846296) (xy 2.509012 -271.656302) (xy 97.675204 -271.656302)
			(xy 97.679164 -271.607248) (xy 97.690941 -271.559464) (xy 97.710232 -271.514188) (xy 97.736535 -271.472592)
			(xy 97.76917 -271.435755) (xy 97.807291 -271.40463) (xy 97.849912 -271.380023) (xy 97.895928 -271.362571)
			(xy 97.944147 -271.352727) (xy 97.993322 -271.350746) (xy 98.042177 -271.356678) (xy 98.089448 -271.37037)
			(xy 98.13391 -271.391468) (xy 98.174413 -271.419424) (xy 98.209906 -271.453516) (xy 98.239471 -271.49286)
			(xy 98.262342 -271.536437) (xy 98.277926 -271.583118) (xy 98.285821 -271.631695) (xy 98.286316 -271.656302)
			(xy 98.615766 -271.656302) (xy 98.61972 -271.607329) (xy 98.631478 -271.559625) (xy 98.650736 -271.514424)
			(xy 98.676995 -271.472898) (xy 98.709576 -271.436122) (xy 98.747634 -271.405048) (xy 98.790184 -271.380482)
			(xy 98.836123 -271.36306) (xy 98.884263 -271.353232) (xy 98.933355 -271.351254) (xy 98.982129 -271.357176)
			(xy 99.029321 -271.370845) (xy 99.07371 -271.391908) (xy 99.114145 -271.419818) (xy 99.149579 -271.453853)
			(xy 99.179095 -271.493132) (xy 99.201928 -271.536636) (xy 99.217487 -271.58324) (xy 99.225368 -271.631736)
			(xy 99.225862 -271.656302) (xy 100.495112 -271.656302) (xy 100.499072 -271.607248) (xy 100.510849 -271.559464)
			(xy 100.53014 -271.514188) (xy 100.556443 -271.472592) (xy 100.589078 -271.435755) (xy 100.627199 -271.40463)
			(xy 100.66982 -271.380023) (xy 100.715836 -271.362571) (xy 100.764055 -271.352727) (xy 100.81323 -271.350746)
			(xy 100.862085 -271.356678) (xy 100.909356 -271.37037) (xy 100.953818 -271.391468) (xy 100.994321 -271.419424)
			(xy 101.029814 -271.453516) (xy 101.059379 -271.49286) (xy 101.08225 -271.536437) (xy 101.097834 -271.583118)
			(xy 101.105729 -271.631695) (xy 101.106224 -271.656302) (xy 101.435674 -271.656302) (xy 101.439628 -271.607329)
			(xy 101.451386 -271.559625) (xy 101.470644 -271.514424) (xy 101.496903 -271.472898) (xy 101.529484 -271.436122)
			(xy 101.567542 -271.405048) (xy 101.610092 -271.380482) (xy 101.656031 -271.36306) (xy 101.704171 -271.353232)
			(xy 101.753263 -271.351254) (xy 101.802037 -271.357176) (xy 101.849229 -271.370845) (xy 101.893618 -271.391908)
			(xy 101.934053 -271.419818) (xy 101.969487 -271.453853) (xy 101.999003 -271.493132) (xy 102.021836 -271.536636)
			(xy 102.037395 -271.58324) (xy 102.045276 -271.631736) (xy 102.04577 -271.656302) (xy 103.315274 -271.656302)
			(xy 103.319234 -271.607248) (xy 103.331011 -271.559464) (xy 103.350302 -271.514188) (xy 103.376605 -271.472592)
			(xy 103.40924 -271.435755) (xy 103.447361 -271.40463) (xy 103.489982 -271.380023) (xy 103.535998 -271.362571)
			(xy 103.584217 -271.352727) (xy 103.633392 -271.350746) (xy 103.682247 -271.356678) (xy 103.729518 -271.37037)
			(xy 103.77398 -271.391468) (xy 103.814483 -271.419424) (xy 103.849976 -271.453516) (xy 103.879541 -271.49286)
			(xy 103.902412 -271.536437) (xy 103.917996 -271.583118) (xy 103.925891 -271.631695) (xy 103.926386 -271.656302)
			(xy 104.255836 -271.656302) (xy 104.25979 -271.607329) (xy 104.271548 -271.559625) (xy 104.290806 -271.514424)
			(xy 104.317065 -271.472898) (xy 104.349646 -271.436122) (xy 104.387704 -271.405048) (xy 104.430254 -271.380482)
			(xy 104.476193 -271.36306) (xy 104.524333 -271.353232) (xy 104.573425 -271.351254) (xy 104.622199 -271.357176)
			(xy 104.669391 -271.370845) (xy 104.71378 -271.391908) (xy 104.754215 -271.419818) (xy 104.789649 -271.453853)
			(xy 104.819165 -271.493132) (xy 104.841998 -271.536636) (xy 104.857557 -271.58324) (xy 104.865438 -271.631736)
			(xy 104.865932 -271.656302) (xy 106.135182 -271.656302) (xy 106.139142 -271.607248) (xy 106.150919 -271.559464)
			(xy 106.17021 -271.514188) (xy 106.196513 -271.472592) (xy 106.229148 -271.435755) (xy 106.267269 -271.40463)
			(xy 106.30989 -271.380023) (xy 106.355906 -271.362571) (xy 106.404125 -271.352727) (xy 106.4533 -271.350746)
			(xy 106.502155 -271.356678) (xy 106.549426 -271.37037) (xy 106.593888 -271.391468) (xy 106.634391 -271.419424)
			(xy 106.669884 -271.453516) (xy 106.699449 -271.49286) (xy 106.72232 -271.536437) (xy 106.737904 -271.583118)
			(xy 106.745799 -271.631695) (xy 106.746294 -271.656302) (xy 107.075744 -271.656302) (xy 107.079698 -271.607329)
			(xy 107.091456 -271.559625) (xy 107.110714 -271.514424) (xy 107.136973 -271.472898) (xy 107.169554 -271.436122)
			(xy 107.207612 -271.405048) (xy 107.250162 -271.380482) (xy 107.296101 -271.36306) (xy 107.344241 -271.353232)
			(xy 107.393333 -271.351254) (xy 107.442107 -271.357176) (xy 107.489299 -271.370845) (xy 107.533688 -271.391908)
			(xy 107.574123 -271.419818) (xy 107.609557 -271.453853) (xy 107.639073 -271.493132) (xy 107.661906 -271.536636)
			(xy 107.677465 -271.58324) (xy 107.685346 -271.631736) (xy 107.68584 -271.656302) (xy 116.468918 -271.656302)
			(xy 116.472878 -271.607248) (xy 116.484655 -271.559464) (xy 116.503946 -271.514188) (xy 116.530249 -271.472592)
			(xy 116.562884 -271.435755) (xy 116.601005 -271.40463) (xy 116.643626 -271.380023) (xy 116.689642 -271.362571)
			(xy 116.737861 -271.352727) (xy 116.787036 -271.350746) (xy 116.835891 -271.356678) (xy 116.883162 -271.37037)
			(xy 116.927624 -271.391468) (xy 116.968127 -271.419424) (xy 117.00362 -271.453516) (xy 117.033185 -271.49286)
			(xy 117.056056 -271.536437) (xy 117.07164 -271.583118) (xy 117.079535 -271.631695) (xy 117.08003 -271.656302)
			(xy 117.40948 -271.656302) (xy 117.413434 -271.607329) (xy 117.425192 -271.559625) (xy 117.44445 -271.514424)
			(xy 117.470709 -271.472898) (xy 117.50329 -271.436122) (xy 117.541348 -271.405048) (xy 117.583898 -271.380482)
			(xy 117.629837 -271.36306) (xy 117.677977 -271.353232) (xy 117.727069 -271.351254) (xy 117.775843 -271.357176)
			(xy 117.823035 -271.370845) (xy 117.867424 -271.391908) (xy 117.907859 -271.419818) (xy 117.943293 -271.453853)
			(xy 117.972809 -271.493132) (xy 117.995642 -271.536636) (xy 118.011201 -271.58324) (xy 118.019082 -271.631736)
			(xy 118.019576 -271.656302) (xy 119.288826 -271.656302) (xy 119.292786 -271.607248) (xy 119.304563 -271.559464)
			(xy 119.323854 -271.514188) (xy 119.350157 -271.472592) (xy 119.382792 -271.435755) (xy 119.420913 -271.40463)
			(xy 119.463534 -271.380023) (xy 119.50955 -271.362571) (xy 119.557769 -271.352727) (xy 119.606944 -271.350746)
			(xy 119.655799 -271.356678) (xy 119.70307 -271.37037) (xy 119.747532 -271.391468) (xy 119.788035 -271.419424)
			(xy 119.823528 -271.453516) (xy 119.853093 -271.49286) (xy 119.875964 -271.536437) (xy 119.891548 -271.583118)
			(xy 119.899443 -271.631695) (xy 119.899938 -271.656302) (xy 120.229388 -271.656302) (xy 120.233342 -271.607329)
			(xy 120.2451 -271.559625) (xy 120.264358 -271.514424) (xy 120.290617 -271.472898) (xy 120.323198 -271.436122)
			(xy 120.361256 -271.405048) (xy 120.403806 -271.380482) (xy 120.449745 -271.36306) (xy 120.497885 -271.353232)
			(xy 120.546977 -271.351254) (xy 120.595751 -271.357176) (xy 120.642943 -271.370845) (xy 120.687332 -271.391908)
			(xy 120.727767 -271.419818) (xy 120.763201 -271.453853) (xy 120.792717 -271.493132) (xy 120.81555 -271.536636)
			(xy 120.831109 -271.58324) (xy 120.83899 -271.631736) (xy 120.839484 -271.656302) (xy 122.108988 -271.656302)
			(xy 122.112948 -271.607248) (xy 122.124725 -271.559464) (xy 122.144016 -271.514188) (xy 122.170319 -271.472592)
			(xy 122.202954 -271.435755) (xy 122.241075 -271.40463) (xy 122.283696 -271.380023) (xy 122.329712 -271.362571)
			(xy 122.377931 -271.352727) (xy 122.427106 -271.350746) (xy 122.475961 -271.356678) (xy 122.523232 -271.37037)
			(xy 122.567694 -271.391468) (xy 122.608197 -271.419424) (xy 122.64369 -271.453516) (xy 122.673255 -271.49286)
			(xy 122.696126 -271.536437) (xy 122.71171 -271.583118) (xy 122.719605 -271.631695) (xy 122.7201 -271.656302)
			(xy 123.04955 -271.656302) (xy 123.053504 -271.607329) (xy 123.065262 -271.559625) (xy 123.08452 -271.514424)
			(xy 123.110779 -271.472898) (xy 123.14336 -271.436122) (xy 123.181418 -271.405048) (xy 123.223968 -271.380482)
			(xy 123.269907 -271.36306) (xy 123.318047 -271.353232) (xy 123.367139 -271.351254) (xy 123.415913 -271.357176)
			(xy 123.463105 -271.370845) (xy 123.507494 -271.391908) (xy 123.547929 -271.419818) (xy 123.583363 -271.453853)
			(xy 123.612879 -271.493132) (xy 123.635712 -271.536636) (xy 123.651271 -271.58324) (xy 123.659152 -271.631736)
			(xy 123.659646 -271.656302) (xy 124.928896 -271.656302) (xy 124.932856 -271.607248) (xy 124.944633 -271.559464)
			(xy 124.963924 -271.514188) (xy 124.990227 -271.472592) (xy 125.022862 -271.435755) (xy 125.060983 -271.40463)
			(xy 125.103604 -271.380023) (xy 125.14962 -271.362571) (xy 125.197839 -271.352727) (xy 125.247014 -271.350746)
			(xy 125.295869 -271.356678) (xy 125.34314 -271.37037) (xy 125.387602 -271.391468) (xy 125.428105 -271.419424)
			(xy 125.463598 -271.453516) (xy 125.493163 -271.49286) (xy 125.516034 -271.536437) (xy 125.531618 -271.583118)
			(xy 125.539513 -271.631695) (xy 125.540008 -271.656302) (xy 125.869458 -271.656302) (xy 125.873412 -271.607329)
			(xy 125.88517 -271.559625) (xy 125.904428 -271.514424) (xy 125.930687 -271.472898) (xy 125.963268 -271.436122)
			(xy 126.001326 -271.405048) (xy 126.043876 -271.380482) (xy 126.089815 -271.36306) (xy 126.137955 -271.353232)
			(xy 126.187047 -271.351254) (xy 126.235821 -271.357176) (xy 126.283013 -271.370845) (xy 126.327402 -271.391908)
			(xy 126.367837 -271.419818) (xy 126.403271 -271.453853) (xy 126.432787 -271.493132) (xy 126.45562 -271.536636)
			(xy 126.471179 -271.58324) (xy 126.47906 -271.631736) (xy 126.479549 -271.656048) (xy 345.615272 -271.656048)
			(xy 345.619232 -271.606994) (xy 345.631009 -271.55921) (xy 345.6503 -271.513934) (xy 345.676603 -271.472338)
			(xy 345.709238 -271.435501) (xy 345.747359 -271.404376) (xy 345.78998 -271.379769) (xy 345.835996 -271.362317)
			(xy 345.884215 -271.352473) (xy 345.93339 -271.350492) (xy 345.982245 -271.356424) (xy 346.029516 -271.370116)
			(xy 346.073978 -271.391214) (xy 346.114481 -271.41917) (xy 346.149974 -271.453262) (xy 346.179539 -271.492606)
			(xy 346.20241 -271.536183) (xy 346.217994 -271.582864) (xy 346.225889 -271.631441) (xy 346.226384 -271.656048)
			(xy 346.555834 -271.656048) (xy 346.559788 -271.607075) (xy 346.571546 -271.559371) (xy 346.590804 -271.51417)
			(xy 346.617063 -271.472644) (xy 346.649644 -271.435868) (xy 346.687702 -271.404794) (xy 346.730252 -271.380228)
			(xy 346.776191 -271.362806) (xy 346.824331 -271.352978) (xy 346.873423 -271.351) (xy 346.922197 -271.356922)
			(xy 346.969389 -271.370591) (xy 347.013778 -271.391654) (xy 347.054213 -271.419564) (xy 347.089647 -271.453599)
			(xy 347.119163 -271.492878) (xy 347.141996 -271.536382) (xy 347.157555 -271.582986) (xy 347.165436 -271.631482)
			(xy 347.16593 -271.656048) (xy 348.43518 -271.656048) (xy 348.43914 -271.606994) (xy 348.450917 -271.55921)
			(xy 348.470208 -271.513934) (xy 348.496511 -271.472338) (xy 348.529146 -271.435501) (xy 348.567267 -271.404376)
			(xy 348.609888 -271.379769) (xy 348.655904 -271.362317) (xy 348.704123 -271.352473) (xy 348.753298 -271.350492)
			(xy 348.802153 -271.356424) (xy 348.849424 -271.370116) (xy 348.893886 -271.391214) (xy 348.934389 -271.41917)
			(xy 348.969882 -271.453262) (xy 348.999447 -271.492606) (xy 349.022318 -271.536183) (xy 349.037902 -271.582864)
			(xy 349.045797 -271.631441) (xy 349.046292 -271.656048) (xy 349.375742 -271.656048) (xy 349.379696 -271.607075)
			(xy 349.391454 -271.559371) (xy 349.410712 -271.51417) (xy 349.436971 -271.472644) (xy 349.469552 -271.435868)
			(xy 349.50761 -271.404794) (xy 349.55016 -271.380228) (xy 349.596099 -271.362806) (xy 349.644239 -271.352978)
			(xy 349.693331 -271.351) (xy 349.742105 -271.356922) (xy 349.789297 -271.370591) (xy 349.833686 -271.391654)
			(xy 349.874121 -271.419564) (xy 349.909555 -271.453599) (xy 349.939071 -271.492878) (xy 349.961904 -271.536382)
			(xy 349.977463 -271.582986) (xy 349.985344 -271.631482) (xy 349.985838 -271.656048) (xy 351.255342 -271.656048)
			(xy 351.259302 -271.606994) (xy 351.271079 -271.55921) (xy 351.29037 -271.513934) (xy 351.316673 -271.472338)
			(xy 351.349308 -271.435501) (xy 351.387429 -271.404376) (xy 351.43005 -271.379769) (xy 351.476066 -271.362317)
			(xy 351.524285 -271.352473) (xy 351.57346 -271.350492) (xy 351.622315 -271.356424) (xy 351.669586 -271.370116)
			(xy 351.714048 -271.391214) (xy 351.754551 -271.41917) (xy 351.790044 -271.453262) (xy 351.819609 -271.492606)
			(xy 351.84248 -271.536183) (xy 351.858064 -271.582864) (xy 351.865959 -271.631441) (xy 351.866454 -271.656048)
			(xy 352.195904 -271.656048) (xy 352.199858 -271.607075) (xy 352.211616 -271.559371) (xy 352.230874 -271.51417)
			(xy 352.257133 -271.472644) (xy 352.289714 -271.435868) (xy 352.327772 -271.404794) (xy 352.370322 -271.380228)
			(xy 352.416261 -271.362806) (xy 352.464401 -271.352978) (xy 352.513493 -271.351) (xy 352.562267 -271.356922)
			(xy 352.609459 -271.370591) (xy 352.653848 -271.391654) (xy 352.694283 -271.419564) (xy 352.729717 -271.453599)
			(xy 352.759233 -271.492878) (xy 352.782066 -271.536382) (xy 352.797625 -271.582986) (xy 352.805506 -271.631482)
			(xy 352.806 -271.656048) (xy 354.07525 -271.656048) (xy 354.07921 -271.606994) (xy 354.090987 -271.55921)
			(xy 354.110278 -271.513934) (xy 354.136581 -271.472338) (xy 354.169216 -271.435501) (xy 354.207337 -271.404376)
			(xy 354.249958 -271.379769) (xy 354.295974 -271.362317) (xy 354.344193 -271.352473) (xy 354.393368 -271.350492)
			(xy 354.442223 -271.356424) (xy 354.489494 -271.370116) (xy 354.533956 -271.391214) (xy 354.574459 -271.41917)
			(xy 354.609952 -271.453262) (xy 354.639517 -271.492606) (xy 354.662388 -271.536183) (xy 354.677972 -271.582864)
			(xy 354.685867 -271.631441) (xy 354.686362 -271.656048) (xy 355.015812 -271.656048) (xy 355.019766 -271.607075)
			(xy 355.031524 -271.559371) (xy 355.050782 -271.51417) (xy 355.077041 -271.472644) (xy 355.109622 -271.435868)
			(xy 355.14768 -271.404794) (xy 355.19023 -271.380228) (xy 355.236169 -271.362806) (xy 355.284309 -271.352978)
			(xy 355.333401 -271.351) (xy 355.382175 -271.356922) (xy 355.429367 -271.370591) (xy 355.473756 -271.391654)
			(xy 355.514191 -271.419564) (xy 355.549625 -271.453599) (xy 355.579141 -271.492878) (xy 355.601974 -271.536382)
			(xy 355.617533 -271.582986) (xy 355.625414 -271.631482) (xy 355.625908 -271.656048) (xy 364.408986 -271.656048)
			(xy 364.412946 -271.606994) (xy 364.424723 -271.55921) (xy 364.444014 -271.513934) (xy 364.470317 -271.472338)
			(xy 364.502952 -271.435501) (xy 364.541073 -271.404376) (xy 364.583694 -271.379769) (xy 364.62971 -271.362317)
			(xy 364.677929 -271.352473) (xy 364.727104 -271.350492) (xy 364.775959 -271.356424) (xy 364.82323 -271.370116)
			(xy 364.867692 -271.391214) (xy 364.908195 -271.41917) (xy 364.943688 -271.453262) (xy 364.973253 -271.492606)
			(xy 364.996124 -271.536183) (xy 365.011708 -271.582864) (xy 365.019603 -271.631441) (xy 365.020098 -271.656048)
			(xy 365.349548 -271.656048) (xy 365.353502 -271.607075) (xy 365.36526 -271.559371) (xy 365.384518 -271.51417)
			(xy 365.410777 -271.472644) (xy 365.443358 -271.435868) (xy 365.481416 -271.404794) (xy 365.523966 -271.380228)
			(xy 365.569905 -271.362806) (xy 365.618045 -271.352978) (xy 365.667137 -271.351) (xy 365.715911 -271.356922)
			(xy 365.763103 -271.370591) (xy 365.807492 -271.391654) (xy 365.847927 -271.419564) (xy 365.883361 -271.453599)
			(xy 365.912877 -271.492878) (xy 365.93571 -271.536382) (xy 365.951269 -271.582986) (xy 365.95915 -271.631482)
			(xy 365.959644 -271.656048) (xy 367.228894 -271.656048) (xy 367.232854 -271.606994) (xy 367.244631 -271.55921)
			(xy 367.263922 -271.513934) (xy 367.290225 -271.472338) (xy 367.32286 -271.435501) (xy 367.360981 -271.404376)
			(xy 367.403602 -271.379769) (xy 367.449618 -271.362317) (xy 367.497837 -271.352473) (xy 367.547012 -271.350492)
			(xy 367.595867 -271.356424) (xy 367.643138 -271.370116) (xy 367.6876 -271.391214) (xy 367.728103 -271.41917)
			(xy 367.763596 -271.453262) (xy 367.793161 -271.492606) (xy 367.816032 -271.536183) (xy 367.831616 -271.582864)
			(xy 367.839511 -271.631441) (xy 367.840006 -271.656048) (xy 368.169456 -271.656048) (xy 368.17341 -271.607075)
			(xy 368.185168 -271.559371) (xy 368.204426 -271.51417) (xy 368.230685 -271.472644) (xy 368.263266 -271.435868)
			(xy 368.301324 -271.404794) (xy 368.343874 -271.380228) (xy 368.389813 -271.362806) (xy 368.437953 -271.352978)
			(xy 368.487045 -271.351) (xy 368.535819 -271.356922) (xy 368.583011 -271.370591) (xy 368.6274 -271.391654)
			(xy 368.667835 -271.419564) (xy 368.703269 -271.453599) (xy 368.732785 -271.492878) (xy 368.755618 -271.536382)
			(xy 368.771177 -271.582986) (xy 368.779058 -271.631482) (xy 368.779552 -271.656048) (xy 370.049056 -271.656048)
			(xy 370.053016 -271.606994) (xy 370.064793 -271.55921) (xy 370.084084 -271.513934) (xy 370.110387 -271.472338)
			(xy 370.143022 -271.435501) (xy 370.181143 -271.404376) (xy 370.223764 -271.379769) (xy 370.26978 -271.362317)
			(xy 370.317999 -271.352473) (xy 370.367174 -271.350492) (xy 370.416029 -271.356424) (xy 370.4633 -271.370116)
			(xy 370.507762 -271.391214) (xy 370.548265 -271.41917) (xy 370.583758 -271.453262) (xy 370.613323 -271.492606)
			(xy 370.636194 -271.536183) (xy 370.651778 -271.582864) (xy 370.659673 -271.631441) (xy 370.660168 -271.656048)
			(xy 370.989618 -271.656048) (xy 370.993572 -271.607075) (xy 371.00533 -271.559371) (xy 371.024588 -271.51417)
			(xy 371.050847 -271.472644) (xy 371.083428 -271.435868) (xy 371.121486 -271.404794) (xy 371.164036 -271.380228)
			(xy 371.209975 -271.362806) (xy 371.258115 -271.352978) (xy 371.307207 -271.351) (xy 371.355981 -271.356922)
			(xy 371.403173 -271.370591) (xy 371.447562 -271.391654) (xy 371.487997 -271.419564) (xy 371.523431 -271.453599)
			(xy 371.552947 -271.492878) (xy 371.57578 -271.536382) (xy 371.591339 -271.582986) (xy 371.59922 -271.631482)
			(xy 371.599714 -271.656048) (xy 372.868964 -271.656048) (xy 372.872924 -271.606994) (xy 372.884701 -271.55921)
			(xy 372.903992 -271.513934) (xy 372.930295 -271.472338) (xy 372.96293 -271.435501) (xy 373.001051 -271.404376)
			(xy 373.043672 -271.379769) (xy 373.089688 -271.362317) (xy 373.137907 -271.352473) (xy 373.187082 -271.350492)
			(xy 373.235937 -271.356424) (xy 373.283208 -271.370116) (xy 373.32767 -271.391214) (xy 373.368173 -271.41917)
			(xy 373.403666 -271.453262) (xy 373.433231 -271.492606) (xy 373.456102 -271.536183) (xy 373.471686 -271.582864)
			(xy 373.479581 -271.631441) (xy 373.480076 -271.656048) (xy 373.809526 -271.656048) (xy 373.81348 -271.607075)
			(xy 373.825238 -271.559371) (xy 373.844496 -271.51417) (xy 373.870755 -271.472644) (xy 373.903336 -271.435868)
			(xy 373.941394 -271.404794) (xy 373.983944 -271.380228) (xy 374.029883 -271.362806) (xy 374.078023 -271.352978)
			(xy 374.127115 -271.351) (xy 374.175889 -271.356922) (xy 374.223081 -271.370591) (xy 374.26747 -271.391654)
			(xy 374.307905 -271.419564) (xy 374.343339 -271.453599) (xy 374.372855 -271.492878) (xy 374.395688 -271.536382)
			(xy 374.411247 -271.582986) (xy 374.419128 -271.631482) (xy 374.419622 -271.656048) (xy 374.419128 -271.680614)
			(xy 374.411247 -271.72911) (xy 374.395688 -271.775714) (xy 374.372855 -271.819218) (xy 374.343339 -271.858497)
			(xy 374.307905 -271.892532) (xy 374.26747 -271.920442) (xy 374.223081 -271.941505) (xy 374.175889 -271.955174)
			(xy 374.127115 -271.961096) (xy 374.078023 -271.959118) (xy 374.029883 -271.94929) (xy 373.983944 -271.931868)
			(xy 373.941394 -271.907302) (xy 373.903336 -271.876228) (xy 373.870755 -271.839452) (xy 373.844496 -271.797926)
			(xy 373.825238 -271.752725) (xy 373.81348 -271.705021) (xy 373.809526 -271.656048) (xy 373.480076 -271.656048)
			(xy 373.479581 -271.680655) (xy 373.471686 -271.729232) (xy 373.456102 -271.775913) (xy 373.433231 -271.81949)
			(xy 373.403666 -271.858834) (xy 373.368173 -271.892926) (xy 373.32767 -271.920882) (xy 373.283208 -271.94198)
			(xy 373.235937 -271.955672) (xy 373.187082 -271.961604) (xy 373.137907 -271.959623) (xy 373.089688 -271.949779)
			(xy 373.043672 -271.932327) (xy 373.001051 -271.90772) (xy 372.96293 -271.876595) (xy 372.930295 -271.839758)
			(xy 372.903992 -271.798162) (xy 372.884701 -271.752886) (xy 372.872924 -271.705102) (xy 372.868964 -271.656048)
			(xy 371.599714 -271.656048) (xy 371.59922 -271.680614) (xy 371.591339 -271.72911) (xy 371.57578 -271.775714)
			(xy 371.552947 -271.819218) (xy 371.523431 -271.858497) (xy 371.487997 -271.892532) (xy 371.447562 -271.920442)
			(xy 371.403173 -271.941505) (xy 371.355981 -271.955174) (xy 371.307207 -271.961096) (xy 371.258115 -271.959118)
			(xy 371.209975 -271.94929) (xy 371.164036 -271.931868) (xy 371.121486 -271.907302) (xy 371.083428 -271.876228)
			(xy 371.050847 -271.839452) (xy 371.024588 -271.797926) (xy 371.00533 -271.752725) (xy 370.993572 -271.705021)
			(xy 370.989618 -271.656048) (xy 370.660168 -271.656048) (xy 370.659673 -271.680655) (xy 370.651778 -271.729232)
			(xy 370.636194 -271.775913) (xy 370.613323 -271.81949) (xy 370.583758 -271.858834) (xy 370.548265 -271.892926)
			(xy 370.507762 -271.920882) (xy 370.4633 -271.94198) (xy 370.416029 -271.955672) (xy 370.367174 -271.961604)
			(xy 370.317999 -271.959623) (xy 370.26978 -271.949779) (xy 370.223764 -271.932327) (xy 370.181143 -271.90772)
			(xy 370.143022 -271.876595) (xy 370.110387 -271.839758) (xy 370.084084 -271.798162) (xy 370.064793 -271.752886)
			(xy 370.053016 -271.705102) (xy 370.049056 -271.656048) (xy 368.779552 -271.656048) (xy 368.779058 -271.680614)
			(xy 368.771177 -271.72911) (xy 368.755618 -271.775714) (xy 368.732785 -271.819218) (xy 368.703269 -271.858497)
			(xy 368.667835 -271.892532) (xy 368.6274 -271.920442) (xy 368.583011 -271.941505) (xy 368.535819 -271.955174)
			(xy 368.487045 -271.961096) (xy 368.437953 -271.959118) (xy 368.389813 -271.94929) (xy 368.343874 -271.931868)
			(xy 368.301324 -271.907302) (xy 368.263266 -271.876228) (xy 368.230685 -271.839452) (xy 368.204426 -271.797926)
			(xy 368.185168 -271.752725) (xy 368.17341 -271.705021) (xy 368.169456 -271.656048) (xy 367.840006 -271.656048)
			(xy 367.839511 -271.680655) (xy 367.831616 -271.729232) (xy 367.816032 -271.775913) (xy 367.793161 -271.81949)
			(xy 367.763596 -271.858834) (xy 367.728103 -271.892926) (xy 367.6876 -271.920882) (xy 367.643138 -271.94198)
			(xy 367.595867 -271.955672) (xy 367.547012 -271.961604) (xy 367.497837 -271.959623) (xy 367.449618 -271.949779)
			(xy 367.403602 -271.932327) (xy 367.360981 -271.90772) (xy 367.32286 -271.876595) (xy 367.290225 -271.839758)
			(xy 367.263922 -271.798162) (xy 367.244631 -271.752886) (xy 367.232854 -271.705102) (xy 367.228894 -271.656048)
			(xy 365.959644 -271.656048) (xy 365.95915 -271.680614) (xy 365.951269 -271.72911) (xy 365.93571 -271.775714)
			(xy 365.912877 -271.819218) (xy 365.883361 -271.858497) (xy 365.847927 -271.892532) (xy 365.807492 -271.920442)
			(xy 365.763103 -271.941505) (xy 365.715911 -271.955174) (xy 365.667137 -271.961096) (xy 365.618045 -271.959118)
			(xy 365.569905 -271.94929) (xy 365.523966 -271.931868) (xy 365.481416 -271.907302) (xy 365.443358 -271.876228)
			(xy 365.410777 -271.839452) (xy 365.384518 -271.797926) (xy 365.36526 -271.752725) (xy 365.353502 -271.705021)
			(xy 365.349548 -271.656048) (xy 365.020098 -271.656048) (xy 365.019603 -271.680655) (xy 365.011708 -271.729232)
			(xy 364.996124 -271.775913) (xy 364.973253 -271.81949) (xy 364.943688 -271.858834) (xy 364.908195 -271.892926)
			(xy 364.867692 -271.920882) (xy 364.82323 -271.94198) (xy 364.775959 -271.955672) (xy 364.727104 -271.961604)
			(xy 364.677929 -271.959623) (xy 364.62971 -271.949779) (xy 364.583694 -271.932327) (xy 364.541073 -271.90772)
			(xy 364.502952 -271.876595) (xy 364.470317 -271.839758) (xy 364.444014 -271.798162) (xy 364.424723 -271.752886)
			(xy 364.412946 -271.705102) (xy 364.408986 -271.656048) (xy 355.625908 -271.656048) (xy 355.625414 -271.680614)
			(xy 355.617533 -271.72911) (xy 355.601974 -271.775714) (xy 355.579141 -271.819218) (xy 355.549625 -271.858497)
			(xy 355.514191 -271.892532) (xy 355.473756 -271.920442) (xy 355.429367 -271.941505) (xy 355.382175 -271.955174)
			(xy 355.333401 -271.961096) (xy 355.284309 -271.959118) (xy 355.236169 -271.94929) (xy 355.19023 -271.931868)
			(xy 355.14768 -271.907302) (xy 355.109622 -271.876228) (xy 355.077041 -271.839452) (xy 355.050782 -271.797926)
			(xy 355.031524 -271.752725) (xy 355.019766 -271.705021) (xy 355.015812 -271.656048) (xy 354.686362 -271.656048)
			(xy 354.685867 -271.680655) (xy 354.677972 -271.729232) (xy 354.662388 -271.775913) (xy 354.639517 -271.81949)
			(xy 354.609952 -271.858834) (xy 354.574459 -271.892926) (xy 354.533956 -271.920882) (xy 354.489494 -271.94198)
			(xy 354.442223 -271.955672) (xy 354.393368 -271.961604) (xy 354.344193 -271.959623) (xy 354.295974 -271.949779)
			(xy 354.249958 -271.932327) (xy 354.207337 -271.90772) (xy 354.169216 -271.876595) (xy 354.136581 -271.839758)
			(xy 354.110278 -271.798162) (xy 354.090987 -271.752886) (xy 354.07921 -271.705102) (xy 354.07525 -271.656048)
			(xy 352.806 -271.656048) (xy 352.805506 -271.680614) (xy 352.797625 -271.72911) (xy 352.782066 -271.775714)
			(xy 352.759233 -271.819218) (xy 352.729717 -271.858497) (xy 352.694283 -271.892532) (xy 352.653848 -271.920442)
			(xy 352.609459 -271.941505) (xy 352.562267 -271.955174) (xy 352.513493 -271.961096) (xy 352.464401 -271.959118)
			(xy 352.416261 -271.94929) (xy 352.370322 -271.931868) (xy 352.327772 -271.907302) (xy 352.289714 -271.876228)
			(xy 352.257133 -271.839452) (xy 352.230874 -271.797926) (xy 352.211616 -271.752725) (xy 352.199858 -271.705021)
			(xy 352.195904 -271.656048) (xy 351.866454 -271.656048) (xy 351.865959 -271.680655) (xy 351.858064 -271.729232)
			(xy 351.84248 -271.775913) (xy 351.819609 -271.81949) (xy 351.790044 -271.858834) (xy 351.754551 -271.892926)
			(xy 351.714048 -271.920882) (xy 351.669586 -271.94198) (xy 351.622315 -271.955672) (xy 351.57346 -271.961604)
			(xy 351.524285 -271.959623) (xy 351.476066 -271.949779) (xy 351.43005 -271.932327) (xy 351.387429 -271.90772)
			(xy 351.349308 -271.876595) (xy 351.316673 -271.839758) (xy 351.29037 -271.798162) (xy 351.271079 -271.752886)
			(xy 351.259302 -271.705102) (xy 351.255342 -271.656048) (xy 349.985838 -271.656048) (xy 349.985344 -271.680614)
			(xy 349.977463 -271.72911) (xy 349.961904 -271.775714) (xy 349.939071 -271.819218) (xy 349.909555 -271.858497)
			(xy 349.874121 -271.892532) (xy 349.833686 -271.920442) (xy 349.789297 -271.941505) (xy 349.742105 -271.955174)
			(xy 349.693331 -271.961096) (xy 349.644239 -271.959118) (xy 349.596099 -271.94929) (xy 349.55016 -271.931868)
			(xy 349.50761 -271.907302) (xy 349.469552 -271.876228) (xy 349.436971 -271.839452) (xy 349.410712 -271.797926)
			(xy 349.391454 -271.752725) (xy 349.379696 -271.705021) (xy 349.375742 -271.656048) (xy 349.046292 -271.656048)
			(xy 349.045797 -271.680655) (xy 349.037902 -271.729232) (xy 349.022318 -271.775913) (xy 348.999447 -271.81949)
			(xy 348.969882 -271.858834) (xy 348.934389 -271.892926) (xy 348.893886 -271.920882) (xy 348.849424 -271.94198)
			(xy 348.802153 -271.955672) (xy 348.753298 -271.961604) (xy 348.704123 -271.959623) (xy 348.655904 -271.949779)
			(xy 348.609888 -271.932327) (xy 348.567267 -271.90772) (xy 348.529146 -271.876595) (xy 348.496511 -271.839758)
			(xy 348.470208 -271.798162) (xy 348.450917 -271.752886) (xy 348.43914 -271.705102) (xy 348.43518 -271.656048)
			(xy 347.16593 -271.656048) (xy 347.165436 -271.680614) (xy 347.157555 -271.72911) (xy 347.141996 -271.775714)
			(xy 347.119163 -271.819218) (xy 347.089647 -271.858497) (xy 347.054213 -271.892532) (xy 347.013778 -271.920442)
			(xy 346.969389 -271.941505) (xy 346.922197 -271.955174) (xy 346.873423 -271.961096) (xy 346.824331 -271.959118)
			(xy 346.776191 -271.94929) (xy 346.730252 -271.931868) (xy 346.687702 -271.907302) (xy 346.649644 -271.876228)
			(xy 346.617063 -271.839452) (xy 346.590804 -271.797926) (xy 346.571546 -271.752725) (xy 346.559788 -271.705021)
			(xy 346.555834 -271.656048) (xy 346.226384 -271.656048) (xy 346.225889 -271.680655) (xy 346.217994 -271.729232)
			(xy 346.20241 -271.775913) (xy 346.179539 -271.81949) (xy 346.149974 -271.858834) (xy 346.114481 -271.892926)
			(xy 346.073978 -271.920882) (xy 346.029516 -271.94198) (xy 345.982245 -271.955672) (xy 345.93339 -271.961604)
			(xy 345.884215 -271.959623) (xy 345.835996 -271.949779) (xy 345.78998 -271.932327) (xy 345.747359 -271.90772)
			(xy 345.709238 -271.876595) (xy 345.676603 -271.839758) (xy 345.6503 -271.798162) (xy 345.631009 -271.752886)
			(xy 345.619232 -271.705102) (xy 345.615272 -271.656048) (xy 126.479549 -271.656048) (xy 126.479554 -271.656302)
			(xy 126.47906 -271.680868) (xy 126.471179 -271.729364) (xy 126.45562 -271.775968) (xy 126.432787 -271.819472)
			(xy 126.403271 -271.858751) (xy 126.367837 -271.892786) (xy 126.327402 -271.920696) (xy 126.283013 -271.941759)
			(xy 126.235821 -271.955428) (xy 126.187047 -271.96135) (xy 126.137955 -271.959372) (xy 126.089815 -271.949544)
			(xy 126.043876 -271.932122) (xy 126.001326 -271.907556) (xy 125.963268 -271.876482) (xy 125.930687 -271.839706)
			(xy 125.904428 -271.79818) (xy 125.88517 -271.752979) (xy 125.873412 -271.705275) (xy 125.869458 -271.656302)
			(xy 125.540008 -271.656302) (xy 125.539513 -271.680909) (xy 125.531618 -271.729486) (xy 125.516034 -271.776167)
			(xy 125.493163 -271.819744) (xy 125.463598 -271.859088) (xy 125.428105 -271.89318) (xy 125.387602 -271.921136)
			(xy 125.34314 -271.942234) (xy 125.295869 -271.955926) (xy 125.247014 -271.961858) (xy 125.197839 -271.959877)
			(xy 125.14962 -271.950033) (xy 125.103604 -271.932581) (xy 125.060983 -271.907974) (xy 125.022862 -271.876849)
			(xy 124.990227 -271.840012) (xy 124.963924 -271.798416) (xy 124.944633 -271.75314) (xy 124.932856 -271.705356)
			(xy 124.928896 -271.656302) (xy 123.659646 -271.656302) (xy 123.659152 -271.680868) (xy 123.651271 -271.729364)
			(xy 123.635712 -271.775968) (xy 123.612879 -271.819472) (xy 123.583363 -271.858751) (xy 123.547929 -271.892786)
			(xy 123.507494 -271.920696) (xy 123.463105 -271.941759) (xy 123.415913 -271.955428) (xy 123.367139 -271.96135)
			(xy 123.318047 -271.959372) (xy 123.269907 -271.949544) (xy 123.223968 -271.932122) (xy 123.181418 -271.907556)
			(xy 123.14336 -271.876482) (xy 123.110779 -271.839706) (xy 123.08452 -271.79818) (xy 123.065262 -271.752979)
			(xy 123.053504 -271.705275) (xy 123.04955 -271.656302) (xy 122.7201 -271.656302) (xy 122.719605 -271.680909)
			(xy 122.71171 -271.729486) (xy 122.696126 -271.776167) (xy 122.673255 -271.819744) (xy 122.64369 -271.859088)
			(xy 122.608197 -271.89318) (xy 122.567694 -271.921136) (xy 122.523232 -271.942234) (xy 122.475961 -271.955926)
			(xy 122.427106 -271.961858) (xy 122.377931 -271.959877) (xy 122.329712 -271.950033) (xy 122.283696 -271.932581)
			(xy 122.241075 -271.907974) (xy 122.202954 -271.876849) (xy 122.170319 -271.840012) (xy 122.144016 -271.798416)
			(xy 122.124725 -271.75314) (xy 122.112948 -271.705356) (xy 122.108988 -271.656302) (xy 120.839484 -271.656302)
			(xy 120.83899 -271.680868) (xy 120.831109 -271.729364) (xy 120.81555 -271.775968) (xy 120.792717 -271.819472)
			(xy 120.763201 -271.858751) (xy 120.727767 -271.892786) (xy 120.687332 -271.920696) (xy 120.642943 -271.941759)
			(xy 120.595751 -271.955428) (xy 120.546977 -271.96135) (xy 120.497885 -271.959372) (xy 120.449745 -271.949544)
			(xy 120.403806 -271.932122) (xy 120.361256 -271.907556) (xy 120.323198 -271.876482) (xy 120.290617 -271.839706)
			(xy 120.264358 -271.79818) (xy 120.2451 -271.752979) (xy 120.233342 -271.705275) (xy 120.229388 -271.656302)
			(xy 119.899938 -271.656302) (xy 119.899443 -271.680909) (xy 119.891548 -271.729486) (xy 119.875964 -271.776167)
			(xy 119.853093 -271.819744) (xy 119.823528 -271.859088) (xy 119.788035 -271.89318) (xy 119.747532 -271.921136)
			(xy 119.70307 -271.942234) (xy 119.655799 -271.955926) (xy 119.606944 -271.961858) (xy 119.557769 -271.959877)
			(xy 119.50955 -271.950033) (xy 119.463534 -271.932581) (xy 119.420913 -271.907974) (xy 119.382792 -271.876849)
			(xy 119.350157 -271.840012) (xy 119.323854 -271.798416) (xy 119.304563 -271.75314) (xy 119.292786 -271.705356)
			(xy 119.288826 -271.656302) (xy 118.019576 -271.656302) (xy 118.019082 -271.680868) (xy 118.011201 -271.729364)
			(xy 117.995642 -271.775968) (xy 117.972809 -271.819472) (xy 117.943293 -271.858751) (xy 117.907859 -271.892786)
			(xy 117.867424 -271.920696) (xy 117.823035 -271.941759) (xy 117.775843 -271.955428) (xy 117.727069 -271.96135)
			(xy 117.677977 -271.959372) (xy 117.629837 -271.949544) (xy 117.583898 -271.932122) (xy 117.541348 -271.907556)
			(xy 117.50329 -271.876482) (xy 117.470709 -271.839706) (xy 117.44445 -271.79818) (xy 117.425192 -271.752979)
			(xy 117.413434 -271.705275) (xy 117.40948 -271.656302) (xy 117.08003 -271.656302) (xy 117.079535 -271.680909)
			(xy 117.07164 -271.729486) (xy 117.056056 -271.776167) (xy 117.033185 -271.819744) (xy 117.00362 -271.859088)
			(xy 116.968127 -271.89318) (xy 116.927624 -271.921136) (xy 116.883162 -271.942234) (xy 116.835891 -271.955926)
			(xy 116.787036 -271.961858) (xy 116.737861 -271.959877) (xy 116.689642 -271.950033) (xy 116.643626 -271.932581)
			(xy 116.601005 -271.907974) (xy 116.562884 -271.876849) (xy 116.530249 -271.840012) (xy 116.503946 -271.798416)
			(xy 116.484655 -271.75314) (xy 116.472878 -271.705356) (xy 116.468918 -271.656302) (xy 107.68584 -271.656302)
			(xy 107.685346 -271.680868) (xy 107.677465 -271.729364) (xy 107.661906 -271.775968) (xy 107.639073 -271.819472)
			(xy 107.609557 -271.858751) (xy 107.574123 -271.892786) (xy 107.533688 -271.920696) (xy 107.489299 -271.941759)
			(xy 107.442107 -271.955428) (xy 107.393333 -271.96135) (xy 107.344241 -271.959372) (xy 107.296101 -271.949544)
			(xy 107.250162 -271.932122) (xy 107.207612 -271.907556) (xy 107.169554 -271.876482) (xy 107.136973 -271.839706)
			(xy 107.110714 -271.79818) (xy 107.091456 -271.752979) (xy 107.079698 -271.705275) (xy 107.075744 -271.656302)
			(xy 106.746294 -271.656302) (xy 106.745799 -271.680909) (xy 106.737904 -271.729486) (xy 106.72232 -271.776167)
			(xy 106.699449 -271.819744) (xy 106.669884 -271.859088) (xy 106.634391 -271.89318) (xy 106.593888 -271.921136)
			(xy 106.549426 -271.942234) (xy 106.502155 -271.955926) (xy 106.4533 -271.961858) (xy 106.404125 -271.959877)
			(xy 106.355906 -271.950033) (xy 106.30989 -271.932581) (xy 106.267269 -271.907974) (xy 106.229148 -271.876849)
			(xy 106.196513 -271.840012) (xy 106.17021 -271.798416) (xy 106.150919 -271.75314) (xy 106.139142 -271.705356)
			(xy 106.135182 -271.656302) (xy 104.865932 -271.656302) (xy 104.865438 -271.680868) (xy 104.857557 -271.729364)
			(xy 104.841998 -271.775968) (xy 104.819165 -271.819472) (xy 104.789649 -271.858751) (xy 104.754215 -271.892786)
			(xy 104.71378 -271.920696) (xy 104.669391 -271.941759) (xy 104.622199 -271.955428) (xy 104.573425 -271.96135)
			(xy 104.524333 -271.959372) (xy 104.476193 -271.949544) (xy 104.430254 -271.932122) (xy 104.387704 -271.907556)
			(xy 104.349646 -271.876482) (xy 104.317065 -271.839706) (xy 104.290806 -271.79818) (xy 104.271548 -271.752979)
			(xy 104.25979 -271.705275) (xy 104.255836 -271.656302) (xy 103.926386 -271.656302) (xy 103.925891 -271.680909)
			(xy 103.917996 -271.729486) (xy 103.902412 -271.776167) (xy 103.879541 -271.819744) (xy 103.849976 -271.859088)
			(xy 103.814483 -271.89318) (xy 103.77398 -271.921136) (xy 103.729518 -271.942234) (xy 103.682247 -271.955926)
			(xy 103.633392 -271.961858) (xy 103.584217 -271.959877) (xy 103.535998 -271.950033) (xy 103.489982 -271.932581)
			(xy 103.447361 -271.907974) (xy 103.40924 -271.876849) (xy 103.376605 -271.840012) (xy 103.350302 -271.798416)
			(xy 103.331011 -271.75314) (xy 103.319234 -271.705356) (xy 103.315274 -271.656302) (xy 102.04577 -271.656302)
			(xy 102.045276 -271.680868) (xy 102.037395 -271.729364) (xy 102.021836 -271.775968) (xy 101.999003 -271.819472)
			(xy 101.969487 -271.858751) (xy 101.934053 -271.892786) (xy 101.893618 -271.920696) (xy 101.849229 -271.941759)
			(xy 101.802037 -271.955428) (xy 101.753263 -271.96135) (xy 101.704171 -271.959372) (xy 101.656031 -271.949544)
			(xy 101.610092 -271.932122) (xy 101.567542 -271.907556) (xy 101.529484 -271.876482) (xy 101.496903 -271.839706)
			(xy 101.470644 -271.79818) (xy 101.451386 -271.752979) (xy 101.439628 -271.705275) (xy 101.435674 -271.656302)
			(xy 101.106224 -271.656302) (xy 101.105729 -271.680909) (xy 101.097834 -271.729486) (xy 101.08225 -271.776167)
			(xy 101.059379 -271.819744) (xy 101.029814 -271.859088) (xy 100.994321 -271.89318) (xy 100.953818 -271.921136)
			(xy 100.909356 -271.942234) (xy 100.862085 -271.955926) (xy 100.81323 -271.961858) (xy 100.764055 -271.959877)
			(xy 100.715836 -271.950033) (xy 100.66982 -271.932581) (xy 100.627199 -271.907974) (xy 100.589078 -271.876849)
			(xy 100.556443 -271.840012) (xy 100.53014 -271.798416) (xy 100.510849 -271.75314) (xy 100.499072 -271.705356)
			(xy 100.495112 -271.656302) (xy 99.225862 -271.656302) (xy 99.225368 -271.680868) (xy 99.217487 -271.729364)
			(xy 99.201928 -271.775968) (xy 99.179095 -271.819472) (xy 99.149579 -271.858751) (xy 99.114145 -271.892786)
			(xy 99.07371 -271.920696) (xy 99.029321 -271.941759) (xy 98.982129 -271.955428) (xy 98.933355 -271.96135)
			(xy 98.884263 -271.959372) (xy 98.836123 -271.949544) (xy 98.790184 -271.932122) (xy 98.747634 -271.907556)
			(xy 98.709576 -271.876482) (xy 98.676995 -271.839706) (xy 98.650736 -271.79818) (xy 98.631478 -271.752979)
			(xy 98.61972 -271.705275) (xy 98.615766 -271.656302) (xy 98.286316 -271.656302) (xy 98.285821 -271.680909)
			(xy 98.277926 -271.729486) (xy 98.262342 -271.776167) (xy 98.239471 -271.819744) (xy 98.209906 -271.859088)
			(xy 98.174413 -271.89318) (xy 98.13391 -271.921136) (xy 98.089448 -271.942234) (xy 98.042177 -271.955926)
			(xy 97.993322 -271.961858) (xy 97.944147 -271.959877) (xy 97.895928 -271.950033) (xy 97.849912 -271.932581)
			(xy 97.807291 -271.907974) (xy 97.76917 -271.876849) (xy 97.736535 -271.840012) (xy 97.710232 -271.798416)
			(xy 97.690941 -271.75314) (xy 97.679164 -271.705356) (xy 97.675204 -271.656302) (xy 2.509012 -271.656302)
			(xy 2.509012 -272.466308) (xy 108.48519 -272.466308) (xy 108.48915 -272.417254) (xy 108.500927 -272.36947)
			(xy 108.520218 -272.324194) (xy 108.546521 -272.282598) (xy 108.579156 -272.245761) (xy 108.617277 -272.214636)
			(xy 108.659898 -272.190029) (xy 108.705914 -272.172577) (xy 108.754133 -272.162733) (xy 108.803308 -272.160752)
			(xy 108.852163 -272.166684) (xy 108.899434 -272.180376) (xy 108.943896 -272.201474) (xy 108.984399 -272.22943)
			(xy 109.019892 -272.263522) (xy 109.049457 -272.302866) (xy 109.072328 -272.346443) (xy 109.087912 -272.393124)
			(xy 109.095807 -272.441701) (xy 109.096302 -272.466308) (xy 109.425752 -272.466308) (xy 109.429706 -272.417335)
			(xy 109.441464 -272.369631) (xy 109.460722 -272.32443) (xy 109.486981 -272.282904) (xy 109.519562 -272.246128)
			(xy 109.55762 -272.215054) (xy 109.60017 -272.190488) (xy 109.646109 -272.173066) (xy 109.694249 -272.163238)
			(xy 109.743341 -272.16126) (xy 109.792115 -272.167182) (xy 109.839307 -272.180851) (xy 109.883696 -272.201914)
			(xy 109.924131 -272.229824) (xy 109.959565 -272.263859) (xy 109.989081 -272.303138) (xy 110.011914 -272.346642)
			(xy 110.027473 -272.393246) (xy 110.035354 -272.441742) (xy 110.035848 -272.466308) (xy 114.11891 -272.466308)
			(xy 114.12287 -272.417254) (xy 114.134647 -272.36947) (xy 114.153938 -272.324194) (xy 114.180241 -272.282598)
			(xy 114.212876 -272.245761) (xy 114.250997 -272.214636) (xy 114.293618 -272.190029) (xy 114.339634 -272.172577)
			(xy 114.387853 -272.162733) (xy 114.437028 -272.160752) (xy 114.485883 -272.166684) (xy 114.533154 -272.180376)
			(xy 114.577616 -272.201474) (xy 114.618119 -272.22943) (xy 114.653612 -272.263522) (xy 114.683177 -272.302866)
			(xy 114.706048 -272.346443) (xy 114.721632 -272.393124) (xy 114.729527 -272.441701) (xy 114.730022 -272.466308)
			(xy 115.059472 -272.466308) (xy 115.063426 -272.417335) (xy 115.075184 -272.369631) (xy 115.094442 -272.32443)
			(xy 115.120701 -272.282904) (xy 115.153282 -272.246128) (xy 115.19134 -272.215054) (xy 115.23389 -272.190488)
			(xy 115.279829 -272.173066) (xy 115.327969 -272.163238) (xy 115.377061 -272.16126) (xy 115.425835 -272.167182)
			(xy 115.473027 -272.180851) (xy 115.517416 -272.201914) (xy 115.557851 -272.229824) (xy 115.593285 -272.263859)
			(xy 115.622801 -272.303138) (xy 115.645634 -272.346642) (xy 115.661193 -272.393246) (xy 115.669074 -272.441742)
			(xy 115.669563 -272.466054) (xy 356.425258 -272.466054) (xy 356.429218 -272.417) (xy 356.440995 -272.369216)
			(xy 356.460286 -272.32394) (xy 356.486589 -272.282344) (xy 356.519224 -272.245507) (xy 356.557345 -272.214382)
			(xy 356.599966 -272.189775) (xy 356.645982 -272.172323) (xy 356.694201 -272.162479) (xy 356.743376 -272.160498)
			(xy 356.792231 -272.16643) (xy 356.839502 -272.180122) (xy 356.883964 -272.20122) (xy 356.924467 -272.229176)
			(xy 356.95996 -272.263268) (xy 356.989525 -272.302612) (xy 357.012396 -272.346189) (xy 357.02798 -272.39287)
			(xy 357.035875 -272.441447) (xy 357.03637 -272.466054) (xy 357.36582 -272.466054) (xy 357.369774 -272.417081)
			(xy 357.381532 -272.369377) (xy 357.40079 -272.324176) (xy 357.427049 -272.28265) (xy 357.45963 -272.245874)
			(xy 357.497688 -272.2148) (xy 357.540238 -272.190234) (xy 357.586177 -272.172812) (xy 357.634317 -272.162984)
			(xy 357.683409 -272.161006) (xy 357.732183 -272.166928) (xy 357.779375 -272.180597) (xy 357.823764 -272.20166)
			(xy 357.864199 -272.22957) (xy 357.899633 -272.263605) (xy 357.929149 -272.302884) (xy 357.951982 -272.346388)
			(xy 357.967541 -272.392992) (xy 357.975422 -272.441488) (xy 357.975916 -272.466054) (xy 362.058978 -272.466054)
			(xy 362.062938 -272.417) (xy 362.074715 -272.369216) (xy 362.094006 -272.32394) (xy 362.120309 -272.282344)
			(xy 362.152944 -272.245507) (xy 362.191065 -272.214382) (xy 362.233686 -272.189775) (xy 362.279702 -272.172323)
			(xy 362.327921 -272.162479) (xy 362.377096 -272.160498) (xy 362.425951 -272.16643) (xy 362.473222 -272.180122)
			(xy 362.517684 -272.20122) (xy 362.558187 -272.229176) (xy 362.59368 -272.263268) (xy 362.623245 -272.302612)
			(xy 362.646116 -272.346189) (xy 362.6617 -272.39287) (xy 362.669595 -272.441447) (xy 362.67009 -272.466054)
			(xy 362.99954 -272.466054) (xy 363.003494 -272.417081) (xy 363.015252 -272.369377) (xy 363.03451 -272.324176)
			(xy 363.060769 -272.28265) (xy 363.09335 -272.245874) (xy 363.131408 -272.2148) (xy 363.173958 -272.190234)
			(xy 363.219897 -272.172812) (xy 363.268037 -272.162984) (xy 363.317129 -272.161006) (xy 363.365903 -272.166928)
			(xy 363.413095 -272.180597) (xy 363.457484 -272.20166) (xy 363.497919 -272.22957) (xy 363.533353 -272.263605)
			(xy 363.562869 -272.302884) (xy 363.585702 -272.346388) (xy 363.601261 -272.392992) (xy 363.609142 -272.441488)
			(xy 363.609636 -272.466054) (xy 363.609142 -272.49062) (xy 363.601261 -272.539116) (xy 363.585702 -272.58572)
			(xy 363.562869 -272.629224) (xy 363.533353 -272.668503) (xy 363.497919 -272.702538) (xy 363.457484 -272.730448)
			(xy 363.413095 -272.751511) (xy 363.365903 -272.76518) (xy 363.317129 -272.771102) (xy 363.268037 -272.769124)
			(xy 363.219897 -272.759296) (xy 363.173958 -272.741874) (xy 363.131408 -272.717308) (xy 363.09335 -272.686234)
			(xy 363.060769 -272.649458) (xy 363.03451 -272.607932) (xy 363.015252 -272.562731) (xy 363.003494 -272.515027)
			(xy 362.99954 -272.466054) (xy 362.67009 -272.466054) (xy 362.669595 -272.490661) (xy 362.6617 -272.539238)
			(xy 362.646116 -272.585919) (xy 362.623245 -272.629496) (xy 362.59368 -272.66884) (xy 362.558187 -272.702932)
			(xy 362.517684 -272.730888) (xy 362.473222 -272.751986) (xy 362.425951 -272.765678) (xy 362.377096 -272.77161)
			(xy 362.327921 -272.769629) (xy 362.279702 -272.759785) (xy 362.233686 -272.742333) (xy 362.191065 -272.717726)
			(xy 362.152944 -272.686601) (xy 362.120309 -272.649764) (xy 362.094006 -272.608168) (xy 362.074715 -272.562892)
			(xy 362.062938 -272.515108) (xy 362.058978 -272.466054) (xy 357.975916 -272.466054) (xy 357.975422 -272.49062)
			(xy 357.967541 -272.539116) (xy 357.951982 -272.58572) (xy 357.929149 -272.629224) (xy 357.899633 -272.668503)
			(xy 357.864199 -272.702538) (xy 357.823764 -272.730448) (xy 357.779375 -272.751511) (xy 357.732183 -272.76518)
			(xy 357.683409 -272.771102) (xy 357.634317 -272.769124) (xy 357.586177 -272.759296) (xy 357.540238 -272.741874)
			(xy 357.497688 -272.717308) (xy 357.45963 -272.686234) (xy 357.427049 -272.649458) (xy 357.40079 -272.607932)
			(xy 357.381532 -272.562731) (xy 357.369774 -272.515027) (xy 357.36582 -272.466054) (xy 357.03637 -272.466054)
			(xy 357.035875 -272.490661) (xy 357.02798 -272.539238) (xy 357.012396 -272.585919) (xy 356.989525 -272.629496)
			(xy 356.95996 -272.66884) (xy 356.924467 -272.702932) (xy 356.883964 -272.730888) (xy 356.839502 -272.751986)
			(xy 356.792231 -272.765678) (xy 356.743376 -272.77161) (xy 356.694201 -272.769629) (xy 356.645982 -272.759785)
			(xy 356.599966 -272.742333) (xy 356.557345 -272.717726) (xy 356.519224 -272.686601) (xy 356.486589 -272.649764)
			(xy 356.460286 -272.608168) (xy 356.440995 -272.562892) (xy 356.429218 -272.515108) (xy 356.425258 -272.466054)
			(xy 115.669563 -272.466054) (xy 115.669568 -272.466308) (xy 115.669074 -272.490874) (xy 115.661193 -272.53937)
			(xy 115.645634 -272.585974) (xy 115.622801 -272.629478) (xy 115.593285 -272.668757) (xy 115.557851 -272.702792)
			(xy 115.517416 -272.730702) (xy 115.473027 -272.751765) (xy 115.425835 -272.765434) (xy 115.377061 -272.771356)
			(xy 115.327969 -272.769378) (xy 115.279829 -272.75955) (xy 115.23389 -272.742128) (xy 115.19134 -272.717562)
			(xy 115.153282 -272.686488) (xy 115.120701 -272.649712) (xy 115.094442 -272.608186) (xy 115.075184 -272.562985)
			(xy 115.063426 -272.515281) (xy 115.059472 -272.466308) (xy 114.730022 -272.466308) (xy 114.729527 -272.490915)
			(xy 114.721632 -272.539492) (xy 114.706048 -272.586173) (xy 114.683177 -272.62975) (xy 114.653612 -272.669094)
			(xy 114.618119 -272.703186) (xy 114.577616 -272.731142) (xy 114.533154 -272.75224) (xy 114.485883 -272.765932)
			(xy 114.437028 -272.771864) (xy 114.387853 -272.769883) (xy 114.339634 -272.760039) (xy 114.293618 -272.742587)
			(xy 114.250997 -272.71798) (xy 114.212876 -272.686855) (xy 114.180241 -272.650018) (xy 114.153938 -272.608422)
			(xy 114.134647 -272.563146) (xy 114.12287 -272.515362) (xy 114.11891 -272.466308) (xy 110.035848 -272.466308)
			(xy 110.035354 -272.490874) (xy 110.027473 -272.53937) (xy 110.011914 -272.585974) (xy 109.989081 -272.629478)
			(xy 109.959565 -272.668757) (xy 109.924131 -272.702792) (xy 109.883696 -272.730702) (xy 109.839307 -272.751765)
			(xy 109.792115 -272.765434) (xy 109.743341 -272.771356) (xy 109.694249 -272.769378) (xy 109.646109 -272.75955)
			(xy 109.60017 -272.742128) (xy 109.55762 -272.717562) (xy 109.519562 -272.686488) (xy 109.486981 -272.649712)
			(xy 109.460722 -272.608186) (xy 109.441464 -272.562985) (xy 109.429706 -272.515281) (xy 109.425752 -272.466308)
			(xy 109.096302 -272.466308) (xy 109.095807 -272.490915) (xy 109.087912 -272.539492) (xy 109.072328 -272.586173)
			(xy 109.049457 -272.62975) (xy 109.019892 -272.669094) (xy 108.984399 -272.703186) (xy 108.943896 -272.731142)
			(xy 108.899434 -272.75224) (xy 108.852163 -272.765932) (xy 108.803308 -272.771864) (xy 108.754133 -272.769883)
			(xy 108.705914 -272.760039) (xy 108.659898 -272.742587) (xy 108.617277 -272.71798) (xy 108.579156 -272.686855)
			(xy 108.546521 -272.650018) (xy 108.520218 -272.608422) (xy 108.500927 -272.563146) (xy 108.48915 -272.515362)
			(xy 108.48519 -272.466308) (xy 2.509012 -272.466308) (xy 2.509012 -273.276314) (xy 97.675204 -273.276314)
			(xy 97.679164 -273.22726) (xy 97.690941 -273.179476) (xy 97.710232 -273.1342) (xy 97.736535 -273.092604)
			(xy 97.76917 -273.055767) (xy 97.807291 -273.024642) (xy 97.849912 -273.000035) (xy 97.895928 -272.982583)
			(xy 97.944147 -272.972739) (xy 97.993322 -272.970758) (xy 98.042177 -272.97669) (xy 98.089448 -272.990382)
			(xy 98.13391 -273.01148) (xy 98.174413 -273.039436) (xy 98.209906 -273.073528) (xy 98.239471 -273.112872)
			(xy 98.262342 -273.156449) (xy 98.277926 -273.20313) (xy 98.285821 -273.251707) (xy 98.286316 -273.276314)
			(xy 98.615766 -273.276314) (xy 98.61972 -273.227341) (xy 98.631478 -273.179637) (xy 98.650736 -273.134436)
			(xy 98.676995 -273.09291) (xy 98.709576 -273.056134) (xy 98.747634 -273.02506) (xy 98.790184 -273.000494)
			(xy 98.836123 -272.983072) (xy 98.884263 -272.973244) (xy 98.933355 -272.971266) (xy 98.982129 -272.977188)
			(xy 99.029321 -272.990857) (xy 99.07371 -273.01192) (xy 99.114145 -273.03983) (xy 99.149579 -273.073865)
			(xy 99.179095 -273.113144) (xy 99.201928 -273.156648) (xy 99.217487 -273.203252) (xy 99.225368 -273.251748)
			(xy 99.225862 -273.276314) (xy 100.495112 -273.276314) (xy 100.499072 -273.22726) (xy 100.510849 -273.179476)
			(xy 100.53014 -273.1342) (xy 100.556443 -273.092604) (xy 100.589078 -273.055767) (xy 100.627199 -273.024642)
			(xy 100.66982 -273.000035) (xy 100.715836 -272.982583) (xy 100.764055 -272.972739) (xy 100.81323 -272.970758)
			(xy 100.862085 -272.97669) (xy 100.909356 -272.990382) (xy 100.953818 -273.01148) (xy 100.994321 -273.039436)
			(xy 101.029814 -273.073528) (xy 101.059379 -273.112872) (xy 101.08225 -273.156449) (xy 101.097834 -273.20313)
			(xy 101.105729 -273.251707) (xy 101.106224 -273.276314) (xy 101.435674 -273.276314) (xy 101.439628 -273.227341)
			(xy 101.451386 -273.179637) (xy 101.470644 -273.134436) (xy 101.496903 -273.09291) (xy 101.529484 -273.056134)
			(xy 101.567542 -273.02506) (xy 101.610092 -273.000494) (xy 101.656031 -272.983072) (xy 101.704171 -272.973244)
			(xy 101.753263 -272.971266) (xy 101.802037 -272.977188) (xy 101.849229 -272.990857) (xy 101.893618 -273.01192)
			(xy 101.934053 -273.03983) (xy 101.969487 -273.073865) (xy 101.999003 -273.113144) (xy 102.021836 -273.156648)
			(xy 102.037395 -273.203252) (xy 102.045276 -273.251748) (xy 102.04577 -273.276314) (xy 103.315274 -273.276314)
			(xy 103.319234 -273.22726) (xy 103.331011 -273.179476) (xy 103.350302 -273.1342) (xy 103.376605 -273.092604)
			(xy 103.40924 -273.055767) (xy 103.447361 -273.024642) (xy 103.489982 -273.000035) (xy 103.535998 -272.982583)
			(xy 103.584217 -272.972739) (xy 103.633392 -272.970758) (xy 103.682247 -272.97669) (xy 103.729518 -272.990382)
			(xy 103.77398 -273.01148) (xy 103.814483 -273.039436) (xy 103.849976 -273.073528) (xy 103.879541 -273.112872)
			(xy 103.902412 -273.156449) (xy 103.917996 -273.20313) (xy 103.925891 -273.251707) (xy 103.926386 -273.276314)
			(xy 104.255836 -273.276314) (xy 104.25979 -273.227341) (xy 104.271548 -273.179637) (xy 104.290806 -273.134436)
			(xy 104.317065 -273.09291) (xy 104.349646 -273.056134) (xy 104.387704 -273.02506) (xy 104.430254 -273.000494)
			(xy 104.476193 -272.983072) (xy 104.524333 -272.973244) (xy 104.573425 -272.971266) (xy 104.622199 -272.977188)
			(xy 104.669391 -272.990857) (xy 104.71378 -273.01192) (xy 104.754215 -273.03983) (xy 104.789649 -273.073865)
			(xy 104.819165 -273.113144) (xy 104.841998 -273.156648) (xy 104.857557 -273.203252) (xy 104.865438 -273.251748)
			(xy 104.865932 -273.276314) (xy 106.135182 -273.276314) (xy 106.139142 -273.22726) (xy 106.150919 -273.179476)
			(xy 106.17021 -273.1342) (xy 106.196513 -273.092604) (xy 106.229148 -273.055767) (xy 106.267269 -273.024642)
			(xy 106.30989 -273.000035) (xy 106.355906 -272.982583) (xy 106.404125 -272.972739) (xy 106.4533 -272.970758)
			(xy 106.502155 -272.97669) (xy 106.549426 -272.990382) (xy 106.593888 -273.01148) (xy 106.634391 -273.039436)
			(xy 106.669884 -273.073528) (xy 106.699449 -273.112872) (xy 106.72232 -273.156449) (xy 106.737904 -273.20313)
			(xy 106.745799 -273.251707) (xy 106.746294 -273.276314) (xy 107.075744 -273.276314) (xy 107.079698 -273.227341)
			(xy 107.091456 -273.179637) (xy 107.110714 -273.134436) (xy 107.136973 -273.09291) (xy 107.169554 -273.056134)
			(xy 107.207612 -273.02506) (xy 107.250162 -273.000494) (xy 107.296101 -272.983072) (xy 107.344241 -272.973244)
			(xy 107.393333 -272.971266) (xy 107.442107 -272.977188) (xy 107.489299 -272.990857) (xy 107.533688 -273.01192)
			(xy 107.574123 -273.03983) (xy 107.609557 -273.073865) (xy 107.639073 -273.113144) (xy 107.661906 -273.156648)
			(xy 107.677465 -273.203252) (xy 107.685346 -273.251748) (xy 107.68584 -273.276314) (xy 116.468918 -273.276314)
			(xy 116.472878 -273.22726) (xy 116.484655 -273.179476) (xy 116.503946 -273.1342) (xy 116.530249 -273.092604)
			(xy 116.562884 -273.055767) (xy 116.601005 -273.024642) (xy 116.643626 -273.000035) (xy 116.689642 -272.982583)
			(xy 116.737861 -272.972739) (xy 116.787036 -272.970758) (xy 116.835891 -272.97669) (xy 116.883162 -272.990382)
			(xy 116.927624 -273.01148) (xy 116.968127 -273.039436) (xy 117.00362 -273.073528) (xy 117.033185 -273.112872)
			(xy 117.056056 -273.156449) (xy 117.07164 -273.20313) (xy 117.079535 -273.251707) (xy 117.08003 -273.276314)
			(xy 117.40948 -273.276314) (xy 117.413434 -273.227341) (xy 117.425192 -273.179637) (xy 117.44445 -273.134436)
			(xy 117.470709 -273.09291) (xy 117.50329 -273.056134) (xy 117.541348 -273.02506) (xy 117.583898 -273.000494)
			(xy 117.629837 -272.983072) (xy 117.677977 -272.973244) (xy 117.727069 -272.971266) (xy 117.775843 -272.977188)
			(xy 117.823035 -272.990857) (xy 117.867424 -273.01192) (xy 117.907859 -273.03983) (xy 117.943293 -273.073865)
			(xy 117.972809 -273.113144) (xy 117.995642 -273.156648) (xy 118.011201 -273.203252) (xy 118.019082 -273.251748)
			(xy 118.019576 -273.276314) (xy 119.288826 -273.276314) (xy 119.292786 -273.22726) (xy 119.304563 -273.179476)
			(xy 119.323854 -273.1342) (xy 119.350157 -273.092604) (xy 119.382792 -273.055767) (xy 119.420913 -273.024642)
			(xy 119.463534 -273.000035) (xy 119.50955 -272.982583) (xy 119.557769 -272.972739) (xy 119.606944 -272.970758)
			(xy 119.655799 -272.97669) (xy 119.70307 -272.990382) (xy 119.747532 -273.01148) (xy 119.788035 -273.039436)
			(xy 119.823528 -273.073528) (xy 119.853093 -273.112872) (xy 119.875964 -273.156449) (xy 119.891548 -273.20313)
			(xy 119.899443 -273.251707) (xy 119.899938 -273.276314) (xy 120.229388 -273.276314) (xy 120.233342 -273.227341)
			(xy 120.2451 -273.179637) (xy 120.264358 -273.134436) (xy 120.290617 -273.09291) (xy 120.323198 -273.056134)
			(xy 120.361256 -273.02506) (xy 120.403806 -273.000494) (xy 120.449745 -272.983072) (xy 120.497885 -272.973244)
			(xy 120.546977 -272.971266) (xy 120.595751 -272.977188) (xy 120.642943 -272.990857) (xy 120.687332 -273.01192)
			(xy 120.727767 -273.03983) (xy 120.763201 -273.073865) (xy 120.792717 -273.113144) (xy 120.81555 -273.156648)
			(xy 120.831109 -273.203252) (xy 120.83899 -273.251748) (xy 120.839484 -273.276314) (xy 122.108988 -273.276314)
			(xy 122.112948 -273.22726) (xy 122.124725 -273.179476) (xy 122.144016 -273.1342) (xy 122.170319 -273.092604)
			(xy 122.202954 -273.055767) (xy 122.241075 -273.024642) (xy 122.283696 -273.000035) (xy 122.329712 -272.982583)
			(xy 122.377931 -272.972739) (xy 122.427106 -272.970758) (xy 122.475961 -272.97669) (xy 122.523232 -272.990382)
			(xy 122.567694 -273.01148) (xy 122.608197 -273.039436) (xy 122.64369 -273.073528) (xy 122.673255 -273.112872)
			(xy 122.696126 -273.156449) (xy 122.71171 -273.20313) (xy 122.719605 -273.251707) (xy 122.7201 -273.276314)
			(xy 123.04955 -273.276314) (xy 123.053504 -273.227341) (xy 123.065262 -273.179637) (xy 123.08452 -273.134436)
			(xy 123.110779 -273.09291) (xy 123.14336 -273.056134) (xy 123.181418 -273.02506) (xy 123.223968 -273.000494)
			(xy 123.269907 -272.983072) (xy 123.318047 -272.973244) (xy 123.367139 -272.971266) (xy 123.415913 -272.977188)
			(xy 123.463105 -272.990857) (xy 123.507494 -273.01192) (xy 123.547929 -273.03983) (xy 123.583363 -273.073865)
			(xy 123.612879 -273.113144) (xy 123.635712 -273.156648) (xy 123.651271 -273.203252) (xy 123.659152 -273.251748)
			(xy 123.659646 -273.276314) (xy 124.928896 -273.276314) (xy 124.932856 -273.22726) (xy 124.944633 -273.179476)
			(xy 124.963924 -273.1342) (xy 124.990227 -273.092604) (xy 125.022862 -273.055767) (xy 125.060983 -273.024642)
			(xy 125.103604 -273.000035) (xy 125.14962 -272.982583) (xy 125.197839 -272.972739) (xy 125.247014 -272.970758)
			(xy 125.295869 -272.97669) (xy 125.34314 -272.990382) (xy 125.387602 -273.01148) (xy 125.428105 -273.039436)
			(xy 125.463598 -273.073528) (xy 125.493163 -273.112872) (xy 125.516034 -273.156449) (xy 125.531618 -273.20313)
			(xy 125.539513 -273.251707) (xy 125.540008 -273.276314) (xy 125.869458 -273.276314) (xy 125.873412 -273.227341)
			(xy 125.88517 -273.179637) (xy 125.904428 -273.134436) (xy 125.930687 -273.09291) (xy 125.963268 -273.056134)
			(xy 126.001326 -273.02506) (xy 126.043876 -273.000494) (xy 126.089815 -272.983072) (xy 126.137955 -272.973244)
			(xy 126.187047 -272.971266) (xy 126.235821 -272.977188) (xy 126.283013 -272.990857) (xy 126.327402 -273.01192)
			(xy 126.367837 -273.03983) (xy 126.403271 -273.073865) (xy 126.432787 -273.113144) (xy 126.45562 -273.156648)
			(xy 126.471179 -273.203252) (xy 126.47906 -273.251748) (xy 126.479549 -273.27606) (xy 345.615272 -273.27606)
			(xy 345.619232 -273.227006) (xy 345.631009 -273.179222) (xy 345.6503 -273.133946) (xy 345.676603 -273.09235)
			(xy 345.709238 -273.055513) (xy 345.747359 -273.024388) (xy 345.78998 -272.999781) (xy 345.835996 -272.982329)
			(xy 345.884215 -272.972485) (xy 345.93339 -272.970504) (xy 345.982245 -272.976436) (xy 346.029516 -272.990128)
			(xy 346.073978 -273.011226) (xy 346.114481 -273.039182) (xy 346.149974 -273.073274) (xy 346.179539 -273.112618)
			(xy 346.20241 -273.156195) (xy 346.217994 -273.202876) (xy 346.225889 -273.251453) (xy 346.226384 -273.27606)
			(xy 346.555834 -273.27606) (xy 346.559788 -273.227087) (xy 346.571546 -273.179383) (xy 346.590804 -273.134182)
			(xy 346.617063 -273.092656) (xy 346.649644 -273.05588) (xy 346.687702 -273.024806) (xy 346.730252 -273.00024)
			(xy 346.776191 -272.982818) (xy 346.824331 -272.97299) (xy 346.873423 -272.971012) (xy 346.922197 -272.976934)
			(xy 346.969389 -272.990603) (xy 347.013778 -273.011666) (xy 347.054213 -273.039576) (xy 347.089647 -273.073611)
			(xy 347.119163 -273.11289) (xy 347.141996 -273.156394) (xy 347.157555 -273.202998) (xy 347.165436 -273.251494)
			(xy 347.16593 -273.27606) (xy 348.43518 -273.27606) (xy 348.43914 -273.227006) (xy 348.450917 -273.179222)
			(xy 348.470208 -273.133946) (xy 348.496511 -273.09235) (xy 348.529146 -273.055513) (xy 348.567267 -273.024388)
			(xy 348.609888 -272.999781) (xy 348.655904 -272.982329) (xy 348.704123 -272.972485) (xy 348.753298 -272.970504)
			(xy 348.802153 -272.976436) (xy 348.849424 -272.990128) (xy 348.893886 -273.011226) (xy 348.934389 -273.039182)
			(xy 348.969882 -273.073274) (xy 348.999447 -273.112618) (xy 349.022318 -273.156195) (xy 349.037902 -273.202876)
			(xy 349.045797 -273.251453) (xy 349.046292 -273.27606) (xy 349.375742 -273.27606) (xy 349.379696 -273.227087)
			(xy 349.391454 -273.179383) (xy 349.410712 -273.134182) (xy 349.436971 -273.092656) (xy 349.469552 -273.05588)
			(xy 349.50761 -273.024806) (xy 349.55016 -273.00024) (xy 349.596099 -272.982818) (xy 349.644239 -272.97299)
			(xy 349.693331 -272.971012) (xy 349.742105 -272.976934) (xy 349.789297 -272.990603) (xy 349.833686 -273.011666)
			(xy 349.874121 -273.039576) (xy 349.909555 -273.073611) (xy 349.939071 -273.11289) (xy 349.961904 -273.156394)
			(xy 349.977463 -273.202998) (xy 349.985344 -273.251494) (xy 349.985838 -273.27606) (xy 351.255342 -273.27606)
			(xy 351.259302 -273.227006) (xy 351.271079 -273.179222) (xy 351.29037 -273.133946) (xy 351.316673 -273.09235)
			(xy 351.349308 -273.055513) (xy 351.387429 -273.024388) (xy 351.43005 -272.999781) (xy 351.476066 -272.982329)
			(xy 351.524285 -272.972485) (xy 351.57346 -272.970504) (xy 351.622315 -272.976436) (xy 351.669586 -272.990128)
			(xy 351.714048 -273.011226) (xy 351.754551 -273.039182) (xy 351.790044 -273.073274) (xy 351.819609 -273.112618)
			(xy 351.84248 -273.156195) (xy 351.858064 -273.202876) (xy 351.865959 -273.251453) (xy 351.866454 -273.27606)
			(xy 352.195904 -273.27606) (xy 352.199858 -273.227087) (xy 352.211616 -273.179383) (xy 352.230874 -273.134182)
			(xy 352.257133 -273.092656) (xy 352.289714 -273.05588) (xy 352.327772 -273.024806) (xy 352.370322 -273.00024)
			(xy 352.416261 -272.982818) (xy 352.464401 -272.97299) (xy 352.513493 -272.971012) (xy 352.562267 -272.976934)
			(xy 352.609459 -272.990603) (xy 352.653848 -273.011666) (xy 352.694283 -273.039576) (xy 352.729717 -273.073611)
			(xy 352.759233 -273.11289) (xy 352.782066 -273.156394) (xy 352.797625 -273.202998) (xy 352.805506 -273.251494)
			(xy 352.806 -273.27606) (xy 354.07525 -273.27606) (xy 354.07921 -273.227006) (xy 354.090987 -273.179222)
			(xy 354.110278 -273.133946) (xy 354.136581 -273.09235) (xy 354.169216 -273.055513) (xy 354.207337 -273.024388)
			(xy 354.249958 -272.999781) (xy 354.295974 -272.982329) (xy 354.344193 -272.972485) (xy 354.393368 -272.970504)
			(xy 354.442223 -272.976436) (xy 354.489494 -272.990128) (xy 354.533956 -273.011226) (xy 354.574459 -273.039182)
			(xy 354.609952 -273.073274) (xy 354.639517 -273.112618) (xy 354.662388 -273.156195) (xy 354.677972 -273.202876)
			(xy 354.685867 -273.251453) (xy 354.686362 -273.27606) (xy 355.015812 -273.27606) (xy 355.019766 -273.227087)
			(xy 355.031524 -273.179383) (xy 355.050782 -273.134182) (xy 355.077041 -273.092656) (xy 355.109622 -273.05588)
			(xy 355.14768 -273.024806) (xy 355.19023 -273.00024) (xy 355.236169 -272.982818) (xy 355.284309 -272.97299)
			(xy 355.333401 -272.971012) (xy 355.382175 -272.976934) (xy 355.429367 -272.990603) (xy 355.473756 -273.011666)
			(xy 355.514191 -273.039576) (xy 355.549625 -273.073611) (xy 355.579141 -273.11289) (xy 355.601974 -273.156394)
			(xy 355.617533 -273.202998) (xy 355.625414 -273.251494) (xy 355.625908 -273.27606) (xy 364.408986 -273.27606)
			(xy 364.412946 -273.227006) (xy 364.424723 -273.179222) (xy 364.444014 -273.133946) (xy 364.470317 -273.09235)
			(xy 364.502952 -273.055513) (xy 364.541073 -273.024388) (xy 364.583694 -272.999781) (xy 364.62971 -272.982329)
			(xy 364.677929 -272.972485) (xy 364.727104 -272.970504) (xy 364.775959 -272.976436) (xy 364.82323 -272.990128)
			(xy 364.867692 -273.011226) (xy 364.908195 -273.039182) (xy 364.943688 -273.073274) (xy 364.973253 -273.112618)
			(xy 364.996124 -273.156195) (xy 365.011708 -273.202876) (xy 365.019603 -273.251453) (xy 365.020098 -273.27606)
			(xy 365.349548 -273.27606) (xy 365.353502 -273.227087) (xy 365.36526 -273.179383) (xy 365.384518 -273.134182)
			(xy 365.410777 -273.092656) (xy 365.443358 -273.05588) (xy 365.481416 -273.024806) (xy 365.523966 -273.00024)
			(xy 365.569905 -272.982818) (xy 365.618045 -272.97299) (xy 365.667137 -272.971012) (xy 365.715911 -272.976934)
			(xy 365.763103 -272.990603) (xy 365.807492 -273.011666) (xy 365.847927 -273.039576) (xy 365.883361 -273.073611)
			(xy 365.912877 -273.11289) (xy 365.93571 -273.156394) (xy 365.951269 -273.202998) (xy 365.95915 -273.251494)
			(xy 365.959644 -273.27606) (xy 367.228894 -273.27606) (xy 367.232854 -273.227006) (xy 367.244631 -273.179222)
			(xy 367.263922 -273.133946) (xy 367.290225 -273.09235) (xy 367.32286 -273.055513) (xy 367.360981 -273.024388)
			(xy 367.403602 -272.999781) (xy 367.449618 -272.982329) (xy 367.497837 -272.972485) (xy 367.547012 -272.970504)
			(xy 367.595867 -272.976436) (xy 367.643138 -272.990128) (xy 367.6876 -273.011226) (xy 367.728103 -273.039182)
			(xy 367.763596 -273.073274) (xy 367.793161 -273.112618) (xy 367.816032 -273.156195) (xy 367.831616 -273.202876)
			(xy 367.839511 -273.251453) (xy 367.840006 -273.27606) (xy 368.169456 -273.27606) (xy 368.17341 -273.227087)
			(xy 368.185168 -273.179383) (xy 368.204426 -273.134182) (xy 368.230685 -273.092656) (xy 368.263266 -273.05588)
			(xy 368.301324 -273.024806) (xy 368.343874 -273.00024) (xy 368.389813 -272.982818) (xy 368.437953 -272.97299)
			(xy 368.487045 -272.971012) (xy 368.535819 -272.976934) (xy 368.583011 -272.990603) (xy 368.6274 -273.011666)
			(xy 368.667835 -273.039576) (xy 368.703269 -273.073611) (xy 368.732785 -273.11289) (xy 368.755618 -273.156394)
			(xy 368.771177 -273.202998) (xy 368.779058 -273.251494) (xy 368.779552 -273.27606) (xy 370.049056 -273.27606)
			(xy 370.053016 -273.227006) (xy 370.064793 -273.179222) (xy 370.084084 -273.133946) (xy 370.110387 -273.09235)
			(xy 370.143022 -273.055513) (xy 370.181143 -273.024388) (xy 370.223764 -272.999781) (xy 370.26978 -272.982329)
			(xy 370.317999 -272.972485) (xy 370.367174 -272.970504) (xy 370.416029 -272.976436) (xy 370.4633 -272.990128)
			(xy 370.507762 -273.011226) (xy 370.548265 -273.039182) (xy 370.583758 -273.073274) (xy 370.613323 -273.112618)
			(xy 370.636194 -273.156195) (xy 370.651778 -273.202876) (xy 370.659673 -273.251453) (xy 370.660168 -273.27606)
			(xy 370.989618 -273.27606) (xy 370.993572 -273.227087) (xy 371.00533 -273.179383) (xy 371.024588 -273.134182)
			(xy 371.050847 -273.092656) (xy 371.083428 -273.05588) (xy 371.121486 -273.024806) (xy 371.164036 -273.00024)
			(xy 371.209975 -272.982818) (xy 371.258115 -272.97299) (xy 371.307207 -272.971012) (xy 371.355981 -272.976934)
			(xy 371.403173 -272.990603) (xy 371.447562 -273.011666) (xy 371.487997 -273.039576) (xy 371.523431 -273.073611)
			(xy 371.552947 -273.11289) (xy 371.57578 -273.156394) (xy 371.591339 -273.202998) (xy 371.59922 -273.251494)
			(xy 371.599714 -273.27606) (xy 372.868964 -273.27606) (xy 372.872924 -273.227006) (xy 372.884701 -273.179222)
			(xy 372.903992 -273.133946) (xy 372.930295 -273.09235) (xy 372.96293 -273.055513) (xy 373.001051 -273.024388)
			(xy 373.043672 -272.999781) (xy 373.089688 -272.982329) (xy 373.137907 -272.972485) (xy 373.187082 -272.970504)
			(xy 373.235937 -272.976436) (xy 373.283208 -272.990128) (xy 373.32767 -273.011226) (xy 373.368173 -273.039182)
			(xy 373.403666 -273.073274) (xy 373.433231 -273.112618) (xy 373.456102 -273.156195) (xy 373.471686 -273.202876)
			(xy 373.479581 -273.251453) (xy 373.480076 -273.27606) (xy 373.809526 -273.27606) (xy 373.81348 -273.227087)
			(xy 373.825238 -273.179383) (xy 373.844496 -273.134182) (xy 373.870755 -273.092656) (xy 373.903336 -273.05588)
			(xy 373.941394 -273.024806) (xy 373.983944 -273.00024) (xy 374.029883 -272.982818) (xy 374.078023 -272.97299)
			(xy 374.127115 -272.971012) (xy 374.175889 -272.976934) (xy 374.223081 -272.990603) (xy 374.26747 -273.011666)
			(xy 374.307905 -273.039576) (xy 374.343339 -273.073611) (xy 374.372855 -273.11289) (xy 374.395688 -273.156394)
			(xy 374.411247 -273.202998) (xy 374.419128 -273.251494) (xy 374.419622 -273.27606) (xy 374.419128 -273.300626)
			(xy 374.411247 -273.349122) (xy 374.395688 -273.395726) (xy 374.372855 -273.43923) (xy 374.343339 -273.478509)
			(xy 374.307905 -273.512544) (xy 374.26747 -273.540454) (xy 374.223081 -273.561517) (xy 374.175889 -273.575186)
			(xy 374.127115 -273.581108) (xy 374.078023 -273.57913) (xy 374.029883 -273.569302) (xy 373.983944 -273.55188)
			(xy 373.941394 -273.527314) (xy 373.903336 -273.49624) (xy 373.870755 -273.459464) (xy 373.844496 -273.417938)
			(xy 373.825238 -273.372737) (xy 373.81348 -273.325033) (xy 373.809526 -273.27606) (xy 373.480076 -273.27606)
			(xy 373.479581 -273.300667) (xy 373.471686 -273.349244) (xy 373.456102 -273.395925) (xy 373.433231 -273.439502)
			(xy 373.403666 -273.478846) (xy 373.368173 -273.512938) (xy 373.32767 -273.540894) (xy 373.283208 -273.561992)
			(xy 373.235937 -273.575684) (xy 373.187082 -273.581616) (xy 373.137907 -273.579635) (xy 373.089688 -273.569791)
			(xy 373.043672 -273.552339) (xy 373.001051 -273.527732) (xy 372.96293 -273.496607) (xy 372.930295 -273.45977)
			(xy 372.903992 -273.418174) (xy 372.884701 -273.372898) (xy 372.872924 -273.325114) (xy 372.868964 -273.27606)
			(xy 371.599714 -273.27606) (xy 371.59922 -273.300626) (xy 371.591339 -273.349122) (xy 371.57578 -273.395726)
			(xy 371.552947 -273.43923) (xy 371.523431 -273.478509) (xy 371.487997 -273.512544) (xy 371.447562 -273.540454)
			(xy 371.403173 -273.561517) (xy 371.355981 -273.575186) (xy 371.307207 -273.581108) (xy 371.258115 -273.57913)
			(xy 371.209975 -273.569302) (xy 371.164036 -273.55188) (xy 371.121486 -273.527314) (xy 371.083428 -273.49624)
			(xy 371.050847 -273.459464) (xy 371.024588 -273.417938) (xy 371.00533 -273.372737) (xy 370.993572 -273.325033)
			(xy 370.989618 -273.27606) (xy 370.660168 -273.27606) (xy 370.659673 -273.300667) (xy 370.651778 -273.349244)
			(xy 370.636194 -273.395925) (xy 370.613323 -273.439502) (xy 370.583758 -273.478846) (xy 370.548265 -273.512938)
			(xy 370.507762 -273.540894) (xy 370.4633 -273.561992) (xy 370.416029 -273.575684) (xy 370.367174 -273.581616)
			(xy 370.317999 -273.579635) (xy 370.26978 -273.569791) (xy 370.223764 -273.552339) (xy 370.181143 -273.527732)
			(xy 370.143022 -273.496607) (xy 370.110387 -273.45977) (xy 370.084084 -273.418174) (xy 370.064793 -273.372898)
			(xy 370.053016 -273.325114) (xy 370.049056 -273.27606) (xy 368.779552 -273.27606) (xy 368.779058 -273.300626)
			(xy 368.771177 -273.349122) (xy 368.755618 -273.395726) (xy 368.732785 -273.43923) (xy 368.703269 -273.478509)
			(xy 368.667835 -273.512544) (xy 368.6274 -273.540454) (xy 368.583011 -273.561517) (xy 368.535819 -273.575186)
			(xy 368.487045 -273.581108) (xy 368.437953 -273.57913) (xy 368.389813 -273.569302) (xy 368.343874 -273.55188)
			(xy 368.301324 -273.527314) (xy 368.263266 -273.49624) (xy 368.230685 -273.459464) (xy 368.204426 -273.417938)
			(xy 368.185168 -273.372737) (xy 368.17341 -273.325033) (xy 368.169456 -273.27606) (xy 367.840006 -273.27606)
			(xy 367.839511 -273.300667) (xy 367.831616 -273.349244) (xy 367.816032 -273.395925) (xy 367.793161 -273.439502)
			(xy 367.763596 -273.478846) (xy 367.728103 -273.512938) (xy 367.6876 -273.540894) (xy 367.643138 -273.561992)
			(xy 367.595867 -273.575684) (xy 367.547012 -273.581616) (xy 367.497837 -273.579635) (xy 367.449618 -273.569791)
			(xy 367.403602 -273.552339) (xy 367.360981 -273.527732) (xy 367.32286 -273.496607) (xy 367.290225 -273.45977)
			(xy 367.263922 -273.418174) (xy 367.244631 -273.372898) (xy 367.232854 -273.325114) (xy 367.228894 -273.27606)
			(xy 365.959644 -273.27606) (xy 365.95915 -273.300626) (xy 365.951269 -273.349122) (xy 365.93571 -273.395726)
			(xy 365.912877 -273.43923) (xy 365.883361 -273.478509) (xy 365.847927 -273.512544) (xy 365.807492 -273.540454)
			(xy 365.763103 -273.561517) (xy 365.715911 -273.575186) (xy 365.667137 -273.581108) (xy 365.618045 -273.57913)
			(xy 365.569905 -273.569302) (xy 365.523966 -273.55188) (xy 365.481416 -273.527314) (xy 365.443358 -273.49624)
			(xy 365.410777 -273.459464) (xy 365.384518 -273.417938) (xy 365.36526 -273.372737) (xy 365.353502 -273.325033)
			(xy 365.349548 -273.27606) (xy 365.020098 -273.27606) (xy 365.019603 -273.300667) (xy 365.011708 -273.349244)
			(xy 364.996124 -273.395925) (xy 364.973253 -273.439502) (xy 364.943688 -273.478846) (xy 364.908195 -273.512938)
			(xy 364.867692 -273.540894) (xy 364.82323 -273.561992) (xy 364.775959 -273.575684) (xy 364.727104 -273.581616)
			(xy 364.677929 -273.579635) (xy 364.62971 -273.569791) (xy 364.583694 -273.552339) (xy 364.541073 -273.527732)
			(xy 364.502952 -273.496607) (xy 364.470317 -273.45977) (xy 364.444014 -273.418174) (xy 364.424723 -273.372898)
			(xy 364.412946 -273.325114) (xy 364.408986 -273.27606) (xy 355.625908 -273.27606) (xy 355.625414 -273.300626)
			(xy 355.617533 -273.349122) (xy 355.601974 -273.395726) (xy 355.579141 -273.43923) (xy 355.549625 -273.478509)
			(xy 355.514191 -273.512544) (xy 355.473756 -273.540454) (xy 355.429367 -273.561517) (xy 355.382175 -273.575186)
			(xy 355.333401 -273.581108) (xy 355.284309 -273.57913) (xy 355.236169 -273.569302) (xy 355.19023 -273.55188)
			(xy 355.14768 -273.527314) (xy 355.109622 -273.49624) (xy 355.077041 -273.459464) (xy 355.050782 -273.417938)
			(xy 355.031524 -273.372737) (xy 355.019766 -273.325033) (xy 355.015812 -273.27606) (xy 354.686362 -273.27606)
			(xy 354.685867 -273.300667) (xy 354.677972 -273.349244) (xy 354.662388 -273.395925) (xy 354.639517 -273.439502)
			(xy 354.609952 -273.478846) (xy 354.574459 -273.512938) (xy 354.533956 -273.540894) (xy 354.489494 -273.561992)
			(xy 354.442223 -273.575684) (xy 354.393368 -273.581616) (xy 354.344193 -273.579635) (xy 354.295974 -273.569791)
			(xy 354.249958 -273.552339) (xy 354.207337 -273.527732) (xy 354.169216 -273.496607) (xy 354.136581 -273.45977)
			(xy 354.110278 -273.418174) (xy 354.090987 -273.372898) (xy 354.07921 -273.325114) (xy 354.07525 -273.27606)
			(xy 352.806 -273.27606) (xy 352.805506 -273.300626) (xy 352.797625 -273.349122) (xy 352.782066 -273.395726)
			(xy 352.759233 -273.43923) (xy 352.729717 -273.478509) (xy 352.694283 -273.512544) (xy 352.653848 -273.540454)
			(xy 352.609459 -273.561517) (xy 352.562267 -273.575186) (xy 352.513493 -273.581108) (xy 352.464401 -273.57913)
			(xy 352.416261 -273.569302) (xy 352.370322 -273.55188) (xy 352.327772 -273.527314) (xy 352.289714 -273.49624)
			(xy 352.257133 -273.459464) (xy 352.230874 -273.417938) (xy 352.211616 -273.372737) (xy 352.199858 -273.325033)
			(xy 352.195904 -273.27606) (xy 351.866454 -273.27606) (xy 351.865959 -273.300667) (xy 351.858064 -273.349244)
			(xy 351.84248 -273.395925) (xy 351.819609 -273.439502) (xy 351.790044 -273.478846) (xy 351.754551 -273.512938)
			(xy 351.714048 -273.540894) (xy 351.669586 -273.561992) (xy 351.622315 -273.575684) (xy 351.57346 -273.581616)
			(xy 351.524285 -273.579635) (xy 351.476066 -273.569791) (xy 351.43005 -273.552339) (xy 351.387429 -273.527732)
			(xy 351.349308 -273.496607) (xy 351.316673 -273.45977) (xy 351.29037 -273.418174) (xy 351.271079 -273.372898)
			(xy 351.259302 -273.325114) (xy 351.255342 -273.27606) (xy 349.985838 -273.27606) (xy 349.985344 -273.300626)
			(xy 349.977463 -273.349122) (xy 349.961904 -273.395726) (xy 349.939071 -273.43923) (xy 349.909555 -273.478509)
			(xy 349.874121 -273.512544) (xy 349.833686 -273.540454) (xy 349.789297 -273.561517) (xy 349.742105 -273.575186)
			(xy 349.693331 -273.581108) (xy 349.644239 -273.57913) (xy 349.596099 -273.569302) (xy 349.55016 -273.55188)
			(xy 349.50761 -273.527314) (xy 349.469552 -273.49624) (xy 349.436971 -273.459464) (xy 349.410712 -273.417938)
			(xy 349.391454 -273.372737) (xy 349.379696 -273.325033) (xy 349.375742 -273.27606) (xy 349.046292 -273.27606)
			(xy 349.045797 -273.300667) (xy 349.037902 -273.349244) (xy 349.022318 -273.395925) (xy 348.999447 -273.439502)
			(xy 348.969882 -273.478846) (xy 348.934389 -273.512938) (xy 348.893886 -273.540894) (xy 348.849424 -273.561992)
			(xy 348.802153 -273.575684) (xy 348.753298 -273.581616) (xy 348.704123 -273.579635) (xy 348.655904 -273.569791)
			(xy 348.609888 -273.552339) (xy 348.567267 -273.527732) (xy 348.529146 -273.496607) (xy 348.496511 -273.45977)
			(xy 348.470208 -273.418174) (xy 348.450917 -273.372898) (xy 348.43914 -273.325114) (xy 348.43518 -273.27606)
			(xy 347.16593 -273.27606) (xy 347.165436 -273.300626) (xy 347.157555 -273.349122) (xy 347.141996 -273.395726)
			(xy 347.119163 -273.43923) (xy 347.089647 -273.478509) (xy 347.054213 -273.512544) (xy 347.013778 -273.540454)
			(xy 346.969389 -273.561517) (xy 346.922197 -273.575186) (xy 346.873423 -273.581108) (xy 346.824331 -273.57913)
			(xy 346.776191 -273.569302) (xy 346.730252 -273.55188) (xy 346.687702 -273.527314) (xy 346.649644 -273.49624)
			(xy 346.617063 -273.459464) (xy 346.590804 -273.417938) (xy 346.571546 -273.372737) (xy 346.559788 -273.325033)
			(xy 346.555834 -273.27606) (xy 346.226384 -273.27606) (xy 346.225889 -273.300667) (xy 346.217994 -273.349244)
			(xy 346.20241 -273.395925) (xy 346.179539 -273.439502) (xy 346.149974 -273.478846) (xy 346.114481 -273.512938)
			(xy 346.073978 -273.540894) (xy 346.029516 -273.561992) (xy 345.982245 -273.575684) (xy 345.93339 -273.581616)
			(xy 345.884215 -273.579635) (xy 345.835996 -273.569791) (xy 345.78998 -273.552339) (xy 345.747359 -273.527732)
			(xy 345.709238 -273.496607) (xy 345.676603 -273.45977) (xy 345.6503 -273.418174) (xy 345.631009 -273.372898)
			(xy 345.619232 -273.325114) (xy 345.615272 -273.27606) (xy 126.479549 -273.27606) (xy 126.479554 -273.276314)
			(xy 126.47906 -273.30088) (xy 126.471179 -273.349376) (xy 126.45562 -273.39598) (xy 126.432787 -273.439484)
			(xy 126.403271 -273.478763) (xy 126.367837 -273.512798) (xy 126.327402 -273.540708) (xy 126.283013 -273.561771)
			(xy 126.235821 -273.57544) (xy 126.187047 -273.581362) (xy 126.137955 -273.579384) (xy 126.089815 -273.569556)
			(xy 126.043876 -273.552134) (xy 126.001326 -273.527568) (xy 125.963268 -273.496494) (xy 125.930687 -273.459718)
			(xy 125.904428 -273.418192) (xy 125.88517 -273.372991) (xy 125.873412 -273.325287) (xy 125.869458 -273.276314)
			(xy 125.540008 -273.276314) (xy 125.539513 -273.300921) (xy 125.531618 -273.349498) (xy 125.516034 -273.396179)
			(xy 125.493163 -273.439756) (xy 125.463598 -273.4791) (xy 125.428105 -273.513192) (xy 125.387602 -273.541148)
			(xy 125.34314 -273.562246) (xy 125.295869 -273.575938) (xy 125.247014 -273.58187) (xy 125.197839 -273.579889)
			(xy 125.14962 -273.570045) (xy 125.103604 -273.552593) (xy 125.060983 -273.527986) (xy 125.022862 -273.496861)
			(xy 124.990227 -273.460024) (xy 124.963924 -273.418428) (xy 124.944633 -273.373152) (xy 124.932856 -273.325368)
			(xy 124.928896 -273.276314) (xy 123.659646 -273.276314) (xy 123.659152 -273.30088) (xy 123.651271 -273.349376)
			(xy 123.635712 -273.39598) (xy 123.612879 -273.439484) (xy 123.583363 -273.478763) (xy 123.547929 -273.512798)
			(xy 123.507494 -273.540708) (xy 123.463105 -273.561771) (xy 123.415913 -273.57544) (xy 123.367139 -273.581362)
			(xy 123.318047 -273.579384) (xy 123.269907 -273.569556) (xy 123.223968 -273.552134) (xy 123.181418 -273.527568)
			(xy 123.14336 -273.496494) (xy 123.110779 -273.459718) (xy 123.08452 -273.418192) (xy 123.065262 -273.372991)
			(xy 123.053504 -273.325287) (xy 123.04955 -273.276314) (xy 122.7201 -273.276314) (xy 122.719605 -273.300921)
			(xy 122.71171 -273.349498) (xy 122.696126 -273.396179) (xy 122.673255 -273.439756) (xy 122.64369 -273.4791)
			(xy 122.608197 -273.513192) (xy 122.567694 -273.541148) (xy 122.523232 -273.562246) (xy 122.475961 -273.575938)
			(xy 122.427106 -273.58187) (xy 122.377931 -273.579889) (xy 122.329712 -273.570045) (xy 122.283696 -273.552593)
			(xy 122.241075 -273.527986) (xy 122.202954 -273.496861) (xy 122.170319 -273.460024) (xy 122.144016 -273.418428)
			(xy 122.124725 -273.373152) (xy 122.112948 -273.325368) (xy 122.108988 -273.276314) (xy 120.839484 -273.276314)
			(xy 120.83899 -273.30088) (xy 120.831109 -273.349376) (xy 120.81555 -273.39598) (xy 120.792717 -273.439484)
			(xy 120.763201 -273.478763) (xy 120.727767 -273.512798) (xy 120.687332 -273.540708) (xy 120.642943 -273.561771)
			(xy 120.595751 -273.57544) (xy 120.546977 -273.581362) (xy 120.497885 -273.579384) (xy 120.449745 -273.569556)
			(xy 120.403806 -273.552134) (xy 120.361256 -273.527568) (xy 120.323198 -273.496494) (xy 120.290617 -273.459718)
			(xy 120.264358 -273.418192) (xy 120.2451 -273.372991) (xy 120.233342 -273.325287) (xy 120.229388 -273.276314)
			(xy 119.899938 -273.276314) (xy 119.899443 -273.300921) (xy 119.891548 -273.349498) (xy 119.875964 -273.396179)
			(xy 119.853093 -273.439756) (xy 119.823528 -273.4791) (xy 119.788035 -273.513192) (xy 119.747532 -273.541148)
			(xy 119.70307 -273.562246) (xy 119.655799 -273.575938) (xy 119.606944 -273.58187) (xy 119.557769 -273.579889)
			(xy 119.50955 -273.570045) (xy 119.463534 -273.552593) (xy 119.420913 -273.527986) (xy 119.382792 -273.496861)
			(xy 119.350157 -273.460024) (xy 119.323854 -273.418428) (xy 119.304563 -273.373152) (xy 119.292786 -273.325368)
			(xy 119.288826 -273.276314) (xy 118.019576 -273.276314) (xy 118.019082 -273.30088) (xy 118.011201 -273.349376)
			(xy 117.995642 -273.39598) (xy 117.972809 -273.439484) (xy 117.943293 -273.478763) (xy 117.907859 -273.512798)
			(xy 117.867424 -273.540708) (xy 117.823035 -273.561771) (xy 117.775843 -273.57544) (xy 117.727069 -273.581362)
			(xy 117.677977 -273.579384) (xy 117.629837 -273.569556) (xy 117.583898 -273.552134) (xy 117.541348 -273.527568)
			(xy 117.50329 -273.496494) (xy 117.470709 -273.459718) (xy 117.44445 -273.418192) (xy 117.425192 -273.372991)
			(xy 117.413434 -273.325287) (xy 117.40948 -273.276314) (xy 117.08003 -273.276314) (xy 117.079535 -273.300921)
			(xy 117.07164 -273.349498) (xy 117.056056 -273.396179) (xy 117.033185 -273.439756) (xy 117.00362 -273.4791)
			(xy 116.968127 -273.513192) (xy 116.927624 -273.541148) (xy 116.883162 -273.562246) (xy 116.835891 -273.575938)
			(xy 116.787036 -273.58187) (xy 116.737861 -273.579889) (xy 116.689642 -273.570045) (xy 116.643626 -273.552593)
			(xy 116.601005 -273.527986) (xy 116.562884 -273.496861) (xy 116.530249 -273.460024) (xy 116.503946 -273.418428)
			(xy 116.484655 -273.373152) (xy 116.472878 -273.325368) (xy 116.468918 -273.276314) (xy 107.68584 -273.276314)
			(xy 107.685346 -273.30088) (xy 107.677465 -273.349376) (xy 107.661906 -273.39598) (xy 107.639073 -273.439484)
			(xy 107.609557 -273.478763) (xy 107.574123 -273.512798) (xy 107.533688 -273.540708) (xy 107.489299 -273.561771)
			(xy 107.442107 -273.57544) (xy 107.393333 -273.581362) (xy 107.344241 -273.579384) (xy 107.296101 -273.569556)
			(xy 107.250162 -273.552134) (xy 107.207612 -273.527568) (xy 107.169554 -273.496494) (xy 107.136973 -273.459718)
			(xy 107.110714 -273.418192) (xy 107.091456 -273.372991) (xy 107.079698 -273.325287) (xy 107.075744 -273.276314)
			(xy 106.746294 -273.276314) (xy 106.745799 -273.300921) (xy 106.737904 -273.349498) (xy 106.72232 -273.396179)
			(xy 106.699449 -273.439756) (xy 106.669884 -273.4791) (xy 106.634391 -273.513192) (xy 106.593888 -273.541148)
			(xy 106.549426 -273.562246) (xy 106.502155 -273.575938) (xy 106.4533 -273.58187) (xy 106.404125 -273.579889)
			(xy 106.355906 -273.570045) (xy 106.30989 -273.552593) (xy 106.267269 -273.527986) (xy 106.229148 -273.496861)
			(xy 106.196513 -273.460024) (xy 106.17021 -273.418428) (xy 106.150919 -273.373152) (xy 106.139142 -273.325368)
			(xy 106.135182 -273.276314) (xy 104.865932 -273.276314) (xy 104.865438 -273.30088) (xy 104.857557 -273.349376)
			(xy 104.841998 -273.39598) (xy 104.819165 -273.439484) (xy 104.789649 -273.478763) (xy 104.754215 -273.512798)
			(xy 104.71378 -273.540708) (xy 104.669391 -273.561771) (xy 104.622199 -273.57544) (xy 104.573425 -273.581362)
			(xy 104.524333 -273.579384) (xy 104.476193 -273.569556) (xy 104.430254 -273.552134) (xy 104.387704 -273.527568)
			(xy 104.349646 -273.496494) (xy 104.317065 -273.459718) (xy 104.290806 -273.418192) (xy 104.271548 -273.372991)
			(xy 104.25979 -273.325287) (xy 104.255836 -273.276314) (xy 103.926386 -273.276314) (xy 103.925891 -273.300921)
			(xy 103.917996 -273.349498) (xy 103.902412 -273.396179) (xy 103.879541 -273.439756) (xy 103.849976 -273.4791)
			(xy 103.814483 -273.513192) (xy 103.77398 -273.541148) (xy 103.729518 -273.562246) (xy 103.682247 -273.575938)
			(xy 103.633392 -273.58187) (xy 103.584217 -273.579889) (xy 103.535998 -273.570045) (xy 103.489982 -273.552593)
			(xy 103.447361 -273.527986) (xy 103.40924 -273.496861) (xy 103.376605 -273.460024) (xy 103.350302 -273.418428)
			(xy 103.331011 -273.373152) (xy 103.319234 -273.325368) (xy 103.315274 -273.276314) (xy 102.04577 -273.276314)
			(xy 102.045276 -273.30088) (xy 102.037395 -273.349376) (xy 102.021836 -273.39598) (xy 101.999003 -273.439484)
			(xy 101.969487 -273.478763) (xy 101.934053 -273.512798) (xy 101.893618 -273.540708) (xy 101.849229 -273.561771)
			(xy 101.802037 -273.57544) (xy 101.753263 -273.581362) (xy 101.704171 -273.579384) (xy 101.656031 -273.569556)
			(xy 101.610092 -273.552134) (xy 101.567542 -273.527568) (xy 101.529484 -273.496494) (xy 101.496903 -273.459718)
			(xy 101.470644 -273.418192) (xy 101.451386 -273.372991) (xy 101.439628 -273.325287) (xy 101.435674 -273.276314)
			(xy 101.106224 -273.276314) (xy 101.105729 -273.300921) (xy 101.097834 -273.349498) (xy 101.08225 -273.396179)
			(xy 101.059379 -273.439756) (xy 101.029814 -273.4791) (xy 100.994321 -273.513192) (xy 100.953818 -273.541148)
			(xy 100.909356 -273.562246) (xy 100.862085 -273.575938) (xy 100.81323 -273.58187) (xy 100.764055 -273.579889)
			(xy 100.715836 -273.570045) (xy 100.66982 -273.552593) (xy 100.627199 -273.527986) (xy 100.589078 -273.496861)
			(xy 100.556443 -273.460024) (xy 100.53014 -273.418428) (xy 100.510849 -273.373152) (xy 100.499072 -273.325368)
			(xy 100.495112 -273.276314) (xy 99.225862 -273.276314) (xy 99.225368 -273.30088) (xy 99.217487 -273.349376)
			(xy 99.201928 -273.39598) (xy 99.179095 -273.439484) (xy 99.149579 -273.478763) (xy 99.114145 -273.512798)
			(xy 99.07371 -273.540708) (xy 99.029321 -273.561771) (xy 98.982129 -273.57544) (xy 98.933355 -273.581362)
			(xy 98.884263 -273.579384) (xy 98.836123 -273.569556) (xy 98.790184 -273.552134) (xy 98.747634 -273.527568)
			(xy 98.709576 -273.496494) (xy 98.676995 -273.459718) (xy 98.650736 -273.418192) (xy 98.631478 -273.372991)
			(xy 98.61972 -273.325287) (xy 98.615766 -273.276314) (xy 98.286316 -273.276314) (xy 98.285821 -273.300921)
			(xy 98.277926 -273.349498) (xy 98.262342 -273.396179) (xy 98.239471 -273.439756) (xy 98.209906 -273.4791)
			(xy 98.174413 -273.513192) (xy 98.13391 -273.541148) (xy 98.089448 -273.562246) (xy 98.042177 -273.575938)
			(xy 97.993322 -273.58187) (xy 97.944147 -273.579889) (xy 97.895928 -273.570045) (xy 97.849912 -273.552593)
			(xy 97.807291 -273.527986) (xy 97.76917 -273.496861) (xy 97.736535 -273.460024) (xy 97.710232 -273.418428)
			(xy 97.690941 -273.373152) (xy 97.679164 -273.325368) (xy 97.675204 -273.276314) (xy 2.509012 -273.276314)
			(xy 2.509012 -274.08632) (xy 108.48519 -274.08632) (xy 108.48915 -274.037266) (xy 108.500927 -273.989482)
			(xy 108.520218 -273.944206) (xy 108.546521 -273.90261) (xy 108.579156 -273.865773) (xy 108.617277 -273.834648)
			(xy 108.659898 -273.810041) (xy 108.705914 -273.792589) (xy 108.754133 -273.782745) (xy 108.803308 -273.780764)
			(xy 108.852163 -273.786696) (xy 108.899434 -273.800388) (xy 108.943896 -273.821486) (xy 108.984399 -273.849442)
			(xy 109.019892 -273.883534) (xy 109.049457 -273.922878) (xy 109.072328 -273.966455) (xy 109.087912 -274.013136)
			(xy 109.095807 -274.061713) (xy 109.096302 -274.08632) (xy 109.425752 -274.08632) (xy 109.429706 -274.037347)
			(xy 109.441464 -273.989643) (xy 109.460722 -273.944442) (xy 109.486981 -273.902916) (xy 109.519562 -273.86614)
			(xy 109.55762 -273.835066) (xy 109.60017 -273.8105) (xy 109.646109 -273.793078) (xy 109.694249 -273.78325)
			(xy 109.743341 -273.781272) (xy 109.792115 -273.787194) (xy 109.839307 -273.800863) (xy 109.883696 -273.821926)
			(xy 109.924131 -273.849836) (xy 109.959565 -273.883871) (xy 109.989081 -273.92315) (xy 110.011914 -273.966654)
			(xy 110.027473 -274.013258) (xy 110.035354 -274.061754) (xy 110.035848 -274.08632) (xy 114.11891 -274.08632)
			(xy 114.12287 -274.037266) (xy 114.134647 -273.989482) (xy 114.153938 -273.944206) (xy 114.180241 -273.90261)
			(xy 114.212876 -273.865773) (xy 114.250997 -273.834648) (xy 114.293618 -273.810041) (xy 114.339634 -273.792589)
			(xy 114.387853 -273.782745) (xy 114.437028 -273.780764) (xy 114.485883 -273.786696) (xy 114.533154 -273.800388)
			(xy 114.577616 -273.821486) (xy 114.618119 -273.849442) (xy 114.653612 -273.883534) (xy 114.683177 -273.922878)
			(xy 114.706048 -273.966455) (xy 114.721632 -274.013136) (xy 114.729527 -274.061713) (xy 114.730022 -274.08632)
			(xy 115.059472 -274.08632) (xy 115.063426 -274.037347) (xy 115.075184 -273.989643) (xy 115.094442 -273.944442)
			(xy 115.120701 -273.902916) (xy 115.153282 -273.86614) (xy 115.19134 -273.835066) (xy 115.23389 -273.8105)
			(xy 115.279829 -273.793078) (xy 115.327969 -273.78325) (xy 115.377061 -273.781272) (xy 115.425835 -273.787194)
			(xy 115.473027 -273.800863) (xy 115.517416 -273.821926) (xy 115.557851 -273.849836) (xy 115.593285 -273.883871)
			(xy 115.622801 -273.92315) (xy 115.645634 -273.966654) (xy 115.661193 -274.013258) (xy 115.669074 -274.061754)
			(xy 115.669563 -274.086066) (xy 356.425258 -274.086066) (xy 356.429218 -274.037012) (xy 356.440995 -273.989228)
			(xy 356.460286 -273.943952) (xy 356.486589 -273.902356) (xy 356.519224 -273.865519) (xy 356.557345 -273.834394)
			(xy 356.599966 -273.809787) (xy 356.645982 -273.792335) (xy 356.694201 -273.782491) (xy 356.743376 -273.78051)
			(xy 356.792231 -273.786442) (xy 356.839502 -273.800134) (xy 356.883964 -273.821232) (xy 356.924467 -273.849188)
			(xy 356.95996 -273.88328) (xy 356.989525 -273.922624) (xy 357.012396 -273.966201) (xy 357.02798 -274.012882)
			(xy 357.035875 -274.061459) (xy 357.03637 -274.086066) (xy 357.36582 -274.086066) (xy 357.369774 -274.037093)
			(xy 357.381532 -273.989389) (xy 357.40079 -273.944188) (xy 357.427049 -273.902662) (xy 357.45963 -273.865886)
			(xy 357.497688 -273.834812) (xy 357.540238 -273.810246) (xy 357.586177 -273.792824) (xy 357.634317 -273.782996)
			(xy 357.683409 -273.781018) (xy 357.732183 -273.78694) (xy 357.779375 -273.800609) (xy 357.823764 -273.821672)
			(xy 357.864199 -273.849582) (xy 357.899633 -273.883617) (xy 357.929149 -273.922896) (xy 357.951982 -273.9664)
			(xy 357.967541 -274.013004) (xy 357.975422 -274.0615) (xy 357.975916 -274.086066) (xy 362.058978 -274.086066)
			(xy 362.062938 -274.037012) (xy 362.074715 -273.989228) (xy 362.094006 -273.943952) (xy 362.120309 -273.902356)
			(xy 362.152944 -273.865519) (xy 362.191065 -273.834394) (xy 362.233686 -273.809787) (xy 362.279702 -273.792335)
			(xy 362.327921 -273.782491) (xy 362.377096 -273.78051) (xy 362.425951 -273.786442) (xy 362.473222 -273.800134)
			(xy 362.517684 -273.821232) (xy 362.558187 -273.849188) (xy 362.59368 -273.88328) (xy 362.623245 -273.922624)
			(xy 362.646116 -273.966201) (xy 362.6617 -274.012882) (xy 362.669595 -274.061459) (xy 362.67009 -274.086066)
			(xy 362.99954 -274.086066) (xy 363.003494 -274.037093) (xy 363.015252 -273.989389) (xy 363.03451 -273.944188)
			(xy 363.060769 -273.902662) (xy 363.09335 -273.865886) (xy 363.131408 -273.834812) (xy 363.173958 -273.810246)
			(xy 363.219897 -273.792824) (xy 363.268037 -273.782996) (xy 363.317129 -273.781018) (xy 363.365903 -273.78694)
			(xy 363.413095 -273.800609) (xy 363.457484 -273.821672) (xy 363.497919 -273.849582) (xy 363.533353 -273.883617)
			(xy 363.562869 -273.922896) (xy 363.585702 -273.9664) (xy 363.601261 -274.013004) (xy 363.609142 -274.0615)
			(xy 363.609636 -274.086066) (xy 363.609142 -274.110632) (xy 363.601261 -274.159128) (xy 363.585702 -274.205732)
			(xy 363.562869 -274.249236) (xy 363.533353 -274.288515) (xy 363.497919 -274.32255) (xy 363.457484 -274.35046)
			(xy 363.413095 -274.371523) (xy 363.365903 -274.385192) (xy 363.317129 -274.391114) (xy 363.268037 -274.389136)
			(xy 363.219897 -274.379308) (xy 363.173958 -274.361886) (xy 363.131408 -274.33732) (xy 363.09335 -274.306246)
			(xy 363.060769 -274.26947) (xy 363.03451 -274.227944) (xy 363.015252 -274.182743) (xy 363.003494 -274.135039)
			(xy 362.99954 -274.086066) (xy 362.67009 -274.086066) (xy 362.669595 -274.110673) (xy 362.6617 -274.15925)
			(xy 362.646116 -274.205931) (xy 362.623245 -274.249508) (xy 362.59368 -274.288852) (xy 362.558187 -274.322944)
			(xy 362.517684 -274.3509) (xy 362.473222 -274.371998) (xy 362.425951 -274.38569) (xy 362.377096 -274.391622)
			(xy 362.327921 -274.389641) (xy 362.279702 -274.379797) (xy 362.233686 -274.362345) (xy 362.191065 -274.337738)
			(xy 362.152944 -274.306613) (xy 362.120309 -274.269776) (xy 362.094006 -274.22818) (xy 362.074715 -274.182904)
			(xy 362.062938 -274.13512) (xy 362.058978 -274.086066) (xy 357.975916 -274.086066) (xy 357.975422 -274.110632)
			(xy 357.967541 -274.159128) (xy 357.951982 -274.205732) (xy 357.929149 -274.249236) (xy 357.899633 -274.288515)
			(xy 357.864199 -274.32255) (xy 357.823764 -274.35046) (xy 357.779375 -274.371523) (xy 357.732183 -274.385192)
			(xy 357.683409 -274.391114) (xy 357.634317 -274.389136) (xy 357.586177 -274.379308) (xy 357.540238 -274.361886)
			(xy 357.497688 -274.33732) (xy 357.45963 -274.306246) (xy 357.427049 -274.26947) (xy 357.40079 -274.227944)
			(xy 357.381532 -274.182743) (xy 357.369774 -274.135039) (xy 357.36582 -274.086066) (xy 357.03637 -274.086066)
			(xy 357.035875 -274.110673) (xy 357.02798 -274.15925) (xy 357.012396 -274.205931) (xy 356.989525 -274.249508)
			(xy 356.95996 -274.288852) (xy 356.924467 -274.322944) (xy 356.883964 -274.3509) (xy 356.839502 -274.371998)
			(xy 356.792231 -274.38569) (xy 356.743376 -274.391622) (xy 356.694201 -274.389641) (xy 356.645982 -274.379797)
			(xy 356.599966 -274.362345) (xy 356.557345 -274.337738) (xy 356.519224 -274.306613) (xy 356.486589 -274.269776)
			(xy 356.460286 -274.22818) (xy 356.440995 -274.182904) (xy 356.429218 -274.13512) (xy 356.425258 -274.086066)
			(xy 115.669563 -274.086066) (xy 115.669568 -274.08632) (xy 115.669074 -274.110886) (xy 115.661193 -274.159382)
			(xy 115.645634 -274.205986) (xy 115.622801 -274.24949) (xy 115.593285 -274.288769) (xy 115.557851 -274.322804)
			(xy 115.517416 -274.350714) (xy 115.473027 -274.371777) (xy 115.425835 -274.385446) (xy 115.377061 -274.391368)
			(xy 115.327969 -274.38939) (xy 115.279829 -274.379562) (xy 115.23389 -274.36214) (xy 115.19134 -274.337574)
			(xy 115.153282 -274.3065) (xy 115.120701 -274.269724) (xy 115.094442 -274.228198) (xy 115.075184 -274.182997)
			(xy 115.063426 -274.135293) (xy 115.059472 -274.08632) (xy 114.730022 -274.08632) (xy 114.729527 -274.110927)
			(xy 114.721632 -274.159504) (xy 114.706048 -274.206185) (xy 114.683177 -274.249762) (xy 114.653612 -274.289106)
			(xy 114.618119 -274.323198) (xy 114.577616 -274.351154) (xy 114.533154 -274.372252) (xy 114.485883 -274.385944)
			(xy 114.437028 -274.391876) (xy 114.387853 -274.389895) (xy 114.339634 -274.380051) (xy 114.293618 -274.362599)
			(xy 114.250997 -274.337992) (xy 114.212876 -274.306867) (xy 114.180241 -274.27003) (xy 114.153938 -274.228434)
			(xy 114.134647 -274.183158) (xy 114.12287 -274.135374) (xy 114.11891 -274.08632) (xy 110.035848 -274.08632)
			(xy 110.035354 -274.110886) (xy 110.027473 -274.159382) (xy 110.011914 -274.205986) (xy 109.989081 -274.24949)
			(xy 109.959565 -274.288769) (xy 109.924131 -274.322804) (xy 109.883696 -274.350714) (xy 109.839307 -274.371777)
			(xy 109.792115 -274.385446) (xy 109.743341 -274.391368) (xy 109.694249 -274.38939) (xy 109.646109 -274.379562)
			(xy 109.60017 -274.36214) (xy 109.55762 -274.337574) (xy 109.519562 -274.3065) (xy 109.486981 -274.269724)
			(xy 109.460722 -274.228198) (xy 109.441464 -274.182997) (xy 109.429706 -274.135293) (xy 109.425752 -274.08632)
			(xy 109.096302 -274.08632) (xy 109.095807 -274.110927) (xy 109.087912 -274.159504) (xy 109.072328 -274.206185)
			(xy 109.049457 -274.249762) (xy 109.019892 -274.289106) (xy 108.984399 -274.323198) (xy 108.943896 -274.351154)
			(xy 108.899434 -274.372252) (xy 108.852163 -274.385944) (xy 108.803308 -274.391876) (xy 108.754133 -274.389895)
			(xy 108.705914 -274.380051) (xy 108.659898 -274.362599) (xy 108.617277 -274.337992) (xy 108.579156 -274.306867)
			(xy 108.546521 -274.27003) (xy 108.520218 -274.228434) (xy 108.500927 -274.183158) (xy 108.48915 -274.135374)
			(xy 108.48519 -274.08632) (xy 2.509012 -274.08632) (xy 2.509012 -274.896326) (xy 97.675204 -274.896326)
			(xy 97.679164 -274.847272) (xy 97.690941 -274.799488) (xy 97.710232 -274.754212) (xy 97.736535 -274.712616)
			(xy 97.76917 -274.675779) (xy 97.807291 -274.644654) (xy 97.849912 -274.620047) (xy 97.895928 -274.602595)
			(xy 97.944147 -274.592751) (xy 97.993322 -274.59077) (xy 98.042177 -274.596702) (xy 98.089448 -274.610394)
			(xy 98.13391 -274.631492) (xy 98.174413 -274.659448) (xy 98.209906 -274.69354) (xy 98.239471 -274.732884)
			(xy 98.262342 -274.776461) (xy 98.277926 -274.823142) (xy 98.285821 -274.871719) (xy 98.286316 -274.896326)
			(xy 98.615766 -274.896326) (xy 98.61972 -274.847353) (xy 98.631478 -274.799649) (xy 98.650736 -274.754448)
			(xy 98.676995 -274.712922) (xy 98.709576 -274.676146) (xy 98.747634 -274.645072) (xy 98.790184 -274.620506)
			(xy 98.836123 -274.603084) (xy 98.884263 -274.593256) (xy 98.933355 -274.591278) (xy 98.982129 -274.5972)
			(xy 99.029321 -274.610869) (xy 99.07371 -274.631932) (xy 99.114145 -274.659842) (xy 99.149579 -274.693877)
			(xy 99.179095 -274.733156) (xy 99.201928 -274.77666) (xy 99.217487 -274.823264) (xy 99.225368 -274.87176)
			(xy 99.225862 -274.896326) (xy 100.495112 -274.896326) (xy 100.499072 -274.847272) (xy 100.510849 -274.799488)
			(xy 100.53014 -274.754212) (xy 100.556443 -274.712616) (xy 100.589078 -274.675779) (xy 100.627199 -274.644654)
			(xy 100.66982 -274.620047) (xy 100.715836 -274.602595) (xy 100.764055 -274.592751) (xy 100.81323 -274.59077)
			(xy 100.862085 -274.596702) (xy 100.909356 -274.610394) (xy 100.953818 -274.631492) (xy 100.994321 -274.659448)
			(xy 101.029814 -274.69354) (xy 101.059379 -274.732884) (xy 101.08225 -274.776461) (xy 101.097834 -274.823142)
			(xy 101.105729 -274.871719) (xy 101.106224 -274.896326) (xy 101.435674 -274.896326) (xy 101.439628 -274.847353)
			(xy 101.451386 -274.799649) (xy 101.470644 -274.754448) (xy 101.496903 -274.712922) (xy 101.529484 -274.676146)
			(xy 101.567542 -274.645072) (xy 101.610092 -274.620506) (xy 101.656031 -274.603084) (xy 101.704171 -274.593256)
			(xy 101.753263 -274.591278) (xy 101.802037 -274.5972) (xy 101.849229 -274.610869) (xy 101.893618 -274.631932)
			(xy 101.934053 -274.659842) (xy 101.969487 -274.693877) (xy 101.999003 -274.733156) (xy 102.021836 -274.77666)
			(xy 102.037395 -274.823264) (xy 102.045276 -274.87176) (xy 102.04577 -274.896326) (xy 103.315274 -274.896326)
			(xy 103.319234 -274.847272) (xy 103.331011 -274.799488) (xy 103.350302 -274.754212) (xy 103.376605 -274.712616)
			(xy 103.40924 -274.675779) (xy 103.447361 -274.644654) (xy 103.489982 -274.620047) (xy 103.535998 -274.602595)
			(xy 103.584217 -274.592751) (xy 103.633392 -274.59077) (xy 103.682247 -274.596702) (xy 103.729518 -274.610394)
			(xy 103.77398 -274.631492) (xy 103.814483 -274.659448) (xy 103.849976 -274.69354) (xy 103.879541 -274.732884)
			(xy 103.902412 -274.776461) (xy 103.917996 -274.823142) (xy 103.925891 -274.871719) (xy 103.926386 -274.896326)
			(xy 104.255836 -274.896326) (xy 104.25979 -274.847353) (xy 104.271548 -274.799649) (xy 104.290806 -274.754448)
			(xy 104.317065 -274.712922) (xy 104.349646 -274.676146) (xy 104.387704 -274.645072) (xy 104.430254 -274.620506)
			(xy 104.476193 -274.603084) (xy 104.524333 -274.593256) (xy 104.573425 -274.591278) (xy 104.622199 -274.5972)
			(xy 104.669391 -274.610869) (xy 104.71378 -274.631932) (xy 104.754215 -274.659842) (xy 104.789649 -274.693877)
			(xy 104.819165 -274.733156) (xy 104.841998 -274.77666) (xy 104.857557 -274.823264) (xy 104.865438 -274.87176)
			(xy 104.865932 -274.896326) (xy 106.135182 -274.896326) (xy 106.139142 -274.847272) (xy 106.150919 -274.799488)
			(xy 106.17021 -274.754212) (xy 106.196513 -274.712616) (xy 106.229148 -274.675779) (xy 106.267269 -274.644654)
			(xy 106.30989 -274.620047) (xy 106.355906 -274.602595) (xy 106.404125 -274.592751) (xy 106.4533 -274.59077)
			(xy 106.502155 -274.596702) (xy 106.549426 -274.610394) (xy 106.593888 -274.631492) (xy 106.634391 -274.659448)
			(xy 106.669884 -274.69354) (xy 106.699449 -274.732884) (xy 106.72232 -274.776461) (xy 106.737904 -274.823142)
			(xy 106.745799 -274.871719) (xy 106.746294 -274.896326) (xy 107.075744 -274.896326) (xy 107.079698 -274.847353)
			(xy 107.091456 -274.799649) (xy 107.110714 -274.754448) (xy 107.136973 -274.712922) (xy 107.169554 -274.676146)
			(xy 107.207612 -274.645072) (xy 107.250162 -274.620506) (xy 107.296101 -274.603084) (xy 107.344241 -274.593256)
			(xy 107.393333 -274.591278) (xy 107.442107 -274.5972) (xy 107.489299 -274.610869) (xy 107.533688 -274.631932)
			(xy 107.574123 -274.659842) (xy 107.609557 -274.693877) (xy 107.639073 -274.733156) (xy 107.661906 -274.77666)
			(xy 107.677465 -274.823264) (xy 107.685346 -274.87176) (xy 107.68584 -274.896326) (xy 116.468918 -274.896326)
			(xy 116.472878 -274.847272) (xy 116.484655 -274.799488) (xy 116.503946 -274.754212) (xy 116.530249 -274.712616)
			(xy 116.562884 -274.675779) (xy 116.601005 -274.644654) (xy 116.643626 -274.620047) (xy 116.689642 -274.602595)
			(xy 116.737861 -274.592751) (xy 116.787036 -274.59077) (xy 116.835891 -274.596702) (xy 116.883162 -274.610394)
			(xy 116.927624 -274.631492) (xy 116.968127 -274.659448) (xy 117.00362 -274.69354) (xy 117.033185 -274.732884)
			(xy 117.056056 -274.776461) (xy 117.07164 -274.823142) (xy 117.079535 -274.871719) (xy 117.08003 -274.896326)
			(xy 117.40948 -274.896326) (xy 117.413434 -274.847353) (xy 117.425192 -274.799649) (xy 117.44445 -274.754448)
			(xy 117.470709 -274.712922) (xy 117.50329 -274.676146) (xy 117.541348 -274.645072) (xy 117.583898 -274.620506)
			(xy 117.629837 -274.603084) (xy 117.677977 -274.593256) (xy 117.727069 -274.591278) (xy 117.775843 -274.5972)
			(xy 117.823035 -274.610869) (xy 117.867424 -274.631932) (xy 117.907859 -274.659842) (xy 117.943293 -274.693877)
			(xy 117.972809 -274.733156) (xy 117.995642 -274.77666) (xy 118.011201 -274.823264) (xy 118.019082 -274.87176)
			(xy 118.019576 -274.896326) (xy 119.288826 -274.896326) (xy 119.292786 -274.847272) (xy 119.304563 -274.799488)
			(xy 119.323854 -274.754212) (xy 119.350157 -274.712616) (xy 119.382792 -274.675779) (xy 119.420913 -274.644654)
			(xy 119.463534 -274.620047) (xy 119.50955 -274.602595) (xy 119.557769 -274.592751) (xy 119.606944 -274.59077)
			(xy 119.655799 -274.596702) (xy 119.70307 -274.610394) (xy 119.747532 -274.631492) (xy 119.788035 -274.659448)
			(xy 119.823528 -274.69354) (xy 119.853093 -274.732884) (xy 119.875964 -274.776461) (xy 119.891548 -274.823142)
			(xy 119.899443 -274.871719) (xy 119.899938 -274.896326) (xy 120.229388 -274.896326) (xy 120.233342 -274.847353)
			(xy 120.2451 -274.799649) (xy 120.264358 -274.754448) (xy 120.290617 -274.712922) (xy 120.323198 -274.676146)
			(xy 120.361256 -274.645072) (xy 120.403806 -274.620506) (xy 120.449745 -274.603084) (xy 120.497885 -274.593256)
			(xy 120.546977 -274.591278) (xy 120.595751 -274.5972) (xy 120.642943 -274.610869) (xy 120.687332 -274.631932)
			(xy 120.727767 -274.659842) (xy 120.763201 -274.693877) (xy 120.792717 -274.733156) (xy 120.81555 -274.77666)
			(xy 120.831109 -274.823264) (xy 120.83899 -274.87176) (xy 120.839484 -274.896326) (xy 122.108988 -274.896326)
			(xy 122.112948 -274.847272) (xy 122.124725 -274.799488) (xy 122.144016 -274.754212) (xy 122.170319 -274.712616)
			(xy 122.202954 -274.675779) (xy 122.241075 -274.644654) (xy 122.283696 -274.620047) (xy 122.329712 -274.602595)
			(xy 122.377931 -274.592751) (xy 122.427106 -274.59077) (xy 122.475961 -274.596702) (xy 122.523232 -274.610394)
			(xy 122.567694 -274.631492) (xy 122.608197 -274.659448) (xy 122.64369 -274.69354) (xy 122.673255 -274.732884)
			(xy 122.696126 -274.776461) (xy 122.71171 -274.823142) (xy 122.719605 -274.871719) (xy 122.7201 -274.896326)
			(xy 123.04955 -274.896326) (xy 123.053504 -274.847353) (xy 123.065262 -274.799649) (xy 123.08452 -274.754448)
			(xy 123.110779 -274.712922) (xy 123.14336 -274.676146) (xy 123.181418 -274.645072) (xy 123.223968 -274.620506)
			(xy 123.269907 -274.603084) (xy 123.318047 -274.593256) (xy 123.367139 -274.591278) (xy 123.415913 -274.5972)
			(xy 123.463105 -274.610869) (xy 123.507494 -274.631932) (xy 123.547929 -274.659842) (xy 123.583363 -274.693877)
			(xy 123.612879 -274.733156) (xy 123.635712 -274.77666) (xy 123.651271 -274.823264) (xy 123.659152 -274.87176)
			(xy 123.659646 -274.896326) (xy 124.928896 -274.896326) (xy 124.932856 -274.847272) (xy 124.944633 -274.799488)
			(xy 124.963924 -274.754212) (xy 124.990227 -274.712616) (xy 125.022862 -274.675779) (xy 125.060983 -274.644654)
			(xy 125.103604 -274.620047) (xy 125.14962 -274.602595) (xy 125.197839 -274.592751) (xy 125.247014 -274.59077)
			(xy 125.295869 -274.596702) (xy 125.34314 -274.610394) (xy 125.387602 -274.631492) (xy 125.428105 -274.659448)
			(xy 125.463598 -274.69354) (xy 125.493163 -274.732884) (xy 125.516034 -274.776461) (xy 125.531618 -274.823142)
			(xy 125.539513 -274.871719) (xy 125.540008 -274.896326) (xy 125.869458 -274.896326) (xy 125.873412 -274.847353)
			(xy 125.88517 -274.799649) (xy 125.904428 -274.754448) (xy 125.930687 -274.712922) (xy 125.963268 -274.676146)
			(xy 126.001326 -274.645072) (xy 126.043876 -274.620506) (xy 126.089815 -274.603084) (xy 126.137955 -274.593256)
			(xy 126.187047 -274.591278) (xy 126.235821 -274.5972) (xy 126.283013 -274.610869) (xy 126.327402 -274.631932)
			(xy 126.367837 -274.659842) (xy 126.403271 -274.693877) (xy 126.432787 -274.733156) (xy 126.45562 -274.77666)
			(xy 126.471179 -274.823264) (xy 126.47906 -274.87176) (xy 126.479549 -274.896072) (xy 345.615272 -274.896072)
			(xy 345.619232 -274.847018) (xy 345.631009 -274.799234) (xy 345.6503 -274.753958) (xy 345.676603 -274.712362)
			(xy 345.709238 -274.675525) (xy 345.747359 -274.6444) (xy 345.78998 -274.619793) (xy 345.835996 -274.602341)
			(xy 345.884215 -274.592497) (xy 345.93339 -274.590516) (xy 345.982245 -274.596448) (xy 346.029516 -274.61014)
			(xy 346.073978 -274.631238) (xy 346.114481 -274.659194) (xy 346.149974 -274.693286) (xy 346.179539 -274.73263)
			(xy 346.20241 -274.776207) (xy 346.217994 -274.822888) (xy 346.225889 -274.871465) (xy 346.226384 -274.896072)
			(xy 346.555834 -274.896072) (xy 346.559788 -274.847099) (xy 346.571546 -274.799395) (xy 346.590804 -274.754194)
			(xy 346.617063 -274.712668) (xy 346.649644 -274.675892) (xy 346.687702 -274.644818) (xy 346.730252 -274.620252)
			(xy 346.776191 -274.60283) (xy 346.824331 -274.593002) (xy 346.873423 -274.591024) (xy 346.922197 -274.596946)
			(xy 346.969389 -274.610615) (xy 347.013778 -274.631678) (xy 347.054213 -274.659588) (xy 347.089647 -274.693623)
			(xy 347.119163 -274.732902) (xy 347.141996 -274.776406) (xy 347.157555 -274.82301) (xy 347.165436 -274.871506)
			(xy 347.16593 -274.896072) (xy 348.43518 -274.896072) (xy 348.43914 -274.847018) (xy 348.450917 -274.799234)
			(xy 348.470208 -274.753958) (xy 348.496511 -274.712362) (xy 348.529146 -274.675525) (xy 348.567267 -274.6444)
			(xy 348.609888 -274.619793) (xy 348.655904 -274.602341) (xy 348.704123 -274.592497) (xy 348.753298 -274.590516)
			(xy 348.802153 -274.596448) (xy 348.849424 -274.61014) (xy 348.893886 -274.631238) (xy 348.934389 -274.659194)
			(xy 348.969882 -274.693286) (xy 348.999447 -274.73263) (xy 349.022318 -274.776207) (xy 349.037902 -274.822888)
			(xy 349.045797 -274.871465) (xy 349.046292 -274.896072) (xy 349.375742 -274.896072) (xy 349.379696 -274.847099)
			(xy 349.391454 -274.799395) (xy 349.410712 -274.754194) (xy 349.436971 -274.712668) (xy 349.469552 -274.675892)
			(xy 349.50761 -274.644818) (xy 349.55016 -274.620252) (xy 349.596099 -274.60283) (xy 349.644239 -274.593002)
			(xy 349.693331 -274.591024) (xy 349.742105 -274.596946) (xy 349.789297 -274.610615) (xy 349.833686 -274.631678)
			(xy 349.874121 -274.659588) (xy 349.909555 -274.693623) (xy 349.939071 -274.732902) (xy 349.961904 -274.776406)
			(xy 349.977463 -274.82301) (xy 349.985344 -274.871506) (xy 349.985838 -274.896072) (xy 351.255342 -274.896072)
			(xy 351.259302 -274.847018) (xy 351.271079 -274.799234) (xy 351.29037 -274.753958) (xy 351.316673 -274.712362)
			(xy 351.349308 -274.675525) (xy 351.387429 -274.6444) (xy 351.43005 -274.619793) (xy 351.476066 -274.602341)
			(xy 351.524285 -274.592497) (xy 351.57346 -274.590516) (xy 351.622315 -274.596448) (xy 351.669586 -274.61014)
			(xy 351.714048 -274.631238) (xy 351.754551 -274.659194) (xy 351.790044 -274.693286) (xy 351.819609 -274.73263)
			(xy 351.84248 -274.776207) (xy 351.858064 -274.822888) (xy 351.865959 -274.871465) (xy 351.866454 -274.896072)
			(xy 352.195904 -274.896072) (xy 352.199858 -274.847099) (xy 352.211616 -274.799395) (xy 352.230874 -274.754194)
			(xy 352.257133 -274.712668) (xy 352.289714 -274.675892) (xy 352.327772 -274.644818) (xy 352.370322 -274.620252)
			(xy 352.416261 -274.60283) (xy 352.464401 -274.593002) (xy 352.513493 -274.591024) (xy 352.562267 -274.596946)
			(xy 352.609459 -274.610615) (xy 352.653848 -274.631678) (xy 352.694283 -274.659588) (xy 352.729717 -274.693623)
			(xy 352.759233 -274.732902) (xy 352.782066 -274.776406) (xy 352.797625 -274.82301) (xy 352.805506 -274.871506)
			(xy 352.806 -274.896072) (xy 354.07525 -274.896072) (xy 354.07921 -274.847018) (xy 354.090987 -274.799234)
			(xy 354.110278 -274.753958) (xy 354.136581 -274.712362) (xy 354.169216 -274.675525) (xy 354.207337 -274.6444)
			(xy 354.249958 -274.619793) (xy 354.295974 -274.602341) (xy 354.344193 -274.592497) (xy 354.393368 -274.590516)
			(xy 354.442223 -274.596448) (xy 354.489494 -274.61014) (xy 354.533956 -274.631238) (xy 354.574459 -274.659194)
			(xy 354.609952 -274.693286) (xy 354.639517 -274.73263) (xy 354.662388 -274.776207) (xy 354.677972 -274.822888)
			(xy 354.685867 -274.871465) (xy 354.686362 -274.896072) (xy 355.015812 -274.896072) (xy 355.019766 -274.847099)
			(xy 355.031524 -274.799395) (xy 355.050782 -274.754194) (xy 355.077041 -274.712668) (xy 355.109622 -274.675892)
			(xy 355.14768 -274.644818) (xy 355.19023 -274.620252) (xy 355.236169 -274.60283) (xy 355.284309 -274.593002)
			(xy 355.333401 -274.591024) (xy 355.382175 -274.596946) (xy 355.429367 -274.610615) (xy 355.473756 -274.631678)
			(xy 355.514191 -274.659588) (xy 355.549625 -274.693623) (xy 355.579141 -274.732902) (xy 355.601974 -274.776406)
			(xy 355.617533 -274.82301) (xy 355.625414 -274.871506) (xy 355.625908 -274.896072) (xy 364.408986 -274.896072)
			(xy 364.412946 -274.847018) (xy 364.424723 -274.799234) (xy 364.444014 -274.753958) (xy 364.470317 -274.712362)
			(xy 364.502952 -274.675525) (xy 364.541073 -274.6444) (xy 364.583694 -274.619793) (xy 364.62971 -274.602341)
			(xy 364.677929 -274.592497) (xy 364.727104 -274.590516) (xy 364.775959 -274.596448) (xy 364.82323 -274.61014)
			(xy 364.867692 -274.631238) (xy 364.908195 -274.659194) (xy 364.943688 -274.693286) (xy 364.973253 -274.73263)
			(xy 364.996124 -274.776207) (xy 365.011708 -274.822888) (xy 365.019603 -274.871465) (xy 365.020098 -274.896072)
			(xy 365.349548 -274.896072) (xy 365.353502 -274.847099) (xy 365.36526 -274.799395) (xy 365.384518 -274.754194)
			(xy 365.410777 -274.712668) (xy 365.443358 -274.675892) (xy 365.481416 -274.644818) (xy 365.523966 -274.620252)
			(xy 365.569905 -274.60283) (xy 365.618045 -274.593002) (xy 365.667137 -274.591024) (xy 365.715911 -274.596946)
			(xy 365.763103 -274.610615) (xy 365.807492 -274.631678) (xy 365.847927 -274.659588) (xy 365.883361 -274.693623)
			(xy 365.912877 -274.732902) (xy 365.93571 -274.776406) (xy 365.951269 -274.82301) (xy 365.95915 -274.871506)
			(xy 365.959644 -274.896072) (xy 367.228894 -274.896072) (xy 367.232854 -274.847018) (xy 367.244631 -274.799234)
			(xy 367.263922 -274.753958) (xy 367.290225 -274.712362) (xy 367.32286 -274.675525) (xy 367.360981 -274.6444)
			(xy 367.403602 -274.619793) (xy 367.449618 -274.602341) (xy 367.497837 -274.592497) (xy 367.547012 -274.590516)
			(xy 367.595867 -274.596448) (xy 367.643138 -274.61014) (xy 367.6876 -274.631238) (xy 367.728103 -274.659194)
			(xy 367.763596 -274.693286) (xy 367.793161 -274.73263) (xy 367.816032 -274.776207) (xy 367.831616 -274.822888)
			(xy 367.839511 -274.871465) (xy 367.840006 -274.896072) (xy 368.169456 -274.896072) (xy 368.17341 -274.847099)
			(xy 368.185168 -274.799395) (xy 368.204426 -274.754194) (xy 368.230685 -274.712668) (xy 368.263266 -274.675892)
			(xy 368.301324 -274.644818) (xy 368.343874 -274.620252) (xy 368.389813 -274.60283) (xy 368.437953 -274.593002)
			(xy 368.487045 -274.591024) (xy 368.535819 -274.596946) (xy 368.583011 -274.610615) (xy 368.6274 -274.631678)
			(xy 368.667835 -274.659588) (xy 368.703269 -274.693623) (xy 368.732785 -274.732902) (xy 368.755618 -274.776406)
			(xy 368.771177 -274.82301) (xy 368.779058 -274.871506) (xy 368.779552 -274.896072) (xy 370.049056 -274.896072)
			(xy 370.053016 -274.847018) (xy 370.064793 -274.799234) (xy 370.084084 -274.753958) (xy 370.110387 -274.712362)
			(xy 370.143022 -274.675525) (xy 370.181143 -274.6444) (xy 370.223764 -274.619793) (xy 370.26978 -274.602341)
			(xy 370.317999 -274.592497) (xy 370.367174 -274.590516) (xy 370.416029 -274.596448) (xy 370.4633 -274.61014)
			(xy 370.507762 -274.631238) (xy 370.548265 -274.659194) (xy 370.583758 -274.693286) (xy 370.613323 -274.73263)
			(xy 370.636194 -274.776207) (xy 370.651778 -274.822888) (xy 370.659673 -274.871465) (xy 370.660168 -274.896072)
			(xy 370.989618 -274.896072) (xy 370.993572 -274.847099) (xy 371.00533 -274.799395) (xy 371.024588 -274.754194)
			(xy 371.050847 -274.712668) (xy 371.083428 -274.675892) (xy 371.121486 -274.644818) (xy 371.164036 -274.620252)
			(xy 371.209975 -274.60283) (xy 371.258115 -274.593002) (xy 371.307207 -274.591024) (xy 371.355981 -274.596946)
			(xy 371.403173 -274.610615) (xy 371.447562 -274.631678) (xy 371.487997 -274.659588) (xy 371.523431 -274.693623)
			(xy 371.552947 -274.732902) (xy 371.57578 -274.776406) (xy 371.591339 -274.82301) (xy 371.59922 -274.871506)
			(xy 371.599714 -274.896072) (xy 372.868964 -274.896072) (xy 372.872924 -274.847018) (xy 372.884701 -274.799234)
			(xy 372.903992 -274.753958) (xy 372.930295 -274.712362) (xy 372.96293 -274.675525) (xy 373.001051 -274.6444)
			(xy 373.043672 -274.619793) (xy 373.089688 -274.602341) (xy 373.137907 -274.592497) (xy 373.187082 -274.590516)
			(xy 373.235937 -274.596448) (xy 373.283208 -274.61014) (xy 373.32767 -274.631238) (xy 373.368173 -274.659194)
			(xy 373.403666 -274.693286) (xy 373.433231 -274.73263) (xy 373.456102 -274.776207) (xy 373.471686 -274.822888)
			(xy 373.479581 -274.871465) (xy 373.480076 -274.896072) (xy 373.809526 -274.896072) (xy 373.81348 -274.847099)
			(xy 373.825238 -274.799395) (xy 373.844496 -274.754194) (xy 373.870755 -274.712668) (xy 373.903336 -274.675892)
			(xy 373.941394 -274.644818) (xy 373.983944 -274.620252) (xy 374.029883 -274.60283) (xy 374.078023 -274.593002)
			(xy 374.127115 -274.591024) (xy 374.175889 -274.596946) (xy 374.223081 -274.610615) (xy 374.26747 -274.631678)
			(xy 374.307905 -274.659588) (xy 374.343339 -274.693623) (xy 374.372855 -274.732902) (xy 374.395688 -274.776406)
			(xy 374.411247 -274.82301) (xy 374.419128 -274.871506) (xy 374.419622 -274.896072) (xy 374.419128 -274.920638)
			(xy 374.411247 -274.969134) (xy 374.395688 -275.015738) (xy 374.372855 -275.059242) (xy 374.343339 -275.098521)
			(xy 374.307905 -275.132556) (xy 374.26747 -275.160466) (xy 374.223081 -275.181529) (xy 374.175889 -275.195198)
			(xy 374.127115 -275.20112) (xy 374.078023 -275.199142) (xy 374.029883 -275.189314) (xy 373.983944 -275.171892)
			(xy 373.941394 -275.147326) (xy 373.903336 -275.116252) (xy 373.870755 -275.079476) (xy 373.844496 -275.03795)
			(xy 373.825238 -274.992749) (xy 373.81348 -274.945045) (xy 373.809526 -274.896072) (xy 373.480076 -274.896072)
			(xy 373.479581 -274.920679) (xy 373.471686 -274.969256) (xy 373.456102 -275.015937) (xy 373.433231 -275.059514)
			(xy 373.403666 -275.098858) (xy 373.368173 -275.13295) (xy 373.32767 -275.160906) (xy 373.283208 -275.182004)
			(xy 373.235937 -275.195696) (xy 373.187082 -275.201628) (xy 373.137907 -275.199647) (xy 373.089688 -275.189803)
			(xy 373.043672 -275.172351) (xy 373.001051 -275.147744) (xy 372.96293 -275.116619) (xy 372.930295 -275.079782)
			(xy 372.903992 -275.038186) (xy 372.884701 -274.99291) (xy 372.872924 -274.945126) (xy 372.868964 -274.896072)
			(xy 371.599714 -274.896072) (xy 371.59922 -274.920638) (xy 371.591339 -274.969134) (xy 371.57578 -275.015738)
			(xy 371.552947 -275.059242) (xy 371.523431 -275.098521) (xy 371.487997 -275.132556) (xy 371.447562 -275.160466)
			(xy 371.403173 -275.181529) (xy 371.355981 -275.195198) (xy 371.307207 -275.20112) (xy 371.258115 -275.199142)
			(xy 371.209975 -275.189314) (xy 371.164036 -275.171892) (xy 371.121486 -275.147326) (xy 371.083428 -275.116252)
			(xy 371.050847 -275.079476) (xy 371.024588 -275.03795) (xy 371.00533 -274.992749) (xy 370.993572 -274.945045)
			(xy 370.989618 -274.896072) (xy 370.660168 -274.896072) (xy 370.659673 -274.920679) (xy 370.651778 -274.969256)
			(xy 370.636194 -275.015937) (xy 370.613323 -275.059514) (xy 370.583758 -275.098858) (xy 370.548265 -275.13295)
			(xy 370.507762 -275.160906) (xy 370.4633 -275.182004) (xy 370.416029 -275.195696) (xy 370.367174 -275.201628)
			(xy 370.317999 -275.199647) (xy 370.26978 -275.189803) (xy 370.223764 -275.172351) (xy 370.181143 -275.147744)
			(xy 370.143022 -275.116619) (xy 370.110387 -275.079782) (xy 370.084084 -275.038186) (xy 370.064793 -274.99291)
			(xy 370.053016 -274.945126) (xy 370.049056 -274.896072) (xy 368.779552 -274.896072) (xy 368.779058 -274.920638)
			(xy 368.771177 -274.969134) (xy 368.755618 -275.015738) (xy 368.732785 -275.059242) (xy 368.703269 -275.098521)
			(xy 368.667835 -275.132556) (xy 368.6274 -275.160466) (xy 368.583011 -275.181529) (xy 368.535819 -275.195198)
			(xy 368.487045 -275.20112) (xy 368.437953 -275.199142) (xy 368.389813 -275.189314) (xy 368.343874 -275.171892)
			(xy 368.301324 -275.147326) (xy 368.263266 -275.116252) (xy 368.230685 -275.079476) (xy 368.204426 -275.03795)
			(xy 368.185168 -274.992749) (xy 368.17341 -274.945045) (xy 368.169456 -274.896072) (xy 367.840006 -274.896072)
			(xy 367.839511 -274.920679) (xy 367.831616 -274.969256) (xy 367.816032 -275.015937) (xy 367.793161 -275.059514)
			(xy 367.763596 -275.098858) (xy 367.728103 -275.13295) (xy 367.6876 -275.160906) (xy 367.643138 -275.182004)
			(xy 367.595867 -275.195696) (xy 367.547012 -275.201628) (xy 367.497837 -275.199647) (xy 367.449618 -275.189803)
			(xy 367.403602 -275.172351) (xy 367.360981 -275.147744) (xy 367.32286 -275.116619) (xy 367.290225 -275.079782)
			(xy 367.263922 -275.038186) (xy 367.244631 -274.99291) (xy 367.232854 -274.945126) (xy 367.228894 -274.896072)
			(xy 365.959644 -274.896072) (xy 365.95915 -274.920638) (xy 365.951269 -274.969134) (xy 365.93571 -275.015738)
			(xy 365.912877 -275.059242) (xy 365.883361 -275.098521) (xy 365.847927 -275.132556) (xy 365.807492 -275.160466)
			(xy 365.763103 -275.181529) (xy 365.715911 -275.195198) (xy 365.667137 -275.20112) (xy 365.618045 -275.199142)
			(xy 365.569905 -275.189314) (xy 365.523966 -275.171892) (xy 365.481416 -275.147326) (xy 365.443358 -275.116252)
			(xy 365.410777 -275.079476) (xy 365.384518 -275.03795) (xy 365.36526 -274.992749) (xy 365.353502 -274.945045)
			(xy 365.349548 -274.896072) (xy 365.020098 -274.896072) (xy 365.019603 -274.920679) (xy 365.011708 -274.969256)
			(xy 364.996124 -275.015937) (xy 364.973253 -275.059514) (xy 364.943688 -275.098858) (xy 364.908195 -275.13295)
			(xy 364.867692 -275.160906) (xy 364.82323 -275.182004) (xy 364.775959 -275.195696) (xy 364.727104 -275.201628)
			(xy 364.677929 -275.199647) (xy 364.62971 -275.189803) (xy 364.583694 -275.172351) (xy 364.541073 -275.147744)
			(xy 364.502952 -275.116619) (xy 364.470317 -275.079782) (xy 364.444014 -275.038186) (xy 364.424723 -274.99291)
			(xy 364.412946 -274.945126) (xy 364.408986 -274.896072) (xy 355.625908 -274.896072) (xy 355.625414 -274.920638)
			(xy 355.617533 -274.969134) (xy 355.601974 -275.015738) (xy 355.579141 -275.059242) (xy 355.549625 -275.098521)
			(xy 355.514191 -275.132556) (xy 355.473756 -275.160466) (xy 355.429367 -275.181529) (xy 355.382175 -275.195198)
			(xy 355.333401 -275.20112) (xy 355.284309 -275.199142) (xy 355.236169 -275.189314) (xy 355.19023 -275.171892)
			(xy 355.14768 -275.147326) (xy 355.109622 -275.116252) (xy 355.077041 -275.079476) (xy 355.050782 -275.03795)
			(xy 355.031524 -274.992749) (xy 355.019766 -274.945045) (xy 355.015812 -274.896072) (xy 354.686362 -274.896072)
			(xy 354.685867 -274.920679) (xy 354.677972 -274.969256) (xy 354.662388 -275.015937) (xy 354.639517 -275.059514)
			(xy 354.609952 -275.098858) (xy 354.574459 -275.13295) (xy 354.533956 -275.160906) (xy 354.489494 -275.182004)
			(xy 354.442223 -275.195696) (xy 354.393368 -275.201628) (xy 354.344193 -275.199647) (xy 354.295974 -275.189803)
			(xy 354.249958 -275.172351) (xy 354.207337 -275.147744) (xy 354.169216 -275.116619) (xy 354.136581 -275.079782)
			(xy 354.110278 -275.038186) (xy 354.090987 -274.99291) (xy 354.07921 -274.945126) (xy 354.07525 -274.896072)
			(xy 352.806 -274.896072) (xy 352.805506 -274.920638) (xy 352.797625 -274.969134) (xy 352.782066 -275.015738)
			(xy 352.759233 -275.059242) (xy 352.729717 -275.098521) (xy 352.694283 -275.132556) (xy 352.653848 -275.160466)
			(xy 352.609459 -275.181529) (xy 352.562267 -275.195198) (xy 352.513493 -275.20112) (xy 352.464401 -275.199142)
			(xy 352.416261 -275.189314) (xy 352.370322 -275.171892) (xy 352.327772 -275.147326) (xy 352.289714 -275.116252)
			(xy 352.257133 -275.079476) (xy 352.230874 -275.03795) (xy 352.211616 -274.992749) (xy 352.199858 -274.945045)
			(xy 352.195904 -274.896072) (xy 351.866454 -274.896072) (xy 351.865959 -274.920679) (xy 351.858064 -274.969256)
			(xy 351.84248 -275.015937) (xy 351.819609 -275.059514) (xy 351.790044 -275.098858) (xy 351.754551 -275.13295)
			(xy 351.714048 -275.160906) (xy 351.669586 -275.182004) (xy 351.622315 -275.195696) (xy 351.57346 -275.201628)
			(xy 351.524285 -275.199647) (xy 351.476066 -275.189803) (xy 351.43005 -275.172351) (xy 351.387429 -275.147744)
			(xy 351.349308 -275.116619) (xy 351.316673 -275.079782) (xy 351.29037 -275.038186) (xy 351.271079 -274.99291)
			(xy 351.259302 -274.945126) (xy 351.255342 -274.896072) (xy 349.985838 -274.896072) (xy 349.985344 -274.920638)
			(xy 349.977463 -274.969134) (xy 349.961904 -275.015738) (xy 349.939071 -275.059242) (xy 349.909555 -275.098521)
			(xy 349.874121 -275.132556) (xy 349.833686 -275.160466) (xy 349.789297 -275.181529) (xy 349.742105 -275.195198)
			(xy 349.693331 -275.20112) (xy 349.644239 -275.199142) (xy 349.596099 -275.189314) (xy 349.55016 -275.171892)
			(xy 349.50761 -275.147326) (xy 349.469552 -275.116252) (xy 349.436971 -275.079476) (xy 349.410712 -275.03795)
			(xy 349.391454 -274.992749) (xy 349.379696 -274.945045) (xy 349.375742 -274.896072) (xy 349.046292 -274.896072)
			(xy 349.045797 -274.920679) (xy 349.037902 -274.969256) (xy 349.022318 -275.015937) (xy 348.999447 -275.059514)
			(xy 348.969882 -275.098858) (xy 348.934389 -275.13295) (xy 348.893886 -275.160906) (xy 348.849424 -275.182004)
			(xy 348.802153 -275.195696) (xy 348.753298 -275.201628) (xy 348.704123 -275.199647) (xy 348.655904 -275.189803)
			(xy 348.609888 -275.172351) (xy 348.567267 -275.147744) (xy 348.529146 -275.116619) (xy 348.496511 -275.079782)
			(xy 348.470208 -275.038186) (xy 348.450917 -274.99291) (xy 348.43914 -274.945126) (xy 348.43518 -274.896072)
			(xy 347.16593 -274.896072) (xy 347.165436 -274.920638) (xy 347.157555 -274.969134) (xy 347.141996 -275.015738)
			(xy 347.119163 -275.059242) (xy 347.089647 -275.098521) (xy 347.054213 -275.132556) (xy 347.013778 -275.160466)
			(xy 346.969389 -275.181529) (xy 346.922197 -275.195198) (xy 346.873423 -275.20112) (xy 346.824331 -275.199142)
			(xy 346.776191 -275.189314) (xy 346.730252 -275.171892) (xy 346.687702 -275.147326) (xy 346.649644 -275.116252)
			(xy 346.617063 -275.079476) (xy 346.590804 -275.03795) (xy 346.571546 -274.992749) (xy 346.559788 -274.945045)
			(xy 346.555834 -274.896072) (xy 346.226384 -274.896072) (xy 346.225889 -274.920679) (xy 346.217994 -274.969256)
			(xy 346.20241 -275.015937) (xy 346.179539 -275.059514) (xy 346.149974 -275.098858) (xy 346.114481 -275.13295)
			(xy 346.073978 -275.160906) (xy 346.029516 -275.182004) (xy 345.982245 -275.195696) (xy 345.93339 -275.201628)
			(xy 345.884215 -275.199647) (xy 345.835996 -275.189803) (xy 345.78998 -275.172351) (xy 345.747359 -275.147744)
			(xy 345.709238 -275.116619) (xy 345.676603 -275.079782) (xy 345.6503 -275.038186) (xy 345.631009 -274.99291)
			(xy 345.619232 -274.945126) (xy 345.615272 -274.896072) (xy 126.479549 -274.896072) (xy 126.479554 -274.896326)
			(xy 126.47906 -274.920892) (xy 126.471179 -274.969388) (xy 126.45562 -275.015992) (xy 126.432787 -275.059496)
			(xy 126.403271 -275.098775) (xy 126.367837 -275.13281) (xy 126.327402 -275.16072) (xy 126.283013 -275.181783)
			(xy 126.235821 -275.195452) (xy 126.187047 -275.201374) (xy 126.137955 -275.199396) (xy 126.089815 -275.189568)
			(xy 126.043876 -275.172146) (xy 126.001326 -275.14758) (xy 125.963268 -275.116506) (xy 125.930687 -275.07973)
			(xy 125.904428 -275.038204) (xy 125.88517 -274.993003) (xy 125.873412 -274.945299) (xy 125.869458 -274.896326)
			(xy 125.540008 -274.896326) (xy 125.539513 -274.920933) (xy 125.531618 -274.96951) (xy 125.516034 -275.016191)
			(xy 125.493163 -275.059768) (xy 125.463598 -275.099112) (xy 125.428105 -275.133204) (xy 125.387602 -275.16116)
			(xy 125.34314 -275.182258) (xy 125.295869 -275.19595) (xy 125.247014 -275.201882) (xy 125.197839 -275.199901)
			(xy 125.14962 -275.190057) (xy 125.103604 -275.172605) (xy 125.060983 -275.147998) (xy 125.022862 -275.116873)
			(xy 124.990227 -275.080036) (xy 124.963924 -275.03844) (xy 124.944633 -274.993164) (xy 124.932856 -274.94538)
			(xy 124.928896 -274.896326) (xy 123.659646 -274.896326) (xy 123.659152 -274.920892) (xy 123.651271 -274.969388)
			(xy 123.635712 -275.015992) (xy 123.612879 -275.059496) (xy 123.583363 -275.098775) (xy 123.547929 -275.13281)
			(xy 123.507494 -275.16072) (xy 123.463105 -275.181783) (xy 123.415913 -275.195452) (xy 123.367139 -275.201374)
			(xy 123.318047 -275.199396) (xy 123.269907 -275.189568) (xy 123.223968 -275.172146) (xy 123.181418 -275.14758)
			(xy 123.14336 -275.116506) (xy 123.110779 -275.07973) (xy 123.08452 -275.038204) (xy 123.065262 -274.993003)
			(xy 123.053504 -274.945299) (xy 123.04955 -274.896326) (xy 122.7201 -274.896326) (xy 122.719605 -274.920933)
			(xy 122.71171 -274.96951) (xy 122.696126 -275.016191) (xy 122.673255 -275.059768) (xy 122.64369 -275.099112)
			(xy 122.608197 -275.133204) (xy 122.567694 -275.16116) (xy 122.523232 -275.182258) (xy 122.475961 -275.19595)
			(xy 122.427106 -275.201882) (xy 122.377931 -275.199901) (xy 122.329712 -275.190057) (xy 122.283696 -275.172605)
			(xy 122.241075 -275.147998) (xy 122.202954 -275.116873) (xy 122.170319 -275.080036) (xy 122.144016 -275.03844)
			(xy 122.124725 -274.993164) (xy 122.112948 -274.94538) (xy 122.108988 -274.896326) (xy 120.839484 -274.896326)
			(xy 120.83899 -274.920892) (xy 120.831109 -274.969388) (xy 120.81555 -275.015992) (xy 120.792717 -275.059496)
			(xy 120.763201 -275.098775) (xy 120.727767 -275.13281) (xy 120.687332 -275.16072) (xy 120.642943 -275.181783)
			(xy 120.595751 -275.195452) (xy 120.546977 -275.201374) (xy 120.497885 -275.199396) (xy 120.449745 -275.189568)
			(xy 120.403806 -275.172146) (xy 120.361256 -275.14758) (xy 120.323198 -275.116506) (xy 120.290617 -275.07973)
			(xy 120.264358 -275.038204) (xy 120.2451 -274.993003) (xy 120.233342 -274.945299) (xy 120.229388 -274.896326)
			(xy 119.899938 -274.896326) (xy 119.899443 -274.920933) (xy 119.891548 -274.96951) (xy 119.875964 -275.016191)
			(xy 119.853093 -275.059768) (xy 119.823528 -275.099112) (xy 119.788035 -275.133204) (xy 119.747532 -275.16116)
			(xy 119.70307 -275.182258) (xy 119.655799 -275.19595) (xy 119.606944 -275.201882) (xy 119.557769 -275.199901)
			(xy 119.50955 -275.190057) (xy 119.463534 -275.172605) (xy 119.420913 -275.147998) (xy 119.382792 -275.116873)
			(xy 119.350157 -275.080036) (xy 119.323854 -275.03844) (xy 119.304563 -274.993164) (xy 119.292786 -274.94538)
			(xy 119.288826 -274.896326) (xy 118.019576 -274.896326) (xy 118.019082 -274.920892) (xy 118.011201 -274.969388)
			(xy 117.995642 -275.015992) (xy 117.972809 -275.059496) (xy 117.943293 -275.098775) (xy 117.907859 -275.13281)
			(xy 117.867424 -275.16072) (xy 117.823035 -275.181783) (xy 117.775843 -275.195452) (xy 117.727069 -275.201374)
			(xy 117.677977 -275.199396) (xy 117.629837 -275.189568) (xy 117.583898 -275.172146) (xy 117.541348 -275.14758)
			(xy 117.50329 -275.116506) (xy 117.470709 -275.07973) (xy 117.44445 -275.038204) (xy 117.425192 -274.993003)
			(xy 117.413434 -274.945299) (xy 117.40948 -274.896326) (xy 117.08003 -274.896326) (xy 117.079535 -274.920933)
			(xy 117.07164 -274.96951) (xy 117.056056 -275.016191) (xy 117.033185 -275.059768) (xy 117.00362 -275.099112)
			(xy 116.968127 -275.133204) (xy 116.927624 -275.16116) (xy 116.883162 -275.182258) (xy 116.835891 -275.19595)
			(xy 116.787036 -275.201882) (xy 116.737861 -275.199901) (xy 116.689642 -275.190057) (xy 116.643626 -275.172605)
			(xy 116.601005 -275.147998) (xy 116.562884 -275.116873) (xy 116.530249 -275.080036) (xy 116.503946 -275.03844)
			(xy 116.484655 -274.993164) (xy 116.472878 -274.94538) (xy 116.468918 -274.896326) (xy 107.68584 -274.896326)
			(xy 107.685346 -274.920892) (xy 107.677465 -274.969388) (xy 107.661906 -275.015992) (xy 107.639073 -275.059496)
			(xy 107.609557 -275.098775) (xy 107.574123 -275.13281) (xy 107.533688 -275.16072) (xy 107.489299 -275.181783)
			(xy 107.442107 -275.195452) (xy 107.393333 -275.201374) (xy 107.344241 -275.199396) (xy 107.296101 -275.189568)
			(xy 107.250162 -275.172146) (xy 107.207612 -275.14758) (xy 107.169554 -275.116506) (xy 107.136973 -275.07973)
			(xy 107.110714 -275.038204) (xy 107.091456 -274.993003) (xy 107.079698 -274.945299) (xy 107.075744 -274.896326)
			(xy 106.746294 -274.896326) (xy 106.745799 -274.920933) (xy 106.737904 -274.96951) (xy 106.72232 -275.016191)
			(xy 106.699449 -275.059768) (xy 106.669884 -275.099112) (xy 106.634391 -275.133204) (xy 106.593888 -275.16116)
			(xy 106.549426 -275.182258) (xy 106.502155 -275.19595) (xy 106.4533 -275.201882) (xy 106.404125 -275.199901)
			(xy 106.355906 -275.190057) (xy 106.30989 -275.172605) (xy 106.267269 -275.147998) (xy 106.229148 -275.116873)
			(xy 106.196513 -275.080036) (xy 106.17021 -275.03844) (xy 106.150919 -274.993164) (xy 106.139142 -274.94538)
			(xy 106.135182 -274.896326) (xy 104.865932 -274.896326) (xy 104.865438 -274.920892) (xy 104.857557 -274.969388)
			(xy 104.841998 -275.015992) (xy 104.819165 -275.059496) (xy 104.789649 -275.098775) (xy 104.754215 -275.13281)
			(xy 104.71378 -275.16072) (xy 104.669391 -275.181783) (xy 104.622199 -275.195452) (xy 104.573425 -275.201374)
			(xy 104.524333 -275.199396) (xy 104.476193 -275.189568) (xy 104.430254 -275.172146) (xy 104.387704 -275.14758)
			(xy 104.349646 -275.116506) (xy 104.317065 -275.07973) (xy 104.290806 -275.038204) (xy 104.271548 -274.993003)
			(xy 104.25979 -274.945299) (xy 104.255836 -274.896326) (xy 103.926386 -274.896326) (xy 103.925891 -274.920933)
			(xy 103.917996 -274.96951) (xy 103.902412 -275.016191) (xy 103.879541 -275.059768) (xy 103.849976 -275.099112)
			(xy 103.814483 -275.133204) (xy 103.77398 -275.16116) (xy 103.729518 -275.182258) (xy 103.682247 -275.19595)
			(xy 103.633392 -275.201882) (xy 103.584217 -275.199901) (xy 103.535998 -275.190057) (xy 103.489982 -275.172605)
			(xy 103.447361 -275.147998) (xy 103.40924 -275.116873) (xy 103.376605 -275.080036) (xy 103.350302 -275.03844)
			(xy 103.331011 -274.993164) (xy 103.319234 -274.94538) (xy 103.315274 -274.896326) (xy 102.04577 -274.896326)
			(xy 102.045276 -274.920892) (xy 102.037395 -274.969388) (xy 102.021836 -275.015992) (xy 101.999003 -275.059496)
			(xy 101.969487 -275.098775) (xy 101.934053 -275.13281) (xy 101.893618 -275.16072) (xy 101.849229 -275.181783)
			(xy 101.802037 -275.195452) (xy 101.753263 -275.201374) (xy 101.704171 -275.199396) (xy 101.656031 -275.189568)
			(xy 101.610092 -275.172146) (xy 101.567542 -275.14758) (xy 101.529484 -275.116506) (xy 101.496903 -275.07973)
			(xy 101.470644 -275.038204) (xy 101.451386 -274.993003) (xy 101.439628 -274.945299) (xy 101.435674 -274.896326)
			(xy 101.106224 -274.896326) (xy 101.105729 -274.920933) (xy 101.097834 -274.96951) (xy 101.08225 -275.016191)
			(xy 101.059379 -275.059768) (xy 101.029814 -275.099112) (xy 100.994321 -275.133204) (xy 100.953818 -275.16116)
			(xy 100.909356 -275.182258) (xy 100.862085 -275.19595) (xy 100.81323 -275.201882) (xy 100.764055 -275.199901)
			(xy 100.715836 -275.190057) (xy 100.66982 -275.172605) (xy 100.627199 -275.147998) (xy 100.589078 -275.116873)
			(xy 100.556443 -275.080036) (xy 100.53014 -275.03844) (xy 100.510849 -274.993164) (xy 100.499072 -274.94538)
			(xy 100.495112 -274.896326) (xy 99.225862 -274.896326) (xy 99.225368 -274.920892) (xy 99.217487 -274.969388)
			(xy 99.201928 -275.015992) (xy 99.179095 -275.059496) (xy 99.149579 -275.098775) (xy 99.114145 -275.13281)
			(xy 99.07371 -275.16072) (xy 99.029321 -275.181783) (xy 98.982129 -275.195452) (xy 98.933355 -275.201374)
			(xy 98.884263 -275.199396) (xy 98.836123 -275.189568) (xy 98.790184 -275.172146) (xy 98.747634 -275.14758)
			(xy 98.709576 -275.116506) (xy 98.676995 -275.07973) (xy 98.650736 -275.038204) (xy 98.631478 -274.993003)
			(xy 98.61972 -274.945299) (xy 98.615766 -274.896326) (xy 98.286316 -274.896326) (xy 98.285821 -274.920933)
			(xy 98.277926 -274.96951) (xy 98.262342 -275.016191) (xy 98.239471 -275.059768) (xy 98.209906 -275.099112)
			(xy 98.174413 -275.133204) (xy 98.13391 -275.16116) (xy 98.089448 -275.182258) (xy 98.042177 -275.19595)
			(xy 97.993322 -275.201882) (xy 97.944147 -275.199901) (xy 97.895928 -275.190057) (xy 97.849912 -275.172605)
			(xy 97.807291 -275.147998) (xy 97.76917 -275.116873) (xy 97.736535 -275.080036) (xy 97.710232 -275.03844)
			(xy 97.690941 -274.993164) (xy 97.679164 -274.94538) (xy 97.675204 -274.896326) (xy 2.509012 -274.896326)
			(xy 2.509012 -275.706332) (xy 108.48519 -275.706332) (xy 108.48915 -275.657278) (xy 108.500927 -275.609494)
			(xy 108.520218 -275.564218) (xy 108.546521 -275.522622) (xy 108.579156 -275.485785) (xy 108.617277 -275.45466)
			(xy 108.659898 -275.430053) (xy 108.705914 -275.412601) (xy 108.754133 -275.402757) (xy 108.803308 -275.400776)
			(xy 108.852163 -275.406708) (xy 108.899434 -275.4204) (xy 108.943896 -275.441498) (xy 108.984399 -275.469454)
			(xy 109.019892 -275.503546) (xy 109.049457 -275.54289) (xy 109.072328 -275.586467) (xy 109.087912 -275.633148)
			(xy 109.095807 -275.681725) (xy 109.096302 -275.706332) (xy 109.425752 -275.706332) (xy 109.429706 -275.657359)
			(xy 109.441464 -275.609655) (xy 109.460722 -275.564454) (xy 109.486981 -275.522928) (xy 109.519562 -275.486152)
			(xy 109.55762 -275.455078) (xy 109.60017 -275.430512) (xy 109.646109 -275.41309) (xy 109.694249 -275.403262)
			(xy 109.743341 -275.401284) (xy 109.792115 -275.407206) (xy 109.839307 -275.420875) (xy 109.883696 -275.441938)
			(xy 109.924131 -275.469848) (xy 109.959565 -275.503883) (xy 109.989081 -275.543162) (xy 110.011914 -275.586666)
			(xy 110.027473 -275.63327) (xy 110.035354 -275.681766) (xy 110.035848 -275.706332) (xy 114.11891 -275.706332)
			(xy 114.12287 -275.657278) (xy 114.134647 -275.609494) (xy 114.153938 -275.564218) (xy 114.180241 -275.522622)
			(xy 114.212876 -275.485785) (xy 114.250997 -275.45466) (xy 114.293618 -275.430053) (xy 114.339634 -275.412601)
			(xy 114.387853 -275.402757) (xy 114.437028 -275.400776) (xy 114.485883 -275.406708) (xy 114.533154 -275.4204)
			(xy 114.577616 -275.441498) (xy 114.618119 -275.469454) (xy 114.653612 -275.503546) (xy 114.683177 -275.54289)
			(xy 114.706048 -275.586467) (xy 114.721632 -275.633148) (xy 114.729527 -275.681725) (xy 114.730022 -275.706332)
			(xy 115.059472 -275.706332) (xy 115.063426 -275.657359) (xy 115.075184 -275.609655) (xy 115.094442 -275.564454)
			(xy 115.120701 -275.522928) (xy 115.153282 -275.486152) (xy 115.19134 -275.455078) (xy 115.23389 -275.430512)
			(xy 115.279829 -275.41309) (xy 115.327969 -275.403262) (xy 115.377061 -275.401284) (xy 115.425835 -275.407206)
			(xy 115.473027 -275.420875) (xy 115.517416 -275.441938) (xy 115.557851 -275.469848) (xy 115.593285 -275.503883)
			(xy 115.622801 -275.543162) (xy 115.645634 -275.586666) (xy 115.661193 -275.63327) (xy 115.669074 -275.681766)
			(xy 115.669563 -275.706078) (xy 356.425258 -275.706078) (xy 356.429218 -275.657024) (xy 356.440995 -275.60924)
			(xy 356.460286 -275.563964) (xy 356.486589 -275.522368) (xy 356.519224 -275.485531) (xy 356.557345 -275.454406)
			(xy 356.599966 -275.429799) (xy 356.645982 -275.412347) (xy 356.694201 -275.402503) (xy 356.743376 -275.400522)
			(xy 356.792231 -275.406454) (xy 356.839502 -275.420146) (xy 356.883964 -275.441244) (xy 356.924467 -275.4692)
			(xy 356.95996 -275.503292) (xy 356.989525 -275.542636) (xy 357.012396 -275.586213) (xy 357.02798 -275.632894)
			(xy 357.035875 -275.681471) (xy 357.03637 -275.706078) (xy 357.36582 -275.706078) (xy 357.369774 -275.657105)
			(xy 357.381532 -275.609401) (xy 357.40079 -275.5642) (xy 357.427049 -275.522674) (xy 357.45963 -275.485898)
			(xy 357.497688 -275.454824) (xy 357.540238 -275.430258) (xy 357.586177 -275.412836) (xy 357.634317 -275.403008)
			(xy 357.683409 -275.40103) (xy 357.732183 -275.406952) (xy 357.779375 -275.420621) (xy 357.823764 -275.441684)
			(xy 357.864199 -275.469594) (xy 357.899633 -275.503629) (xy 357.929149 -275.542908) (xy 357.951982 -275.586412)
			(xy 357.967541 -275.633016) (xy 357.975422 -275.681512) (xy 357.975916 -275.706078) (xy 362.058978 -275.706078)
			(xy 362.062938 -275.657024) (xy 362.074715 -275.60924) (xy 362.094006 -275.563964) (xy 362.120309 -275.522368)
			(xy 362.152944 -275.485531) (xy 362.191065 -275.454406) (xy 362.233686 -275.429799) (xy 362.279702 -275.412347)
			(xy 362.327921 -275.402503) (xy 362.377096 -275.400522) (xy 362.425951 -275.406454) (xy 362.473222 -275.420146)
			(xy 362.517684 -275.441244) (xy 362.558187 -275.4692) (xy 362.59368 -275.503292) (xy 362.623245 -275.542636)
			(xy 362.646116 -275.586213) (xy 362.6617 -275.632894) (xy 362.669595 -275.681471) (xy 362.67009 -275.706078)
			(xy 362.99954 -275.706078) (xy 363.003494 -275.657105) (xy 363.015252 -275.609401) (xy 363.03451 -275.5642)
			(xy 363.060769 -275.522674) (xy 363.09335 -275.485898) (xy 363.131408 -275.454824) (xy 363.173958 -275.430258)
			(xy 363.219897 -275.412836) (xy 363.268037 -275.403008) (xy 363.317129 -275.40103) (xy 363.365903 -275.406952)
			(xy 363.413095 -275.420621) (xy 363.457484 -275.441684) (xy 363.497919 -275.469594) (xy 363.533353 -275.503629)
			(xy 363.562869 -275.542908) (xy 363.585702 -275.586412) (xy 363.601261 -275.633016) (xy 363.609142 -275.681512)
			(xy 363.609636 -275.706078) (xy 363.609142 -275.730644) (xy 363.601261 -275.77914) (xy 363.585702 -275.825744)
			(xy 363.562869 -275.869248) (xy 363.533353 -275.908527) (xy 363.497919 -275.942562) (xy 363.457484 -275.970472)
			(xy 363.413095 -275.991535) (xy 363.365903 -276.005204) (xy 363.317129 -276.011126) (xy 363.268037 -276.009148)
			(xy 363.219897 -275.99932) (xy 363.173958 -275.981898) (xy 363.131408 -275.957332) (xy 363.09335 -275.926258)
			(xy 363.060769 -275.889482) (xy 363.03451 -275.847956) (xy 363.015252 -275.802755) (xy 363.003494 -275.755051)
			(xy 362.99954 -275.706078) (xy 362.67009 -275.706078) (xy 362.669595 -275.730685) (xy 362.6617 -275.779262)
			(xy 362.646116 -275.825943) (xy 362.623245 -275.86952) (xy 362.59368 -275.908864) (xy 362.558187 -275.942956)
			(xy 362.517684 -275.970912) (xy 362.473222 -275.99201) (xy 362.425951 -276.005702) (xy 362.377096 -276.011634)
			(xy 362.327921 -276.009653) (xy 362.279702 -275.999809) (xy 362.233686 -275.982357) (xy 362.191065 -275.95775)
			(xy 362.152944 -275.926625) (xy 362.120309 -275.889788) (xy 362.094006 -275.848192) (xy 362.074715 -275.802916)
			(xy 362.062938 -275.755132) (xy 362.058978 -275.706078) (xy 357.975916 -275.706078) (xy 357.975422 -275.730644)
			(xy 357.967541 -275.77914) (xy 357.951982 -275.825744) (xy 357.929149 -275.869248) (xy 357.899633 -275.908527)
			(xy 357.864199 -275.942562) (xy 357.823764 -275.970472) (xy 357.779375 -275.991535) (xy 357.732183 -276.005204)
			(xy 357.683409 -276.011126) (xy 357.634317 -276.009148) (xy 357.586177 -275.99932) (xy 357.540238 -275.981898)
			(xy 357.497688 -275.957332) (xy 357.45963 -275.926258) (xy 357.427049 -275.889482) (xy 357.40079 -275.847956)
			(xy 357.381532 -275.802755) (xy 357.369774 -275.755051) (xy 357.36582 -275.706078) (xy 357.03637 -275.706078)
			(xy 357.035875 -275.730685) (xy 357.02798 -275.779262) (xy 357.012396 -275.825943) (xy 356.989525 -275.86952)
			(xy 356.95996 -275.908864) (xy 356.924467 -275.942956) (xy 356.883964 -275.970912) (xy 356.839502 -275.99201)
			(xy 356.792231 -276.005702) (xy 356.743376 -276.011634) (xy 356.694201 -276.009653) (xy 356.645982 -275.999809)
			(xy 356.599966 -275.982357) (xy 356.557345 -275.95775) (xy 356.519224 -275.926625) (xy 356.486589 -275.889788)
			(xy 356.460286 -275.848192) (xy 356.440995 -275.802916) (xy 356.429218 -275.755132) (xy 356.425258 -275.706078)
			(xy 115.669563 -275.706078) (xy 115.669568 -275.706332) (xy 115.669074 -275.730898) (xy 115.661193 -275.779394)
			(xy 115.645634 -275.825998) (xy 115.622801 -275.869502) (xy 115.593285 -275.908781) (xy 115.557851 -275.942816)
			(xy 115.517416 -275.970726) (xy 115.473027 -275.991789) (xy 115.425835 -276.005458) (xy 115.377061 -276.01138)
			(xy 115.327969 -276.009402) (xy 115.279829 -275.999574) (xy 115.23389 -275.982152) (xy 115.19134 -275.957586)
			(xy 115.153282 -275.926512) (xy 115.120701 -275.889736) (xy 115.094442 -275.84821) (xy 115.075184 -275.803009)
			(xy 115.063426 -275.755305) (xy 115.059472 -275.706332) (xy 114.730022 -275.706332) (xy 114.729527 -275.730939)
			(xy 114.721632 -275.779516) (xy 114.706048 -275.826197) (xy 114.683177 -275.869774) (xy 114.653612 -275.909118)
			(xy 114.618119 -275.94321) (xy 114.577616 -275.971166) (xy 114.533154 -275.992264) (xy 114.485883 -276.005956)
			(xy 114.437028 -276.011888) (xy 114.387853 -276.009907) (xy 114.339634 -276.000063) (xy 114.293618 -275.982611)
			(xy 114.250997 -275.958004) (xy 114.212876 -275.926879) (xy 114.180241 -275.890042) (xy 114.153938 -275.848446)
			(xy 114.134647 -275.80317) (xy 114.12287 -275.755386) (xy 114.11891 -275.706332) (xy 110.035848 -275.706332)
			(xy 110.035354 -275.730898) (xy 110.027473 -275.779394) (xy 110.011914 -275.825998) (xy 109.989081 -275.869502)
			(xy 109.959565 -275.908781) (xy 109.924131 -275.942816) (xy 109.883696 -275.970726) (xy 109.839307 -275.991789)
			(xy 109.792115 -276.005458) (xy 109.743341 -276.01138) (xy 109.694249 -276.009402) (xy 109.646109 -275.999574)
			(xy 109.60017 -275.982152) (xy 109.55762 -275.957586) (xy 109.519562 -275.926512) (xy 109.486981 -275.889736)
			(xy 109.460722 -275.84821) (xy 109.441464 -275.803009) (xy 109.429706 -275.755305) (xy 109.425752 -275.706332)
			(xy 109.096302 -275.706332) (xy 109.095807 -275.730939) (xy 109.087912 -275.779516) (xy 109.072328 -275.826197)
			(xy 109.049457 -275.869774) (xy 109.019892 -275.909118) (xy 108.984399 -275.94321) (xy 108.943896 -275.971166)
			(xy 108.899434 -275.992264) (xy 108.852163 -276.005956) (xy 108.803308 -276.011888) (xy 108.754133 -276.009907)
			(xy 108.705914 -276.000063) (xy 108.659898 -275.982611) (xy 108.617277 -275.958004) (xy 108.579156 -275.926879)
			(xy 108.546521 -275.890042) (xy 108.520218 -275.848446) (xy 108.500927 -275.80317) (xy 108.48915 -275.755386)
			(xy 108.48519 -275.706332) (xy 2.509012 -275.706332) (xy 2.509012 -276.516338) (xy 97.675204 -276.516338)
			(xy 97.679164 -276.467284) (xy 97.690941 -276.4195) (xy 97.710232 -276.374224) (xy 97.736535 -276.332628)
			(xy 97.76917 -276.295791) (xy 97.807291 -276.264666) (xy 97.849912 -276.240059) (xy 97.895928 -276.222607)
			(xy 97.944147 -276.212763) (xy 97.993322 -276.210782) (xy 98.042177 -276.216714) (xy 98.089448 -276.230406)
			(xy 98.13391 -276.251504) (xy 98.174413 -276.27946) (xy 98.209906 -276.313552) (xy 98.239471 -276.352896)
			(xy 98.262342 -276.396473) (xy 98.277926 -276.443154) (xy 98.285821 -276.491731) (xy 98.286316 -276.516338)
			(xy 98.615766 -276.516338) (xy 98.61972 -276.467365) (xy 98.631478 -276.419661) (xy 98.650736 -276.37446)
			(xy 98.676995 -276.332934) (xy 98.709576 -276.296158) (xy 98.747634 -276.265084) (xy 98.790184 -276.240518)
			(xy 98.836123 -276.223096) (xy 98.884263 -276.213268) (xy 98.933355 -276.21129) (xy 98.982129 -276.217212)
			(xy 99.029321 -276.230881) (xy 99.07371 -276.251944) (xy 99.114145 -276.279854) (xy 99.149579 -276.313889)
			(xy 99.179095 -276.353168) (xy 99.201928 -276.396672) (xy 99.217487 -276.443276) (xy 99.225368 -276.491772)
			(xy 99.225862 -276.516338) (xy 100.495112 -276.516338) (xy 100.499072 -276.467284) (xy 100.510849 -276.4195)
			(xy 100.53014 -276.374224) (xy 100.556443 -276.332628) (xy 100.589078 -276.295791) (xy 100.627199 -276.264666)
			(xy 100.66982 -276.240059) (xy 100.715836 -276.222607) (xy 100.764055 -276.212763) (xy 100.81323 -276.210782)
			(xy 100.862085 -276.216714) (xy 100.909356 -276.230406) (xy 100.953818 -276.251504) (xy 100.994321 -276.27946)
			(xy 101.029814 -276.313552) (xy 101.059379 -276.352896) (xy 101.08225 -276.396473) (xy 101.097834 -276.443154)
			(xy 101.105729 -276.491731) (xy 101.106224 -276.516338) (xy 101.435674 -276.516338) (xy 101.439628 -276.467365)
			(xy 101.451386 -276.419661) (xy 101.470644 -276.37446) (xy 101.496903 -276.332934) (xy 101.529484 -276.296158)
			(xy 101.567542 -276.265084) (xy 101.610092 -276.240518) (xy 101.656031 -276.223096) (xy 101.704171 -276.213268)
			(xy 101.753263 -276.21129) (xy 101.802037 -276.217212) (xy 101.849229 -276.230881) (xy 101.893618 -276.251944)
			(xy 101.934053 -276.279854) (xy 101.969487 -276.313889) (xy 101.999003 -276.353168) (xy 102.021836 -276.396672)
			(xy 102.037395 -276.443276) (xy 102.045276 -276.491772) (xy 102.04577 -276.516338) (xy 103.315274 -276.516338)
			(xy 103.319234 -276.467284) (xy 103.331011 -276.4195) (xy 103.350302 -276.374224) (xy 103.376605 -276.332628)
			(xy 103.40924 -276.295791) (xy 103.447361 -276.264666) (xy 103.489982 -276.240059) (xy 103.535998 -276.222607)
			(xy 103.584217 -276.212763) (xy 103.633392 -276.210782) (xy 103.682247 -276.216714) (xy 103.729518 -276.230406)
			(xy 103.77398 -276.251504) (xy 103.814483 -276.27946) (xy 103.849976 -276.313552) (xy 103.879541 -276.352896)
			(xy 103.902412 -276.396473) (xy 103.917996 -276.443154) (xy 103.925891 -276.491731) (xy 103.926386 -276.516338)
			(xy 104.255836 -276.516338) (xy 104.25979 -276.467365) (xy 104.271548 -276.419661) (xy 104.290806 -276.37446)
			(xy 104.317065 -276.332934) (xy 104.349646 -276.296158) (xy 104.387704 -276.265084) (xy 104.430254 -276.240518)
			(xy 104.476193 -276.223096) (xy 104.524333 -276.213268) (xy 104.573425 -276.21129) (xy 104.622199 -276.217212)
			(xy 104.669391 -276.230881) (xy 104.71378 -276.251944) (xy 104.754215 -276.279854) (xy 104.789649 -276.313889)
			(xy 104.819165 -276.353168) (xy 104.841998 -276.396672) (xy 104.857557 -276.443276) (xy 104.865438 -276.491772)
			(xy 104.865932 -276.516338) (xy 106.135182 -276.516338) (xy 106.139142 -276.467284) (xy 106.150919 -276.4195)
			(xy 106.17021 -276.374224) (xy 106.196513 -276.332628) (xy 106.229148 -276.295791) (xy 106.267269 -276.264666)
			(xy 106.30989 -276.240059) (xy 106.355906 -276.222607) (xy 106.404125 -276.212763) (xy 106.4533 -276.210782)
			(xy 106.502155 -276.216714) (xy 106.549426 -276.230406) (xy 106.593888 -276.251504) (xy 106.634391 -276.27946)
			(xy 106.669884 -276.313552) (xy 106.699449 -276.352896) (xy 106.72232 -276.396473) (xy 106.737904 -276.443154)
			(xy 106.745799 -276.491731) (xy 106.746294 -276.516338) (xy 107.075744 -276.516338) (xy 107.079698 -276.467365)
			(xy 107.091456 -276.419661) (xy 107.110714 -276.37446) (xy 107.136973 -276.332934) (xy 107.169554 -276.296158)
			(xy 107.207612 -276.265084) (xy 107.250162 -276.240518) (xy 107.296101 -276.223096) (xy 107.344241 -276.213268)
			(xy 107.393333 -276.21129) (xy 107.442107 -276.217212) (xy 107.489299 -276.230881) (xy 107.533688 -276.251944)
			(xy 107.574123 -276.279854) (xy 107.609557 -276.313889) (xy 107.639073 -276.353168) (xy 107.661906 -276.396672)
			(xy 107.677465 -276.443276) (xy 107.685346 -276.491772) (xy 107.68584 -276.516338) (xy 116.468918 -276.516338)
			(xy 116.472878 -276.467284) (xy 116.484655 -276.4195) (xy 116.503946 -276.374224) (xy 116.530249 -276.332628)
			(xy 116.562884 -276.295791) (xy 116.601005 -276.264666) (xy 116.643626 -276.240059) (xy 116.689642 -276.222607)
			(xy 116.737861 -276.212763) (xy 116.787036 -276.210782) (xy 116.835891 -276.216714) (xy 116.883162 -276.230406)
			(xy 116.927624 -276.251504) (xy 116.968127 -276.27946) (xy 117.00362 -276.313552) (xy 117.033185 -276.352896)
			(xy 117.056056 -276.396473) (xy 117.07164 -276.443154) (xy 117.079535 -276.491731) (xy 117.08003 -276.516338)
			(xy 117.40948 -276.516338) (xy 117.413434 -276.467365) (xy 117.425192 -276.419661) (xy 117.44445 -276.37446)
			(xy 117.470709 -276.332934) (xy 117.50329 -276.296158) (xy 117.541348 -276.265084) (xy 117.583898 -276.240518)
			(xy 117.629837 -276.223096) (xy 117.677977 -276.213268) (xy 117.727069 -276.21129) (xy 117.775843 -276.217212)
			(xy 117.823035 -276.230881) (xy 117.867424 -276.251944) (xy 117.907859 -276.279854) (xy 117.943293 -276.313889)
			(xy 117.972809 -276.353168) (xy 117.995642 -276.396672) (xy 118.011201 -276.443276) (xy 118.019082 -276.491772)
			(xy 118.019576 -276.516338) (xy 119.288826 -276.516338) (xy 119.292786 -276.467284) (xy 119.304563 -276.4195)
			(xy 119.323854 -276.374224) (xy 119.350157 -276.332628) (xy 119.382792 -276.295791) (xy 119.420913 -276.264666)
			(xy 119.463534 -276.240059) (xy 119.50955 -276.222607) (xy 119.557769 -276.212763) (xy 119.606944 -276.210782)
			(xy 119.655799 -276.216714) (xy 119.70307 -276.230406) (xy 119.747532 -276.251504) (xy 119.788035 -276.27946)
			(xy 119.823528 -276.313552) (xy 119.853093 -276.352896) (xy 119.875964 -276.396473) (xy 119.891548 -276.443154)
			(xy 119.899443 -276.491731) (xy 119.899938 -276.516338) (xy 120.229388 -276.516338) (xy 120.233342 -276.467365)
			(xy 120.2451 -276.419661) (xy 120.264358 -276.37446) (xy 120.290617 -276.332934) (xy 120.323198 -276.296158)
			(xy 120.361256 -276.265084) (xy 120.403806 -276.240518) (xy 120.449745 -276.223096) (xy 120.497885 -276.213268)
			(xy 120.546977 -276.21129) (xy 120.595751 -276.217212) (xy 120.642943 -276.230881) (xy 120.687332 -276.251944)
			(xy 120.727767 -276.279854) (xy 120.763201 -276.313889) (xy 120.792717 -276.353168) (xy 120.81555 -276.396672)
			(xy 120.831109 -276.443276) (xy 120.83899 -276.491772) (xy 120.839484 -276.516338) (xy 122.108988 -276.516338)
			(xy 122.112948 -276.467284) (xy 122.124725 -276.4195) (xy 122.144016 -276.374224) (xy 122.170319 -276.332628)
			(xy 122.202954 -276.295791) (xy 122.241075 -276.264666) (xy 122.283696 -276.240059) (xy 122.329712 -276.222607)
			(xy 122.377931 -276.212763) (xy 122.427106 -276.210782) (xy 122.475961 -276.216714) (xy 122.523232 -276.230406)
			(xy 122.567694 -276.251504) (xy 122.608197 -276.27946) (xy 122.64369 -276.313552) (xy 122.673255 -276.352896)
			(xy 122.696126 -276.396473) (xy 122.71171 -276.443154) (xy 122.719605 -276.491731) (xy 122.7201 -276.516338)
			(xy 123.04955 -276.516338) (xy 123.053504 -276.467365) (xy 123.065262 -276.419661) (xy 123.08452 -276.37446)
			(xy 123.110779 -276.332934) (xy 123.14336 -276.296158) (xy 123.181418 -276.265084) (xy 123.223968 -276.240518)
			(xy 123.269907 -276.223096) (xy 123.318047 -276.213268) (xy 123.367139 -276.21129) (xy 123.415913 -276.217212)
			(xy 123.463105 -276.230881) (xy 123.507494 -276.251944) (xy 123.547929 -276.279854) (xy 123.583363 -276.313889)
			(xy 123.612879 -276.353168) (xy 123.635712 -276.396672) (xy 123.651271 -276.443276) (xy 123.659152 -276.491772)
			(xy 123.659646 -276.516338) (xy 124.928896 -276.516338) (xy 124.932856 -276.467284) (xy 124.944633 -276.4195)
			(xy 124.963924 -276.374224) (xy 124.990227 -276.332628) (xy 125.022862 -276.295791) (xy 125.060983 -276.264666)
			(xy 125.103604 -276.240059) (xy 125.14962 -276.222607) (xy 125.197839 -276.212763) (xy 125.247014 -276.210782)
			(xy 125.295869 -276.216714) (xy 125.34314 -276.230406) (xy 125.387602 -276.251504) (xy 125.428105 -276.27946)
			(xy 125.463598 -276.313552) (xy 125.493163 -276.352896) (xy 125.516034 -276.396473) (xy 125.531618 -276.443154)
			(xy 125.539513 -276.491731) (xy 125.540008 -276.516338) (xy 125.869458 -276.516338) (xy 125.873412 -276.467365)
			(xy 125.88517 -276.419661) (xy 125.904428 -276.37446) (xy 125.930687 -276.332934) (xy 125.963268 -276.296158)
			(xy 126.001326 -276.265084) (xy 126.043876 -276.240518) (xy 126.089815 -276.223096) (xy 126.137955 -276.213268)
			(xy 126.187047 -276.21129) (xy 126.235821 -276.217212) (xy 126.283013 -276.230881) (xy 126.327402 -276.251944)
			(xy 126.367837 -276.279854) (xy 126.403271 -276.313889) (xy 126.432787 -276.353168) (xy 126.45562 -276.396672)
			(xy 126.471179 -276.443276) (xy 126.47906 -276.491772) (xy 126.479549 -276.516084) (xy 345.615272 -276.516084)
			(xy 345.619232 -276.46703) (xy 345.631009 -276.419246) (xy 345.6503 -276.37397) (xy 345.676603 -276.332374)
			(xy 345.709238 -276.295537) (xy 345.747359 -276.264412) (xy 345.78998 -276.239805) (xy 345.835996 -276.222353)
			(xy 345.884215 -276.212509) (xy 345.93339 -276.210528) (xy 345.982245 -276.21646) (xy 346.029516 -276.230152)
			(xy 346.073978 -276.25125) (xy 346.114481 -276.279206) (xy 346.149974 -276.313298) (xy 346.179539 -276.352642)
			(xy 346.20241 -276.396219) (xy 346.217994 -276.4429) (xy 346.225889 -276.491477) (xy 346.226384 -276.516084)
			(xy 346.555834 -276.516084) (xy 346.559788 -276.467111) (xy 346.571546 -276.419407) (xy 346.590804 -276.374206)
			(xy 346.617063 -276.33268) (xy 346.649644 -276.295904) (xy 346.687702 -276.26483) (xy 346.730252 -276.240264)
			(xy 346.776191 -276.222842) (xy 346.824331 -276.213014) (xy 346.873423 -276.211036) (xy 346.922197 -276.216958)
			(xy 346.969389 -276.230627) (xy 347.013778 -276.25169) (xy 347.054213 -276.2796) (xy 347.089647 -276.313635)
			(xy 347.119163 -276.352914) (xy 347.141996 -276.396418) (xy 347.157555 -276.443022) (xy 347.165436 -276.491518)
			(xy 347.16593 -276.516084) (xy 348.43518 -276.516084) (xy 348.43914 -276.46703) (xy 348.450917 -276.419246)
			(xy 348.470208 -276.37397) (xy 348.496511 -276.332374) (xy 348.529146 -276.295537) (xy 348.567267 -276.264412)
			(xy 348.609888 -276.239805) (xy 348.655904 -276.222353) (xy 348.704123 -276.212509) (xy 348.753298 -276.210528)
			(xy 348.802153 -276.21646) (xy 348.849424 -276.230152) (xy 348.893886 -276.25125) (xy 348.934389 -276.279206)
			(xy 348.969882 -276.313298) (xy 348.999447 -276.352642) (xy 349.022318 -276.396219) (xy 349.037902 -276.4429)
			(xy 349.045797 -276.491477) (xy 349.046292 -276.516084) (xy 349.375742 -276.516084) (xy 349.379696 -276.467111)
			(xy 349.391454 -276.419407) (xy 349.410712 -276.374206) (xy 349.436971 -276.33268) (xy 349.469552 -276.295904)
			(xy 349.50761 -276.26483) (xy 349.55016 -276.240264) (xy 349.596099 -276.222842) (xy 349.644239 -276.213014)
			(xy 349.693331 -276.211036) (xy 349.742105 -276.216958) (xy 349.789297 -276.230627) (xy 349.833686 -276.25169)
			(xy 349.874121 -276.2796) (xy 349.909555 -276.313635) (xy 349.939071 -276.352914) (xy 349.961904 -276.396418)
			(xy 349.977463 -276.443022) (xy 349.985344 -276.491518) (xy 349.985838 -276.516084) (xy 351.255342 -276.516084)
			(xy 351.259302 -276.46703) (xy 351.271079 -276.419246) (xy 351.29037 -276.37397) (xy 351.316673 -276.332374)
			(xy 351.349308 -276.295537) (xy 351.387429 -276.264412) (xy 351.43005 -276.239805) (xy 351.476066 -276.222353)
			(xy 351.524285 -276.212509) (xy 351.57346 -276.210528) (xy 351.622315 -276.21646) (xy 351.669586 -276.230152)
			(xy 351.714048 -276.25125) (xy 351.754551 -276.279206) (xy 351.790044 -276.313298) (xy 351.819609 -276.352642)
			(xy 351.84248 -276.396219) (xy 351.858064 -276.4429) (xy 351.865959 -276.491477) (xy 351.866454 -276.516084)
			(xy 352.195904 -276.516084) (xy 352.199858 -276.467111) (xy 352.211616 -276.419407) (xy 352.230874 -276.374206)
			(xy 352.257133 -276.33268) (xy 352.289714 -276.295904) (xy 352.327772 -276.26483) (xy 352.370322 -276.240264)
			(xy 352.416261 -276.222842) (xy 352.464401 -276.213014) (xy 352.513493 -276.211036) (xy 352.562267 -276.216958)
			(xy 352.609459 -276.230627) (xy 352.653848 -276.25169) (xy 352.694283 -276.2796) (xy 352.729717 -276.313635)
			(xy 352.759233 -276.352914) (xy 352.782066 -276.396418) (xy 352.797625 -276.443022) (xy 352.805506 -276.491518)
			(xy 352.806 -276.516084) (xy 354.07525 -276.516084) (xy 354.07921 -276.46703) (xy 354.090987 -276.419246)
			(xy 354.110278 -276.37397) (xy 354.136581 -276.332374) (xy 354.169216 -276.295537) (xy 354.207337 -276.264412)
			(xy 354.249958 -276.239805) (xy 354.295974 -276.222353) (xy 354.344193 -276.212509) (xy 354.393368 -276.210528)
			(xy 354.442223 -276.21646) (xy 354.489494 -276.230152) (xy 354.533956 -276.25125) (xy 354.574459 -276.279206)
			(xy 354.609952 -276.313298) (xy 354.639517 -276.352642) (xy 354.662388 -276.396219) (xy 354.677972 -276.4429)
			(xy 354.685867 -276.491477) (xy 354.686362 -276.516084) (xy 355.015812 -276.516084) (xy 355.019766 -276.467111)
			(xy 355.031524 -276.419407) (xy 355.050782 -276.374206) (xy 355.077041 -276.33268) (xy 355.109622 -276.295904)
			(xy 355.14768 -276.26483) (xy 355.19023 -276.240264) (xy 355.236169 -276.222842) (xy 355.284309 -276.213014)
			(xy 355.333401 -276.211036) (xy 355.382175 -276.216958) (xy 355.429367 -276.230627) (xy 355.473756 -276.25169)
			(xy 355.514191 -276.2796) (xy 355.549625 -276.313635) (xy 355.579141 -276.352914) (xy 355.601974 -276.396418)
			(xy 355.617533 -276.443022) (xy 355.625414 -276.491518) (xy 355.625908 -276.516084) (xy 364.408986 -276.516084)
			(xy 364.412946 -276.46703) (xy 364.424723 -276.419246) (xy 364.444014 -276.37397) (xy 364.470317 -276.332374)
			(xy 364.502952 -276.295537) (xy 364.541073 -276.264412) (xy 364.583694 -276.239805) (xy 364.62971 -276.222353)
			(xy 364.677929 -276.212509) (xy 364.727104 -276.210528) (xy 364.775959 -276.21646) (xy 364.82323 -276.230152)
			(xy 364.867692 -276.25125) (xy 364.908195 -276.279206) (xy 364.943688 -276.313298) (xy 364.973253 -276.352642)
			(xy 364.996124 -276.396219) (xy 365.011708 -276.4429) (xy 365.019603 -276.491477) (xy 365.020098 -276.516084)
			(xy 365.349548 -276.516084) (xy 365.353502 -276.467111) (xy 365.36526 -276.419407) (xy 365.384518 -276.374206)
			(xy 365.410777 -276.33268) (xy 365.443358 -276.295904) (xy 365.481416 -276.26483) (xy 365.523966 -276.240264)
			(xy 365.569905 -276.222842) (xy 365.618045 -276.213014) (xy 365.667137 -276.211036) (xy 365.715911 -276.216958)
			(xy 365.763103 -276.230627) (xy 365.807492 -276.25169) (xy 365.847927 -276.2796) (xy 365.883361 -276.313635)
			(xy 365.912877 -276.352914) (xy 365.93571 -276.396418) (xy 365.951269 -276.443022) (xy 365.95915 -276.491518)
			(xy 365.959644 -276.516084) (xy 367.228894 -276.516084) (xy 367.232854 -276.46703) (xy 367.244631 -276.419246)
			(xy 367.263922 -276.37397) (xy 367.290225 -276.332374) (xy 367.32286 -276.295537) (xy 367.360981 -276.264412)
			(xy 367.403602 -276.239805) (xy 367.449618 -276.222353) (xy 367.497837 -276.212509) (xy 367.547012 -276.210528)
			(xy 367.595867 -276.21646) (xy 367.643138 -276.230152) (xy 367.6876 -276.25125) (xy 367.728103 -276.279206)
			(xy 367.763596 -276.313298) (xy 367.793161 -276.352642) (xy 367.816032 -276.396219) (xy 367.831616 -276.4429)
			(xy 367.839511 -276.491477) (xy 367.840006 -276.516084) (xy 368.169456 -276.516084) (xy 368.17341 -276.467111)
			(xy 368.185168 -276.419407) (xy 368.204426 -276.374206) (xy 368.230685 -276.33268) (xy 368.263266 -276.295904)
			(xy 368.301324 -276.26483) (xy 368.343874 -276.240264) (xy 368.389813 -276.222842) (xy 368.437953 -276.213014)
			(xy 368.487045 -276.211036) (xy 368.535819 -276.216958) (xy 368.583011 -276.230627) (xy 368.6274 -276.25169)
			(xy 368.667835 -276.2796) (xy 368.703269 -276.313635) (xy 368.732785 -276.352914) (xy 368.755618 -276.396418)
			(xy 368.771177 -276.443022) (xy 368.779058 -276.491518) (xy 368.779552 -276.516084) (xy 370.049056 -276.516084)
			(xy 370.053016 -276.46703) (xy 370.064793 -276.419246) (xy 370.084084 -276.37397) (xy 370.110387 -276.332374)
			(xy 370.143022 -276.295537) (xy 370.181143 -276.264412) (xy 370.223764 -276.239805) (xy 370.26978 -276.222353)
			(xy 370.317999 -276.212509) (xy 370.367174 -276.210528) (xy 370.416029 -276.21646) (xy 370.4633 -276.230152)
			(xy 370.507762 -276.25125) (xy 370.548265 -276.279206) (xy 370.583758 -276.313298) (xy 370.613323 -276.352642)
			(xy 370.636194 -276.396219) (xy 370.651778 -276.4429) (xy 370.659673 -276.491477) (xy 370.660168 -276.516084)
			(xy 370.989618 -276.516084) (xy 370.993572 -276.467111) (xy 371.00533 -276.419407) (xy 371.024588 -276.374206)
			(xy 371.050847 -276.33268) (xy 371.083428 -276.295904) (xy 371.121486 -276.26483) (xy 371.164036 -276.240264)
			(xy 371.209975 -276.222842) (xy 371.258115 -276.213014) (xy 371.307207 -276.211036) (xy 371.355981 -276.216958)
			(xy 371.403173 -276.230627) (xy 371.447562 -276.25169) (xy 371.487997 -276.2796) (xy 371.523431 -276.313635)
			(xy 371.552947 -276.352914) (xy 371.57578 -276.396418) (xy 371.591339 -276.443022) (xy 371.59922 -276.491518)
			(xy 371.599714 -276.516084) (xy 372.868964 -276.516084) (xy 372.872924 -276.46703) (xy 372.884701 -276.419246)
			(xy 372.903992 -276.37397) (xy 372.930295 -276.332374) (xy 372.96293 -276.295537) (xy 373.001051 -276.264412)
			(xy 373.043672 -276.239805) (xy 373.089688 -276.222353) (xy 373.137907 -276.212509) (xy 373.187082 -276.210528)
			(xy 373.235937 -276.21646) (xy 373.283208 -276.230152) (xy 373.32767 -276.25125) (xy 373.368173 -276.279206)
			(xy 373.403666 -276.313298) (xy 373.433231 -276.352642) (xy 373.456102 -276.396219) (xy 373.471686 -276.4429)
			(xy 373.479581 -276.491477) (xy 373.480076 -276.516084) (xy 373.809526 -276.516084) (xy 373.81348 -276.467111)
			(xy 373.825238 -276.419407) (xy 373.844496 -276.374206) (xy 373.870755 -276.33268) (xy 373.903336 -276.295904)
			(xy 373.941394 -276.26483) (xy 373.983944 -276.240264) (xy 374.029883 -276.222842) (xy 374.078023 -276.213014)
			(xy 374.127115 -276.211036) (xy 374.175889 -276.216958) (xy 374.223081 -276.230627) (xy 374.26747 -276.25169)
			(xy 374.307905 -276.2796) (xy 374.343339 -276.313635) (xy 374.372855 -276.352914) (xy 374.395688 -276.396418)
			(xy 374.411247 -276.443022) (xy 374.419128 -276.491518) (xy 374.419622 -276.516084) (xy 374.419128 -276.54065)
			(xy 374.411247 -276.589146) (xy 374.395688 -276.63575) (xy 374.372855 -276.679254) (xy 374.343339 -276.718533)
			(xy 374.307905 -276.752568) (xy 374.26747 -276.780478) (xy 374.223081 -276.801541) (xy 374.175889 -276.81521)
			(xy 374.127115 -276.821132) (xy 374.078023 -276.819154) (xy 374.029883 -276.809326) (xy 373.983944 -276.791904)
			(xy 373.941394 -276.767338) (xy 373.903336 -276.736264) (xy 373.870755 -276.699488) (xy 373.844496 -276.657962)
			(xy 373.825238 -276.612761) (xy 373.81348 -276.565057) (xy 373.809526 -276.516084) (xy 373.480076 -276.516084)
			(xy 373.479581 -276.540691) (xy 373.471686 -276.589268) (xy 373.456102 -276.635949) (xy 373.433231 -276.679526)
			(xy 373.403666 -276.71887) (xy 373.368173 -276.752962) (xy 373.32767 -276.780918) (xy 373.283208 -276.802016)
			(xy 373.235937 -276.815708) (xy 373.187082 -276.82164) (xy 373.137907 -276.819659) (xy 373.089688 -276.809815)
			(xy 373.043672 -276.792363) (xy 373.001051 -276.767756) (xy 372.96293 -276.736631) (xy 372.930295 -276.699794)
			(xy 372.903992 -276.658198) (xy 372.884701 -276.612922) (xy 372.872924 -276.565138) (xy 372.868964 -276.516084)
			(xy 371.599714 -276.516084) (xy 371.59922 -276.54065) (xy 371.591339 -276.589146) (xy 371.57578 -276.63575)
			(xy 371.552947 -276.679254) (xy 371.523431 -276.718533) (xy 371.487997 -276.752568) (xy 371.447562 -276.780478)
			(xy 371.403173 -276.801541) (xy 371.355981 -276.81521) (xy 371.307207 -276.821132) (xy 371.258115 -276.819154)
			(xy 371.209975 -276.809326) (xy 371.164036 -276.791904) (xy 371.121486 -276.767338) (xy 371.083428 -276.736264)
			(xy 371.050847 -276.699488) (xy 371.024588 -276.657962) (xy 371.00533 -276.612761) (xy 370.993572 -276.565057)
			(xy 370.989618 -276.516084) (xy 370.660168 -276.516084) (xy 370.659673 -276.540691) (xy 370.651778 -276.589268)
			(xy 370.636194 -276.635949) (xy 370.613323 -276.679526) (xy 370.583758 -276.71887) (xy 370.548265 -276.752962)
			(xy 370.507762 -276.780918) (xy 370.4633 -276.802016) (xy 370.416029 -276.815708) (xy 370.367174 -276.82164)
			(xy 370.317999 -276.819659) (xy 370.26978 -276.809815) (xy 370.223764 -276.792363) (xy 370.181143 -276.767756)
			(xy 370.143022 -276.736631) (xy 370.110387 -276.699794) (xy 370.084084 -276.658198) (xy 370.064793 -276.612922)
			(xy 370.053016 -276.565138) (xy 370.049056 -276.516084) (xy 368.779552 -276.516084) (xy 368.779058 -276.54065)
			(xy 368.771177 -276.589146) (xy 368.755618 -276.63575) (xy 368.732785 -276.679254) (xy 368.703269 -276.718533)
			(xy 368.667835 -276.752568) (xy 368.6274 -276.780478) (xy 368.583011 -276.801541) (xy 368.535819 -276.81521)
			(xy 368.487045 -276.821132) (xy 368.437953 -276.819154) (xy 368.389813 -276.809326) (xy 368.343874 -276.791904)
			(xy 368.301324 -276.767338) (xy 368.263266 -276.736264) (xy 368.230685 -276.699488) (xy 368.204426 -276.657962)
			(xy 368.185168 -276.612761) (xy 368.17341 -276.565057) (xy 368.169456 -276.516084) (xy 367.840006 -276.516084)
			(xy 367.839511 -276.540691) (xy 367.831616 -276.589268) (xy 367.816032 -276.635949) (xy 367.793161 -276.679526)
			(xy 367.763596 -276.71887) (xy 367.728103 -276.752962) (xy 367.6876 -276.780918) (xy 367.643138 -276.802016)
			(xy 367.595867 -276.815708) (xy 367.547012 -276.82164) (xy 367.497837 -276.819659) (xy 367.449618 -276.809815)
			(xy 367.403602 -276.792363) (xy 367.360981 -276.767756) (xy 367.32286 -276.736631) (xy 367.290225 -276.699794)
			(xy 367.263922 -276.658198) (xy 367.244631 -276.612922) (xy 367.232854 -276.565138) (xy 367.228894 -276.516084)
			(xy 365.959644 -276.516084) (xy 365.95915 -276.54065) (xy 365.951269 -276.589146) (xy 365.93571 -276.63575)
			(xy 365.912877 -276.679254) (xy 365.883361 -276.718533) (xy 365.847927 -276.752568) (xy 365.807492 -276.780478)
			(xy 365.763103 -276.801541) (xy 365.715911 -276.81521) (xy 365.667137 -276.821132) (xy 365.618045 -276.819154)
			(xy 365.569905 -276.809326) (xy 365.523966 -276.791904) (xy 365.481416 -276.767338) (xy 365.443358 -276.736264)
			(xy 365.410777 -276.699488) (xy 365.384518 -276.657962) (xy 365.36526 -276.612761) (xy 365.353502 -276.565057)
			(xy 365.349548 -276.516084) (xy 365.020098 -276.516084) (xy 365.019603 -276.540691) (xy 365.011708 -276.589268)
			(xy 364.996124 -276.635949) (xy 364.973253 -276.679526) (xy 364.943688 -276.71887) (xy 364.908195 -276.752962)
			(xy 364.867692 -276.780918) (xy 364.82323 -276.802016) (xy 364.775959 -276.815708) (xy 364.727104 -276.82164)
			(xy 364.677929 -276.819659) (xy 364.62971 -276.809815) (xy 364.583694 -276.792363) (xy 364.541073 -276.767756)
			(xy 364.502952 -276.736631) (xy 364.470317 -276.699794) (xy 364.444014 -276.658198) (xy 364.424723 -276.612922)
			(xy 364.412946 -276.565138) (xy 364.408986 -276.516084) (xy 355.625908 -276.516084) (xy 355.625414 -276.54065)
			(xy 355.617533 -276.589146) (xy 355.601974 -276.63575) (xy 355.579141 -276.679254) (xy 355.549625 -276.718533)
			(xy 355.514191 -276.752568) (xy 355.473756 -276.780478) (xy 355.429367 -276.801541) (xy 355.382175 -276.81521)
			(xy 355.333401 -276.821132) (xy 355.284309 -276.819154) (xy 355.236169 -276.809326) (xy 355.19023 -276.791904)
			(xy 355.14768 -276.767338) (xy 355.109622 -276.736264) (xy 355.077041 -276.699488) (xy 355.050782 -276.657962)
			(xy 355.031524 -276.612761) (xy 355.019766 -276.565057) (xy 355.015812 -276.516084) (xy 354.686362 -276.516084)
			(xy 354.685867 -276.540691) (xy 354.677972 -276.589268) (xy 354.662388 -276.635949) (xy 354.639517 -276.679526)
			(xy 354.609952 -276.71887) (xy 354.574459 -276.752962) (xy 354.533956 -276.780918) (xy 354.489494 -276.802016)
			(xy 354.442223 -276.815708) (xy 354.393368 -276.82164) (xy 354.344193 -276.819659) (xy 354.295974 -276.809815)
			(xy 354.249958 -276.792363) (xy 354.207337 -276.767756) (xy 354.169216 -276.736631) (xy 354.136581 -276.699794)
			(xy 354.110278 -276.658198) (xy 354.090987 -276.612922) (xy 354.07921 -276.565138) (xy 354.07525 -276.516084)
			(xy 352.806 -276.516084) (xy 352.805506 -276.54065) (xy 352.797625 -276.589146) (xy 352.782066 -276.63575)
			(xy 352.759233 -276.679254) (xy 352.729717 -276.718533) (xy 352.694283 -276.752568) (xy 352.653848 -276.780478)
			(xy 352.609459 -276.801541) (xy 352.562267 -276.81521) (xy 352.513493 -276.821132) (xy 352.464401 -276.819154)
			(xy 352.416261 -276.809326) (xy 352.370322 -276.791904) (xy 352.327772 -276.767338) (xy 352.289714 -276.736264)
			(xy 352.257133 -276.699488) (xy 352.230874 -276.657962) (xy 352.211616 -276.612761) (xy 352.199858 -276.565057)
			(xy 352.195904 -276.516084) (xy 351.866454 -276.516084) (xy 351.865959 -276.540691) (xy 351.858064 -276.589268)
			(xy 351.84248 -276.635949) (xy 351.819609 -276.679526) (xy 351.790044 -276.71887) (xy 351.754551 -276.752962)
			(xy 351.714048 -276.780918) (xy 351.669586 -276.802016) (xy 351.622315 -276.815708) (xy 351.57346 -276.82164)
			(xy 351.524285 -276.819659) (xy 351.476066 -276.809815) (xy 351.43005 -276.792363) (xy 351.387429 -276.767756)
			(xy 351.349308 -276.736631) (xy 351.316673 -276.699794) (xy 351.29037 -276.658198) (xy 351.271079 -276.612922)
			(xy 351.259302 -276.565138) (xy 351.255342 -276.516084) (xy 349.985838 -276.516084) (xy 349.985344 -276.54065)
			(xy 349.977463 -276.589146) (xy 349.961904 -276.63575) (xy 349.939071 -276.679254) (xy 349.909555 -276.718533)
			(xy 349.874121 -276.752568) (xy 349.833686 -276.780478) (xy 349.789297 -276.801541) (xy 349.742105 -276.81521)
			(xy 349.693331 -276.821132) (xy 349.644239 -276.819154) (xy 349.596099 -276.809326) (xy 349.55016 -276.791904)
			(xy 349.50761 -276.767338) (xy 349.469552 -276.736264) (xy 349.436971 -276.699488) (xy 349.410712 -276.657962)
			(xy 349.391454 -276.612761) (xy 349.379696 -276.565057) (xy 349.375742 -276.516084) (xy 349.046292 -276.516084)
			(xy 349.045797 -276.540691) (xy 349.037902 -276.589268) (xy 349.022318 -276.635949) (xy 348.999447 -276.679526)
			(xy 348.969882 -276.71887) (xy 348.934389 -276.752962) (xy 348.893886 -276.780918) (xy 348.849424 -276.802016)
			(xy 348.802153 -276.815708) (xy 348.753298 -276.82164) (xy 348.704123 -276.819659) (xy 348.655904 -276.809815)
			(xy 348.609888 -276.792363) (xy 348.567267 -276.767756) (xy 348.529146 -276.736631) (xy 348.496511 -276.699794)
			(xy 348.470208 -276.658198) (xy 348.450917 -276.612922) (xy 348.43914 -276.565138) (xy 348.43518 -276.516084)
			(xy 347.16593 -276.516084) (xy 347.165436 -276.54065) (xy 347.157555 -276.589146) (xy 347.141996 -276.63575)
			(xy 347.119163 -276.679254) (xy 347.089647 -276.718533) (xy 347.054213 -276.752568) (xy 347.013778 -276.780478)
			(xy 346.969389 -276.801541) (xy 346.922197 -276.81521) (xy 346.873423 -276.821132) (xy 346.824331 -276.819154)
			(xy 346.776191 -276.809326) (xy 346.730252 -276.791904) (xy 346.687702 -276.767338) (xy 346.649644 -276.736264)
			(xy 346.617063 -276.699488) (xy 346.590804 -276.657962) (xy 346.571546 -276.612761) (xy 346.559788 -276.565057)
			(xy 346.555834 -276.516084) (xy 346.226384 -276.516084) (xy 346.225889 -276.540691) (xy 346.217994 -276.589268)
			(xy 346.20241 -276.635949) (xy 346.179539 -276.679526) (xy 346.149974 -276.71887) (xy 346.114481 -276.752962)
			(xy 346.073978 -276.780918) (xy 346.029516 -276.802016) (xy 345.982245 -276.815708) (xy 345.93339 -276.82164)
			(xy 345.884215 -276.819659) (xy 345.835996 -276.809815) (xy 345.78998 -276.792363) (xy 345.747359 -276.767756)
			(xy 345.709238 -276.736631) (xy 345.676603 -276.699794) (xy 345.6503 -276.658198) (xy 345.631009 -276.612922)
			(xy 345.619232 -276.565138) (xy 345.615272 -276.516084) (xy 126.479549 -276.516084) (xy 126.479554 -276.516338)
			(xy 126.47906 -276.540904) (xy 126.471179 -276.5894) (xy 126.45562 -276.636004) (xy 126.432787 -276.679508)
			(xy 126.403271 -276.718787) (xy 126.367837 -276.752822) (xy 126.327402 -276.780732) (xy 126.283013 -276.801795)
			(xy 126.235821 -276.815464) (xy 126.187047 -276.821386) (xy 126.137955 -276.819408) (xy 126.089815 -276.80958)
			(xy 126.043876 -276.792158) (xy 126.001326 -276.767592) (xy 125.963268 -276.736518) (xy 125.930687 -276.699742)
			(xy 125.904428 -276.658216) (xy 125.88517 -276.613015) (xy 125.873412 -276.565311) (xy 125.869458 -276.516338)
			(xy 125.540008 -276.516338) (xy 125.539513 -276.540945) (xy 125.531618 -276.589522) (xy 125.516034 -276.636203)
			(xy 125.493163 -276.67978) (xy 125.463598 -276.719124) (xy 125.428105 -276.753216) (xy 125.387602 -276.781172)
			(xy 125.34314 -276.80227) (xy 125.295869 -276.815962) (xy 125.247014 -276.821894) (xy 125.197839 -276.819913)
			(xy 125.14962 -276.810069) (xy 125.103604 -276.792617) (xy 125.060983 -276.76801) (xy 125.022862 -276.736885)
			(xy 124.990227 -276.700048) (xy 124.963924 -276.658452) (xy 124.944633 -276.613176) (xy 124.932856 -276.565392)
			(xy 124.928896 -276.516338) (xy 123.659646 -276.516338) (xy 123.659152 -276.540904) (xy 123.651271 -276.5894)
			(xy 123.635712 -276.636004) (xy 123.612879 -276.679508) (xy 123.583363 -276.718787) (xy 123.547929 -276.752822)
			(xy 123.507494 -276.780732) (xy 123.463105 -276.801795) (xy 123.415913 -276.815464) (xy 123.367139 -276.821386)
			(xy 123.318047 -276.819408) (xy 123.269907 -276.80958) (xy 123.223968 -276.792158) (xy 123.181418 -276.767592)
			(xy 123.14336 -276.736518) (xy 123.110779 -276.699742) (xy 123.08452 -276.658216) (xy 123.065262 -276.613015)
			(xy 123.053504 -276.565311) (xy 123.04955 -276.516338) (xy 122.7201 -276.516338) (xy 122.719605 -276.540945)
			(xy 122.71171 -276.589522) (xy 122.696126 -276.636203) (xy 122.673255 -276.67978) (xy 122.64369 -276.719124)
			(xy 122.608197 -276.753216) (xy 122.567694 -276.781172) (xy 122.523232 -276.80227) (xy 122.475961 -276.815962)
			(xy 122.427106 -276.821894) (xy 122.377931 -276.819913) (xy 122.329712 -276.810069) (xy 122.283696 -276.792617)
			(xy 122.241075 -276.76801) (xy 122.202954 -276.736885) (xy 122.170319 -276.700048) (xy 122.144016 -276.658452)
			(xy 122.124725 -276.613176) (xy 122.112948 -276.565392) (xy 122.108988 -276.516338) (xy 120.839484 -276.516338)
			(xy 120.83899 -276.540904) (xy 120.831109 -276.5894) (xy 120.81555 -276.636004) (xy 120.792717 -276.679508)
			(xy 120.763201 -276.718787) (xy 120.727767 -276.752822) (xy 120.687332 -276.780732) (xy 120.642943 -276.801795)
			(xy 120.595751 -276.815464) (xy 120.546977 -276.821386) (xy 120.497885 -276.819408) (xy 120.449745 -276.80958)
			(xy 120.403806 -276.792158) (xy 120.361256 -276.767592) (xy 120.323198 -276.736518) (xy 120.290617 -276.699742)
			(xy 120.264358 -276.658216) (xy 120.2451 -276.613015) (xy 120.233342 -276.565311) (xy 120.229388 -276.516338)
			(xy 119.899938 -276.516338) (xy 119.899443 -276.540945) (xy 119.891548 -276.589522) (xy 119.875964 -276.636203)
			(xy 119.853093 -276.67978) (xy 119.823528 -276.719124) (xy 119.788035 -276.753216) (xy 119.747532 -276.781172)
			(xy 119.70307 -276.80227) (xy 119.655799 -276.815962) (xy 119.606944 -276.821894) (xy 119.557769 -276.819913)
			(xy 119.50955 -276.810069) (xy 119.463534 -276.792617) (xy 119.420913 -276.76801) (xy 119.382792 -276.736885)
			(xy 119.350157 -276.700048) (xy 119.323854 -276.658452) (xy 119.304563 -276.613176) (xy 119.292786 -276.565392)
			(xy 119.288826 -276.516338) (xy 118.019576 -276.516338) (xy 118.019082 -276.540904) (xy 118.011201 -276.5894)
			(xy 117.995642 -276.636004) (xy 117.972809 -276.679508) (xy 117.943293 -276.718787) (xy 117.907859 -276.752822)
			(xy 117.867424 -276.780732) (xy 117.823035 -276.801795) (xy 117.775843 -276.815464) (xy 117.727069 -276.821386)
			(xy 117.677977 -276.819408) (xy 117.629837 -276.80958) (xy 117.583898 -276.792158) (xy 117.541348 -276.767592)
			(xy 117.50329 -276.736518) (xy 117.470709 -276.699742) (xy 117.44445 -276.658216) (xy 117.425192 -276.613015)
			(xy 117.413434 -276.565311) (xy 117.40948 -276.516338) (xy 117.08003 -276.516338) (xy 117.079535 -276.540945)
			(xy 117.07164 -276.589522) (xy 117.056056 -276.636203) (xy 117.033185 -276.67978) (xy 117.00362 -276.719124)
			(xy 116.968127 -276.753216) (xy 116.927624 -276.781172) (xy 116.883162 -276.80227) (xy 116.835891 -276.815962)
			(xy 116.787036 -276.821894) (xy 116.737861 -276.819913) (xy 116.689642 -276.810069) (xy 116.643626 -276.792617)
			(xy 116.601005 -276.76801) (xy 116.562884 -276.736885) (xy 116.530249 -276.700048) (xy 116.503946 -276.658452)
			(xy 116.484655 -276.613176) (xy 116.472878 -276.565392) (xy 116.468918 -276.516338) (xy 107.68584 -276.516338)
			(xy 107.685346 -276.540904) (xy 107.677465 -276.5894) (xy 107.661906 -276.636004) (xy 107.639073 -276.679508)
			(xy 107.609557 -276.718787) (xy 107.574123 -276.752822) (xy 107.533688 -276.780732) (xy 107.489299 -276.801795)
			(xy 107.442107 -276.815464) (xy 107.393333 -276.821386) (xy 107.344241 -276.819408) (xy 107.296101 -276.80958)
			(xy 107.250162 -276.792158) (xy 107.207612 -276.767592) (xy 107.169554 -276.736518) (xy 107.136973 -276.699742)
			(xy 107.110714 -276.658216) (xy 107.091456 -276.613015) (xy 107.079698 -276.565311) (xy 107.075744 -276.516338)
			(xy 106.746294 -276.516338) (xy 106.745799 -276.540945) (xy 106.737904 -276.589522) (xy 106.72232 -276.636203)
			(xy 106.699449 -276.67978) (xy 106.669884 -276.719124) (xy 106.634391 -276.753216) (xy 106.593888 -276.781172)
			(xy 106.549426 -276.80227) (xy 106.502155 -276.815962) (xy 106.4533 -276.821894) (xy 106.404125 -276.819913)
			(xy 106.355906 -276.810069) (xy 106.30989 -276.792617) (xy 106.267269 -276.76801) (xy 106.229148 -276.736885)
			(xy 106.196513 -276.700048) (xy 106.17021 -276.658452) (xy 106.150919 -276.613176) (xy 106.139142 -276.565392)
			(xy 106.135182 -276.516338) (xy 104.865932 -276.516338) (xy 104.865438 -276.540904) (xy 104.857557 -276.5894)
			(xy 104.841998 -276.636004) (xy 104.819165 -276.679508) (xy 104.789649 -276.718787) (xy 104.754215 -276.752822)
			(xy 104.71378 -276.780732) (xy 104.669391 -276.801795) (xy 104.622199 -276.815464) (xy 104.573425 -276.821386)
			(xy 104.524333 -276.819408) (xy 104.476193 -276.80958) (xy 104.430254 -276.792158) (xy 104.387704 -276.767592)
			(xy 104.349646 -276.736518) (xy 104.317065 -276.699742) (xy 104.290806 -276.658216) (xy 104.271548 -276.613015)
			(xy 104.25979 -276.565311) (xy 104.255836 -276.516338) (xy 103.926386 -276.516338) (xy 103.925891 -276.540945)
			(xy 103.917996 -276.589522) (xy 103.902412 -276.636203) (xy 103.879541 -276.67978) (xy 103.849976 -276.719124)
			(xy 103.814483 -276.753216) (xy 103.77398 -276.781172) (xy 103.729518 -276.80227) (xy 103.682247 -276.815962)
			(xy 103.633392 -276.821894) (xy 103.584217 -276.819913) (xy 103.535998 -276.810069) (xy 103.489982 -276.792617)
			(xy 103.447361 -276.76801) (xy 103.40924 -276.736885) (xy 103.376605 -276.700048) (xy 103.350302 -276.658452)
			(xy 103.331011 -276.613176) (xy 103.319234 -276.565392) (xy 103.315274 -276.516338) (xy 102.04577 -276.516338)
			(xy 102.045276 -276.540904) (xy 102.037395 -276.5894) (xy 102.021836 -276.636004) (xy 101.999003 -276.679508)
			(xy 101.969487 -276.718787) (xy 101.934053 -276.752822) (xy 101.893618 -276.780732) (xy 101.849229 -276.801795)
			(xy 101.802037 -276.815464) (xy 101.753263 -276.821386) (xy 101.704171 -276.819408) (xy 101.656031 -276.80958)
			(xy 101.610092 -276.792158) (xy 101.567542 -276.767592) (xy 101.529484 -276.736518) (xy 101.496903 -276.699742)
			(xy 101.470644 -276.658216) (xy 101.451386 -276.613015) (xy 101.439628 -276.565311) (xy 101.435674 -276.516338)
			(xy 101.106224 -276.516338) (xy 101.105729 -276.540945) (xy 101.097834 -276.589522) (xy 101.08225 -276.636203)
			(xy 101.059379 -276.67978) (xy 101.029814 -276.719124) (xy 100.994321 -276.753216) (xy 100.953818 -276.781172)
			(xy 100.909356 -276.80227) (xy 100.862085 -276.815962) (xy 100.81323 -276.821894) (xy 100.764055 -276.819913)
			(xy 100.715836 -276.810069) (xy 100.66982 -276.792617) (xy 100.627199 -276.76801) (xy 100.589078 -276.736885)
			(xy 100.556443 -276.700048) (xy 100.53014 -276.658452) (xy 100.510849 -276.613176) (xy 100.499072 -276.565392)
			(xy 100.495112 -276.516338) (xy 99.225862 -276.516338) (xy 99.225368 -276.540904) (xy 99.217487 -276.5894)
			(xy 99.201928 -276.636004) (xy 99.179095 -276.679508) (xy 99.149579 -276.718787) (xy 99.114145 -276.752822)
			(xy 99.07371 -276.780732) (xy 99.029321 -276.801795) (xy 98.982129 -276.815464) (xy 98.933355 -276.821386)
			(xy 98.884263 -276.819408) (xy 98.836123 -276.80958) (xy 98.790184 -276.792158) (xy 98.747634 -276.767592)
			(xy 98.709576 -276.736518) (xy 98.676995 -276.699742) (xy 98.650736 -276.658216) (xy 98.631478 -276.613015)
			(xy 98.61972 -276.565311) (xy 98.615766 -276.516338) (xy 98.286316 -276.516338) (xy 98.285821 -276.540945)
			(xy 98.277926 -276.589522) (xy 98.262342 -276.636203) (xy 98.239471 -276.67978) (xy 98.209906 -276.719124)
			(xy 98.174413 -276.753216) (xy 98.13391 -276.781172) (xy 98.089448 -276.80227) (xy 98.042177 -276.815962)
			(xy 97.993322 -276.821894) (xy 97.944147 -276.819913) (xy 97.895928 -276.810069) (xy 97.849912 -276.792617)
			(xy 97.807291 -276.76801) (xy 97.76917 -276.736885) (xy 97.736535 -276.700048) (xy 97.710232 -276.658452)
			(xy 97.690941 -276.613176) (xy 97.679164 -276.565392) (xy 97.675204 -276.516338) (xy 2.509012 -276.516338)
			(xy 2.509012 -277.326344) (xy 108.48519 -277.326344) (xy 108.48915 -277.27729) (xy 108.500927 -277.229506)
			(xy 108.520218 -277.18423) (xy 108.546521 -277.142634) (xy 108.579156 -277.105797) (xy 108.617277 -277.074672)
			(xy 108.659898 -277.050065) (xy 108.705914 -277.032613) (xy 108.754133 -277.022769) (xy 108.803308 -277.020788)
			(xy 108.852163 -277.02672) (xy 108.899434 -277.040412) (xy 108.943896 -277.06151) (xy 108.984399 -277.089466)
			(xy 109.019892 -277.123558) (xy 109.049457 -277.162902) (xy 109.072328 -277.206479) (xy 109.087912 -277.25316)
			(xy 109.095807 -277.301737) (xy 109.096302 -277.326344) (xy 109.425752 -277.326344) (xy 109.429706 -277.277371)
			(xy 109.441464 -277.229667) (xy 109.460722 -277.184466) (xy 109.486981 -277.14294) (xy 109.519562 -277.106164)
			(xy 109.55762 -277.07509) (xy 109.60017 -277.050524) (xy 109.646109 -277.033102) (xy 109.694249 -277.023274)
			(xy 109.743341 -277.021296) (xy 109.792115 -277.027218) (xy 109.839307 -277.040887) (xy 109.883696 -277.06195)
			(xy 109.924131 -277.08986) (xy 109.959565 -277.123895) (xy 109.989081 -277.163174) (xy 110.011914 -277.206678)
			(xy 110.027473 -277.253282) (xy 110.035354 -277.301778) (xy 110.035848 -277.326344) (xy 114.11891 -277.326344)
			(xy 114.12287 -277.27729) (xy 114.134647 -277.229506) (xy 114.153938 -277.18423) (xy 114.180241 -277.142634)
			(xy 114.212876 -277.105797) (xy 114.250997 -277.074672) (xy 114.293618 -277.050065) (xy 114.339634 -277.032613)
			(xy 114.387853 -277.022769) (xy 114.437028 -277.020788) (xy 114.485883 -277.02672) (xy 114.533154 -277.040412)
			(xy 114.577616 -277.06151) (xy 114.618119 -277.089466) (xy 114.653612 -277.123558) (xy 114.683177 -277.162902)
			(xy 114.706048 -277.206479) (xy 114.721632 -277.25316) (xy 114.729527 -277.301737) (xy 114.730022 -277.326344)
			(xy 115.059472 -277.326344) (xy 115.063426 -277.277371) (xy 115.075184 -277.229667) (xy 115.094442 -277.184466)
			(xy 115.120701 -277.14294) (xy 115.153282 -277.106164) (xy 115.19134 -277.07509) (xy 115.23389 -277.050524)
			(xy 115.279829 -277.033102) (xy 115.327969 -277.023274) (xy 115.377061 -277.021296) (xy 115.425835 -277.027218)
			(xy 115.473027 -277.040887) (xy 115.517416 -277.06195) (xy 115.557851 -277.08986) (xy 115.593285 -277.123895)
			(xy 115.622801 -277.163174) (xy 115.645634 -277.206678) (xy 115.661193 -277.253282) (xy 115.669074 -277.301778)
			(xy 115.669563 -277.32609) (xy 356.425258 -277.32609) (xy 356.429218 -277.277036) (xy 356.440995 -277.229252)
			(xy 356.460286 -277.183976) (xy 356.486589 -277.14238) (xy 356.519224 -277.105543) (xy 356.557345 -277.074418)
			(xy 356.599966 -277.049811) (xy 356.645982 -277.032359) (xy 356.694201 -277.022515) (xy 356.743376 -277.020534)
			(xy 356.792231 -277.026466) (xy 356.839502 -277.040158) (xy 356.883964 -277.061256) (xy 356.924467 -277.089212)
			(xy 356.95996 -277.123304) (xy 356.989525 -277.162648) (xy 357.012396 -277.206225) (xy 357.02798 -277.252906)
			(xy 357.035875 -277.301483) (xy 357.03637 -277.32609) (xy 357.36582 -277.32609) (xy 357.369774 -277.277117)
			(xy 357.381532 -277.229413) (xy 357.40079 -277.184212) (xy 357.427049 -277.142686) (xy 357.45963 -277.10591)
			(xy 357.497688 -277.074836) (xy 357.540238 -277.05027) (xy 357.586177 -277.032848) (xy 357.634317 -277.02302)
			(xy 357.683409 -277.021042) (xy 357.732183 -277.026964) (xy 357.779375 -277.040633) (xy 357.823764 -277.061696)
			(xy 357.864199 -277.089606) (xy 357.899633 -277.123641) (xy 357.929149 -277.16292) (xy 357.951982 -277.206424)
			(xy 357.967541 -277.253028) (xy 357.975422 -277.301524) (xy 357.975916 -277.32609) (xy 362.058978 -277.32609)
			(xy 362.062938 -277.277036) (xy 362.074715 -277.229252) (xy 362.094006 -277.183976) (xy 362.120309 -277.14238)
			(xy 362.152944 -277.105543) (xy 362.191065 -277.074418) (xy 362.233686 -277.049811) (xy 362.279702 -277.032359)
			(xy 362.327921 -277.022515) (xy 362.377096 -277.020534) (xy 362.425951 -277.026466) (xy 362.473222 -277.040158)
			(xy 362.517684 -277.061256) (xy 362.558187 -277.089212) (xy 362.59368 -277.123304) (xy 362.623245 -277.162648)
			(xy 362.646116 -277.206225) (xy 362.6617 -277.252906) (xy 362.669595 -277.301483) (xy 362.67009 -277.32609)
			(xy 362.99954 -277.32609) (xy 363.003494 -277.277117) (xy 363.015252 -277.229413) (xy 363.03451 -277.184212)
			(xy 363.060769 -277.142686) (xy 363.09335 -277.10591) (xy 363.131408 -277.074836) (xy 363.173958 -277.05027)
			(xy 363.219897 -277.032848) (xy 363.268037 -277.02302) (xy 363.317129 -277.021042) (xy 363.365903 -277.026964)
			(xy 363.413095 -277.040633) (xy 363.457484 -277.061696) (xy 363.497919 -277.089606) (xy 363.533353 -277.123641)
			(xy 363.562869 -277.16292) (xy 363.585702 -277.206424) (xy 363.601261 -277.253028) (xy 363.609142 -277.301524)
			(xy 363.609636 -277.32609) (xy 363.609142 -277.350656) (xy 363.601261 -277.399152) (xy 363.585702 -277.445756)
			(xy 363.562869 -277.48926) (xy 363.533353 -277.528539) (xy 363.497919 -277.562574) (xy 363.457484 -277.590484)
			(xy 363.413095 -277.611547) (xy 363.365903 -277.625216) (xy 363.317129 -277.631138) (xy 363.268037 -277.62916)
			(xy 363.219897 -277.619332) (xy 363.173958 -277.60191) (xy 363.131408 -277.577344) (xy 363.09335 -277.54627)
			(xy 363.060769 -277.509494) (xy 363.03451 -277.467968) (xy 363.015252 -277.422767) (xy 363.003494 -277.375063)
			(xy 362.99954 -277.32609) (xy 362.67009 -277.32609) (xy 362.669595 -277.350697) (xy 362.6617 -277.399274)
			(xy 362.646116 -277.445955) (xy 362.623245 -277.489532) (xy 362.59368 -277.528876) (xy 362.558187 -277.562968)
			(xy 362.517684 -277.590924) (xy 362.473222 -277.612022) (xy 362.425951 -277.625714) (xy 362.377096 -277.631646)
			(xy 362.327921 -277.629665) (xy 362.279702 -277.619821) (xy 362.233686 -277.602369) (xy 362.191065 -277.577762)
			(xy 362.152944 -277.546637) (xy 362.120309 -277.5098) (xy 362.094006 -277.468204) (xy 362.074715 -277.422928)
			(xy 362.062938 -277.375144) (xy 362.058978 -277.32609) (xy 357.975916 -277.32609) (xy 357.975422 -277.350656)
			(xy 357.967541 -277.399152) (xy 357.951982 -277.445756) (xy 357.929149 -277.48926) (xy 357.899633 -277.528539)
			(xy 357.864199 -277.562574) (xy 357.823764 -277.590484) (xy 357.779375 -277.611547) (xy 357.732183 -277.625216)
			(xy 357.683409 -277.631138) (xy 357.634317 -277.62916) (xy 357.586177 -277.619332) (xy 357.540238 -277.60191)
			(xy 357.497688 -277.577344) (xy 357.45963 -277.54627) (xy 357.427049 -277.509494) (xy 357.40079 -277.467968)
			(xy 357.381532 -277.422767) (xy 357.369774 -277.375063) (xy 357.36582 -277.32609) (xy 357.03637 -277.32609)
			(xy 357.035875 -277.350697) (xy 357.02798 -277.399274) (xy 357.012396 -277.445955) (xy 356.989525 -277.489532)
			(xy 356.95996 -277.528876) (xy 356.924467 -277.562968) (xy 356.883964 -277.590924) (xy 356.839502 -277.612022)
			(xy 356.792231 -277.625714) (xy 356.743376 -277.631646) (xy 356.694201 -277.629665) (xy 356.645982 -277.619821)
			(xy 356.599966 -277.602369) (xy 356.557345 -277.577762) (xy 356.519224 -277.546637) (xy 356.486589 -277.5098)
			(xy 356.460286 -277.468204) (xy 356.440995 -277.422928) (xy 356.429218 -277.375144) (xy 356.425258 -277.32609)
			(xy 115.669563 -277.32609) (xy 115.669568 -277.326344) (xy 115.669074 -277.35091) (xy 115.661193 -277.399406)
			(xy 115.645634 -277.44601) (xy 115.622801 -277.489514) (xy 115.593285 -277.528793) (xy 115.557851 -277.562828)
			(xy 115.517416 -277.590738) (xy 115.473027 -277.611801) (xy 115.425835 -277.62547) (xy 115.377061 -277.631392)
			(xy 115.327969 -277.629414) (xy 115.279829 -277.619586) (xy 115.23389 -277.602164) (xy 115.19134 -277.577598)
			(xy 115.153282 -277.546524) (xy 115.120701 -277.509748) (xy 115.094442 -277.468222) (xy 115.075184 -277.423021)
			(xy 115.063426 -277.375317) (xy 115.059472 -277.326344) (xy 114.730022 -277.326344) (xy 114.729527 -277.350951)
			(xy 114.721632 -277.399528) (xy 114.706048 -277.446209) (xy 114.683177 -277.489786) (xy 114.653612 -277.52913)
			(xy 114.618119 -277.563222) (xy 114.577616 -277.591178) (xy 114.533154 -277.612276) (xy 114.485883 -277.625968)
			(xy 114.437028 -277.6319) (xy 114.387853 -277.629919) (xy 114.339634 -277.620075) (xy 114.293618 -277.602623)
			(xy 114.250997 -277.578016) (xy 114.212876 -277.546891) (xy 114.180241 -277.510054) (xy 114.153938 -277.468458)
			(xy 114.134647 -277.423182) (xy 114.12287 -277.375398) (xy 114.11891 -277.326344) (xy 110.035848 -277.326344)
			(xy 110.035354 -277.35091) (xy 110.027473 -277.399406) (xy 110.011914 -277.44601) (xy 109.989081 -277.489514)
			(xy 109.959565 -277.528793) (xy 109.924131 -277.562828) (xy 109.883696 -277.590738) (xy 109.839307 -277.611801)
			(xy 109.792115 -277.62547) (xy 109.743341 -277.631392) (xy 109.694249 -277.629414) (xy 109.646109 -277.619586)
			(xy 109.60017 -277.602164) (xy 109.55762 -277.577598) (xy 109.519562 -277.546524) (xy 109.486981 -277.509748)
			(xy 109.460722 -277.468222) (xy 109.441464 -277.423021) (xy 109.429706 -277.375317) (xy 109.425752 -277.326344)
			(xy 109.096302 -277.326344) (xy 109.095807 -277.350951) (xy 109.087912 -277.399528) (xy 109.072328 -277.446209)
			(xy 109.049457 -277.489786) (xy 109.019892 -277.52913) (xy 108.984399 -277.563222) (xy 108.943896 -277.591178)
			(xy 108.899434 -277.612276) (xy 108.852163 -277.625968) (xy 108.803308 -277.6319) (xy 108.754133 -277.629919)
			(xy 108.705914 -277.620075) (xy 108.659898 -277.602623) (xy 108.617277 -277.578016) (xy 108.579156 -277.546891)
			(xy 108.546521 -277.510054) (xy 108.520218 -277.468458) (xy 108.500927 -277.423182) (xy 108.48915 -277.375398)
			(xy 108.48519 -277.326344) (xy 2.509012 -277.326344) (xy 2.509012 -278.13635) (xy 97.675204 -278.13635)
			(xy 97.679164 -278.087296) (xy 97.690941 -278.039512) (xy 97.710232 -277.994236) (xy 97.736535 -277.95264)
			(xy 97.76917 -277.915803) (xy 97.807291 -277.884678) (xy 97.849912 -277.860071) (xy 97.895928 -277.842619)
			(xy 97.944147 -277.832775) (xy 97.993322 -277.830794) (xy 98.042177 -277.836726) (xy 98.089448 -277.850418)
			(xy 98.13391 -277.871516) (xy 98.174413 -277.899472) (xy 98.209906 -277.933564) (xy 98.239471 -277.972908)
			(xy 98.262342 -278.016485) (xy 98.277926 -278.063166) (xy 98.285821 -278.111743) (xy 98.286316 -278.13635)
			(xy 98.615766 -278.13635) (xy 98.61972 -278.087377) (xy 98.631478 -278.039673) (xy 98.650736 -277.994472)
			(xy 98.676995 -277.952946) (xy 98.709576 -277.91617) (xy 98.747634 -277.885096) (xy 98.790184 -277.86053)
			(xy 98.836123 -277.843108) (xy 98.884263 -277.83328) (xy 98.933355 -277.831302) (xy 98.982129 -277.837224)
			(xy 99.029321 -277.850893) (xy 99.07371 -277.871956) (xy 99.114145 -277.899866) (xy 99.149579 -277.933901)
			(xy 99.179095 -277.97318) (xy 99.201928 -278.016684) (xy 99.217487 -278.063288) (xy 99.225368 -278.111784)
			(xy 99.225862 -278.13635) (xy 100.495112 -278.13635) (xy 100.499072 -278.087296) (xy 100.510849 -278.039512)
			(xy 100.53014 -277.994236) (xy 100.556443 -277.95264) (xy 100.589078 -277.915803) (xy 100.627199 -277.884678)
			(xy 100.66982 -277.860071) (xy 100.715836 -277.842619) (xy 100.764055 -277.832775) (xy 100.81323 -277.830794)
			(xy 100.862085 -277.836726) (xy 100.909356 -277.850418) (xy 100.953818 -277.871516) (xy 100.994321 -277.899472)
			(xy 101.029814 -277.933564) (xy 101.059379 -277.972908) (xy 101.08225 -278.016485) (xy 101.097834 -278.063166)
			(xy 101.105729 -278.111743) (xy 101.106224 -278.13635) (xy 101.435674 -278.13635) (xy 101.439628 -278.087377)
			(xy 101.451386 -278.039673) (xy 101.470644 -277.994472) (xy 101.496903 -277.952946) (xy 101.529484 -277.91617)
			(xy 101.567542 -277.885096) (xy 101.610092 -277.86053) (xy 101.656031 -277.843108) (xy 101.704171 -277.83328)
			(xy 101.753263 -277.831302) (xy 101.802037 -277.837224) (xy 101.849229 -277.850893) (xy 101.893618 -277.871956)
			(xy 101.934053 -277.899866) (xy 101.969487 -277.933901) (xy 101.999003 -277.97318) (xy 102.021836 -278.016684)
			(xy 102.037395 -278.063288) (xy 102.045276 -278.111784) (xy 102.04577 -278.13635) (xy 103.315274 -278.13635)
			(xy 103.319234 -278.087296) (xy 103.331011 -278.039512) (xy 103.350302 -277.994236) (xy 103.376605 -277.95264)
			(xy 103.40924 -277.915803) (xy 103.447361 -277.884678) (xy 103.489982 -277.860071) (xy 103.535998 -277.842619)
			(xy 103.584217 -277.832775) (xy 103.633392 -277.830794) (xy 103.682247 -277.836726) (xy 103.729518 -277.850418)
			(xy 103.77398 -277.871516) (xy 103.814483 -277.899472) (xy 103.849976 -277.933564) (xy 103.879541 -277.972908)
			(xy 103.902412 -278.016485) (xy 103.917996 -278.063166) (xy 103.925891 -278.111743) (xy 103.926386 -278.13635)
			(xy 104.255836 -278.13635) (xy 104.25979 -278.087377) (xy 104.271548 -278.039673) (xy 104.290806 -277.994472)
			(xy 104.317065 -277.952946) (xy 104.349646 -277.91617) (xy 104.387704 -277.885096) (xy 104.430254 -277.86053)
			(xy 104.476193 -277.843108) (xy 104.524333 -277.83328) (xy 104.573425 -277.831302) (xy 104.622199 -277.837224)
			(xy 104.669391 -277.850893) (xy 104.71378 -277.871956) (xy 104.754215 -277.899866) (xy 104.789649 -277.933901)
			(xy 104.819165 -277.97318) (xy 104.841998 -278.016684) (xy 104.857557 -278.063288) (xy 104.865438 -278.111784)
			(xy 104.865932 -278.13635) (xy 106.135182 -278.13635) (xy 106.139142 -278.087296) (xy 106.150919 -278.039512)
			(xy 106.17021 -277.994236) (xy 106.196513 -277.95264) (xy 106.229148 -277.915803) (xy 106.267269 -277.884678)
			(xy 106.30989 -277.860071) (xy 106.355906 -277.842619) (xy 106.404125 -277.832775) (xy 106.4533 -277.830794)
			(xy 106.502155 -277.836726) (xy 106.549426 -277.850418) (xy 106.593888 -277.871516) (xy 106.634391 -277.899472)
			(xy 106.669884 -277.933564) (xy 106.699449 -277.972908) (xy 106.72232 -278.016485) (xy 106.737904 -278.063166)
			(xy 106.745799 -278.111743) (xy 106.746294 -278.13635) (xy 107.075744 -278.13635) (xy 107.079698 -278.087377)
			(xy 107.091456 -278.039673) (xy 107.110714 -277.994472) (xy 107.136973 -277.952946) (xy 107.169554 -277.91617)
			(xy 107.207612 -277.885096) (xy 107.250162 -277.86053) (xy 107.296101 -277.843108) (xy 107.344241 -277.83328)
			(xy 107.393333 -277.831302) (xy 107.442107 -277.837224) (xy 107.489299 -277.850893) (xy 107.533688 -277.871956)
			(xy 107.574123 -277.899866) (xy 107.609557 -277.933901) (xy 107.639073 -277.97318) (xy 107.661906 -278.016684)
			(xy 107.677465 -278.063288) (xy 107.685346 -278.111784) (xy 107.68584 -278.13635) (xy 116.468918 -278.13635)
			(xy 116.472878 -278.087296) (xy 116.484655 -278.039512) (xy 116.503946 -277.994236) (xy 116.530249 -277.95264)
			(xy 116.562884 -277.915803) (xy 116.601005 -277.884678) (xy 116.643626 -277.860071) (xy 116.689642 -277.842619)
			(xy 116.737861 -277.832775) (xy 116.787036 -277.830794) (xy 116.835891 -277.836726) (xy 116.883162 -277.850418)
			(xy 116.927624 -277.871516) (xy 116.968127 -277.899472) (xy 117.00362 -277.933564) (xy 117.033185 -277.972908)
			(xy 117.056056 -278.016485) (xy 117.07164 -278.063166) (xy 117.079535 -278.111743) (xy 117.08003 -278.13635)
			(xy 117.40948 -278.13635) (xy 117.413434 -278.087377) (xy 117.425192 -278.039673) (xy 117.44445 -277.994472)
			(xy 117.470709 -277.952946) (xy 117.50329 -277.91617) (xy 117.541348 -277.885096) (xy 117.583898 -277.86053)
			(xy 117.629837 -277.843108) (xy 117.677977 -277.83328) (xy 117.727069 -277.831302) (xy 117.775843 -277.837224)
			(xy 117.823035 -277.850893) (xy 117.867424 -277.871956) (xy 117.907859 -277.899866) (xy 117.943293 -277.933901)
			(xy 117.972809 -277.97318) (xy 117.995642 -278.016684) (xy 118.011201 -278.063288) (xy 118.019082 -278.111784)
			(xy 118.019576 -278.13635) (xy 119.288826 -278.13635) (xy 119.292786 -278.087296) (xy 119.304563 -278.039512)
			(xy 119.323854 -277.994236) (xy 119.350157 -277.95264) (xy 119.382792 -277.915803) (xy 119.420913 -277.884678)
			(xy 119.463534 -277.860071) (xy 119.50955 -277.842619) (xy 119.557769 -277.832775) (xy 119.606944 -277.830794)
			(xy 119.655799 -277.836726) (xy 119.70307 -277.850418) (xy 119.747532 -277.871516) (xy 119.788035 -277.899472)
			(xy 119.823528 -277.933564) (xy 119.853093 -277.972908) (xy 119.875964 -278.016485) (xy 119.891548 -278.063166)
			(xy 119.899443 -278.111743) (xy 119.899938 -278.13635) (xy 120.229388 -278.13635) (xy 120.233342 -278.087377)
			(xy 120.2451 -278.039673) (xy 120.264358 -277.994472) (xy 120.290617 -277.952946) (xy 120.323198 -277.91617)
			(xy 120.361256 -277.885096) (xy 120.403806 -277.86053) (xy 120.449745 -277.843108) (xy 120.497885 -277.83328)
			(xy 120.546977 -277.831302) (xy 120.595751 -277.837224) (xy 120.642943 -277.850893) (xy 120.687332 -277.871956)
			(xy 120.727767 -277.899866) (xy 120.763201 -277.933901) (xy 120.792717 -277.97318) (xy 120.81555 -278.016684)
			(xy 120.831109 -278.063288) (xy 120.83899 -278.111784) (xy 120.839484 -278.13635) (xy 122.108988 -278.13635)
			(xy 122.112948 -278.087296) (xy 122.124725 -278.039512) (xy 122.144016 -277.994236) (xy 122.170319 -277.95264)
			(xy 122.202954 -277.915803) (xy 122.241075 -277.884678) (xy 122.283696 -277.860071) (xy 122.329712 -277.842619)
			(xy 122.377931 -277.832775) (xy 122.427106 -277.830794) (xy 122.475961 -277.836726) (xy 122.523232 -277.850418)
			(xy 122.567694 -277.871516) (xy 122.608197 -277.899472) (xy 122.64369 -277.933564) (xy 122.673255 -277.972908)
			(xy 122.696126 -278.016485) (xy 122.71171 -278.063166) (xy 122.719605 -278.111743) (xy 122.7201 -278.13635)
			(xy 123.04955 -278.13635) (xy 123.053504 -278.087377) (xy 123.065262 -278.039673) (xy 123.08452 -277.994472)
			(xy 123.110779 -277.952946) (xy 123.14336 -277.91617) (xy 123.181418 -277.885096) (xy 123.223968 -277.86053)
			(xy 123.269907 -277.843108) (xy 123.318047 -277.83328) (xy 123.367139 -277.831302) (xy 123.415913 -277.837224)
			(xy 123.463105 -277.850893) (xy 123.507494 -277.871956) (xy 123.547929 -277.899866) (xy 123.583363 -277.933901)
			(xy 123.612879 -277.97318) (xy 123.635712 -278.016684) (xy 123.651271 -278.063288) (xy 123.659152 -278.111784)
			(xy 123.659646 -278.13635) (xy 124.928896 -278.13635) (xy 124.932856 -278.087296) (xy 124.944633 -278.039512)
			(xy 124.963924 -277.994236) (xy 124.990227 -277.95264) (xy 125.022862 -277.915803) (xy 125.060983 -277.884678)
			(xy 125.103604 -277.860071) (xy 125.14962 -277.842619) (xy 125.197839 -277.832775) (xy 125.247014 -277.830794)
			(xy 125.295869 -277.836726) (xy 125.34314 -277.850418) (xy 125.387602 -277.871516) (xy 125.428105 -277.899472)
			(xy 125.463598 -277.933564) (xy 125.493163 -277.972908) (xy 125.516034 -278.016485) (xy 125.531618 -278.063166)
			(xy 125.539513 -278.111743) (xy 125.540008 -278.13635) (xy 125.869458 -278.13635) (xy 125.873412 -278.087377)
			(xy 125.88517 -278.039673) (xy 125.904428 -277.994472) (xy 125.930687 -277.952946) (xy 125.963268 -277.91617)
			(xy 126.001326 -277.885096) (xy 126.043876 -277.86053) (xy 126.089815 -277.843108) (xy 126.137955 -277.83328)
			(xy 126.187047 -277.831302) (xy 126.235821 -277.837224) (xy 126.283013 -277.850893) (xy 126.327402 -277.871956)
			(xy 126.367837 -277.899866) (xy 126.403271 -277.933901) (xy 126.432787 -277.97318) (xy 126.45562 -278.016684)
			(xy 126.471179 -278.063288) (xy 126.47906 -278.111784) (xy 126.479549 -278.136096) (xy 345.615272 -278.136096)
			(xy 345.619232 -278.087042) (xy 345.631009 -278.039258) (xy 345.6503 -277.993982) (xy 345.676603 -277.952386)
			(xy 345.709238 -277.915549) (xy 345.747359 -277.884424) (xy 345.78998 -277.859817) (xy 345.835996 -277.842365)
			(xy 345.884215 -277.832521) (xy 345.93339 -277.83054) (xy 345.982245 -277.836472) (xy 346.029516 -277.850164)
			(xy 346.073978 -277.871262) (xy 346.114481 -277.899218) (xy 346.149974 -277.93331) (xy 346.179539 -277.972654)
			(xy 346.20241 -278.016231) (xy 346.217994 -278.062912) (xy 346.225889 -278.111489) (xy 346.226384 -278.136096)
			(xy 346.555834 -278.136096) (xy 346.559788 -278.087123) (xy 346.571546 -278.039419) (xy 346.590804 -277.994218)
			(xy 346.617063 -277.952692) (xy 346.649644 -277.915916) (xy 346.687702 -277.884842) (xy 346.730252 -277.860276)
			(xy 346.776191 -277.842854) (xy 346.824331 -277.833026) (xy 346.873423 -277.831048) (xy 346.922197 -277.83697)
			(xy 346.969389 -277.850639) (xy 347.013778 -277.871702) (xy 347.054213 -277.899612) (xy 347.089647 -277.933647)
			(xy 347.119163 -277.972926) (xy 347.141996 -278.01643) (xy 347.157555 -278.063034) (xy 347.165436 -278.11153)
			(xy 347.16593 -278.136096) (xy 348.43518 -278.136096) (xy 348.43914 -278.087042) (xy 348.450917 -278.039258)
			(xy 348.470208 -277.993982) (xy 348.496511 -277.952386) (xy 348.529146 -277.915549) (xy 348.567267 -277.884424)
			(xy 348.609888 -277.859817) (xy 348.655904 -277.842365) (xy 348.704123 -277.832521) (xy 348.753298 -277.83054)
			(xy 348.802153 -277.836472) (xy 348.849424 -277.850164) (xy 348.893886 -277.871262) (xy 348.934389 -277.899218)
			(xy 348.969882 -277.93331) (xy 348.999447 -277.972654) (xy 349.022318 -278.016231) (xy 349.037902 -278.062912)
			(xy 349.045797 -278.111489) (xy 349.046292 -278.136096) (xy 349.375742 -278.136096) (xy 349.379696 -278.087123)
			(xy 349.391454 -278.039419) (xy 349.410712 -277.994218) (xy 349.436971 -277.952692) (xy 349.469552 -277.915916)
			(xy 349.50761 -277.884842) (xy 349.55016 -277.860276) (xy 349.596099 -277.842854) (xy 349.644239 -277.833026)
			(xy 349.693331 -277.831048) (xy 349.742105 -277.83697) (xy 349.789297 -277.850639) (xy 349.833686 -277.871702)
			(xy 349.874121 -277.899612) (xy 349.909555 -277.933647) (xy 349.939071 -277.972926) (xy 349.961904 -278.01643)
			(xy 349.977463 -278.063034) (xy 349.985344 -278.11153) (xy 349.985838 -278.136096) (xy 351.255342 -278.136096)
			(xy 351.259302 -278.087042) (xy 351.271079 -278.039258) (xy 351.29037 -277.993982) (xy 351.316673 -277.952386)
			(xy 351.349308 -277.915549) (xy 351.387429 -277.884424) (xy 351.43005 -277.859817) (xy 351.476066 -277.842365)
			(xy 351.524285 -277.832521) (xy 351.57346 -277.83054) (xy 351.622315 -277.836472) (xy 351.669586 -277.850164)
			(xy 351.714048 -277.871262) (xy 351.754551 -277.899218) (xy 351.790044 -277.93331) (xy 351.819609 -277.972654)
			(xy 351.84248 -278.016231) (xy 351.858064 -278.062912) (xy 351.865959 -278.111489) (xy 351.866454 -278.136096)
			(xy 352.195904 -278.136096) (xy 352.199858 -278.087123) (xy 352.211616 -278.039419) (xy 352.230874 -277.994218)
			(xy 352.257133 -277.952692) (xy 352.289714 -277.915916) (xy 352.327772 -277.884842) (xy 352.370322 -277.860276)
			(xy 352.416261 -277.842854) (xy 352.464401 -277.833026) (xy 352.513493 -277.831048) (xy 352.562267 -277.83697)
			(xy 352.609459 -277.850639) (xy 352.653848 -277.871702) (xy 352.694283 -277.899612) (xy 352.729717 -277.933647)
			(xy 352.759233 -277.972926) (xy 352.782066 -278.01643) (xy 352.797625 -278.063034) (xy 352.805506 -278.11153)
			(xy 352.806 -278.136096) (xy 354.07525 -278.136096) (xy 354.07921 -278.087042) (xy 354.090987 -278.039258)
			(xy 354.110278 -277.993982) (xy 354.136581 -277.952386) (xy 354.169216 -277.915549) (xy 354.207337 -277.884424)
			(xy 354.249958 -277.859817) (xy 354.295974 -277.842365) (xy 354.344193 -277.832521) (xy 354.393368 -277.83054)
			(xy 354.442223 -277.836472) (xy 354.489494 -277.850164) (xy 354.533956 -277.871262) (xy 354.574459 -277.899218)
			(xy 354.609952 -277.93331) (xy 354.639517 -277.972654) (xy 354.662388 -278.016231) (xy 354.677972 -278.062912)
			(xy 354.685867 -278.111489) (xy 354.686362 -278.136096) (xy 355.015812 -278.136096) (xy 355.019766 -278.087123)
			(xy 355.031524 -278.039419) (xy 355.050782 -277.994218) (xy 355.077041 -277.952692) (xy 355.109622 -277.915916)
			(xy 355.14768 -277.884842) (xy 355.19023 -277.860276) (xy 355.236169 -277.842854) (xy 355.284309 -277.833026)
			(xy 355.333401 -277.831048) (xy 355.382175 -277.83697) (xy 355.429367 -277.850639) (xy 355.473756 -277.871702)
			(xy 355.514191 -277.899612) (xy 355.549625 -277.933647) (xy 355.579141 -277.972926) (xy 355.601974 -278.01643)
			(xy 355.617533 -278.063034) (xy 355.625414 -278.11153) (xy 355.625908 -278.136096) (xy 364.408986 -278.136096)
			(xy 364.412946 -278.087042) (xy 364.424723 -278.039258) (xy 364.444014 -277.993982) (xy 364.470317 -277.952386)
			(xy 364.502952 -277.915549) (xy 364.541073 -277.884424) (xy 364.583694 -277.859817) (xy 364.62971 -277.842365)
			(xy 364.677929 -277.832521) (xy 364.727104 -277.83054) (xy 364.775959 -277.836472) (xy 364.82323 -277.850164)
			(xy 364.867692 -277.871262) (xy 364.908195 -277.899218) (xy 364.943688 -277.93331) (xy 364.973253 -277.972654)
			(xy 364.996124 -278.016231) (xy 365.011708 -278.062912) (xy 365.019603 -278.111489) (xy 365.020098 -278.136096)
			(xy 365.349548 -278.136096) (xy 365.353502 -278.087123) (xy 365.36526 -278.039419) (xy 365.384518 -277.994218)
			(xy 365.410777 -277.952692) (xy 365.443358 -277.915916) (xy 365.481416 -277.884842) (xy 365.523966 -277.860276)
			(xy 365.569905 -277.842854) (xy 365.618045 -277.833026) (xy 365.667137 -277.831048) (xy 365.715911 -277.83697)
			(xy 365.763103 -277.850639) (xy 365.807492 -277.871702) (xy 365.847927 -277.899612) (xy 365.883361 -277.933647)
			(xy 365.912877 -277.972926) (xy 365.93571 -278.01643) (xy 365.951269 -278.063034) (xy 365.95915 -278.11153)
			(xy 365.959644 -278.136096) (xy 367.228894 -278.136096) (xy 367.232854 -278.087042) (xy 367.244631 -278.039258)
			(xy 367.263922 -277.993982) (xy 367.290225 -277.952386) (xy 367.32286 -277.915549) (xy 367.360981 -277.884424)
			(xy 367.403602 -277.859817) (xy 367.449618 -277.842365) (xy 367.497837 -277.832521) (xy 367.547012 -277.83054)
			(xy 367.595867 -277.836472) (xy 367.643138 -277.850164) (xy 367.6876 -277.871262) (xy 367.728103 -277.899218)
			(xy 367.763596 -277.93331) (xy 367.793161 -277.972654) (xy 367.816032 -278.016231) (xy 367.831616 -278.062912)
			(xy 367.839511 -278.111489) (xy 367.840006 -278.136096) (xy 368.169456 -278.136096) (xy 368.17341 -278.087123)
			(xy 368.185168 -278.039419) (xy 368.204426 -277.994218) (xy 368.230685 -277.952692) (xy 368.263266 -277.915916)
			(xy 368.301324 -277.884842) (xy 368.343874 -277.860276) (xy 368.389813 -277.842854) (xy 368.437953 -277.833026)
			(xy 368.487045 -277.831048) (xy 368.535819 -277.83697) (xy 368.583011 -277.850639) (xy 368.6274 -277.871702)
			(xy 368.667835 -277.899612) (xy 368.703269 -277.933647) (xy 368.732785 -277.972926) (xy 368.755618 -278.01643)
			(xy 368.771177 -278.063034) (xy 368.779058 -278.11153) (xy 368.779552 -278.136096) (xy 370.049056 -278.136096)
			(xy 370.053016 -278.087042) (xy 370.064793 -278.039258) (xy 370.084084 -277.993982) (xy 370.110387 -277.952386)
			(xy 370.143022 -277.915549) (xy 370.181143 -277.884424) (xy 370.223764 -277.859817) (xy 370.26978 -277.842365)
			(xy 370.317999 -277.832521) (xy 370.367174 -277.83054) (xy 370.416029 -277.836472) (xy 370.4633 -277.850164)
			(xy 370.507762 -277.871262) (xy 370.548265 -277.899218) (xy 370.583758 -277.93331) (xy 370.613323 -277.972654)
			(xy 370.636194 -278.016231) (xy 370.651778 -278.062912) (xy 370.659673 -278.111489) (xy 370.660168 -278.136096)
			(xy 370.989618 -278.136096) (xy 370.993572 -278.087123) (xy 371.00533 -278.039419) (xy 371.024588 -277.994218)
			(xy 371.050847 -277.952692) (xy 371.083428 -277.915916) (xy 371.121486 -277.884842) (xy 371.164036 -277.860276)
			(xy 371.209975 -277.842854) (xy 371.258115 -277.833026) (xy 371.307207 -277.831048) (xy 371.355981 -277.83697)
			(xy 371.403173 -277.850639) (xy 371.447562 -277.871702) (xy 371.487997 -277.899612) (xy 371.523431 -277.933647)
			(xy 371.552947 -277.972926) (xy 371.57578 -278.01643) (xy 371.591339 -278.063034) (xy 371.59922 -278.11153)
			(xy 371.599714 -278.136096) (xy 372.868964 -278.136096) (xy 372.872924 -278.087042) (xy 372.884701 -278.039258)
			(xy 372.903992 -277.993982) (xy 372.930295 -277.952386) (xy 372.96293 -277.915549) (xy 373.001051 -277.884424)
			(xy 373.043672 -277.859817) (xy 373.089688 -277.842365) (xy 373.137907 -277.832521) (xy 373.187082 -277.83054)
			(xy 373.235937 -277.836472) (xy 373.283208 -277.850164) (xy 373.32767 -277.871262) (xy 373.368173 -277.899218)
			(xy 373.403666 -277.93331) (xy 373.433231 -277.972654) (xy 373.456102 -278.016231) (xy 373.471686 -278.062912)
			(xy 373.479581 -278.111489) (xy 373.480076 -278.136096) (xy 373.809526 -278.136096) (xy 373.81348 -278.087123)
			(xy 373.825238 -278.039419) (xy 373.844496 -277.994218) (xy 373.870755 -277.952692) (xy 373.903336 -277.915916)
			(xy 373.941394 -277.884842) (xy 373.983944 -277.860276) (xy 374.029883 -277.842854) (xy 374.078023 -277.833026)
			(xy 374.127115 -277.831048) (xy 374.175889 -277.83697) (xy 374.223081 -277.850639) (xy 374.26747 -277.871702)
			(xy 374.307905 -277.899612) (xy 374.343339 -277.933647) (xy 374.372855 -277.972926) (xy 374.395688 -278.01643)
			(xy 374.411247 -278.063034) (xy 374.419128 -278.11153) (xy 374.419622 -278.136096) (xy 374.419128 -278.160662)
			(xy 374.411247 -278.209158) (xy 374.395688 -278.255762) (xy 374.372855 -278.299266) (xy 374.343339 -278.338545)
			(xy 374.307905 -278.37258) (xy 374.26747 -278.40049) (xy 374.223081 -278.421553) (xy 374.175889 -278.435222)
			(xy 374.127115 -278.441144) (xy 374.078023 -278.439166) (xy 374.029883 -278.429338) (xy 373.983944 -278.411916)
			(xy 373.941394 -278.38735) (xy 373.903336 -278.356276) (xy 373.870755 -278.3195) (xy 373.844496 -278.277974)
			(xy 373.825238 -278.232773) (xy 373.81348 -278.185069) (xy 373.809526 -278.136096) (xy 373.480076 -278.136096)
			(xy 373.479581 -278.160703) (xy 373.471686 -278.20928) (xy 373.456102 -278.255961) (xy 373.433231 -278.299538)
			(xy 373.403666 -278.338882) (xy 373.368173 -278.372974) (xy 373.32767 -278.40093) (xy 373.283208 -278.422028)
			(xy 373.235937 -278.43572) (xy 373.187082 -278.441652) (xy 373.137907 -278.439671) (xy 373.089688 -278.429827)
			(xy 373.043672 -278.412375) (xy 373.001051 -278.387768) (xy 372.96293 -278.356643) (xy 372.930295 -278.319806)
			(xy 372.903992 -278.27821) (xy 372.884701 -278.232934) (xy 372.872924 -278.18515) (xy 372.868964 -278.136096)
			(xy 371.599714 -278.136096) (xy 371.59922 -278.160662) (xy 371.591339 -278.209158) (xy 371.57578 -278.255762)
			(xy 371.552947 -278.299266) (xy 371.523431 -278.338545) (xy 371.487997 -278.37258) (xy 371.447562 -278.40049)
			(xy 371.403173 -278.421553) (xy 371.355981 -278.435222) (xy 371.307207 -278.441144) (xy 371.258115 -278.439166)
			(xy 371.209975 -278.429338) (xy 371.164036 -278.411916) (xy 371.121486 -278.38735) (xy 371.083428 -278.356276)
			(xy 371.050847 -278.3195) (xy 371.024588 -278.277974) (xy 371.00533 -278.232773) (xy 370.993572 -278.185069)
			(xy 370.989618 -278.136096) (xy 370.660168 -278.136096) (xy 370.659673 -278.160703) (xy 370.651778 -278.20928)
			(xy 370.636194 -278.255961) (xy 370.613323 -278.299538) (xy 370.583758 -278.338882) (xy 370.548265 -278.372974)
			(xy 370.507762 -278.40093) (xy 370.4633 -278.422028) (xy 370.416029 -278.43572) (xy 370.367174 -278.441652)
			(xy 370.317999 -278.439671) (xy 370.26978 -278.429827) (xy 370.223764 -278.412375) (xy 370.181143 -278.387768)
			(xy 370.143022 -278.356643) (xy 370.110387 -278.319806) (xy 370.084084 -278.27821) (xy 370.064793 -278.232934)
			(xy 370.053016 -278.18515) (xy 370.049056 -278.136096) (xy 368.779552 -278.136096) (xy 368.779058 -278.160662)
			(xy 368.771177 -278.209158) (xy 368.755618 -278.255762) (xy 368.732785 -278.299266) (xy 368.703269 -278.338545)
			(xy 368.667835 -278.37258) (xy 368.6274 -278.40049) (xy 368.583011 -278.421553) (xy 368.535819 -278.435222)
			(xy 368.487045 -278.441144) (xy 368.437953 -278.439166) (xy 368.389813 -278.429338) (xy 368.343874 -278.411916)
			(xy 368.301324 -278.38735) (xy 368.263266 -278.356276) (xy 368.230685 -278.3195) (xy 368.204426 -278.277974)
			(xy 368.185168 -278.232773) (xy 368.17341 -278.185069) (xy 368.169456 -278.136096) (xy 367.840006 -278.136096)
			(xy 367.839511 -278.160703) (xy 367.831616 -278.20928) (xy 367.816032 -278.255961) (xy 367.793161 -278.299538)
			(xy 367.763596 -278.338882) (xy 367.728103 -278.372974) (xy 367.6876 -278.40093) (xy 367.643138 -278.422028)
			(xy 367.595867 -278.43572) (xy 367.547012 -278.441652) (xy 367.497837 -278.439671) (xy 367.449618 -278.429827)
			(xy 367.403602 -278.412375) (xy 367.360981 -278.387768) (xy 367.32286 -278.356643) (xy 367.290225 -278.319806)
			(xy 367.263922 -278.27821) (xy 367.244631 -278.232934) (xy 367.232854 -278.18515) (xy 367.228894 -278.136096)
			(xy 365.959644 -278.136096) (xy 365.95915 -278.160662) (xy 365.951269 -278.209158) (xy 365.93571 -278.255762)
			(xy 365.912877 -278.299266) (xy 365.883361 -278.338545) (xy 365.847927 -278.37258) (xy 365.807492 -278.40049)
			(xy 365.763103 -278.421553) (xy 365.715911 -278.435222) (xy 365.667137 -278.441144) (xy 365.618045 -278.439166)
			(xy 365.569905 -278.429338) (xy 365.523966 -278.411916) (xy 365.481416 -278.38735) (xy 365.443358 -278.356276)
			(xy 365.410777 -278.3195) (xy 365.384518 -278.277974) (xy 365.36526 -278.232773) (xy 365.353502 -278.185069)
			(xy 365.349548 -278.136096) (xy 365.020098 -278.136096) (xy 365.019603 -278.160703) (xy 365.011708 -278.20928)
			(xy 364.996124 -278.255961) (xy 364.973253 -278.299538) (xy 364.943688 -278.338882) (xy 364.908195 -278.372974)
			(xy 364.867692 -278.40093) (xy 364.82323 -278.422028) (xy 364.775959 -278.43572) (xy 364.727104 -278.441652)
			(xy 364.677929 -278.439671) (xy 364.62971 -278.429827) (xy 364.583694 -278.412375) (xy 364.541073 -278.387768)
			(xy 364.502952 -278.356643) (xy 364.470317 -278.319806) (xy 364.444014 -278.27821) (xy 364.424723 -278.232934)
			(xy 364.412946 -278.18515) (xy 364.408986 -278.136096) (xy 355.625908 -278.136096) (xy 355.625414 -278.160662)
			(xy 355.617533 -278.209158) (xy 355.601974 -278.255762) (xy 355.579141 -278.299266) (xy 355.549625 -278.338545)
			(xy 355.514191 -278.37258) (xy 355.473756 -278.40049) (xy 355.429367 -278.421553) (xy 355.382175 -278.435222)
			(xy 355.333401 -278.441144) (xy 355.284309 -278.439166) (xy 355.236169 -278.429338) (xy 355.19023 -278.411916)
			(xy 355.14768 -278.38735) (xy 355.109622 -278.356276) (xy 355.077041 -278.3195) (xy 355.050782 -278.277974)
			(xy 355.031524 -278.232773) (xy 355.019766 -278.185069) (xy 355.015812 -278.136096) (xy 354.686362 -278.136096)
			(xy 354.685867 -278.160703) (xy 354.677972 -278.20928) (xy 354.662388 -278.255961) (xy 354.639517 -278.299538)
			(xy 354.609952 -278.338882) (xy 354.574459 -278.372974) (xy 354.533956 -278.40093) (xy 354.489494 -278.422028)
			(xy 354.442223 -278.43572) (xy 354.393368 -278.441652) (xy 354.344193 -278.439671) (xy 354.295974 -278.429827)
			(xy 354.249958 -278.412375) (xy 354.207337 -278.387768) (xy 354.169216 -278.356643) (xy 354.136581 -278.319806)
			(xy 354.110278 -278.27821) (xy 354.090987 -278.232934) (xy 354.07921 -278.18515) (xy 354.07525 -278.136096)
			(xy 352.806 -278.136096) (xy 352.805506 -278.160662) (xy 352.797625 -278.209158) (xy 352.782066 -278.255762)
			(xy 352.759233 -278.299266) (xy 352.729717 -278.338545) (xy 352.694283 -278.37258) (xy 352.653848 -278.40049)
			(xy 352.609459 -278.421553) (xy 352.562267 -278.435222) (xy 352.513493 -278.441144) (xy 352.464401 -278.439166)
			(xy 352.416261 -278.429338) (xy 352.370322 -278.411916) (xy 352.327772 -278.38735) (xy 352.289714 -278.356276)
			(xy 352.257133 -278.3195) (xy 352.230874 -278.277974) (xy 352.211616 -278.232773) (xy 352.199858 -278.185069)
			(xy 352.195904 -278.136096) (xy 351.866454 -278.136096) (xy 351.865959 -278.160703) (xy 351.858064 -278.20928)
			(xy 351.84248 -278.255961) (xy 351.819609 -278.299538) (xy 351.790044 -278.338882) (xy 351.754551 -278.372974)
			(xy 351.714048 -278.40093) (xy 351.669586 -278.422028) (xy 351.622315 -278.43572) (xy 351.57346 -278.441652)
			(xy 351.524285 -278.439671) (xy 351.476066 -278.429827) (xy 351.43005 -278.412375) (xy 351.387429 -278.387768)
			(xy 351.349308 -278.356643) (xy 351.316673 -278.319806) (xy 351.29037 -278.27821) (xy 351.271079 -278.232934)
			(xy 351.259302 -278.18515) (xy 351.255342 -278.136096) (xy 349.985838 -278.136096) (xy 349.985344 -278.160662)
			(xy 349.977463 -278.209158) (xy 349.961904 -278.255762) (xy 349.939071 -278.299266) (xy 349.909555 -278.338545)
			(xy 349.874121 -278.37258) (xy 349.833686 -278.40049) (xy 349.789297 -278.421553) (xy 349.742105 -278.435222)
			(xy 349.693331 -278.441144) (xy 349.644239 -278.439166) (xy 349.596099 -278.429338) (xy 349.55016 -278.411916)
			(xy 349.50761 -278.38735) (xy 349.469552 -278.356276) (xy 349.436971 -278.3195) (xy 349.410712 -278.277974)
			(xy 349.391454 -278.232773) (xy 349.379696 -278.185069) (xy 349.375742 -278.136096) (xy 349.046292 -278.136096)
			(xy 349.045797 -278.160703) (xy 349.037902 -278.20928) (xy 349.022318 -278.255961) (xy 348.999447 -278.299538)
			(xy 348.969882 -278.338882) (xy 348.934389 -278.372974) (xy 348.893886 -278.40093) (xy 348.849424 -278.422028)
			(xy 348.802153 -278.43572) (xy 348.753298 -278.441652) (xy 348.704123 -278.439671) (xy 348.655904 -278.429827)
			(xy 348.609888 -278.412375) (xy 348.567267 -278.387768) (xy 348.529146 -278.356643) (xy 348.496511 -278.319806)
			(xy 348.470208 -278.27821) (xy 348.450917 -278.232934) (xy 348.43914 -278.18515) (xy 348.43518 -278.136096)
			(xy 347.16593 -278.136096) (xy 347.165436 -278.160662) (xy 347.157555 -278.209158) (xy 347.141996 -278.255762)
			(xy 347.119163 -278.299266) (xy 347.089647 -278.338545) (xy 347.054213 -278.37258) (xy 347.013778 -278.40049)
			(xy 346.969389 -278.421553) (xy 346.922197 -278.435222) (xy 346.873423 -278.441144) (xy 346.824331 -278.439166)
			(xy 346.776191 -278.429338) (xy 346.730252 -278.411916) (xy 346.687702 -278.38735) (xy 346.649644 -278.356276)
			(xy 346.617063 -278.3195) (xy 346.590804 -278.277974) (xy 346.571546 -278.232773) (xy 346.559788 -278.185069)
			(xy 346.555834 -278.136096) (xy 346.226384 -278.136096) (xy 346.225889 -278.160703) (xy 346.217994 -278.20928)
			(xy 346.20241 -278.255961) (xy 346.179539 -278.299538) (xy 346.149974 -278.338882) (xy 346.114481 -278.372974)
			(xy 346.073978 -278.40093) (xy 346.029516 -278.422028) (xy 345.982245 -278.43572) (xy 345.93339 -278.441652)
			(xy 345.884215 -278.439671) (xy 345.835996 -278.429827) (xy 345.78998 -278.412375) (xy 345.747359 -278.387768)
			(xy 345.709238 -278.356643) (xy 345.676603 -278.319806) (xy 345.6503 -278.27821) (xy 345.631009 -278.232934)
			(xy 345.619232 -278.18515) (xy 345.615272 -278.136096) (xy 126.479549 -278.136096) (xy 126.479554 -278.13635)
			(xy 126.47906 -278.160916) (xy 126.471179 -278.209412) (xy 126.45562 -278.256016) (xy 126.432787 -278.29952)
			(xy 126.403271 -278.338799) (xy 126.367837 -278.372834) (xy 126.327402 -278.400744) (xy 126.283013 -278.421807)
			(xy 126.235821 -278.435476) (xy 126.187047 -278.441398) (xy 126.137955 -278.43942) (xy 126.089815 -278.429592)
			(xy 126.043876 -278.41217) (xy 126.001326 -278.387604) (xy 125.963268 -278.35653) (xy 125.930687 -278.319754)
			(xy 125.904428 -278.278228) (xy 125.88517 -278.233027) (xy 125.873412 -278.185323) (xy 125.869458 -278.13635)
			(xy 125.540008 -278.13635) (xy 125.539513 -278.160957) (xy 125.531618 -278.209534) (xy 125.516034 -278.256215)
			(xy 125.493163 -278.299792) (xy 125.463598 -278.339136) (xy 125.428105 -278.373228) (xy 125.387602 -278.401184)
			(xy 125.34314 -278.422282) (xy 125.295869 -278.435974) (xy 125.247014 -278.441906) (xy 125.197839 -278.439925)
			(xy 125.14962 -278.430081) (xy 125.103604 -278.412629) (xy 125.060983 -278.388022) (xy 125.022862 -278.356897)
			(xy 124.990227 -278.32006) (xy 124.963924 -278.278464) (xy 124.944633 -278.233188) (xy 124.932856 -278.185404)
			(xy 124.928896 -278.13635) (xy 123.659646 -278.13635) (xy 123.659152 -278.160916) (xy 123.651271 -278.209412)
			(xy 123.635712 -278.256016) (xy 123.612879 -278.29952) (xy 123.583363 -278.338799) (xy 123.547929 -278.372834)
			(xy 123.507494 -278.400744) (xy 123.463105 -278.421807) (xy 123.415913 -278.435476) (xy 123.367139 -278.441398)
			(xy 123.318047 -278.43942) (xy 123.269907 -278.429592) (xy 123.223968 -278.41217) (xy 123.181418 -278.387604)
			(xy 123.14336 -278.35653) (xy 123.110779 -278.319754) (xy 123.08452 -278.278228) (xy 123.065262 -278.233027)
			(xy 123.053504 -278.185323) (xy 123.04955 -278.13635) (xy 122.7201 -278.13635) (xy 122.719605 -278.160957)
			(xy 122.71171 -278.209534) (xy 122.696126 -278.256215) (xy 122.673255 -278.299792) (xy 122.64369 -278.339136)
			(xy 122.608197 -278.373228) (xy 122.567694 -278.401184) (xy 122.523232 -278.422282) (xy 122.475961 -278.435974)
			(xy 122.427106 -278.441906) (xy 122.377931 -278.439925) (xy 122.329712 -278.430081) (xy 122.283696 -278.412629)
			(xy 122.241075 -278.388022) (xy 122.202954 -278.356897) (xy 122.170319 -278.32006) (xy 122.144016 -278.278464)
			(xy 122.124725 -278.233188) (xy 122.112948 -278.185404) (xy 122.108988 -278.13635) (xy 120.839484 -278.13635)
			(xy 120.83899 -278.160916) (xy 120.831109 -278.209412) (xy 120.81555 -278.256016) (xy 120.792717 -278.29952)
			(xy 120.763201 -278.338799) (xy 120.727767 -278.372834) (xy 120.687332 -278.400744) (xy 120.642943 -278.421807)
			(xy 120.595751 -278.435476) (xy 120.546977 -278.441398) (xy 120.497885 -278.43942) (xy 120.449745 -278.429592)
			(xy 120.403806 -278.41217) (xy 120.361256 -278.387604) (xy 120.323198 -278.35653) (xy 120.290617 -278.319754)
			(xy 120.264358 -278.278228) (xy 120.2451 -278.233027) (xy 120.233342 -278.185323) (xy 120.229388 -278.13635)
			(xy 119.899938 -278.13635) (xy 119.899443 -278.160957) (xy 119.891548 -278.209534) (xy 119.875964 -278.256215)
			(xy 119.853093 -278.299792) (xy 119.823528 -278.339136) (xy 119.788035 -278.373228) (xy 119.747532 -278.401184)
			(xy 119.70307 -278.422282) (xy 119.655799 -278.435974) (xy 119.606944 -278.441906) (xy 119.557769 -278.439925)
			(xy 119.50955 -278.430081) (xy 119.463534 -278.412629) (xy 119.420913 -278.388022) (xy 119.382792 -278.356897)
			(xy 119.350157 -278.32006) (xy 119.323854 -278.278464) (xy 119.304563 -278.233188) (xy 119.292786 -278.185404)
			(xy 119.288826 -278.13635) (xy 118.019576 -278.13635) (xy 118.019082 -278.160916) (xy 118.011201 -278.209412)
			(xy 117.995642 -278.256016) (xy 117.972809 -278.29952) (xy 117.943293 -278.338799) (xy 117.907859 -278.372834)
			(xy 117.867424 -278.400744) (xy 117.823035 -278.421807) (xy 117.775843 -278.435476) (xy 117.727069 -278.441398)
			(xy 117.677977 -278.43942) (xy 117.629837 -278.429592) (xy 117.583898 -278.41217) (xy 117.541348 -278.387604)
			(xy 117.50329 -278.35653) (xy 117.470709 -278.319754) (xy 117.44445 -278.278228) (xy 117.425192 -278.233027)
			(xy 117.413434 -278.185323) (xy 117.40948 -278.13635) (xy 117.08003 -278.13635) (xy 117.079535 -278.160957)
			(xy 117.07164 -278.209534) (xy 117.056056 -278.256215) (xy 117.033185 -278.299792) (xy 117.00362 -278.339136)
			(xy 116.968127 -278.373228) (xy 116.927624 -278.401184) (xy 116.883162 -278.422282) (xy 116.835891 -278.435974)
			(xy 116.787036 -278.441906) (xy 116.737861 -278.439925) (xy 116.689642 -278.430081) (xy 116.643626 -278.412629)
			(xy 116.601005 -278.388022) (xy 116.562884 -278.356897) (xy 116.530249 -278.32006) (xy 116.503946 -278.278464)
			(xy 116.484655 -278.233188) (xy 116.472878 -278.185404) (xy 116.468918 -278.13635) (xy 107.68584 -278.13635)
			(xy 107.685346 -278.160916) (xy 107.677465 -278.209412) (xy 107.661906 -278.256016) (xy 107.639073 -278.29952)
			(xy 107.609557 -278.338799) (xy 107.574123 -278.372834) (xy 107.533688 -278.400744) (xy 107.489299 -278.421807)
			(xy 107.442107 -278.435476) (xy 107.393333 -278.441398) (xy 107.344241 -278.43942) (xy 107.296101 -278.429592)
			(xy 107.250162 -278.41217) (xy 107.207612 -278.387604) (xy 107.169554 -278.35653) (xy 107.136973 -278.319754)
			(xy 107.110714 -278.278228) (xy 107.091456 -278.233027) (xy 107.079698 -278.185323) (xy 107.075744 -278.13635)
			(xy 106.746294 -278.13635) (xy 106.745799 -278.160957) (xy 106.737904 -278.209534) (xy 106.72232 -278.256215)
			(xy 106.699449 -278.299792) (xy 106.669884 -278.339136) (xy 106.634391 -278.373228) (xy 106.593888 -278.401184)
			(xy 106.549426 -278.422282) (xy 106.502155 -278.435974) (xy 106.4533 -278.441906) (xy 106.404125 -278.439925)
			(xy 106.355906 -278.430081) (xy 106.30989 -278.412629) (xy 106.267269 -278.388022) (xy 106.229148 -278.356897)
			(xy 106.196513 -278.32006) (xy 106.17021 -278.278464) (xy 106.150919 -278.233188) (xy 106.139142 -278.185404)
			(xy 106.135182 -278.13635) (xy 104.865932 -278.13635) (xy 104.865438 -278.160916) (xy 104.857557 -278.209412)
			(xy 104.841998 -278.256016) (xy 104.819165 -278.29952) (xy 104.789649 -278.338799) (xy 104.754215 -278.372834)
			(xy 104.71378 -278.400744) (xy 104.669391 -278.421807) (xy 104.622199 -278.435476) (xy 104.573425 -278.441398)
			(xy 104.524333 -278.43942) (xy 104.476193 -278.429592) (xy 104.430254 -278.41217) (xy 104.387704 -278.387604)
			(xy 104.349646 -278.35653) (xy 104.317065 -278.319754) (xy 104.290806 -278.278228) (xy 104.271548 -278.233027)
			(xy 104.25979 -278.185323) (xy 104.255836 -278.13635) (xy 103.926386 -278.13635) (xy 103.925891 -278.160957)
			(xy 103.917996 -278.209534) (xy 103.902412 -278.256215) (xy 103.879541 -278.299792) (xy 103.849976 -278.339136)
			(xy 103.814483 -278.373228) (xy 103.77398 -278.401184) (xy 103.729518 -278.422282) (xy 103.682247 -278.435974)
			(xy 103.633392 -278.441906) (xy 103.584217 -278.439925) (xy 103.535998 -278.430081) (xy 103.489982 -278.412629)
			(xy 103.447361 -278.388022) (xy 103.40924 -278.356897) (xy 103.376605 -278.32006) (xy 103.350302 -278.278464)
			(xy 103.331011 -278.233188) (xy 103.319234 -278.185404) (xy 103.315274 -278.13635) (xy 102.04577 -278.13635)
			(xy 102.045276 -278.160916) (xy 102.037395 -278.209412) (xy 102.021836 -278.256016) (xy 101.999003 -278.29952)
			(xy 101.969487 -278.338799) (xy 101.934053 -278.372834) (xy 101.893618 -278.400744) (xy 101.849229 -278.421807)
			(xy 101.802037 -278.435476) (xy 101.753263 -278.441398) (xy 101.704171 -278.43942) (xy 101.656031 -278.429592)
			(xy 101.610092 -278.41217) (xy 101.567542 -278.387604) (xy 101.529484 -278.35653) (xy 101.496903 -278.319754)
			(xy 101.470644 -278.278228) (xy 101.451386 -278.233027) (xy 101.439628 -278.185323) (xy 101.435674 -278.13635)
			(xy 101.106224 -278.13635) (xy 101.105729 -278.160957) (xy 101.097834 -278.209534) (xy 101.08225 -278.256215)
			(xy 101.059379 -278.299792) (xy 101.029814 -278.339136) (xy 100.994321 -278.373228) (xy 100.953818 -278.401184)
			(xy 100.909356 -278.422282) (xy 100.862085 -278.435974) (xy 100.81323 -278.441906) (xy 100.764055 -278.439925)
			(xy 100.715836 -278.430081) (xy 100.66982 -278.412629) (xy 100.627199 -278.388022) (xy 100.589078 -278.356897)
			(xy 100.556443 -278.32006) (xy 100.53014 -278.278464) (xy 100.510849 -278.233188) (xy 100.499072 -278.185404)
			(xy 100.495112 -278.13635) (xy 99.225862 -278.13635) (xy 99.225368 -278.160916) (xy 99.217487 -278.209412)
			(xy 99.201928 -278.256016) (xy 99.179095 -278.29952) (xy 99.149579 -278.338799) (xy 99.114145 -278.372834)
			(xy 99.07371 -278.400744) (xy 99.029321 -278.421807) (xy 98.982129 -278.435476) (xy 98.933355 -278.441398)
			(xy 98.884263 -278.43942) (xy 98.836123 -278.429592) (xy 98.790184 -278.41217) (xy 98.747634 -278.387604)
			(xy 98.709576 -278.35653) (xy 98.676995 -278.319754) (xy 98.650736 -278.278228) (xy 98.631478 -278.233027)
			(xy 98.61972 -278.185323) (xy 98.615766 -278.13635) (xy 98.286316 -278.13635) (xy 98.285821 -278.160957)
			(xy 98.277926 -278.209534) (xy 98.262342 -278.256215) (xy 98.239471 -278.299792) (xy 98.209906 -278.339136)
			(xy 98.174413 -278.373228) (xy 98.13391 -278.401184) (xy 98.089448 -278.422282) (xy 98.042177 -278.435974)
			(xy 97.993322 -278.441906) (xy 97.944147 -278.439925) (xy 97.895928 -278.430081) (xy 97.849912 -278.412629)
			(xy 97.807291 -278.388022) (xy 97.76917 -278.356897) (xy 97.736535 -278.32006) (xy 97.710232 -278.278464)
			(xy 97.690941 -278.233188) (xy 97.679164 -278.185404) (xy 97.675204 -278.13635) (xy 2.509012 -278.13635)
			(xy 2.509012 -278.946356) (xy 108.48519 -278.946356) (xy 108.48915 -278.897302) (xy 108.500927 -278.849518)
			(xy 108.520218 -278.804242) (xy 108.546521 -278.762646) (xy 108.579156 -278.725809) (xy 108.617277 -278.694684)
			(xy 108.659898 -278.670077) (xy 108.705914 -278.652625) (xy 108.754133 -278.642781) (xy 108.803308 -278.6408)
			(xy 108.852163 -278.646732) (xy 108.899434 -278.660424) (xy 108.943896 -278.681522) (xy 108.984399 -278.709478)
			(xy 109.019892 -278.74357) (xy 109.049457 -278.782914) (xy 109.072328 -278.826491) (xy 109.087912 -278.873172)
			(xy 109.095807 -278.921749) (xy 109.096302 -278.946356) (xy 109.425752 -278.946356) (xy 109.429706 -278.897383)
			(xy 109.441464 -278.849679) (xy 109.460722 -278.804478) (xy 109.486981 -278.762952) (xy 109.519562 -278.726176)
			(xy 109.55762 -278.695102) (xy 109.60017 -278.670536) (xy 109.646109 -278.653114) (xy 109.694249 -278.643286)
			(xy 109.743341 -278.641308) (xy 109.792115 -278.64723) (xy 109.839307 -278.660899) (xy 109.883696 -278.681962)
			(xy 109.924131 -278.709872) (xy 109.959565 -278.743907) (xy 109.989081 -278.783186) (xy 110.011914 -278.82669)
			(xy 110.027473 -278.873294) (xy 110.035354 -278.92179) (xy 110.035848 -278.946356) (xy 114.11891 -278.946356)
			(xy 114.12287 -278.897302) (xy 114.134647 -278.849518) (xy 114.153938 -278.804242) (xy 114.180241 -278.762646)
			(xy 114.212876 -278.725809) (xy 114.250997 -278.694684) (xy 114.293618 -278.670077) (xy 114.339634 -278.652625)
			(xy 114.387853 -278.642781) (xy 114.437028 -278.6408) (xy 114.485883 -278.646732) (xy 114.533154 -278.660424)
			(xy 114.577616 -278.681522) (xy 114.618119 -278.709478) (xy 114.653612 -278.74357) (xy 114.683177 -278.782914)
			(xy 114.706048 -278.826491) (xy 114.721632 -278.873172) (xy 114.729527 -278.921749) (xy 114.730022 -278.946356)
			(xy 115.059472 -278.946356) (xy 115.063426 -278.897383) (xy 115.075184 -278.849679) (xy 115.094442 -278.804478)
			(xy 115.120701 -278.762952) (xy 115.153282 -278.726176) (xy 115.19134 -278.695102) (xy 115.23389 -278.670536)
			(xy 115.279829 -278.653114) (xy 115.327969 -278.643286) (xy 115.377061 -278.641308) (xy 115.425835 -278.64723)
			(xy 115.473027 -278.660899) (xy 115.517416 -278.681962) (xy 115.557851 -278.709872) (xy 115.593285 -278.743907)
			(xy 115.622801 -278.783186) (xy 115.645634 -278.82669) (xy 115.661193 -278.873294) (xy 115.669074 -278.92179)
			(xy 115.669563 -278.946102) (xy 356.425258 -278.946102) (xy 356.429218 -278.897048) (xy 356.440995 -278.849264)
			(xy 356.460286 -278.803988) (xy 356.486589 -278.762392) (xy 356.519224 -278.725555) (xy 356.557345 -278.69443)
			(xy 356.599966 -278.669823) (xy 356.645982 -278.652371) (xy 356.694201 -278.642527) (xy 356.743376 -278.640546)
			(xy 356.792231 -278.646478) (xy 356.839502 -278.66017) (xy 356.883964 -278.681268) (xy 356.924467 -278.709224)
			(xy 356.95996 -278.743316) (xy 356.989525 -278.78266) (xy 357.012396 -278.826237) (xy 357.02798 -278.872918)
			(xy 357.035875 -278.921495) (xy 357.03637 -278.946102) (xy 357.36582 -278.946102) (xy 357.369774 -278.897129)
			(xy 357.381532 -278.849425) (xy 357.40079 -278.804224) (xy 357.427049 -278.762698) (xy 357.45963 -278.725922)
			(xy 357.497688 -278.694848) (xy 357.540238 -278.670282) (xy 357.586177 -278.65286) (xy 357.634317 -278.643032)
			(xy 357.683409 -278.641054) (xy 357.732183 -278.646976) (xy 357.779375 -278.660645) (xy 357.823764 -278.681708)
			(xy 357.864199 -278.709618) (xy 357.899633 -278.743653) (xy 357.929149 -278.782932) (xy 357.951982 -278.826436)
			(xy 357.967541 -278.87304) (xy 357.975422 -278.921536) (xy 357.975916 -278.946102) (xy 362.058978 -278.946102)
			(xy 362.062938 -278.897048) (xy 362.074715 -278.849264) (xy 362.094006 -278.803988) (xy 362.120309 -278.762392)
			(xy 362.152944 -278.725555) (xy 362.191065 -278.69443) (xy 362.233686 -278.669823) (xy 362.279702 -278.652371)
			(xy 362.327921 -278.642527) (xy 362.377096 -278.640546) (xy 362.425951 -278.646478) (xy 362.473222 -278.66017)
			(xy 362.517684 -278.681268) (xy 362.558187 -278.709224) (xy 362.59368 -278.743316) (xy 362.623245 -278.78266)
			(xy 362.646116 -278.826237) (xy 362.6617 -278.872918) (xy 362.669595 -278.921495) (xy 362.67009 -278.946102)
			(xy 362.99954 -278.946102) (xy 363.003494 -278.897129) (xy 363.015252 -278.849425) (xy 363.03451 -278.804224)
			(xy 363.060769 -278.762698) (xy 363.09335 -278.725922) (xy 363.131408 -278.694848) (xy 363.173958 -278.670282)
			(xy 363.219897 -278.65286) (xy 363.268037 -278.643032) (xy 363.317129 -278.641054) (xy 363.365903 -278.646976)
			(xy 363.413095 -278.660645) (xy 363.457484 -278.681708) (xy 363.497919 -278.709618) (xy 363.533353 -278.743653)
			(xy 363.562869 -278.782932) (xy 363.585702 -278.826436) (xy 363.601261 -278.87304) (xy 363.609142 -278.921536)
			(xy 363.609636 -278.946102) (xy 363.609142 -278.970668) (xy 363.601261 -279.019164) (xy 363.585702 -279.065768)
			(xy 363.562869 -279.109272) (xy 363.533353 -279.148551) (xy 363.497919 -279.182586) (xy 363.457484 -279.210496)
			(xy 363.413095 -279.231559) (xy 363.365903 -279.245228) (xy 363.317129 -279.25115) (xy 363.268037 -279.249172)
			(xy 363.219897 -279.239344) (xy 363.173958 -279.221922) (xy 363.131408 -279.197356) (xy 363.09335 -279.166282)
			(xy 363.060769 -279.129506) (xy 363.03451 -279.08798) (xy 363.015252 -279.042779) (xy 363.003494 -278.995075)
			(xy 362.99954 -278.946102) (xy 362.67009 -278.946102) (xy 362.669595 -278.970709) (xy 362.6617 -279.019286)
			(xy 362.646116 -279.065967) (xy 362.623245 -279.109544) (xy 362.59368 -279.148888) (xy 362.558187 -279.18298)
			(xy 362.517684 -279.210936) (xy 362.473222 -279.232034) (xy 362.425951 -279.245726) (xy 362.377096 -279.251658)
			(xy 362.327921 -279.249677) (xy 362.279702 -279.239833) (xy 362.233686 -279.222381) (xy 362.191065 -279.197774)
			(xy 362.152944 -279.166649) (xy 362.120309 -279.129812) (xy 362.094006 -279.088216) (xy 362.074715 -279.04294)
			(xy 362.062938 -278.995156) (xy 362.058978 -278.946102) (xy 357.975916 -278.946102) (xy 357.975422 -278.970668)
			(xy 357.967541 -279.019164) (xy 357.951982 -279.065768) (xy 357.929149 -279.109272) (xy 357.899633 -279.148551)
			(xy 357.864199 -279.182586) (xy 357.823764 -279.210496) (xy 357.779375 -279.231559) (xy 357.732183 -279.245228)
			(xy 357.683409 -279.25115) (xy 357.634317 -279.249172) (xy 357.586177 -279.239344) (xy 357.540238 -279.221922)
			(xy 357.497688 -279.197356) (xy 357.45963 -279.166282) (xy 357.427049 -279.129506) (xy 357.40079 -279.08798)
			(xy 357.381532 -279.042779) (xy 357.369774 -278.995075) (xy 357.36582 -278.946102) (xy 357.03637 -278.946102)
			(xy 357.035875 -278.970709) (xy 357.02798 -279.019286) (xy 357.012396 -279.065967) (xy 356.989525 -279.109544)
			(xy 356.95996 -279.148888) (xy 356.924467 -279.18298) (xy 356.883964 -279.210936) (xy 356.839502 -279.232034)
			(xy 356.792231 -279.245726) (xy 356.743376 -279.251658) (xy 356.694201 -279.249677) (xy 356.645982 -279.239833)
			(xy 356.599966 -279.222381) (xy 356.557345 -279.197774) (xy 356.519224 -279.166649) (xy 356.486589 -279.129812)
			(xy 356.460286 -279.088216) (xy 356.440995 -279.04294) (xy 356.429218 -278.995156) (xy 356.425258 -278.946102)
			(xy 115.669563 -278.946102) (xy 115.669568 -278.946356) (xy 115.669074 -278.970922) (xy 115.661193 -279.019418)
			(xy 115.645634 -279.066022) (xy 115.622801 -279.109526) (xy 115.593285 -279.148805) (xy 115.557851 -279.18284)
			(xy 115.517416 -279.21075) (xy 115.473027 -279.231813) (xy 115.425835 -279.245482) (xy 115.377061 -279.251404)
			(xy 115.327969 -279.249426) (xy 115.279829 -279.239598) (xy 115.23389 -279.222176) (xy 115.19134 -279.19761)
			(xy 115.153282 -279.166536) (xy 115.120701 -279.12976) (xy 115.094442 -279.088234) (xy 115.075184 -279.043033)
			(xy 115.063426 -278.995329) (xy 115.059472 -278.946356) (xy 114.730022 -278.946356) (xy 114.729527 -278.970963)
			(xy 114.721632 -279.01954) (xy 114.706048 -279.066221) (xy 114.683177 -279.109798) (xy 114.653612 -279.149142)
			(xy 114.618119 -279.183234) (xy 114.577616 -279.21119) (xy 114.533154 -279.232288) (xy 114.485883 -279.24598)
			(xy 114.437028 -279.251912) (xy 114.387853 -279.249931) (xy 114.339634 -279.240087) (xy 114.293618 -279.222635)
			(xy 114.250997 -279.198028) (xy 114.212876 -279.166903) (xy 114.180241 -279.130066) (xy 114.153938 -279.08847)
			(xy 114.134647 -279.043194) (xy 114.12287 -278.99541) (xy 114.11891 -278.946356) (xy 110.035848 -278.946356)
			(xy 110.035354 -278.970922) (xy 110.027473 -279.019418) (xy 110.011914 -279.066022) (xy 109.989081 -279.109526)
			(xy 109.959565 -279.148805) (xy 109.924131 -279.18284) (xy 109.883696 -279.21075) (xy 109.839307 -279.231813)
			(xy 109.792115 -279.245482) (xy 109.743341 -279.251404) (xy 109.694249 -279.249426) (xy 109.646109 -279.239598)
			(xy 109.60017 -279.222176) (xy 109.55762 -279.19761) (xy 109.519562 -279.166536) (xy 109.486981 -279.12976)
			(xy 109.460722 -279.088234) (xy 109.441464 -279.043033) (xy 109.429706 -278.995329) (xy 109.425752 -278.946356)
			(xy 109.096302 -278.946356) (xy 109.095807 -278.970963) (xy 109.087912 -279.01954) (xy 109.072328 -279.066221)
			(xy 109.049457 -279.109798) (xy 109.019892 -279.149142) (xy 108.984399 -279.183234) (xy 108.943896 -279.21119)
			(xy 108.899434 -279.232288) (xy 108.852163 -279.24598) (xy 108.803308 -279.251912) (xy 108.754133 -279.249931)
			(xy 108.705914 -279.240087) (xy 108.659898 -279.222635) (xy 108.617277 -279.198028) (xy 108.579156 -279.166903)
			(xy 108.546521 -279.130066) (xy 108.520218 -279.08847) (xy 108.500927 -279.043194) (xy 108.48915 -278.99541)
			(xy 108.48519 -278.946356) (xy 2.509012 -278.946356) (xy 2.509012 -279.756362) (xy 106.135182 -279.756362)
			(xy 106.139142 -279.707308) (xy 106.150919 -279.659524) (xy 106.17021 -279.614248) (xy 106.196513 -279.572652)
			(xy 106.229148 -279.535815) (xy 106.267269 -279.50469) (xy 106.30989 -279.480083) (xy 106.355906 -279.462631)
			(xy 106.404125 -279.452787) (xy 106.4533 -279.450806) (xy 106.502155 -279.456738) (xy 106.549426 -279.47043)
			(xy 106.593888 -279.491528) (xy 106.634391 -279.519484) (xy 106.669884 -279.553576) (xy 106.699449 -279.59292)
			(xy 106.72232 -279.636497) (xy 106.737904 -279.683178) (xy 106.745799 -279.731755) (xy 106.746294 -279.756362)
			(xy 107.075744 -279.756362) (xy 107.079698 -279.707389) (xy 107.091456 -279.659685) (xy 107.110714 -279.614484)
			(xy 107.136973 -279.572958) (xy 107.169554 -279.536182) (xy 107.207612 -279.505108) (xy 107.250162 -279.480542)
			(xy 107.296101 -279.46312) (xy 107.344241 -279.453292) (xy 107.393333 -279.451314) (xy 107.442107 -279.457236)
			(xy 107.489299 -279.470905) (xy 107.533688 -279.491968) (xy 107.574123 -279.519878) (xy 107.609557 -279.553913)
			(xy 107.639073 -279.593192) (xy 107.661906 -279.636696) (xy 107.677465 -279.6833) (xy 107.685346 -279.731796)
			(xy 107.68584 -279.756362) (xy 116.468918 -279.756362) (xy 116.472878 -279.707308) (xy 116.484655 -279.659524)
			(xy 116.503946 -279.614248) (xy 116.530249 -279.572652) (xy 116.562884 -279.535815) (xy 116.601005 -279.50469)
			(xy 116.643626 -279.480083) (xy 116.689642 -279.462631) (xy 116.737861 -279.452787) (xy 116.787036 -279.450806)
			(xy 116.835891 -279.456738) (xy 116.883162 -279.47043) (xy 116.927624 -279.491528) (xy 116.968127 -279.519484)
			(xy 117.00362 -279.553576) (xy 117.033185 -279.59292) (xy 117.056056 -279.636497) (xy 117.07164 -279.683178)
			(xy 117.079535 -279.731755) (xy 117.08003 -279.756362) (xy 117.40948 -279.756362) (xy 117.413434 -279.707389)
			(xy 117.425192 -279.659685) (xy 117.44445 -279.614484) (xy 117.470709 -279.572958) (xy 117.50329 -279.536182)
			(xy 117.541348 -279.505108) (xy 117.583898 -279.480542) (xy 117.629837 -279.46312) (xy 117.677977 -279.453292)
			(xy 117.727069 -279.451314) (xy 117.775843 -279.457236) (xy 117.823035 -279.470905) (xy 117.867424 -279.491968)
			(xy 117.907859 -279.519878) (xy 117.943293 -279.553913) (xy 117.972809 -279.593192) (xy 117.995642 -279.636696)
			(xy 118.011201 -279.6833) (xy 118.019082 -279.731796) (xy 118.019571 -279.756108) (xy 354.07525 -279.756108)
			(xy 354.07921 -279.707054) (xy 354.090987 -279.65927) (xy 354.110278 -279.613994) (xy 354.136581 -279.572398)
			(xy 354.169216 -279.535561) (xy 354.207337 -279.504436) (xy 354.249958 -279.479829) (xy 354.295974 -279.462377)
			(xy 354.344193 -279.452533) (xy 354.393368 -279.450552) (xy 354.442223 -279.456484) (xy 354.489494 -279.470176)
			(xy 354.533956 -279.491274) (xy 354.574459 -279.51923) (xy 354.609952 -279.553322) (xy 354.639517 -279.592666)
			(xy 354.662388 -279.636243) (xy 354.677972 -279.682924) (xy 354.685867 -279.731501) (xy 354.686362 -279.756108)
			(xy 355.015812 -279.756108) (xy 355.019766 -279.707135) (xy 355.031524 -279.659431) (xy 355.050782 -279.61423)
			(xy 355.077041 -279.572704) (xy 355.109622 -279.535928) (xy 355.14768 -279.504854) (xy 355.19023 -279.480288)
			(xy 355.236169 -279.462866) (xy 355.284309 -279.453038) (xy 355.333401 -279.45106) (xy 355.382175 -279.456982)
			(xy 355.429367 -279.470651) (xy 355.473756 -279.491714) (xy 355.514191 -279.519624) (xy 355.549625 -279.553659)
			(xy 355.579141 -279.592938) (xy 355.601974 -279.636442) (xy 355.617533 -279.683046) (xy 355.625414 -279.731542)
			(xy 355.625908 -279.756108) (xy 364.408986 -279.756108) (xy 364.412946 -279.707054) (xy 364.424723 -279.65927)
			(xy 364.444014 -279.613994) (xy 364.470317 -279.572398) (xy 364.502952 -279.535561) (xy 364.541073 -279.504436)
			(xy 364.583694 -279.479829) (xy 364.62971 -279.462377) (xy 364.677929 -279.452533) (xy 364.727104 -279.450552)
			(xy 364.775959 -279.456484) (xy 364.82323 -279.470176) (xy 364.867692 -279.491274) (xy 364.908195 -279.51923)
			(xy 364.943688 -279.553322) (xy 364.973253 -279.592666) (xy 364.996124 -279.636243) (xy 365.011708 -279.682924)
			(xy 365.019603 -279.731501) (xy 365.020098 -279.756108) (xy 365.349548 -279.756108) (xy 365.353502 -279.707135)
			(xy 365.36526 -279.659431) (xy 365.384518 -279.61423) (xy 365.410777 -279.572704) (xy 365.443358 -279.535928)
			(xy 365.481416 -279.504854) (xy 365.523966 -279.480288) (xy 365.569905 -279.462866) (xy 365.618045 -279.453038)
			(xy 365.667137 -279.45106) (xy 365.715911 -279.456982) (xy 365.763103 -279.470651) (xy 365.807492 -279.491714)
			(xy 365.847927 -279.519624) (xy 365.883361 -279.553659) (xy 365.912877 -279.592938) (xy 365.93571 -279.636442)
			(xy 365.951269 -279.683046) (xy 365.95915 -279.731542) (xy 365.959644 -279.756108) (xy 365.95915 -279.780674)
			(xy 365.951269 -279.82917) (xy 365.93571 -279.875774) (xy 365.912877 -279.919278) (xy 365.883361 -279.958557)
			(xy 365.847927 -279.992592) (xy 365.807492 -280.020502) (xy 365.763103 -280.041565) (xy 365.715911 -280.055234)
			(xy 365.667137 -280.061156) (xy 365.618045 -280.059178) (xy 365.569905 -280.04935) (xy 365.523966 -280.031928)
			(xy 365.481416 -280.007362) (xy 365.443358 -279.976288) (xy 365.410777 -279.939512) (xy 365.384518 -279.897986)
			(xy 365.36526 -279.852785) (xy 365.353502 -279.805081) (xy 365.349548 -279.756108) (xy 365.020098 -279.756108)
			(xy 365.019603 -279.780715) (xy 365.011708 -279.829292) (xy 364.996124 -279.875973) (xy 364.973253 -279.91955)
			(xy 364.943688 -279.958894) (xy 364.908195 -279.992986) (xy 364.867692 -280.020942) (xy 364.82323 -280.04204)
			(xy 364.775959 -280.055732) (xy 364.727104 -280.061664) (xy 364.677929 -280.059683) (xy 364.62971 -280.049839)
			(xy 364.583694 -280.032387) (xy 364.541073 -280.00778) (xy 364.502952 -279.976655) (xy 364.470317 -279.939818)
			(xy 364.444014 -279.898222) (xy 364.424723 -279.852946) (xy 364.412946 -279.805162) (xy 364.408986 -279.756108)
			(xy 355.625908 -279.756108) (xy 355.625414 -279.780674) (xy 355.617533 -279.82917) (xy 355.601974 -279.875774)
			(xy 355.579141 -279.919278) (xy 355.549625 -279.958557) (xy 355.514191 -279.992592) (xy 355.473756 -280.020502)
			(xy 355.429367 -280.041565) (xy 355.382175 -280.055234) (xy 355.333401 -280.061156) (xy 355.284309 -280.059178)
			(xy 355.236169 -280.04935) (xy 355.19023 -280.031928) (xy 355.14768 -280.007362) (xy 355.109622 -279.976288)
			(xy 355.077041 -279.939512) (xy 355.050782 -279.897986) (xy 355.031524 -279.852785) (xy 355.019766 -279.805081)
			(xy 355.015812 -279.756108) (xy 354.686362 -279.756108) (xy 354.685867 -279.780715) (xy 354.677972 -279.829292)
			(xy 354.662388 -279.875973) (xy 354.639517 -279.91955) (xy 354.609952 -279.958894) (xy 354.574459 -279.992986)
			(xy 354.533956 -280.020942) (xy 354.489494 -280.04204) (xy 354.442223 -280.055732) (xy 354.393368 -280.061664)
			(xy 354.344193 -280.059683) (xy 354.295974 -280.049839) (xy 354.249958 -280.032387) (xy 354.207337 -280.00778)
			(xy 354.169216 -279.976655) (xy 354.136581 -279.939818) (xy 354.110278 -279.898222) (xy 354.090987 -279.852946)
			(xy 354.07921 -279.805162) (xy 354.07525 -279.756108) (xy 118.019571 -279.756108) (xy 118.019576 -279.756362)
			(xy 118.019082 -279.780928) (xy 118.011201 -279.829424) (xy 117.995642 -279.876028) (xy 117.972809 -279.919532)
			(xy 117.943293 -279.958811) (xy 117.907859 -279.992846) (xy 117.867424 -280.020756) (xy 117.823035 -280.041819)
			(xy 117.775843 -280.055488) (xy 117.727069 -280.06141) (xy 117.677977 -280.059432) (xy 117.629837 -280.049604)
			(xy 117.583898 -280.032182) (xy 117.541348 -280.007616) (xy 117.50329 -279.976542) (xy 117.470709 -279.939766)
			(xy 117.44445 -279.89824) (xy 117.425192 -279.853039) (xy 117.413434 -279.805335) (xy 117.40948 -279.756362)
			(xy 117.08003 -279.756362) (xy 117.079535 -279.780969) (xy 117.07164 -279.829546) (xy 117.056056 -279.876227)
			(xy 117.033185 -279.919804) (xy 117.00362 -279.959148) (xy 116.968127 -279.99324) (xy 116.927624 -280.021196)
			(xy 116.883162 -280.042294) (xy 116.835891 -280.055986) (xy 116.787036 -280.061918) (xy 116.737861 -280.059937)
			(xy 116.689642 -280.050093) (xy 116.643626 -280.032641) (xy 116.601005 -280.008034) (xy 116.562884 -279.976909)
			(xy 116.530249 -279.940072) (xy 116.503946 -279.898476) (xy 116.484655 -279.8532) (xy 116.472878 -279.805416)
			(xy 116.468918 -279.756362) (xy 107.68584 -279.756362) (xy 107.685346 -279.780928) (xy 107.677465 -279.829424)
			(xy 107.661906 -279.876028) (xy 107.639073 -279.919532) (xy 107.609557 -279.958811) (xy 107.574123 -279.992846)
			(xy 107.533688 -280.020756) (xy 107.489299 -280.041819) (xy 107.442107 -280.055488) (xy 107.393333 -280.06141)
			(xy 107.344241 -280.059432) (xy 107.296101 -280.049604) (xy 107.250162 -280.032182) (xy 107.207612 -280.007616)
			(xy 107.169554 -279.976542) (xy 107.136973 -279.939766) (xy 107.110714 -279.89824) (xy 107.091456 -279.853039)
			(xy 107.079698 -279.805335) (xy 107.075744 -279.756362) (xy 106.746294 -279.756362) (xy 106.745799 -279.780969)
			(xy 106.737904 -279.829546) (xy 106.72232 -279.876227) (xy 106.699449 -279.919804) (xy 106.669884 -279.959148)
			(xy 106.634391 -279.99324) (xy 106.593888 -280.021196) (xy 106.549426 -280.042294) (xy 106.502155 -280.055986)
			(xy 106.4533 -280.061918) (xy 106.404125 -280.059937) (xy 106.355906 -280.050093) (xy 106.30989 -280.032641)
			(xy 106.267269 -280.008034) (xy 106.229148 -279.976909) (xy 106.196513 -279.940072) (xy 106.17021 -279.898476)
			(xy 106.150919 -279.8532) (xy 106.139142 -279.805416) (xy 106.135182 -279.756362) (xy 2.509012 -279.756362)
			(xy 2.509012 -300.146974) (xy 340.219284 -300.146974) (xy 340.219284 -299.130974) (xy 340.21977 -299.103723)
			(xy 340.227526 -299.049775) (xy 340.242881 -298.99748) (xy 340.265523 -298.947903) (xy 340.294989 -298.902053)
			(xy 340.33068 -298.860862) (xy 340.371871 -298.825171) (xy 340.417721 -298.795705) (xy 340.467298 -298.773063)
			(xy 340.519593 -298.757708) (xy 340.573541 -298.749952) (xy 340.628043 -298.749952) (xy 340.681991 -298.757708)
			(xy 340.734286 -298.773063) (xy 340.783863 -298.795705) (xy 340.829713 -298.825171) (xy 340.870904 -298.860862)
			(xy 340.906595 -298.902053) (xy 340.936061 -298.947903) (xy 340.958703 -298.99748) (xy 340.974058 -299.049775)
			(xy 340.981814 -299.103723) (xy 340.9823 -299.130974) (xy 340.9823 -300.146974) (xy 340.981814 -300.174225)
			(xy 340.974058 -300.228173) (xy 340.958703 -300.280468) (xy 340.936061 -300.330045) (xy 340.906595 -300.375895)
			(xy 340.870904 -300.417086) (xy 340.829713 -300.452777) (xy 340.783863 -300.482243) (xy 340.734286 -300.504885)
			(xy 340.681991 -300.52024) (xy 340.628043 -300.527996) (xy 340.573541 -300.527996) (xy 340.519593 -300.52024)
			(xy 340.467298 -300.504885) (xy 340.417721 -300.482243) (xy 340.371871 -300.452777) (xy 340.33068 -300.417086)
			(xy 340.294989 -300.375895) (xy 340.265523 -300.330045) (xy 340.242881 -300.280468) (xy 340.227526 -300.228173)
			(xy 340.21977 -300.174225) (xy 340.219284 -300.146974) (xy 2.509012 -300.146974) (xy 2.509012 -304.780442)
			(xy 78.81214 -304.780442) (xy 78.81617 -304.638107) (xy 78.828245 -304.496227) (xy 78.848328 -304.355259)
			(xy 78.876355 -304.215652) (xy 78.912235 -304.077854) (xy 78.955853 -303.942307) (xy 79.00707 -303.809445)
			(xy 79.065721 -303.679693) (xy 79.131619 -303.553467) (xy 79.204553 -303.431171) (xy 79.28429 -303.313198)
			(xy 79.370572 -303.199925) (xy 79.463125 -303.091714) (xy 79.561652 -302.988913) (xy 79.665837 -302.891851)
			(xy 79.775346 -302.800839) (xy 79.889829 -302.716167) (xy 80.008919 -302.638109) (xy 80.132234 -302.566913)
			(xy 80.25938 -302.502807) (xy 80.389949 -302.445998) (xy 80.523523 -302.396666) (xy 80.659674 -302.35497)
			(xy 80.797965 -302.321044) (xy 80.937955 -302.294996) (xy 81.079194 -302.27691) (xy 81.22123 -302.266843)
			(xy 81.363608 -302.264828) (xy 81.505872 -302.270871) (xy 81.647566 -302.284953) (xy 81.788236 -302.307029)
			(xy 81.927433 -302.337029) (xy 82.064709 -302.374855) (xy 82.199625 -302.420387) (xy 82.331749 -302.473478)
			(xy 82.460658 -302.53396) (xy 82.585939 -302.601638) (xy 82.70719 -302.676295) (xy 82.824023 -302.757693)
			(xy 82.936064 -302.84557) (xy 83.042954 -302.939645) (xy 83.144351 -303.039617) (xy 83.239929 -303.145165)
			(xy 83.329383 -303.255951) (xy 83.412425 -303.37162) (xy 83.488791 -303.491803) (xy 83.558235 -303.616113)
			(xy 83.620535 -303.744154) (xy 83.675491 -303.875513) (xy 83.722928 -304.009772) (xy 83.762692 -304.146499)
			(xy 83.794658 -304.285257) (xy 83.818723 -304.425601) (xy 83.834809 -304.567082) (xy 83.842864 -304.709246)
			(xy 83.843368 -304.780442) (xy 140.011408 -304.780442) (xy 140.015438 -304.638078) (xy 140.027516 -304.49617)
			(xy 140.047604 -304.355173) (xy 140.075636 -304.215538) (xy 140.111523 -304.077712) (xy 140.15515 -303.942138)
			(xy 140.206377 -303.809249) (xy 140.26504 -303.67947) (xy 140.330952 -303.553219) (xy 140.403901 -303.430899)
			(xy 140.483653 -303.312902) (xy 140.569953 -303.199606) (xy 140.662525 -303.091373) (xy 140.761071 -302.988551)
			(xy 140.865277 -302.89147) (xy 140.974809 -302.800439) (xy 141.089315 -302.715751) (xy 141.208429 -302.637676)
			(xy 141.331769 -302.566466) (xy 141.45894 -302.502347) (xy 141.589536 -302.445526) (xy 141.723136 -302.396185)
			(xy 141.859315 -302.35448) (xy 141.997634 -302.320547) (xy 142.137652 -302.294494) (xy 142.278919 -302.276404)
			(xy 142.420984 -302.266335) (xy 142.563391 -302.26432) (xy 142.705684 -302.270364) (xy 142.847406 -302.28445)
			(xy 142.988105 -302.30653) (xy 143.12733 -302.336535) (xy 143.264634 -302.374369) (xy 143.399577 -302.41991)
			(xy 143.531728 -302.473013) (xy 143.660663 -302.533507) (xy 143.785969 -302.601198) (xy 143.907245 -302.675871)
			(xy 144.024101 -302.757285) (xy 144.136165 -302.845179) (xy 144.243077 -302.939273) (xy 144.344494 -303.039265)
			(xy 144.440091 -303.144834) (xy 144.529563 -303.255643) (xy 144.612622 -303.371336) (xy 144.689003 -303.491543)
			(xy 144.758461 -303.615878) (xy 144.820774 -303.743944) (xy 144.875741 -303.875331) (xy 144.923187 -304.009616)
			(xy 144.96296 -304.146371) (xy 144.994932 -304.285157) (xy 145.019002 -304.425529) (xy 145.035091 -304.567039)
			(xy 145.043148 -304.709231) (xy 145.04365 -304.780188) (xy 326.752208 -304.780188) (xy 326.756238 -304.637853)
			(xy 326.768313 -304.495973) (xy 326.788396 -304.355005) (xy 326.816423 -304.215398) (xy 326.852303 -304.0776)
			(xy 326.895921 -303.942053) (xy 326.947138 -303.809191) (xy 327.005789 -303.679439) (xy 327.071687 -303.553213)
			(xy 327.144621 -303.430917) (xy 327.224358 -303.312944) (xy 327.31064 -303.199671) (xy 327.403193 -303.09146)
			(xy 327.50172 -302.988659) (xy 327.605905 -302.891597) (xy 327.715414 -302.800585) (xy 327.829897 -302.715913)
			(xy 327.948987 -302.637855) (xy 328.072302 -302.566659) (xy 328.199448 -302.502553) (xy 328.330017 -302.445744)
			(xy 328.463591 -302.396412) (xy 328.599742 -302.354716) (xy 328.738033 -302.32079) (xy 328.878023 -302.294742)
			(xy 329.019262 -302.276656) (xy 329.161298 -302.266589) (xy 329.303676 -302.264574) (xy 329.44594 -302.270617)
			(xy 329.587634 -302.284699) (xy 329.728304 -302.306775) (xy 329.867501 -302.336775) (xy 330.004777 -302.374601)
			(xy 330.139693 -302.420133) (xy 330.271817 -302.473224) (xy 330.400726 -302.533706) (xy 330.526007 -302.601384)
			(xy 330.647258 -302.676041) (xy 330.764091 -302.757439) (xy 330.876132 -302.845316) (xy 330.983022 -302.939391)
			(xy 331.084419 -303.039363) (xy 331.179997 -303.144911) (xy 331.269451 -303.255697) (xy 331.352493 -303.371366)
			(xy 331.428859 -303.491549) (xy 331.498303 -303.615859) (xy 331.560603 -303.7439) (xy 331.615559 -303.875259)
			(xy 331.662996 -304.009518) (xy 331.70276 -304.146245) (xy 331.734726 -304.285003) (xy 331.758791 -304.425347)
			(xy 331.774877 -304.566828) (xy 331.781353 -304.681128) (xy 333.795116 -304.681128) (xy 333.795116 -303.817528)
			(xy 333.795602 -303.790259) (xy 333.803364 -303.736275) (xy 333.818729 -303.683945) (xy 333.841386 -303.634335)
			(xy 333.870872 -303.588454) (xy 333.906587 -303.547237) (xy 333.947804 -303.511522) (xy 333.993685 -303.482036)
			(xy 334.043295 -303.459379) (xy 334.095625 -303.444014) (xy 334.149609 -303.436252) (xy 334.204147 -303.436252)
			(xy 334.258131 -303.444014) (xy 334.310461 -303.459379) (xy 334.360071 -303.482036) (xy 334.405952 -303.511522)
			(xy 334.447169 -303.547237) (xy 334.482884 -303.588454) (xy 334.51237 -303.634335) (xy 334.535027 -303.683945)
			(xy 334.550392 -303.736275) (xy 334.558154 -303.790259) (xy 334.55864 -303.817528) (xy 334.55864 -304.681128)
			(xy 334.558154 -304.708397) (xy 334.550392 -304.762381) (xy 334.545164 -304.780188) (xy 387.951476 -304.780188)
			(xy 387.955506 -304.637824) (xy 387.967584 -304.495916) (xy 387.987672 -304.354919) (xy 388.015704 -304.215284)
			(xy 388.051591 -304.077458) (xy 388.095218 -303.941884) (xy 388.146445 -303.808995) (xy 388.205108 -303.679216)
			(xy 388.27102 -303.552965) (xy 388.343969 -303.430645) (xy 388.423721 -303.312648) (xy 388.510021 -303.199352)
			(xy 388.602593 -303.091119) (xy 388.701139 -302.988297) (xy 388.805345 -302.891216) (xy 388.914877 -302.800185)
			(xy 389.029383 -302.715497) (xy 389.148497 -302.637422) (xy 389.271837 -302.566212) (xy 389.399008 -302.502093)
			(xy 389.529604 -302.445272) (xy 389.663204 -302.395931) (xy 389.799383 -302.354226) (xy 389.937702 -302.320293)
			(xy 390.07772 -302.29424) (xy 390.218987 -302.27615) (xy 390.361052 -302.266081) (xy 390.503459 -302.264066)
			(xy 390.645752 -302.27011) (xy 390.787474 -302.284196) (xy 390.928173 -302.306276) (xy 391.067398 -302.336281)
			(xy 391.204702 -302.374115) (xy 391.339645 -302.419656) (xy 391.471796 -302.472759) (xy 391.600731 -302.533253)
			(xy 391.726037 -302.600944) (xy 391.847313 -302.675617) (xy 391.964169 -302.757031) (xy 392.076233 -302.844925)
			(xy 392.183145 -302.939019) (xy 392.284562 -303.039011) (xy 392.380159 -303.14458) (xy 392.469631 -303.255389)
			(xy 392.55269 -303.371082) (xy 392.629071 -303.491289) (xy 392.698529 -303.615624) (xy 392.760842 -303.74369)
			(xy 392.815809 -303.875077) (xy 392.863255 -304.009362) (xy 392.903028 -304.146117) (xy 392.935 -304.284903)
			(xy 392.95907 -304.425275) (xy 392.975159 -304.566785) (xy 392.983216 -304.708977) (xy 392.98372 -304.780188)
			(xy 392.983216 -304.851399) (xy 392.975159 -304.993591) (xy 392.95907 -305.135101) (xy 392.935 -305.275473)
			(xy 392.903028 -305.414259) (xy 392.863255 -305.551014) (xy 392.815809 -305.685299) (xy 392.760842 -305.816686)
			(xy 392.698529 -305.944752) (xy 392.629071 -306.069087) (xy 392.55269 -306.189294) (xy 392.469631 -306.304987)
			(xy 392.380159 -306.415796) (xy 392.284562 -306.521365) (xy 392.183145 -306.621357) (xy 392.076233 -306.715451)
			(xy 391.964169 -306.803345) (xy 391.847313 -306.884759) (xy 391.726037 -306.959432) (xy 391.600731 -307.027123)
			(xy 391.471796 -307.087617) (xy 391.339645 -307.14072) (xy 391.204702 -307.186261) (xy 391.067398 -307.224095)
			(xy 390.928173 -307.2541) (xy 390.787474 -307.27618) (xy 390.645752 -307.290266) (xy 390.503459 -307.29631)
			(xy 390.361052 -307.294295) (xy 390.218987 -307.284226) (xy 390.07772 -307.266136) (xy 389.937702 -307.240083)
			(xy 389.799383 -307.20615) (xy 389.663204 -307.164445) (xy 389.529604 -307.115104) (xy 389.399008 -307.058283)
			(xy 389.271837 -306.994164) (xy 389.148497 -306.922954) (xy 389.029383 -306.844879) (xy 388.914877 -306.760191)
			(xy 388.805345 -306.66916) (xy 388.701139 -306.572079) (xy 388.602593 -306.469257) (xy 388.510021 -306.361024)
			(xy 388.423721 -306.247728) (xy 388.343969 -306.129731) (xy 388.27102 -306.007411) (xy 388.205108 -305.88116)
			(xy 388.146445 -305.751381) (xy 388.095218 -305.618492) (xy 388.051591 -305.482918) (xy 388.015704 -305.345092)
			(xy 387.987672 -305.205457) (xy 387.967584 -305.06446) (xy 387.955506 -304.922552) (xy 387.951476 -304.780188)
			(xy 334.545164 -304.780188) (xy 334.535027 -304.814711) (xy 334.51237 -304.864321) (xy 334.482884 -304.910202)
			(xy 334.447169 -304.951419) (xy 334.405952 -304.987134) (xy 334.360071 -305.01662) (xy 334.310461 -305.039277)
			(xy 334.258131 -305.054642) (xy 334.204147 -305.062404) (xy 334.149609 -305.062404) (xy 334.095625 -305.054642)
			(xy 334.043295 -305.039277) (xy 333.993685 -305.01662) (xy 333.947804 -304.987134) (xy 333.906587 -304.951419)
			(xy 333.870872 -304.910202) (xy 333.841386 -304.864321) (xy 333.818729 -304.814711) (xy 333.803364 -304.762381)
			(xy 333.795602 -304.708397) (xy 333.795116 -304.681128) (xy 331.781353 -304.681128) (xy 331.782932 -304.708992)
			(xy 331.783436 -304.780188) (xy 331.782932 -304.851384) (xy 331.774877 -304.993548) (xy 331.758791 -305.135029)
			(xy 331.734726 -305.275373) (xy 331.70276 -305.414131) (xy 331.662996 -305.550858) (xy 331.615559 -305.685117)
			(xy 331.560603 -305.816476) (xy 331.498303 -305.944517) (xy 331.428859 -306.068827) (xy 331.352493 -306.18901)
			(xy 331.269451 -306.304679) (xy 331.179997 -306.415465) (xy 331.164149 -306.432966) (xy 340.495636 -306.432966)
			(xy 340.495636 -305.569366) (xy 340.496122 -305.542115) (xy 340.503878 -305.488167) (xy 340.519233 -305.435872)
			(xy 340.541875 -305.386295) (xy 340.571341 -305.340445) (xy 340.607032 -305.299254) (xy 340.648223 -305.263563)
			(xy 340.694073 -305.234097) (xy 340.74365 -305.211455) (xy 340.795945 -305.1961) (xy 340.849893 -305.188344)
			(xy 340.904395 -305.188344) (xy 340.958343 -305.1961) (xy 341.010638 -305.211455) (xy 341.060215 -305.234097)
			(xy 341.106065 -305.263563) (xy 341.147256 -305.299254) (xy 341.182947 -305.340445) (xy 341.212413 -305.386295)
			(xy 341.235055 -305.435872) (xy 341.25041 -305.488167) (xy 341.258166 -305.542115) (xy 341.258652 -305.569366)
			(xy 341.258652 -306.432966) (xy 341.258166 -306.460217) (xy 341.25041 -306.514165) (xy 341.235055 -306.56646)
			(xy 341.212413 -306.616037) (xy 341.182947 -306.661887) (xy 341.147256 -306.703078) (xy 341.106065 -306.738769)
			(xy 341.060215 -306.768235) (xy 341.010638 -306.790877) (xy 340.958343 -306.806232) (xy 340.904395 -306.813988)
			(xy 340.849893 -306.813988) (xy 340.795945 -306.806232) (xy 340.74365 -306.790877) (xy 340.694073 -306.768235)
			(xy 340.648223 -306.738769) (xy 340.607032 -306.703078) (xy 340.571341 -306.661887) (xy 340.541875 -306.616037)
			(xy 340.519233 -306.56646) (xy 340.503878 -306.514165) (xy 340.496122 -306.460217) (xy 340.495636 -306.432966)
			(xy 331.164149 -306.432966) (xy 331.084419 -306.521013) (xy 330.983022 -306.620985) (xy 330.876132 -306.71506)
			(xy 330.764091 -306.802937) (xy 330.647258 -306.884335) (xy 330.526007 -306.958992) (xy 330.400726 -307.02667)
			(xy 330.271817 -307.087152) (xy 330.139693 -307.140243) (xy 330.004777 -307.185775) (xy 329.867501 -307.223601)
			(xy 329.728304 -307.253601) (xy 329.587634 -307.275677) (xy 329.44594 -307.289759) (xy 329.303676 -307.295802)
			(xy 329.161298 -307.293787) (xy 329.019262 -307.28372) (xy 328.878023 -307.265634) (xy 328.738033 -307.239586)
			(xy 328.599742 -307.20566) (xy 328.463591 -307.163964) (xy 328.330017 -307.114632) (xy 328.199448 -307.057823)
			(xy 328.072302 -306.993717) (xy 327.948987 -306.922521) (xy 327.829897 -306.844463) (xy 327.715414 -306.759791)
			(xy 327.605905 -306.668779) (xy 327.50172 -306.571717) (xy 327.403193 -306.468916) (xy 327.31064 -306.360705)
			(xy 327.224358 -306.247432) (xy 327.144621 -306.129459) (xy 327.071687 -306.007163) (xy 327.005789 -305.880937)
			(xy 326.947138 -305.751185) (xy 326.895921 -305.618323) (xy 326.852303 -305.482776) (xy 326.816423 -305.344978)
			(xy 326.788396 -305.205371) (xy 326.768313 -305.064403) (xy 326.756238 -304.922523) (xy 326.752208 -304.780188)
			(xy 145.04365 -304.780188) (xy 145.043652 -304.780442) (xy 145.043148 -304.851653) (xy 145.035091 -304.993845)
			(xy 145.019002 -305.135355) (xy 144.994932 -305.275727) (xy 144.96296 -305.414513) (xy 144.923187 -305.551268)
			(xy 144.875741 -305.685553) (xy 144.820774 -305.81694) (xy 144.758461 -305.945006) (xy 144.689003 -306.069341)
			(xy 144.612622 -306.189548) (xy 144.529563 -306.305241) (xy 144.440091 -306.41605) (xy 144.344494 -306.521619)
			(xy 144.243077 -306.621611) (xy 144.136165 -306.715705) (xy 144.024101 -306.803599) (xy 143.907245 -306.885013)
			(xy 143.785969 -306.959686) (xy 143.660663 -307.027377) (xy 143.531728 -307.087871) (xy 143.399577 -307.140974)
			(xy 143.264634 -307.186515) (xy 143.12733 -307.224349) (xy 142.988105 -307.254354) (xy 142.847406 -307.276434)
			(xy 142.705684 -307.29052) (xy 142.563391 -307.296564) (xy 142.420984 -307.294549) (xy 142.278919 -307.28448)
			(xy 142.137652 -307.26639) (xy 141.997634 -307.240337) (xy 141.859315 -307.206404) (xy 141.723136 -307.164699)
			(xy 141.589536 -307.115358) (xy 141.45894 -307.058537) (xy 141.331769 -306.994418) (xy 141.208429 -306.923208)
			(xy 141.089315 -306.845133) (xy 140.974809 -306.760445) (xy 140.865277 -306.669414) (xy 140.761071 -306.572333)
			(xy 140.662525 -306.469511) (xy 140.569953 -306.361278) (xy 140.483653 -306.247982) (xy 140.403901 -306.129985)
			(xy 140.330952 -306.007665) (xy 140.26504 -305.881414) (xy 140.206377 -305.751635) (xy 140.15515 -305.618746)
			(xy 140.111523 -305.483172) (xy 140.075636 -305.345346) (xy 140.047604 -305.205711) (xy 140.027516 -305.064714)
			(xy 140.015438 -304.922806) (xy 140.011408 -304.780442) (xy 83.843368 -304.780442) (xy 83.842864 -304.851638)
			(xy 83.834809 -304.993802) (xy 83.818723 -305.135283) (xy 83.794658 -305.275627) (xy 83.762692 -305.414385)
			(xy 83.722928 -305.551112) (xy 83.675491 -305.685371) (xy 83.620535 -305.81673) (xy 83.558235 -305.944771)
			(xy 83.488791 -306.069081) (xy 83.412425 -306.189264) (xy 83.329383 -306.304933) (xy 83.239929 -306.415719)
			(xy 83.144351 -306.521267) (xy 83.042954 -306.621239) (xy 82.936064 -306.715314) (xy 82.824023 -306.803191)
			(xy 82.70719 -306.884589) (xy 82.585939 -306.959246) (xy 82.460658 -307.026924) (xy 82.331749 -307.087406)
			(xy 82.199625 -307.140497) (xy 82.064709 -307.186029) (xy 81.927433 -307.223855) (xy 81.788236 -307.253855)
			(xy 81.647566 -307.275931) (xy 81.505872 -307.290013) (xy 81.363608 -307.296056) (xy 81.22123 -307.294041)
			(xy 81.079194 -307.283974) (xy 80.937955 -307.265888) (xy 80.797965 -307.23984) (xy 80.659674 -307.205914)
			(xy 80.523523 -307.164218) (xy 80.389949 -307.114886) (xy 80.25938 -307.058077) (xy 80.132234 -306.993971)
			(xy 80.008919 -306.922775) (xy 79.889829 -306.844717) (xy 79.775346 -306.760045) (xy 79.665837 -306.669033)
			(xy 79.561652 -306.571971) (xy 79.463125 -306.46917) (xy 79.370572 -306.360959) (xy 79.28429 -306.247686)
			(xy 79.204553 -306.129713) (xy 79.131619 -306.007417) (xy 79.065721 -305.881191) (xy 79.00707 -305.751439)
			(xy 78.955853 -305.618577) (xy 78.912235 -305.48303) (xy 78.876355 -305.345232) (xy 78.848328 -305.205625)
			(xy 78.828245 -305.064657) (xy 78.81617 -304.922777) (xy 78.81214 -304.780442) (xy 2.509012 -304.780442)
			(xy 2.509012 -309.504588) (xy 79.192628 -309.504588) (xy 79.192628 -308.640988) (xy 79.193114 -308.613737)
			(xy 79.20087 -308.559789) (xy 79.216225 -308.507494) (xy 79.238867 -308.457917) (xy 79.268333 -308.412067)
			(xy 79.304024 -308.370876) (xy 79.345215 -308.335185) (xy 79.391065 -308.305719) (xy 79.440642 -308.283077)
			(xy 79.492937 -308.267722) (xy 79.546885 -308.259966) (xy 79.601387 -308.259966) (xy 79.655335 -308.267722)
			(xy 79.70763 -308.283077) (xy 79.757207 -308.305719) (xy 79.803057 -308.335185) (xy 79.844248 -308.370876)
			(xy 79.879939 -308.412067) (xy 79.909405 -308.457917) (xy 79.92811 -308.498873) (xy 93.275072 -308.498873)
			(xy 93.275072 -308.444327) (xy 93.282834 -308.390335) (xy 93.298202 -308.337998) (xy 93.320862 -308.288381)
			(xy 93.350352 -308.242493) (xy 93.386073 -308.20127) (xy 93.427297 -308.16555) (xy 93.473184 -308.13606)
			(xy 93.522802 -308.113401) (xy 93.575139 -308.098034) (xy 93.629131 -308.090271) (xy 93.656404 -308.089808)
			(xy 94.520004 -308.089808) (xy 94.547271 -308.090355) (xy 94.60125 -308.098116) (xy 94.653575 -308.113481)
			(xy 94.703181 -308.136135) (xy 94.749058 -308.165619) (xy 94.790271 -308.201331) (xy 94.825983 -308.242546)
			(xy 94.855467 -308.288423) (xy 94.878121 -308.338029) (xy 94.893485 -308.390354) (xy 94.901246 -308.444333)
			(xy 94.901246 -308.498867) (xy 94.893485 -308.552846) (xy 94.878121 -308.605171) (xy 94.855467 -308.654777)
			(xy 94.825983 -308.700654) (xy 94.790271 -308.741869) (xy 94.749058 -308.777581) (xy 94.703181 -308.807065)
			(xy 94.653575 -308.829719) (xy 94.60125 -308.845084) (xy 94.547271 -308.852845) (xy 94.520004 -308.853332)
			(xy 93.656404 -308.853332) (xy 93.629131 -308.852929) (xy 93.575139 -308.845166) (xy 93.522802 -308.829799)
			(xy 93.473184 -308.80714) (xy 93.427297 -308.77765) (xy 93.386073 -308.74193) (xy 93.350352 -308.700707)
			(xy 93.320862 -308.654819) (xy 93.298202 -308.605202) (xy 93.282834 -308.552865) (xy 93.275072 -308.498873)
			(xy 79.92811 -308.498873) (xy 79.932047 -308.507494) (xy 79.947402 -308.559789) (xy 79.955158 -308.613737)
			(xy 79.955644 -308.640988) (xy 79.955644 -309.303166) (xy 341.51824 -309.303166) (xy 341.51824 -308.439566)
			(xy 341.518726 -308.412297) (xy 341.526488 -308.358313) (xy 341.541853 -308.305983) (xy 341.56451 -308.256373)
			(xy 341.593996 -308.210492) (xy 341.629711 -308.169275) (xy 341.670928 -308.13356) (xy 341.716809 -308.104074)
			(xy 341.766419 -308.081417) (xy 341.818749 -308.066052) (xy 341.872733 -308.05829) (xy 341.927271 -308.05829)
			(xy 341.981255 -308.066052) (xy 342.033585 -308.081417) (xy 342.083195 -308.104074) (xy 342.129076 -308.13356)
			(xy 342.170293 -308.169275) (xy 342.206008 -308.210492) (xy 342.235494 -308.256373) (xy 342.258151 -308.305983)
			(xy 342.273516 -308.358313) (xy 342.281278 -308.412297) (xy 342.281764 -308.439566) (xy 342.281764 -309.303166)
			(xy 342.281278 -309.330435) (xy 342.273516 -309.384419) (xy 342.258151 -309.436749) (xy 342.235494 -309.486359)
			(xy 342.206008 -309.53224) (xy 342.170293 -309.573457) (xy 342.129076 -309.609172) (xy 342.083195 -309.638658)
			(xy 342.033585 -309.661315) (xy 341.981255 -309.67668) (xy 341.927271 -309.684442) (xy 341.872733 -309.684442)
			(xy 341.818749 -309.67668) (xy 341.766419 -309.661315) (xy 341.716809 -309.638658) (xy 341.670928 -309.609172)
			(xy 341.629711 -309.573457) (xy 341.593996 -309.53224) (xy 341.56451 -309.486359) (xy 341.541853 -309.436749)
			(xy 341.526488 -309.384419) (xy 341.518726 -309.330435) (xy 341.51824 -309.303166) (xy 79.955644 -309.303166)
			(xy 79.955644 -309.504588) (xy 79.955158 -309.531839) (xy 79.947402 -309.585787) (xy 79.932047 -309.638082)
			(xy 79.909405 -309.687659) (xy 79.879939 -309.733509) (xy 79.844248 -309.7747) (xy 79.803057 -309.810391)
			(xy 79.757207 -309.839857) (xy 79.70763 -309.862499) (xy 79.655335 -309.877854) (xy 79.601387 -309.88561)
			(xy 79.546885 -309.88561) (xy 79.492937 -309.877854) (xy 79.440642 -309.862499) (xy 79.391065 -309.839857)
			(xy 79.345215 -309.810391) (xy 79.304024 -309.7747) (xy 79.268333 -309.733509) (xy 79.238867 -309.687659)
			(xy 79.216225 -309.638082) (xy 79.20087 -309.585787) (xy 79.193114 -309.531839) (xy 79.192628 -309.504588)
			(xy 2.509012 -309.504588) (xy 2.509012 -310.603646) (xy 98.925888 -310.603646) (xy 98.925888 -309.740046)
			(xy 98.926374 -309.712795) (xy 98.93413 -309.658847) (xy 98.949485 -309.606552) (xy 98.972127 -309.556975)
			(xy 99.001593 -309.511125) (xy 99.037284 -309.469934) (xy 99.078475 -309.434243) (xy 99.124325 -309.404777)
			(xy 99.173902 -309.382135) (xy 99.226197 -309.36678) (xy 99.280145 -309.359024) (xy 99.334647 -309.359024)
			(xy 99.388595 -309.36678) (xy 99.44089 -309.382135) (xy 99.490467 -309.404777) (xy 99.536317 -309.434243)
			(xy 99.577508 -309.469934) (xy 99.613199 -309.511125) (xy 99.642665 -309.556975) (xy 99.665307 -309.606552)
			(xy 99.680662 -309.658847) (xy 99.688418 -309.712795) (xy 99.688904 -309.740046) (xy 99.688904 -310.603646)
			(xy 99.688418 -310.630897) (xy 99.680662 -310.684845) (xy 99.665307 -310.73714) (xy 99.642665 -310.786717)
			(xy 99.613199 -310.832567) (xy 99.577508 -310.873758) (xy 99.536317 -310.909449) (xy 99.490467 -310.938915)
			(xy 99.44089 -310.961557) (xy 99.388595 -310.976912) (xy 99.334647 -310.984668) (xy 99.280145 -310.984668)
			(xy 99.226197 -310.976912) (xy 99.173902 -310.961557) (xy 99.124325 -310.938915) (xy 99.078475 -310.909449)
			(xy 99.037284 -310.873758) (xy 99.001593 -310.832567) (xy 98.972127 -310.786717) (xy 98.949485 -310.73714)
			(xy 98.93413 -310.684845) (xy 98.926374 -310.630897) (xy 98.925888 -310.603646) (xy 2.509012 -310.603646)
			(xy 2.509012 -311.513728) (xy 347.772228 -311.513728) (xy 347.772228 -310.650128) (xy 347.772714 -310.622859)
			(xy 347.780476 -310.568875) (xy 347.795841 -310.516545) (xy 347.818498 -310.466935) (xy 347.847984 -310.421054)
			(xy 347.883699 -310.379837) (xy 347.924916 -310.344122) (xy 347.970797 -310.314636) (xy 348.020407 -310.291979)
			(xy 348.072737 -310.276614) (xy 348.126721 -310.268852) (xy 348.181259 -310.268852) (xy 348.235243 -310.276614)
			(xy 348.287573 -310.291979) (xy 348.337183 -310.314636) (xy 348.383064 -310.344122) (xy 348.424281 -310.379837)
			(xy 348.459996 -310.421054) (xy 348.489482 -310.466935) (xy 348.512139 -310.516545) (xy 348.527504 -310.568875)
			(xy 348.535266 -310.622859) (xy 348.535752 -310.650128) (xy 348.535752 -311.513728) (xy 348.535266 -311.540997)
			(xy 348.527504 -311.594981) (xy 348.512139 -311.647311) (xy 348.489482 -311.696921) (xy 348.459996 -311.742802)
			(xy 348.424281 -311.784019) (xy 348.383064 -311.819734) (xy 348.337183 -311.84922) (xy 348.287573 -311.871877)
			(xy 348.235243 -311.887242) (xy 348.181259 -311.895004) (xy 348.126721 -311.895004) (xy 348.072737 -311.887242)
			(xy 348.020407 -311.871877) (xy 347.970797 -311.84922) (xy 347.924916 -311.819734) (xy 347.883699 -311.784019)
			(xy 347.847984 -311.742802) (xy 347.818498 -311.696921) (xy 347.795841 -311.647311) (xy 347.780476 -311.594981)
			(xy 347.772714 -311.540997) (xy 347.772228 -311.513728) (xy 2.509012 -311.513728) (xy 2.509012 -314.997338)
			(xy 98.330512 -314.997338) (xy 98.330512 -314.133738) (xy 98.330998 -314.106487) (xy 98.338754 -314.052539)
			(xy 98.354109 -314.000244) (xy 98.376751 -313.950667) (xy 98.406217 -313.904817) (xy 98.441908 -313.863626)
			(xy 98.483099 -313.827935) (xy 98.528949 -313.798469) (xy 98.578526 -313.775827) (xy 98.630821 -313.760472)
			(xy 98.684769 -313.752716) (xy 98.739271 -313.752716) (xy 98.793219 -313.760472) (xy 98.845514 -313.775827)
			(xy 98.895091 -313.798469) (xy 98.940941 -313.827935) (xy 98.982132 -313.863626) (xy 99.017823 -313.904817)
			(xy 99.047289 -313.950667) (xy 99.069931 -314.000244) (xy 99.085286 -314.052539) (xy 99.093042 -314.106487)
			(xy 99.093528 -314.133738) (xy 99.093528 -314.997338) (xy 99.093042 -315.024589) (xy 99.085286 -315.078537)
			(xy 99.069931 -315.130832) (xy 99.047289 -315.180409) (xy 99.017823 -315.226259) (xy 98.982132 -315.26745)
			(xy 98.940941 -315.303141) (xy 98.895091 -315.332607) (xy 98.845514 -315.355249) (xy 98.793219 -315.370604)
			(xy 98.739271 -315.37836) (xy 98.684769 -315.37836) (xy 98.630821 -315.370604) (xy 98.578526 -315.355249)
			(xy 98.528949 -315.332607) (xy 98.483099 -315.303141) (xy 98.441908 -315.26745) (xy 98.406217 -315.226259)
			(xy 98.376751 -315.180409) (xy 98.354109 -315.130832) (xy 98.338754 -315.078537) (xy 98.330998 -315.024589)
			(xy 98.330512 -314.997338) (xy 2.509012 -314.997338) (xy 2.509012 -336.9884) (xy 70.218517 -336.9884)
			(xy 70.222508 -336.904617) (xy 70.234446 -336.821593) (xy 70.254221 -336.74008) (xy 70.281655 -336.660815)
			(xy 70.3165 -336.584518) (xy 70.35844 -336.511878) (xy 70.407095 -336.443554) (xy 70.462025 -336.380164)
			(xy 70.522731 -336.322283) (xy 70.588664 -336.270435) (xy 70.659228 -336.225089) (xy 70.733783 -336.186656)
			(xy 70.811653 -336.155484) (xy 70.892134 -336.131855) (xy 70.974497 -336.115984) (xy 71.057995 -336.108014)
			(xy 71.099934 -336.107532) (xy 71.137123 -336.107938) (xy 71.211236 -336.114223) (xy 71.284556 -336.126727)
			(xy 71.356562 -336.145363) (xy 71.39178 -336.157316) (xy 71.399977 -336.15983) (xy 71.417111 -336.15983)
			(xy 71.425308 -336.157316) (xy 71.460496 -336.145371) (xy 71.532436 -336.126725) (xy 71.605692 -336.114215)
			(xy 71.679742 -336.107929) (xy 71.7169 -336.107532) (xy 71.717408 -336.107532) (xy 71.748142 -336.108294)
			(xy 71.757646 -336.056715) (xy 71.787316 -335.956115) (xy 71.807324 -335.907634) (xy 71.810983 -335.897931)
			(xy 71.810971 -335.877211) (xy 71.807324 -335.867502) (xy 71.790219 -335.826242) (xy 71.763427 -335.741032)
			(xy 71.74539 -335.653549) (xy 71.736293 -335.564691) (xy 71.735696 -335.52003) (xy 71.735696 -335.519268)
			(xy 71.736195 -335.477343) (xy 71.744165 -335.393872) (xy 71.760034 -335.311537) (xy 71.783657 -335.231083)
			(xy 71.814821 -335.153239) (xy 71.853244 -335.078709) (xy 71.898577 -335.00817) (xy 71.95041 -334.942259)
			(xy 72.008273 -334.881573) (xy 72.071643 -334.826663) (xy 72.139946 -334.778025) (xy 72.212563 -334.7361)
			(xy 72.288836 -334.701267) (xy 72.368075 -334.673842) (xy 72.449561 -334.654073) (xy 72.532558 -334.64214)
			(xy 72.616314 -334.638151) (xy 72.70007 -334.64214) (xy 72.783067 -334.654073) (xy 72.864553 -334.673842)
			(xy 72.943792 -334.701267) (xy 73.020065 -334.7361) (xy 73.092682 -334.778025) (xy 73.160985 -334.826663)
			(xy 73.224355 -334.881573) (xy 73.282218 -334.942259) (xy 73.334051 -335.00817) (xy 73.379384 -335.078709)
			(xy 73.417807 -335.153239) (xy 73.448971 -335.231083) (xy 73.472594 -335.311537) (xy 73.488463 -335.393872)
			(xy 73.496433 -335.477343) (xy 73.496932 -335.519268) (xy 73.496932 -335.52003) (xy 73.496371 -335.564694)
			(xy 73.487295 -335.653559) (xy 73.46926 -335.741047) (xy 73.442452 -335.826257) (xy 73.425304 -335.867502)
			(xy 73.421681 -335.877216) (xy 73.421669 -335.897926) (xy 73.425304 -335.907634) (xy 73.441139 -335.945575)
			(xy 73.466487 -336.02379) (xy 73.484436 -336.104027) (xy 73.494829 -336.185587) (xy 73.496678 -336.226658)
			(xy 73.496932 -336.24012) (xy 73.51141 -336.263234) (xy 73.61301 -336.31759) (xy 73.639934 -336.316828)
			(xy 73.651618 -336.309462) (xy 73.686811 -336.288202) (xy 73.76042 -336.251553) (xy 73.837094 -336.221845)
			(xy 73.91618 -336.199333) (xy 73.997005 -336.184209) (xy 74.07888 -336.1766) (xy 74.119994 -336.176112)
			(xy 74.161107 -336.176619) (xy 74.242983 -336.184205) (xy 74.32381 -336.199313) (xy 74.402898 -336.221815)
			(xy 74.479573 -336.251518) (xy 74.553179 -336.288168) (xy 74.623091 -336.331454) (xy 74.68871 -336.381006)
			(xy 74.749477 -336.4364) (xy 74.804874 -336.497166) (xy 74.854428 -336.562783) (xy 74.897716 -336.632693)
			(xy 74.934369 -336.706298) (xy 74.964075 -336.782971) (xy 74.986579 -336.862059) (xy 75.001691 -336.942885)
			(xy 75.005252 -336.9813) (xy 78.574105 -336.9813) (xy 78.578096 -336.897517) (xy 78.590033 -336.814493)
			(xy 78.609809 -336.732979) (xy 78.637243 -336.653715) (xy 78.672087 -336.577417) (xy 78.714027 -336.504776)
			(xy 78.762681 -336.436452) (xy 78.81761 -336.373061) (xy 78.878316 -336.31518) (xy 78.94425 -336.26333)
			(xy 79.014813 -336.217984) (xy 79.089367 -336.179549) (xy 79.167237 -336.148376) (xy 79.247718 -336.124747)
			(xy 79.330081 -336.108874) (xy 79.413579 -336.100902) (xy 79.455518 -336.10042) (xy 79.492708 -336.100802)
			(xy 79.566821 -336.107094) (xy 79.640141 -336.119606) (xy 79.712146 -336.138248) (xy 79.747364 -336.150204)
			(xy 79.755561 -336.152718) (xy 79.772695 -336.152718) (xy 79.780892 -336.150204) (xy 79.816103 -336.138226)
			(xy 79.888108 -336.119576) (xy 79.961431 -336.107072) (xy 80.035547 -336.100804) (xy 80.072738 -336.10042)
			(xy 80.10906 -336.101182) (xy 80.115245 -336.066241) (xy 80.132513 -335.997409) (xy 80.155273 -335.930194)
			(xy 80.169004 -335.897474) (xy 80.172641 -335.887764) (xy 80.172644 -335.86705) (xy 80.169004 -335.857342)
			(xy 80.151879 -335.81609) (xy 80.125092 -335.730877) (xy 80.107061 -335.643392) (xy 80.09797 -335.554532)
			(xy 80.097376 -335.50987) (xy 80.097376 -335.509108) (xy 80.097875 -335.467183) (xy 80.105845 -335.383712)
			(xy 80.121714 -335.301377) (xy 80.145337 -335.220923) (xy 80.176501 -335.143079) (xy 80.214924 -335.068549)
			(xy 80.260257 -334.99801) (xy 80.31209 -334.932099) (xy 80.369953 -334.871413) (xy 80.433323 -334.816503)
			(xy 80.501626 -334.767865) (xy 80.574243 -334.72594) (xy 80.650516 -334.691107) (xy 80.729755 -334.663682)
			(xy 80.811241 -334.643913) (xy 80.894238 -334.63198) (xy 80.977994 -334.627991) (xy 81.06175 -334.63198)
			(xy 81.144747 -334.643913) (xy 81.226233 -334.663682) (xy 81.305472 -334.691107) (xy 81.381745 -334.72594)
			(xy 81.454362 -334.767865) (xy 81.522665 -334.816503) (xy 81.586035 -334.871413) (xy 81.643898 -334.932099)
			(xy 81.695731 -334.99801) (xy 81.741064 -335.068549) (xy 81.779487 -335.143079) (xy 81.810651 -335.220923)
			(xy 81.834274 -335.301377) (xy 81.850143 -335.383712) (xy 81.858113 -335.467183) (xy 81.858612 -335.509108)
			(xy 81.858612 -335.50987) (xy 81.858066 -335.554534) (xy 81.848986 -335.6434) (xy 81.830947 -335.730888)
			(xy 81.804134 -335.816098) (xy 81.786984 -335.857342) (xy 81.783338 -335.867049) (xy 81.783341 -335.887765)
			(xy 81.786984 -335.897474) (xy 81.802748 -335.935334) (xy 81.827987 -336.013369) (xy 81.845871 -336.093411)
			(xy 81.856247 -336.174768) (xy 81.858104 -336.215736) (xy 81.858828 -336.22455) (xy 81.865419 -336.240944)
			(xy 81.877182 -336.254128) (xy 81.884774 -336.258662) (xy 81.973928 -336.306922) (xy 82.000852 -336.30616)
			(xy 82.012536 -336.299048) (xy 82.047432 -336.278305) (xy 82.120306 -336.242523) (xy 82.19614 -336.213534)
			(xy 82.2743 -336.191579) (xy 82.354137 -336.176843) (xy 82.434985 -336.169448) (xy 82.475578 -336.169)
			(xy 82.516691 -336.169534) (xy 82.598566 -336.177119) (xy 82.679391 -336.192225) (xy 82.758479 -336.214725)
			(xy 82.835153 -336.244426) (xy 82.908759 -336.281075) (xy 82.97867 -336.324359) (xy 83.044289 -336.373909)
			(xy 83.105056 -336.429302) (xy 83.160453 -336.490065) (xy 83.210007 -336.555681) (xy 83.253296 -336.625589)
			(xy 83.28995 -336.699193) (xy 83.319656 -336.775864) (xy 83.342161 -336.85495) (xy 83.357273 -336.935775)
			(xy 83.360149 -336.9668) (xy 86.931981 -336.9668) (xy 86.935971 -336.883042) (xy 86.947905 -336.800043)
			(xy 86.967674 -336.718554) (xy 86.9951 -336.639313) (xy 87.029935 -336.563039) (xy 87.071862 -336.490421)
			(xy 87.120503 -336.422117) (xy 87.175416 -336.358746) (xy 87.236104 -336.300883) (xy 87.302018 -336.24905)
			(xy 87.37256 -336.203717) (xy 87.447092 -336.165296) (xy 87.52494 -336.134133) (xy 87.605396 -336.110512)
			(xy 87.687734 -336.094645) (xy 87.771208 -336.086677) (xy 87.813134 -336.086196) (xy 87.81415 -336.086196)
			(xy 87.851207 -336.086587) (xy 87.925057 -336.092856) (xy 87.998119 -336.105302) (xy 88.069879 -336.123838)
			(xy 88.10498 -336.135726) (xy 88.113177 -336.13824) (xy 88.130311 -336.13824) (xy 88.138508 -336.135726)
			(xy 88.173727 -336.123789) (xy 88.245736 -336.1052) (xy 88.319058 -336.092757) (xy 88.393169 -336.086549)
			(xy 88.430354 -336.086196) (xy 88.454992 -336.08645) (xy 88.464629 -336.040549) (xy 88.49238 -335.950951)
			(xy 88.510364 -335.907634) (xy 88.514021 -335.89793) (xy 88.514009 -335.877211) (xy 88.510364 -335.867502)
			(xy 88.493256 -335.826243) (xy 88.466465 -335.741033) (xy 88.448429 -335.65355) (xy 88.439333 -335.564691)
			(xy 88.438736 -335.52003) (xy 88.438736 -335.519268) (xy 88.439235 -335.477343) (xy 88.447205 -335.393872)
			(xy 88.463074 -335.311537) (xy 88.486697 -335.231083) (xy 88.517861 -335.153239) (xy 88.556284 -335.078709)
			(xy 88.601617 -335.00817) (xy 88.65345 -334.942259) (xy 88.711313 -334.881573) (xy 88.774683 -334.826663)
			(xy 88.842986 -334.778025) (xy 88.915603 -334.7361) (xy 88.991876 -334.701267) (xy 89.071115 -334.673842)
			(xy 89.152601 -334.654073) (xy 89.235598 -334.64214) (xy 89.319354 -334.638151) (xy 89.40311 -334.64214)
			(xy 89.486107 -334.654073) (xy 89.567593 -334.673842) (xy 89.646832 -334.701267) (xy 89.723105 -334.7361)
			(xy 89.795722 -334.778025) (xy 89.864025 -334.826663) (xy 89.927395 -334.881573) (xy 89.985258 -334.942259)
			(xy 90.037091 -335.00817) (xy 90.082424 -335.078709) (xy 90.120847 -335.153239) (xy 90.152011 -335.231083)
			(xy 90.175634 -335.311537) (xy 90.191503 -335.393872) (xy 90.199473 -335.477343) (xy 90.199972 -335.519268)
			(xy 90.199972 -335.52003) (xy 90.199408 -335.564694) (xy 90.190332 -335.653559) (xy 90.172298 -335.741047)
			(xy 90.145491 -335.826257) (xy 90.128344 -335.867502) (xy 90.124724 -335.877216) (xy 90.124712 -335.897925)
			(xy 90.128344 -335.907634) (xy 90.14352 -335.944017) (xy 90.168055 -336.018939) (xy 90.185802 -336.095753)
			(xy 90.196619 -336.173844) (xy 90.198956 -336.213196) (xy 90.198956 -336.21345) (xy 90.199799 -336.222253)
			(xy 90.206694 -336.238523) (xy 90.218709 -336.251482) (xy 90.226388 -336.255868) (xy 90.316812 -336.302604)
			(xy 90.343482 -336.301334) (xy 90.355166 -336.293968) (xy 90.390883 -336.271832) (xy 90.465707 -336.233583)
			(xy 90.543804 -336.20256) (xy 90.624479 -336.17904) (xy 90.707013 -336.163233) (xy 90.790669 -336.155279)
			(xy 90.832686 -336.154776) (xy 90.833194 -336.154776) (xy 90.874302 -336.155218) (xy 90.956167 -336.162803)
			(xy 91.036983 -336.177907) (xy 91.116061 -336.200402) (xy 91.192727 -336.230097) (xy 91.266326 -336.266738)
			(xy 91.336231 -336.310013) (xy 91.401845 -336.359552) (xy 91.46261 -336.414933) (xy 91.518006 -336.475684)
			(xy 91.567562 -336.541286) (xy 91.610854 -336.61118) (xy 91.647513 -336.68477) (xy 91.677227 -336.761428)
			(xy 91.699742 -336.840501) (xy 91.714867 -336.921313) (xy 91.722471 -337.003176) (xy 91.722641 -337.0176)
			(xy 95.263181 -337.0176) (xy 95.267171 -336.933842) (xy 95.279105 -336.850843) (xy 95.298874 -336.769354)
			(xy 95.3263 -336.690113) (xy 95.361135 -336.613839) (xy 95.403062 -336.541221) (xy 95.451703 -336.472917)
			(xy 95.506616 -336.409546) (xy 95.567304 -336.351683) (xy 95.633218 -336.29985) (xy 95.70376 -336.254517)
			(xy 95.778292 -336.216096) (xy 95.85614 -336.184933) (xy 95.936596 -336.161312) (xy 96.018934 -336.145445)
			(xy 96.102408 -336.137477) (xy 96.144334 -336.136996) (xy 96.14535 -336.136996) (xy 96.182407 -336.137387)
			(xy 96.256257 -336.143656) (xy 96.329319 -336.156102) (xy 96.401079 -336.174638) (xy 96.43618 -336.186526)
			(xy 96.444377 -336.18904) (xy 96.461511 -336.18904) (xy 96.469708 -336.186526) (xy 96.504897 -336.174599)
			(xy 96.576843 -336.15602) (xy 96.650101 -336.143577) (xy 96.724146 -336.137359) (xy 96.7613 -336.136996)
			(xy 96.761808 -336.136996) (xy 96.796352 -336.137504) (xy 96.805918 -336.09484) (xy 96.832381 -336.0115)
			(xy 96.849184 -335.971134) (xy 96.852845 -335.961431) (xy 96.852833 -335.940711) (xy 96.849184 -335.931002)
			(xy 96.832077 -335.889743) (xy 96.805286 -335.804532) (xy 96.78725 -335.717049) (xy 96.778153 -335.628191)
			(xy 96.777556 -335.58353) (xy 96.777556 -335.582768) (xy 96.778055 -335.540843) (xy 96.786025 -335.457372)
			(xy 96.801894 -335.375037) (xy 96.825517 -335.294583) (xy 96.856681 -335.216739) (xy 96.895104 -335.142209)
			(xy 96.940437 -335.07167) (xy 96.99227 -335.005759) (xy 97.050133 -334.945073) (xy 97.113503 -334.890163)
			(xy 97.181806 -334.841525) (xy 97.254423 -334.7996) (xy 97.330696 -334.764767) (xy 97.409935 -334.737342)
			(xy 97.491421 -334.717573) (xy 97.574418 -334.70564) (xy 97.658174 -334.701651) (xy 97.74193 -334.70564)
			(xy 97.824927 -334.717573) (xy 97.906413 -334.737342) (xy 97.985652 -334.764767) (xy 98.061925 -334.7996)
			(xy 98.134542 -334.841525) (xy 98.202845 -334.890163) (xy 98.266215 -334.945073) (xy 98.324078 -335.005759)
			(xy 98.375911 -335.07167) (xy 98.421244 -335.142209) (xy 98.459667 -335.216739) (xy 98.490831 -335.294583)
			(xy 98.514454 -335.375037) (xy 98.530323 -335.457372) (xy 98.538293 -335.540843) (xy 98.538792 -335.582768)
			(xy 98.538792 -335.58353) (xy 98.538226 -335.628194) (xy 98.529151 -335.717059) (xy 98.511117 -335.804547)
			(xy 98.484311 -335.889757) (xy 98.467164 -335.931002) (xy 98.463542 -335.940716) (xy 98.463531 -335.961426)
			(xy 98.467164 -335.971134) (xy 98.48433 -336.012473) (xy 98.511159 -336.097874) (xy 98.529194 -336.185554)
			(xy 98.538249 -336.27461) (xy 98.538792 -336.319368) (xy 98.538552 -336.350973) (xy 98.534101 -336.414026)
			(xy 98.529902 -336.445352) (xy 98.528378 -336.45602) (xy 98.53422 -336.477102) (xy 98.590608 -336.543396)
			(xy 98.597904 -336.55118) (xy 98.617064 -336.560504) (xy 98.627692 -336.56143) (xy 98.6282 -336.56143)
			(xy 98.671147 -336.563026) (xy 98.756458 -336.573467) (xy 98.840365 -336.592088) (xy 98.922084 -336.618714)
			(xy 99.000854 -336.653099) (xy 99.07594 -336.69492) (xy 99.146643 -336.743788) (xy 99.212303 -336.799248)
			(xy 99.272307 -336.860782) (xy 99.326097 -336.927817) (xy 99.362614 -336.9836) (xy 318.155561 -336.9836)
			(xy 318.15955 -336.899842) (xy 318.171484 -336.816843) (xy 318.191253 -336.735354) (xy 318.218678 -336.656114)
			(xy 318.253512 -336.579839) (xy 318.295438 -336.50722) (xy 318.344078 -336.438916) (xy 318.398989 -336.375544)
			(xy 318.459676 -336.317679) (xy 318.525589 -336.265845) (xy 318.59613 -336.220511) (xy 318.670661 -336.182087)
			(xy 318.748507 -336.150922) (xy 318.828963 -336.127298) (xy 318.911301 -336.111429) (xy 318.994774 -336.103459)
			(xy 319.0367 -336.10296) (xy 319.037716 -336.10296) (xy 319.074773 -336.103363) (xy 319.148622 -336.109628)
			(xy 319.221685 -336.122071) (xy 319.293445 -336.140604) (xy 319.328546 -336.15249) (xy 319.336743 -336.155004)
			(xy 319.353877 -336.155004) (xy 319.362074 -336.15249) (xy 319.397267 -336.140575) (xy 319.469212 -336.121992)
			(xy 319.542468 -336.109546) (xy 319.616513 -336.103324) (xy 319.653666 -336.10296) (xy 319.654174 -336.10296)
			(xy 319.681606 -336.103214) (xy 319.687655 -336.066844) (xy 319.704988 -335.995173) (xy 319.728195 -335.925184)
			(xy 319.742312 -335.891124) (xy 319.745871 -335.881532) (xy 319.745875 -335.86109) (xy 319.742312 -335.8515)
			(xy 319.725303 -335.810117) (xy 319.698681 -335.724692) (xy 319.680772 -335.637026) (xy 319.671759 -335.548004)
			(xy 319.671192 -335.503266) (xy 319.671192 -335.503012) (xy 319.671696 -335.460664) (xy 319.679747 -335.37635)
			(xy 319.695776 -335.293184) (xy 319.719637 -335.211917) (xy 319.751116 -335.133287) (xy 319.789927 -335.058006)
			(xy 319.835717 -334.986754) (xy 319.888073 -334.920178) (xy 319.946521 -334.85888) (xy 320.010531 -334.803415)
			(xy 320.079523 -334.754286) (xy 320.152873 -334.711937) (xy 320.229916 -334.676753) (xy 320.309955 -334.649051)
			(xy 320.392264 -334.629083) (xy 320.476099 -334.61703) (xy 320.5607 -334.613) (xy 320.645301 -334.61703)
			(xy 320.729136 -334.629083) (xy 320.811445 -334.649051) (xy 320.891484 -334.676753) (xy 320.968527 -334.711937)
			(xy 321.041877 -334.754286) (xy 321.110869 -334.803415) (xy 321.174879 -334.85888) (xy 321.233327 -334.920178)
			(xy 321.285683 -334.986754) (xy 321.331473 -335.058006) (xy 321.370284 -335.133287) (xy 321.401763 -335.211917)
			(xy 321.425624 -335.293184) (xy 321.441653 -335.37635) (xy 321.449704 -335.460664) (xy 321.450208 -335.503012)
			(xy 321.450208 -335.503266) (xy 321.449645 -335.548004) (xy 321.440627 -335.637026) (xy 321.422721 -335.724694)
			(xy 321.396107 -335.810121) (xy 321.379088 -335.8515) (xy 321.375596 -335.861115) (xy 321.37573 -335.881553)
			(xy 321.379342 -335.891124) (xy 321.395061 -335.929255) (xy 321.42019 -336.007817) (xy 321.437947 -336.088366)
			(xy 321.448179 -336.170212) (xy 321.449954 -336.211418) (xy 321.450208 -336.22488) (xy 321.464178 -336.24774)
			(xy 321.564762 -336.303112) (xy 321.591432 -336.302604) (xy 321.603116 -336.295746) (xy 321.637431 -336.275914)
			(xy 321.708951 -336.241747) (xy 321.783227 -336.214078) (xy 321.859671 -336.193127) (xy 321.937675 -336.179058)
			(xy 322.016621 -336.171985) (xy 322.056252 -336.17154) (xy 322.05676 -336.17154) (xy 322.097864 -336.17199)
			(xy 322.179721 -336.179572) (xy 322.26053 -336.194675) (xy 322.3396 -336.21717) (xy 322.416257 -336.246866)
			(xy 322.489847 -336.283508) (xy 322.559742 -336.326784) (xy 322.625346 -336.376325) (xy 322.686098 -336.431708)
			(xy 322.74148 -336.492461) (xy 322.791021 -336.558064) (xy 322.834296 -336.62796) (xy 322.870938 -336.70155)
			(xy 322.900632 -336.778207) (xy 322.923127 -336.857278) (xy 322.938229 -336.938087) (xy 322.941787 -336.9765)
			(xy 326.511148 -336.9765) (xy 326.515138 -336.892742) (xy 326.527072 -336.809743) (xy 326.546841 -336.728254)
			(xy 326.574266 -336.649013) (xy 326.609099 -336.572737) (xy 326.651025 -336.500118) (xy 326.699664 -336.431814)
			(xy 326.754575 -336.368441) (xy 326.815262 -336.310576) (xy 326.881174 -336.258741) (xy 326.951715 -336.213406)
			(xy 327.026246 -336.174981) (xy 327.104092 -336.143815) (xy 327.184547 -336.12019) (xy 327.266885 -336.104319)
			(xy 327.350358 -336.096347) (xy 327.392284 -336.095848) (xy 327.3933 -336.095848) (xy 327.430357 -336.096256)
			(xy 327.504206 -336.10252) (xy 327.577268 -336.114961) (xy 327.649028 -336.133493) (xy 327.68413 -336.145378)
			(xy 327.692327 -336.147892) (xy 327.709461 -336.147892) (xy 327.717658 -336.145378) (xy 327.752881 -336.133453)
			(xy 327.824889 -336.114861) (xy 327.898209 -336.102415) (xy 327.972319 -336.096203) (xy 328.009504 -336.095848)
			(xy 328.043286 -336.096356) (xy 328.05281 -336.047304) (xy 328.081456 -335.951571) (xy 328.100436 -335.905348)
			(xy 328.10398 -335.895751) (xy 328.103994 -335.875314) (xy 328.100436 -335.865724) (xy 328.083404 -335.82435)
			(xy 328.056787 -335.738922) (xy 328.038886 -335.651253) (xy 328.02988 -335.562229) (xy 328.029316 -335.51749)
			(xy 328.029316 -335.517236) (xy 328.02982 -335.474888) (xy 328.037871 -335.390574) (xy 328.0539 -335.307408)
			(xy 328.077761 -335.226141) (xy 328.10924 -335.147511) (xy 328.148051 -335.07223) (xy 328.193841 -335.000978)
			(xy 328.246197 -334.934402) (xy 328.304645 -334.873104) (xy 328.368655 -334.817639) (xy 328.437647 -334.76851)
			(xy 328.510997 -334.726161) (xy 328.58804 -334.690977) (xy 328.668079 -334.663275) (xy 328.750388 -334.643307)
			(xy 328.834223 -334.631254) (xy 328.918824 -334.627224) (xy 329.003425 -334.631254) (xy 329.08726 -334.643307)
			(xy 329.169569 -334.663275) (xy 329.249608 -334.690977) (xy 329.326651 -334.726161) (xy 329.400001 -334.76851)
			(xy 329.468993 -334.817639) (xy 329.533003 -334.873104) (xy 329.591451 -334.934402) (xy 329.643807 -335.000978)
			(xy 329.689597 -335.07223) (xy 329.728408 -335.147511) (xy 329.759887 -335.226141) (xy 329.783748 -335.307408)
			(xy 329.799777 -335.390574) (xy 329.807828 -335.474888) (xy 329.808332 -335.517236) (xy 329.808332 -335.51749)
			(xy 329.807775 -335.562229) (xy 329.798756 -335.651251) (xy 329.780848 -335.738918) (xy 329.754231 -335.824345)
			(xy 329.737212 -335.865724) (xy 329.733624 -335.875308) (xy 329.733638 -335.895757) (xy 329.737212 -335.905348)
			(xy 329.752022 -335.941175) (xy 329.776095 -336.014872) (xy 329.793653 -336.090386) (xy 329.804563 -336.167144)
			(xy 329.807062 -336.20583) (xy 329.807824 -336.219038) (xy 329.822048 -336.24139) (xy 329.91044 -336.288888)
			(xy 329.918254 -336.292745) (xy 329.93547 -336.295369) (xy 329.95256 -336.292022) (xy 329.960224 -336.287872)
			(xy 329.994483 -336.268147) (xy 330.065868 -336.23417) (xy 330.139986 -336.206662) (xy 330.216254 -336.18584)
			(xy 330.294068 -336.171868) (xy 330.372815 -336.164856) (xy 330.412344 -336.164428) (xy 330.453448 -336.164825)
			(xy 330.535306 -336.172414) (xy 330.616114 -336.187524) (xy 330.695183 -336.210025) (xy 330.771839 -336.239726)
			(xy 330.845427 -336.276373) (xy 330.91532 -336.319653) (xy 330.980922 -336.369198) (xy 331.041672 -336.424584)
			(xy 331.097053 -336.48534) (xy 331.146592 -336.550946) (xy 331.189866 -336.620843) (xy 331.226507 -336.694434)
			(xy 331.256201 -336.771093) (xy 331.278695 -336.850164) (xy 331.293797 -336.930973) (xy 331.296671 -336.962)
			(xy 334.868517 -336.962) (xy 334.872507 -336.878219) (xy 334.884444 -336.795197) (xy 334.904219 -336.713686)
			(xy 334.931652 -336.634423) (xy 334.966495 -336.558127) (xy 335.008433 -336.485488) (xy 335.057086 -336.417165)
			(xy 335.112013 -336.353776) (xy 335.172717 -336.295895) (xy 335.238647 -336.244046) (xy 335.309208 -336.198699)
			(xy 335.38376 -336.160265) (xy 335.461628 -336.129092) (xy 335.542106 -336.105461) (xy 335.624466 -336.089588)
			(xy 335.707962 -336.081615) (xy 335.7499 -336.081116) (xy 335.78709 -336.081504) (xy 335.861203 -336.087794)
			(xy 335.934522 -336.100304) (xy 336.006528 -336.118945) (xy 336.041746 -336.1309) (xy 336.049943 -336.133414)
			(xy 336.067077 -336.133414) (xy 336.075274 -336.1309) (xy 336.110487 -336.118927) (xy 336.182491 -336.100276)
			(xy 336.255813 -336.08777) (xy 336.329929 -336.0815) (xy 336.36712 -336.081116) (xy 336.407506 -336.082132)
			(xy 336.417036 -336.036786) (xy 336.444265 -335.948213) (xy 336.461862 -335.905348) (xy 336.465474 -335.895775)
			(xy 336.465619 -335.875336) (xy 336.462116 -335.865724) (xy 336.445083 -335.824351) (xy 336.418467 -335.738922)
			(xy 336.400565 -335.651253) (xy 336.39156 -335.562229) (xy 336.390996 -335.51749) (xy 336.390996 -335.517236)
			(xy 336.3915 -335.474888) (xy 336.399551 -335.390574) (xy 336.41558 -335.307408) (xy 336.439441 -335.226141)
			(xy 336.47092 -335.147511) (xy 336.509731 -335.07223) (xy 336.555521 -335.000978) (xy 336.607877 -334.934402)
			(xy 336.666325 -334.873104) (xy 336.730335 -334.817639) (xy 336.799327 -334.76851) (xy 336.872677 -334.726161)
			(xy 336.94972 -334.690977) (xy 337.029759 -334.663275) (xy 337.112068 -334.643307) (xy 337.195903 -334.631254)
			(xy 337.280504 -334.627224) (xy 337.365105 -334.631254) (xy 337.44894 -334.643307) (xy 337.531249 -334.663275)
			(xy 337.611288 -334.690977) (xy 337.688331 -334.726161) (xy 337.761681 -334.76851) (xy 337.830673 -334.817639)
			(xy 337.894683 -334.873104) (xy 337.953131 -334.934402) (xy 338.005487 -335.000978) (xy 338.051277 -335.07223)
			(xy 338.090088 -335.147511) (xy 338.121567 -335.226141) (xy 338.145428 -335.307408) (xy 338.161457 -335.390574)
			(xy 338.169508 -335.474888) (xy 338.170012 -335.517236) (xy 338.170012 -335.51749) (xy 338.169456 -335.562229)
			(xy 338.160437 -335.651251) (xy 338.142528 -335.738918) (xy 338.115912 -335.824345) (xy 338.098892 -335.865724)
			(xy 338.095386 -335.875335) (xy 338.09553 -335.895777) (xy 338.099146 -335.905348) (xy 338.117792 -335.95091)
			(xy 338.146101 -336.045203) (xy 338.163844 -336.142042) (xy 338.16798 -336.191098) (xy 338.168919 -336.199672)
			(xy 338.175759 -336.215494) (xy 338.187449 -336.228161) (xy 338.194904 -336.2325) (xy 338.283042 -336.278728)
			(xy 338.309204 -336.27822) (xy 338.320634 -336.271616) (xy 338.354723 -336.252133) (xy 338.425722 -336.218592)
			(xy 338.499399 -336.191437) (xy 338.575183 -336.170878) (xy 338.652483 -336.157075) (xy 338.730699 -336.150137)
			(xy 338.76996 -336.149696) (xy 338.811054 -336.150204) (xy 338.892893 -336.157783) (xy 338.973684 -336.172879)
			(xy 339.052737 -336.195365) (xy 339.129379 -336.225047) (xy 339.202956 -336.261673) (xy 339.27284 -336.304931)
			(xy 339.338435 -336.354452) (xy 339.399182 -336.409813) (xy 339.454563 -336.470542) (xy 339.504105 -336.536121)
			(xy 339.547386 -336.605991) (xy 339.584036 -336.679555) (xy 339.613743 -336.756188) (xy 339.636254 -336.835234)
			(xy 339.651377 -336.916019) (xy 339.658982 -336.997856) (xy 339.659159 -337.0128) (xy 343.199717 -337.0128)
			(xy 343.203707 -336.929019) (xy 343.215644 -336.845997) (xy 343.235419 -336.764486) (xy 343.262852 -336.685223)
			(xy 343.297695 -336.608927) (xy 343.339633 -336.536288) (xy 343.388286 -336.467965) (xy 343.443213 -336.404576)
			(xy 343.503917 -336.346695) (xy 343.569847 -336.294846) (xy 343.640408 -336.249499) (xy 343.71496 -336.211065)
			(xy 343.792828 -336.179892) (xy 343.873306 -336.156261) (xy 343.955666 -336.140388) (xy 344.039162 -336.132415)
			(xy 344.0811 -336.131916) (xy 344.11829 -336.132304) (xy 344.192403 -336.138594) (xy 344.265722 -336.151104)
			(xy 344.337728 -336.169745) (xy 344.372946 -336.1817) (xy 344.381143 -336.184214) (xy 344.398277 -336.184214)
			(xy 344.406474 -336.1817) (xy 344.441687 -336.169727) (xy 344.513691 -336.151076) (xy 344.587013 -336.13857)
			(xy 344.661129 -336.1323) (xy 344.69832 -336.131916) (xy 344.712798 -336.13217) (xy 344.724169 -336.131792)
			(xy 344.744841 -336.122355) (xy 344.759419 -336.104924) (xy 344.762836 -336.09407) (xy 344.771457 -336.062103)
			(xy 344.792812 -335.999426) (xy 344.805508 -335.968848) (xy 344.809054 -335.959252) (xy 344.809067 -335.938814)
			(xy 344.805508 -335.929224) (xy 344.788475 -335.887851) (xy 344.761859 -335.802423) (xy 344.743957 -335.714753)
			(xy 344.734952 -335.625729) (xy 344.734388 -335.58099) (xy 344.734388 -335.580736) (xy 344.734892 -335.538388)
			(xy 344.742943 -335.454074) (xy 344.758972 -335.370908) (xy 344.782833 -335.289641) (xy 344.814312 -335.211011)
			(xy 344.853123 -335.13573) (xy 344.898913 -335.064478) (xy 344.951269 -334.997902) (xy 345.009717 -334.936604)
			(xy 345.073727 -334.881139) (xy 345.142719 -334.83201) (xy 345.216069 -334.789661) (xy 345.293112 -334.754477)
			(xy 345.373151 -334.726775) (xy 345.45546 -334.706807) (xy 345.539295 -334.694754) (xy 345.623896 -334.690724)
			(xy 345.708497 -334.694754) (xy 345.792332 -334.706807) (xy 345.874641 -334.726775) (xy 345.95468 -334.754477)
			(xy 346.031723 -334.789661) (xy 346.105073 -334.83201) (xy 346.174065 -334.881139) (xy 346.238075 -334.936604)
			(xy 346.296523 -334.997902) (xy 346.348879 -335.064478) (xy 346.394669 -335.13573) (xy 346.43348 -335.211011)
			(xy 346.464959 -335.289641) (xy 346.48882 -335.370908) (xy 346.504849 -335.454074) (xy 346.5129 -335.538388)
			(xy 346.513404 -335.580736) (xy 346.513404 -335.58099) (xy 346.512849 -335.625729) (xy 346.50383 -335.714751)
			(xy 346.485921 -335.802418) (xy 346.459304 -335.887845) (xy 346.442284 -335.929224) (xy 346.438698 -335.938808)
			(xy 346.438711 -335.959257) (xy 346.442284 -335.968848) (xy 346.459319 -336.010255) (xy 346.48595 -336.095744)
			(xy 346.503854 -336.183477) (xy 346.51285 -336.272565) (xy 346.513404 -336.317336) (xy 346.513182 -336.348682)
			(xy 346.508857 -336.411225) (xy 346.504768 -336.442304) (xy 346.503244 -336.452972) (xy 346.508832 -336.473546)
			(xy 346.56268 -336.539586) (xy 346.569651 -336.547336) (xy 346.588142 -336.55691) (xy 346.598494 -336.558128)
			(xy 346.599002 -336.558128) (xy 346.640786 -336.561293) (xy 346.723543 -336.574476) (xy 346.804694 -336.595383)
			(xy 346.883519 -336.62383) (xy 346.959319 -336.659564) (xy 347.031422 -336.702268) (xy 347.09919 -336.751564)
			(xy 347.162022 -336.807015) (xy 347.21936 -336.868129) (xy 347.270696 -336.934365) (xy 347.315576 -337.005135)
			(xy 347.353601 -337.079812) (xy 347.384434 -337.157734) (xy 347.407802 -337.238211) (xy 347.423499 -337.320529)
			(xy 347.431384 -337.403958) (xy 347.431868 -337.445858) (xy 347.431868 -337.446874) (xy 347.431339 -337.489485)
			(xy 347.423121 -337.57431) (xy 347.406824 -337.657959) (xy 347.382599 -337.739665) (xy 347.367098 -337.77936)
			(xy 347.363634 -337.789438) (xy 347.36443 -337.810709) (xy 347.368622 -337.820508) (xy 347.385666 -337.856788)
			(xy 347.413917 -337.931808) (xy 347.435302 -338.009067) (xy 347.449648 -338.087936) (xy 347.456838 -338.167776)
			(xy 347.457268 -338.207858) (xy 347.456674 -338.254253) (xy 347.447033 -338.346541) (xy 347.42784 -338.437325)
			(xy 347.399305 -338.525619) (xy 347.381068 -338.568284) (xy 347.377284 -338.578233) (xy 347.377268 -338.599491)
			(xy 347.381068 -338.609432) (xy 347.399296 -338.652101) (xy 347.427845 -338.740391) (xy 347.447043 -338.831174)
			(xy 347.456681 -338.923462) (xy 347.457268 -338.969858) (xy 347.456674 -339.016253) (xy 347.447033 -339.108541)
			(xy 347.42784 -339.199325) (xy 347.399305 -339.287619) (xy 347.381068 -339.330284) (xy 347.377284 -339.340233)
			(xy 347.377268 -339.361491) (xy 347.381068 -339.371432) (xy 347.39928 -339.414039) (xy 347.427799 -339.502205)
			(xy 347.446995 -339.592859) (xy 347.456658 -339.685018) (xy 347.457268 -339.73135) (xy 347.457268 -339.731858)
			(xy 347.456747 -339.772964) (xy 347.449167 -339.854825) (xy 347.434067 -339.935639) (xy 347.411576 -340.014714)
			(xy 347.381885 -340.091377) (xy 347.345249 -340.164975) (xy 347.30198 -340.234878) (xy 347.252446 -340.300492)
			(xy 347.19707 -340.361256) (xy 347.136324 -340.416653) (xy 347.070727 -340.466209) (xy 347.000838 -340.509502)
			(xy 346.927254 -340.546163) (xy 346.8506 -340.575879) (xy 346.771533 -340.598397) (xy 346.690725 -340.613525)
			(xy 346.608866 -340.621133) (xy 346.56776 -340.62162) (xy 346.525159 -340.621134) (xy 346.440349 -340.612975)
			(xy 346.356708 -340.596745) (xy 346.275001 -340.572593) (xy 346.195978 -340.540739) (xy 346.120362 -340.501477)
			(xy 346.048846 -340.455165) (xy 345.982085 -340.402229) (xy 345.920691 -340.343152) (xy 345.865226 -340.278476)
			(xy 345.840304 -340.243922) (xy 345.834713 -340.236567) (xy 345.819465 -340.226159) (xy 345.810586 -340.223602)
			(xy 345.769427 -340.213207) (xy 345.689122 -340.185668) (xy 345.611806 -340.150603) (xy 345.538183 -340.108332)
			(xy 345.468921 -340.05924) (xy 345.40465 -340.003772) (xy 345.345957 -339.942434) (xy 345.293373 -339.875784)
			(xy 345.247379 -339.804427) (xy 345.208391 -339.729013) (xy 345.176765 -339.650228) (xy 345.152789 -339.568788)
			(xy 345.136679 -339.485435) (xy 345.128584 -339.400926) (xy 345.128088 -339.358478) (xy 345.128088 -339.358224)
			(xy 345.128648 -339.313485) (xy 345.137666 -339.224464) (xy 345.155574 -339.136796) (xy 345.182189 -339.051369)
			(xy 345.199208 -339.00999) (xy 345.202787 -339.000403) (xy 345.202779 -338.979957) (xy 345.199208 -338.970366)
			(xy 345.182177 -338.928958) (xy 345.155545 -338.843469) (xy 345.13764 -338.755736) (xy 345.128642 -338.666649)
			(xy 345.128088 -338.621878) (xy 345.128637 -338.577108) (xy 345.137642 -338.488021) (xy 345.15555 -338.400289)
			(xy 345.182178 -338.314799) (xy 345.199208 -338.27339) (xy 345.202787 -338.263803) (xy 345.202779 -338.243357)
			(xy 345.199208 -338.233766) (xy 345.182177 -338.192358) (xy 345.155545 -338.106869) (xy 345.13764 -338.019136)
			(xy 345.128642 -337.930049) (xy 345.128088 -337.885278) (xy 345.128088 -337.87334) (xy 345.101609 -337.867394)
			(xy 345.049374 -337.852651) (xy 345.023694 -337.843876) (xy 345.015497 -337.841362) (xy 344.998363 -337.841362)
			(xy 344.990166 -337.843876) (xy 344.95495 -337.855837) (xy 344.882946 -337.874492) (xy 344.809626 -337.887)
			(xy 344.73551 -337.893274) (xy 344.69832 -337.89366) (xy 344.661131 -337.893262) (xy 344.587018 -337.886974)
			(xy 344.513698 -337.874467) (xy 344.441692 -337.855829) (xy 344.406474 -337.843876) (xy 344.398277 -337.841362)
			(xy 344.381143 -337.841362) (xy 344.372946 -337.843876) (xy 344.337731 -337.855842) (xy 344.265728 -337.874496)
			(xy 344.192406 -337.887003) (xy 344.11829 -337.893275) (xy 344.0811 -337.89366) (xy 344.039162 -337.893185)
			(xy 343.955666 -337.885212) (xy 343.873306 -337.869339) (xy 343.792828 -337.845708) (xy 343.71496 -337.814535)
			(xy 343.640408 -337.776101) (xy 343.569847 -337.730754) (xy 343.503917 -337.678905) (xy 343.443213 -337.621024)
			(xy 343.388286 -337.557635) (xy 343.339633 -337.489312) (xy 343.297695 -337.416673) (xy 343.262852 -337.340377)
			(xy 343.235419 -337.261114) (xy 343.215644 -337.179603) (xy 343.203707 -337.096581) (xy 343.199717 -337.0128)
			(xy 339.659159 -337.0128) (xy 339.659468 -337.03895) (xy 339.659468 -337.039458) (xy 339.6589 -337.084228)
			(xy 339.649901 -337.173314) (xy 339.631999 -337.261046) (xy 339.605375 -337.346537) (xy 339.588348 -337.387946)
			(xy 339.584808 -337.397544) (xy 339.584792 -337.41798) (xy 339.588348 -337.42757) (xy 339.605388 -337.468975)
			(xy 339.632018 -337.554465) (xy 339.649921 -337.642198) (xy 339.658915 -337.731287) (xy 339.659468 -337.776058)
			(xy 339.6589 -337.820828) (xy 339.649901 -337.909914) (xy 339.631999 -337.997646) (xy 339.605375 -338.083137)
			(xy 339.588348 -338.124546) (xy 339.584808 -338.134144) (xy 339.584792 -338.15458) (xy 339.588348 -338.16417)
			(xy 339.605377 -338.205545) (xy 339.631995 -338.290972) (xy 339.649897 -338.378641) (xy 339.658904 -338.467665)
			(xy 339.659468 -338.512404) (xy 339.659468 -338.512658) (xy 339.658947 -338.553764) (xy 339.651367 -338.635625)
			(xy 339.636267 -338.716439) (xy 339.613776 -338.795514) (xy 339.584085 -338.872177) (xy 339.547449 -338.945775)
			(xy 339.50418 -339.015678) (xy 339.454646 -339.081292) (xy 339.39927 -339.142056) (xy 339.338524 -339.197453)
			(xy 339.272927 -339.247009) (xy 339.203038 -339.290302) (xy 339.129454 -339.326963) (xy 339.0528 -339.356679)
			(xy 338.973733 -339.379197) (xy 338.892925 -339.394325) (xy 338.811066 -339.401933) (xy 338.76996 -339.40242)
			(xy 338.728351 -339.40191) (xy 338.645495 -339.394139) (xy 338.563727 -339.378669) (xy 338.483759 -339.355636)
			(xy 338.40629 -339.325239) (xy 338.331996 -339.287745) (xy 338.296504 -339.266022) (xy 338.287367 -339.260856)
			(xy 338.26665 -339.257639) (xy 338.246374 -339.262975) (xy 338.23783 -339.26907) (xy 338.204174 -339.295024)
			(xy 338.132784 -339.341153) (xy 338.057318 -339.380258) (xy 337.978465 -339.411983) (xy 337.896945 -339.436039)
			(xy 337.8135 -339.452205) (xy 337.728894 -339.460335) (xy 337.686396 -339.46084) (xy 337.645302 -339.460338)
			(xy 337.563464 -339.452755) (xy 337.482675 -339.437656) (xy 337.403623 -339.415168) (xy 337.326982 -339.385484)
			(xy 337.253407 -339.348856) (xy 337.183524 -339.305597) (xy 337.11793 -339.256076) (xy 337.057184 -339.200716)
			(xy 337.001804 -339.139987) (xy 336.952262 -339.074409) (xy 336.908981 -339.00454) (xy 336.87233 -338.930976)
			(xy 336.842621 -338.854345) (xy 336.820109 -338.7753) (xy 336.804984 -338.694515) (xy 336.797375 -338.61268)
			(xy 336.796888 -338.571586) (xy 336.796888 -338.571078) (xy 336.797437 -338.526308) (xy 336.806442 -338.437221)
			(xy 336.82435 -338.349489) (xy 336.850978 -338.263999) (xy 336.868008 -338.22259) (xy 336.871587 -338.213003)
			(xy 336.871579 -338.192557) (xy 336.868008 -338.182966) (xy 336.850977 -338.141558) (xy 336.824345 -338.056069)
			(xy 336.80644 -337.968336) (xy 336.797442 -337.879249) (xy 336.796888 -337.834478) (xy 336.796888 -337.82254)
			(xy 336.770409 -337.816594) (xy 336.718174 -337.801851) (xy 336.692494 -337.793076) (xy 336.684297 -337.790562)
			(xy 336.667163 -337.790562) (xy 336.658966 -337.793076) (xy 336.62375 -337.805037) (xy 336.551746 -337.823692)
			(xy 336.478426 -337.8362) (xy 336.40431 -337.842474) (xy 336.36712 -337.84286) (xy 336.329931 -337.842462)
			(xy 336.255818 -337.836174) (xy 336.182498 -337.823667) (xy 336.110492 -337.805029) (xy 336.075274 -337.793076)
			(xy 336.067077 -337.790562) (xy 336.049943 -337.790562) (xy 336.041746 -337.793076) (xy 336.006531 -337.805042)
			(xy 335.934528 -337.823696) (xy 335.861206 -337.836203) (xy 335.78709 -337.842475) (xy 335.7499 -337.84286)
			(xy 335.707962 -337.842385) (xy 335.624466 -337.834412) (xy 335.542106 -337.818539) (xy 335.461628 -337.794908)
			(xy 335.38376 -337.763735) (xy 335.309208 -337.725301) (xy 335.238647 -337.679954) (xy 335.172717 -337.628105)
			(xy 335.112013 -337.570224) (xy 335.057086 -337.506835) (xy 335.008433 -337.438512) (xy 334.966495 -337.365873)
			(xy 334.931652 -337.289577) (xy 334.904219 -337.210314) (xy 334.884444 -337.128803) (xy 334.872507 -337.045781)
			(xy 334.868517 -336.962) (xy 331.296671 -336.962) (xy 331.301379 -337.012832) (xy 331.301852 -337.053936)
			(xy 331.301852 -337.05419) (xy 331.301293 -337.098929) (xy 331.292274 -337.18795) (xy 331.274367 -337.275618)
			(xy 331.247751 -337.361045) (xy 331.230732 -337.402424) (xy 331.227148 -337.412009) (xy 331.227161 -337.432457)
			(xy 331.230732 -337.442048) (xy 331.247764 -337.483456) (xy 331.274397 -337.568945) (xy 331.292302 -337.656677)
			(xy 331.301298 -337.745765) (xy 331.301852 -337.790536) (xy 331.301312 -337.835307) (xy 331.292305 -337.924394)
			(xy 331.274395 -338.012126) (xy 331.247763 -338.097615) (xy 331.230732 -338.139024) (xy 331.227148 -338.148609)
			(xy 331.227161 -338.169057) (xy 331.230732 -338.178648) (xy 331.247759 -338.220024) (xy 331.274376 -338.305451)
			(xy 331.292279 -338.39312) (xy 331.301287 -338.482143) (xy 331.301852 -338.526882) (xy 331.301852 -338.527136)
			(xy 331.301368 -338.568238) (xy 331.29378 -338.65009) (xy 331.278673 -338.730894) (xy 331.256175 -338.809959)
			(xy 331.226478 -338.886611) (xy 331.189836 -338.960196) (xy 331.14656 -339.030087) (xy 331.097021 -339.095686)
			(xy 331.041641 -339.156436) (xy 330.980892 -339.211816) (xy 330.915293 -339.261356) (xy 330.845403 -339.304632)
			(xy 330.771818 -339.341275) (xy 330.695167 -339.370972) (xy 330.616102 -339.393471) (xy 330.535298 -339.408579)
			(xy 330.453446 -339.416167) (xy 330.412344 -339.416644) (xy 330.411582 -339.416644) (xy 330.370042 -339.416142)
			(xy 330.287326 -339.408361) (xy 330.205695 -339.392907) (xy 330.125859 -339.369913) (xy 330.048513 -339.339581)
			(xy 329.97433 -339.302172) (xy 329.938888 -339.2805) (xy 329.929757 -339.275322) (xy 329.909036 -339.272112)
			(xy 329.888759 -339.277452) (xy 329.880214 -339.283548) (xy 329.846565 -339.30947) (xy 329.775191 -339.355528)
			(xy 329.699752 -339.394575) (xy 329.620935 -339.426254) (xy 329.539458 -339.450278) (xy 329.456062 -339.466427)
			(xy 329.371506 -339.474554) (xy 329.329034 -339.475064) (xy 329.32878 -339.475064) (xy 329.287675 -339.474667)
			(xy 329.205817 -339.46708) (xy 329.125007 -339.451972) (xy 329.045936 -339.429472) (xy 328.969279 -339.399772)
			(xy 328.895689 -339.363126) (xy 328.825795 -339.319846) (xy 328.760192 -339.270301) (xy 328.69944 -339.214915)
			(xy 328.644058 -339.154159) (xy 328.594518 -339.088553) (xy 328.551243 -339.018655) (xy 328.514602 -338.945062)
			(xy 328.484908 -338.868403) (xy 328.462414 -338.789331) (xy 328.447312 -338.70852) (xy 328.43973 -338.626661)
			(xy 328.439272 -338.585556) (xy 328.439272 -338.585302) (xy 328.43986 -338.540564) (xy 328.44887 -338.451543)
			(xy 328.466769 -338.363876) (xy 328.493377 -338.278448) (xy 328.510392 -338.237068) (xy 328.513984 -338.227485)
			(xy 328.513968 -338.207035) (xy 328.510392 -338.197444) (xy 328.493353 -338.156039) (xy 328.466723 -338.070549)
			(xy 328.44882 -337.982815) (xy 328.439825 -337.893727) (xy 328.439272 -337.848956) (xy 328.439272 -337.837018)
			(xy 328.412793 -337.831074) (xy 328.360558 -337.81633) (xy 328.334878 -337.807554) (xy 328.326681 -337.80504)
			(xy 328.309547 -337.80504) (xy 328.30135 -337.807554) (xy 328.266125 -337.819474) (xy 328.194118 -337.838068)
			(xy 328.120798 -337.850516) (xy 328.046689 -337.856728) (xy 328.009504 -337.857084) (xy 327.97232 -337.856715)
			(xy 327.898212 -337.850493) (xy 327.824892 -337.838051) (xy 327.752881 -337.819476) (xy 327.717658 -337.807554)
			(xy 327.709461 -337.80504) (xy 327.692327 -337.80504) (xy 327.68413 -337.807554) (xy 327.649029 -337.819442)
			(xy 327.577272 -337.837992) (xy 327.504209 -337.850438) (xy 327.430358 -337.856691) (xy 327.3933 -337.857084)
			(xy 327.392284 -337.857084) (xy 327.350358 -337.856653) (xy 327.266885 -337.848681) (xy 327.184547 -337.83281)
			(xy 327.104092 -337.809185) (xy 327.026246 -337.778019) (xy 326.951715 -337.739594) (xy 326.881174 -337.694259)
			(xy 326.815262 -337.642424) (xy 326.754575 -337.584559) (xy 326.699664 -337.521186) (xy 326.651025 -337.452882)
			(xy 326.609099 -337.380263) (xy 326.574266 -337.303987) (xy 326.546841 -337.224746) (xy 326.527072 -337.143257)
			(xy 326.515138 -337.060258) (xy 326.511148 -336.9765) (xy 322.941787 -336.9765) (xy 322.94581 -337.019944)
			(xy 322.946268 -337.061048) (xy 322.946268 -337.061302) (xy 322.945685 -337.10604) (xy 322.936674 -337.195061)
			(xy 322.918774 -337.282729) (xy 322.892164 -337.368156) (xy 322.875148 -337.409536) (xy 322.871556 -337.419119)
			(xy 322.871574 -337.439569) (xy 322.875148 -337.44916) (xy 322.892185 -337.490566) (xy 322.918816 -337.576056)
			(xy 322.93672 -337.663789) (xy 322.945715 -337.752877) (xy 322.946268 -337.797648) (xy 322.945697 -337.842418)
			(xy 322.936698 -337.931504) (xy 322.918797 -338.019236) (xy 322.892175 -338.104727) (xy 322.875148 -338.146136)
			(xy 322.871556 -338.155719) (xy 322.871574 -338.176169) (xy 322.875148 -338.18576) (xy 322.892174 -338.227136)
			(xy 322.918792 -338.312563) (xy 322.936696 -338.400232) (xy 322.945704 -338.489255) (xy 322.946268 -338.533994)
			(xy 322.946268 -338.534248) (xy 322.945879 -338.575352) (xy 322.938289 -338.65721) (xy 322.923179 -338.738019)
			(xy 322.900678 -338.817088) (xy 322.870976 -338.893744) (xy 322.834329 -338.967333) (xy 322.791048 -339.037226)
			(xy 322.741503 -339.102828) (xy 322.686116 -339.163578) (xy 322.62536 -339.218959) (xy 322.559753 -339.268498)
			(xy 322.489856 -339.311772) (xy 322.416264 -339.348412) (xy 322.339605 -339.378106) (xy 322.260533 -339.400599)
			(xy 322.179723 -339.415702) (xy 322.097864 -339.423283) (xy 322.05676 -339.423756) (xy 322.055998 -339.423756)
			(xy 322.014458 -339.423244) (xy 321.931742 -339.415465) (xy 321.850112 -339.400013) (xy 321.770276 -339.377021)
			(xy 321.69293 -339.34669) (xy 321.618746 -339.309284) (xy 321.583304 -339.287612) (xy 321.574167 -339.282447)
			(xy 321.55345 -339.279232) (xy 321.533175 -339.284566) (xy 321.52463 -339.29066) (xy 321.491012 -339.316622)
			(xy 321.419631 -339.362677) (xy 321.344187 -339.401718) (xy 321.265365 -339.433392) (xy 321.183883 -339.457409)
			(xy 321.100483 -339.47355) (xy 321.015924 -339.48167) (xy 320.97345 -339.482176) (xy 320.973196 -339.482176)
			(xy 320.932092 -339.481752) (xy 320.850234 -339.474166) (xy 320.769426 -339.459059) (xy 320.690356 -339.436561)
			(xy 320.613699 -339.406863) (xy 320.54011 -339.370219) (xy 320.470216 -339.326941) (xy 320.404613 -339.277398)
			(xy 320.343861 -339.222013) (xy 320.288479 -339.161259) (xy 320.238939 -339.095655) (xy 320.195664 -339.025759)
			(xy 320.159022 -338.952168) (xy 320.129327 -338.87551) (xy 320.106832 -338.796439) (xy 320.091729 -338.71563)
			(xy 320.084147 -338.633772) (xy 320.083688 -338.592668) (xy 320.083688 -338.592414) (xy 320.084245 -338.547675)
			(xy 320.093264 -338.458653) (xy 320.111172 -338.370986) (xy 320.137789 -338.285559) (xy 320.154808 -338.24418)
			(xy 320.158393 -338.234595) (xy 320.158381 -338.214147) (xy 320.154808 -338.204556) (xy 320.137774 -338.163149)
			(xy 320.111142 -338.07766) (xy 320.093238 -337.989927) (xy 320.084242 -337.900839) (xy 320.083688 -337.856068)
			(xy 320.083688 -337.84413) (xy 320.057209 -337.838184) (xy 320.004974 -337.823441) (xy 319.979294 -337.814666)
			(xy 319.971097 -337.812152) (xy 319.953963 -337.812152) (xy 319.945766 -337.814666) (xy 319.910549 -337.82661)
			(xy 319.838539 -337.845197) (xy 319.765217 -337.857638) (xy 319.691106 -337.863844) (xy 319.65392 -337.864196)
			(xy 319.616736 -337.863827) (xy 319.542628 -337.857606) (xy 319.469308 -337.845164) (xy 319.397297 -337.826589)
			(xy 319.362074 -337.814666) (xy 319.353877 -337.812152) (xy 319.336743 -337.812152) (xy 319.328546 -337.814666)
			(xy 319.293452 -337.826578) (xy 319.221693 -337.845121) (xy 319.148627 -337.85756) (xy 319.074774 -337.863807)
			(xy 319.037716 -337.864196) (xy 319.0367 -337.864196) (xy 318.994774 -337.863741) (xy 318.911301 -337.855771)
			(xy 318.828963 -337.839902) (xy 318.748507 -337.816278) (xy 318.670661 -337.785113) (xy 318.59613 -337.746689)
			(xy 318.525589 -337.701355) (xy 318.459676 -337.649521) (xy 318.398989 -337.591656) (xy 318.344078 -337.528284)
			(xy 318.295438 -337.45998) (xy 318.253512 -337.387361) (xy 318.218678 -337.311086) (xy 318.191253 -337.231846)
			(xy 318.171484 -337.150357) (xy 318.15955 -337.067358) (xy 318.155561 -336.9836) (xy 99.362614 -336.9836)
			(xy 99.373171 -336.999727) (xy 99.41309 -337.075842) (xy 99.445481 -337.155452) (xy 99.470043 -337.237815)
			(xy 99.486546 -337.322163) (xy 99.494837 -337.40771) (xy 99.495356 -337.450684) (xy 99.495356 -337.451192)
			(xy 99.494833 -337.493866) (xy 99.486634 -337.578818) (xy 99.47034 -337.662596) (xy 99.446101 -337.744429)
			(xy 99.430586 -337.784186) (xy 99.426944 -337.794219) (xy 99.427619 -337.815536) (xy 99.431856 -337.825334)
			(xy 99.448914 -337.861614) (xy 99.477225 -337.936624) (xy 99.498666 -338.013878) (xy 99.513065 -338.092749)
			(xy 99.520304 -338.172597) (xy 99.520756 -338.212684) (xy 99.520272 -338.252763) (xy 99.512982 -338.33259)
			(xy 99.498549 -338.411439) (xy 99.488244 -338.450174) (xy 99.485843 -338.460698) (xy 99.489132 -338.482012)
			(xy 99.494594 -338.491322) (xy 99.517345 -338.52734) (xy 99.556637 -338.602937) (xy 99.588514 -338.681946)
			(xy 99.612684 -338.763644) (xy 99.628925 -338.847279) (xy 99.637089 -338.932085) (xy 99.637596 -338.974684)
			(xy 99.637001 -339.021087) (xy 99.627302 -339.113385) (xy 99.608039 -339.204171) (xy 99.579422 -339.292455)
			(xy 99.561142 -339.33511) (xy 99.557344 -339.345055) (xy 99.557338 -339.366316) (xy 99.561142 -339.376258)
			(xy 99.579397 -339.418922) (xy 99.607993 -339.507209) (xy 99.627252 -339.597991) (xy 99.636966 -339.690283)
			(xy 99.637596 -339.736684) (xy 99.637118 -339.777779) (xy 99.629538 -339.859619) (xy 99.614439 -339.94041)
			(xy 99.591952 -340.019465) (xy 99.562267 -340.096107) (xy 99.525639 -340.169684) (xy 99.482378 -340.239568)
			(xy 99.432856 -340.305164) (xy 99.377493 -340.36591) (xy 99.316762 -340.421291) (xy 99.251181 -340.470833)
			(xy 99.18131 -340.514113) (xy 99.107743 -340.550763) (xy 99.031109 -340.58047) (xy 98.952062 -340.60298)
			(xy 98.871275 -340.618102) (xy 98.789437 -340.625707) (xy 98.748342 -340.626192) (xy 98.747834 -340.626192)
			(xy 98.704859 -340.625663) (xy 98.619309 -340.617375) (xy 98.534957 -340.600874) (xy 98.45259 -340.576313)
			(xy 98.372977 -340.543922) (xy 98.296859 -340.504001) (xy 98.224947 -340.456925) (xy 98.157912 -340.403131)
			(xy 98.096378 -340.343122) (xy 98.040919 -340.277458) (xy 98.01606 -340.242398) (xy 98.010455 -340.235056)
			(xy 97.995216 -340.224641) (xy 97.986342 -340.222078) (xy 97.94544 -340.211492) (xy 97.865683 -340.183605)
			(xy 97.788928 -340.148281) (xy 97.715869 -340.105839) (xy 97.647164 -340.05666) (xy 97.583432 -340.001188)
			(xy 97.525246 -339.939922) (xy 97.473132 -339.873416) (xy 97.427559 -339.802268) (xy 97.388937 -339.727119)
			(xy 97.357615 -339.648646) (xy 97.333875 -339.567557) (xy 97.317931 -339.484583) (xy 97.309927 -339.40047)
			(xy 97.309432 -339.358224) (xy 97.309829 -339.321956) (xy 97.315809 -339.249667) (xy 97.327648 -339.178103)
			(xy 97.336102 -339.142832) (xy 97.338115 -339.132729) (xy 97.334853 -339.112411) (xy 97.329752 -339.103462)
			(xy 97.30766 -339.067807) (xy 97.269551 -338.993079) (xy 97.238646 -338.915096) (xy 97.215218 -338.83455)
			(xy 97.199477 -338.752156) (xy 97.191562 -338.668646) (xy 97.191068 -338.626704) (xy 97.191648 -338.581935)
			(xy 97.200654 -338.49285) (xy 97.218554 -338.405119) (xy 97.245168 -338.319627) (xy 97.262188 -338.278216)
			(xy 97.265753 -338.268625) (xy 97.265754 -338.248182) (xy 97.262188 -338.238592) (xy 97.245172 -338.197246)
			(xy 97.218563 -338.111882) (xy 97.20066 -338.024278) (xy 97.191642 -337.935319) (xy 97.191068 -337.890612)
			(xy 97.191068 -337.889596) (xy 97.191322 -337.878166) (xy 97.164844 -337.872216) (xy 97.112609 -337.857476)
			(xy 97.086928 -337.848702) (xy 97.078731 -337.846188) (xy 97.061597 -337.846188) (xy 97.0534 -337.848702)
			(xy 97.01818 -337.860638) (xy 96.946171 -337.879227) (xy 96.87285 -337.89167) (xy 96.798739 -337.897878)
			(xy 96.761554 -337.898232) (xy 96.724369 -337.89788) (xy 96.650261 -337.891654) (xy 96.576941 -337.879206)
			(xy 96.504931 -337.860627) (xy 96.469708 -337.848702) (xy 96.461511 -337.846188) (xy 96.444377 -337.846188)
			(xy 96.43618 -337.848702) (xy 96.401082 -337.860602) (xy 96.329324 -337.879149) (xy 96.25626 -337.891592)
			(xy 96.182408 -337.897841) (xy 96.14535 -337.898232) (xy 96.144334 -337.898232) (xy 96.102408 -337.897723)
			(xy 96.018934 -337.889755) (xy 95.936596 -337.873888) (xy 95.85614 -337.850267) (xy 95.778292 -337.819104)
			(xy 95.70376 -337.780683) (xy 95.633218 -337.73535) (xy 95.567304 -337.683517) (xy 95.506616 -337.625654)
			(xy 95.451703 -337.562283) (xy 95.403062 -337.493979) (xy 95.361135 -337.421361) (xy 95.3263 -337.345087)
			(xy 95.298874 -337.265846) (xy 95.279105 -337.184357) (xy 95.267171 -337.101358) (xy 95.263181 -337.0176)
			(xy 91.722641 -337.0176) (xy 91.722956 -337.044284) (xy 91.722404 -337.089054) (xy 91.71339 -337.178139)
			(xy 91.695482 -337.26587) (xy 91.668861 -337.351361) (xy 91.651836 -337.392772) (xy 91.648282 -337.402366)
			(xy 91.648276 -337.422805) (xy 91.651836 -337.432396) (xy 91.668872 -337.473803) (xy 91.695506 -337.559291)
			(xy 91.71341 -337.647024) (xy 91.722404 -337.736113) (xy 91.722956 -337.780884) (xy 91.722404 -337.825654)
			(xy 91.71339 -337.914739) (xy 91.695482 -338.00247) (xy 91.668861 -338.087961) (xy 91.651836 -338.129372)
			(xy 91.648282 -338.138966) (xy 91.648276 -338.159405) (xy 91.651836 -338.168996) (xy 91.668872 -338.210403)
			(xy 91.695506 -338.295891) (xy 91.71341 -338.383624) (xy 91.722404 -338.472713) (xy 91.722956 -338.517484)
			(xy 91.722432 -338.558593) (xy 91.714846 -338.64046) (xy 91.699738 -338.721278) (xy 91.677236 -338.800357)
			(xy 91.647532 -338.877021) (xy 91.610881 -338.950618) (xy 91.567594 -339.020518) (xy 91.518041 -339.086125)
			(xy 91.462645 -339.146879) (xy 91.401879 -339.202262) (xy 91.336261 -339.251801) (xy 91.266352 -339.295073)
			(xy 91.192747 -339.331709) (xy 91.116076 -339.361396) (xy 91.036993 -339.383882) (xy 90.956172 -339.398973)
			(xy 90.874303 -339.406541) (xy 90.833194 -339.406992) (xy 90.791589 -339.406554) (xy 90.70874 -339.398816)
			(xy 90.626975 -339.383379) (xy 90.547007 -339.360379) (xy 90.469535 -339.330016) (xy 90.395235 -339.292555)
			(xy 90.359738 -339.270848) (xy 90.350631 -339.26562) (xy 90.329893 -339.262421) (xy 90.309608 -339.267785)
			(xy 90.301064 -339.273896) (xy 90.267427 -339.299833) (xy 90.196051 -339.345891) (xy 90.12061 -339.384937)
			(xy 90.041791 -339.416615) (xy 89.960312 -339.440636) (xy 89.876914 -339.456781) (xy 89.792357 -339.464905)
			(xy 89.749884 -339.465412) (xy 89.74963 -339.465412) (xy 89.708522 -339.464959) (xy 89.626657 -339.457377)
			(xy 89.545841 -339.442274) (xy 89.466762 -339.41978) (xy 89.390096 -339.390087) (xy 89.316497 -339.353447)
			(xy 89.246591 -339.310173) (xy 89.180976 -339.260635) (xy 89.120211 -339.205254) (xy 89.064815 -339.144504)
			(xy 89.015259 -339.078902) (xy 88.971967 -339.009008) (xy 88.935308 -338.935418) (xy 88.905594 -338.85876)
			(xy 88.883079 -338.779687) (xy 88.867956 -338.698875) (xy 88.860352 -338.617012) (xy 88.859868 -338.575904)
			(xy 88.860448 -338.531135) (xy 88.869454 -338.44205) (xy 88.887354 -338.354319) (xy 88.913968 -338.268827)
			(xy 88.930988 -338.227416) (xy 88.934553 -338.217825) (xy 88.934554 -338.197382) (xy 88.930988 -338.187792)
			(xy 88.913972 -338.146446) (xy 88.887363 -338.061082) (xy 88.86946 -337.973478) (xy 88.860442 -337.884519)
			(xy 88.859868 -337.839812) (xy 88.859868 -337.838796) (xy 88.860122 -337.827366) (xy 88.833644 -337.821416)
			(xy 88.781409 -337.806676) (xy 88.755728 -337.797902) (xy 88.747531 -337.795388) (xy 88.730397 -337.795388)
			(xy 88.7222 -337.797902) (xy 88.68698 -337.809838) (xy 88.614971 -337.828427) (xy 88.54165 -337.84087)
			(xy 88.467539 -337.847078) (xy 88.430354 -337.847432) (xy 88.393169 -337.84708) (xy 88.319061 -337.840854)
			(xy 88.245741 -337.828406) (xy 88.173731 -337.809827) (xy 88.138508 -337.797902) (xy 88.130311 -337.795388)
			(xy 88.113177 -337.795388) (xy 88.10498 -337.797902) (xy 88.069882 -337.809802) (xy 87.998124 -337.828349)
			(xy 87.92506 -337.840792) (xy 87.851208 -337.847041) (xy 87.81415 -337.847432) (xy 87.813134 -337.847432)
			(xy 87.771208 -337.846923) (xy 87.687734 -337.838955) (xy 87.605396 -337.823088) (xy 87.52494 -337.799467)
			(xy 87.447092 -337.768304) (xy 87.37256 -337.729883) (xy 87.302018 -337.68455) (xy 87.236104 -337.632717)
			(xy 87.175416 -337.574854) (xy 87.120503 -337.511483) (xy 87.071862 -337.443179) (xy 87.029935 -337.370561)
			(xy 86.9951 -337.294287) (xy 86.967674 -337.215046) (xy 86.947905 -337.133557) (xy 86.935971 -337.050558)
			(xy 86.931981 -336.9668) (xy 83.360149 -336.9668) (xy 83.364863 -337.017649) (xy 83.36534 -337.058762)
			(xy 83.364781 -337.103532) (xy 83.35577 -337.192617) (xy 83.337863 -337.280348) (xy 83.311243 -337.365839)
			(xy 83.29422 -337.40725) (xy 83.290679 -337.416847) (xy 83.290665 -337.437283) (xy 83.29422 -337.446874)
			(xy 83.311248 -337.488284) (xy 83.337884 -337.573771) (xy 83.355791 -337.661503) (xy 83.364787 -337.750591)
			(xy 83.36534 -337.795362) (xy 83.364781 -337.840132) (xy 83.35577 -337.929217) (xy 83.337863 -338.016948)
			(xy 83.311243 -338.102439) (xy 83.29422 -338.14385) (xy 83.290679 -338.153447) (xy 83.290665 -338.173883)
			(xy 83.29422 -338.183474) (xy 83.311248 -338.224884) (xy 83.337884 -338.310371) (xy 83.355791 -338.398103)
			(xy 83.364787 -338.487191) (xy 83.36534 -338.531962) (xy 83.364865 -338.573077) (xy 83.357281 -338.654956)
			(xy 83.342174 -338.735786) (xy 83.319674 -338.814878) (xy 83.289971 -338.891556) (xy 83.253319 -338.965166)
			(xy 83.210032 -339.03508) (xy 83.160479 -339.100701) (xy 83.105082 -339.16147) (xy 83.044313 -339.216869)
			(xy 82.978693 -339.266423) (xy 82.90878 -339.309712) (xy 82.83517 -339.346364) (xy 82.758493 -339.376068)
			(xy 82.679402 -339.398571) (xy 82.598572 -339.413679) (xy 82.516693 -339.421265) (xy 82.475578 -339.421724)
			(xy 82.433968 -339.421253) (xy 82.351111 -339.413475) (xy 82.269342 -339.397998) (xy 82.189374 -339.374957)
			(xy 82.111906 -339.344554) (xy 82.037613 -339.307053) (xy 82.002122 -339.285326) (xy 81.992978 -339.280175)
			(xy 81.972265 -339.276953) (xy 81.951992 -339.282282) (xy 81.943448 -339.288374) (xy 81.909821 -339.314367)
			(xy 81.838426 -339.360491) (xy 81.762954 -339.399592) (xy 81.684096 -339.431311) (xy 81.602571 -339.455361)
			(xy 81.519123 -339.471521) (xy 81.434513 -339.479643) (xy 81.392014 -339.480144) (xy 81.350899 -339.479688)
			(xy 81.269019 -339.472102) (xy 81.188189 -339.456993) (xy 81.109097 -339.434491) (xy 81.032419 -339.404786)
			(xy 80.95881 -339.368133) (xy 80.888896 -339.324845) (xy 80.823275 -339.27529) (xy 80.762506 -339.219892)
			(xy 80.707108 -339.159122) (xy 80.657553 -339.093501) (xy 80.614265 -339.023587) (xy 80.577612 -338.949977)
			(xy 80.547908 -338.873299) (xy 80.525406 -338.794207) (xy 80.510297 -338.713377) (xy 80.502712 -338.631497)
			(xy 80.502252 -338.590382) (xy 80.502826 -338.545613) (xy 80.511834 -338.456528) (xy 80.529735 -338.368797)
			(xy 80.556351 -338.283305) (xy 80.573372 -338.241894) (xy 80.576945 -338.232306) (xy 80.576939 -338.211861)
			(xy 80.573372 -338.20227) (xy 80.556348 -338.160927) (xy 80.529742 -338.075562) (xy 80.511841 -337.987957)
			(xy 80.502825 -337.898997) (xy 80.502252 -337.85429) (xy 80.502252 -337.853274) (xy 80.502506 -337.841844)
			(xy 80.476028 -337.835896) (xy 80.423793 -337.821155) (xy 80.398112 -337.81238) (xy 80.389915 -337.809866)
			(xy 80.372781 -337.809866) (xy 80.364584 -337.81238) (xy 80.329366 -337.824336) (xy 80.257364 -337.842992)
			(xy 80.184043 -337.855502) (xy 80.109928 -337.861777) (xy 80.072738 -337.862164) (xy 80.035549 -337.861761)
			(xy 79.961436 -337.855475) (xy 79.888116 -337.842969) (xy 79.81611 -337.824332) (xy 79.780892 -337.81238)
			(xy 79.772695 -337.809866) (xy 79.755561 -337.809866) (xy 79.747364 -337.81238) (xy 79.712148 -337.824342)
			(xy 79.640145 -337.842996) (xy 79.566824 -337.855505) (xy 79.492708 -337.861778) (xy 79.455518 -337.862164)
			(xy 79.413579 -337.861698) (xy 79.330081 -337.853726) (xy 79.247718 -337.837853) (xy 79.167237 -337.814224)
			(xy 79.089367 -337.783051) (xy 79.014813 -337.744616) (xy 78.94425 -337.69927) (xy 78.878316 -337.64742)
			(xy 78.81761 -337.589539) (xy 78.762681 -337.526148) (xy 78.714027 -337.457824) (xy 78.672087 -337.385183)
			(xy 78.637243 -337.308885) (xy 78.609809 -337.229621) (xy 78.590033 -337.148107) (xy 78.578096 -337.065083)
			(xy 78.574105 -336.9813) (xy 75.005252 -336.9813) (xy 75.00928 -337.024761) (xy 75.009756 -337.065874)
			(xy 75.009201 -337.110644) (xy 75.000188 -337.199729) (xy 74.982281 -337.28746) (xy 74.95566 -337.372951)
			(xy 74.938636 -337.414362) (xy 74.935088 -337.423957) (xy 74.935078 -337.444395) (xy 74.938636 -337.453986)
			(xy 74.955669 -337.495394) (xy 74.982303 -337.580882) (xy 75.000209 -337.668615) (xy 75.009203 -337.757703)
			(xy 75.009756 -337.802474) (xy 75.009201 -337.847244) (xy 75.000188 -337.936329) (xy 74.982281 -338.02406)
			(xy 74.95566 -338.109551) (xy 74.938636 -338.150962) (xy 74.935088 -338.160557) (xy 74.935078 -338.180995)
			(xy 74.938636 -338.190586) (xy 74.955669 -338.231994) (xy 74.982303 -338.317482) (xy 75.000209 -338.405215)
			(xy 75.009203 -338.494303) (xy 75.009756 -338.539074) (xy 75.009277 -338.580189) (xy 75.001692 -338.662067)
			(xy 74.986584 -338.742897) (xy 74.964083 -338.821988) (xy 74.93438 -338.898665) (xy 74.897729 -338.972274)
			(xy 74.854442 -339.042187) (xy 74.804888 -339.107809) (xy 74.749492 -339.168577) (xy 74.688724 -339.223976)
			(xy 74.623104 -339.27353) (xy 74.553192 -339.316819) (xy 74.479583 -339.353472) (xy 74.402907 -339.383177)
			(xy 74.323816 -339.40568) (xy 74.242987 -339.420789) (xy 74.161109 -339.428376) (xy 74.119994 -339.428836)
			(xy 74.078384 -339.428356) (xy 73.995528 -339.420579) (xy 73.913759 -339.405104) (xy 73.833791 -339.382065)
			(xy 73.756322 -339.351663) (xy 73.682029 -339.314164) (xy 73.646538 -339.292438) (xy 73.63743 -339.287211)
			(xy 73.616693 -339.284013) (xy 73.596408 -339.289376) (xy 73.587864 -339.295486) (xy 73.554233 -339.321473)
			(xy 73.482838 -339.367598) (xy 73.407368 -339.406699) (xy 73.32851 -339.438419) (xy 73.246986 -339.46247)
			(xy 73.163538 -339.47863) (xy 73.078929 -339.486754) (xy 73.03643 -339.487256) (xy 72.995315 -339.486773)
			(xy 72.913437 -339.479188) (xy 72.832607 -339.464081) (xy 72.753517 -339.44158) (xy 72.67684 -339.411877)
			(xy 72.60323 -339.375226) (xy 72.533317 -339.33194) (xy 72.467696 -339.282387) (xy 72.406927 -339.22699)
			(xy 72.351529 -339.166223) (xy 72.301974 -339.100603) (xy 72.258685 -339.030691) (xy 72.222032 -338.957082)
			(xy 72.192327 -338.880406) (xy 72.169824 -338.801316) (xy 72.154715 -338.720487) (xy 72.147128 -338.638609)
			(xy 72.146668 -338.597494) (xy 72.147245 -338.552725) (xy 72.156251 -338.46364) (xy 72.174152 -338.375909)
			(xy 72.200767 -338.290417) (xy 72.217788 -338.249006) (xy 72.221359 -338.239417) (xy 72.221356 -338.218972)
			(xy 72.217788 -338.209382) (xy 72.200768 -338.168037) (xy 72.174161 -338.082673) (xy 72.156259 -337.995068)
			(xy 72.147241 -337.906109) (xy 72.146668 -337.861402) (xy 72.146668 -337.860386) (xy 72.146922 -337.848956)
			(xy 72.120444 -337.843006) (xy 72.068209 -337.828266) (xy 72.042528 -337.819492) (xy 72.034331 -337.816978)
			(xy 72.017197 -337.816978) (xy 72.009 -337.819492) (xy 71.973781 -337.831444) (xy 71.901779 -337.850101)
			(xy 71.828459 -337.862612) (xy 71.754344 -337.868888) (xy 71.717154 -337.869276) (xy 71.679965 -337.868873)
			(xy 71.605852 -337.862587) (xy 71.532532 -337.850082) (xy 71.460526 -337.831445) (xy 71.425308 -337.819492)
			(xy 71.417111 -337.816978) (xy 71.399977 -337.816978) (xy 71.39178 -337.819492) (xy 71.356562 -337.83145)
			(xy 71.28456 -337.850105) (xy 71.211239 -337.862615) (xy 71.137124 -337.868889) (xy 71.099934 -337.869276)
			(xy 71.057995 -337.868786) (xy 70.974497 -337.860816) (xy 70.892134 -337.844945) (xy 70.811653 -337.821316)
			(xy 70.733783 -337.790144) (xy 70.659228 -337.751711) (xy 70.588664 -337.706365) (xy 70.522731 -337.654517)
			(xy 70.462025 -337.596636) (xy 70.407095 -337.533246) (xy 70.35844 -337.464922) (xy 70.3165 -337.392282)
			(xy 70.281655 -337.315985) (xy 70.254221 -337.23672) (xy 70.234446 -337.155207) (xy 70.222508 -337.072183)
			(xy 70.218517 -336.9884) (xy 2.509012 -336.9884) (xy 2.509012 -341.9277) (xy 103.538816 -341.9277)
			(xy 103.542807 -341.843921) (xy 103.554743 -341.760902) (xy 103.574517 -341.679392) (xy 103.601948 -341.600131)
			(xy 103.63679 -341.523837) (xy 103.678726 -341.4512) (xy 103.727376 -341.382878) (xy 103.7823 -341.319489)
			(xy 103.843001 -341.261608) (xy 103.908929 -341.20976) (xy 103.979486 -341.164412) (xy 104.054035 -341.125977)
			(xy 104.131899 -341.094802) (xy 104.212375 -341.071169) (xy 104.294732 -341.055293) (xy 104.378225 -341.047317)
			(xy 104.420162 -341.046816) (xy 104.457351 -341.047215) (xy 104.531464 -341.053502) (xy 104.604784 -341.066008)
			(xy 104.67679 -341.084646) (xy 104.712008 -341.0966) (xy 104.720205 -341.099114) (xy 104.737339 -341.099114)
			(xy 104.745536 -341.0966) (xy 104.780752 -341.084638) (xy 104.852755 -341.065983) (xy 104.926076 -341.053475)
			(xy 105.000192 -341.047202) (xy 105.037382 -341.046816) (xy 105.07218 -341.047578) (xy 105.081741 -341.004913)
			(xy 105.108207 -340.921573) (xy 105.125012 -340.881208) (xy 105.128629 -340.871492) (xy 105.128644 -340.850784)
			(xy 105.125012 -340.841076) (xy 105.107898 -340.799819) (xy 105.081109 -340.714608) (xy 105.063074 -340.627124)
			(xy 105.053979 -340.538265) (xy 105.053384 -340.493604) (xy 105.053384 -340.492842) (xy 105.053883 -340.450917)
			(xy 105.061853 -340.367446) (xy 105.077722 -340.285111) (xy 105.101345 -340.204657) (xy 105.132509 -340.126813)
			(xy 105.170932 -340.052283) (xy 105.216265 -339.981744) (xy 105.268098 -339.915833) (xy 105.325961 -339.855147)
			(xy 105.389331 -339.800237) (xy 105.457634 -339.751599) (xy 105.530251 -339.709674) (xy 105.606524 -339.674841)
			(xy 105.685763 -339.647416) (xy 105.767249 -339.627647) (xy 105.850246 -339.615714) (xy 105.934002 -339.611725)
			(xy 106.017758 -339.615714) (xy 106.100755 -339.627647) (xy 106.182241 -339.647416) (xy 106.26148 -339.674841)
			(xy 106.337753 -339.709674) (xy 106.41037 -339.751599) (xy 106.478673 -339.800237) (xy 106.542043 -339.855147)
			(xy 106.599906 -339.915833) (xy 106.651739 -339.981744) (xy 106.697072 -340.052283) (xy 106.735495 -340.126813)
			(xy 106.766659 -340.204657) (xy 106.790282 -340.285111) (xy 106.806151 -340.367446) (xy 106.814121 -340.450917)
			(xy 106.81462 -340.492842) (xy 106.81462 -340.493604) (xy 106.814051 -340.538267) (xy 106.804977 -340.627133)
			(xy 106.786945 -340.714621) (xy 106.760139 -340.799831) (xy 106.742992 -340.841076) (xy 106.739326 -340.850777)
			(xy 106.739342 -340.871499) (xy 106.742992 -340.881208) (xy 106.751628 -340.901528) (xy 106.756582 -340.912278)
			(xy 106.774248 -340.927996) (xy 106.797062 -340.934212) (xy 106.808778 -340.932516) (xy 106.8525 -340.924198)
			(xy 106.941059 -340.915292) (xy 106.985562 -340.914736) (xy 106.98607 -340.914736) (xy 107.027176 -340.915241)
			(xy 107.109038 -340.922823) (xy 107.189852 -340.937924) (xy 107.268928 -340.960416) (xy 107.345591 -340.990108)
			(xy 107.419189 -341.026745) (xy 107.489092 -341.070016) (xy 107.554706 -341.119551) (xy 107.61547 -341.174927)
			(xy 107.670867 -341.235674) (xy 107.720423 -341.301272) (xy 107.763716 -341.371161) (xy 107.800377 -341.444747)
			(xy 107.830093 -341.521401) (xy 107.85261 -341.60047) (xy 107.867738 -341.681278) (xy 107.875346 -341.763138)
			(xy 107.875832 -341.804244) (xy 107.875268 -341.849014) (xy 107.867795 -341.9229) (xy 351.475729 -341.9229)
			(xy 351.479719 -341.839138) (xy 351.491654 -341.756134) (xy 351.511424 -341.674641) (xy 351.538852 -341.595396)
			(xy 351.573688 -341.519117) (xy 351.615617 -341.446494) (xy 351.66426 -341.378187) (xy 351.719176 -341.314813)
			(xy 351.779867 -341.256945) (xy 351.845785 -341.205109) (xy 351.916331 -341.159774) (xy 351.990867 -341.12135)
			(xy 352.068718 -341.090185) (xy 352.149179 -341.066562) (xy 352.231522 -341.050694) (xy 352.314999 -341.042726)
			(xy 352.356928 -341.042244) (xy 352.357944 -341.042244) (xy 352.395001 -341.04264) (xy 352.46885 -341.048907)
			(xy 352.541913 -341.061352) (xy 352.613673 -341.079887) (xy 352.648774 -341.091774) (xy 352.656971 -341.094288)
			(xy 352.674105 -341.094288) (xy 352.682302 -341.091774) (xy 352.717522 -341.079841) (xy 352.789531 -341.06125)
			(xy 352.862852 -341.048806) (xy 352.936963 -341.042598) (xy 352.974148 -341.042244) (xy 352.988626 -341.042244)
			(xy 352.999994 -341.041829) (xy 353.020668 -341.032414) (xy 353.035248 -341.014994) (xy 353.038664 -341.004144)
			(xy 353.047281 -340.972176) (xy 353.068638 -340.909499) (xy 353.081336 -340.878922) (xy 353.084895 -340.86933)
			(xy 353.084899 -340.848889) (xy 353.081336 -340.839298) (xy 353.064328 -340.797915) (xy 353.037705 -340.71249)
			(xy 353.019796 -340.624824) (xy 353.010783 -340.535802) (xy 353.010216 -340.491064) (xy 353.010216 -340.49081)
			(xy 353.01072 -340.448462) (xy 353.018771 -340.364148) (xy 353.0348 -340.280982) (xy 353.058661 -340.199715)
			(xy 353.09014 -340.121085) (xy 353.128951 -340.045804) (xy 353.174741 -339.974552) (xy 353.227097 -339.907976)
			(xy 353.285545 -339.846678) (xy 353.349555 -339.791213) (xy 353.418547 -339.742084) (xy 353.491897 -339.699735)
			(xy 353.56894 -339.664551) (xy 353.648979 -339.636849) (xy 353.731288 -339.616881) (xy 353.815123 -339.604828)
			(xy 353.899724 -339.600798) (xy 353.984325 -339.604828) (xy 354.06816 -339.616881) (xy 354.150469 -339.636849)
			(xy 354.230508 -339.664551) (xy 354.307551 -339.699735) (xy 354.380901 -339.742084) (xy 354.449893 -339.791213)
			(xy 354.513903 -339.846678) (xy 354.572351 -339.907976) (xy 354.624707 -339.974552) (xy 354.670497 -340.045804)
			(xy 354.709308 -340.121085) (xy 354.740787 -340.199715) (xy 354.764648 -340.280982) (xy 354.780677 -340.364148)
			(xy 354.788728 -340.448462) (xy 354.789232 -340.49081) (xy 354.789232 -340.491064) (xy 354.788666 -340.535802)
			(xy 354.779649 -340.624824) (xy 354.761744 -340.712491) (xy 354.73513 -340.797919) (xy 354.718112 -340.839298)
			(xy 354.714539 -340.848887) (xy 354.714543 -340.869332) (xy 354.718112 -340.878922) (xy 354.735129 -340.920302)
			(xy 354.761749 -341.005728) (xy 354.779655 -341.093395) (xy 354.788666 -341.182417) (xy 354.789232 -341.227156)
			(xy 354.789232 -341.228172) (xy 354.789643 -341.238195) (xy 354.79731 -341.256718) (xy 354.811486 -341.270892)
			(xy 354.830009 -341.278557) (xy 354.840032 -341.278972) (xy 354.840286 -341.278972) (xy 354.84794 -341.278603)
			(xy 354.862532 -341.273956) (xy 354.868988 -341.269828) (xy 354.869242 -341.269828) (xy 354.906515 -341.244617)
			(xy 354.985224 -341.200991) (xy 355.067937 -341.165538) (xy 355.153807 -341.13862) (xy 355.241957 -341.120513)
			(xy 355.331485 -341.111402) (xy 355.37648 -341.110824) (xy 355.376988 -341.110824) (xy 355.418092 -341.111264)
			(xy 355.499949 -341.118848) (xy 355.580757 -341.133953) (xy 355.659827 -341.15645) (xy 355.736484 -341.186147)
			(xy 355.810073 -341.22279) (xy 355.879967 -341.266067) (xy 355.94557 -341.315609) (xy 356.006322 -341.370992)
			(xy 356.061704 -341.431745) (xy 356.111244 -341.497349) (xy 356.15452 -341.567245) (xy 356.191162 -341.640835)
			(xy 356.220857 -341.717492) (xy 356.243352 -341.796562) (xy 356.258455 -341.877371) (xy 356.266037 -341.959228)
			(xy 356.266496 -342.000332) (xy 356.266496 -342.000586) (xy 356.26594 -342.045325) (xy 356.256921 -342.134347)
			(xy 356.239013 -342.222014) (xy 356.212396 -342.307441) (xy 356.195376 -342.34882) (xy 356.191792 -342.358405)
			(xy 356.191804 -342.378853) (xy 356.195376 -342.388444) (xy 356.212409 -342.429852) (xy 356.239041 -342.515341)
			(xy 356.256946 -342.603073) (xy 356.265942 -342.692161) (xy 356.266496 -342.736932) (xy 356.265952 -342.781703)
			(xy 356.256945 -342.87079) (xy 356.239036 -342.958522) (xy 356.212407 -343.044011) (xy 356.195376 -343.08542)
			(xy 356.191792 -343.095005) (xy 356.191804 -343.115453) (xy 356.195376 -343.125044) (xy 356.212398 -343.166422)
			(xy 356.239017 -343.251848) (xy 356.256922 -343.339516) (xy 356.265931 -343.428539) (xy 356.266496 -343.473278)
			(xy 356.266496 -343.473532) (xy 356.266064 -343.514635) (xy 356.258476 -343.596491) (xy 356.243368 -343.677298)
			(xy 356.220868 -343.756366) (xy 356.191169 -343.83302) (xy 356.154525 -343.906608) (xy 356.111246 -343.9765)
			(xy 356.061704 -344.042101) (xy 356.00632 -344.102851) (xy 355.945567 -344.158232) (xy 355.879964 -344.207771)
			(xy 355.810069 -344.251046) (xy 355.73648 -344.287687) (xy 355.659824 -344.317382) (xy 355.580755 -344.339878)
			(xy 355.499948 -344.354982) (xy 355.418091 -344.362566) (xy 355.376988 -344.36304) (xy 355.376226 -344.36304)
			(xy 355.334685 -344.362565) (xy 355.251968 -344.35478) (xy 355.170337 -344.33932) (xy 355.090501 -344.316321)
			(xy 355.013156 -344.285984) (xy 354.938974 -344.248571) (xy 354.903532 -344.226896) (xy 354.894382 -344.221758)
			(xy 354.873674 -344.218535) (xy 354.853403 -344.223857) (xy 354.844858 -344.229944) (xy 354.811228 -344.255891)
			(xy 354.73985 -344.301947) (xy 354.664408 -344.340991) (xy 354.585588 -344.372667) (xy 354.504107 -344.396686)
			(xy 354.420709 -344.412831) (xy 354.336151 -344.420953) (xy 354.293678 -344.42146) (xy 354.293424 -344.42146)
			(xy 354.25232 -344.421025) (xy 354.170462 -344.413441) (xy 354.089653 -344.398337) (xy 354.010583 -344.375841)
			(xy 353.933926 -344.346144) (xy 353.860336 -344.309501) (xy 353.790441 -344.266224) (xy 353.724837 -344.216682)
			(xy 353.664085 -344.161298) (xy 353.608703 -344.100544) (xy 353.559163 -344.03494) (xy 353.515887 -343.965043)
			(xy 353.479246 -343.891453) (xy 353.449552 -343.814794) (xy 353.427057 -343.735723) (xy 353.411955 -343.654914)
			(xy 353.404374 -343.573056) (xy 353.403916 -343.531952) (xy 353.403916 -343.531698) (xy 353.4045 -343.48696)
			(xy 353.413511 -343.397939) (xy 353.431411 -343.310272) (xy 353.45802 -343.224844) (xy 353.475036 -343.183464)
			(xy 353.478628 -343.173881) (xy 353.47861 -343.153431) (xy 353.475036 -343.14384) (xy 353.457998 -343.102434)
			(xy 353.431368 -343.016945) (xy 353.413464 -342.929211) (xy 353.404469 -342.840123) (xy 353.403916 -342.795352)
			(xy 353.403916 -342.783414) (xy 353.377438 -342.777466) (xy 353.325203 -342.762725) (xy 353.299522 -342.75395)
			(xy 353.291325 -342.751436) (xy 353.274191 -342.751436) (xy 353.265994 -342.75395) (xy 353.230774 -342.765885)
			(xy 353.158765 -342.784475) (xy 353.085444 -342.796919) (xy 353.011333 -342.803127) (xy 352.974148 -342.80348)
			(xy 352.936964 -342.803098) (xy 352.862857 -342.79688) (xy 352.789537 -342.784441) (xy 352.717525 -342.76587)
			(xy 352.682302 -342.75395) (xy 352.674105 -342.751436) (xy 352.656971 -342.751436) (xy 352.648774 -342.75395)
			(xy 352.613678 -342.765853) (xy 352.541919 -342.784399) (xy 352.468854 -342.796841) (xy 352.395002 -342.80309)
			(xy 352.357944 -342.80348) (xy 352.356928 -342.80348) (xy 352.314999 -342.803074) (xy 352.231522 -342.795106)
			(xy 352.149179 -342.779238) (xy 352.068718 -342.755615) (xy 351.990867 -342.72445) (xy 351.916331 -342.686026)
			(xy 351.845785 -342.640691) (xy 351.779867 -342.588855) (xy 351.719176 -342.530987) (xy 351.66426 -342.467613)
			(xy 351.615617 -342.399306) (xy 351.573688 -342.326683) (xy 351.538852 -342.250404) (xy 351.511424 -342.171159)
			(xy 351.491654 -342.089666) (xy 351.479719 -342.006662) (xy 351.475729 -341.9229) (xy 107.867795 -341.9229)
			(xy 107.866258 -341.938099) (xy 107.848353 -342.02583) (xy 107.821735 -342.111321) (xy 107.804712 -342.152732)
			(xy 107.80112 -342.162315) (xy 107.801136 -342.182765) (xy 107.804712 -342.192356) (xy 107.821734 -342.233768)
			(xy 107.848372 -342.319255) (xy 107.86628 -342.406986) (xy 107.875278 -342.496074) (xy 107.875832 -342.540844)
			(xy 107.875405 -342.579435) (xy 107.868704 -342.656327) (xy 107.855365 -342.732349) (xy 107.835489 -342.806929)
			(xy 107.822746 -342.843358) (xy 107.81982 -342.852801) (xy 107.820595 -342.872535) (xy 107.82427 -342.881712)
			(xy 107.843302 -342.9251) (xy 107.873066 -343.015053) (xy 107.893096 -343.107662) (xy 107.903166 -343.201875)
			(xy 107.903772 -343.24925) (xy 107.903772 -343.249504) (xy 107.903199 -343.294273) (xy 107.894192 -343.383358)
			(xy 107.87629 -343.471089) (xy 107.849674 -343.556581) (xy 107.832652 -343.597992) (xy 107.829086 -343.607582)
			(xy 107.829087 -343.628025) (xy 107.832652 -343.637616) (xy 107.849695 -343.67902) (xy 107.876327 -343.76451)
			(xy 107.894229 -343.852244) (xy 107.903221 -343.941333) (xy 107.903772 -343.986104) (xy 107.903338 -344.0272)
			(xy 107.895755 -344.109042) (xy 107.880654 -344.189835) (xy 107.858164 -344.268891) (xy 107.828477 -344.345534)
			(xy 107.791846 -344.419112) (xy 107.748583 -344.488997) (xy 107.699057 -344.554593) (xy 107.643692 -344.61534)
			(xy 107.582958 -344.670721) (xy 107.517374 -344.720262) (xy 107.447499 -344.763541) (xy 107.37393 -344.80019)
			(xy 107.297294 -344.829896) (xy 107.218244 -344.852405) (xy 107.137454 -344.867525) (xy 107.055614 -344.875128)
			(xy 107.014518 -344.875612) (xy 107.01401 -344.875612) (xy 106.971454 -344.875048) (xy 106.886731 -344.866913)
			(xy 106.803172 -344.850725) (xy 106.72154 -344.826633) (xy 106.642582 -344.794856) (xy 106.567018 -344.755685)
			(xy 106.49554 -344.709478) (xy 106.428801 -344.656658) (xy 106.36741 -344.597706) (xy 106.311928 -344.533162)
			(xy 106.262863 -344.463615) (xy 106.220663 -344.389701) (xy 106.202734 -344.351102) (xy 106.197143 -344.340314)
			(xy 106.178175 -344.325188) (xy 106.166412 -344.322146) (xy 106.123815 -344.31302) (xy 106.04054 -344.287419)
			(xy 105.960165 -344.253801) (xy 105.883461 -344.212489) (xy 105.811162 -344.163878) (xy 105.74396 -344.108434)
			(xy 105.682498 -344.046687) (xy 105.627365 -343.979229) (xy 105.579089 -343.906705) (xy 105.538133 -343.829811)
			(xy 105.504888 -343.749281) (xy 105.479672 -343.665888) (xy 105.462727 -343.58043) (xy 105.454216 -343.493725)
			(xy 105.453688 -343.450164) (xy 105.454253 -343.405394) (xy 105.463263 -343.316309) (xy 105.481167 -343.228578)
			(xy 105.507785 -343.143087) (xy 105.524808 -343.101676) (xy 105.528395 -343.092092) (xy 105.528382 -343.071643)
			(xy 105.524808 -343.062052) (xy 105.508891 -343.02338) (xy 105.483531 -342.943684) (xy 105.46577 -342.861957)
			(xy 105.460292 -342.820498) (xy 105.458558 -342.81058) (xy 105.448632 -342.793088) (xy 105.43277 -342.780723)
			(xy 105.423208 -342.777572) (xy 105.40795 -342.773353) (xy 105.377717 -342.763951) (xy 105.362756 -342.758776)
			(xy 105.354559 -342.756262) (xy 105.337425 -342.756262) (xy 105.329228 -342.758776) (xy 105.294015 -342.770747)
			(xy 105.222011 -342.789399) (xy 105.148689 -342.801905) (xy 105.074572 -342.808175) (xy 105.037382 -342.80856)
			(xy 105.000192 -342.808173) (xy 104.926079 -342.801882) (xy 104.85276 -342.789372) (xy 104.780754 -342.770731)
			(xy 104.745536 -342.758776) (xy 104.737339 -342.756262) (xy 104.720205 -342.756262) (xy 104.712008 -342.758776)
			(xy 104.676797 -342.770753) (xy 104.604792 -342.789403) (xy 104.531469 -342.801908) (xy 104.457353 -342.808176)
			(xy 104.420162 -342.80856) (xy 104.378225 -342.808083) (xy 104.294732 -342.800107) (xy 104.212375 -342.784231)
			(xy 104.131899 -342.760598) (xy 104.054035 -342.729423) (xy 103.979486 -342.690988) (xy 103.908929 -342.64564)
			(xy 103.843001 -342.593792) (xy 103.7823 -342.535911) (xy 103.727376 -342.472522) (xy 103.678726 -342.4042)
			(xy 103.63679 -342.331563) (xy 103.601948 -342.255269) (xy 103.574517 -342.176008) (xy 103.554743 -342.094498)
			(xy 103.542807 -342.011479) (xy 103.538816 -341.9277) (xy 2.509012 -341.9277) (xy 2.509012 -345.238324)
			(xy 88.42502 -345.238324) (xy 88.42502 -345.237562) (xy 88.425476 -345.196455) (xy 88.433064 -345.114592)
			(xy 88.448171 -345.033778) (xy 88.470668 -344.954703) (xy 88.500364 -344.87804) (xy 88.537005 -344.804443)
			(xy 88.58028 -344.73454) (xy 88.629818 -344.668927) (xy 88.685198 -344.608163) (xy 88.745947 -344.552768)
			(xy 88.811546 -344.503212) (xy 88.881438 -344.459919) (xy 88.955025 -344.423259) (xy 89.031681 -344.393542)
			(xy 89.110751 -344.371024) (xy 89.19156 -344.355896) (xy 89.273421 -344.348287) (xy 89.314528 -344.3478)
			(xy 89.358923 -344.348358) (xy 89.447268 -344.357247) (xy 89.534288 -344.374894) (xy 89.619117 -344.401123)
			(xy 89.660222 -344.417904) (xy 89.668919 -344.421068) (xy 89.687398 -344.421734) (xy 89.69629 -344.419174)
			(xy 89.742575 -344.404089) (xy 89.837607 -344.382956) (xy 89.934379 -344.372329) (xy 89.983056 -344.371676)
			(xy 89.984326 -344.371676) (xy 90.022483 -344.372111) (xy 90.098512 -344.378695) (xy 90.173695 -344.391776)
			(xy 90.24748 -344.411259) (xy 90.283538 -344.423746) (xy 90.291854 -344.426332) (xy 90.309258 -344.426332)
			(xy 90.317574 -344.423746) (xy 90.353782 -344.41121) (xy 90.427885 -344.391692) (xy 90.503391 -344.378612)
			(xy 90.579741 -344.372068) (xy 90.618056 -344.371676) (xy 90.664451 -344.372276) (xy 90.756739 -344.381916)
			(xy 90.847523 -344.401107) (xy 90.935817 -344.429641) (xy 90.978482 -344.447876) (xy 90.988424 -344.451682)
			(xy 91.009688 -344.451682) (xy 91.01963 -344.447876) (xy 91.062298 -344.429645) (xy 91.150588 -344.401097)
			(xy 91.241371 -344.381901) (xy 91.33366 -344.372263) (xy 91.380056 -344.371676) (xy 91.418372 -344.372058)
			(xy 91.494725 -344.378586) (xy 91.570232 -344.391667) (xy 91.644331 -344.411203) (xy 91.680538 -344.423746)
			(xy 91.688854 -344.426332) (xy 91.706258 -344.426332) (xy 91.714574 -344.423746) (xy 91.750782 -344.41121)
			(xy 91.824885 -344.391692) (xy 91.900391 -344.378612) (xy 91.976741 -344.372068) (xy 92.015056 -344.371676)
			(xy 92.053372 -344.372058) (xy 92.129725 -344.378586) (xy 92.205232 -344.391667) (xy 92.279331 -344.411203)
			(xy 92.315538 -344.423746) (xy 92.323854 -344.426332) (xy 92.341258 -344.426332) (xy 92.349574 -344.423746)
			(xy 92.385691 -344.411238) (xy 92.459606 -344.391753) (xy 92.534918 -344.378674) (xy 92.611074 -344.372097)
			(xy 92.649294 -344.371676) (xy 92.650056 -344.371676) (xy 92.691158 -344.372194) (xy 92.773012 -344.379775)
			(xy 92.853817 -344.394876) (xy 92.932883 -344.417369) (xy 93.009537 -344.447061) (xy 93.083125 -344.4837)
			(xy 93.153018 -344.526972) (xy 93.21862 -344.576508) (xy 93.279371 -344.631887) (xy 93.334753 -344.692634)
			(xy 93.384294 -344.758233) (xy 93.427571 -344.828123) (xy 93.464215 -344.901708) (xy 93.493912 -344.97836)
			(xy 93.51641 -345.057425) (xy 93.531517 -345.138229) (xy 93.539103 -345.220082) (xy 93.539564 -345.261184)
			(xy 93.539564 -345.261692) (xy 93.539139 -345.302203) (xy 93.531771 -345.38289) (xy 93.517086 -345.462571)
			(xy 93.495207 -345.540583) (xy 93.466315 -345.616279) (xy 93.448886 -345.652852) (xy 93.444973 -345.661871)
			(xy 93.443532 -345.68146) (xy 93.446092 -345.690952) (xy 93.460285 -345.736019) (xy 93.480192 -345.828387)
			(xy 93.490186 -345.922345) (xy 93.490796 -345.96959) (xy 93.490238 -346.015229) (xy 93.480936 -346.106032)
			(xy 93.462388 -346.195406) (xy 93.44914 -346.239084) (xy 93.446696 -346.248096) (xy 93.447735 -346.266724)
			(xy 93.451172 -346.275406) (xy 93.469867 -346.318487) (xy 93.49915 -346.407722) (xy 93.518862 -346.499547)
			(xy 93.527728 -346.583) (xy 200.85558 -346.583) (xy 200.856207 -346.536598) (xy 200.865897 -346.444301)
			(xy 200.88515 -346.353515) (xy 200.913758 -346.26523) (xy 200.932034 -346.222574) (xy 200.935843 -346.212632)
			(xy 200.935843 -346.191368) (xy 200.932034 -346.181426) (xy 200.913772 -346.138765) (xy 200.885179 -346.050477)
			(xy 200.865922 -345.959694) (xy 200.856209 -345.867401) (xy 200.85558 -345.821) (xy 200.856064 -345.779859)
			(xy 200.863695 -345.69793) (xy 200.878855 -345.617056) (xy 200.901414 -345.537926) (xy 200.931179 -345.461215)
			(xy 200.967897 -345.38758) (xy 200.989184 -345.35237) (xy 200.993752 -345.344157) (xy 200.997195 -345.3257)
			(xy 200.993752 -345.307243) (xy 200.989184 -345.29903) (xy 200.967885 -345.263826) (xy 200.931155 -345.190194)
			(xy 200.901383 -345.113484) (xy 200.878824 -345.034352) (xy 200.86367 -344.953474) (xy 200.856051 -344.871542)
			(xy 200.85558 -344.8304) (xy 200.856207 -344.783998) (xy 200.865897 -344.691701) (xy 200.88515 -344.600915)
			(xy 200.913758 -344.51263) (xy 200.932034 -344.469974) (xy 200.935843 -344.460032) (xy 200.935843 -344.438768)
			(xy 200.932034 -344.428826) (xy 200.913772 -344.386165) (xy 200.885179 -344.297877) (xy 200.865922 -344.207094)
			(xy 200.856209 -344.114801) (xy 200.85558 -344.0684) (xy 200.856084 -344.026039) (xy 200.864137 -343.941702)
			(xy 200.880171 -343.858512) (xy 200.904039 -343.777222) (xy 200.935527 -343.69857) (xy 200.974349 -343.623267)
			(xy 201.020152 -343.551995) (xy 201.072523 -343.485399) (xy 201.130988 -343.424084) (xy 201.195016 -343.368603)
			(xy 201.264028 -343.31946) (xy 201.337398 -343.2771) (xy 201.414463 -343.241905) (xy 201.494525 -343.214196)
			(xy 201.576858 -343.194222) (xy 201.660717 -343.182165) (xy 201.745342 -343.178134) (xy 201.829967 -343.182165)
			(xy 201.913826 -343.194222) (xy 201.996159 -343.214196) (xy 202.076221 -343.241905) (xy 202.153286 -343.2771)
			(xy 202.226656 -343.31946) (xy 202.295668 -343.368603) (xy 202.359696 -343.424084) (xy 202.418161 -343.485399)
			(xy 202.470532 -343.551995) (xy 202.516335 -343.623267) (xy 202.555157 -343.69857) (xy 202.586645 -343.777222)
			(xy 202.610513 -343.858512) (xy 202.626547 -343.941702) (xy 202.6346 -344.026039) (xy 202.635104 -344.0684)
			(xy 202.634479 -344.114802) (xy 202.624789 -344.2071) (xy 202.605534 -344.297885) (xy 202.576926 -344.38617)
			(xy 202.55865 -344.428826) (xy 202.554842 -344.438768) (xy 202.554842 -344.460032) (xy 202.55865 -344.469974)
			(xy 202.576911 -344.512635) (xy 202.605505 -344.600923) (xy 202.624762 -344.691706) (xy 202.634475 -344.783999)
			(xy 202.635104 -344.8304) (xy 202.634622 -344.871541) (xy 202.626991 -344.95347) (xy 202.611831 -345.034344)
			(xy 202.589272 -345.113474) (xy 202.559506 -345.190185) (xy 202.522787 -345.263821) (xy 202.5015 -345.29903)
			(xy 202.496933 -345.307243) (xy 202.493491 -345.3257) (xy 202.496933 -345.344157) (xy 202.5015 -345.35237)
			(xy 202.522797 -345.387575) (xy 202.559528 -345.461207) (xy 202.5893 -345.537917) (xy 202.61186 -345.617049)
			(xy 202.627014 -345.697926) (xy 202.634633 -345.779858) (xy 202.635104 -345.821) (xy 202.634479 -345.867402)
			(xy 202.624789 -345.9597) (xy 202.605534 -346.050485) (xy 202.576926 -346.13877) (xy 202.55865 -346.181426)
			(xy 202.554842 -346.191368) (xy 202.554842 -346.212632) (xy 202.55865 -346.222574) (xy 202.576911 -346.265235)
			(xy 202.605505 -346.353523) (xy 202.624762 -346.444306) (xy 202.634475 -346.536599) (xy 202.635104 -346.583)
			(xy 202.6346 -346.625361) (xy 202.626547 -346.709698) (xy 202.610513 -346.792888) (xy 202.586645 -346.874178)
			(xy 202.555157 -346.95283) (xy 202.516335 -347.028133) (xy 202.470532 -347.099405) (xy 202.418161 -347.166001)
			(xy 202.359696 -347.227316) (xy 202.295668 -347.282797) (xy 202.226656 -347.33194) (xy 202.153286 -347.3743)
			(xy 202.076221 -347.409495) (xy 201.996159 -347.437204) (xy 201.913826 -347.457178) (xy 201.829967 -347.469235)
			(xy 201.745342 -347.473267) (xy 201.660717 -347.469235) (xy 201.576858 -347.457178) (xy 201.494525 -347.437204)
			(xy 201.414463 -347.409495) (xy 201.337398 -347.3743) (xy 201.264028 -347.33194) (xy 201.195016 -347.282797)
			(xy 201.130988 -347.227316) (xy 201.072523 -347.166001) (xy 201.020152 -347.099405) (xy 200.974349 -347.028133)
			(xy 200.935527 -346.95283) (xy 200.904039 -346.874178) (xy 200.880171 -346.792888) (xy 200.864137 -346.709698)
			(xy 200.856084 -346.625361) (xy 200.85558 -346.583) (xy 93.527728 -346.583) (xy 93.528784 -346.592938)
			(xy 93.529404 -346.639896) (xy 93.528944 -346.681007) (xy 93.521356 -346.762877) (xy 93.506246 -346.843698)
			(xy 93.483741 -346.92278) (xy 93.454034 -346.999447) (xy 93.417379 -347.073045) (xy 93.374088 -347.142947)
			(xy 93.324531 -347.208555) (xy 93.269131 -347.26931) (xy 93.20836 -347.324693) (xy 93.142737 -347.374232)
			(xy 93.072823 -347.417503) (xy 92.999214 -347.454137) (xy 92.922539 -347.483822) (xy 92.843451 -347.506304)
			(xy 92.762626 -347.521391) (xy 92.680753 -347.528955) (xy 92.639642 -347.529404) (xy 92.601326 -347.529024)
			(xy 92.524973 -347.522495) (xy 92.449466 -347.509414) (xy 92.375367 -347.489878) (xy 92.33916 -347.477334)
			(xy 92.330844 -347.474748) (xy 92.31344 -347.474748) (xy 92.305124 -347.477334) (xy 92.268906 -347.489842)
			(xy 92.194807 -347.509368) (xy 92.119304 -347.522455) (xy 92.042956 -347.529008) (xy 92.004642 -347.529404)
			(xy 91.961529 -347.52892) (xy 91.875703 -347.520642) (xy 91.791081 -347.504091) (xy 91.70846 -347.479423)
			(xy 91.668346 -347.463618) (xy 91.658977 -347.460281) (xy 91.639107 -347.460281) (xy 91.629738 -347.463618)
			(xy 91.589623 -347.479419) (xy 91.506999 -347.504075) (xy 91.422379 -347.520627) (xy 91.336554 -347.528919)
			(xy 91.293442 -347.529404) (xy 91.255126 -347.529024) (xy 91.178773 -347.522495) (xy 91.103266 -347.509414)
			(xy 91.029167 -347.489878) (xy 90.99296 -347.477334) (xy 90.984644 -347.474748) (xy 90.96724 -347.474748)
			(xy 90.958924 -347.477334) (xy 90.922706 -347.489842) (xy 90.848607 -347.509368) (xy 90.773104 -347.522455)
			(xy 90.696756 -347.529008) (xy 90.658442 -347.529404) (xy 90.620126 -347.529024) (xy 90.543773 -347.522495)
			(xy 90.468266 -347.509414) (xy 90.394167 -347.489878) (xy 90.35796 -347.477334) (xy 90.349644 -347.474748)
			(xy 90.33224 -347.474748) (xy 90.323924 -347.477334) (xy 90.287706 -347.489842) (xy 90.213607 -347.509368)
			(xy 90.138104 -347.522455) (xy 90.061756 -347.529008) (xy 90.023442 -347.529404) (xy 89.985126 -347.529024)
			(xy 89.908773 -347.522495) (xy 89.833266 -347.509414) (xy 89.759167 -347.489878) (xy 89.72296 -347.477334)
			(xy 89.714644 -347.474748) (xy 89.69724 -347.474748) (xy 89.688924 -347.477334) (xy 89.652807 -347.489842)
			(xy 89.578892 -347.509327) (xy 89.50358 -347.522407) (xy 89.427424 -347.528983) (xy 89.389204 -347.529404)
			(xy 89.388442 -347.529404) (xy 89.347337 -347.528847) (xy 89.265478 -347.521267) (xy 89.184667 -347.506168)
			(xy 89.105593 -347.483678) (xy 89.028932 -347.453989) (xy 88.955336 -347.417355) (xy 88.885433 -347.374087)
			(xy 88.81982 -347.324556) (xy 88.759057 -347.269183) (xy 88.70366 -347.20844) (xy 88.654104 -347.142846)
			(xy 88.61081 -347.07296) (xy 88.574148 -346.999378) (xy 88.54443 -346.922728) (xy 88.52191 -346.843663)
			(xy 88.506779 -346.762857) (xy 88.499168 -346.681001) (xy 88.49868 -346.639896) (xy 88.49928 -346.594251)
			(xy 88.508675 -346.503445) (xy 88.527305 -346.414075) (xy 88.54059 -346.370402) (xy 88.543039 -346.361391)
			(xy 88.541996 -346.342762) (xy 88.538558 -346.33408) (xy 88.519895 -346.290993) (xy 88.490688 -346.201748)
			(xy 88.471043 -346.109924) (xy 88.461176 -346.016541) (xy 88.46058 -345.96959) (xy 88.460997 -345.930463)
			(xy 88.467845 -345.852508) (xy 88.481506 -345.775455) (xy 88.501874 -345.699897) (xy 88.514936 -345.663012)
			(xy 88.517951 -345.653293) (xy 88.516917 -345.632991) (xy 88.512904 -345.623642) (xy 88.496039 -345.587523)
			(xy 88.46806 -345.512874) (xy 88.44687 -345.436021) (xy 88.432638 -345.357582) (xy 88.425479 -345.278184)
			(xy 88.42502 -345.238324) (xy 2.509012 -345.238324) (xy 2.509012 -348.70949) (xy 28.410141 -348.70949)
			(xy 28.414132 -348.625708) (xy 28.426069 -348.542686) (xy 28.445844 -348.461173) (xy 28.473277 -348.38191)
			(xy 28.508121 -348.305613) (xy 28.550059 -348.232974) (xy 28.598712 -348.16465) (xy 28.65364 -348.101261)
			(xy 28.714345 -348.043379) (xy 28.780276 -347.99153) (xy 28.850838 -347.946183) (xy 28.92539 -347.907749)
			(xy 29.003259 -347.876576) (xy 29.083738 -347.852945) (xy 29.166099 -347.837072) (xy 29.249596 -347.829099)
			(xy 29.291534 -347.828616) (xy 29.328723 -347.829023) (xy 29.402836 -347.835307) (xy 29.476156 -347.847812)
			(xy 29.548162 -347.866448) (xy 29.58338 -347.8784) (xy 29.591577 -347.880914) (xy 29.608711 -347.880914)
			(xy 29.616908 -347.8784) (xy 29.652035 -347.866473) (xy 29.723849 -347.847849) (xy 29.796976 -347.835339)
			(xy 29.870898 -347.829031) (xy 29.907992 -347.828616) (xy 29.909516 -347.828616) (xy 29.916374 -347.82887)
			(xy 29.922431 -347.792721) (xy 29.939716 -347.721486) (xy 29.962803 -347.651915) (xy 29.976826 -347.61805)
			(xy 29.980289 -347.608427) (xy 29.980173 -347.587996) (xy 29.976572 -347.578426) (xy 29.959544 -347.537016)
			(xy 29.932908 -347.451529) (xy 29.915001 -347.363797) (xy 29.906005 -347.274709) (xy 29.905452 -347.229938)
			(xy 29.905933 -347.189355) (xy 29.913331 -347.108527) (xy 29.928059 -347.028709) (xy 29.949995 -346.950564)
			(xy 29.978957 -346.874741) (xy 30.014703 -346.801871) (xy 30.056938 -346.732559) (xy 30.10531 -346.667382)
			(xy 30.159416 -346.606881) (xy 30.218807 -346.551559) (xy 30.28299 -346.501876) (xy 30.351431 -346.458245)
			(xy 30.38729 -346.439236) (xy 30.395816 -346.434265) (xy 30.408633 -346.419285) (xy 30.414885 -346.400588)
			(xy 30.414722 -346.390722) (xy 30.41396 -346.365322) (xy 30.414481 -346.337437) (xy 30.422793 -346.28229)
			(xy 30.439231 -346.228998) (xy 30.463429 -346.178752) (xy 30.494845 -346.132673) (xy 30.532778 -346.091791)
			(xy 30.57638 -346.057019) (xy 30.624678 -346.029134) (xy 30.676593 -346.008759) (xy 30.730964 -345.996349)
			(xy 30.786578 -345.992182) (xy 30.842192 -345.996349) (xy 30.896563 -346.008759) (xy 30.948478 -346.029134)
			(xy 30.996776 -346.057019) (xy 31.040378 -346.091791) (xy 31.078311 -346.132673) (xy 31.109727 -346.178752)
			(xy 31.133925 -346.228998) (xy 31.150363 -346.28229) (xy 31.158675 -346.337437) (xy 31.159196 -346.365322)
			(xy 31.158688 -346.383356) (xy 31.15866 -346.393249) (xy 31.165282 -346.411875) (xy 31.178455 -346.426614)
			(xy 31.187136 -346.431362) (xy 31.224041 -346.449965) (xy 31.294555 -346.49308) (xy 31.360766 -346.542551)
			(xy 31.4221 -346.597952) (xy 31.47803 -346.658805) (xy 31.528073 -346.724585) (xy 31.571797 -346.794724)
			(xy 31.608825 -346.868616) (xy 31.638837 -346.945626) (xy 31.661575 -347.025088) (xy 31.676842 -347.106317)
			(xy 31.684507 -347.188612) (xy 31.684976 -347.229938) (xy 31.684414 -347.274708) (xy 31.675404 -347.363793)
			(xy 31.657499 -347.451524) (xy 31.630879 -347.537015) (xy 31.613856 -347.578426) (xy 31.61027 -347.58801)
			(xy 31.610284 -347.608459) (xy 31.613856 -347.61805) (xy 31.630031 -347.657368) (xy 31.655701 -347.738424)
			(xy 31.673532 -347.821557) (xy 31.68336 -347.906011) (xy 31.684722 -347.948504) (xy 31.684976 -347.96222)
			(xy 31.6992 -347.985588) (xy 31.788862 -348.034102) (xy 31.796927 -348.038113) (xy 31.814734 -348.040741)
			(xy 31.832352 -348.037052) (xy 31.84017 -348.032578) (xy 31.875522 -348.010993) (xy 31.949529 -347.973778)
			(xy 32.026677 -347.943609) (xy 32.106297 -347.920748) (xy 32.187699 -347.905393) (xy 32.270176 -347.897677)
			(xy 32.311594 -347.897196) (xy 32.352707 -347.897719) (xy 32.434582 -347.905305) (xy 32.515408 -347.920413)
			(xy 32.594495 -347.942914) (xy 32.671169 -347.972616) (xy 32.744775 -348.009266) (xy 32.814686 -348.05255)
			(xy 32.880304 -348.102101) (xy 32.941071 -348.157495) (xy 32.996468 -348.218259) (xy 33.046022 -348.283875)
			(xy 33.089311 -348.353783) (xy 33.125965 -348.427387) (xy 33.155671 -348.504059) (xy 33.178176 -348.583145)
			(xy 33.193289 -348.66397) (xy 33.197509 -348.70949) (xy 36.690541 -348.70949) (xy 36.694532 -348.625708)
			(xy 36.706469 -348.542686) (xy 36.726244 -348.461173) (xy 36.753677 -348.38191) (xy 36.788521 -348.305613)
			(xy 36.830459 -348.232974) (xy 36.879112 -348.16465) (xy 36.93404 -348.101261) (xy 36.994745 -348.043379)
			(xy 37.060676 -347.99153) (xy 37.131238 -347.946183) (xy 37.20579 -347.907749) (xy 37.283659 -347.876576)
			(xy 37.364138 -347.852945) (xy 37.446499 -347.837072) (xy 37.529996 -347.829099) (xy 37.571934 -347.828616)
			(xy 37.609123 -347.829023) (xy 37.683236 -347.835307) (xy 37.756556 -347.847812) (xy 37.828562 -347.866448)
			(xy 37.86378 -347.8784) (xy 37.871977 -347.880914) (xy 37.889111 -347.880914) (xy 37.897308 -347.8784)
			(xy 37.93549 -347.865472) (xy 38.013674 -347.845816) (xy 38.093328 -347.833391) (xy 38.133528 -347.830394)
			(xy 38.144516 -347.829167) (xy 38.163935 -347.818636) (xy 38.177169 -347.800949) (xy 38.18001 -347.790262)
			(xy 38.189419 -347.748079) (xy 38.215379 -347.665637) (xy 38.231826 -347.62567) (xy 38.235335 -347.61606)
			(xy 38.235189 -347.595617) (xy 38.231572 -347.586046) (xy 38.21455 -347.544634) (xy 38.187912 -347.459147)
			(xy 38.170004 -347.371416) (xy 38.161006 -347.282328) (xy 38.160452 -347.237558) (xy 38.160956 -347.195197)
			(xy 38.169009 -347.11086) (xy 38.185043 -347.02767) (xy 38.208911 -346.94638) (xy 38.240399 -346.867728)
			(xy 38.279221 -346.792425) (xy 38.325024 -346.721153) (xy 38.377395 -346.654557) (xy 38.43586 -346.593242)
			(xy 38.499888 -346.537761) (xy 38.5689 -346.488618) (xy 38.64227 -346.446258) (xy 38.719335 -346.411063)
			(xy 38.799397 -346.383354) (xy 38.88173 -346.36338) (xy 38.965589 -346.351323) (xy 39.050214 -346.347292)
			(xy 39.134839 -346.351323) (xy 39.218698 -346.36338) (xy 39.301031 -346.383354) (xy 39.381093 -346.411063)
			(xy 39.458158 -346.446258) (xy 39.531528 -346.488618) (xy 39.60054 -346.537761) (xy 39.664568 -346.593242)
			(xy 39.723033 -346.654557) (xy 39.775404 -346.721153) (xy 39.821207 -346.792425) (xy 39.860029 -346.867728)
			(xy 39.891517 -346.94638) (xy 39.915385 -347.02767) (xy 39.931419 -347.11086) (xy 39.939472 -347.195197)
			(xy 39.939976 -347.237558) (xy 39.939421 -347.282328) (xy 39.930409 -347.371413) (xy 39.912502 -347.459144)
			(xy 39.88588 -347.544635) (xy 39.868856 -347.586046) (xy 39.865251 -347.595621) (xy 39.865104 -347.616057)
			(xy 39.868602 -347.62567) (xy 39.88516 -347.665899) (xy 39.911278 -347.748887) (xy 39.929176 -347.834027)
			(xy 39.938683 -347.920507) (xy 39.939722 -347.963998) (xy 39.939722 -347.964252) (xy 39.94031 -347.973302)
			(xy 39.94696 -347.990157) (xy 39.959055 -348.003648) (xy 39.9669 -348.008194) (xy 40.058086 -348.056454)
			(xy 40.086026 -348.05493) (xy 40.09771 -348.04731) (xy 40.134305 -348.023444) (xy 40.211348 -347.98223)
			(xy 40.292061 -347.948768) (xy 40.375665 -347.923381) (xy 40.461356 -347.906311) (xy 40.548307 -347.897725)
			(xy 40.591994 -347.897196) (xy 40.633107 -347.897719) (xy 40.714982 -347.905305) (xy 40.795808 -347.920413)
			(xy 40.874895 -347.942914) (xy 40.951569 -347.972616) (xy 41.025175 -348.009266) (xy 41.095086 -348.05255)
			(xy 41.160704 -348.102101) (xy 41.221471 -348.157495) (xy 41.276868 -348.218259) (xy 41.326422 -348.283875)
			(xy 41.369711 -348.353783) (xy 41.406365 -348.427387) (xy 41.436071 -348.504059) (xy 41.458576 -348.583145)
			(xy 41.473689 -348.66397) (xy 41.47791 -348.7095) (xy 44.996301 -348.7095) (xy 45.000292 -348.625716)
			(xy 45.01223 -348.54269) (xy 45.032006 -348.461175) (xy 45.05944 -348.381909) (xy 45.094286 -348.30561)
			(xy 45.136227 -348.232969) (xy 45.184883 -348.164644) (xy 45.239813 -348.101253) (xy 45.30052 -348.043371)
			(xy 45.366455 -347.991522) (xy 45.43702 -347.946175) (xy 45.511576 -347.907741) (xy 45.589448 -347.876568)
			(xy 45.66993 -347.852939) (xy 45.752294 -347.837068) (xy 45.835794 -347.829098) (xy 45.877734 -347.828616)
			(xy 45.914923 -347.829023) (xy 45.989036 -347.835307) (xy 46.062356 -347.847812) (xy 46.134362 -347.866448)
			(xy 46.16958 -347.8784) (xy 46.177777 -347.880914) (xy 46.194911 -347.880914) (xy 46.203108 -347.8784)
			(xy 46.238327 -347.866445) (xy 46.310329 -347.847789) (xy 46.383649 -347.835279) (xy 46.457764 -347.829003)
			(xy 46.494954 -347.828616) (xy 46.496732 -347.82887) (xy 46.506097 -347.78788) (xy 46.53154 -347.707736)
			(xy 46.547532 -347.66885) (xy 46.551076 -347.659253) (xy 46.55109 -347.638816) (xy 46.547532 -347.629226)
			(xy 46.530501 -347.587817) (xy 46.503866 -347.502329) (xy 46.485961 -347.414597) (xy 46.476965 -347.325509)
			(xy 46.476412 -347.280738) (xy 46.476916 -347.238377) (xy 46.484969 -347.15404) (xy 46.501003 -347.07085)
			(xy 46.524871 -346.98956) (xy 46.556359 -346.910908) (xy 46.595181 -346.835605) (xy 46.640984 -346.764333)
			(xy 46.693355 -346.697737) (xy 46.75182 -346.636422) (xy 46.815848 -346.580941) (xy 46.88486 -346.531798)
			(xy 46.95823 -346.489438) (xy 47.035295 -346.454243) (xy 47.115357 -346.426534) (xy 47.19769 -346.40656)
			(xy 47.281549 -346.394503) (xy 47.366174 -346.390472) (xy 47.450799 -346.394503) (xy 47.534658 -346.40656)
			(xy 47.616991 -346.426534) (xy 47.697053 -346.454243) (xy 47.774118 -346.489438) (xy 47.847488 -346.531798)
			(xy 47.9165 -346.580941) (xy 47.980528 -346.636422) (xy 48.038993 -346.697737) (xy 48.091364 -346.764333)
			(xy 48.137167 -346.835605) (xy 48.175989 -346.910908) (xy 48.207477 -346.98956) (xy 48.231345 -347.07085)
			(xy 48.247379 -347.15404) (xy 48.255432 -347.238377) (xy 48.255936 -347.280738) (xy 48.25537 -347.325508)
			(xy 48.24636 -347.414592) (xy 48.228456 -347.502324) (xy 48.201838 -347.587815) (xy 48.184816 -347.629226)
			(xy 48.181232 -347.638811) (xy 48.181246 -347.659259) (xy 48.184816 -347.66885) (xy 48.199304 -347.703977)
			(xy 48.222973 -347.776187) (xy 48.2404 -347.850153) (xy 48.251457 -347.925335) (xy 48.254158 -347.963236)
			(xy 48.255104 -347.972078) (xy 48.26215 -347.988388) (xy 48.274337 -348.001315) (xy 48.282098 -348.005654)
			(xy 48.37303 -348.051374) (xy 48.3997 -348.04985) (xy 48.41113 -348.04223) (xy 48.447343 -348.019182)
			(xy 48.523387 -347.979349) (xy 48.602912 -347.947022) (xy 48.685181 -347.922504) (xy 48.769429 -347.90602)
			(xy 48.854872 -347.897725) (xy 48.897794 -347.897196) (xy 48.938907 -347.897719) (xy 49.020782 -347.905305)
			(xy 49.101608 -347.920413) (xy 49.180695 -347.942914) (xy 49.257369 -347.972616) (xy 49.330975 -348.009266)
			(xy 49.400886 -348.05255) (xy 49.466504 -348.102101) (xy 49.527271 -348.157495) (xy 49.582668 -348.218259)
			(xy 49.632222 -348.283875) (xy 49.675511 -348.353783) (xy 49.712165 -348.427387) (xy 49.741871 -348.504059)
			(xy 49.764376 -348.583145) (xy 49.779489 -348.66397) (xy 49.78371 -348.7095) (xy 53.352901 -348.7095)
			(xy 53.356892 -348.625716) (xy 53.36883 -348.54269) (xy 53.388606 -348.461175) (xy 53.41604 -348.381909)
			(xy 53.450886 -348.30561) (xy 53.492827 -348.232969) (xy 53.541483 -348.164644) (xy 53.596413 -348.101253)
			(xy 53.65712 -348.043371) (xy 53.723055 -347.991522) (xy 53.79362 -347.946175) (xy 53.868176 -347.907741)
			(xy 53.946048 -347.876568) (xy 54.02653 -347.852939) (xy 54.108894 -347.837068) (xy 54.192394 -347.829098)
			(xy 54.234334 -347.828616) (xy 54.271523 -347.829023) (xy 54.345636 -347.835307) (xy 54.418956 -347.847812)
			(xy 54.490962 -347.866448) (xy 54.52618 -347.8784) (xy 54.534377 -347.880914) (xy 54.551511 -347.880914)
			(xy 54.559708 -347.8784) (xy 54.594654 -347.86653) (xy 54.66609 -347.847969) (xy 54.738831 -347.835458)
			(xy 54.812365 -347.829087) (xy 54.849268 -347.828616) (xy 54.85384 -347.82887) (xy 54.854348 -347.82887)
			(xy 54.863907 -347.782599) (xy 54.89152 -347.692237) (xy 54.909466 -347.64853) (xy 54.912939 -347.63891)
			(xy 54.912815 -347.618477) (xy 54.909212 -347.608906) (xy 54.892173 -347.5675) (xy 54.865541 -347.482011)
			(xy 54.847637 -347.394278) (xy 54.838644 -347.305189) (xy 54.838092 -347.260418) (xy 54.838596 -347.218057)
			(xy 54.846649 -347.13372) (xy 54.862683 -347.05053) (xy 54.886551 -346.96924) (xy 54.918039 -346.890588)
			(xy 54.956861 -346.815285) (xy 55.002664 -346.744013) (xy 55.055035 -346.677417) (xy 55.1135 -346.616102)
			(xy 55.177528 -346.560621) (xy 55.24654 -346.511478) (xy 55.31991 -346.469118) (xy 55.396975 -346.433923)
			(xy 55.477037 -346.406214) (xy 55.55937 -346.38624) (xy 55.643229 -346.374183) (xy 55.727854 -346.370152)
			(xy 55.812479 -346.374183) (xy 55.896338 -346.38624) (xy 55.978671 -346.406214) (xy 56.058733 -346.433923)
			(xy 56.135798 -346.469118) (xy 56.209168 -346.511478) (xy 56.27818 -346.560621) (xy 56.342208 -346.616102)
			(xy 56.400673 -346.677417) (xy 56.453044 -346.744013) (xy 56.498847 -346.815285) (xy 56.537669 -346.890588)
			(xy 56.569157 -346.96924) (xy 56.593025 -347.05053) (xy 56.609059 -347.13372) (xy 56.617112 -347.218057)
			(xy 56.617616 -347.260418) (xy 56.617044 -347.305187) (xy 56.608037 -347.394272) (xy 56.590134 -347.482003)
			(xy 56.563518 -347.567495) (xy 56.546496 -347.608906) (xy 56.542919 -347.618493) (xy 56.542926 -347.63894)
			(xy 56.546496 -347.64853) (xy 56.561684 -347.685398) (xy 56.586189 -347.761282) (xy 56.603812 -347.839053)
			(xy 56.614411 -347.918088) (xy 56.6166 -347.957902) (xy 56.617108 -347.971364) (xy 56.63184 -347.994224)
			(xy 56.734456 -348.047564) (xy 56.761634 -348.04604) (xy 56.773064 -348.038674) (xy 56.808981 -348.016152)
			(xy 56.88432 -347.977266) (xy 56.963017 -347.945725) (xy 57.044358 -347.921816) (xy 57.127605 -347.905754)
			(xy 57.212003 -347.897686) (xy 57.254394 -347.897196) (xy 57.295507 -347.897719) (xy 57.377382 -347.905305)
			(xy 57.458208 -347.920413) (xy 57.537295 -347.942914) (xy 57.613969 -347.972616) (xy 57.687575 -348.009266)
			(xy 57.757486 -348.05255) (xy 57.823104 -348.102101) (xy 57.883871 -348.157495) (xy 57.939268 -348.218259)
			(xy 57.988822 -348.283875) (xy 58.032111 -348.353783) (xy 58.068765 -348.427387) (xy 58.098471 -348.504059)
			(xy 58.120976 -348.583145) (xy 58.136089 -348.66397) (xy 58.14031 -348.7095) (xy 61.684101 -348.7095)
			(xy 61.688092 -348.625716) (xy 61.70003 -348.54269) (xy 61.719806 -348.461175) (xy 61.74724 -348.381909)
			(xy 61.782086 -348.30561) (xy 61.824027 -348.232969) (xy 61.872683 -348.164644) (xy 61.927613 -348.101253)
			(xy 61.98832 -348.043371) (xy 62.054255 -347.991522) (xy 62.12482 -347.946175) (xy 62.199376 -347.907741)
			(xy 62.277248 -347.876568) (xy 62.35773 -347.852939) (xy 62.440094 -347.837068) (xy 62.523594 -347.829098)
			(xy 62.565534 -347.828616) (xy 62.602723 -347.829023) (xy 62.676836 -347.835307) (xy 62.750156 -347.847812)
			(xy 62.822162 -347.866448) (xy 62.85738 -347.8784) (xy 62.865577 -347.880914) (xy 62.882711 -347.880914)
			(xy 62.890908 -347.8784) (xy 62.926096 -347.866455) (xy 62.998036 -347.847809) (xy 63.071292 -347.835299)
			(xy 63.145342 -347.829013) (xy 63.1825 -347.828616) (xy 63.183008 -347.828616) (xy 63.206122 -347.829124)
			(xy 63.215205 -347.793715) (xy 63.238479 -347.724411) (xy 63.252604 -347.690694) (xy 63.256229 -347.680981)
			(xy 63.25624 -347.66027) (xy 63.252604 -347.650562) (xy 63.235485 -347.609307) (xy 63.208697 -347.524095)
			(xy 63.190664 -347.436611) (xy 63.181571 -347.347751) (xy 63.180976 -347.30309) (xy 63.180976 -347.302328)
			(xy 63.181475 -347.260403) (xy 63.189445 -347.176932) (xy 63.205314 -347.094597) (xy 63.228937 -347.014143)
			(xy 63.260101 -346.936299) (xy 63.298524 -346.861769) (xy 63.343857 -346.79123) (xy 63.39569 -346.725319)
			(xy 63.453553 -346.664633) (xy 63.516923 -346.609723) (xy 63.585226 -346.561085) (xy 63.657843 -346.51916)
			(xy 63.734116 -346.484327) (xy 63.813355 -346.456902) (xy 63.894841 -346.437133) (xy 63.977838 -346.4252)
			(xy 64.061594 -346.421211) (xy 64.14535 -346.4252) (xy 64.228347 -346.437133) (xy 64.309833 -346.456902)
			(xy 64.389072 -346.484327) (xy 64.465345 -346.51916) (xy 64.537962 -346.561085) (xy 64.606265 -346.609723)
			(xy 64.669635 -346.664633) (xy 64.727498 -346.725319) (xy 64.779331 -346.79123) (xy 64.824664 -346.861769)
			(xy 64.863087 -346.936299) (xy 64.894251 -347.014143) (xy 64.917874 -347.094597) (xy 64.933743 -347.176932)
			(xy 64.941713 -347.260403) (xy 64.942212 -347.302328) (xy 64.942212 -347.30309) (xy 64.941639 -347.347753)
			(xy 64.932567 -347.436619) (xy 64.914535 -347.524107) (xy 64.88773 -347.609317) (xy 64.870584 -347.650562)
			(xy 64.866927 -347.660266) (xy 64.866937 -347.680985) (xy 64.870584 -347.690694) (xy 64.888862 -347.734789)
			(xy 64.91689 -347.826038) (xy 64.934892 -347.919782) (xy 64.939418 -347.9673) (xy 64.940434 -347.980508)
			(xy 64.955674 -348.00286) (xy 65.046352 -348.047056) (xy 65.054393 -348.050544) (xy 65.071798 -348.052482)
			(xy 65.088843 -348.048463) (xy 65.09639 -348.044008) (xy 65.096644 -348.043754) (xy 65.132959 -348.020439)
			(xy 65.209305 -347.980191) (xy 65.289189 -347.947525) (xy 65.371861 -347.922748) (xy 65.456544 -347.906093)
			(xy 65.542442 -347.897716) (xy 65.585594 -347.897196) (xy 65.626707 -347.897719) (xy 65.708582 -347.905305)
			(xy 65.789408 -347.920413) (xy 65.868495 -347.942914) (xy 65.945169 -347.972616) (xy 66.018775 -348.009266)
			(xy 66.088686 -348.05255) (xy 66.154304 -348.102101) (xy 66.215071 -348.157495) (xy 66.270468 -348.218259)
			(xy 66.320022 -348.283875) (xy 66.363311 -348.353783) (xy 66.399965 -348.427387) (xy 66.429671 -348.504059)
			(xy 66.452176 -348.583145) (xy 66.467289 -348.66397) (xy 66.474879 -348.745845) (xy 66.475356 -348.786958)
			(xy 66.474795 -348.831728) (xy 66.467942 -348.89948) (xy 81.294224 -348.89948) (xy 81.294687 -348.858913)
			(xy 81.30208 -348.778118) (xy 81.316804 -348.698332) (xy 81.338734 -348.620219) (xy 81.36769 -348.544429)
			(xy 81.385156 -348.507812) (xy 81.389058 -348.498717) (xy 81.390365 -348.478988) (xy 81.387696 -348.469458)
			(xy 81.373498 -348.424437) (xy 81.353605 -348.332151) (xy 81.343609 -348.238277) (xy 81.342992 -348.191074)
			(xy 81.343496 -348.148713) (xy 81.351549 -348.064376) (xy 81.367583 -347.981186) (xy 81.391451 -347.899896)
			(xy 81.422939 -347.821244) (xy 81.461761 -347.745941) (xy 81.507564 -347.674669) (xy 81.559935 -347.608073)
			(xy 81.6184 -347.546758) (xy 81.682428 -347.491277) (xy 81.75144 -347.442134) (xy 81.82481 -347.399774)
			(xy 81.901875 -347.364579) (xy 81.981937 -347.33687) (xy 82.06427 -347.316896) (xy 82.148129 -347.304839)
			(xy 82.232754 -347.300808) (xy 82.317379 -347.304839) (xy 82.401238 -347.316896) (xy 82.483571 -347.33687)
			(xy 82.563633 -347.364579) (xy 82.640698 -347.399774) (xy 82.714068 -347.442134) (xy 82.78308 -347.491277)
			(xy 82.847108 -347.546758) (xy 82.905573 -347.608073) (xy 82.957944 -347.674669) (xy 83.003747 -347.745941)
			(xy 83.042569 -347.821244) (xy 83.074057 -347.899896) (xy 83.097925 -347.981186) (xy 83.113959 -348.064376)
			(xy 83.122012 -348.148713) (xy 83.122516 -348.191074) (xy 83.12207 -348.231641) (xy 83.114672 -348.312437)
			(xy 83.099945 -348.392223) (xy 83.07801 -348.470336) (xy 83.049051 -348.546125) (xy 83.031584 -348.582742)
			(xy 83.027707 -348.591846) (xy 83.026383 -348.611567) (xy 83.029044 -348.621096) (xy 83.043232 -348.66612)
			(xy 83.063129 -348.758404) (xy 83.073129 -348.852278) (xy 83.073245 -348.861126) (xy 83.956144 -348.861126)
			(xy 83.956552 -348.820564) (xy 83.963891 -348.739773) (xy 83.978566 -348.659987) (xy 84.000454 -348.581872)
			(xy 84.029373 -348.506078) (xy 84.046822 -348.469458) (xy 84.05073 -348.460437) (xy 84.052174 -348.440849)
			(xy 84.049616 -348.431358) (xy 84.035467 -348.386455) (xy 84.015597 -348.294425) (xy 84.005567 -348.200811)
			(xy 84.004912 -348.153736) (xy 84.004912 -348.15272) (xy 84.005416 -348.110372) (xy 84.013467 -348.026058)
			(xy 84.029496 -347.942892) (xy 84.053357 -347.861625) (xy 84.084836 -347.782995) (xy 84.123647 -347.707714)
			(xy 84.169437 -347.636462) (xy 84.221793 -347.569886) (xy 84.280241 -347.508588) (xy 84.344251 -347.453123)
			(xy 84.413243 -347.403994) (xy 84.486593 -347.361645) (xy 84.563636 -347.326461) (xy 84.643675 -347.298759)
			(xy 84.725984 -347.278791) (xy 84.809819 -347.266738) (xy 84.89442 -347.262708) (xy 84.979021 -347.266738)
			(xy 85.062856 -347.278791) (xy 85.145165 -347.298759) (xy 85.225204 -347.326461) (xy 85.302247 -347.361645)
			(xy 85.375597 -347.403994) (xy 85.444589 -347.453123) (xy 85.508599 -347.508588) (xy 85.567047 -347.569886)
			(xy 85.619403 -347.636462) (xy 85.665193 -347.707714) (xy 85.704004 -347.782995) (xy 85.735483 -347.861625)
			(xy 85.759344 -347.942892) (xy 85.775373 -348.026058) (xy 85.783424 -348.110372) (xy 85.783928 -348.15272)
			(xy 85.783928 -348.153228) (xy 85.783471 -348.193738) (xy 85.77611 -348.274424) (xy 85.761432 -348.354104)
			(xy 85.73956 -348.432117) (xy 85.710675 -348.507814) (xy 85.69325 -348.544388) (xy 85.689318 -348.553401)
			(xy 85.687887 -348.572996) (xy 85.690456 -348.582488) (xy 85.70466 -348.627551) (xy 85.721282 -348.7047)
			(xy 275.231844 -348.7047) (xy 275.235834 -348.620942) (xy 275.247768 -348.537942) (xy 275.267537 -348.456452)
			(xy 275.294962 -348.377211) (xy 275.329796 -348.300935) (xy 275.371722 -348.228316) (xy 275.420361 -348.16001)
			(xy 275.475273 -348.096638) (xy 275.53596 -348.038772) (xy 275.601873 -347.986937) (xy 275.672414 -347.941602)
			(xy 275.746946 -347.903177) (xy 275.824792 -347.872011) (xy 275.905248 -347.848386) (xy 275.987586 -347.832515)
			(xy 276.071059 -347.824543) (xy 276.112986 -347.824044) (xy 276.114002 -347.824044) (xy 276.151059 -347.824452)
			(xy 276.224908 -347.830716) (xy 276.29797 -347.843157) (xy 276.36973 -347.861689) (xy 276.404832 -347.873574)
			(xy 276.413029 -347.876088) (xy 276.430163 -347.876088) (xy 276.43836 -347.873574) (xy 276.478966 -347.8599)
			(xy 276.562216 -347.839604) (xy 276.647042 -347.827484) (xy 276.68982 -347.82506) (xy 276.700434 -347.823969)
			(xy 276.719453 -347.814348) (xy 276.732947 -347.797851) (xy 276.736302 -347.787722) (xy 276.744404 -347.759433)
			(xy 276.763852 -347.703889) (xy 276.775164 -347.676724) (xy 276.778721 -347.667131) (xy 276.778725 -347.646691)
			(xy 276.775164 -347.6371) (xy 276.758127 -347.595694) (xy 276.731493 -347.510205) (xy 276.713589 -347.422472)
			(xy 276.704596 -347.333383) (xy 276.704044 -347.288612) (xy 276.704548 -347.246251) (xy 276.712601 -347.161914)
			(xy 276.728635 -347.078724) (xy 276.752503 -346.997434) (xy 276.783991 -346.918782) (xy 276.822813 -346.843479)
			(xy 276.868616 -346.772207) (xy 276.920987 -346.705611) (xy 276.979452 -346.644296) (xy 277.04348 -346.588815)
			(xy 277.112492 -346.539672) (xy 277.185862 -346.497312) (xy 277.262927 -346.462117) (xy 277.342989 -346.434408)
			(xy 277.425322 -346.414434) (xy 277.509181 -346.402377) (xy 277.593806 -346.398346) (xy 277.678431 -346.402377)
			(xy 277.76229 -346.414434) (xy 277.844623 -346.434408) (xy 277.924685 -346.462117) (xy 278.00175 -346.497312)
			(xy 278.07512 -346.539672) (xy 278.144132 -346.588815) (xy 278.20816 -346.644296) (xy 278.266625 -346.705611)
			(xy 278.318996 -346.772207) (xy 278.364799 -346.843479) (xy 278.403621 -346.918782) (xy 278.435109 -346.997434)
			(xy 278.458977 -347.078724) (xy 278.475011 -347.161914) (xy 278.483064 -347.246251) (xy 278.483568 -347.288612)
			(xy 278.482998 -347.333381) (xy 278.47399 -347.422466) (xy 278.456088 -347.510198) (xy 278.42947 -347.595689)
			(xy 278.412448 -347.6371) (xy 278.408812 -347.646665) (xy 278.408686 -347.667111) (xy 278.412194 -347.676724)
			(xy 278.426408 -347.711074) (xy 278.449728 -347.781668) (xy 278.467082 -347.85396) (xy 278.478348 -347.927447)
			(xy 278.481282 -347.964506) (xy 278.482267 -347.973327) (xy 278.489457 -347.989544) (xy 278.501708 -348.002373)
			(xy 278.509476 -348.00667) (xy 278.600662 -348.051628) (xy 278.62784 -348.049596) (xy 278.639016 -348.04223)
			(xy 278.675581 -348.018458) (xy 278.752524 -347.977387) (xy 278.833117 -347.944041) (xy 278.916586 -347.91874)
			(xy 279.00213 -347.901729) (xy 279.088929 -347.893169) (xy 279.132538 -347.892624) (xy 279.133046 -347.892624)
			(xy 279.174153 -347.893069) (xy 279.256016 -347.900657) (xy 279.336831 -347.915765) (xy 279.415907 -347.938263)
			(xy 279.49257 -347.96796) (xy 279.566167 -348.004602) (xy 279.63607 -348.047877) (xy 279.701683 -348.097416)
			(xy 279.762447 -348.152796) (xy 279.817842 -348.213546) (xy 279.867398 -348.279147) (xy 279.91069 -348.349039)
			(xy 279.947351 -348.422627) (xy 279.977067 -348.499283) (xy 279.999585 -348.578353) (xy 280.014712 -348.659164)
			(xy 280.018945 -348.7047) (xy 283.512244 -348.7047) (xy 283.516234 -348.620942) (xy 283.528168 -348.537942)
			(xy 283.547937 -348.456452) (xy 283.575362 -348.377211) (xy 283.610196 -348.300935) (xy 283.652122 -348.228316)
			(xy 283.700761 -348.16001) (xy 283.755673 -348.096638) (xy 283.81636 -348.038772) (xy 283.882273 -347.986937)
			(xy 283.952814 -347.941602) (xy 284.027346 -347.903177) (xy 284.105192 -347.872011) (xy 284.185648 -347.848386)
			(xy 284.267986 -347.832515) (xy 284.351459 -347.824543) (xy 284.393386 -347.824044) (xy 284.394402 -347.824044)
			(xy 284.431459 -347.824452) (xy 284.505308 -347.830716) (xy 284.57837 -347.843157) (xy 284.65013 -347.861689)
			(xy 284.685232 -347.873574) (xy 284.693429 -347.876088) (xy 284.710563 -347.876088) (xy 284.71876 -347.873574)
			(xy 284.756938 -347.860634) (xy 284.835124 -347.840982) (xy 284.91478 -347.828562) (xy 284.95498 -347.825568)
			(xy 284.965838 -347.82436) (xy 284.985096 -347.814096) (xy 284.99831 -347.79673) (xy 285.001208 -347.786198)
			(xy 285.010486 -347.747118) (xy 285.035162 -347.670674) (xy 285.050484 -347.633544) (xy 285.054028 -347.623948)
			(xy 285.05404 -347.603511) (xy 285.050484 -347.59392) (xy 285.033454 -347.552511) (xy 285.006819 -347.467023)
			(xy 284.988912 -347.379291) (xy 284.979917 -347.290203) (xy 284.979364 -347.245432) (xy 284.979868 -347.203071)
			(xy 284.987921 -347.118734) (xy 285.003955 -347.035544) (xy 285.027823 -346.954254) (xy 285.059311 -346.875602)
			(xy 285.098133 -346.800299) (xy 285.143936 -346.729027) (xy 285.196307 -346.662431) (xy 285.254772 -346.601116)
			(xy 285.3188 -346.545635) (xy 285.387812 -346.496492) (xy 285.461182 -346.454132) (xy 285.538247 -346.418937)
			(xy 285.618309 -346.391228) (xy 285.700642 -346.371254) (xy 285.784501 -346.359197) (xy 285.869126 -346.355166)
			(xy 285.953751 -346.359197) (xy 286.03761 -346.371254) (xy 286.119943 -346.391228) (xy 286.200005 -346.418937)
			(xy 286.27707 -346.454132) (xy 286.35044 -346.496492) (xy 286.419452 -346.545635) (xy 286.48348 -346.601116)
			(xy 286.541945 -346.662431) (xy 286.594316 -346.729027) (xy 286.640119 -346.800299) (xy 286.678941 -346.875602)
			(xy 286.710429 -346.954254) (xy 286.734297 -347.035544) (xy 286.750331 -347.118734) (xy 286.758384 -347.203071)
			(xy 286.758888 -347.245432) (xy 286.758323 -347.290202) (xy 286.749314 -347.379287) (xy 286.73141 -347.467018)
			(xy 286.704791 -347.552509) (xy 286.687768 -347.59392) (xy 286.684185 -347.603505) (xy 286.684197 -347.623953)
			(xy 286.687768 -347.633544) (xy 286.703871 -347.672618) (xy 286.72945 -347.753174) (xy 286.747275 -347.835792)
			(xy 286.757183 -347.919728) (xy 286.758634 -347.961966) (xy 286.758888 -347.975936) (xy 286.77362 -347.999558)
			(xy 286.86506 -348.047056) (xy 286.873276 -348.050887) (xy 286.891249 -348.053129) (xy 286.908879 -348.048973)
			(xy 286.916622 -348.044262) (xy 286.916876 -348.044008) (xy 286.95358 -348.019938) (xy 287.030887 -347.978361)
			(xy 287.111915 -347.944605) (xy 287.195876 -347.918998) (xy 287.281951 -347.901791) (xy 287.369303 -347.893149)
			(xy 287.413192 -347.892624) (xy 287.413446 -347.892624) (xy 287.454553 -347.893069) (xy 287.536416 -347.900657)
			(xy 287.617231 -347.915765) (xy 287.696307 -347.938263) (xy 287.77297 -347.96796) (xy 287.846567 -348.004602)
			(xy 287.91647 -348.047877) (xy 287.982083 -348.097416) (xy 288.042847 -348.152796) (xy 288.098242 -348.213546)
			(xy 288.147798 -348.279147) (xy 288.19109 -348.349039) (xy 288.227751 -348.422627) (xy 288.257467 -348.499283)
			(xy 288.279985 -348.578353) (xy 288.295112 -348.659164) (xy 288.299345 -348.7047) (xy 291.818044 -348.7047)
			(xy 291.822034 -348.620942) (xy 291.833968 -348.537942) (xy 291.853737 -348.456452) (xy 291.881162 -348.377211)
			(xy 291.915996 -348.300935) (xy 291.957922 -348.228316) (xy 292.006561 -348.16001) (xy 292.061473 -348.096638)
			(xy 292.12216 -348.038772) (xy 292.188073 -347.986937) (xy 292.258614 -347.941602) (xy 292.333146 -347.903177)
			(xy 292.410992 -347.872011) (xy 292.491448 -347.848386) (xy 292.573786 -347.832515) (xy 292.657259 -347.824543)
			(xy 292.699186 -347.824044) (xy 292.700202 -347.824044) (xy 292.737259 -347.824452) (xy 292.811108 -347.830716)
			(xy 292.88417 -347.843157) (xy 292.95593 -347.861689) (xy 292.991032 -347.873574) (xy 292.999229 -347.876088)
			(xy 293.016363 -347.876088) (xy 293.02456 -347.873574) (xy 293.057737 -347.862322) (xy 293.125493 -347.844496)
			(xy 293.194454 -347.832123) (xy 293.229284 -347.828362) (xy 293.240044 -347.82673) (xy 293.258819 -347.815766)
			(xy 293.271409 -347.798041) (xy 293.273988 -347.787468) (xy 293.28351 -347.742121) (xy 293.310744 -347.653548)
			(xy 293.328344 -347.610684) (xy 293.331924 -347.601098) (xy 293.331914 -347.580651) (xy 293.328344 -347.57106)
			(xy 293.311293 -347.529659) (xy 293.284663 -347.444168) (xy 293.266763 -347.356433) (xy 293.257774 -347.267343)
			(xy 293.257224 -347.222572) (xy 293.257728 -347.180211) (xy 293.265781 -347.095874) (xy 293.281815 -347.012684)
			(xy 293.305683 -346.931394) (xy 293.337171 -346.852742) (xy 293.375993 -346.777439) (xy 293.421796 -346.706167)
			(xy 293.474167 -346.639571) (xy 293.532632 -346.578256) (xy 293.59666 -346.522775) (xy 293.665672 -346.473632)
			(xy 293.739042 -346.431272) (xy 293.816107 -346.396077) (xy 293.896169 -346.368368) (xy 293.978502 -346.348394)
			(xy 294.062361 -346.336337) (xy 294.146986 -346.332306) (xy 294.231611 -346.336337) (xy 294.31547 -346.348394)
			(xy 294.397803 -346.368368) (xy 294.477865 -346.396077) (xy 294.55493 -346.431272) (xy 294.6283 -346.473632)
			(xy 294.697312 -346.522775) (xy 294.76134 -346.578256) (xy 294.819805 -346.639571) (xy 294.872176 -346.706167)
			(xy 294.917979 -346.777439) (xy 294.956801 -346.852742) (xy 294.988289 -346.931394) (xy 295.012157 -347.012684)
			(xy 295.028191 -347.095874) (xy 295.036244 -347.180211) (xy 295.036748 -347.222572) (xy 295.036192 -347.267342)
			(xy 295.027179 -347.356427) (xy 295.009272 -347.444158) (xy 294.982652 -347.529649) (xy 294.965628 -347.57106)
			(xy 294.962081 -347.580656) (xy 294.96207 -347.601093) (xy 294.965628 -347.610684) (xy 294.982659 -347.652092)
			(xy 295.009295 -347.73758) (xy 295.0272 -347.825313) (xy 295.036195 -347.914401) (xy 295.036748 -347.959172)
			(xy 295.036494 -347.977206) (xy 295.03624 -347.991684) (xy 295.050718 -348.016576) (xy 295.157144 -348.071948)
			(xy 295.185846 -348.069916) (xy 295.19753 -348.061534) (xy 295.230035 -348.038582) (xy 295.298406 -347.997866)
			(xy 295.370142 -347.963421) (xy 295.444669 -347.935524) (xy 295.521391 -347.914398) (xy 295.599693 -347.900211)
			(xy 295.67895 -347.893078) (xy 295.718738 -347.892624) (xy 295.719246 -347.892624) (xy 295.760353 -347.893069)
			(xy 295.842216 -347.900657) (xy 295.923031 -347.915765) (xy 296.002107 -347.938263) (xy 296.07877 -347.96796)
			(xy 296.152367 -348.004602) (xy 296.22227 -348.047877) (xy 296.287883 -348.097416) (xy 296.348647 -348.152796)
			(xy 296.404042 -348.213546) (xy 296.453598 -348.279147) (xy 296.49689 -348.349039) (xy 296.533551 -348.422627)
			(xy 296.563267 -348.499283) (xy 296.585785 -348.578353) (xy 296.600912 -348.659164) (xy 296.605145 -348.7047)
			(xy 300.174644 -348.7047) (xy 300.178634 -348.620942) (xy 300.190568 -348.537942) (xy 300.210337 -348.456452)
			(xy 300.237762 -348.377211) (xy 300.272596 -348.300935) (xy 300.314522 -348.228316) (xy 300.363161 -348.16001)
			(xy 300.418073 -348.096638) (xy 300.47876 -348.038772) (xy 300.544673 -347.986937) (xy 300.615214 -347.941602)
			(xy 300.689746 -347.903177) (xy 300.767592 -347.872011) (xy 300.848048 -347.848386) (xy 300.930386 -347.832515)
			(xy 301.013859 -347.824543) (xy 301.055786 -347.824044) (xy 301.056802 -347.824044) (xy 301.093859 -347.824452)
			(xy 301.167708 -347.830716) (xy 301.24077 -347.843157) (xy 301.31253 -347.861689) (xy 301.347632 -347.873574)
			(xy 301.355829 -347.876088) (xy 301.372963 -347.876088) (xy 301.38116 -347.873574) (xy 301.419296 -347.860641)
			(xy 301.497398 -347.840993) (xy 301.576968 -347.828568) (xy 301.617126 -347.825568) (xy 301.627844 -347.824451)
			(xy 301.646914 -347.814446) (xy 301.660249 -347.797535) (xy 301.663354 -347.787214) (xy 301.672203 -347.75314)
			(xy 301.694583 -347.686387) (xy 301.708058 -347.653864) (xy 301.711569 -347.644255) (xy 301.711421 -347.623811)
			(xy 301.707804 -347.61424) (xy 301.690776 -347.57283) (xy 301.66414 -347.487343) (xy 301.646234 -347.39961)
			(xy 301.637237 -347.310523) (xy 301.636684 -347.265752) (xy 301.637188 -347.223391) (xy 301.645241 -347.139054)
			(xy 301.661275 -347.055864) (xy 301.685143 -346.974574) (xy 301.716631 -346.895922) (xy 301.755453 -346.820619)
			(xy 301.801256 -346.749347) (xy 301.853627 -346.682751) (xy 301.912092 -346.621436) (xy 301.97612 -346.565955)
			(xy 302.045132 -346.516812) (xy 302.118502 -346.474452) (xy 302.195567 -346.439257) (xy 302.275629 -346.411548)
			(xy 302.357962 -346.391574) (xy 302.441821 -346.379517) (xy 302.526446 -346.375486) (xy 302.611071 -346.379517)
			(xy 302.69493 -346.391574) (xy 302.777263 -346.411548) (xy 302.857325 -346.439257) (xy 302.93439 -346.474452)
			(xy 303.00776 -346.516812) (xy 303.076772 -346.565955) (xy 303.1408 -346.621436) (xy 303.199265 -346.682751)
			(xy 303.251636 -346.749347) (xy 303.297439 -346.820619) (xy 303.336261 -346.895922) (xy 303.367749 -346.974574)
			(xy 303.391617 -347.055864) (xy 303.407651 -347.139054) (xy 303.415704 -347.223391) (xy 303.416208 -347.265752)
			(xy 303.415649 -347.310522) (xy 303.406637 -347.399607) (xy 303.388731 -347.487338) (xy 303.362111 -347.572829)
			(xy 303.345088 -347.61424) (xy 303.341549 -347.623838) (xy 303.341532 -347.644274) (xy 303.345088 -347.653864)
			(xy 303.36051 -347.691224) (xy 303.385289 -347.768163) (xy 303.402976 -347.847034) (xy 303.413426 -347.927187)
			(xy 303.415446 -347.967554) (xy 303.415954 -347.981524) (xy 303.430686 -348.004638) (xy 303.535334 -348.057216)
			(xy 303.562766 -348.055184) (xy 303.574196 -348.04731) (xy 303.611146 -348.022772) (xy 303.689046 -347.980345)
			(xy 303.770779 -347.945874) (xy 303.855535 -347.919702) (xy 303.942473 -347.902087) (xy 304.030732 -347.893205)
			(xy 304.075084 -347.892624) (xy 304.075846 -347.892624) (xy 304.116953 -347.893069) (xy 304.198816 -347.900657)
			(xy 304.279631 -347.915765) (xy 304.358707 -347.938263) (xy 304.43537 -347.96796) (xy 304.508967 -348.004602)
			(xy 304.57887 -348.047877) (xy 304.644483 -348.097416) (xy 304.705247 -348.152796) (xy 304.760642 -348.213546)
			(xy 304.810198 -348.279147) (xy 304.85349 -348.349039) (xy 304.890151 -348.422627) (xy 304.919867 -348.499283)
			(xy 304.942385 -348.578353) (xy 304.957512 -348.659164) (xy 304.961745 -348.7047) (xy 308.505844 -348.7047)
			(xy 308.509834 -348.620942) (xy 308.521768 -348.537942) (xy 308.541537 -348.456452) (xy 308.568962 -348.377211)
			(xy 308.603796 -348.300935) (xy 308.645722 -348.228316) (xy 308.694361 -348.16001) (xy 308.749273 -348.096638)
			(xy 308.80996 -348.038772) (xy 308.875873 -347.986937) (xy 308.946414 -347.941602) (xy 309.020946 -347.903177)
			(xy 309.098792 -347.872011) (xy 309.179248 -347.848386) (xy 309.261586 -347.832515) (xy 309.345059 -347.824543)
			(xy 309.386986 -347.824044) (xy 309.388002 -347.824044) (xy 309.425059 -347.824452) (xy 309.498908 -347.830716)
			(xy 309.57197 -347.843157) (xy 309.64373 -347.861689) (xy 309.678832 -347.873574) (xy 309.687029 -347.876088)
			(xy 309.704163 -347.876088) (xy 309.71236 -347.873574) (xy 309.752087 -347.860214) (xy 309.833476 -347.84017)
			(xy 309.916402 -347.827952) (xy 309.958232 -347.825314) (xy 309.969008 -347.824123) (xy 309.988202 -347.814097)
			(xy 310.001607 -347.79709) (xy 310.004714 -347.786706) (xy 310.013576 -347.75276) (xy 310.035956 -347.686262)
			(xy 310.049418 -347.653864) (xy 310.052931 -347.644255) (xy 310.052783 -347.623811) (xy 310.049164 -347.61424)
			(xy 310.03214 -347.572829) (xy 310.005503 -347.487342) (xy 309.987595 -347.39961) (xy 309.978598 -347.310522)
			(xy 309.978044 -347.265752) (xy 309.978548 -347.223391) (xy 309.986601 -347.139054) (xy 310.002635 -347.055864)
			(xy 310.026503 -346.974574) (xy 310.057991 -346.895922) (xy 310.096813 -346.820619) (xy 310.142616 -346.749347)
			(xy 310.194987 -346.682751) (xy 310.253452 -346.621436) (xy 310.31748 -346.565955) (xy 310.386492 -346.516812)
			(xy 310.459862 -346.474452) (xy 310.536927 -346.439257) (xy 310.616989 -346.411548) (xy 310.699322 -346.391574)
			(xy 310.783181 -346.379517) (xy 310.867806 -346.375486) (xy 310.952431 -346.379517) (xy 311.03629 -346.391574)
			(xy 311.118623 -346.411548) (xy 311.198685 -346.439257) (xy 311.27575 -346.474452) (xy 311.34912 -346.516812)
			(xy 311.418132 -346.565955) (xy 311.48216 -346.621436) (xy 311.540625 -346.682751) (xy 311.592996 -346.749347)
			(xy 311.638799 -346.820619) (xy 311.677621 -346.895922) (xy 311.709109 -346.974574) (xy 311.732977 -347.055864)
			(xy 311.749011 -347.139054) (xy 311.757064 -347.223391) (xy 311.757568 -347.265752) (xy 311.757012 -347.310522)
			(xy 311.748 -347.399607) (xy 311.730093 -347.487338) (xy 311.703472 -347.572829) (xy 311.686448 -347.61424)
			(xy 311.682911 -347.623839) (xy 311.682894 -347.644274) (xy 311.686448 -347.653864) (xy 311.701578 -347.690518)
			(xy 311.725997 -347.765967) (xy 311.743615 -347.843288) (xy 311.754293 -347.921869) (xy 311.756552 -347.961458)
			(xy 311.757251 -347.970429) (xy 311.764179 -347.987026) (xy 311.776392 -348.000229) (xy 311.784238 -348.004638)
			(xy 311.875678 -348.050866) (xy 311.902856 -348.049088) (xy 311.914286 -348.041468) (xy 311.950798 -348.017804)
			(xy 312.027605 -347.976914) (xy 312.10804 -347.943725) (xy 312.191333 -347.918554) (xy 312.276687 -347.901641)
			(xy 312.363285 -347.893148) (xy 312.406792 -347.892624) (xy 312.407046 -347.892624) (xy 312.448153 -347.893069)
			(xy 312.530016 -347.900657) (xy 312.610831 -347.915765) (xy 312.689907 -347.938263) (xy 312.76657 -347.96796)
			(xy 312.840167 -348.004602) (xy 312.91007 -348.047877) (xy 312.975683 -348.097416) (xy 313.036447 -348.152796)
			(xy 313.091842 -348.213546) (xy 313.141398 -348.279147) (xy 313.18469 -348.349039) (xy 313.221351 -348.422627)
			(xy 313.251067 -348.499283) (xy 313.273585 -348.578353) (xy 313.288712 -348.659164) (xy 313.296321 -348.741025)
			(xy 313.296808 -348.782132) (xy 313.296242 -348.826902) (xy 313.287233 -348.915987) (xy 313.269329 -349.003718)
			(xy 313.242711 -349.089209) (xy 313.225688 -349.13062) (xy 313.222104 -349.140205) (xy 313.222115 -349.160653)
			(xy 313.225688 -349.170244) (xy 313.242711 -349.211656) (xy 313.269347 -349.297143) (xy 313.287256 -349.384874)
			(xy 313.291976 -349.43161) (xy 326.552821 -349.43161) (xy 326.556826 -349.325861) (xy 326.568816 -349.220718)
			(xy 326.588725 -349.116783) (xy 326.616436 -349.014651) (xy 326.651793 -348.914907) (xy 326.694591 -348.818123)
			(xy 326.744587 -348.724853) (xy 326.801494 -348.635632) (xy 326.864985 -348.550969) (xy 326.934697 -348.471351)
			(xy 327.010231 -348.397233) (xy 327.091154 -348.32904) (xy 327.177003 -348.267162) (xy 327.267286 -348.211955)
			(xy 327.361485 -348.163733) (xy 327.459062 -348.122773) (xy 327.559457 -348.089311) (xy 327.662095 -348.063537)
			(xy 327.766388 -348.045599) (xy 327.871739 -348.0356) (xy 327.977545 -348.033597) (xy 328.083199 -348.039602)
			(xy 328.188096 -348.053581) (xy 328.291636 -348.075452) (xy 328.393225 -348.105092) (xy 328.492282 -348.14233)
			(xy 328.588239 -348.186952) (xy 328.680546 -348.238704) (xy 328.768675 -348.297289) (xy 328.852121 -348.362371)
			(xy 328.930405 -348.433577) (xy 329.00308 -348.5105) (xy 329.06973 -348.5927) (xy 329.129972 -348.679704)
			(xy 329.183461 -348.771015) (xy 329.229892 -348.86611) (xy 329.268997 -348.964444) (xy 329.300554 -349.065455)
			(xy 329.324381 -349.168562) (xy 329.340342 -349.273176) (xy 329.348346 -349.378698) (xy 329.348846 -349.43161)
			(xy 334.012801 -349.43161) (xy 334.016806 -349.325861) (xy 334.028796 -349.220718) (xy 334.048705 -349.116783)
			(xy 334.076416 -349.014651) (xy 334.111773 -348.914907) (xy 334.154571 -348.818123) (xy 334.204567 -348.724853)
			(xy 334.261474 -348.635632) (xy 334.324965 -348.550969) (xy 334.394677 -348.471351) (xy 334.470211 -348.397233)
			(xy 334.551134 -348.32904) (xy 334.636983 -348.267162) (xy 334.727266 -348.211955) (xy 334.821465 -348.163733)
			(xy 334.919042 -348.122773) (xy 335.019437 -348.089311) (xy 335.122075 -348.063537) (xy 335.226368 -348.045599)
			(xy 335.331719 -348.0356) (xy 335.437525 -348.033597) (xy 335.543179 -348.039602) (xy 335.648076 -348.053581)
			(xy 335.751616 -348.075452) (xy 335.853205 -348.105092) (xy 335.952262 -348.14233) (xy 336.048219 -348.186952)
			(xy 336.140526 -348.238704) (xy 336.228655 -348.297289) (xy 336.312101 -348.362371) (xy 336.390385 -348.433577)
			(xy 336.46306 -348.5105) (xy 336.52971 -348.5927) (xy 336.589952 -348.679704) (xy 336.643441 -348.771015)
			(xy 336.689872 -348.86611) (xy 336.728977 -348.964444) (xy 336.760534 -349.065455) (xy 336.784361 -349.168562)
			(xy 336.800322 -349.273176) (xy 336.808326 -349.378698) (xy 336.808826 -349.43161) (xy 336.808326 -349.484522)
			(xy 336.800322 -349.590044) (xy 336.784361 -349.694658) (xy 336.760534 -349.797765) (xy 336.728977 -349.898776)
			(xy 336.689872 -349.99711) (xy 336.643441 -350.092205) (xy 336.589952 -350.183516) (xy 336.52971 -350.27052)
			(xy 336.46306 -350.35272) (xy 336.390385 -350.429643) (xy 336.312101 -350.500849) (xy 336.228655 -350.565931)
			(xy 336.140526 -350.624516) (xy 336.048219 -350.676268) (xy 335.952262 -350.72089) (xy 335.853205 -350.758128)
			(xy 335.751616 -350.787768) (xy 335.648076 -350.809639) (xy 335.543179 -350.823618) (xy 335.437525 -350.829623)
			(xy 335.331719 -350.82762) (xy 335.226368 -350.817621) (xy 335.122075 -350.799683) (xy 335.019437 -350.773909)
			(xy 334.919042 -350.740447) (xy 334.821465 -350.699487) (xy 334.727266 -350.651265) (xy 334.636983 -350.596058)
			(xy 334.551134 -350.53418) (xy 334.470211 -350.465987) (xy 334.394677 -350.391869) (xy 334.324965 -350.312251)
			(xy 334.261474 -350.227588) (xy 334.204567 -350.138367) (xy 334.154571 -350.045097) (xy 334.111773 -349.948313)
			(xy 334.076416 -349.848569) (xy 334.048705 -349.746437) (xy 334.028796 -349.642502) (xy 334.016806 -349.537359)
			(xy 334.012801 -349.43161) (xy 329.348846 -349.43161) (xy 329.348346 -349.484522) (xy 329.340342 -349.590044)
			(xy 329.324381 -349.694658) (xy 329.300554 -349.797765) (xy 329.268997 -349.898776) (xy 329.229892 -349.99711)
			(xy 329.183461 -350.092205) (xy 329.129972 -350.183516) (xy 329.06973 -350.27052) (xy 329.00308 -350.35272)
			(xy 328.930405 -350.429643) (xy 328.852121 -350.500849) (xy 328.768675 -350.565931) (xy 328.680546 -350.624516)
			(xy 328.588239 -350.676268) (xy 328.492282 -350.72089) (xy 328.393225 -350.758128) (xy 328.291636 -350.787768)
			(xy 328.188096 -350.809639) (xy 328.083199 -350.823618) (xy 327.977545 -350.829623) (xy 327.871739 -350.82762)
			(xy 327.766388 -350.817621) (xy 327.662095 -350.799683) (xy 327.559457 -350.773909) (xy 327.459062 -350.740447)
			(xy 327.361485 -350.699487) (xy 327.267286 -350.651265) (xy 327.177003 -350.596058) (xy 327.091154 -350.53418)
			(xy 327.010231 -350.465987) (xy 326.934697 -350.391869) (xy 326.864985 -350.312251) (xy 326.801494 -350.227588)
			(xy 326.744587 -350.138367) (xy 326.694591 -350.045097) (xy 326.651793 -349.948313) (xy 326.616436 -349.848569)
			(xy 326.588725 -349.746437) (xy 326.568816 -349.642502) (xy 326.556826 -349.537359) (xy 326.552821 -349.43161)
			(xy 313.291976 -349.43161) (xy 313.296254 -349.473962) (xy 313.296808 -349.518732) (xy 313.296242 -349.563502)
			(xy 313.287233 -349.652587) (xy 313.269329 -349.740318) (xy 313.242711 -349.825809) (xy 313.225688 -349.86722)
			(xy 313.222104 -349.876805) (xy 313.222115 -349.897253) (xy 313.225688 -349.906844) (xy 313.242711 -349.948256)
			(xy 313.269347 -350.033743) (xy 313.287256 -350.121474) (xy 313.296254 -350.210562) (xy 313.296808 -350.255332)
			(xy 313.296378 -350.296443) (xy 313.288787 -350.378314) (xy 313.273674 -350.459136) (xy 313.251166 -350.538217)
			(xy 313.221457 -350.614885) (xy 313.184799 -350.688483) (xy 313.141506 -350.758385) (xy 313.091947 -350.823993)
			(xy 313.036545 -350.884747) (xy 312.975772 -350.94013) (xy 312.910148 -350.989668) (xy 312.840233 -351.032938)
			(xy 312.766623 -351.069572) (xy 312.689946 -351.099257) (xy 312.610857 -351.121739) (xy 312.530031 -351.136827)
			(xy 312.448157 -351.144391) (xy 312.407046 -351.14484) (xy 312.365442 -351.14437) (xy 312.282594 -351.136637)
			(xy 312.200829 -351.121206) (xy 312.120862 -351.098211) (xy 312.043389 -351.067854) (xy 311.969088 -351.0304)
			(xy 311.93359 -351.008696) (xy 311.924458 -351.003521) (xy 311.903738 -351.00031) (xy 311.883461 -351.005649)
			(xy 311.874916 -351.011744) (xy 311.841266 -351.037664) (xy 311.769892 -351.083723) (xy 311.694453 -351.12277)
			(xy 311.615637 -351.15445) (xy 311.53416 -351.178473) (xy 311.450764 -351.194623) (xy 311.366208 -351.20275)
			(xy 311.323736 -351.20326) (xy 311.323482 -351.20326) (xy 311.282375 -351.202805) (xy 311.200511 -351.195219)
			(xy 311.119697 -351.180113) (xy 311.04062 -351.157617) (xy 310.963956 -351.127921) (xy 310.890359 -351.09128)
			(xy 310.820455 -351.048006) (xy 310.754841 -350.998468) (xy 310.694077 -350.943088) (xy 310.638682 -350.882339)
			(xy 310.589126 -350.816738) (xy 310.545833 -350.746846) (xy 310.509173 -350.673258) (xy 310.479458 -350.596602)
			(xy 310.456941 -350.517531) (xy 310.441814 -350.43672) (xy 310.434206 -350.354859) (xy 310.43372 -350.313752)
			(xy 310.434279 -350.268982) (xy 310.44329 -350.179897) (xy 310.461196 -350.092166) (xy 310.487816 -350.006675)
			(xy 310.50484 -349.965264) (xy 310.508432 -349.955681) (xy 310.508415 -349.935231) (xy 310.50484 -349.92564)
			(xy 310.487836 -349.884289) (xy 310.461225 -349.798927) (xy 310.443318 -349.711324) (xy 310.434296 -349.622367)
			(xy 310.43372 -349.57766) (xy 310.43372 -349.576644) (xy 310.433974 -349.565214) (xy 310.407495 -349.559269)
			(xy 310.35526 -349.544526) (xy 310.32958 -349.53575) (xy 310.321383 -349.533236) (xy 310.304249 -349.533236)
			(xy 310.296052 -349.53575) (xy 310.260836 -349.547697) (xy 310.188826 -349.566284) (xy 310.115503 -349.578724)
			(xy 310.041392 -349.584928) (xy 310.004206 -349.58528) (xy 309.967022 -349.584911) (xy 309.892914 -349.578689)
			(xy 309.819594 -349.566246) (xy 309.747583 -349.547672) (xy 309.71236 -349.53575) (xy 309.704163 -349.533236)
			(xy 309.687029 -349.533236) (xy 309.678832 -349.53575) (xy 309.64373 -349.547637) (xy 309.571974 -349.566187)
			(xy 309.498911 -349.578634) (xy 309.42506 -349.584887) (xy 309.388002 -349.58528) (xy 309.386986 -349.58528)
			(xy 309.345059 -349.584857) (xy 309.261586 -349.576885) (xy 309.179248 -349.561014) (xy 309.098792 -349.537389)
			(xy 309.020946 -349.506223) (xy 308.946414 -349.467798) (xy 308.875873 -349.422463) (xy 308.80996 -349.370628)
			(xy 308.749273 -349.312762) (xy 308.694361 -349.24939) (xy 308.645722 -349.181084) (xy 308.603796 -349.108465)
			(xy 308.568962 -349.032189) (xy 308.541537 -348.952948) (xy 308.521768 -348.871458) (xy 308.509834 -348.788458)
			(xy 308.505844 -348.7047) (xy 304.961745 -348.7047) (xy 304.965121 -348.741025) (xy 304.965608 -348.782132)
			(xy 304.965042 -348.826902) (xy 304.956033 -348.915987) (xy 304.938129 -349.003718) (xy 304.911511 -349.089209)
			(xy 304.894488 -349.13062) (xy 304.890904 -349.140205) (xy 304.890915 -349.160653) (xy 304.894488 -349.170244)
			(xy 304.911511 -349.211656) (xy 304.938147 -349.297143) (xy 304.956056 -349.384874) (xy 304.965054 -349.473962)
			(xy 304.965608 -349.518732) (xy 304.965042 -349.563502) (xy 304.956033 -349.652587) (xy 304.938129 -349.740318)
			(xy 304.911511 -349.825809) (xy 304.894488 -349.86722) (xy 304.890904 -349.876805) (xy 304.890915 -349.897253)
			(xy 304.894488 -349.906844) (xy 304.911511 -349.948256) (xy 304.938147 -350.033743) (xy 304.956056 -350.121474)
			(xy 304.965054 -350.210562) (xy 304.965608 -350.255332) (xy 304.965178 -350.296443) (xy 304.957587 -350.378314)
			(xy 304.942474 -350.459136) (xy 304.919966 -350.538217) (xy 304.890257 -350.614885) (xy 304.853599 -350.688483)
			(xy 304.810306 -350.758385) (xy 304.760747 -350.823993) (xy 304.705345 -350.884747) (xy 304.644572 -350.94013)
			(xy 304.578948 -350.989668) (xy 304.509033 -351.032938) (xy 304.435423 -351.069572) (xy 304.358746 -351.099257)
			(xy 304.279657 -351.121739) (xy 304.198831 -351.136827) (xy 304.116957 -351.144391) (xy 304.075846 -351.14484)
			(xy 304.034242 -351.14437) (xy 303.951394 -351.136637) (xy 303.869629 -351.121206) (xy 303.789662 -351.098211)
			(xy 303.712189 -351.067854) (xy 303.637888 -351.0304) (xy 303.60239 -351.008696) (xy 303.593258 -351.003521)
			(xy 303.572538 -351.00031) (xy 303.552261 -351.005649) (xy 303.543716 -351.011744) (xy 303.510066 -351.037664)
			(xy 303.438692 -351.083723) (xy 303.363253 -351.12277) (xy 303.284437 -351.15445) (xy 303.20296 -351.178473)
			(xy 303.119564 -351.194623) (xy 303.035008 -351.20275) (xy 302.992536 -351.20326) (xy 302.992282 -351.20326)
			(xy 302.951175 -351.202805) (xy 302.869311 -351.195219) (xy 302.788497 -351.180113) (xy 302.70942 -351.157617)
			(xy 302.632756 -351.127921) (xy 302.559159 -351.09128) (xy 302.489255 -351.048006) (xy 302.423641 -350.998468)
			(xy 302.362877 -350.943088) (xy 302.307482 -350.882339) (xy 302.257926 -350.816738) (xy 302.214633 -350.746846)
			(xy 302.177973 -350.673258) (xy 302.148258 -350.596602) (xy 302.125741 -350.517531) (xy 302.110614 -350.43672)
			(xy 302.103006 -350.354859) (xy 302.10252 -350.313752) (xy 302.103079 -350.268982) (xy 302.11209 -350.179897)
			(xy 302.129996 -350.092166) (xy 302.156616 -350.006675) (xy 302.17364 -349.965264) (xy 302.177232 -349.955681)
			(xy 302.177215 -349.935231) (xy 302.17364 -349.92564) (xy 302.156636 -349.884289) (xy 302.130025 -349.798927)
			(xy 302.112118 -349.711324) (xy 302.103096 -349.622367) (xy 302.10252 -349.57766) (xy 302.10252 -349.576644)
			(xy 302.102774 -349.565214) (xy 302.076295 -349.559269) (xy 302.02406 -349.544526) (xy 301.99838 -349.53575)
			(xy 301.990183 -349.533236) (xy 301.973049 -349.533236) (xy 301.964852 -349.53575) (xy 301.929636 -349.547697)
			(xy 301.857626 -349.566284) (xy 301.784303 -349.578724) (xy 301.710192 -349.584928) (xy 301.673006 -349.58528)
			(xy 301.635822 -349.584911) (xy 301.561714 -349.578689) (xy 301.488394 -349.566246) (xy 301.416383 -349.547672)
			(xy 301.38116 -349.53575) (xy 301.372963 -349.533236) (xy 301.355829 -349.533236) (xy 301.347632 -349.53575)
			(xy 301.31253 -349.547637) (xy 301.240774 -349.566187) (xy 301.167711 -349.578634) (xy 301.09386 -349.584887)
			(xy 301.056802 -349.58528) (xy 301.055786 -349.58528) (xy 301.013859 -349.584857) (xy 300.930386 -349.576885)
			(xy 300.848048 -349.561014) (xy 300.767592 -349.537389) (xy 300.689746 -349.506223) (xy 300.615214 -349.467798)
			(xy 300.544673 -349.422463) (xy 300.47876 -349.370628) (xy 300.418073 -349.312762) (xy 300.363161 -349.24939)
			(xy 300.314522 -349.181084) (xy 300.272596 -349.108465) (xy 300.237762 -349.032189) (xy 300.210337 -348.952948)
			(xy 300.190568 -348.871458) (xy 300.178634 -348.788458) (xy 300.174644 -348.7047) (xy 296.605145 -348.7047)
			(xy 296.608521 -348.741025) (xy 296.609008 -348.782132) (xy 296.608442 -348.826902) (xy 296.599433 -348.915987)
			(xy 296.581529 -349.003718) (xy 296.554911 -349.089209) (xy 296.537888 -349.13062) (xy 296.534304 -349.140205)
			(xy 296.534315 -349.160653) (xy 296.537888 -349.170244) (xy 296.554911 -349.211656) (xy 296.581547 -349.297143)
			(xy 296.599456 -349.384874) (xy 296.608454 -349.473962) (xy 296.609008 -349.518732) (xy 296.608442 -349.563502)
			(xy 296.599433 -349.652587) (xy 296.581529 -349.740318) (xy 296.554911 -349.825809) (xy 296.537888 -349.86722)
			(xy 296.534304 -349.876805) (xy 296.534315 -349.897253) (xy 296.537888 -349.906844) (xy 296.554911 -349.948256)
			(xy 296.581547 -350.033743) (xy 296.599456 -350.121474) (xy 296.608454 -350.210562) (xy 296.609008 -350.255332)
			(xy 296.608578 -350.296443) (xy 296.600987 -350.378314) (xy 296.585874 -350.459136) (xy 296.563366 -350.538217)
			(xy 296.533657 -350.614885) (xy 296.496999 -350.688483) (xy 296.453706 -350.758385) (xy 296.404147 -350.823993)
			(xy 296.348745 -350.884747) (xy 296.287972 -350.94013) (xy 296.222348 -350.989668) (xy 296.152433 -351.032938)
			(xy 296.078823 -351.069572) (xy 296.002146 -351.099257) (xy 295.923057 -351.121739) (xy 295.842231 -351.136827)
			(xy 295.760357 -351.144391) (xy 295.719246 -351.14484) (xy 295.677642 -351.14437) (xy 295.594794 -351.136637)
			(xy 295.513029 -351.121206) (xy 295.433062 -351.098211) (xy 295.355589 -351.067854) (xy 295.281288 -351.0304)
			(xy 295.24579 -351.008696) (xy 295.236658 -351.003521) (xy 295.215938 -351.00031) (xy 295.195661 -351.005649)
			(xy 295.187116 -351.011744) (xy 295.153466 -351.037664) (xy 295.082092 -351.083723) (xy 295.006653 -351.12277)
			(xy 294.927837 -351.15445) (xy 294.84636 -351.178473) (xy 294.762964 -351.194623) (xy 294.678408 -351.20275)
			(xy 294.635936 -351.20326) (xy 294.635682 -351.20326) (xy 294.594575 -351.202805) (xy 294.512711 -351.195219)
			(xy 294.431897 -351.180113) (xy 294.35282 -351.157617) (xy 294.276156 -351.127921) (xy 294.202559 -351.09128)
			(xy 294.132655 -351.048006) (xy 294.067041 -350.998468) (xy 294.006277 -350.943088) (xy 293.950882 -350.882339)
			(xy 293.901326 -350.816738) (xy 293.858033 -350.746846) (xy 293.821373 -350.673258) (xy 293.791658 -350.596602)
			(xy 293.769141 -350.517531) (xy 293.754014 -350.43672) (xy 293.746406 -350.354859) (xy 293.74592 -350.313752)
			(xy 293.746479 -350.268982) (xy 293.75549 -350.179897) (xy 293.773396 -350.092166) (xy 293.800016 -350.006675)
			(xy 293.81704 -349.965264) (xy 293.820632 -349.955681) (xy 293.820615 -349.935231) (xy 293.81704 -349.92564)
			(xy 293.800036 -349.884289) (xy 293.773425 -349.798927) (xy 293.755518 -349.711324) (xy 293.746496 -349.622367)
			(xy 293.74592 -349.57766) (xy 293.74592 -349.576644) (xy 293.746174 -349.565214) (xy 293.719695 -349.559269)
			(xy 293.66746 -349.544526) (xy 293.64178 -349.53575) (xy 293.633583 -349.533236) (xy 293.616449 -349.533236)
			(xy 293.608252 -349.53575) (xy 293.573036 -349.547697) (xy 293.501026 -349.566284) (xy 293.427703 -349.578724)
			(xy 293.353592 -349.584928) (xy 293.316406 -349.58528) (xy 293.279222 -349.584911) (xy 293.205114 -349.578689)
			(xy 293.131794 -349.566246) (xy 293.059783 -349.547672) (xy 293.02456 -349.53575) (xy 293.016363 -349.533236)
			(xy 292.999229 -349.533236) (xy 292.991032 -349.53575) (xy 292.95593 -349.547637) (xy 292.884174 -349.566187)
			(xy 292.811111 -349.578634) (xy 292.73726 -349.584887) (xy 292.700202 -349.58528) (xy 292.699186 -349.58528)
			(xy 292.657259 -349.584857) (xy 292.573786 -349.576885) (xy 292.491448 -349.561014) (xy 292.410992 -349.537389)
			(xy 292.333146 -349.506223) (xy 292.258614 -349.467798) (xy 292.188073 -349.422463) (xy 292.12216 -349.370628)
			(xy 292.061473 -349.312762) (xy 292.006561 -349.24939) (xy 291.957922 -349.181084) (xy 291.915996 -349.108465)
			(xy 291.881162 -349.032189) (xy 291.853737 -348.952948) (xy 291.833968 -348.871458) (xy 291.822034 -348.788458)
			(xy 291.818044 -348.7047) (xy 288.299345 -348.7047) (xy 288.302721 -348.741025) (xy 288.303208 -348.782132)
			(xy 288.302642 -348.826902) (xy 288.293633 -348.915987) (xy 288.275729 -349.003718) (xy 288.249111 -349.089209)
			(xy 288.232088 -349.13062) (xy 288.228504 -349.140205) (xy 288.228515 -349.160653) (xy 288.232088 -349.170244)
			(xy 288.249111 -349.211656) (xy 288.275747 -349.297143) (xy 288.293656 -349.384874) (xy 288.302654 -349.473962)
			(xy 288.303208 -349.518732) (xy 288.302642 -349.563502) (xy 288.293633 -349.652587) (xy 288.275729 -349.740318)
			(xy 288.249111 -349.825809) (xy 288.232088 -349.86722) (xy 288.228504 -349.876805) (xy 288.228515 -349.897253)
			(xy 288.232088 -349.906844) (xy 288.249111 -349.948256) (xy 288.275747 -350.033743) (xy 288.293656 -350.121474)
			(xy 288.302654 -350.210562) (xy 288.303208 -350.255332) (xy 288.302778 -350.296443) (xy 288.295187 -350.378314)
			(xy 288.280074 -350.459136) (xy 288.257566 -350.538217) (xy 288.227857 -350.614885) (xy 288.191199 -350.688483)
			(xy 288.147906 -350.758385) (xy 288.098347 -350.823993) (xy 288.042945 -350.884747) (xy 287.982172 -350.94013)
			(xy 287.916548 -350.989668) (xy 287.846633 -351.032938) (xy 287.773023 -351.069572) (xy 287.696346 -351.099257)
			(xy 287.617257 -351.121739) (xy 287.536431 -351.136827) (xy 287.454557 -351.144391) (xy 287.413446 -351.14484)
			(xy 287.371842 -351.14437) (xy 287.288994 -351.136637) (xy 287.207229 -351.121206) (xy 287.127262 -351.098211)
			(xy 287.049789 -351.067854) (xy 286.975488 -351.0304) (xy 286.93999 -351.008696) (xy 286.930858 -351.003521)
			(xy 286.910138 -351.00031) (xy 286.889861 -351.005649) (xy 286.881316 -351.011744) (xy 286.847666 -351.037664)
			(xy 286.776292 -351.083723) (xy 286.700853 -351.12277) (xy 286.622037 -351.15445) (xy 286.54056 -351.178473)
			(xy 286.457164 -351.194623) (xy 286.372608 -351.20275) (xy 286.330136 -351.20326) (xy 286.329882 -351.20326)
			(xy 286.288775 -351.202805) (xy 286.206911 -351.195219) (xy 286.126097 -351.180113) (xy 286.04702 -351.157617)
			(xy 285.970356 -351.127921) (xy 285.896759 -351.09128) (xy 285.826855 -351.048006) (xy 285.761241 -350.998468)
			(xy 285.700477 -350.943088) (xy 285.645082 -350.882339) (xy 285.595526 -350.816738) (xy 285.552233 -350.746846)
			(xy 285.515573 -350.673258) (xy 285.485858 -350.596602) (xy 285.463341 -350.517531) (xy 285.448214 -350.43672)
			(xy 285.440606 -350.354859) (xy 285.44012 -350.313752) (xy 285.440679 -350.268982) (xy 285.44969 -350.179897)
			(xy 285.467596 -350.092166) (xy 285.494216 -350.006675) (xy 285.51124 -349.965264) (xy 285.514832 -349.955681)
			(xy 285.514815 -349.935231) (xy 285.51124 -349.92564) (xy 285.494236 -349.884289) (xy 285.467625 -349.798927)
			(xy 285.449718 -349.711324) (xy 285.440696 -349.622367) (xy 285.44012 -349.57766) (xy 285.44012 -349.576644)
			(xy 285.440374 -349.565214) (xy 285.413895 -349.559269) (xy 285.36166 -349.544526) (xy 285.33598 -349.53575)
			(xy 285.327783 -349.533236) (xy 285.310649 -349.533236) (xy 285.302452 -349.53575) (xy 285.267236 -349.547697)
			(xy 285.195226 -349.566284) (xy 285.121903 -349.578724) (xy 285.047792 -349.584928) (xy 285.010606 -349.58528)
			(xy 284.973422 -349.584911) (xy 284.899314 -349.578689) (xy 284.825994 -349.566246) (xy 284.753983 -349.547672)
			(xy 284.71876 -349.53575) (xy 284.710563 -349.533236) (xy 284.693429 -349.533236) (xy 284.685232 -349.53575)
			(xy 284.65013 -349.547637) (xy 284.578374 -349.566187) (xy 284.505311 -349.578634) (xy 284.43146 -349.584887)
			(xy 284.394402 -349.58528) (xy 284.393386 -349.58528) (xy 284.351459 -349.584857) (xy 284.267986 -349.576885)
			(xy 284.185648 -349.561014) (xy 284.105192 -349.537389) (xy 284.027346 -349.506223) (xy 283.952814 -349.467798)
			(xy 283.882273 -349.422463) (xy 283.81636 -349.370628) (xy 283.755673 -349.312762) (xy 283.700761 -349.24939)
			(xy 283.652122 -349.181084) (xy 283.610196 -349.108465) (xy 283.575362 -349.032189) (xy 283.547937 -348.952948)
			(xy 283.528168 -348.871458) (xy 283.516234 -348.788458) (xy 283.512244 -348.7047) (xy 280.018945 -348.7047)
			(xy 280.022321 -348.741025) (xy 280.022808 -348.782132) (xy 280.022242 -348.826902) (xy 280.013233 -348.915987)
			(xy 279.995329 -349.003718) (xy 279.968711 -349.089209) (xy 279.951688 -349.13062) (xy 279.948104 -349.140205)
			(xy 279.948115 -349.160653) (xy 279.951688 -349.170244) (xy 279.968711 -349.211656) (xy 279.995347 -349.297143)
			(xy 280.013256 -349.384874) (xy 280.022254 -349.473962) (xy 280.022808 -349.518732) (xy 280.022242 -349.563502)
			(xy 280.013233 -349.652587) (xy 279.995329 -349.740318) (xy 279.968711 -349.825809) (xy 279.951688 -349.86722)
			(xy 279.948104 -349.876805) (xy 279.948115 -349.897253) (xy 279.951688 -349.906844) (xy 279.968711 -349.948256)
			(xy 279.995347 -350.033743) (xy 280.013256 -350.121474) (xy 280.022254 -350.210562) (xy 280.022808 -350.255332)
			(xy 280.022378 -350.296443) (xy 280.014787 -350.378314) (xy 279.999674 -350.459136) (xy 279.977166 -350.538217)
			(xy 279.947457 -350.614885) (xy 279.910799 -350.688483) (xy 279.867506 -350.758385) (xy 279.817947 -350.823993)
			(xy 279.762545 -350.884747) (xy 279.701772 -350.94013) (xy 279.636148 -350.989668) (xy 279.566233 -351.032938)
			(xy 279.492623 -351.069572) (xy 279.415946 -351.099257) (xy 279.336857 -351.121739) (xy 279.256031 -351.136827)
			(xy 279.174157 -351.144391) (xy 279.133046 -351.14484) (xy 279.091442 -351.14437) (xy 279.008594 -351.136637)
			(xy 278.926829 -351.121206) (xy 278.846862 -351.098211) (xy 278.769389 -351.067854) (xy 278.695088 -351.0304)
			(xy 278.65959 -351.008696) (xy 278.650458 -351.003521) (xy 278.629738 -351.00031) (xy 278.609461 -351.005649)
			(xy 278.600916 -351.011744) (xy 278.567266 -351.037664) (xy 278.495892 -351.083723) (xy 278.420453 -351.12277)
			(xy 278.341637 -351.15445) (xy 278.26016 -351.178473) (xy 278.176764 -351.194623) (xy 278.092208 -351.20275)
			(xy 278.049736 -351.20326) (xy 278.049482 -351.20326) (xy 278.008375 -351.202805) (xy 277.926511 -351.195219)
			(xy 277.845697 -351.180113) (xy 277.76662 -351.157617) (xy 277.689956 -351.127921) (xy 277.616359 -351.09128)
			(xy 277.546455 -351.048006) (xy 277.480841 -350.998468) (xy 277.420077 -350.943088) (xy 277.364682 -350.882339)
			(xy 277.315126 -350.816738) (xy 277.271833 -350.746846) (xy 277.235173 -350.673258) (xy 277.205458 -350.596602)
			(xy 277.182941 -350.517531) (xy 277.167814 -350.43672) (xy 277.160206 -350.354859) (xy 277.15972 -350.313752)
			(xy 277.160279 -350.268982) (xy 277.16929 -350.179897) (xy 277.187196 -350.092166) (xy 277.213816 -350.006675)
			(xy 277.23084 -349.965264) (xy 277.234432 -349.955681) (xy 277.234415 -349.935231) (xy 277.23084 -349.92564)
			(xy 277.213836 -349.884289) (xy 277.187225 -349.798927) (xy 277.169318 -349.711324) (xy 277.160296 -349.622367)
			(xy 277.15972 -349.57766) (xy 277.15972 -349.576644) (xy 277.159974 -349.565214) (xy 277.133495 -349.559269)
			(xy 277.08126 -349.544526) (xy 277.05558 -349.53575) (xy 277.047383 -349.533236) (xy 277.030249 -349.533236)
			(xy 277.022052 -349.53575) (xy 276.986836 -349.547697) (xy 276.914826 -349.566284) (xy 276.841503 -349.578724)
			(xy 276.767392 -349.584928) (xy 276.730206 -349.58528) (xy 276.693022 -349.584911) (xy 276.618914 -349.578689)
			(xy 276.545594 -349.566246) (xy 276.473583 -349.547672) (xy 276.43836 -349.53575) (xy 276.430163 -349.533236)
			(xy 276.413029 -349.533236) (xy 276.404832 -349.53575) (xy 276.36973 -349.547637) (xy 276.297974 -349.566187)
			(xy 276.224911 -349.578634) (xy 276.15106 -349.584887) (xy 276.114002 -349.58528) (xy 276.112986 -349.58528)
			(xy 276.071059 -349.584857) (xy 275.987586 -349.576885) (xy 275.905248 -349.561014) (xy 275.824792 -349.537389)
			(xy 275.746946 -349.506223) (xy 275.672414 -349.467798) (xy 275.601873 -349.422463) (xy 275.53596 -349.370628)
			(xy 275.475273 -349.312762) (xy 275.420361 -349.24939) (xy 275.371722 -349.181084) (xy 275.329796 -349.108465)
			(xy 275.294962 -349.032189) (xy 275.267537 -348.952948) (xy 275.247768 -348.871458) (xy 275.235834 -348.788458)
			(xy 275.231844 -348.7047) (xy 85.721282 -348.7047) (xy 85.724562 -348.719921) (xy 85.734552 -348.813881)
			(xy 85.73516 -348.861126) (xy 85.734613 -348.906766) (xy 85.725307 -348.997569) (xy 85.706754 -349.086942)
			(xy 85.693504 -349.13062) (xy 85.691044 -349.139629) (xy 85.692095 -349.15826) (xy 85.695536 -349.166942)
			(xy 85.714247 -349.210016) (xy 85.743525 -349.299254) (xy 85.763232 -349.391081) (xy 85.77315 -349.484473)
			(xy 85.773768 -349.531432) (xy 85.77323 -349.574377) (xy 85.764932 -349.659867) (xy 85.748446 -349.744161)
			(xy 85.723925 -349.826477) (xy 85.708236 -349.866458) (xy 85.704966 -349.875707) (xy 85.704968 -349.895308)
			(xy 85.708236 -349.904558) (xy 85.723933 -349.944537) (xy 85.748482 -350.026848) (xy 85.764973 -350.111143)
			(xy 85.773254 -350.196637) (xy 85.773768 -350.239584) (xy 85.773768 -350.239838) (xy 85.773264 -350.282199)
			(xy 85.765211 -350.366536) (xy 85.749177 -350.449726) (xy 85.725309 -350.531016) (xy 85.693821 -350.609668)
			(xy 85.654999 -350.684971) (xy 85.609196 -350.756243) (xy 85.556825 -350.822839) (xy 85.49836 -350.884154)
			(xy 85.434332 -350.939635) (xy 85.36532 -350.988778) (xy 85.29195 -351.031138) (xy 85.214885 -351.066333)
			(xy 85.134823 -351.094042) (xy 85.05249 -351.114016) (xy 84.968631 -351.126073) (xy 84.884006 -351.130105)
			(xy 84.799381 -351.126073) (xy 84.715522 -351.114016) (xy 84.633189 -351.094042) (xy 84.553127 -351.066333)
			(xy 84.476062 -351.031138) (xy 84.402692 -350.988778) (xy 84.33368 -350.939635) (xy 84.269652 -350.884154)
			(xy 84.211187 -350.822839) (xy 84.158816 -350.756243) (xy 84.113013 -350.684971) (xy 84.074191 -350.609668)
			(xy 84.042703 -350.531016) (xy 84.018835 -350.449726) (xy 84.002801 -350.366536) (xy 83.994748 -350.282199)
			(xy 83.994244 -350.239838) (xy 83.994244 -350.239584) (xy 83.994787 -350.196639) (xy 84.003083 -350.111149)
			(xy 84.019568 -350.026855) (xy 84.044088 -349.944539) (xy 84.059776 -349.904558) (xy 84.063037 -349.895306)
			(xy 84.06304 -349.875708) (xy 84.059776 -349.866458) (xy 84.044053 -349.826489) (xy 84.019511 -349.744174)
			(xy 84.003027 -349.659876) (xy 83.994754 -349.57438) (xy 83.994244 -349.531432) (xy 83.994855 -349.485787)
			(xy 84.004246 -349.394981) (xy 84.022872 -349.305612) (xy 84.036154 -349.261938) (xy 84.038586 -349.252923)
			(xy 84.037555 -349.234298) (xy 84.034122 -349.225616) (xy 84.015469 -349.182525) (xy 83.98626 -349.093282)
			(xy 83.966612 -349.001459) (xy 83.956742 -348.908077) (xy 83.956144 -348.861126) (xy 83.073245 -348.861126)
			(xy 83.073748 -348.89948) (xy 83.073141 -348.945125) (xy 83.063748 -349.035931) (xy 83.045121 -349.1253)
			(xy 83.031838 -349.168974) (xy 83.0294 -349.177987) (xy 83.030435 -349.196614) (xy 83.03387 -349.205296)
			(xy 83.052527 -349.248385) (xy 83.081735 -349.337629) (xy 83.101382 -349.429453) (xy 83.111251 -349.522835)
			(xy 83.111848 -349.569786) (xy 83.111412 -349.610119) (xy 83.104141 -349.690457) (xy 83.08963 -349.769807)
			(xy 83.067997 -349.847519) (xy 83.039422 -349.922954) (xy 83.022186 -349.959422) (xy 83.017653 -349.970011)
			(xy 83.017661 -349.993024) (xy 83.022186 -350.003618) (xy 83.039387 -350.040045) (xy 83.067929 -350.115383)
			(xy 83.089551 -350.19299) (xy 83.104075 -350.272234) (xy 83.111383 -350.352465) (xy 83.111848 -350.392746)
			(xy 83.111848 -350.393) (xy 83.111344 -350.435361) (xy 83.103291 -350.519698) (xy 83.087257 -350.602888)
			(xy 83.063389 -350.684178) (xy 83.031901 -350.76283) (xy 82.993079 -350.838133) (xy 82.947276 -350.909405)
			(xy 82.894905 -350.976001) (xy 82.83644 -351.037316) (xy 82.772412 -351.092797) (xy 82.7034 -351.14194)
			(xy 82.63003 -351.1843) (xy 82.552965 -351.219495) (xy 82.472903 -351.247204) (xy 82.39057 -351.267178)
			(xy 82.306711 -351.279235) (xy 82.222086 -351.283267) (xy 82.137461 -351.279235) (xy 82.053602 -351.267178)
			(xy 81.971269 -351.247204) (xy 81.891207 -351.219495) (xy 81.814142 -351.1843) (xy 81.740772 -351.14194)
			(xy 81.67176 -351.092797) (xy 81.607732 -351.037316) (xy 81.549267 -350.976001) (xy 81.496896 -350.909405)
			(xy 81.451093 -350.838133) (xy 81.412271 -350.76283) (xy 81.380783 -350.684178) (xy 81.356915 -350.602888)
			(xy 81.340881 -350.519698) (xy 81.332828 -350.435361) (xy 81.332324 -350.393) (xy 81.332778 -350.35266)
			(xy 81.340081 -350.272312) (xy 81.354637 -350.192956) (xy 81.376326 -350.115246) (xy 81.404968 -350.039822)
			(xy 81.42224 -350.003364) (xy 81.426812 -349.992711) (xy 81.426828 -349.969558) (xy 81.42224 -349.958914)
			(xy 81.405059 -349.922483) (xy 81.376548 -349.847143) (xy 81.35497 -349.769534) (xy 81.340501 -349.69029)
			(xy 81.33326 -349.610063) (xy 81.332832 -349.569786) (xy 81.333382 -349.524146) (xy 81.342687 -349.433343)
			(xy 81.361239 -349.34397) (xy 81.374488 -349.300292) (xy 81.376942 -349.291282) (xy 81.375896 -349.272652)
			(xy 81.372456 -349.26397) (xy 81.353748 -349.220894) (xy 81.32447 -349.131657) (xy 81.304762 -349.039831)
			(xy 81.294843 -348.946439) (xy 81.294224 -348.89948) (xy 66.467942 -348.89948) (xy 66.465784 -348.920813)
			(xy 66.447878 -349.008544) (xy 66.421259 -349.094035) (xy 66.404236 -349.135446) (xy 66.400697 -349.145044)
			(xy 66.400681 -349.16548) (xy 66.404236 -349.17507) (xy 66.421263 -349.21648) (xy 66.4479 -349.301967)
			(xy 66.465806 -349.3897) (xy 66.474803 -349.478787) (xy 66.475356 -349.523558) (xy 66.474795 -349.568328)
			(xy 66.465784 -349.657413) (xy 66.447878 -349.745144) (xy 66.421259 -349.830635) (xy 66.404236 -349.872046)
			(xy 66.400697 -349.881644) (xy 66.400681 -349.90208) (xy 66.404236 -349.91167) (xy 66.421263 -349.95308)
			(xy 66.4479 -350.038567) (xy 66.465806 -350.1263) (xy 66.474803 -350.215387) (xy 66.475356 -350.260158)
			(xy 66.474861 -350.301272) (xy 66.467278 -350.383151) (xy 66.452172 -350.46398) (xy 66.429672 -350.54307)
			(xy 66.39997 -350.619748) (xy 66.36332 -350.693357) (xy 66.320034 -350.76327) (xy 66.270482 -350.828891)
			(xy 66.215086 -350.88966) (xy 66.154319 -350.945059) (xy 66.0887 -350.994614) (xy 66.018788 -351.037902)
			(xy 65.94518 -351.074555) (xy 65.868505 -351.10426) (xy 65.789415 -351.126764) (xy 65.708586 -351.141873)
			(xy 65.626708 -351.14946) (xy 65.585594 -351.14992) (xy 65.543984 -351.149442) (xy 65.461127 -351.141665)
			(xy 65.379358 -351.12619) (xy 65.299391 -351.10315) (xy 65.221922 -351.072748) (xy 65.147629 -351.035248)
			(xy 65.112138 -351.013522) (xy 65.10303 -351.008297) (xy 65.082293 -351.005101) (xy 65.062008 -351.010462)
			(xy 65.053464 -351.01657) (xy 65.019831 -351.042555) (xy 64.948437 -351.08868) (xy 64.872967 -351.127782)
			(xy 64.79411 -351.159503) (xy 64.712585 -351.183553) (xy 64.629138 -351.199714) (xy 64.544529 -351.207838)
			(xy 64.50203 -351.20834) (xy 64.460915 -351.207873) (xy 64.379035 -351.200288) (xy 64.298205 -351.185181)
			(xy 64.219114 -351.162679) (xy 64.142436 -351.132976) (xy 64.068826 -351.096324) (xy 63.998912 -351.053036)
			(xy 63.93329 -351.003482) (xy 63.872521 -350.948084) (xy 63.817123 -350.887316) (xy 63.767568 -350.821695)
			(xy 63.72428 -350.751781) (xy 63.687628 -350.678172) (xy 63.657923 -350.601494) (xy 63.635421 -350.522403)
			(xy 63.620313 -350.441573) (xy 63.612727 -350.359693) (xy 63.612268 -350.318578) (xy 63.61284 -350.273809)
			(xy 63.621847 -350.184724) (xy 63.63975 -350.096993) (xy 63.666366 -350.011501) (xy 63.683388 -349.97009)
			(xy 63.686968 -349.960503) (xy 63.68696 -349.940056) (xy 63.683388 -349.930466) (xy 63.666363 -349.889123)
			(xy 63.639757 -349.803758) (xy 63.621856 -349.716153) (xy 63.612841 -349.627193) (xy 63.612268 -349.582486)
			(xy 63.612268 -349.58147) (xy 63.612522 -349.57004) (xy 63.586044 -349.564091) (xy 63.533809 -349.54935)
			(xy 63.508128 -349.540576) (xy 63.499931 -349.538062) (xy 63.482797 -349.538062) (xy 63.4746 -349.540576)
			(xy 63.43938 -349.552528) (xy 63.367379 -349.571185) (xy 63.294059 -349.583696) (xy 63.219944 -349.589972)
			(xy 63.182754 -349.59036) (xy 63.145565 -349.589952) (xy 63.071452 -349.583667) (xy 62.998133 -349.571163)
			(xy 62.926126 -349.552528) (xy 62.890908 -349.540576) (xy 62.882711 -349.538062) (xy 62.865577 -349.538062)
			(xy 62.85738 -349.540576) (xy 62.822162 -349.552533) (xy 62.75016 -349.571189) (xy 62.676839 -349.583699)
			(xy 62.602724 -349.589973) (xy 62.565534 -349.59036) (xy 62.523594 -349.589902) (xy 62.440094 -349.581932)
			(xy 62.35773 -349.566061) (xy 62.277248 -349.542432) (xy 62.199376 -349.511259) (xy 62.12482 -349.472825)
			(xy 62.054255 -349.427478) (xy 61.98832 -349.375629) (xy 61.927613 -349.317747) (xy 61.872683 -349.254356)
			(xy 61.824027 -349.186031) (xy 61.782086 -349.11339) (xy 61.74724 -349.037091) (xy 61.719806 -348.957825)
			(xy 61.70003 -348.87631) (xy 61.688092 -348.793284) (xy 61.684101 -348.7095) (xy 58.14031 -348.7095)
			(xy 58.143679 -348.745845) (xy 58.144156 -348.786958) (xy 58.143595 -348.831728) (xy 58.134584 -348.920813)
			(xy 58.116678 -349.008544) (xy 58.090059 -349.094035) (xy 58.073036 -349.135446) (xy 58.069497 -349.145044)
			(xy 58.069481 -349.16548) (xy 58.073036 -349.17507) (xy 58.090063 -349.21648) (xy 58.1167 -349.301967)
			(xy 58.134606 -349.3897) (xy 58.143603 -349.478787) (xy 58.144156 -349.523558) (xy 58.143595 -349.568328)
			(xy 58.134584 -349.657413) (xy 58.116678 -349.745144) (xy 58.090059 -349.830635) (xy 58.073036 -349.872046)
			(xy 58.069497 -349.881644) (xy 58.069481 -349.90208) (xy 58.073036 -349.91167) (xy 58.090063 -349.95308)
			(xy 58.1167 -350.038567) (xy 58.134606 -350.1263) (xy 58.143603 -350.215387) (xy 58.144156 -350.260158)
			(xy 58.143661 -350.301272) (xy 58.136078 -350.383151) (xy 58.120972 -350.46398) (xy 58.098472 -350.54307)
			(xy 58.06877 -350.619748) (xy 58.03212 -350.693357) (xy 57.988834 -350.76327) (xy 57.939282 -350.828891)
			(xy 57.883886 -350.88966) (xy 57.823119 -350.945059) (xy 57.7575 -350.994614) (xy 57.687588 -351.037902)
			(xy 57.61398 -351.074555) (xy 57.537305 -351.10426) (xy 57.458215 -351.126764) (xy 57.377386 -351.141873)
			(xy 57.295508 -351.14946) (xy 57.254394 -351.14992) (xy 57.212784 -351.149442) (xy 57.129927 -351.141665)
			(xy 57.048158 -351.12619) (xy 56.968191 -351.10315) (xy 56.890722 -351.072748) (xy 56.816429 -351.035248)
			(xy 56.780938 -351.013522) (xy 56.77183 -351.008297) (xy 56.751093 -351.005101) (xy 56.730808 -351.010462)
			(xy 56.722264 -351.01657) (xy 56.688631 -351.042555) (xy 56.617237 -351.08868) (xy 56.541767 -351.127782)
			(xy 56.46291 -351.159503) (xy 56.381385 -351.183553) (xy 56.297938 -351.199714) (xy 56.213329 -351.207838)
			(xy 56.17083 -351.20834) (xy 56.129715 -351.207873) (xy 56.047835 -351.200288) (xy 55.967005 -351.185181)
			(xy 55.887914 -351.162679) (xy 55.811236 -351.132976) (xy 55.737626 -351.096324) (xy 55.667712 -351.053036)
			(xy 55.60209 -351.003482) (xy 55.541321 -350.948084) (xy 55.485923 -350.887316) (xy 55.436368 -350.821695)
			(xy 55.39308 -350.751781) (xy 55.356428 -350.678172) (xy 55.326723 -350.601494) (xy 55.304221 -350.522403)
			(xy 55.289113 -350.441573) (xy 55.281527 -350.359693) (xy 55.281068 -350.318578) (xy 55.28164 -350.273809)
			(xy 55.290647 -350.184724) (xy 55.30855 -350.096993) (xy 55.335166 -350.011501) (xy 55.352188 -349.97009)
			(xy 55.355768 -349.960503) (xy 55.35576 -349.940056) (xy 55.352188 -349.930466) (xy 55.335163 -349.889123)
			(xy 55.308557 -349.803758) (xy 55.290656 -349.716153) (xy 55.281641 -349.627193) (xy 55.281068 -349.582486)
			(xy 55.281068 -349.58147) (xy 55.281322 -349.57004) (xy 55.254844 -349.564091) (xy 55.202609 -349.54935)
			(xy 55.176928 -349.540576) (xy 55.168731 -349.538062) (xy 55.151597 -349.538062) (xy 55.1434 -349.540576)
			(xy 55.10818 -349.552528) (xy 55.036179 -349.571185) (xy 54.962859 -349.583696) (xy 54.888744 -349.589972)
			(xy 54.851554 -349.59036) (xy 54.814365 -349.589952) (xy 54.740252 -349.583667) (xy 54.666933 -349.571163)
			(xy 54.594926 -349.552528) (xy 54.559708 -349.540576) (xy 54.551511 -349.538062) (xy 54.534377 -349.538062)
			(xy 54.52618 -349.540576) (xy 54.490962 -349.552533) (xy 54.41896 -349.571189) (xy 54.345639 -349.583699)
			(xy 54.271524 -349.589973) (xy 54.234334 -349.59036) (xy 54.192394 -349.589902) (xy 54.108894 -349.581932)
			(xy 54.02653 -349.566061) (xy 53.946048 -349.542432) (xy 53.868176 -349.511259) (xy 53.79362 -349.472825)
			(xy 53.723055 -349.427478) (xy 53.65712 -349.375629) (xy 53.596413 -349.317747) (xy 53.541483 -349.254356)
			(xy 53.492827 -349.186031) (xy 53.450886 -349.11339) (xy 53.41604 -349.037091) (xy 53.388606 -348.957825)
			(xy 53.36883 -348.87631) (xy 53.356892 -348.793284) (xy 53.352901 -348.7095) (xy 49.78371 -348.7095)
			(xy 49.787079 -348.745845) (xy 49.787556 -348.786958) (xy 49.786995 -348.831728) (xy 49.777984 -348.920813)
			(xy 49.760078 -349.008544) (xy 49.733459 -349.094035) (xy 49.716436 -349.135446) (xy 49.712897 -349.145044)
			(xy 49.712881 -349.16548) (xy 49.716436 -349.17507) (xy 49.733463 -349.21648) (xy 49.7601 -349.301967)
			(xy 49.778006 -349.3897) (xy 49.787003 -349.478787) (xy 49.787556 -349.523558) (xy 49.786995 -349.568328)
			(xy 49.777984 -349.657413) (xy 49.760078 -349.745144) (xy 49.733459 -349.830635) (xy 49.716436 -349.872046)
			(xy 49.712897 -349.881644) (xy 49.712881 -349.90208) (xy 49.716436 -349.91167) (xy 49.733463 -349.95308)
			(xy 49.7601 -350.038567) (xy 49.778006 -350.1263) (xy 49.787003 -350.215387) (xy 49.787556 -350.260158)
			(xy 49.787061 -350.301272) (xy 49.779478 -350.383151) (xy 49.764372 -350.46398) (xy 49.741872 -350.54307)
			(xy 49.71217 -350.619748) (xy 49.67552 -350.693357) (xy 49.632234 -350.76327) (xy 49.582682 -350.828891)
			(xy 49.527286 -350.88966) (xy 49.466519 -350.945059) (xy 49.4009 -350.994614) (xy 49.330988 -351.037902)
			(xy 49.25738 -351.074555) (xy 49.180705 -351.10426) (xy 49.101615 -351.126764) (xy 49.020786 -351.141873)
			(xy 48.938908 -351.14946) (xy 48.897794 -351.14992) (xy 48.856184 -351.149442) (xy 48.773327 -351.141665)
			(xy 48.691558 -351.12619) (xy 48.611591 -351.10315) (xy 48.534122 -351.072748) (xy 48.459829 -351.035248)
			(xy 48.424338 -351.013522) (xy 48.41523 -351.008297) (xy 48.394493 -351.005101) (xy 48.374208 -351.010462)
			(xy 48.365664 -351.01657) (xy 48.332031 -351.042555) (xy 48.260637 -351.08868) (xy 48.185167 -351.127782)
			(xy 48.10631 -351.159503) (xy 48.024785 -351.183553) (xy 47.941338 -351.199714) (xy 47.856729 -351.207838)
			(xy 47.81423 -351.20834) (xy 47.773115 -351.207873) (xy 47.691235 -351.200288) (xy 47.610405 -351.185181)
			(xy 47.531314 -351.162679) (xy 47.454636 -351.132976) (xy 47.381026 -351.096324) (xy 47.311112 -351.053036)
			(xy 47.24549 -351.003482) (xy 47.184721 -350.948084) (xy 47.129323 -350.887316) (xy 47.079768 -350.821695)
			(xy 47.03648 -350.751781) (xy 46.999828 -350.678172) (xy 46.970123 -350.601494) (xy 46.947621 -350.522403)
			(xy 46.932513 -350.441573) (xy 46.924927 -350.359693) (xy 46.924468 -350.318578) (xy 46.92504 -350.273809)
			(xy 46.934047 -350.184724) (xy 46.95195 -350.096993) (xy 46.978566 -350.011501) (xy 46.995588 -349.97009)
			(xy 46.999168 -349.960503) (xy 46.99916 -349.940056) (xy 46.995588 -349.930466) (xy 46.978563 -349.889123)
			(xy 46.951957 -349.803758) (xy 46.934056 -349.716153) (xy 46.925041 -349.627193) (xy 46.924468 -349.582486)
			(xy 46.924468 -349.58147) (xy 46.924722 -349.57004) (xy 46.898244 -349.564091) (xy 46.846009 -349.54935)
			(xy 46.820328 -349.540576) (xy 46.812131 -349.538062) (xy 46.794997 -349.538062) (xy 46.7868 -349.540576)
			(xy 46.75158 -349.552528) (xy 46.679579 -349.571185) (xy 46.606259 -349.583696) (xy 46.532144 -349.589972)
			(xy 46.494954 -349.59036) (xy 46.457765 -349.589952) (xy 46.383652 -349.583667) (xy 46.310333 -349.571163)
			(xy 46.238326 -349.552528) (xy 46.203108 -349.540576) (xy 46.194911 -349.538062) (xy 46.177777 -349.538062)
			(xy 46.16958 -349.540576) (xy 46.134362 -349.552533) (xy 46.06236 -349.571189) (xy 45.989039 -349.583699)
			(xy 45.914924 -349.589973) (xy 45.877734 -349.59036) (xy 45.835794 -349.589902) (xy 45.752294 -349.581932)
			(xy 45.66993 -349.566061) (xy 45.589448 -349.542432) (xy 45.511576 -349.511259) (xy 45.43702 -349.472825)
			(xy 45.366455 -349.427478) (xy 45.30052 -349.375629) (xy 45.239813 -349.317747) (xy 45.184883 -349.254356)
			(xy 45.136227 -349.186031) (xy 45.094286 -349.11339) (xy 45.05944 -349.037091) (xy 45.032006 -348.957825)
			(xy 45.01223 -348.87631) (xy 45.000292 -348.793284) (xy 44.996301 -348.7095) (xy 41.47791 -348.7095)
			(xy 41.481279 -348.745845) (xy 41.481756 -348.786958) (xy 41.481195 -348.831728) (xy 41.472184 -348.920813)
			(xy 41.454278 -349.008544) (xy 41.427659 -349.094035) (xy 41.410636 -349.135446) (xy 41.407097 -349.145044)
			(xy 41.407081 -349.16548) (xy 41.410636 -349.17507) (xy 41.427663 -349.21648) (xy 41.4543 -349.301967)
			(xy 41.472206 -349.3897) (xy 41.481203 -349.478787) (xy 41.481756 -349.523558) (xy 41.481195 -349.568328)
			(xy 41.472184 -349.657413) (xy 41.454278 -349.745144) (xy 41.427659 -349.830635) (xy 41.410636 -349.872046)
			(xy 41.407097 -349.881644) (xy 41.407081 -349.90208) (xy 41.410636 -349.91167) (xy 41.427663 -349.95308)
			(xy 41.4543 -350.038567) (xy 41.472206 -350.1263) (xy 41.481203 -350.215387) (xy 41.481756 -350.260158)
			(xy 41.481261 -350.301272) (xy 41.473678 -350.383151) (xy 41.458572 -350.46398) (xy 41.436072 -350.54307)
			(xy 41.40637 -350.619748) (xy 41.36972 -350.693357) (xy 41.326434 -350.76327) (xy 41.276882 -350.828891)
			(xy 41.221486 -350.88966) (xy 41.160719 -350.945059) (xy 41.0951 -350.994614) (xy 41.025188 -351.037902)
			(xy 40.95158 -351.074555) (xy 40.874905 -351.10426) (xy 40.795815 -351.126764) (xy 40.714986 -351.141873)
			(xy 40.633108 -351.14946) (xy 40.591994 -351.14992) (xy 40.550384 -351.149442) (xy 40.467527 -351.141665)
			(xy 40.385758 -351.12619) (xy 40.305791 -351.10315) (xy 40.228322 -351.072748) (xy 40.154029 -351.035248)
			(xy 40.118538 -351.013522) (xy 40.10943 -351.008297) (xy 40.088693 -351.005101) (xy 40.068408 -351.010462)
			(xy 40.059864 -351.01657) (xy 40.026231 -351.042555) (xy 39.954837 -351.08868) (xy 39.879367 -351.127782)
			(xy 39.80051 -351.159503) (xy 39.718985 -351.183553) (xy 39.635538 -351.199714) (xy 39.550929 -351.207838)
			(xy 39.50843 -351.20834) (xy 39.467315 -351.207873) (xy 39.385435 -351.200288) (xy 39.304605 -351.185181)
			(xy 39.225514 -351.162679) (xy 39.148836 -351.132976) (xy 39.075226 -351.096324) (xy 39.005312 -351.053036)
			(xy 38.93969 -351.003482) (xy 38.878921 -350.948084) (xy 38.823523 -350.887316) (xy 38.773968 -350.821695)
			(xy 38.73068 -350.751781) (xy 38.694028 -350.678172) (xy 38.664323 -350.601494) (xy 38.641821 -350.522403)
			(xy 38.626713 -350.441573) (xy 38.619127 -350.359693) (xy 38.618668 -350.318578) (xy 38.61924 -350.273809)
			(xy 38.628247 -350.184724) (xy 38.64615 -350.096993) (xy 38.672766 -350.011501) (xy 38.689788 -349.97009)
			(xy 38.693368 -349.960503) (xy 38.69336 -349.940056) (xy 38.689788 -349.930466) (xy 38.672763 -349.889123)
			(xy 38.646157 -349.803758) (xy 38.628256 -349.716153) (xy 38.619241 -349.627193) (xy 38.618668 -349.582486)
			(xy 38.618668 -349.58147) (xy 38.618922 -349.57004) (xy 38.592444 -349.564091) (xy 38.540209 -349.54935)
			(xy 38.514528 -349.540576) (xy 38.506331 -349.538062) (xy 38.489197 -349.538062) (xy 38.481 -349.540576)
			(xy 38.44578 -349.552528) (xy 38.373779 -349.571185) (xy 38.300459 -349.583696) (xy 38.226344 -349.589972)
			(xy 38.189154 -349.59036) (xy 38.151965 -349.589952) (xy 38.077852 -349.583667) (xy 38.004533 -349.571163)
			(xy 37.932526 -349.552528) (xy 37.897308 -349.540576) (xy 37.889111 -349.538062) (xy 37.871977 -349.538062)
			(xy 37.86378 -349.540576) (xy 37.828562 -349.552533) (xy 37.75656 -349.571189) (xy 37.683239 -349.583699)
			(xy 37.609124 -349.589973) (xy 37.571934 -349.59036) (xy 37.529996 -349.589881) (xy 37.446499 -349.581908)
			(xy 37.364138 -349.566035) (xy 37.283659 -349.542404) (xy 37.20579 -349.511231) (xy 37.131238 -349.472797)
			(xy 37.060676 -349.42745) (xy 36.994745 -349.375601) (xy 36.93404 -349.317719) (xy 36.879112 -349.25433)
			(xy 36.830459 -349.186006) (xy 36.788521 -349.113367) (xy 36.753677 -349.03707) (xy 36.726244 -348.957807)
			(xy 36.706469 -348.876294) (xy 36.694532 -348.793272) (xy 36.690541 -348.70949) (xy 33.197509 -348.70949)
			(xy 33.200879 -348.745845) (xy 33.201356 -348.786958) (xy 33.200795 -348.831728) (xy 33.191784 -348.920813)
			(xy 33.173878 -349.008544) (xy 33.147259 -349.094035) (xy 33.130236 -349.135446) (xy 33.126697 -349.145044)
			(xy 33.126681 -349.16548) (xy 33.130236 -349.17507) (xy 33.147263 -349.21648) (xy 33.1739 -349.301967)
			(xy 33.191806 -349.3897) (xy 33.200803 -349.478787) (xy 33.201356 -349.523558) (xy 33.200795 -349.568328)
			(xy 33.191784 -349.657413) (xy 33.173878 -349.745144) (xy 33.147259 -349.830635) (xy 33.130236 -349.872046)
			(xy 33.126697 -349.881644) (xy 33.126681 -349.90208) (xy 33.130236 -349.91167) (xy 33.147263 -349.95308)
			(xy 33.1739 -350.038567) (xy 33.191806 -350.1263) (xy 33.200803 -350.215387) (xy 33.201356 -350.260158)
			(xy 33.200861 -350.301272) (xy 33.193278 -350.383151) (xy 33.178172 -350.46398) (xy 33.155672 -350.54307)
			(xy 33.12597 -350.619748) (xy 33.08932 -350.693357) (xy 33.046034 -350.76327) (xy 32.996482 -350.828891)
			(xy 32.941086 -350.88966) (xy 32.880319 -350.945059) (xy 32.8147 -350.994614) (xy 32.744788 -351.037902)
			(xy 32.67118 -351.074555) (xy 32.594505 -351.10426) (xy 32.515415 -351.126764) (xy 32.434586 -351.141873)
			(xy 32.352708 -351.14946) (xy 32.311594 -351.14992) (xy 32.269984 -351.149442) (xy 32.187127 -351.141665)
			(xy 32.105358 -351.12619) (xy 32.025391 -351.10315) (xy 31.947922 -351.072748) (xy 31.873629 -351.035248)
			(xy 31.838138 -351.013522) (xy 31.82903 -351.008297) (xy 31.808293 -351.005101) (xy 31.788008 -351.010462)
			(xy 31.779464 -351.01657) (xy 31.745831 -351.042555) (xy 31.674437 -351.08868) (xy 31.598967 -351.127782)
			(xy 31.52011 -351.159503) (xy 31.438585 -351.183553) (xy 31.355138 -351.199714) (xy 31.270529 -351.207838)
			(xy 31.22803 -351.20834) (xy 31.186915 -351.207873) (xy 31.105035 -351.200288) (xy 31.024205 -351.185181)
			(xy 30.945114 -351.162679) (xy 30.868436 -351.132976) (xy 30.794826 -351.096324) (xy 30.724912 -351.053036)
			(xy 30.65929 -351.003482) (xy 30.598521 -350.948084) (xy 30.543123 -350.887316) (xy 30.493568 -350.821695)
			(xy 30.45028 -350.751781) (xy 30.413628 -350.678172) (xy 30.383923 -350.601494) (xy 30.361421 -350.522403)
			(xy 30.346313 -350.441573) (xy 30.338727 -350.359693) (xy 30.338268 -350.318578) (xy 30.33884 -350.273809)
			(xy 30.347847 -350.184724) (xy 30.36575 -350.096993) (xy 30.392366 -350.011501) (xy 30.409388 -349.97009)
			(xy 30.412968 -349.960503) (xy 30.41296 -349.940056) (xy 30.409388 -349.930466) (xy 30.392363 -349.889123)
			(xy 30.365757 -349.803758) (xy 30.347856 -349.716153) (xy 30.338841 -349.627193) (xy 30.338268 -349.582486)
			(xy 30.338268 -349.58147) (xy 30.338522 -349.57004) (xy 30.312044 -349.564091) (xy 30.259809 -349.54935)
			(xy 30.234128 -349.540576) (xy 30.225931 -349.538062) (xy 30.208797 -349.538062) (xy 30.2006 -349.540576)
			(xy 30.16538 -349.552528) (xy 30.093379 -349.571185) (xy 30.020059 -349.583696) (xy 29.945944 -349.589972)
			(xy 29.908754 -349.59036) (xy 29.871565 -349.589952) (xy 29.797452 -349.583667) (xy 29.724133 -349.571163)
			(xy 29.652126 -349.552528) (xy 29.616908 -349.540576) (xy 29.608711 -349.538062) (xy 29.591577 -349.538062)
			(xy 29.58338 -349.540576) (xy 29.548162 -349.552533) (xy 29.47616 -349.571189) (xy 29.402839 -349.583699)
			(xy 29.328724 -349.589973) (xy 29.291534 -349.59036) (xy 29.249596 -349.589881) (xy 29.166099 -349.581908)
			(xy 29.083738 -349.566035) (xy 29.003259 -349.542404) (xy 28.92539 -349.511231) (xy 28.850838 -349.472797)
			(xy 28.780276 -349.42745) (xy 28.714345 -349.375601) (xy 28.65364 -349.317719) (xy 28.598712 -349.25433)
			(xy 28.550059 -349.186006) (xy 28.508121 -349.113367) (xy 28.473277 -349.03707) (xy 28.445844 -348.957807)
			(xy 28.426069 -348.876294) (xy 28.414132 -348.793272) (xy 28.410141 -348.70949) (xy 2.509012 -348.70949)
			(xy 2.509012 -351.637854) (xy 73.92162 -351.637854) (xy 73.922073 -351.597287) (xy 73.929469 -351.516491)
			(xy 73.944194 -351.436705) (xy 73.966127 -351.358593) (xy 73.995085 -351.282803) (xy 74.012552 -351.246186)
			(xy 74.016468 -351.237096) (xy 74.017766 -351.217362) (xy 74.015092 -351.207832) (xy 74.000912 -351.162806)
			(xy 73.981012 -351.070523) (xy 73.971009 -350.97665) (xy 73.970388 -350.929448) (xy 73.970892 -350.887087)
			(xy 73.978945 -350.80275) (xy 73.994979 -350.71956) (xy 74.018847 -350.63827) (xy 74.050335 -350.559618)
			(xy 74.089157 -350.484315) (xy 74.13496 -350.413043) (xy 74.187331 -350.346447) (xy 74.245796 -350.285132)
			(xy 74.309824 -350.229651) (xy 74.378836 -350.180508) (xy 74.452206 -350.138148) (xy 74.529271 -350.102953)
			(xy 74.609333 -350.075244) (xy 74.691666 -350.05527) (xy 74.775525 -350.043213) (xy 74.86015 -350.039182)
			(xy 74.944775 -350.043213) (xy 75.028634 -350.05527) (xy 75.110967 -350.075244) (xy 75.191029 -350.102953)
			(xy 75.268094 -350.138148) (xy 75.341464 -350.180508) (xy 75.410476 -350.229651) (xy 75.474504 -350.285132)
			(xy 75.532969 -350.346447) (xy 75.58534 -350.413043) (xy 75.631143 -350.484315) (xy 75.669965 -350.559618)
			(xy 75.701453 -350.63827) (xy 75.725321 -350.71956) (xy 75.741355 -350.80275) (xy 75.749408 -350.887087)
			(xy 75.749912 -350.929448) (xy 75.749456 -350.970015) (xy 75.742061 -351.05081) (xy 75.727336 -351.130596)
			(xy 75.705403 -351.208709) (xy 75.676446 -351.284499) (xy 75.65898 -351.321116) (xy 75.655063 -351.330206)
			(xy 75.653765 -351.34994) (xy 75.65644 -351.35947) (xy 75.670621 -351.404496) (xy 75.69052 -351.496779)
			(xy 75.700524 -351.590652) (xy 75.70064 -351.5995) (xy 76.58354 -351.5995) (xy 76.583977 -351.558938)
			(xy 76.59131 -351.478148) (xy 76.605978 -351.398363) (xy 76.62786 -351.320247) (xy 76.656772 -351.244452)
			(xy 76.674218 -351.207832) (xy 76.67814 -351.198816) (xy 76.679575 -351.179224) (xy 76.677012 -351.169732)
			(xy 76.662856 -351.124831) (xy 76.642989 -351.0328) (xy 76.632962 -350.939185) (xy 76.632308 -350.89211)
			(xy 76.632308 -350.891094) (xy 76.632812 -350.848746) (xy 76.640863 -350.764432) (xy 76.656892 -350.681266)
			(xy 76.680753 -350.599999) (xy 76.712232 -350.521369) (xy 76.751043 -350.446088) (xy 76.796833 -350.374836)
			(xy 76.849189 -350.30826) (xy 76.907637 -350.246962) (xy 76.971647 -350.191497) (xy 77.040639 -350.142368)
			(xy 77.113989 -350.100019) (xy 77.191032 -350.064835) (xy 77.271071 -350.037133) (xy 77.35338 -350.017165)
			(xy 77.437215 -350.005112) (xy 77.521816 -350.001082) (xy 77.606417 -350.005112) (xy 77.690252 -350.017165)
			(xy 77.772561 -350.037133) (xy 77.8526 -350.064835) (xy 77.929643 -350.100019) (xy 78.002993 -350.142368)
			(xy 78.071985 -350.191497) (xy 78.135995 -350.246962) (xy 78.194443 -350.30826) (xy 78.246799 -350.374836)
			(xy 78.292589 -350.446088) (xy 78.3314 -350.521369) (xy 78.362879 -350.599999) (xy 78.38674 -350.681266)
			(xy 78.402769 -350.764432) (xy 78.41082 -350.848746) (xy 78.411324 -350.891094) (xy 78.411324 -350.891602)
			(xy 78.410897 -350.932113) (xy 78.403528 -351.0128) (xy 78.388844 -351.09248) (xy 78.366965 -351.170492)
			(xy 78.338074 -351.246189) (xy 78.320646 -351.282762) (xy 78.316728 -351.291779) (xy 78.315288 -351.31137)
			(xy 78.317852 -351.320862) (xy 78.33205 -351.365927) (xy 78.351954 -351.458296) (xy 78.361947 -351.552255)
			(xy 78.362556 -351.5995) (xy 78.362003 -351.645139) (xy 78.352699 -351.735943) (xy 78.334149 -351.825316)
			(xy 78.3209 -351.868994) (xy 78.318454 -351.878006) (xy 78.319496 -351.896634) (xy 78.322932 -351.905316)
			(xy 78.341634 -351.948394) (xy 78.370914 -352.03763) (xy 78.390624 -352.129456) (xy 78.400545 -352.222848)
			(xy 78.401164 -352.269806) (xy 78.401164 -352.27006) (xy 78.400635 -352.313006) (xy 78.392335 -352.398495)
			(xy 78.375846 -352.482789) (xy 78.351322 -352.565106) (xy 78.335632 -352.605086) (xy 78.332346 -352.614331)
			(xy 78.332359 -352.633935) (xy 78.335632 -352.643186) (xy 78.351338 -352.683162) (xy 78.375884 -352.765474)
			(xy 78.392373 -352.84977) (xy 78.400651 -352.935265) (xy 78.401164 -352.978212) (xy 78.40066 -353.020573)
			(xy 78.392607 -353.10491) (xy 78.376573 -353.1881) (xy 78.352705 -353.26939) (xy 78.346936 -353.2838)
			(xy 182.729656 -353.2838) (xy 182.733646 -353.200045) (xy 182.745579 -353.117047) (xy 182.765347 -353.035561)
			(xy 182.792771 -352.956321) (xy 182.827603 -352.880048) (xy 182.869527 -352.807431) (xy 182.918163 -352.739127)
			(xy 182.973072 -352.675756) (xy 183.033756 -352.617891) (xy 183.099666 -352.566056) (xy 183.170204 -352.520721)
			(xy 183.244732 -352.482296) (xy 183.322575 -352.451129) (xy 183.403028 -352.427503) (xy 183.485362 -352.411631)
			(xy 183.568833 -352.403656) (xy 183.610758 -352.403156) (xy 183.611774 -352.403156) (xy 183.648831 -352.403571)
			(xy 183.72268 -352.409833) (xy 183.795742 -352.422272) (xy 183.867502 -352.440802) (xy 183.902604 -352.452686)
			(xy 183.910801 -352.4552) (xy 183.927935 -352.4552) (xy 183.936132 -352.452686) (xy 183.964337 -352.443048)
			(xy 184.021791 -352.42716) (xy 184.05094 -352.420936) (xy 184.060579 -352.41851) (xy 184.077071 -352.407448)
			(xy 184.088123 -352.390948) (xy 184.090564 -352.381312) (xy 184.100088 -352.337416) (xy 184.126813 -352.251655)
			(xy 184.143904 -352.210116) (xy 184.147468 -352.200525) (xy 184.147469 -352.180082) (xy 184.143904 -352.170492)
			(xy 184.126892 -352.12911) (xy 184.100271 -352.043685) (xy 184.082363 -351.956018) (xy 184.073351 -351.866996)
			(xy 184.072784 -351.822258) (xy 184.072784 -351.822004) (xy 184.073288 -351.779656) (xy 184.081339 -351.695342)
			(xy 184.097368 -351.612176) (xy 184.121229 -351.530909) (xy 184.152708 -351.452279) (xy 184.191519 -351.376998)
			(xy 184.237309 -351.305746) (xy 184.289665 -351.23917) (xy 184.348113 -351.177872) (xy 184.412123 -351.122407)
			(xy 184.481115 -351.073278) (xy 184.554465 -351.030929) (xy 184.631508 -350.995745) (xy 184.711547 -350.968043)
			(xy 184.793856 -350.948075) (xy 184.877691 -350.936022) (xy 184.962292 -350.931992) (xy 185.046893 -350.936022)
			(xy 185.130728 -350.948075) (xy 185.213037 -350.968043) (xy 185.293076 -350.995745) (xy 185.370119 -351.030929)
			(xy 185.443469 -351.073278) (xy 185.512461 -351.122407) (xy 185.576471 -351.177872) (xy 185.634919 -351.23917)
			(xy 185.687275 -351.305746) (xy 185.733065 -351.376998) (xy 185.771876 -351.452279) (xy 185.803355 -351.530909)
			(xy 185.827216 -351.612176) (xy 185.843245 -351.695342) (xy 185.851296 -351.779656) (xy 185.8518 -351.822004)
			(xy 185.8518 -351.822258) (xy 185.851234 -351.866996) (xy 185.842218 -351.956018) (xy 185.824312 -352.043685)
			(xy 185.797698 -352.129113) (xy 185.78068 -352.170492) (xy 185.777112 -352.180082) (xy 185.777113 -352.200525)
			(xy 185.78068 -352.210116) (xy 185.797704 -352.251527) (xy 185.824339 -352.337015) (xy 185.842246 -352.424746)
			(xy 185.851245 -352.513834) (xy 185.8518 -352.558604) (xy 185.85116 -352.609084) (xy 185.839825 -352.709404)
			(xy 185.829194 -352.758756) (xy 185.826997 -352.771225) (xy 185.833664 -352.795617) (xy 185.841894 -352.805238)
			(xy 185.882534 -352.847656) (xy 185.889646 -352.846132) (xy 185.898412 -352.843862) (xy 185.913646 -352.834103)
			(xy 185.919364 -352.827082) (xy 185.944527 -352.794419) (xy 185.999939 -352.733355) (xy 186.060764 -352.67768)
			(xy 186.126478 -352.627872) (xy 186.196519 -352.584357) (xy 186.270286 -352.547509) (xy 186.347146 -352.517645)
			(xy 186.426439 -352.49502) (xy 186.507485 -352.479828) (xy 186.589589 -352.472201) (xy 186.630818 -352.471736)
			(xy 186.671925 -352.472195) (xy 186.753788 -352.479781) (xy 186.834603 -352.494887) (xy 186.913679 -352.517383)
			(xy 186.990343 -352.547078) (xy 187.06394 -352.583719) (xy 187.133844 -352.626993) (xy 187.199457 -352.676531)
			(xy 187.260221 -352.73191) (xy 187.315617 -352.792659) (xy 187.365173 -352.85826) (xy 187.408465 -352.928152)
			(xy 187.445126 -353.001739) (xy 187.474841 -353.078395) (xy 187.497359 -353.157466) (xy 187.512486 -353.238276)
			(xy 187.519078 -353.3092) (xy 191.056256 -353.3092) (xy 191.060246 -353.225443) (xy 191.07218 -353.142444)
			(xy 191.091948 -353.060956) (xy 191.119373 -352.981715) (xy 191.154206 -352.90544) (xy 191.196132 -352.832822)
			(xy 191.244771 -352.764518) (xy 191.299682 -352.701146) (xy 191.360368 -352.643281) (xy 191.42628 -352.591447)
			(xy 191.49682 -352.546112) (xy 191.57135 -352.507688) (xy 191.649196 -352.476522) (xy 191.729651 -352.452897)
			(xy 191.811988 -352.437027) (xy 191.89546 -352.429055) (xy 191.937386 -352.428556) (xy 191.938402 -352.428556)
			(xy 191.975459 -352.428963) (xy 192.049308 -352.435227) (xy 192.12237 -352.447669) (xy 192.194131 -352.466201)
			(xy 192.229232 -352.478086) (xy 192.237429 -352.4806) (xy 192.254563 -352.4806) (xy 192.26276 -352.478086)
			(xy 192.290041 -352.468747) (xy 192.345585 -352.453243) (xy 192.373758 -352.447098) (xy 192.383527 -352.444576)
			(xy 192.400163 -352.433196) (xy 192.411142 -352.416293) (xy 192.413382 -352.406458) (xy 192.422838 -352.357349)
			(xy 192.451357 -352.261489) (xy 192.470278 -352.215196) (xy 192.473919 -352.205632) (xy 192.474045 -352.185185)
			(xy 192.470532 -352.175572) (xy 192.453515 -352.134192) (xy 192.426895 -352.048766) (xy 192.408989 -351.961099)
			(xy 192.399978 -351.872077) (xy 192.399412 -351.827338) (xy 192.399412 -351.827084) (xy 192.399916 -351.784736)
			(xy 192.407967 -351.700422) (xy 192.423996 -351.617256) (xy 192.447857 -351.535989) (xy 192.479336 -351.457359)
			(xy 192.518147 -351.382078) (xy 192.563937 -351.310826) (xy 192.616293 -351.24425) (xy 192.674741 -351.182952)
			(xy 192.738751 -351.127487) (xy 192.807743 -351.078358) (xy 192.881093 -351.036009) (xy 192.958136 -351.000825)
			(xy 193.038175 -350.973123) (xy 193.120484 -350.953155) (xy 193.204319 -350.941102) (xy 193.28892 -350.937072)
			(xy 193.373521 -350.941102) (xy 193.457356 -350.953155) (xy 193.539665 -350.973123) (xy 193.619704 -351.000825)
			(xy 193.696747 -351.036009) (xy 193.770097 -351.078358) (xy 193.839089 -351.127487) (xy 193.903099 -351.182952)
			(xy 193.961547 -351.24425) (xy 194.013903 -351.310826) (xy 194.059693 -351.382078) (xy 194.098504 -351.457359)
			(xy 194.129983 -351.535989) (xy 194.153844 -351.617256) (xy 194.169873 -351.700422) (xy 194.177924 -351.784736)
			(xy 194.178428 -351.827084) (xy 194.178428 -351.827338) (xy 194.177853 -351.872076) (xy 194.168839 -351.961098)
			(xy 194.150936 -352.048765) (xy 194.124325 -352.134193) (xy 194.107308 -352.175572) (xy 194.10375 -352.185165)
			(xy 194.103744 -352.205606) (xy 194.107308 -352.215196) (xy 194.12436 -352.256596) (xy 194.150986 -352.342088)
			(xy 194.165052 -352.41103) (xy 206.449676 -352.41103) (xy 206.449676 -351.54743) (xy 206.450162 -351.520179)
			(xy 206.457918 -351.466231) (xy 206.473273 -351.413936) (xy 206.495915 -351.364359) (xy 206.525381 -351.318509)
			(xy 206.561072 -351.277318) (xy 206.602263 -351.241627) (xy 206.648113 -351.212161) (xy 206.69769 -351.189519)
			(xy 206.749985 -351.174164) (xy 206.803933 -351.166408) (xy 206.858435 -351.166408) (xy 206.912383 -351.174164)
			(xy 206.964678 -351.189519) (xy 207.014255 -351.212161) (xy 207.060105 -351.241627) (xy 207.101296 -351.277318)
			(xy 207.136987 -351.318509) (xy 207.166453 -351.364359) (xy 207.189095 -351.413936) (xy 207.20445 -351.466231)
			(xy 207.212206 -351.520179) (xy 207.212692 -351.54743) (xy 207.212692 -352.41103) (xy 207.212206 -352.438281)
			(xy 207.20445 -352.492229) (xy 207.189095 -352.544524) (xy 207.166453 -352.594101) (xy 207.136987 -352.639951)
			(xy 207.101296 -352.681142) (xy 207.060105 -352.716833) (xy 207.014255 -352.746299) (xy 206.964678 -352.768941)
			(xy 206.912383 -352.784296) (xy 206.858435 -352.792052) (xy 206.803933 -352.792052) (xy 206.749985 -352.784296)
			(xy 206.69769 -352.768941) (xy 206.648113 -352.746299) (xy 206.602263 -352.716833) (xy 206.561072 -352.681142)
			(xy 206.525381 -352.639951) (xy 206.495915 -352.594101) (xy 206.473273 -352.544524) (xy 206.457918 -352.492229)
			(xy 206.450162 -352.438281) (xy 206.449676 -352.41103) (xy 194.165052 -352.41103) (xy 194.168886 -352.429823)
			(xy 194.177877 -352.518913) (xy 194.178428 -352.563684) (xy 194.178055 -352.600778) (xy 194.171875 -352.674709)
			(xy 194.159556 -352.747868) (xy 194.150742 -352.783902) (xy 194.149 -352.792252) (xy 194.15051 -352.809229)
			(xy 194.157543 -352.824754) (xy 194.163188 -352.831146) (xy 194.203574 -352.874326) (xy 194.216274 -352.871532)
			(xy 194.225043 -352.869274) (xy 194.240276 -352.859506) (xy 194.245992 -352.852482) (xy 194.271138 -352.819805)
			(xy 194.326552 -352.758742) (xy 194.387379 -352.703068) (xy 194.453095 -352.65326) (xy 194.523138 -352.609746)
			(xy 194.596907 -352.5729) (xy 194.673768 -352.543037) (xy 194.753063 -352.520414) (xy 194.834111 -352.505225)
			(xy 194.916217 -352.4976) (xy 194.957446 -352.497136) (xy 194.998553 -352.497569) (xy 195.080417 -352.505157)
			(xy 195.161232 -352.520265) (xy 195.240309 -352.542764) (xy 195.316973 -352.572461) (xy 195.390571 -352.609104)
			(xy 195.460474 -352.652379) (xy 195.526087 -352.701919) (xy 195.586851 -352.757301) (xy 195.642247 -352.818051)
			(xy 195.691802 -352.883653) (xy 195.735094 -352.953546) (xy 195.744851 -352.973132) (xy 338.849208 -352.973132)
			(xy 338.849825 -352.926972) (xy 338.859426 -352.835153) (xy 338.878488 -352.744823) (xy 338.906804 -352.656953)
			(xy 338.9249 -352.614484) (xy 338.928699 -352.60454) (xy 338.928703 -352.583278) (xy 338.9249 -352.573336)
			(xy 338.90688 -352.530918) (xy 338.878719 -352.443158) (xy 338.859786 -352.352956) (xy 338.850284 -352.26128)
			(xy 338.849716 -352.215196) (xy 338.850295 -352.1688) (xy 338.859941 -352.076512) (xy 338.879138 -351.985728)
			(xy 338.907678 -351.897435) (xy 338.925916 -351.85477) (xy 338.929722 -351.844828) (xy 338.929721 -351.823565)
			(xy 338.925916 -351.813622) (xy 338.907694 -351.771019) (xy 338.879176 -351.682852) (xy 338.859983 -351.592196)
			(xy 338.850324 -351.500036) (xy 338.849716 -351.453704) (xy 338.849716 -351.453196) (xy 338.850148 -351.412092)
			(xy 338.857734 -351.330235) (xy 338.87284 -351.249427) (xy 338.895338 -351.170357) (xy 338.925036 -351.093701)
			(xy 338.96168 -351.020112) (xy 339.004958 -350.950218) (xy 339.0545 -350.884616) (xy 339.109884 -350.823864)
			(xy 339.170637 -350.768482) (xy 339.236241 -350.718942) (xy 339.306137 -350.675666) (xy 339.379727 -350.639025)
			(xy 339.456384 -350.609329) (xy 339.535454 -350.586834) (xy 339.616263 -350.57173) (xy 339.69812 -350.564147)
			(xy 339.739224 -350.563688) (xy 339.739732 -350.563688) (xy 339.786063 -350.564321) (xy 339.87822 -350.573985)
			(xy 339.968874 -350.593172) (xy 340.057044 -350.621677) (xy 340.09965 -350.639888) (xy 340.109592 -350.643694)
			(xy 340.130856 -350.643694) (xy 340.140798 -350.639888) (xy 340.183427 -350.621646) (xy 340.271658 -350.593118)
			(xy 340.36238 -350.573927) (xy 340.454606 -350.564283) (xy 340.50097 -350.563688) (xy 340.501478 -350.563688)
			(xy 340.547841 -350.56431) (xy 340.640063 -350.57396) (xy 340.730782 -350.593148) (xy 340.819014 -350.621665)
			(xy 340.86165 -350.639888) (xy 340.871592 -350.643694) (xy 340.892856 -350.643694) (xy 340.902798 -350.639888)
			(xy 340.945427 -350.621646) (xy 341.033658 -350.593118) (xy 341.12438 -350.573927) (xy 341.216606 -350.564283)
			(xy 341.26297 -350.563688) (xy 341.263478 -350.563688) (xy 341.309841 -350.56431) (xy 341.402063 -350.57396)
			(xy 341.492782 -350.593148) (xy 341.581014 -350.621665) (xy 341.62365 -350.639888) (xy 341.633592 -350.643694)
			(xy 341.654856 -350.643694) (xy 341.664798 -350.639888) (xy 341.707427 -350.621646) (xy 341.795658 -350.593118)
			(xy 341.88638 -350.573927) (xy 341.978606 -350.564283) (xy 342.02497 -350.563688) (xy 342.025478 -350.563688)
			(xy 342.071841 -350.56431) (xy 342.164063 -350.57396) (xy 342.254782 -350.593148) (xy 342.343014 -350.621665)
			(xy 342.38565 -350.639888) (xy 342.395592 -350.643694) (xy 342.416856 -350.643694) (xy 342.426798 -350.639888)
			(xy 342.469427 -350.621646) (xy 342.557658 -350.593118) (xy 342.64838 -350.573927) (xy 342.740606 -350.564283)
			(xy 342.78697 -350.563688) (xy 342.787478 -350.563688) (xy 342.833911 -350.564319) (xy 342.926269 -350.574013)
			(xy 343.017117 -350.593266) (xy 343.105468 -350.621869) (xy 343.148158 -350.640142) (xy 343.156911 -350.643584)
			(xy 343.175683 -350.644482) (xy 343.184734 -350.64192) (xy 343.229904 -350.627586) (xy 343.322519 -350.607479)
			(xy 343.416748 -350.597344) (xy 343.464134 -350.596708) (xy 343.465404 -350.596708) (xy 343.506508 -350.597148)
			(xy 343.588364 -350.604734) (xy 343.669172 -350.61984) (xy 343.748241 -350.642338) (xy 343.824897 -350.672035)
			(xy 343.898486 -350.708679) (xy 343.968379 -350.751956) (xy 344.033982 -350.801498) (xy 344.094733 -350.856881)
			(xy 344.150115 -350.917634) (xy 344.199655 -350.983237) (xy 344.242931 -351.053132) (xy 344.279573 -351.126721)
			(xy 344.309269 -351.203378) (xy 344.331765 -351.282448) (xy 344.346869 -351.363255) (xy 344.354453 -351.445112)
			(xy 344.354912 -351.486216) (xy 344.354912 -351.486724) (xy 344.354311 -351.533056) (xy 344.344638 -351.625214)
			(xy 344.325441 -351.715868) (xy 344.296928 -351.804037) (xy 344.278712 -351.846642) (xy 344.274897 -351.856581)
			(xy 344.274903 -351.877848) (xy 344.278712 -351.88779) (xy 344.296962 -351.93045) (xy 344.325505 -352.018743)
			(xy 344.344696 -352.109529) (xy 344.354328 -352.20182) (xy 344.354912 -352.248216) (xy 344.354328 -352.294369)
			(xy 344.344776 -352.386179) (xy 344.325776 -352.476508) (xy 344.297531 -352.564386) (xy 344.279474 -352.606864)
			(xy 344.275648 -352.6168) (xy 344.275662 -352.638069) (xy 344.279474 -352.648012) (xy 344.29749 -352.690438)
			(xy 344.325707 -352.77819) (xy 344.344711 -352.868387) (xy 344.354297 -352.960064) (xy 344.354912 -353.006152)
			(xy 344.354402 -353.047262) (xy 344.34922 -353.1032) (xy 423.453493 -353.1032) (xy 423.457484 -353.019415)
			(xy 423.469422 -352.936388) (xy 423.489198 -352.854872) (xy 423.516634 -352.775605) (xy 423.55148 -352.699305)
			(xy 423.593421 -352.626663) (xy 423.642078 -352.558337) (xy 423.697009 -352.494945) (xy 423.757718 -352.437063)
			(xy 423.823654 -352.385213) (xy 423.89422 -352.339866) (xy 423.968777 -352.301432) (xy 424.04665 -352.270259)
			(xy 424.127133 -352.24663) (xy 424.209499 -352.230759) (xy 424.293 -352.222789) (xy 424.33494 -352.222308)
			(xy 424.372129 -352.222714) (xy 424.446242 -352.228999) (xy 424.519562 -352.241503) (xy 424.591568 -352.260139)
			(xy 424.626786 -352.272092) (xy 424.634983 -352.274606) (xy 424.652117 -352.274606) (xy 424.660314 -352.272092)
			(xy 424.687596 -352.262757) (xy 424.74314 -352.24725) (xy 424.771312 -352.241104) (xy 424.781089 -352.238609)
			(xy 424.797722 -352.227214) (xy 424.808697 -352.210302) (xy 424.810936 -352.200464) (xy 424.820391 -352.151355)
			(xy 424.84891 -352.055495) (xy 424.867832 -352.009202) (xy 424.871403 -351.999613) (xy 424.871399 -351.979169)
			(xy 424.867832 -351.969578) (xy 424.850786 -351.928175) (xy 424.824155 -351.842685) (xy 424.806254 -351.754951)
			(xy 424.797263 -351.665861) (xy 424.796712 -351.62109) (xy 424.797216 -351.578729) (xy 424.805269 -351.494392)
			(xy 424.821303 -351.411202) (xy 424.845171 -351.329912) (xy 424.876659 -351.25126) (xy 424.915481 -351.175957)
			(xy 424.961284 -351.104685) (xy 425.013655 -351.038089) (xy 425.07212 -350.976774) (xy 425.136148 -350.921293)
			(xy 425.20516 -350.87215) (xy 425.27853 -350.82979) (xy 425.355595 -350.794595) (xy 425.435657 -350.766886)
			(xy 425.51799 -350.746912) (xy 425.601849 -350.734855) (xy 425.686474 -350.730824) (xy 425.771099 -350.734855)
			(xy 425.854958 -350.746912) (xy 425.937291 -350.766886) (xy 426.017353 -350.794595) (xy 426.094418 -350.82979)
			(xy 426.167788 -350.87215) (xy 426.2368 -350.921293) (xy 426.300828 -350.976774) (xy 426.359293 -351.038089)
			(xy 426.411664 -351.104685) (xy 426.457467 -351.175957) (xy 426.496289 -351.25126) (xy 426.527777 -351.329912)
			(xy 426.551645 -351.411202) (xy 426.567679 -351.494392) (xy 426.575732 -351.578729) (xy 426.576236 -351.62109)
			(xy 426.575653 -351.665859) (xy 426.566649 -351.754944) (xy 426.548749 -351.842675) (xy 426.522136 -351.928167)
			(xy 426.505116 -351.969578) (xy 426.501559 -351.979171) (xy 426.501555 -351.999611) (xy 426.505116 -352.009202)
			(xy 426.522153 -352.050608) (xy 426.548787 -352.136097) (xy 426.566691 -352.22383) (xy 426.575684 -352.312919)
			(xy 426.576236 -352.35769) (xy 426.575843 -352.394784) (xy 426.569667 -352.468714) (xy 426.557358 -352.541873)
			(xy 426.54855 -352.577908) (xy 426.5467 -352.586267) (xy 426.54815 -352.603318) (xy 426.55512 -352.618947)
			(xy 426.560742 -352.625406) (xy 426.601128 -352.668332) (xy 426.613574 -352.665538) (xy 426.622391 -352.663274)
			(xy 426.637739 -352.653501) (xy 426.643546 -352.646488) (xy 426.66867 -352.613784) (xy 426.724067 -352.552685)
			(xy 426.784882 -352.496976) (xy 426.850593 -352.447136) (xy 426.920635 -352.403592) (xy 426.994408 -352.366719)
			(xy 427.071277 -352.336834) (xy 427.150582 -352.314192) (xy 427.231643 -352.298989) (xy 427.313763 -352.291354)
			(xy 427.355 -352.290888) (xy 427.396095 -352.291366) (xy 427.477934 -352.298948) (xy 427.558725 -352.314048)
			(xy 427.637779 -352.336536) (xy 427.71442 -352.366221) (xy 427.787997 -352.40285) (xy 427.85788 -352.44611)
			(xy 427.923475 -352.495633) (xy 427.984222 -352.550996) (xy 428.039602 -352.611726) (xy 428.089144 -352.677307)
			(xy 428.132424 -352.747178) (xy 428.169074 -352.820744) (xy 428.198782 -352.897377) (xy 428.221293 -352.976424)
			(xy 428.236416 -353.05721) (xy 428.243051 -353.1286) (xy 431.780208 -353.1286) (xy 431.784199 -353.04482)
			(xy 431.796136 -352.961799) (xy 431.815909 -352.880289) (xy 431.843342 -352.801027) (xy 431.878184 -352.724732)
			(xy 431.92012 -352.652094) (xy 431.968771 -352.583771) (xy 432.023696 -352.520381) (xy 432.084398 -352.4625)
			(xy 432.150327 -352.410651) (xy 432.220886 -352.365303) (xy 432.295436 -352.326868) (xy 432.373301 -352.295693)
			(xy 432.453778 -352.27206) (xy 432.536136 -352.256184) (xy 432.619631 -352.248208) (xy 432.661568 -352.247708)
			(xy 432.698757 -352.248106) (xy 432.77287 -352.254393) (xy 432.84619 -352.2669) (xy 432.918196 -352.285538)
			(xy 432.953414 -352.297492) (xy 432.961611 -352.300006) (xy 432.978745 -352.300006) (xy 432.986942 -352.297492)
			(xy 433.014223 -352.288155) (xy 433.069768 -352.27265) (xy 433.09794 -352.266504) (xy 433.107722 -352.264025)
			(xy 433.124353 -352.252622) (xy 433.135327 -352.235704) (xy 433.137564 -352.225864) (xy 433.147017 -352.176755)
			(xy 433.175537 -352.080895) (xy 433.19446 -352.034602) (xy 433.19803 -352.025013) (xy 433.198026 -352.004569)
			(xy 433.19446 -351.994978) (xy 433.177416 -351.953575) (xy 433.150784 -351.868085) (xy 433.132882 -351.780351)
			(xy 433.123891 -351.691261) (xy 433.12334 -351.64649) (xy 433.123844 -351.604129) (xy 433.131897 -351.519792)
			(xy 433.147931 -351.436602) (xy 433.171799 -351.355312) (xy 433.203287 -351.27666) (xy 433.242109 -351.201357)
			(xy 433.287912 -351.130085) (xy 433.340283 -351.063489) (xy 433.398748 -351.002174) (xy 433.462776 -350.946693)
			(xy 433.531788 -350.89755) (xy 433.605158 -350.85519) (xy 433.682223 -350.819995) (xy 433.762285 -350.792286)
			(xy 433.844618 -350.772312) (xy 433.928477 -350.760255) (xy 434.013102 -350.756224) (xy 434.097727 -350.760255)
			(xy 434.181586 -350.772312) (xy 434.263919 -350.792286) (xy 434.343981 -350.819995) (xy 434.421046 -350.85519)
			(xy 434.494416 -350.89755) (xy 434.563428 -350.946693) (xy 434.627456 -351.002174) (xy 434.685921 -351.063489)
			(xy 434.738292 -351.130085) (xy 434.784095 -351.201357) (xy 434.822917 -351.27666) (xy 434.854405 -351.355312)
			(xy 434.878273 -351.436602) (xy 434.894307 -351.519792) (xy 434.90236 -351.604129) (xy 434.902864 -351.64649)
			(xy 434.902279 -351.691259) (xy 434.893275 -351.780343) (xy 434.875376 -351.868074) (xy 434.848764 -351.953566)
			(xy 434.831744 -351.994978) (xy 434.828186 -352.00457) (xy 434.828182 -352.025011) (xy 434.831744 -352.034602)
			(xy 434.848782 -352.076008) (xy 434.875415 -352.161497) (xy 434.893319 -352.24923) (xy 434.902312 -352.338319)
			(xy 434.902864 -352.38309) (xy 434.90247 -352.420184) (xy 434.896295 -352.494114) (xy 434.883986 -352.567273)
			(xy 434.875178 -352.603308) (xy 434.873347 -352.611669) (xy 434.874795 -352.628716) (xy 434.881755 -352.644345)
			(xy 434.88737 -352.650806) (xy 434.927756 -352.693732) (xy 434.940202 -352.690938) (xy 434.94901 -352.688645)
			(xy 434.964363 -352.678893) (xy 434.970174 -352.671888) (xy 434.995281 -352.639171) (xy 435.05068 -352.578072)
			(xy 435.111497 -352.522364) (xy 435.17721 -352.472524) (xy 435.247255 -352.428982) (xy 435.321029 -352.39211)
			(xy 435.3979 -352.362226) (xy 435.477207 -352.339586) (xy 435.558269 -352.324385) (xy 435.64039 -352.316753)
			(xy 435.681628 -352.316288) (xy 435.722723 -352.31674) (xy 435.804563 -352.324324) (xy 435.885355 -352.339426)
			(xy 435.964409 -352.361917) (xy 436.04105 -352.391604) (xy 436.114627 -352.428235) (xy 436.18451 -352.471497)
			(xy 436.250105 -352.521022) (xy 436.310851 -352.576386) (xy 436.366231 -352.637118) (xy 436.415773 -352.7027)
			(xy 436.459053 -352.772572) (xy 436.495703 -352.846139) (xy 436.52541 -352.922773) (xy 436.547921 -353.001821)
			(xy 436.563044 -353.082609) (xy 436.57065 -353.164447) (xy 436.571136 -353.205542) (xy 436.571136 -353.20605)
			(xy 436.570568 -353.25082) (xy 436.561569 -353.339906) (xy 436.543667 -353.427639) (xy 436.517044 -353.513129)
			(xy 436.500016 -353.554538) (xy 436.496425 -353.564121) (xy 436.496444 -353.58457) (xy 436.500016 -353.594162)
			(xy 436.517052 -353.635569) (xy 436.543684 -353.721058) (xy 436.561588 -353.808791) (xy 436.570583 -353.897879)
			(xy 436.571136 -353.94265) (xy 436.570568 -353.98742) (xy 436.561569 -354.076506) (xy 436.543667 -354.164239)
			(xy 436.517044 -354.249729) (xy 436.500016 -354.291138) (xy 436.496425 -354.300721) (xy 436.496444 -354.32117)
			(xy 436.500016 -354.330762) (xy 436.517046 -354.372136) (xy 436.543663 -354.457564) (xy 436.561565 -354.545233)
			(xy 436.570572 -354.634257) (xy 436.571136 -354.678996) (xy 436.571136 -354.67925) (xy 436.57064 -354.720357)
			(xy 436.56306 -354.80222) (xy 436.547959 -354.883035) (xy 436.525468 -354.962112) (xy 436.495777 -355.038776)
			(xy 436.45914 -355.112375) (xy 436.415869 -355.18228) (xy 436.366333 -355.247894) (xy 436.310956 -355.308659)
			(xy 436.250208 -355.364056) (xy 436.184609 -355.413612) (xy 436.114718 -355.456904) (xy 436.041131 -355.493565)
			(xy 435.964475 -355.523279) (xy 435.885405 -355.545796) (xy 435.804595 -355.560921) (xy 435.722735 -355.568527)
			(xy 435.681628 -355.569012) (xy 435.640018 -355.568519) (xy 435.557162 -355.560745) (xy 435.475393 -355.545272)
			(xy 435.395426 -355.522236) (xy 435.317957 -355.491836) (xy 435.243663 -355.454339) (xy 435.208172 -355.432614)
			(xy 435.199049 -355.42742) (xy 435.178322 -355.424214) (xy 435.158043 -355.429561) (xy 435.149498 -355.435662)
			(xy 435.115852 -355.46163) (xy 435.044461 -355.507757) (xy 434.968993 -355.546861) (xy 434.890138 -355.578584)
			(xy 434.808616 -355.602638) (xy 434.72517 -355.618802) (xy 434.640562 -355.626929) (xy 434.598064 -355.627432)
			(xy 434.556969 -355.626968) (xy 434.47513 -355.619383) (xy 434.39434 -355.604281) (xy 434.315287 -355.58179)
			(xy 434.238646 -355.552103) (xy 434.16507 -355.515472) (xy 434.095187 -355.472211) (xy 434.029593 -355.422687)
			(xy 433.968847 -355.367324) (xy 433.913467 -355.306593) (xy 433.863926 -355.241013) (xy 433.820645 -355.171141)
			(xy 433.783995 -355.097576) (xy 433.754287 -355.020943) (xy 433.731775 -354.941896) (xy 433.71665 -354.86111)
			(xy 433.709043 -354.779273) (xy 433.708556 -354.738178) (xy 433.708556 -354.73767) (xy 433.709098 -354.692899)
			(xy 433.718104 -354.603812) (xy 433.736014 -354.51608) (xy 433.762645 -354.430591) (xy 433.779676 -354.389182)
			(xy 433.783256 -354.379596) (xy 433.783245 -354.359149) (xy 433.779676 -354.349558) (xy 433.762646 -354.308149)
			(xy 433.736013 -354.222661) (xy 433.718107 -354.134928) (xy 433.70911 -354.045841) (xy 433.708556 -354.00107)
			(xy 433.708556 -353.989132) (xy 433.682076 -353.983189) (xy 433.629842 -353.968444) (xy 433.604162 -353.959668)
			(xy 433.595965 -353.957154) (xy 433.578831 -353.957154) (xy 433.570634 -353.959668) (xy 433.535422 -353.971642)
			(xy 433.463417 -353.990292) (xy 433.390095 -354.002797) (xy 433.315979 -354.009067) (xy 433.278788 -354.009452)
			(xy 433.241598 -354.009064) (xy 433.167486 -354.002773) (xy 433.094166 -353.990263) (xy 433.02216 -353.971623)
			(xy 432.986942 -353.959668) (xy 432.978745 -353.957154) (xy 432.961611 -353.957154) (xy 432.953414 -353.959668)
			(xy 432.918203 -353.971647) (xy 432.846198 -353.990296) (xy 432.772875 -354.0028) (xy 432.698759 -354.009068)
			(xy 432.661568 -354.009452) (xy 432.619631 -354.008992) (xy 432.536136 -354.001016) (xy 432.453778 -353.98514)
			(xy 432.373301 -353.961507) (xy 432.295436 -353.930332) (xy 432.220886 -353.891897) (xy 432.150327 -353.846549)
			(xy 432.084398 -353.7947) (xy 432.023696 -353.736819) (xy 431.968771 -353.673429) (xy 431.92012 -353.605106)
			(xy 431.878184 -353.532468) (xy 431.843342 -353.456173) (xy 431.815909 -353.376911) (xy 431.796136 -353.295401)
			(xy 431.784199 -353.21238) (xy 431.780208 -353.1286) (xy 428.243051 -353.1286) (xy 428.244022 -353.139047)
			(xy 428.244508 -353.180142) (xy 428.244508 -353.18065) (xy 428.243935 -353.22542) (xy 428.234936 -353.314506)
			(xy 428.217036 -353.402238) (xy 428.190415 -353.487729) (xy 428.173388 -353.529138) (xy 428.169793 -353.53872)
			(xy 428.169812 -353.559171) (xy 428.173388 -353.568762) (xy 428.190428 -353.610167) (xy 428.217058 -353.695657)
			(xy 428.23496 -353.783391) (xy 428.243955 -353.872479) (xy 428.244508 -353.91725) (xy 428.243935 -353.96202)
			(xy 428.234936 -354.051106) (xy 428.217036 -354.138838) (xy 428.190415 -354.224329) (xy 428.173388 -354.265738)
			(xy 428.169793 -354.27532) (xy 428.169812 -354.295771) (xy 428.173388 -354.305362) (xy 428.190417 -354.346737)
			(xy 428.217034 -354.432165) (xy 428.234937 -354.519833) (xy 428.243944 -354.608857) (xy 428.244508 -354.653596)
			(xy 428.244508 -354.65385) (xy 428.24394 -354.694955) (xy 428.23636 -354.776814) (xy 428.221262 -354.857624)
			(xy 428.198773 -354.936698) (xy 428.169085 -355.013359) (xy 428.132451 -355.086955) (xy 428.089184 -355.156857)
			(xy 428.039654 -355.22247) (xy 427.984281 -355.283233) (xy 427.923539 -355.33863) (xy 427.857946 -355.388186)
			(xy 427.788061 -355.431481) (xy 427.714479 -355.468143) (xy 427.63783 -355.497861) (xy 427.558765 -355.520382)
			(xy 427.47796 -355.535512) (xy 427.396104 -355.543124) (xy 427.355 -355.543612) (xy 427.31339 -355.543132)
			(xy 427.230533 -355.535356) (xy 427.148764 -355.519881) (xy 427.068797 -355.496842) (xy 426.991328 -355.46644)
			(xy 426.917035 -355.42894) (xy 426.881544 -355.407214) (xy 426.872433 -355.401996) (xy 426.851698 -355.398798)
			(xy 426.831415 -355.404156) (xy 426.82287 -355.410262) (xy 426.789234 -355.436243) (xy 426.717841 -355.482369)
			(xy 426.642371 -355.521471) (xy 426.563514 -355.553192) (xy 426.481991 -355.577244) (xy 426.398543 -355.593405)
			(xy 426.313935 -355.60153) (xy 426.271436 -355.602032) (xy 426.230342 -355.601499) (xy 426.148505 -355.593921)
			(xy 426.067716 -355.578825) (xy 425.988664 -355.55634) (xy 425.912023 -355.526659) (xy 425.838448 -355.490033)
			(xy 425.768565 -355.446777) (xy 425.70297 -355.397258) (xy 425.642223 -355.341899) (xy 425.586843 -355.281172)
			(xy 425.537301 -355.215595) (xy 425.49402 -355.145727) (xy 425.457368 -355.072164) (xy 425.42766 -354.995534)
			(xy 425.405147 -354.91649) (xy 425.390023 -354.835706) (xy 425.382415 -354.753872) (xy 425.381928 -354.712778)
			(xy 425.381928 -354.71227) (xy 425.382471 -354.667499) (xy 425.391478 -354.578412) (xy 425.409387 -354.49068)
			(xy 425.436017 -354.40519) (xy 425.453048 -354.363782) (xy 425.45663 -354.354196) (xy 425.456619 -354.333749)
			(xy 425.453048 -354.324158) (xy 425.436017 -354.28275) (xy 425.409384 -354.197261) (xy 425.391479 -354.109528)
			(xy 425.382482 -354.020441) (xy 425.381928 -353.97567) (xy 425.381928 -353.963732) (xy 425.35545 -353.957782)
			(xy 425.303215 -353.943042) (xy 425.277534 -353.934268) (xy 425.269337 -353.931754) (xy 425.252203 -353.931754)
			(xy 425.244006 -353.934268) (xy 425.208787 -353.946222) (xy 425.136785 -353.964878) (xy 425.063465 -353.977388)
			(xy 424.98935 -353.983664) (xy 424.95216 -353.984052) (xy 424.914971 -353.983643) (xy 424.840858 -353.977359)
			(xy 424.767539 -353.964855) (xy 424.695532 -353.94622) (xy 424.660314 -353.934268) (xy 424.652117 -353.931754)
			(xy 424.634983 -353.931754) (xy 424.626786 -353.934268) (xy 424.591569 -353.946227) (xy 424.519566 -353.964882)
			(xy 424.446245 -353.977391) (xy 424.37213 -353.983665) (xy 424.33494 -353.984052) (xy 424.293 -353.983611)
			(xy 424.209499 -353.975641) (xy 424.127133 -353.95977) (xy 424.04665 -353.936141) (xy 423.968777 -353.904968)
			(xy 423.89422 -353.866534) (xy 423.823654 -353.821187) (xy 423.757718 -353.769337) (xy 423.697009 -353.711455)
			(xy 423.642078 -353.648063) (xy 423.593421 -353.579737) (xy 423.55148 -353.507095) (xy 423.516634 -353.430795)
			(xy 423.489198 -353.351528) (xy 423.469422 -353.270012) (xy 423.457484 -353.186985) (xy 423.453493 -353.1032)
			(xy 344.34922 -353.1032) (xy 344.346818 -353.129131) (xy 344.331712 -353.20995) (xy 344.309211 -353.289031)
			(xy 344.279508 -353.365698) (xy 344.242856 -353.439296) (xy 344.199569 -353.509197) (xy 344.150015 -353.574806)
			(xy 344.094618 -353.635561) (xy 344.03385 -353.690944) (xy 343.968231 -353.740483) (xy 343.898319 -353.783755)
			(xy 343.824713 -353.82039) (xy 343.748039 -353.850075) (xy 343.668954 -353.872558) (xy 343.58813 -353.887646)
			(xy 343.50626 -353.895211) (xy 343.46515 -353.89566) (xy 343.421566 -353.895134) (xy 343.334811 -353.886653)
			(xy 343.249302 -353.869729) (xy 343.165858 -353.844524) (xy 343.085279 -353.81128) (xy 343.046558 -353.791266)
			(xy 343.035092 -353.785848) (xy 343.009764 -353.785848) (xy 342.998298 -353.791266) (xy 342.959077 -353.812027)
			(xy 342.877306 -353.846516) (xy 342.792508 -353.872694) (xy 342.705525 -353.890299) (xy 342.617221 -353.899159)
			(xy 342.572848 -353.899724) (xy 342.571578 -353.899724) (xy 342.533421 -353.899288) (xy 342.457393 -353.892705)
			(xy 342.382209 -353.879623) (xy 342.308424 -353.86014) (xy 342.272366 -353.847654) (xy 342.26405 -353.845068)
			(xy 342.246646 -353.845068) (xy 342.23833 -353.847654) (xy 342.202121 -353.860189) (xy 342.128019 -353.879707)
			(xy 342.052513 -353.892787) (xy 341.976163 -353.899332) (xy 341.937848 -353.899724) (xy 341.899532 -353.899341)
			(xy 341.823179 -353.892813) (xy 341.747672 -353.879733) (xy 341.673573 -353.860197) (xy 341.637366 -353.847654)
			(xy 341.62905 -353.845068) (xy 341.611646 -353.845068) (xy 341.60333 -353.847654) (xy 341.567121 -353.860189)
			(xy 341.493019 -353.879707) (xy 341.417513 -353.892787) (xy 341.341163 -353.899332) (xy 341.302848 -353.899724)
			(xy 341.264532 -353.899341) (xy 341.188179 -353.892813) (xy 341.112672 -353.879733) (xy 341.038573 -353.860197)
			(xy 341.002366 -353.847654) (xy 340.99405 -353.845068) (xy 340.976646 -353.845068) (xy 340.96833 -353.847654)
			(xy 340.932121 -353.860189) (xy 340.858019 -353.879707) (xy 340.782513 -353.892787) (xy 340.706163 -353.899332)
			(xy 340.667848 -353.899724) (xy 340.626539 -353.899263) (xy 340.544274 -353.89164) (xy 340.463071 -353.876418)
			(xy 340.38363 -353.853729) (xy 340.306637 -353.823768) (xy 340.232755 -353.786793) (xy 340.19744 -353.765358)
			(xy 340.189803 -353.761082) (xy 340.172701 -353.75742) (xy 340.155358 -353.759679) (xy 340.147402 -353.763326)
			(xy 340.109501 -353.782381) (xy 340.030769 -353.813979) (xy 339.949386 -353.837938) (xy 339.866091 -353.85404)
			(xy 339.781642 -353.862138) (xy 339.739224 -353.86264) (xy 339.73897 -353.86264) (xy 339.697862 -353.862216)
			(xy 339.615997 -353.854629) (xy 339.535181 -353.839522) (xy 339.456103 -353.817024) (xy 339.379438 -353.787327)
			(xy 339.30584 -353.750684) (xy 339.235936 -353.707408) (xy 339.170322 -353.657867) (xy 339.109558 -353.602485)
			(xy 339.054162 -353.541734) (xy 339.004606 -353.476131) (xy 338.961314 -353.406237) (xy 338.924655 -353.332646)
			(xy 338.89494 -353.255988) (xy 338.872425 -353.176916) (xy 338.857299 -353.096103) (xy 338.849693 -353.01424)
			(xy 338.849208 -352.973132) (xy 195.744851 -352.973132) (xy 195.771754 -353.027135) (xy 195.80147 -353.103792)
			(xy 195.823987 -353.182863) (xy 195.839114 -353.263674) (xy 195.846722 -353.345537) (xy 195.847208 -353.386644)
			(xy 195.846646 -353.431414) (xy 195.837635 -353.520499) (xy 195.81973 -353.60823) (xy 195.793111 -353.693721)
			(xy 195.776088 -353.735132) (xy 195.772497 -353.744715) (xy 195.772513 -353.765165) (xy 195.776088 -353.774756)
			(xy 195.793114 -353.816166) (xy 195.81975 -353.901654) (xy 195.837657 -353.989386) (xy 195.846654 -354.078474)
			(xy 195.847208 -354.123244) (xy 195.846646 -354.168014) (xy 195.837635 -354.257099) (xy 195.81973 -354.34483)
			(xy 195.793111 -354.430321) (xy 195.776088 -354.471732) (xy 195.772497 -354.481315) (xy 195.772513 -354.501765)
			(xy 195.776088 -354.511356) (xy 195.793114 -354.552766) (xy 195.81975 -354.638254) (xy 195.837657 -354.725986)
			(xy 195.846654 -354.815074) (xy 195.847208 -354.859844) (xy 195.84679 -354.900955) (xy 195.839198 -354.982827)
			(xy 195.824083 -355.063648) (xy 195.801575 -355.14273) (xy 195.771864 -355.219398) (xy 195.742079 -355.279198)
			(xy 285.476188 -355.279198) (xy 285.476597 -355.238082) (xy 285.484185 -355.1562) (xy 285.499295 -355.075367)
			(xy 285.5218 -354.996274) (xy 285.551507 -354.919594) (xy 285.588163 -354.845983) (xy 285.631455 -354.776069)
			(xy 285.681013 -354.710447) (xy 285.736414 -354.649677) (xy 285.797187 -354.594279) (xy 285.862811 -354.544725)
			(xy 285.932729 -354.501438) (xy 286.006342 -354.464786) (xy 286.083023 -354.435084) (xy 286.162118 -354.412584)
			(xy 286.242951 -354.397477) (xy 286.324834 -354.389894) (xy 286.36595 -354.389436) (xy 286.404239 -354.389856)
			(xy 286.480533 -354.39646) (xy 286.555976 -354.409605) (xy 286.630007 -354.429194) (xy 286.666178 -354.44176)
			(xy 286.674615 -354.444411) (xy 286.692285 -354.444411) (xy 286.700722 -354.44176) (xy 286.736903 -354.429226)
			(xy 286.810935 -354.409651) (xy 286.886373 -354.396501) (xy 286.962662 -354.389874) (xy 287.00095 -354.389436)
			(xy 287.039239 -354.389856) (xy 287.115533 -354.39646) (xy 287.190976 -354.409605) (xy 287.265007 -354.429194)
			(xy 287.301178 -354.44176) (xy 287.309615 -354.444411) (xy 287.327285 -354.444411) (xy 287.335722 -354.44176)
			(xy 287.371903 -354.429226) (xy 287.445935 -354.409651) (xy 287.521373 -354.396501) (xy 287.597662 -354.389874)
			(xy 287.63595 -354.389436) (xy 287.674239 -354.389856) (xy 287.750533 -354.39646) (xy 287.825976 -354.409605)
			(xy 287.900007 -354.429194) (xy 287.936178 -354.44176) (xy 287.944615 -354.444411) (xy 287.962285 -354.444411)
			(xy 287.970722 -354.44176) (xy 288.006903 -354.429226) (xy 288.080935 -354.409651) (xy 288.156373 -354.396501)
			(xy 288.232662 -354.389874) (xy 288.27095 -354.389436) (xy 288.309239 -354.389856) (xy 288.385533 -354.39646)
			(xy 288.460976 -354.409605) (xy 288.535007 -354.429194) (xy 288.571178 -354.44176) (xy 288.579615 -354.444411)
			(xy 288.597285 -354.444411) (xy 288.605722 -354.44176) (xy 288.641903 -354.429226) (xy 288.715935 -354.409651)
			(xy 288.791373 -354.396501) (xy 288.867662 -354.389874) (xy 288.90595 -354.389436) (xy 288.947064 -354.389946)
			(xy 289.028942 -354.397529) (xy 289.10977 -354.412634) (xy 289.18886 -354.435133) (xy 289.265537 -354.464834)
			(xy 289.339146 -354.501483) (xy 289.409059 -354.544768) (xy 289.47468 -354.594319) (xy 289.535449 -354.649714)
			(xy 289.590847 -354.71048) (xy 289.640402 -354.776098) (xy 289.683691 -354.846009) (xy 289.720345 -354.919615)
			(xy 289.75005 -354.99629) (xy 289.772554 -355.075379) (xy 289.787664 -355.156207) (xy 289.795251 -355.238084)
			(xy 289.795712 -355.279198) (xy 289.795298 -355.318061) (xy 289.788487 -355.395488) (xy 289.77495 -355.472025)
			(xy 289.75479 -355.547092) (xy 289.741864 -355.583744) (xy 289.739034 -355.592628) (xy 289.739308 -355.611259)
			(xy 289.742372 -355.620066) (xy 289.757559 -355.659473) (xy 289.781314 -355.740522) (xy 289.797291 -355.823456)
			(xy 289.805346 -355.907529) (xy 289.805872 -355.949758) (xy 289.805454 -355.988048) (xy 289.79885 -356.064341)
			(xy 289.785704 -356.139784) (xy 289.766114 -356.213815) (xy 289.753548 -356.249986) (xy 289.750918 -356.258428)
			(xy 289.750905 -356.276094) (xy 289.753548 -356.28453) (xy 289.766084 -356.32071) (xy 289.785659 -356.394742)
			(xy 289.798808 -356.470181) (xy 289.805435 -356.54647) (xy 289.805872 -356.584758) (xy 289.805362 -356.625872)
			(xy 289.797778 -356.707749) (xy 289.782672 -356.788578) (xy 289.760173 -356.867667) (xy 289.730472 -356.944344)
			(xy 289.693822 -357.017952) (xy 289.650537 -357.087865) (xy 289.600986 -357.153486) (xy 289.545592 -357.214255)
			(xy 289.484826 -357.269653) (xy 289.419208 -357.319208) (xy 289.349298 -357.362497) (xy 289.275691 -357.399151)
			(xy 289.199017 -357.428856) (xy 289.119928 -357.45136) (xy 289.039101 -357.466471) (xy 288.957224 -357.474059)
			(xy 288.91611 -357.47452) (xy 288.87782 -357.474114) (xy 288.801526 -357.467506) (xy 288.726084 -357.454357)
			(xy 288.652053 -357.434764) (xy 288.615882 -357.422196) (xy 288.607445 -357.419545) (xy 288.589775 -357.419545)
			(xy 288.581338 -357.422196) (xy 288.54516 -357.434739) (xy 288.471127 -357.454312) (xy 288.395688 -357.46746)
			(xy 288.319398 -357.474084) (xy 288.28111 -357.47452) (xy 288.24282 -357.474114) (xy 288.166526 -357.467506)
			(xy 288.091084 -357.454357) (xy 288.017053 -357.434764) (xy 287.980882 -357.422196) (xy 287.972445 -357.419545)
			(xy 287.954775 -357.419545) (xy 287.946338 -357.422196) (xy 287.91016 -357.434739) (xy 287.836127 -357.454312)
			(xy 287.760688 -357.46746) (xy 287.684398 -357.474084) (xy 287.64611 -357.47452) (xy 287.60782 -357.474114)
			(xy 287.531526 -357.467506) (xy 287.456084 -357.454357) (xy 287.382053 -357.434764) (xy 287.345882 -357.422196)
			(xy 287.337445 -357.419545) (xy 287.319775 -357.419545) (xy 287.311338 -357.422196) (xy 287.27516 -357.434739)
			(xy 287.201127 -357.454312) (xy 287.125688 -357.46746) (xy 287.049398 -357.474084) (xy 287.01111 -357.47452)
			(xy 286.97282 -357.474114) (xy 286.896526 -357.467506) (xy 286.821084 -357.454357) (xy 286.747053 -357.434764)
			(xy 286.710882 -357.422196) (xy 286.702445 -357.419545) (xy 286.684775 -357.419545) (xy 286.676338 -357.422196)
			(xy 286.64016 -357.434739) (xy 286.566127 -357.454312) (xy 286.490688 -357.46746) (xy 286.414398 -357.474084)
			(xy 286.37611 -357.47452) (xy 286.334994 -357.474092) (xy 286.253113 -357.466505) (xy 286.172281 -357.451395)
			(xy 286.093188 -357.428892) (xy 286.016509 -357.399186) (xy 285.942899 -357.362532) (xy 285.872984 -357.319241)
			(xy 285.807362 -357.269685) (xy 285.746593 -357.214284) (xy 285.691195 -357.153513) (xy 285.641641 -357.08789)
			(xy 285.598353 -357.017973) (xy 285.561701 -356.944361) (xy 285.531998 -356.867681) (xy 285.509497 -356.788588)
			(xy 285.49439 -356.707755) (xy 285.486807 -356.625874) (xy 285.486348 -356.584758) (xy 285.48677 -356.546469)
			(xy 285.493373 -356.470175) (xy 285.506518 -356.394732) (xy 285.526107 -356.320701) (xy 285.538672 -356.28453)
			(xy 285.541343 -356.276098) (xy 285.541329 -356.258423) (xy 285.538672 -356.249986) (xy 285.526141 -356.213804)
			(xy 285.506565 -356.139773) (xy 285.493414 -356.064334) (xy 285.486786 -355.988046) (xy 285.486348 -355.949758)
			(xy 285.486781 -355.910896) (xy 285.493587 -355.833469) (xy 285.507119 -355.756932) (xy 285.527272 -355.681865)
			(xy 285.540196 -355.645212) (xy 285.542998 -355.636321) (xy 285.542744 -355.617697) (xy 285.539688 -355.60889)
			(xy 285.524486 -355.569489) (xy 285.500735 -355.488437) (xy 285.484763 -355.405502) (xy 285.476712 -355.321427)
			(xy 285.476188 -355.279198) (xy 195.742079 -355.279198) (xy 195.735206 -355.292996) (xy 195.691912 -355.362897)
			(xy 195.642352 -355.428505) (xy 195.586949 -355.48926) (xy 195.526176 -355.544642) (xy 195.460551 -355.59418)
			(xy 195.390636 -355.637451) (xy 195.317025 -355.674085) (xy 195.240348 -355.703769) (xy 195.161258 -355.726251)
			(xy 195.080432 -355.741339) (xy 194.998557 -355.748903) (xy 194.957446 -355.749352) (xy 194.915842 -355.74888)
			(xy 194.832994 -355.741147) (xy 194.75123 -355.725716) (xy 194.671262 -355.702722) (xy 194.593789 -355.672366)
			(xy 194.519488 -355.634911) (xy 194.48399 -355.613208) (xy 194.474858 -355.608031) (xy 194.454138 -355.60482)
			(xy 194.433861 -355.61016) (xy 194.425316 -355.616256) (xy 194.391667 -355.642178) (xy 194.320293 -355.688236)
			(xy 194.244854 -355.727283) (xy 194.166037 -355.758962) (xy 194.08456 -355.782986) (xy 194.001164 -355.799135)
			(xy 193.916608 -355.807262) (xy 193.874136 -355.807772) (xy 193.873882 -355.807772) (xy 193.832775 -355.807305)
			(xy 193.750912 -355.799719) (xy 193.670098 -355.784614) (xy 193.591023 -355.762118) (xy 193.514359 -355.732423)
			(xy 193.440762 -355.695782) (xy 193.370859 -355.652509) (xy 193.305245 -355.602971) (xy 193.244482 -355.547592)
			(xy 193.189086 -355.486844) (xy 193.13953 -355.421244) (xy 193.096237 -355.351353) (xy 193.059577 -355.277766)
			(xy 193.029861 -355.201111) (xy 193.007343 -355.122041) (xy 192.992215 -355.041231) (xy 192.984607 -354.959371)
			(xy 192.98412 -354.918264) (xy 192.984683 -354.873494) (xy 192.993693 -354.784409) (xy 193.011598 -354.696678)
			(xy 193.038217 -354.611187) (xy 193.05524 -354.569776) (xy 193.058825 -354.560191) (xy 193.058812 -354.539743)
			(xy 193.05524 -354.530152) (xy 193.03824 -354.4888) (xy 193.011628 -354.403438) (xy 192.99372 -354.315836)
			(xy 192.984697 -354.226879) (xy 192.98412 -354.182172) (xy 192.98412 -354.181156) (xy 192.984374 -354.169726)
			(xy 192.957895 -354.163781) (xy 192.90566 -354.149038) (xy 192.87998 -354.140262) (xy 192.871783 -354.137748)
			(xy 192.854649 -354.137748) (xy 192.846452 -354.140262) (xy 192.811236 -354.152209) (xy 192.739226 -354.170796)
			(xy 192.665903 -354.183236) (xy 192.591792 -354.18944) (xy 192.554606 -354.189792) (xy 192.517422 -354.189422)
			(xy 192.443314 -354.1832) (xy 192.369994 -354.170758) (xy 192.297983 -354.152184) (xy 192.26276 -354.140262)
			(xy 192.254563 -354.137748) (xy 192.237429 -354.137748) (xy 192.229232 -354.140262) (xy 192.19413 -354.15215)
			(xy 192.122374 -354.1707) (xy 192.049311 -354.183146) (xy 191.97546 -354.189399) (xy 191.938402 -354.189792)
			(xy 191.937386 -354.189792) (xy 191.89546 -354.189345) (xy 191.811988 -354.181373) (xy 191.729651 -354.165503)
			(xy 191.649196 -354.141878) (xy 191.57135 -354.110712) (xy 191.49682 -354.072288) (xy 191.42628 -354.026953)
			(xy 191.360368 -353.975119) (xy 191.299682 -353.917254) (xy 191.244771 -353.853882) (xy 191.196132 -353.785578)
			(xy 191.154206 -353.71296) (xy 191.119373 -353.636685) (xy 191.091948 -353.557444) (xy 191.07218 -353.475956)
			(xy 191.060246 -353.392957) (xy 191.056256 -353.3092) (xy 187.519078 -353.3092) (xy 187.520094 -353.320137)
			(xy 187.52058 -353.361244) (xy 187.52002 -353.406014) (xy 187.511009 -353.495099) (xy 187.493104 -353.58283)
			(xy 187.466484 -353.668321) (xy 187.44946 -353.709732) (xy 187.44587 -353.719315) (xy 187.445886 -353.739765)
			(xy 187.44946 -353.749356) (xy 187.466484 -353.790767) (xy 187.493121 -353.876254) (xy 187.511029 -353.963986)
			(xy 187.520026 -354.053074) (xy 187.52058 -354.097844) (xy 187.52002 -354.142614) (xy 187.511009 -354.231699)
			(xy 187.493104 -354.31943) (xy 187.466484 -354.404921) (xy 187.44946 -354.446332) (xy 187.44587 -354.455915)
			(xy 187.445886 -354.476365) (xy 187.44946 -354.485956) (xy 187.466484 -354.527367) (xy 187.493121 -354.612854)
			(xy 187.511029 -354.700586) (xy 187.520026 -354.789674) (xy 187.52058 -354.834444) (xy 187.520189 -354.875556)
			(xy 187.512597 -354.957429) (xy 187.497482 -355.038252) (xy 187.474973 -355.117336) (xy 187.445261 -355.194004)
			(xy 187.408601 -355.267604) (xy 187.365306 -355.337506) (xy 187.315744 -355.403115) (xy 187.260339 -355.46387)
			(xy 187.199564 -355.519252) (xy 187.133937 -355.56879) (xy 187.064019 -355.61206) (xy 186.990406 -355.648693)
			(xy 186.913727 -355.678376) (xy 186.834635 -355.700857) (xy 186.753806 -355.715942) (xy 186.67193 -355.723505)
			(xy 186.630818 -355.723952) (xy 186.589214 -355.723494) (xy 186.506365 -355.715758) (xy 186.424601 -355.700325)
			(xy 186.344633 -355.677328) (xy 186.267161 -355.646969) (xy 186.192859 -355.609513) (xy 186.157362 -355.587808)
			(xy 186.148243 -355.582606) (xy 186.127514 -355.579404) (xy 186.107233 -355.584754) (xy 186.098688 -355.590856)
			(xy 186.065049 -355.616791) (xy 185.993673 -355.662848) (xy 185.918232 -355.701893) (xy 185.839413 -355.73357)
			(xy 185.757935 -355.757592) (xy 185.674537 -355.773739) (xy 185.589981 -355.781864) (xy 185.547508 -355.782372)
			(xy 185.547254 -355.782372) (xy 185.506147 -355.781931) (xy 185.424283 -355.774343) (xy 185.343469 -355.759235)
			(xy 185.264393 -355.736737) (xy 185.187729 -355.70704) (xy 185.114132 -355.670398) (xy 185.044229 -355.627122)
			(xy 184.978615 -355.577583) (xy 184.917852 -355.522202) (xy 184.862456 -355.461452) (xy 184.812901 -355.395851)
			(xy 184.769609 -355.325959) (xy 184.732948 -355.252371) (xy 184.703232 -355.175714) (xy 184.680715 -355.096644)
			(xy 184.665587 -355.015833) (xy 184.657979 -354.933971) (xy 184.657492 -354.892864) (xy 184.658057 -354.848094)
			(xy 184.667066 -354.759009) (xy 184.684971 -354.671278) (xy 184.711589 -354.585787) (xy 184.728612 -354.544376)
			(xy 184.732199 -354.534792) (xy 184.732185 -354.514343) (xy 184.728612 -354.504752) (xy 184.711616 -354.463398)
			(xy 184.685002 -354.378037) (xy 184.667093 -354.290435) (xy 184.658069 -354.201478) (xy 184.657492 -354.156772)
			(xy 184.657492 -354.155756) (xy 184.657746 -354.144326) (xy 184.631266 -354.138384) (xy 184.579032 -354.123639)
			(xy 184.553352 -354.114862) (xy 184.545155 -354.112348) (xy 184.528021 -354.112348) (xy 184.519824 -354.114862)
			(xy 184.484602 -354.126789) (xy 184.412594 -354.145381) (xy 184.339273 -354.157827) (xy 184.265163 -354.164037)
			(xy 184.227978 -354.164392) (xy 184.190794 -354.16403) (xy 184.116686 -354.157806) (xy 184.043366 -354.145361)
			(xy 183.971355 -354.126785) (xy 183.936132 -354.114862) (xy 183.927935 -354.112348) (xy 183.910801 -354.112348)
			(xy 183.902604 -354.114862) (xy 183.867505 -354.126757) (xy 183.795747 -354.145305) (xy 183.722684 -354.157749)
			(xy 183.648832 -354.164001) (xy 183.611774 -354.164392) (xy 183.610758 -354.164392) (xy 183.568833 -354.163944)
			(xy 183.485362 -354.155969) (xy 183.403028 -354.140097) (xy 183.322575 -354.11647) (xy 183.244732 -354.085304)
			(xy 183.170204 -354.046879) (xy 183.099666 -354.001544) (xy 183.033756 -353.949709) (xy 182.973072 -353.891844)
			(xy 182.918163 -353.828473) (xy 182.869527 -353.760169) (xy 182.827603 -353.687552) (xy 182.792771 -353.611278)
			(xy 182.765347 -353.532039) (xy 182.745579 -353.450553) (xy 182.733646 -353.367555) (xy 182.729656 -353.2838)
			(xy 78.346936 -353.2838) (xy 78.321217 -353.348042) (xy 78.282395 -353.423345) (xy 78.236592 -353.494617)
			(xy 78.184221 -353.561213) (xy 78.125756 -353.622528) (xy 78.061728 -353.678009) (xy 77.992716 -353.727152)
			(xy 77.919346 -353.769512) (xy 77.842281 -353.804707) (xy 77.762219 -353.832416) (xy 77.679886 -353.85239)
			(xy 77.596027 -353.864447) (xy 77.511402 -353.868479) (xy 77.426777 -353.864447) (xy 77.342918 -353.85239)
			(xy 77.260585 -353.832416) (xy 77.180523 -353.804707) (xy 77.103458 -353.769512) (xy 77.030088 -353.727152)
			(xy 76.961076 -353.678009) (xy 76.897048 -353.622528) (xy 76.838583 -353.561213) (xy 76.786212 -353.494617)
			(xy 76.740409 -353.423345) (xy 76.701587 -353.348042) (xy 76.670099 -353.26939) (xy 76.646231 -353.1881)
			(xy 76.630197 -353.10491) (xy 76.622144 -353.020573) (xy 76.62164 -352.978212) (xy 76.622159 -352.935266)
			(xy 76.630462 -352.849776) (xy 76.646954 -352.765482) (xy 76.671481 -352.683166) (xy 76.687172 -352.643186)
			(xy 76.690418 -352.63393) (xy 76.690431 -352.614336) (xy 76.687172 -352.605086) (xy 76.671458 -352.565114)
			(xy 76.646914 -352.4828) (xy 76.630427 -352.398503) (xy 76.622152 -352.313007) (xy 76.62164 -352.27006)
			(xy 76.62164 -352.269806) (xy 76.622244 -352.224161) (xy 76.631638 -352.133355) (xy 76.650266 -352.043985)
			(xy 76.66355 -352.000312) (xy 76.665996 -351.9913) (xy 76.664956 -351.972672) (xy 76.661518 -351.96399)
			(xy 76.642856 -351.920903) (xy 76.61365 -351.831658) (xy 76.594004 -351.739834) (xy 76.584137 -351.646451)
			(xy 76.58354 -351.5995) (xy 75.70064 -351.5995) (xy 75.701144 -351.637854) (xy 75.70053 -351.683499)
			(xy 75.691141 -351.774304) (xy 75.672516 -351.863674) (xy 75.659234 -351.907348) (xy 75.65681 -351.916364)
			(xy 75.657836 -351.934988) (xy 75.661266 -351.94367) (xy 75.679947 -351.986749) (xy 75.709149 -352.075997)
			(xy 75.728789 -352.167824) (xy 75.738651 -352.261208) (xy 75.739244 -352.30816) (xy 75.738798 -352.348493)
			(xy 75.731529 -352.428831) (xy 75.71702 -352.508181) (xy 75.69539 -352.585893) (xy 75.666817 -352.661328)
			(xy 75.649582 -352.697796) (xy 75.645066 -352.708391) (xy 75.645063 -352.731399) (xy 75.649582 -352.741992)
			(xy 75.666809 -352.778407) (xy 75.695346 -352.853748) (xy 75.716963 -352.931359) (xy 75.731481 -353.010605)
			(xy 75.738782 -353.090838) (xy 75.739244 -353.13112) (xy 75.739244 -353.131374) (xy 75.73874 -353.173735)
			(xy 75.730687 -353.258072) (xy 75.714653 -353.341262) (xy 75.690785 -353.422552) (xy 75.659297 -353.501204)
			(xy 75.620475 -353.576507) (xy 75.574672 -353.647779) (xy 75.522301 -353.714375) (xy 75.463836 -353.77569)
			(xy 75.399808 -353.831171) (xy 75.330796 -353.880314) (xy 75.257426 -353.922674) (xy 75.180361 -353.957869)
			(xy 75.100299 -353.985578) (xy 75.017966 -354.005552) (xy 74.934107 -354.017609) (xy 74.849482 -354.021641)
			(xy 74.764857 -354.017609) (xy 74.680998 -354.005552) (xy 74.598665 -353.985578) (xy 74.518603 -353.957869)
			(xy 74.441538 -353.922674) (xy 74.368168 -353.880314) (xy 74.299156 -353.831171) (xy 74.235128 -353.77569)
			(xy 74.176663 -353.714375) (xy 74.124292 -353.647779) (xy 74.078489 -353.576507) (xy 74.039667 -353.501204)
			(xy 74.008179 -353.422552) (xy 73.984311 -353.341262) (xy 73.968277 -353.258072) (xy 73.960224 -353.173735)
			(xy 73.95972 -353.131374) (xy 73.960164 -353.091034) (xy 73.96747 -353.010685) (xy 73.982028 -352.931329)
			(xy 74.003719 -352.85362) (xy 74.032363 -352.778196) (xy 74.049636 -352.741738) (xy 74.054225 -352.731091)
			(xy 74.054231 -352.707932) (xy 74.049636 -352.697288) (xy 74.032445 -352.660861) (xy 74.003936 -352.58552)
			(xy 73.98236 -352.50791) (xy 73.967893 -352.428665) (xy 73.960655 -352.348437) (xy 73.960228 -352.30816)
			(xy 73.960797 -352.262521) (xy 73.970094 -352.171718) (xy 73.988639 -352.082344) (xy 74.001884 -352.038666)
			(xy 74.004352 -352.029659) (xy 74.003297 -352.011026) (xy 73.999852 -352.002344) (xy 73.981136 -351.959272)
			(xy 73.95186 -351.870033) (xy 73.932154 -351.778206) (xy 73.922237 -351.684813) (xy 73.92162 -351.637854)
			(xy 2.509012 -351.637854) (xy 2.509012 -358.071674) (xy 14.438884 -358.071674) (xy 14.438884 -357.208074)
			(xy 14.43937 -357.180805) (xy 14.447132 -357.126821) (xy 14.462497 -357.074491) (xy 14.485154 -357.024881)
			(xy 14.51464 -356.979) (xy 14.550355 -356.937783) (xy 14.591572 -356.902068) (xy 14.637453 -356.872582)
			(xy 14.687063 -356.849925) (xy 14.739393 -356.83456) (xy 14.793377 -356.826798) (xy 14.847915 -356.826798)
			(xy 14.901899 -356.83456) (xy 14.954229 -356.849925) (xy 15.003839 -356.872582) (xy 15.04972 -356.902068)
			(xy 15.090937 -356.937783) (xy 15.126652 -356.979) (xy 15.156138 -357.024881) (xy 15.178795 -357.074491)
			(xy 15.19416 -357.126821) (xy 15.201922 -357.180805) (xy 15.202408 -357.208074) (xy 15.202408 -358.071674)
			(xy 15.201922 -358.098943) (xy 15.19416 -358.152927) (xy 15.178795 -358.205257) (xy 15.156138 -358.254867)
			(xy 15.126652 -358.300748) (xy 15.090937 -358.341965) (xy 15.04972 -358.37768) (xy 15.003839 -358.407166)
			(xy 14.954229 -358.429823) (xy 14.901899 -358.445188) (xy 14.847915 -358.45295) (xy 14.793377 -358.45295)
			(xy 14.739393 -358.445188) (xy 14.687063 -358.429823) (xy 14.637453 -358.407166) (xy 14.591572 -358.37768)
			(xy 14.550355 -358.341965) (xy 14.51464 -358.300748) (xy 14.485154 -358.254867) (xy 14.462497 -358.205257)
			(xy 14.447132 -358.152927) (xy 14.43937 -358.098943) (xy 14.438884 -358.071674) (xy 2.509012 -358.071674)
			(xy 2.509012 -358.549194) (xy 40.47998 -358.549194) (xy 40.47998 -358.548686) (xy 40.480371 -358.510677)
			(xy 40.486871 -358.434938) (xy 40.499812 -358.36003) (xy 40.519101 -358.286501) (xy 40.544596 -358.214886)
			(xy 40.55999 -358.180132) (xy 40.563435 -358.171803) (xy 40.56487 -358.153848) (xy 40.562784 -358.14508)
			(xy 40.551663 -358.104882) (xy 40.536092 -358.022938) (xy 40.528245 -357.939897) (xy 40.527732 -357.898192)
			(xy 40.528135 -357.859902) (xy 40.534744 -357.783608) (xy 40.547894 -357.708165) (xy 40.567488 -357.634135)
			(xy 40.580056 -357.597964) (xy 40.58271 -357.589528) (xy 40.582708 -357.571857) (xy 40.580056 -357.56342)
			(xy 40.567506 -357.527245) (xy 40.547935 -357.453211) (xy 40.53479 -357.37777) (xy 40.528167 -357.30148)
			(xy 40.527732 -357.263192) (xy 40.528236 -357.220831) (xy 40.536289 -357.136494) (xy 40.552323 -357.053304)
			(xy 40.576191 -356.972014) (xy 40.607679 -356.893362) (xy 40.646501 -356.818059) (xy 40.692304 -356.746787)
			(xy 40.744675 -356.680191) (xy 40.80314 -356.618876) (xy 40.867168 -356.563395) (xy 40.93618 -356.514252)
			(xy 41.00955 -356.471892) (xy 41.086615 -356.436697) (xy 41.166677 -356.408988) (xy 41.24901 -356.389014)
			(xy 41.332869 -356.376957) (xy 41.417494 -356.372926) (xy 41.502119 -356.376957) (xy 41.585978 -356.389014)
			(xy 41.668311 -356.408988) (xy 41.748373 -356.436697) (xy 41.825438 -356.471892) (xy 41.898808 -356.514252)
			(xy 41.96782 -356.563395) (xy 42.031848 -356.618876) (xy 42.090313 -356.680191) (xy 42.142684 -356.746787)
			(xy 42.188487 -356.818059) (xy 42.227309 -356.893362) (xy 42.258797 -356.972014) (xy 42.282665 -357.053304)
			(xy 42.298699 -357.136494) (xy 42.306752 -357.220831) (xy 42.307256 -357.263192) (xy 42.306849 -357.301482)
			(xy 42.300241 -357.377776) (xy 42.287093 -357.453218) (xy 42.2675 -357.527249) (xy 42.254932 -357.56342)
			(xy 42.252286 -357.571858) (xy 42.252283 -357.589527) (xy 42.254932 -357.597964) (xy 42.267477 -357.634141)
			(xy 42.28705 -357.708174) (xy 42.300196 -357.783614) (xy 42.30682 -357.859904) (xy 42.307256 -357.898192)
			(xy 42.307256 -357.8987) (xy 42.306856 -357.936708) (xy 42.300359 -358.012447) (xy 42.287419 -358.087355)
			(xy 42.268132 -358.160885) (xy 42.242639 -358.2325) (xy 42.227246 -358.267254) (xy 42.223809 -358.275586)
			(xy 42.222368 -358.293538) (xy 42.224452 -358.302306) (xy 42.23557 -358.342505) (xy 42.251142 -358.424449)
			(xy 42.258991 -358.507489) (xy 42.259032 -358.51084) (xy 43.046396 -358.51084) (xy 43.046759 -358.47278)
			(xy 43.053225 -358.396935) (xy 43.066156 -358.321921) (xy 43.085458 -358.248289) (xy 43.110988 -358.176577)
			(xy 43.126406 -358.141778) (xy 43.129746 -358.133421) (xy 43.131033 -358.115482) (xy 43.128946 -358.106726)
			(xy 43.117873 -358.066521) (xy 43.102375 -357.984574) (xy 43.094614 -357.901538) (xy 43.094148 -357.859838)
			(xy 43.094524 -357.821522) (xy 43.101053 -357.745169) (xy 43.114136 -357.669662) (xy 43.133673 -357.595562)
			(xy 43.146218 -357.559356) (xy 43.148787 -357.551035) (xy 43.148799 -357.533636) (xy 43.146218 -357.52532)
			(xy 43.13374 -357.489193) (xy 43.114246 -357.415282) (xy 43.101158 -357.339973) (xy 43.094573 -357.263819)
			(xy 43.094148 -357.2256) (xy 43.094148 -357.224838) (xy 43.094652 -357.18249) (xy 43.102703 -357.098176)
			(xy 43.118732 -357.01501) (xy 43.142593 -356.933743) (xy 43.174072 -356.855113) (xy 43.212883 -356.779832)
			(xy 43.258673 -356.70858) (xy 43.311029 -356.642004) (xy 43.369477 -356.580706) (xy 43.433487 -356.525241)
			(xy 43.502479 -356.476112) (xy 43.575829 -356.433763) (xy 43.652872 -356.398579) (xy 43.732911 -356.370877)
			(xy 43.81522 -356.350909) (xy 43.899055 -356.338856) (xy 43.983656 -356.334826) (xy 44.068257 -356.338856)
			(xy 44.152092 -356.350909) (xy 44.234401 -356.370877) (xy 44.31444 -356.398579) (xy 44.391483 -356.433763)
			(xy 44.464833 -356.476112) (xy 44.533825 -356.525241) (xy 44.597835 -356.580706) (xy 44.656283 -356.642004)
			(xy 44.708639 -356.70858) (xy 44.754429 -356.779832) (xy 44.79324 -356.855113) (xy 44.824719 -356.933743)
			(xy 44.84858 -357.01501) (xy 44.864609 -357.098176) (xy 44.87266 -357.18249) (xy 44.873164 -357.224838)
			(xy 44.873164 -357.2256) (xy 44.87277 -357.263821) (xy 44.866201 -357.339979) (xy 44.853113 -357.415292)
			(xy 44.833602 -357.489202) (xy 44.821094 -357.52532) (xy 44.818487 -357.533631) (xy 44.818499 -357.55104)
			(xy 44.821094 -357.559356) (xy 44.833623 -357.595567) (xy 44.853143 -357.669669) (xy 44.866225 -357.745173)
			(xy 44.872771 -357.821523) (xy 44.873164 -357.859838) (xy 44.872788 -357.897898) (xy 44.866324 -357.973742)
			(xy 44.853395 -358.048756) (xy 44.837736 -358.108504) (xy 46.991016 -358.108504) (xy 46.991016 -358.107996)
			(xy 46.991417 -358.069988) (xy 46.997915 -357.994249) (xy 47.010854 -357.919341) (xy 47.030141 -357.845811)
			(xy 47.055634 -357.774197) (xy 47.071026 -357.739442) (xy 47.074466 -357.731111) (xy 47.075906 -357.713158)
			(xy 47.07382 -357.70439) (xy 47.0627 -357.664192) (xy 47.047129 -357.582247) (xy 47.039281 -357.499207)
			(xy 47.038768 -357.457502) (xy 47.039173 -357.419212) (xy 47.045781 -357.342918) (xy 47.05893 -357.267476)
			(xy 47.078524 -357.193445) (xy 47.091092 -357.157274) (xy 47.09374 -357.148837) (xy 47.093741 -357.131167)
			(xy 47.091092 -357.12273) (xy 47.078546 -357.086553) (xy 47.058974 -357.01252) (xy 47.045827 -356.93708)
			(xy 47.039204 -356.86079) (xy 47.038768 -356.822502) (xy 47.0392 -356.781386) (xy 47.046788 -356.699506)
			(xy 47.061898 -356.618674) (xy 47.084402 -356.539582) (xy 47.114108 -356.462904) (xy 47.150762 -356.389293)
			(xy 47.194052 -356.319379) (xy 47.243609 -356.253758) (xy 47.299008 -356.192989) (xy 47.359779 -356.137591)
			(xy 47.425402 -356.088036) (xy 47.495318 -356.044749) (xy 47.568929 -356.008097) (xy 47.645609 -355.978393)
			(xy 47.724702 -355.955891) (xy 47.805533 -355.940784) (xy 47.887414 -355.933199) (xy 47.92853 -355.93274)
			(xy 47.969637 -355.933252) (xy 48.051499 -355.940877) (xy 48.132307 -355.956023) (xy 48.211373 -355.97856)
			(xy 48.288023 -356.008296) (xy 48.325024 -356.026212) (xy 48.335846 -356.030917) (xy 48.359414 -356.030917)
			(xy 48.370236 -356.026212) (xy 48.407247 -356.008316) (xy 48.483894 -355.978575) (xy 48.562957 -355.956031)
			(xy 48.643763 -355.940876) (xy 48.725623 -355.93324) (xy 48.76673 -355.93274) (xy 48.80502 -355.933136)
			(xy 48.881314 -355.939747) (xy 48.956757 -355.952899) (xy 49.030787 -355.972495) (xy 49.066958 -355.985064)
			(xy 49.075395 -355.987715) (xy 49.093065 -355.987715) (xy 49.101502 -355.985064) (xy 49.137675 -355.972508)
			(xy 49.21171 -355.952938) (xy 49.287151 -355.939795) (xy 49.363442 -355.933174) (xy 49.40173 -355.93274)
			(xy 49.44002 -355.933136) (xy 49.516314 -355.939747) (xy 49.591757 -355.952899) (xy 49.665787 -355.972495)
			(xy 49.701958 -355.985064) (xy 49.710395 -355.987715) (xy 49.728065 -355.987715) (xy 49.736502 -355.985064)
			(xy 49.772675 -355.972508) (xy 49.84671 -355.952938) (xy 49.922151 -355.939795) (xy 49.998442 -355.933174)
			(xy 50.03673 -355.93274) (xy 50.07502 -355.933136) (xy 50.151314 -355.939747) (xy 50.226757 -355.952899)
			(xy 50.300787 -355.972495) (xy 50.336958 -355.985064) (xy 50.345395 -355.987715) (xy 50.363065 -355.987715)
			(xy 50.371502 -355.985064) (xy 50.407675 -355.972508) (xy 50.48171 -355.952938) (xy 50.557151 -355.939795)
			(xy 50.633442 -355.933174) (xy 50.67173 -355.93274) (xy 50.712845 -355.933184) (xy 50.794723 -355.940774)
			(xy 50.875552 -355.955886) (xy 50.954642 -355.978392) (xy 51.031318 -356.008098) (xy 51.104926 -356.044753)
			(xy 51.174838 -356.088043) (xy 51.240458 -356.137599) (xy 51.301225 -356.192997) (xy 51.356622 -356.253767)
			(xy 51.406175 -356.319388) (xy 51.449463 -356.389302) (xy 51.486115 -356.462911) (xy 51.515819 -356.539588)
			(xy 51.538321 -356.618679) (xy 51.55343 -356.699508) (xy 51.561017 -356.781387) (xy 51.561492 -356.822502)
			(xy 51.561091 -356.860792) (xy 51.554482 -356.937086) (xy 51.541332 -357.012529) (xy 51.521737 -357.086559)
			(xy 51.509168 -357.12273) (xy 51.506515 -357.131166) (xy 51.506516 -357.148837) (xy 51.509168 -357.157274)
			(xy 51.521713 -357.193451) (xy 51.541286 -357.267484) (xy 51.554433 -357.342924) (xy 51.561057 -357.419214)
			(xy 51.561492 -357.457502) (xy 51.561492 -357.45801) (xy 51.561093 -357.496018) (xy 51.554594 -357.571757)
			(xy 51.541655 -357.646665) (xy 51.522368 -357.720195) (xy 51.496874 -357.791809) (xy 51.481482 -357.826564)
			(xy 51.478039 -357.834894) (xy 51.476603 -357.852848) (xy 51.478688 -357.861616) (xy 51.48981 -357.901814)
			(xy 51.50538 -357.983758) (xy 51.513227 -358.066799) (xy 51.51374 -358.108504) (xy 51.513251 -358.149614)
			(xy 51.505664 -358.231482) (xy 51.490553 -358.312301) (xy 51.468049 -358.391381) (xy 51.438343 -358.468047)
			(xy 51.401689 -358.541644) (xy 51.3584 -358.611544) (xy 51.308844 -358.677152) (xy 51.253446 -358.737906)
			(xy 51.192678 -358.793289) (xy 51.127058 -358.842827) (xy 51.057146 -358.886099) (xy 50.98354 -358.922734)
			(xy 50.906867 -358.952421) (xy 50.827781 -358.974905) (xy 50.746958 -358.989995) (xy 50.665088 -358.997562)
			(xy 50.623978 -358.998012) (xy 50.585661 -358.99765) (xy 50.509308 -358.991116) (xy 50.433801 -358.97803)
			(xy 50.359702 -358.958488) (xy 50.323496 -358.945942) (xy 50.31518 -358.943356) (xy 50.297776 -358.943356)
			(xy 50.28946 -358.945942) (xy 50.253248 -358.958468) (xy 50.179147 -358.977989) (xy 50.103642 -358.991071)
			(xy 50.027293 -358.997619) (xy 49.988978 -358.998012) (xy 49.950661 -358.99765) (xy 49.874308 -358.991116)
			(xy 49.798801 -358.97803) (xy 49.724702 -358.958488) (xy 49.688496 -358.945942) (xy 49.68018 -358.943356)
			(xy 49.662776 -358.943356) (xy 49.65446 -358.945942) (xy 49.618248 -358.958468) (xy 49.544147 -358.977989)
			(xy 49.468642 -358.991071) (xy 49.392293 -358.997619) (xy 49.353978 -358.998012) (xy 49.315661 -358.99765)
			(xy 49.239308 -358.991116) (xy 49.163801 -358.97803) (xy 49.089702 -358.958488) (xy 49.053496 -358.945942)
			(xy 49.04518 -358.943356) (xy 49.027776 -358.943356) (xy 49.01946 -358.945942) (xy 48.983339 -358.95844)
			(xy 48.909426 -358.977928) (xy 48.834115 -358.99101) (xy 48.757959 -358.99759) (xy 48.71974 -358.998012)
			(xy 48.718978 -358.998012) (xy 48.677876 -358.99753) (xy 48.596022 -358.989953) (xy 48.515216 -358.974857)
			(xy 48.436148 -358.95237) (xy 48.359491 -358.922685) (xy 48.322484 -358.904794) (xy 48.311662 -358.900089)
			(xy 48.288094 -358.900089) (xy 48.277272 -358.904794) (xy 48.240271 -358.922698) (xy 48.163612 -358.952379)
			(xy 48.084542 -358.974864) (xy 48.003735 -358.98996) (xy 47.92188 -358.997539) (xy 47.880778 -358.998012)
			(xy 47.839669 -358.997608) (xy 47.757803 -358.990022) (xy 47.676986 -358.974915) (xy 47.597907 -358.952416)
			(xy 47.52124 -358.922719) (xy 47.447641 -358.886075) (xy 47.377735 -358.842798) (xy 47.312121 -358.793256)
			(xy 47.251356 -358.737873) (xy 47.19596 -358.677119) (xy 47.146405 -358.611515) (xy 47.103114 -358.541618)
			(xy 47.066455 -358.468026) (xy 47.036742 -358.391366) (xy 47.014227 -358.312292) (xy 46.999104 -358.231477)
			(xy 46.9915 -358.149612) (xy 46.991016 -358.108504) (xy 44.837736 -358.108504) (xy 44.834097 -358.122388)
			(xy 44.808571 -358.1941) (xy 44.793154 -358.2289) (xy 44.789778 -358.237249) (xy 44.788481 -358.255202)
			(xy 44.790614 -358.263952) (xy 44.801704 -358.304153) (xy 44.817195 -358.386101) (xy 44.82495 -358.46914)
			(xy 44.825412 -358.51084) (xy 44.824852 -358.556303) (xy 44.815599 -358.646758) (xy 44.797171 -358.735798)
			(xy 44.78401 -358.779318) (xy 44.78146 -358.788893) (xy 44.783017 -358.808626) (xy 44.787058 -358.817672)
			(xy 44.805431 -358.855048) (xy 44.835897 -358.932566) (xy 44.858991 -359.012591) (xy 44.87451 -359.094423)
			(xy 44.882318 -359.177347) (xy 44.882816 -359.218992) (xy 44.882816 -359.219246) (xy 44.882312 -359.261594)
			(xy 44.874261 -359.345908) (xy 44.858232 -359.429074) (xy 44.834371 -359.510341) (xy 44.802892 -359.588971)
			(xy 44.764081 -359.664252) (xy 44.718291 -359.735504) (xy 44.665935 -359.80208) (xy 44.607487 -359.863378)
			(xy 44.543477 -359.918843) (xy 44.474485 -359.967972) (xy 44.401135 -360.010321) (xy 44.324092 -360.045505)
			(xy 44.244053 -360.073207) (xy 44.161744 -360.093175) (xy 44.077909 -360.105228) (xy 43.993308 -360.109259)
			(xy 43.908707 -360.105228) (xy 43.824872 -360.093175) (xy 43.742563 -360.073207) (xy 43.662524 -360.045505)
			(xy 43.585481 -360.010321) (xy 43.512131 -359.967972) (xy 43.443139 -359.918843) (xy 43.379129 -359.863378)
			(xy 43.320681 -359.80208) (xy 43.268325 -359.735504) (xy 43.222535 -359.664252) (xy 43.183724 -359.588971)
			(xy 43.152245 -359.510341) (xy 43.128384 -359.429074) (xy 43.112355 -359.345908) (xy 43.104304 -359.261594)
			(xy 43.1038 -359.219246) (xy 43.1038 -359.218738) (xy 43.104382 -359.17336) (xy 43.113653 -359.083077)
			(xy 43.132063 -358.994207) (xy 43.145202 -358.950768) (xy 43.147759 -358.941194) (xy 43.146197 -358.921461)
			(xy 43.142154 -358.912414) (xy 43.123767 -358.875016) (xy 43.093286 -358.797449) (xy 43.070189 -358.717372)
			(xy 43.054676 -358.635487) (xy 43.046883 -358.552511) (xy 43.046396 -358.51084) (xy 42.259032 -358.51084)
			(xy 42.259504 -358.549194) (xy 42.258889 -358.594663) (xy 42.249552 -358.685121) (xy 42.231047 -358.774157)
			(xy 42.217848 -358.817672) (xy 42.215273 -358.827242) (xy 42.216849 -358.846979) (xy 42.220896 -358.856026)
			(xy 42.239309 -358.893418) (xy 42.269845 -358.970977) (xy 42.292996 -359.051051) (xy 42.308559 -359.132939)
			(xy 42.316398 -359.215923) (xy 42.316908 -359.2576) (xy 42.316404 -359.299961) (xy 42.308351 -359.384298)
			(xy 42.292317 -359.467488) (xy 42.268449 -359.548778) (xy 42.236961 -359.62743) (xy 42.198139 -359.702733)
			(xy 42.152336 -359.774005) (xy 42.099965 -359.840601) (xy 42.0415 -359.901916) (xy 41.977472 -359.957397)
			(xy 41.90846 -360.00654) (xy 41.83509 -360.0489) (xy 41.758025 -360.084095) (xy 41.677963 -360.111804)
			(xy 41.59563 -360.131778) (xy 41.511771 -360.143835) (xy 41.427146 -360.147867) (xy 41.342521 -360.143835)
			(xy 41.258662 -360.131778) (xy 41.176329 -360.111804) (xy 41.096267 -360.084095) (xy 41.019202 -360.0489)
			(xy 40.945832 -360.00654) (xy 40.87682 -359.957397) (xy 40.812792 -359.901916) (xy 40.754327 -359.840601)
			(xy 40.701956 -359.774005) (xy 40.656153 -359.702733) (xy 40.617331 -359.62743) (xy 40.585843 -359.548778)
			(xy 40.561975 -359.467488) (xy 40.545941 -359.384298) (xy 40.537888 -359.299961) (xy 40.537384 -359.2576)
			(xy 40.537998 -359.212131) (xy 40.547335 -359.121673) (xy 40.565841 -359.032637) (xy 40.57904 -358.989122)
			(xy 40.581619 -358.979553) (xy 40.580041 -358.959815) (xy 40.575992 -358.950768) (xy 40.557613 -358.91336)
			(xy 40.527071 -358.835806) (xy 40.503913 -358.755736) (xy 40.488342 -358.673851) (xy 40.480494 -358.59087)
			(xy 40.47998 -358.549194) (xy 2.509012 -358.549194) (xy 2.509012 -361.825848) (xy 5.986007 -361.825848)
			(xy 5.986007 -361.696708) (xy 5.993957 -361.567813) (xy 6.009827 -361.439653) (xy 6.033556 -361.312712)
			(xy 6.065055 -361.187473) (xy 6.104204 -361.06441) (xy 6.150855 -360.943991) (xy 6.20483 -360.826672)
			(xy 6.265925 -360.712898) (xy 6.333908 -360.603101) (xy 6.408522 -360.497698) (xy 6.489483 -360.397088)
			(xy 6.576483 -360.301653) (xy 6.669194 -360.211754) (xy 6.767264 -360.127733) (xy 6.870319 -360.049909)
			(xy 6.97797 -359.978577) (xy 7.089809 -359.914007) (xy 7.20541 -359.856445) (xy 7.324335 -359.806108)
			(xy 7.446134 -359.763188) (xy 7.570344 -359.727847) (xy 7.696493 -359.70022) (xy 7.824105 -359.680411)
			(xy 7.952694 -359.668495) (xy 8.081772 -359.664519) (xy 8.21085 -359.668495) (xy 8.339439 -359.680411)
			(xy 8.467051 -359.70022) (xy 8.5932 -359.727847) (xy 8.71741 -359.763188) (xy 8.839209 -359.806108)
			(xy 8.958134 -359.856445) (xy 9.073735 -359.914007) (xy 9.185574 -359.978577) (xy 9.293225 -360.049909)
			(xy 9.39628 -360.127733) (xy 9.49435 -360.211754) (xy 9.587061 -360.301653) (xy 9.674061 -360.397088)
			(xy 9.689764 -360.416602) (xy 12.542012 -360.416602) (xy 12.542012 -359.553002) (xy 12.542498 -359.525751)
			(xy 12.550254 -359.471803) (xy 12.565609 -359.419508) (xy 12.588251 -359.369931) (xy 12.617717 -359.324081)
			(xy 12.653408 -359.28289) (xy 12.694599 -359.247199) (xy 12.740449 -359.217733) (xy 12.790026 -359.195091)
			(xy 12.842321 -359.179736) (xy 12.896269 -359.17198) (xy 12.950771 -359.17198) (xy 13.004719 -359.179736)
			(xy 13.057014 -359.195091) (xy 13.106591 -359.217733) (xy 13.152441 -359.247199) (xy 13.193632 -359.28289)
			(xy 13.229323 -359.324081) (xy 13.258789 -359.369931) (xy 13.281431 -359.419508) (xy 13.296786 -359.471803)
			(xy 13.304542 -359.525751) (xy 13.305028 -359.553002) (xy 13.305028 -360.416602) (xy 13.304542 -360.443853)
			(xy 13.296786 -360.497801) (xy 13.281431 -360.550096) (xy 13.258789 -360.599673) (xy 13.229323 -360.645523)
			(xy 13.193632 -360.686714) (xy 13.152441 -360.722405) (xy 13.106591 -360.751871) (xy 13.057014 -360.774513)
			(xy 13.004719 -360.789868) (xy 12.950771 -360.797624) (xy 12.896269 -360.797624) (xy 12.842321 -360.789868)
			(xy 12.790026 -360.774513) (xy 12.740449 -360.751871) (xy 12.694599 -360.722405) (xy 12.653408 -360.686714)
			(xy 12.617717 -360.645523) (xy 12.588251 -360.599673) (xy 12.565609 -360.550096) (xy 12.550254 -360.497801)
			(xy 12.542498 -360.443853) (xy 12.542012 -360.416602) (xy 9.689764 -360.416602) (xy 9.755022 -360.497698)
			(xy 9.829636 -360.603101) (xy 9.897619 -360.712898) (xy 9.958714 -360.826672) (xy 10.012689 -360.943991)
			(xy 10.05934 -361.06441) (xy 10.098489 -361.187473) (xy 10.129988 -361.312712) (xy 10.153717 -361.439653)
			(xy 10.169587 -361.567813) (xy 10.177537 -361.696708) (xy 10.178034 -361.761278) (xy 10.177537 -361.825848)
			(xy 10.169587 -361.954743) (xy 10.153717 -362.082903) (xy 10.129988 -362.209844) (xy 10.098489 -362.335083)
			(xy 10.079022 -362.396278) (xy 165.733984 -362.396278) (xy 165.733984 -361.532678) (xy 165.73447 -361.505409)
			(xy 165.742232 -361.451425) (xy 165.757597 -361.399095) (xy 165.780254 -361.349485) (xy 165.80974 -361.303604)
			(xy 165.845455 -361.262387) (xy 165.886672 -361.226672) (xy 165.932553 -361.197186) (xy 165.982163 -361.174529)
			(xy 166.034493 -361.159164) (xy 166.088477 -361.151402) (xy 166.143015 -361.151402) (xy 166.196999 -361.159164)
			(xy 166.249329 -361.174529) (xy 166.298939 -361.197186) (xy 166.34482 -361.226672) (xy 166.386037 -361.262387)
			(xy 166.421752 -361.303604) (xy 166.451238 -361.349485) (xy 166.473895 -361.399095) (xy 166.48926 -361.451425)
			(xy 166.497022 -361.505409) (xy 166.497508 -361.532678) (xy 166.497508 -362.234988) (xy 185.144664 -362.234988)
			(xy 185.144664 -362.23448) (xy 185.145268 -362.188148) (xy 185.154941 -362.09599) (xy 185.174137 -362.005336)
			(xy 185.202649 -361.917167) (xy 185.220864 -361.874562) (xy 185.224678 -361.864622) (xy 185.224673 -361.843356)
			(xy 185.220864 -361.833414) (xy 185.202614 -361.790754) (xy 185.174071 -361.702461) (xy 185.15488 -361.611675)
			(xy 185.145248 -361.519384) (xy 185.144664 -361.472988) (xy 185.145245 -361.426592) (xy 185.154891 -361.334304)
			(xy 185.174088 -361.24352) (xy 185.202626 -361.155227) (xy 185.220864 -361.112562) (xy 185.224678 -361.102622)
			(xy 185.224673 -361.081356) (xy 185.220864 -361.071414) (xy 185.202636 -361.028813) (xy 185.17412 -360.940645)
			(xy 185.154929 -360.849989) (xy 185.145271 -360.757828) (xy 185.144664 -360.711496) (xy 185.144664 -360.710988)
			(xy 185.145155 -360.669886) (xy 185.152741 -360.588033) (xy 185.167846 -360.507229) (xy 185.190343 -360.428164)
			(xy 185.220039 -360.351511) (xy 185.25668 -360.277925) (xy 185.299955 -360.208034) (xy 185.349493 -360.142434)
			(xy 185.404873 -360.081684) (xy 185.465622 -360.026303) (xy 185.531221 -359.976764) (xy 185.601111 -359.933488)
			(xy 185.674696 -359.896845) (xy 185.751348 -359.867148) (xy 185.830414 -359.84465) (xy 185.911217 -359.829543)
			(xy 185.99307 -359.821956) (xy 186.034172 -359.82148) (xy 186.03468 -359.82148) (xy 186.081011 -359.822097)
			(xy 186.173169 -359.831765) (xy 186.263823 -359.850958) (xy 186.351992 -359.879466) (xy 186.394598 -359.89768)
			(xy 186.40454 -359.901486) (xy 186.425804 -359.901486) (xy 186.435746 -359.89768) (xy 186.478352 -359.879466)
			(xy 186.566519 -359.850947) (xy 186.657173 -359.831752) (xy 186.749332 -359.822089) (xy 186.795664 -359.82148)
			(xy 186.796172 -359.82148) (xy 186.837274 -359.821979) (xy 186.919129 -359.829561) (xy 186.999934 -359.844664)
			(xy 187.079001 -359.867158) (xy 187.155656 -359.896852) (xy 187.229243 -359.933492) (xy 187.299136 -359.976765)
			(xy 187.364738 -360.026303) (xy 187.425489 -360.081682) (xy 187.480872 -360.142431) (xy 187.530412 -360.208031)
			(xy 187.573689 -360.277922) (xy 187.610332 -360.351508) (xy 187.640029 -360.428161) (xy 187.662527 -360.507227)
			(xy 187.677633 -360.588032) (xy 187.685219 -360.669886) (xy 187.68568 -360.710988) (xy 187.68568 -360.711496)
			(xy 187.685072 -360.757828) (xy 187.684417 -360.764074) (xy 211.161635 -360.764074) (xy 211.16566 -360.621882)
			(xy 211.177723 -360.480146) (xy 211.197786 -360.33932) (xy 211.225784 -360.199854) (xy 211.261628 -360.062195)
			(xy 211.305202 -359.926785) (xy 211.356367 -359.794057) (xy 211.41496 -359.664436) (xy 211.480791 -359.538338)
			(xy 211.553652 -359.416166) (xy 211.633307 -359.298312) (xy 211.719503 -359.185153) (xy 211.811962 -359.077051)
			(xy 211.91039 -358.974354) (xy 212.014469 -358.87739) (xy 212.123868 -358.78647) (xy 212.238236 -358.701884)
			(xy 212.357205 -358.623904) (xy 212.480396 -358.55278) (xy 212.607413 -358.488739) (xy 212.73785 -358.431987)
			(xy 212.871289 -358.382705) (xy 213.007302 -358.341051) (xy 213.145454 -358.307159) (xy 213.285303 -358.281138)
			(xy 213.426399 -358.26307) (xy 213.568291 -358.253013) (xy 213.710526 -358.251) (xy 213.852646 -358.257037)
			(xy 213.994197 -358.271105) (xy 214.134726 -358.293159) (xy 214.273781 -358.323128) (xy 214.410919 -358.360916)
			(xy 214.545699 -358.406402) (xy 214.67769 -358.45944) (xy 214.806469 -358.519861) (xy 214.931623 -358.58747)
			(xy 215.052751 -358.662052) (xy 215.169467 -358.743368) (xy 215.281395 -358.831156) (xy 215.388177 -358.925136)
			(xy 215.489471 -359.025006) (xy 215.584952 -359.130448) (xy 215.674316 -359.241122) (xy 215.757274 -359.356675)
			(xy 215.833563 -359.476736) (xy 215.902937 -359.600921) (xy 215.965174 -359.728832) (xy 216.020075 -359.860059)
			(xy 216.067463 -359.994182) (xy 216.107188 -360.130771) (xy 216.139121 -360.269389) (xy 216.163162 -360.409591)
			(xy 216.179231 -360.550929) (xy 216.187279 -360.69295) (xy 216.187782 -360.764074) (xy 255.611635 -360.764074)
			(xy 255.61566 -360.621882) (xy 255.627723 -360.480146) (xy 255.647786 -360.33932) (xy 255.675784 -360.199854)
			(xy 255.711628 -360.062195) (xy 255.755202 -359.926785) (xy 255.806367 -359.794057) (xy 255.86496 -359.664436)
			(xy 255.930791 -359.538338) (xy 256.003652 -359.416166) (xy 256.083307 -359.298312) (xy 256.169503 -359.185153)
			(xy 256.261962 -359.077051) (xy 256.36039 -358.974354) (xy 256.464469 -358.87739) (xy 256.573868 -358.78647)
			(xy 256.688236 -358.701884) (xy 256.807205 -358.623904) (xy 256.930396 -358.55278) (xy 257.057413 -358.488739)
			(xy 257.18785 -358.431987) (xy 257.321289 -358.382705) (xy 257.457302 -358.341051) (xy 257.595454 -358.307159)
			(xy 257.735303 -358.281138) (xy 257.876399 -358.26307) (xy 258.018291 -358.253013) (xy 258.160526 -358.251)
			(xy 258.302646 -358.257037) (xy 258.444197 -358.271105) (xy 258.584726 -358.293159) (xy 258.723781 -358.323128)
			(xy 258.860919 -358.360916) (xy 258.995699 -358.406402) (xy 259.12769 -358.45944) (xy 259.256469 -358.519861)
			(xy 259.381623 -358.58747) (xy 259.502751 -358.662052) (xy 259.619467 -358.743368) (xy 259.652996 -358.769666)
			(xy 294.901627 -358.769666) (xy 294.905632 -358.663917) (xy 294.917622 -358.558774) (xy 294.937531 -358.454839)
			(xy 294.965242 -358.352707) (xy 295.000599 -358.252963) (xy 295.043397 -358.156179) (xy 295.093393 -358.062909)
			(xy 295.1503 -357.973688) (xy 295.213791 -357.889025) (xy 295.283503 -357.809407) (xy 295.359037 -357.735289)
			(xy 295.43996 -357.667096) (xy 295.525809 -357.605218) (xy 295.616092 -357.550011) (xy 295.710291 -357.501789)
			(xy 295.807868 -357.460829) (xy 295.908263 -357.427367) (xy 296.010901 -357.401593) (xy 296.115194 -357.383655)
			(xy 296.220545 -357.373656) (xy 296.326351 -357.371653) (xy 296.432005 -357.377658) (xy 296.536902 -357.391637)
			(xy 296.640442 -357.413508) (xy 296.742031 -357.443148) (xy 296.841088 -357.480386) (xy 296.937045 -357.525008)
			(xy 297.029352 -357.57676) (xy 297.117481 -357.635345) (xy 297.200927 -357.700427) (xy 297.279211 -357.771633)
			(xy 297.351886 -357.848556) (xy 297.418536 -357.930756) (xy 297.478778 -358.01776) (xy 297.532267 -358.109071)
			(xy 297.578698 -358.204166) (xy 297.617803 -358.3025) (xy 297.64936 -358.403511) (xy 297.673187 -358.506618)
			(xy 297.689148 -358.611232) (xy 297.697152 -358.716754) (xy 297.697652 -358.769666) (xy 297.697152 -358.822578)
			(xy 297.689148 -358.9281) (xy 297.673187 -359.032714) (xy 297.64936 -359.135821) (xy 297.617803 -359.236832)
			(xy 297.578698 -359.335166) (xy 297.532267 -359.430261) (xy 297.478778 -359.521572) (xy 297.418536 -359.608576)
			(xy 297.351886 -359.690776) (xy 297.279211 -359.767699) (xy 297.200927 -359.838905) (xy 297.117481 -359.903987)
			(xy 297.029352 -359.962572) (xy 296.937045 -360.014324) (xy 296.841088 -360.058946) (xy 296.742031 -360.096184)
			(xy 296.640442 -360.125824) (xy 296.536902 -360.147695) (xy 296.432005 -360.161674) (xy 296.326351 -360.167679)
			(xy 296.220545 -360.165676) (xy 296.115194 -360.155677) (xy 296.010901 -360.137739) (xy 295.908263 -360.111965)
			(xy 295.807868 -360.078503) (xy 295.710291 -360.037543) (xy 295.616092 -359.989321) (xy 295.525809 -359.934114)
			(xy 295.43996 -359.872236) (xy 295.359037 -359.804043) (xy 295.283503 -359.729925) (xy 295.213791 -359.650307)
			(xy 295.1503 -359.565644) (xy 295.093393 -359.476423) (xy 295.043397 -359.383153) (xy 295.000599 -359.286369)
			(xy 294.965242 -359.186625) (xy 294.937531 -359.084493) (xy 294.917622 -358.980558) (xy 294.905632 -358.875415)
			(xy 294.901627 -358.769666) (xy 259.652996 -358.769666) (xy 259.731395 -358.831156) (xy 259.838177 -358.925136)
			(xy 259.939471 -359.025006) (xy 260.034952 -359.130448) (xy 260.124316 -359.241122) (xy 260.207274 -359.356675)
			(xy 260.283563 -359.476736) (xy 260.352937 -359.600921) (xy 260.415174 -359.728832) (xy 260.470075 -359.860059)
			(xy 260.517463 -359.994182) (xy 260.557188 -360.130771) (xy 260.589121 -360.269389) (xy 260.613162 -360.409591)
			(xy 260.629231 -360.550929) (xy 260.637279 -360.69295) (xy 260.637782 -360.764074) (xy 260.637279 -360.835198)
			(xy 260.629231 -360.977219) (xy 260.613162 -361.118557) (xy 260.589121 -361.258759) (xy 260.557188 -361.397377)
			(xy 260.517463 -361.533966) (xy 260.470075 -361.668089) (xy 260.415174 -361.799316) (xy 260.401302 -361.827826)
			(xy 430.615097 -361.827826) (xy 430.619102 -361.722077) (xy 430.631092 -361.616934) (xy 430.651001 -361.512999)
			(xy 430.678712 -361.410867) (xy 430.714069 -361.311123) (xy 430.756867 -361.214339) (xy 430.806863 -361.121069)
			(xy 430.86377 -361.031848) (xy 430.927261 -360.947185) (xy 430.996973 -360.867567) (xy 431.072507 -360.793449)
			(xy 431.15343 -360.725256) (xy 431.239279 -360.663378) (xy 431.329562 -360.608171) (xy 431.423761 -360.559949)
			(xy 431.521338 -360.518989) (xy 431.621733 -360.485527) (xy 431.724371 -360.459753) (xy 431.828664 -360.441815)
			(xy 431.934015 -360.431816) (xy 432.039821 -360.429813) (xy 432.145475 -360.435818) (xy 432.250372 -360.449797)
			(xy 432.353912 -360.471668) (xy 432.455501 -360.501308) (xy 432.554558 -360.538546) (xy 432.650515 -360.583168)
			(xy 432.742822 -360.63492) (xy 432.830951 -360.693505) (xy 432.914397 -360.758587) (xy 432.992681 -360.829793)
			(xy 433.065356 -360.906716) (xy 433.132006 -360.988916) (xy 433.192248 -361.07592) (xy 433.245737 -361.167231)
			(xy 433.292168 -361.262326) (xy 433.331273 -361.36066) (xy 433.36283 -361.461671) (xy 433.370787 -361.496102)
			(xy 434.579776 -361.496102) (xy 434.580404 -361.4497) (xy 434.590093 -361.357403) (xy 434.609347 -361.266617)
			(xy 434.637954 -361.178332) (xy 434.65623 -361.135676) (xy 434.660038 -361.125734) (xy 434.660039 -361.10447)
			(xy 434.65623 -361.094528) (xy 434.637968 -361.051867) (xy 434.609375 -360.963579) (xy 434.590118 -360.872796)
			(xy 434.580405 -360.780503) (xy 434.579776 -360.734102) (xy 434.580404 -360.6877) (xy 434.590093 -360.595403)
			(xy 434.609347 -360.504617) (xy 434.637954 -360.416332) (xy 434.65623 -360.373676) (xy 434.660038 -360.363734)
			(xy 434.660039 -360.34247) (xy 434.65623 -360.332528) (xy 434.637968 -360.289867) (xy 434.609375 -360.201579)
			(xy 434.590118 -360.110796) (xy 434.580405 -360.018503) (xy 434.579776 -359.972102) (xy 434.5802 -359.930986)
			(xy 434.587788 -359.849105) (xy 434.602898 -359.768273) (xy 434.625402 -359.68918) (xy 434.655109 -359.612502)
			(xy 434.691763 -359.538891) (xy 434.735054 -359.468977) (xy 434.784611 -359.403355) (xy 434.840011 -359.342586)
			(xy 434.900783 -359.287188) (xy 434.966406 -359.237634) (xy 435.036323 -359.194346) (xy 435.109935 -359.157694)
			(xy 435.186615 -359.127991) (xy 435.265708 -359.10549) (xy 435.346541 -359.090383) (xy 435.428422 -359.082799)
			(xy 435.469538 -359.08234) (xy 435.51594 -359.082957) (xy 435.608238 -359.09265) (xy 435.699023 -359.111907)
			(xy 435.787308 -359.140517) (xy 435.829964 -359.158794) (xy 435.839906 -359.1626) (xy 435.86117 -359.1626)
			(xy 435.871112 -359.158794) (xy 435.913767 -359.140517) (xy 436.002057 -359.111928) (xy 436.092842 -359.092675)
			(xy 436.185137 -359.082967) (xy 436.231538 -359.08234) (xy 436.272653 -359.082777) (xy 436.354532 -359.090367)
			(xy 436.435361 -359.10548) (xy 436.514451 -359.127986) (xy 436.591127 -359.157693) (xy 436.664735 -359.194349)
			(xy 436.734647 -359.237639) (xy 436.800266 -359.287195) (xy 436.861034 -359.342595) (xy 436.91643 -359.403364)
			(xy 436.965984 -359.468986) (xy 437.009271 -359.5389) (xy 437.045923 -359.61251) (xy 437.075627 -359.689187)
			(xy 437.098129 -359.768278) (xy 437.113238 -359.849108) (xy 437.120825 -359.930987) (xy 437.1213 -359.972102)
			(xy 437.120676 -360.018504) (xy 437.110985 -360.110802) (xy 437.091731 -360.201587) (xy 437.063122 -360.289872)
			(xy 437.044846 -360.332528) (xy 437.041037 -360.34247) (xy 437.041038 -360.363734) (xy 437.044846 -360.373676)
			(xy 437.063108 -360.416337) (xy 437.091701 -360.504625) (xy 437.110959 -360.595408) (xy 437.120671 -360.687701)
			(xy 437.1213 -360.734102) (xy 437.120676 -360.780504) (xy 437.110985 -360.872802) (xy 437.091731 -360.963587)
			(xy 437.063122 -361.051872) (xy 437.044846 -361.094528) (xy 437.041037 -361.10447) (xy 437.041038 -361.125734)
			(xy 437.044846 -361.135676) (xy 437.063108 -361.178337) (xy 437.091701 -361.266625) (xy 437.110959 -361.357408)
			(xy 437.120671 -361.449701) (xy 437.1213 -361.496102) (xy 437.120789 -361.537215) (xy 437.113202 -361.619091)
			(xy 437.098093 -361.699917) (xy 437.075592 -361.779004) (xy 437.045889 -361.855678) (xy 437.009238 -361.929285)
			(xy 436.965952 -361.999196) (xy 436.916401 -362.064814) (xy 436.861007 -362.125581) (xy 436.800242 -362.180978)
			(xy 436.734625 -362.230532) (xy 436.664716 -362.273821) (xy 436.591111 -362.310474) (xy 436.514439 -362.34018)
			(xy 436.435352 -362.362685) (xy 436.354526 -362.377797) (xy 436.272651 -362.385387) (xy 436.231538 -362.385864)
			(xy 436.185135 -362.385256) (xy 436.092838 -362.37556) (xy 436.002052 -362.356301) (xy 435.913768 -362.327688)
			(xy 435.871112 -362.30941) (xy 435.86117 -362.305604) (xy 435.839906 -362.305604) (xy 435.829964 -362.30941)
			(xy 435.787299 -362.327662) (xy 435.699012 -362.356257) (xy 435.608231 -362.375517) (xy 435.515939 -362.385233)
			(xy 435.469538 -362.385864) (xy 435.428424 -362.385365) (xy 435.346546 -362.377782) (xy 435.265717 -362.362675)
			(xy 435.186627 -362.340175) (xy 435.10995 -362.310473) (xy 435.036341 -362.273823) (xy 434.966428 -362.230538)
			(xy 434.900807 -362.180986) (xy 434.840038 -362.12559) (xy 434.78464 -362.064824) (xy 434.735085 -361.999205)
			(xy 434.691796 -361.929294) (xy 434.655143 -361.855686) (xy 434.625438 -361.779011) (xy 434.602934 -361.699922)
			(xy 434.587824 -361.619094) (xy 434.580237 -361.537216) (xy 434.579776 -361.496102) (xy 433.370787 -361.496102)
			(xy 433.386657 -361.564778) (xy 433.402618 -361.669392) (xy 433.410622 -361.774914) (xy 433.411122 -361.827826)
			(xy 433.410622 -361.880738) (xy 433.402618 -361.98626) (xy 433.386657 -362.090874) (xy 433.36283 -362.193981)
			(xy 433.331273 -362.294992) (xy 433.292168 -362.393326) (xy 433.245737 -362.488421) (xy 433.192248 -362.579732)
			(xy 433.132006 -362.666736) (xy 433.065356 -362.748936) (xy 432.992681 -362.825859) (xy 432.914397 -362.897065)
			(xy 432.830951 -362.962147) (xy 432.742822 -363.020732) (xy 432.650515 -363.072484) (xy 432.554558 -363.117106)
			(xy 432.455501 -363.154344) (xy 432.353912 -363.183984) (xy 432.250372 -363.205855) (xy 432.145475 -363.219834)
			(xy 432.039821 -363.225839) (xy 431.934015 -363.223836) (xy 431.828664 -363.213837) (xy 431.724371 -363.195899)
			(xy 431.621733 -363.170125) (xy 431.521338 -363.136663) (xy 431.423761 -363.095703) (xy 431.329562 -363.047481)
			(xy 431.239279 -362.992274) (xy 431.15343 -362.930396) (xy 431.072507 -362.862203) (xy 430.996973 -362.788085)
			(xy 430.927261 -362.708467) (xy 430.86377 -362.623804) (xy 430.806863 -362.534583) (xy 430.756867 -362.441313)
			(xy 430.714069 -362.344529) (xy 430.678712 -362.244785) (xy 430.651001 -362.142653) (xy 430.631092 -362.038718)
			(xy 430.619102 -361.933575) (xy 430.615097 -361.827826) (xy 260.401302 -361.827826) (xy 260.352937 -361.927227)
			(xy 260.283563 -362.051412) (xy 260.207274 -362.171473) (xy 260.124316 -362.287026) (xy 260.034952 -362.3977)
			(xy 259.939471 -362.503142) (xy 259.838177 -362.603012) (xy 259.731395 -362.696992) (xy 259.619467 -362.78478)
			(xy 259.502751 -362.866096) (xy 259.381623 -362.940678) (xy 259.256469 -363.008287) (xy 259.12769 -363.068708)
			(xy 258.995699 -363.121746) (xy 258.860919 -363.167232) (xy 258.723781 -363.20502) (xy 258.584726 -363.234989)
			(xy 258.444197 -363.257043) (xy 258.302646 -363.271111) (xy 258.160526 -363.277148) (xy 258.018291 -363.275135)
			(xy 257.876399 -363.265078) (xy 257.735303 -363.24701) (xy 257.595454 -363.220989) (xy 257.457302 -363.187097)
			(xy 257.321289 -363.145443) (xy 257.18785 -363.096161) (xy 257.057413 -363.039409) (xy 256.930396 -362.975368)
			(xy 256.807205 -362.904244) (xy 256.688236 -362.826264) (xy 256.573868 -362.741678) (xy 256.464469 -362.650758)
			(xy 256.36039 -362.553794) (xy 256.261962 -362.451097) (xy 256.169503 -362.342995) (xy 256.083307 -362.229836)
			(xy 256.003652 -362.111982) (xy 255.930791 -361.98981) (xy 255.86496 -361.863712) (xy 255.806367 -361.734091)
			(xy 255.755202 -361.601363) (xy 255.711628 -361.465953) (xy 255.675784 -361.328294) (xy 255.647786 -361.188828)
			(xy 255.627723 -361.048002) (xy 255.61566 -360.906266) (xy 255.611635 -360.764074) (xy 216.187782 -360.764074)
			(xy 216.187279 -360.835198) (xy 216.179231 -360.977219) (xy 216.163162 -361.118557) (xy 216.139121 -361.258759)
			(xy 216.107188 -361.397377) (xy 216.067463 -361.533966) (xy 216.020075 -361.668089) (xy 215.965174 -361.799316)
			(xy 215.902937 -361.927227) (xy 215.833563 -362.051412) (xy 215.757274 -362.171473) (xy 215.674316 -362.287026)
			(xy 215.584952 -362.3977) (xy 215.489471 -362.503142) (xy 215.388177 -362.603012) (xy 215.281395 -362.696992)
			(xy 215.169467 -362.78478) (xy 215.052751 -362.866096) (xy 214.931623 -362.940678) (xy 214.806469 -363.008287)
			(xy 214.67769 -363.068708) (xy 214.545699 -363.121746) (xy 214.410919 -363.167232) (xy 214.273781 -363.20502)
			(xy 214.134726 -363.234989) (xy 213.994197 -363.257043) (xy 213.852646 -363.271111) (xy 213.710526 -363.277148)
			(xy 213.568291 -363.275135) (xy 213.426399 -363.265078) (xy 213.285303 -363.24701) (xy 213.145454 -363.220989)
			(xy 213.007302 -363.187097) (xy 212.871289 -363.145443) (xy 212.73785 -363.096161) (xy 212.607413 -363.039409)
			(xy 212.480396 -362.975368) (xy 212.357205 -362.904244) (xy 212.238236 -362.826264) (xy 212.123868 -362.741678)
			(xy 212.014469 -362.650758) (xy 211.91039 -362.553794) (xy 211.811962 -362.451097) (xy 211.719503 -362.342995)
			(xy 211.633307 -362.229836) (xy 211.553652 -362.111982) (xy 211.480791 -361.98981) (xy 211.41496 -361.863712)
			(xy 211.356367 -361.734091) (xy 211.305202 -361.601363) (xy 211.261628 -361.465953) (xy 211.225784 -361.328294)
			(xy 211.197786 -361.188828) (xy 211.177723 -361.048002) (xy 211.16566 -360.906266) (xy 211.161635 -360.764074)
			(xy 187.684417 -360.764074) (xy 187.675402 -360.849986) (xy 187.656207 -360.94064) (xy 187.627695 -361.028809)
			(xy 187.60948 -361.071414) (xy 187.605683 -361.081359) (xy 187.605679 -361.10262) (xy 187.60948 -361.112562)
			(xy 187.627719 -361.155227) (xy 187.656265 -361.243518) (xy 187.67546 -361.334302) (xy 187.685094 -361.426592)
			(xy 187.68568 -361.472988) (xy 187.685095 -361.519384) (xy 187.675451 -361.611672) (xy 187.656256 -361.702456)
			(xy 187.627718 -361.790749) (xy 187.60948 -361.833414) (xy 187.605683 -361.843359) (xy 187.605679 -361.86462)
			(xy 187.60948 -361.874562) (xy 187.627696 -361.917167) (xy 187.656216 -362.005334) (xy 187.67541 -362.095988)
			(xy 187.685071 -362.188148) (xy 187.68568 -362.23448) (xy 187.68568 -362.234988) (xy 187.685236 -362.276092)
			(xy 187.677652 -362.357949) (xy 187.664078 -362.430568) (xy 190.281567 -362.430568) (xy 190.285572 -362.324819)
			(xy 190.297562 -362.219676) (xy 190.317471 -362.115741) (xy 190.345182 -362.013609) (xy 190.380539 -361.913865)
			(xy 190.423337 -361.817081) (xy 190.473333 -361.723811) (xy 190.53024 -361.63459) (xy 190.593731 -361.549927)
			(xy 190.663443 -361.470309) (xy 190.738977 -361.396191) (xy 190.8199 -361.327998) (xy 190.905749 -361.26612)
			(xy 190.996032 -361.210913) (xy 191.090231 -361.162691) (xy 191.187808 -361.121731) (xy 191.288203 -361.088269)
			(xy 191.390841 -361.062495) (xy 191.495134 -361.044557) (xy 191.600485 -361.034558) (xy 191.706291 -361.032555)
			(xy 191.811945 -361.03856) (xy 191.916842 -361.052539) (xy 192.020382 -361.07441) (xy 192.121971 -361.10405)
			(xy 192.221028 -361.141288) (xy 192.316985 -361.18591) (xy 192.409292 -361.237662) (xy 192.497421 -361.296247)
			(xy 192.580867 -361.361329) (xy 192.659151 -361.432535) (xy 192.731826 -361.509458) (xy 192.798476 -361.591658)
			(xy 192.858718 -361.678662) (xy 192.912207 -361.769973) (xy 192.958638 -361.865068) (xy 192.997743 -361.963402)
			(xy 193.0293 -362.064413) (xy 193.053127 -362.16752) (xy 193.069088 -362.272134) (xy 193.077092 -362.377656)
			(xy 193.077592 -362.430568) (xy 193.077092 -362.48348) (xy 193.069088 -362.589002) (xy 193.053127 -362.693616)
			(xy 193.0293 -362.796723) (xy 192.997743 -362.897734) (xy 192.958638 -362.996068) (xy 192.912207 -363.091163)
			(xy 192.858718 -363.182474) (xy 192.798476 -363.269478) (xy 192.731826 -363.351678) (xy 192.659151 -363.428601)
			(xy 192.580867 -363.499807) (xy 192.497421 -363.564889) (xy 192.409292 -363.623474) (xy 192.316985 -363.675226)
			(xy 192.221028 -363.719848) (xy 192.121971 -363.757086) (xy 192.020382 -363.786726) (xy 191.916842 -363.808597)
			(xy 191.811945 -363.822576) (xy 191.706291 -363.828581) (xy 191.600485 -363.826578) (xy 191.495134 -363.816579)
			(xy 191.390841 -363.798641) (xy 191.288203 -363.772867) (xy 191.187808 -363.739405) (xy 191.090231 -363.698445)
			(xy 190.996032 -363.650223) (xy 190.905749 -363.595016) (xy 190.8199 -363.533138) (xy 190.738977 -363.464945)
			(xy 190.663443 -363.390827) (xy 190.593731 -363.311209) (xy 190.53024 -363.226546) (xy 190.473333 -363.137325)
			(xy 190.423337 -363.044055) (xy 190.380539 -362.947271) (xy 190.345182 -362.847527) (xy 190.317471 -362.745395)
			(xy 190.297562 -362.64146) (xy 190.285572 -362.536317) (xy 190.281567 -362.430568) (xy 187.664078 -362.430568)
			(xy 187.662547 -362.438757) (xy 187.64005 -362.517826) (xy 187.610354 -362.594483) (xy 187.573711 -362.668072)
			(xy 187.530434 -362.737966) (xy 187.480892 -362.803569) (xy 187.425509 -362.86432) (xy 187.364756 -362.919703)
			(xy 187.299153 -362.969243) (xy 187.229258 -363.012519) (xy 187.155668 -363.04916) (xy 187.079011 -363.078856)
			(xy 186.999941 -363.101351) (xy 186.919133 -363.116454) (xy 186.837276 -363.124037) (xy 186.796172 -363.124496)
			(xy 186.795664 -363.124496) (xy 186.749333 -363.123866) (xy 186.657176 -363.114202) (xy 186.566521 -363.095013)
			(xy 186.478352 -363.066508) (xy 186.435746 -363.048296) (xy 186.425804 -363.04449) (xy 186.40454 -363.04449)
			(xy 186.394598 -363.048296) (xy 186.351999 -363.066527) (xy 186.26383 -363.095042) (xy 186.173173 -363.114232)
			(xy 186.081013 -363.123889) (xy 186.03468 -363.124496) (xy 186.034172 -363.124496) (xy 185.993069 -363.12406)
			(xy 185.911213 -363.116473) (xy 185.830407 -363.101365) (xy 185.751339 -363.078866) (xy 185.674684 -363.049167)
			(xy 185.601097 -363.012522) (xy 185.531204 -362.969244) (xy 185.465603 -362.919702) (xy 185.404853 -362.864319)
			(xy 185.349472 -362.803566) (xy 185.299933 -362.737963) (xy 185.256658 -362.668068) (xy 185.220017 -362.594479)
			(xy 185.190322 -362.517823) (xy 185.167826 -362.438755) (xy 185.152722 -362.357947) (xy 185.145138 -362.276091)
			(xy 185.144664 -362.234988) (xy 166.497508 -362.234988) (xy 166.497508 -362.396278) (xy 166.497022 -362.423547)
			(xy 166.48926 -362.477531) (xy 166.473895 -362.529861) (xy 166.451238 -362.579471) (xy 166.421752 -362.625352)
			(xy 166.386037 -362.666569) (xy 166.34482 -362.702284) (xy 166.298939 -362.73177) (xy 166.249329 -362.754427)
			(xy 166.196999 -362.769792) (xy 166.143015 -362.777554) (xy 166.088477 -362.777554) (xy 166.034493 -362.769792)
			(xy 165.982163 -362.754427) (xy 165.932553 -362.73177) (xy 165.886672 -362.702284) (xy 165.845455 -362.666569)
			(xy 165.80974 -362.625352) (xy 165.780254 -362.579471) (xy 165.757597 -362.529861) (xy 165.742232 -362.477531)
			(xy 165.73447 -362.423547) (xy 165.733984 -362.396278) (xy 10.079022 -362.396278) (xy 10.05934 -362.458146)
			(xy 10.012689 -362.578565) (xy 9.958714 -362.695884) (xy 9.897619 -362.809658) (xy 9.829636 -362.919455)
			(xy 9.755022 -363.024858) (xy 9.674061 -363.125468) (xy 9.587061 -363.220903) (xy 9.49435 -363.310802)
			(xy 9.39628 -363.394823) (xy 9.293225 -363.472647) (xy 9.185574 -363.543979) (xy 9.073735 -363.608549)
			(xy 8.958134 -363.666111) (xy 8.839209 -363.716448) (xy 8.71741 -363.759368) (xy 8.5932 -363.794709)
			(xy 8.467051 -363.822336) (xy 8.339439 -363.842145) (xy 8.21085 -363.854061) (xy 8.081772 -363.858038)
			(xy 7.952694 -363.854061) (xy 7.824105 -363.842145) (xy 7.696493 -363.822336) (xy 7.570344 -363.794709)
			(xy 7.446134 -363.759368) (xy 7.324335 -363.716448) (xy 7.20541 -363.666111) (xy 7.089809 -363.608549)
			(xy 6.97797 -363.543979) (xy 6.870319 -363.472647) (xy 6.767264 -363.394823) (xy 6.669194 -363.310802)
			(xy 6.576483 -363.220903) (xy 6.489483 -363.125468) (xy 6.408522 -363.024858) (xy 6.333908 -362.919455)
			(xy 6.265925 -362.809658) (xy 6.20483 -362.695884) (xy 6.150855 -362.578565) (xy 6.104204 -362.458146)
			(xy 6.065055 -362.335083) (xy 6.033556 -362.209844) (xy 6.009827 -362.082903) (xy 5.993957 -361.954743)
			(xy 5.986007 -361.825848) (xy 2.509012 -361.825848) (xy 2.509012 -369.062565) (xy 44.335754 -369.062565)
			(xy 44.335754 -369.008035) (xy 44.343514 -368.95406) (xy 44.358876 -368.901738) (xy 44.381527 -368.852135)
			(xy 44.411006 -368.806259) (xy 44.446714 -368.765046) (xy 44.487923 -368.729334) (xy 44.533794 -368.699849)
			(xy 44.583395 -368.677192) (xy 44.635715 -368.661824) (xy 44.689689 -368.654057) (xy 44.716954 -368.653568)
			(xy 45.580554 -368.653568) (xy 45.607829 -368.653968) (xy 45.661825 -368.661726) (xy 45.714168 -368.677089)
			(xy 45.763791 -368.699746) (xy 45.809684 -368.729235) (xy 45.850912 -368.764955) (xy 45.886638 -368.80618)
			(xy 45.916132 -368.852069) (xy 45.938795 -368.901689) (xy 45.954164 -368.95403) (xy 45.961928 -369.008025)
			(xy 45.961928 -369.062565) (xy 51.142954 -369.062565) (xy 51.142954 -369.008035) (xy 51.150714 -368.95406)
			(xy 51.166076 -368.901738) (xy 51.188727 -368.852135) (xy 51.218206 -368.806259) (xy 51.253914 -368.765046)
			(xy 51.295123 -368.729334) (xy 51.340994 -368.699849) (xy 51.390595 -368.677192) (xy 51.442915 -368.661824)
			(xy 51.496889 -368.654057) (xy 51.524154 -368.653568) (xy 52.387754 -368.653568) (xy 52.415029 -368.653968)
			(xy 52.469025 -368.661726) (xy 52.521368 -368.677089) (xy 52.570991 -368.699746) (xy 52.616884 -368.729235)
			(xy 52.658112 -368.764955) (xy 52.693838 -368.80618) (xy 52.723332 -368.852069) (xy 52.745995 -368.901689)
			(xy 52.761364 -368.95403) (xy 52.769128 -369.008025) (xy 52.769128 -369.062565) (xy 57.950154 -369.062565)
			(xy 57.950154 -369.008035) (xy 57.957914 -368.95406) (xy 57.973276 -368.901738) (xy 57.995927 -368.852135)
			(xy 58.025406 -368.806259) (xy 58.061114 -368.765046) (xy 58.102323 -368.729334) (xy 58.148194 -368.699849)
			(xy 58.197795 -368.677192) (xy 58.250115 -368.661824) (xy 58.304089 -368.654057) (xy 58.331354 -368.653568)
			(xy 59.194954 -368.653568) (xy 59.222229 -368.653968) (xy 59.276225 -368.661726) (xy 59.328568 -368.677089)
			(xy 59.378191 -368.699746) (xy 59.424084 -368.729235) (xy 59.465312 -368.764955) (xy 59.501038 -368.80618)
			(xy 59.530532 -368.852069) (xy 59.553195 -368.901689) (xy 59.568564 -368.95403) (xy 59.576328 -369.008025)
			(xy 59.576328 -369.062565) (xy 64.757354 -369.062565) (xy 64.757354 -369.008035) (xy 64.765114 -368.95406)
			(xy 64.780476 -368.901738) (xy 64.803127 -368.852135) (xy 64.832606 -368.806259) (xy 64.868314 -368.765046)
			(xy 64.909523 -368.729334) (xy 64.955394 -368.699849) (xy 65.004995 -368.677192) (xy 65.057315 -368.661824)
			(xy 65.111289 -368.654057) (xy 65.138554 -368.653568) (xy 66.002154 -368.653568) (xy 66.029429 -368.653968)
			(xy 66.083425 -368.661726) (xy 66.135768 -368.677089) (xy 66.185391 -368.699746) (xy 66.231284 -368.729235)
			(xy 66.272512 -368.764955) (xy 66.308238 -368.80618) (xy 66.337732 -368.852069) (xy 66.360395 -368.901689)
			(xy 66.375764 -368.95403) (xy 66.383528 -369.008025) (xy 66.383528 -369.062565) (xy 68.160954 -369.062565)
			(xy 68.160954 -369.008035) (xy 68.168714 -368.95406) (xy 68.184076 -368.901738) (xy 68.206727 -368.852135)
			(xy 68.236206 -368.806259) (xy 68.271914 -368.765046) (xy 68.313123 -368.729334) (xy 68.358994 -368.699849)
			(xy 68.408595 -368.677192) (xy 68.460915 -368.661824) (xy 68.514889 -368.654057) (xy 68.542154 -368.653568)
			(xy 69.405754 -368.653568) (xy 69.433029 -368.653968) (xy 69.487025 -368.661726) (xy 69.539368 -368.677089)
			(xy 69.588991 -368.699746) (xy 69.634884 -368.729235) (xy 69.676112 -368.764955) (xy 69.711838 -368.80618)
			(xy 69.741332 -368.852069) (xy 69.763995 -368.901689) (xy 69.779364 -368.95403) (xy 69.787128 -369.008025)
			(xy 69.787128 -369.062569) (xy 76.863431 -369.062569) (xy 76.863431 -369.008031) (xy 76.871193 -368.954048)
			(xy 76.886558 -368.90172) (xy 76.909214 -368.85211) (xy 76.9387 -368.80623) (xy 76.974414 -368.765013)
			(xy 77.015632 -368.729298) (xy 77.061512 -368.699813) (xy 77.111121 -368.677157) (xy 77.16345 -368.661793)
			(xy 77.217433 -368.654031) (xy 77.244702 -368.653568) (xy 78.108302 -368.653568) (xy 78.135573 -368.653995)
			(xy 78.189561 -368.661757) (xy 78.241894 -368.677124) (xy 78.291508 -368.699782) (xy 78.337393 -368.72927)
			(xy 78.378613 -368.764988) (xy 78.414331 -368.806209) (xy 78.443819 -368.852093) (xy 78.466477 -368.901707)
			(xy 78.481843 -368.954041) (xy 78.489606 -369.008029) (xy 78.489606 -369.062569) (xy 83.670631 -369.062569)
			(xy 83.670631 -369.008031) (xy 83.678393 -368.954048) (xy 83.693758 -368.90172) (xy 83.716414 -368.85211)
			(xy 83.7459 -368.80623) (xy 83.781614 -368.765013) (xy 83.822832 -368.729298) (xy 83.868712 -368.699813)
			(xy 83.918321 -368.677157) (xy 83.97065 -368.661793) (xy 84.024633 -368.654031) (xy 84.051902 -368.653568)
			(xy 84.915502 -368.653568) (xy 84.942773 -368.653995) (xy 84.996761 -368.661757) (xy 85.049094 -368.677124)
			(xy 85.098708 -368.699782) (xy 85.144593 -368.72927) (xy 85.185813 -368.764988) (xy 85.221531 -368.806209)
			(xy 85.251019 -368.852093) (xy 85.273677 -368.901707) (xy 85.289043 -368.954041) (xy 85.296806 -369.008029)
			(xy 85.296806 -369.062569) (xy 90.477831 -369.062569) (xy 90.477831 -369.008031) (xy 90.485593 -368.954048)
			(xy 90.500958 -368.90172) (xy 90.523614 -368.85211) (xy 90.5531 -368.80623) (xy 90.588814 -368.765013)
			(xy 90.630032 -368.729298) (xy 90.675912 -368.699813) (xy 90.725521 -368.677157) (xy 90.77785 -368.661793)
			(xy 90.831833 -368.654031) (xy 90.859102 -368.653568) (xy 91.722702 -368.653568) (xy 91.749973 -368.653995)
			(xy 91.803961 -368.661757) (xy 91.856294 -368.677124) (xy 91.905908 -368.699782) (xy 91.951793 -368.72927)
			(xy 91.993013 -368.764988) (xy 92.028731 -368.806209) (xy 92.058219 -368.852093) (xy 92.080877 -368.901707)
			(xy 92.096243 -368.954041) (xy 92.104006 -369.008029) (xy 92.104006 -369.062569) (xy 97.285031 -369.062569)
			(xy 97.285031 -369.008031) (xy 97.292793 -368.954048) (xy 97.308158 -368.90172) (xy 97.330814 -368.85211)
			(xy 97.3603 -368.80623) (xy 97.396014 -368.765013) (xy 97.437232 -368.729298) (xy 97.483112 -368.699813)
			(xy 97.532721 -368.677157) (xy 97.58505 -368.661793) (xy 97.639033 -368.654031) (xy 97.666302 -368.653568)
			(xy 98.529902 -368.653568) (xy 98.557173 -368.653995) (xy 98.611161 -368.661757) (xy 98.663494 -368.677124)
			(xy 98.713108 -368.699782) (xy 98.758993 -368.72927) (xy 98.800213 -368.764988) (xy 98.835931 -368.806209)
			(xy 98.865419 -368.852093) (xy 98.888077 -368.901707) (xy 98.903443 -368.954041) (xy 98.911206 -369.008029)
			(xy 98.911206 -369.062569) (xy 100.688631 -369.062569) (xy 100.688631 -369.008031) (xy 100.696393 -368.954048)
			(xy 100.711758 -368.90172) (xy 100.734414 -368.85211) (xy 100.7639 -368.80623) (xy 100.799614 -368.765013)
			(xy 100.840832 -368.729298) (xy 100.886712 -368.699813) (xy 100.936321 -368.677157) (xy 100.98865 -368.661793)
			(xy 101.042633 -368.654031) (xy 101.069902 -368.653568) (xy 101.933502 -368.653568) (xy 101.960773 -368.653995)
			(xy 102.014761 -368.661757) (xy 102.067094 -368.677124) (xy 102.116708 -368.699782) (xy 102.162593 -368.72927)
			(xy 102.203813 -368.764988) (xy 102.239531 -368.806209) (xy 102.269019 -368.852093) (xy 102.291677 -368.901707)
			(xy 102.307043 -368.954041) (xy 102.314806 -369.008029) (xy 102.314806 -369.062567) (xy 111.435654 -369.062567)
			(xy 111.435654 -369.008033) (xy 111.443415 -368.954054) (xy 111.458779 -368.901729) (xy 111.481433 -368.852123)
			(xy 111.510917 -368.806246) (xy 111.546629 -368.765031) (xy 111.587842 -368.729319) (xy 111.633719 -368.699835)
			(xy 111.683325 -368.677181) (xy 111.73565 -368.661816) (xy 111.789629 -368.654055) (xy 111.816896 -368.653568)
			(xy 112.680496 -368.653568) (xy 112.707769 -368.653971) (xy 112.761761 -368.661734) (xy 112.814098 -368.677101)
			(xy 112.863716 -368.69976) (xy 112.909603 -368.72925) (xy 112.950827 -368.76497) (xy 112.986548 -368.806193)
			(xy 113.016038 -368.852081) (xy 113.038698 -368.901698) (xy 113.054066 -368.954035) (xy 113.061828 -369.008027)
			(xy 113.061828 -369.062567) (xy 118.242854 -369.062567) (xy 118.242854 -369.008033) (xy 118.250615 -368.954054)
			(xy 118.265979 -368.901729) (xy 118.288633 -368.852123) (xy 118.318117 -368.806246) (xy 118.353829 -368.765031)
			(xy 118.395042 -368.729319) (xy 118.440919 -368.699835) (xy 118.490525 -368.677181) (xy 118.54285 -368.661816)
			(xy 118.596829 -368.654055) (xy 118.624096 -368.653568) (xy 119.487696 -368.653568) (xy 119.514969 -368.653971)
			(xy 119.568961 -368.661734) (xy 119.621298 -368.677101) (xy 119.670916 -368.69976) (xy 119.716803 -368.72925)
			(xy 119.758027 -368.76497) (xy 119.793748 -368.806193) (xy 119.823238 -368.852081) (xy 119.845898 -368.901698)
			(xy 119.861266 -368.954035) (xy 119.869028 -369.008027) (xy 119.869028 -369.062567) (xy 125.050054 -369.062567)
			(xy 125.050054 -369.008033) (xy 125.057815 -368.954054) (xy 125.073179 -368.901729) (xy 125.095833 -368.852123)
			(xy 125.125317 -368.806246) (xy 125.161029 -368.765031) (xy 125.202242 -368.729319) (xy 125.248119 -368.699835)
			(xy 125.297725 -368.677181) (xy 125.35005 -368.661816) (xy 125.404029 -368.654055) (xy 125.431296 -368.653568)
			(xy 126.294896 -368.653568) (xy 126.322169 -368.653971) (xy 126.376161 -368.661734) (xy 126.428498 -368.677101)
			(xy 126.478116 -368.69976) (xy 126.524003 -368.72925) (xy 126.565227 -368.76497) (xy 126.600948 -368.806193)
			(xy 126.630438 -368.852081) (xy 126.653098 -368.901698) (xy 126.668466 -368.954035) (xy 126.676228 -369.008027)
			(xy 126.676228 -369.062567) (xy 131.857254 -369.062567) (xy 131.857254 -369.008033) (xy 131.865015 -368.954054)
			(xy 131.880379 -368.901729) (xy 131.903033 -368.852123) (xy 131.932517 -368.806246) (xy 131.968229 -368.765031)
			(xy 132.009442 -368.729319) (xy 132.055319 -368.699835) (xy 132.104925 -368.677181) (xy 132.15725 -368.661816)
			(xy 132.211229 -368.654055) (xy 132.238496 -368.653568) (xy 133.102096 -368.653568) (xy 133.129369 -368.653971)
			(xy 133.183361 -368.661734) (xy 133.235698 -368.677101) (xy 133.285316 -368.69976) (xy 133.331203 -368.72925)
			(xy 133.372427 -368.76497) (xy 133.408148 -368.806193) (xy 133.437638 -368.852081) (xy 133.460298 -368.901698)
			(xy 133.475666 -368.954035) (xy 133.483428 -369.008027) (xy 133.483428 -369.062567) (xy 135.260854 -369.062567)
			(xy 135.260854 -369.008033) (xy 135.268615 -368.954054) (xy 135.283979 -368.901729) (xy 135.306633 -368.852123)
			(xy 135.336117 -368.806246) (xy 135.371829 -368.765031) (xy 135.413042 -368.729319) (xy 135.458919 -368.699835)
			(xy 135.508525 -368.677181) (xy 135.56085 -368.661816) (xy 135.614829 -368.654055) (xy 135.642096 -368.653568)
			(xy 136.505696 -368.653568) (xy 136.532969 -368.653971) (xy 136.586961 -368.661734) (xy 136.639298 -368.677101)
			(xy 136.688916 -368.69976) (xy 136.734803 -368.72925) (xy 136.776027 -368.76497) (xy 136.811748 -368.806193)
			(xy 136.841238 -368.852081) (xy 136.863898 -368.901698) (xy 136.879266 -368.954035) (xy 136.887028 -369.008027)
			(xy 136.887028 -369.062573) (xy 136.879266 -369.116565) (xy 136.863898 -369.168902) (xy 136.841238 -369.218519)
			(xy 136.811748 -369.264407) (xy 136.776027 -369.30563) (xy 136.734803 -369.34135) (xy 136.688916 -369.37084)
			(xy 136.639298 -369.393499) (xy 136.586961 -369.408866) (xy 136.532969 -369.416629) (xy 136.505696 -369.417092)
			(xy 135.642096 -369.417092) (xy 135.614829 -369.416545) (xy 135.56085 -369.408784) (xy 135.508525 -369.393419)
			(xy 135.458919 -369.370765) (xy 135.413042 -369.341281) (xy 135.371829 -369.305569) (xy 135.336117 -369.264354)
			(xy 135.306633 -369.218477) (xy 135.283979 -369.168871) (xy 135.268615 -369.116546) (xy 135.260854 -369.062567)
			(xy 133.483428 -369.062567) (xy 133.483428 -369.062573) (xy 133.475666 -369.116565) (xy 133.460298 -369.168902)
			(xy 133.437638 -369.218519) (xy 133.408148 -369.264407) (xy 133.372427 -369.30563) (xy 133.331203 -369.34135)
			(xy 133.285316 -369.37084) (xy 133.235698 -369.393499) (xy 133.183361 -369.408866) (xy 133.129369 -369.416629)
			(xy 133.102096 -369.417092) (xy 132.238496 -369.417092) (xy 132.211229 -369.416545) (xy 132.15725 -369.408784)
			(xy 132.104925 -369.393419) (xy 132.055319 -369.370765) (xy 132.009442 -369.341281) (xy 131.968229 -369.305569)
			(xy 131.932517 -369.264354) (xy 131.903033 -369.218477) (xy 131.880379 -369.168871) (xy 131.865015 -369.116546)
			(xy 131.857254 -369.062567) (xy 126.676228 -369.062567) (xy 126.676228 -369.062573) (xy 126.668466 -369.116565)
			(xy 126.653098 -369.168902) (xy 126.630438 -369.218519) (xy 126.600948 -369.264407) (xy 126.565227 -369.30563)
			(xy 126.524003 -369.34135) (xy 126.478116 -369.37084) (xy 126.428498 -369.393499) (xy 126.376161 -369.408866)
			(xy 126.322169 -369.416629) (xy 126.294896 -369.417092) (xy 125.431296 -369.417092) (xy 125.404029 -369.416545)
			(xy 125.35005 -369.408784) (xy 125.297725 -369.393419) (xy 125.248119 -369.370765) (xy 125.202242 -369.341281)
			(xy 125.161029 -369.305569) (xy 125.125317 -369.264354) (xy 125.095833 -369.218477) (xy 125.073179 -369.168871)
			(xy 125.057815 -369.116546) (xy 125.050054 -369.062567) (xy 119.869028 -369.062567) (xy 119.869028 -369.062573)
			(xy 119.861266 -369.116565) (xy 119.845898 -369.168902) (xy 119.823238 -369.218519) (xy 119.793748 -369.264407)
			(xy 119.758027 -369.30563) (xy 119.716803 -369.34135) (xy 119.670916 -369.37084) (xy 119.621298 -369.393499)
			(xy 119.568961 -369.408866) (xy 119.514969 -369.416629) (xy 119.487696 -369.417092) (xy 118.624096 -369.417092)
			(xy 118.596829 -369.416545) (xy 118.54285 -369.408784) (xy 118.490525 -369.393419) (xy 118.440919 -369.370765)
			(xy 118.395042 -369.341281) (xy 118.353829 -369.305569) (xy 118.318117 -369.264354) (xy 118.288633 -369.218477)
			(xy 118.265979 -369.168871) (xy 118.250615 -369.116546) (xy 118.242854 -369.062567) (xy 113.061828 -369.062567)
			(xy 113.061828 -369.062573) (xy 113.054066 -369.116565) (xy 113.038698 -369.168902) (xy 113.016038 -369.218519)
			(xy 112.986548 -369.264407) (xy 112.950827 -369.30563) (xy 112.909603 -369.34135) (xy 112.863716 -369.37084)
			(xy 112.814098 -369.393499) (xy 112.761761 -369.408866) (xy 112.707769 -369.416629) (xy 112.680496 -369.417092)
			(xy 111.816896 -369.417092) (xy 111.789629 -369.416545) (xy 111.73565 -369.408784) (xy 111.683325 -369.393419)
			(xy 111.633719 -369.370765) (xy 111.587842 -369.341281) (xy 111.546629 -369.305569) (xy 111.510917 -369.264354)
			(xy 111.481433 -369.218477) (xy 111.458779 -369.168871) (xy 111.443415 -369.116546) (xy 111.435654 -369.062567)
			(xy 102.314806 -369.062567) (xy 102.314806 -369.062571) (xy 102.307043 -369.116559) (xy 102.291677 -369.168893)
			(xy 102.269019 -369.218507) (xy 102.239531 -369.264391) (xy 102.203813 -369.305612) (xy 102.162593 -369.34133)
			(xy 102.116708 -369.370818) (xy 102.067094 -369.393476) (xy 102.014761 -369.408843) (xy 101.960773 -369.416605)
			(xy 101.933502 -369.417092) (xy 101.069902 -369.417092) (xy 101.042633 -369.416569) (xy 100.98865 -369.408807)
			(xy 100.936321 -369.393443) (xy 100.886712 -369.370787) (xy 100.840832 -369.341302) (xy 100.799614 -369.305587)
			(xy 100.7639 -369.26437) (xy 100.734414 -369.21849) (xy 100.711758 -369.16888) (xy 100.696393 -369.116552)
			(xy 100.688631 -369.062569) (xy 98.911206 -369.062569) (xy 98.911206 -369.062571) (xy 98.903443 -369.116559)
			(xy 98.888077 -369.168893) (xy 98.865419 -369.218507) (xy 98.835931 -369.264391) (xy 98.800213 -369.305612)
			(xy 98.758993 -369.34133) (xy 98.713108 -369.370818) (xy 98.663494 -369.393476) (xy 98.611161 -369.408843)
			(xy 98.557173 -369.416605) (xy 98.529902 -369.417092) (xy 97.666302 -369.417092) (xy 97.639033 -369.416569)
			(xy 97.58505 -369.408807) (xy 97.532721 -369.393443) (xy 97.483112 -369.370787) (xy 97.437232 -369.341302)
			(xy 97.396014 -369.305587) (xy 97.3603 -369.26437) (xy 97.330814 -369.21849) (xy 97.308158 -369.16888)
			(xy 97.292793 -369.116552) (xy 97.285031 -369.062569) (xy 92.104006 -369.062569) (xy 92.104006 -369.062571)
			(xy 92.096243 -369.116559) (xy 92.080877 -369.168893) (xy 92.058219 -369.218507) (xy 92.028731 -369.264391)
			(xy 91.993013 -369.305612) (xy 91.951793 -369.34133) (xy 91.905908 -369.370818) (xy 91.856294 -369.393476)
			(xy 91.803961 -369.408843) (xy 91.749973 -369.416605) (xy 91.722702 -369.417092) (xy 90.859102 -369.417092)
			(xy 90.831833 -369.416569) (xy 90.77785 -369.408807) (xy 90.725521 -369.393443) (xy 90.675912 -369.370787)
			(xy 90.630032 -369.341302) (xy 90.588814 -369.305587) (xy 90.5531 -369.26437) (xy 90.523614 -369.21849)
			(xy 90.500958 -369.16888) (xy 90.485593 -369.116552) (xy 90.477831 -369.062569) (xy 85.296806 -369.062569)
			(xy 85.296806 -369.062571) (xy 85.289043 -369.116559) (xy 85.273677 -369.168893) (xy 85.251019 -369.218507)
			(xy 85.221531 -369.264391) (xy 85.185813 -369.305612) (xy 85.144593 -369.34133) (xy 85.098708 -369.370818)
			(xy 85.049094 -369.393476) (xy 84.996761 -369.408843) (xy 84.942773 -369.416605) (xy 84.915502 -369.417092)
			(xy 84.051902 -369.417092) (xy 84.024633 -369.416569) (xy 83.97065 -369.408807) (xy 83.918321 -369.393443)
			(xy 83.868712 -369.370787) (xy 83.822832 -369.341302) (xy 83.781614 -369.305587) (xy 83.7459 -369.26437)
			(xy 83.716414 -369.21849) (xy 83.693758 -369.16888) (xy 83.678393 -369.116552) (xy 83.670631 -369.062569)
			(xy 78.489606 -369.062569) (xy 78.489606 -369.062571) (xy 78.481843 -369.116559) (xy 78.466477 -369.168893)
			(xy 78.443819 -369.218507) (xy 78.414331 -369.264391) (xy 78.378613 -369.305612) (xy 78.337393 -369.34133)
			(xy 78.291508 -369.370818) (xy 78.241894 -369.393476) (xy 78.189561 -369.408843) (xy 78.135573 -369.416605)
			(xy 78.108302 -369.417092) (xy 77.244702 -369.417092) (xy 77.217433 -369.416569) (xy 77.16345 -369.408807)
			(xy 77.111121 -369.393443) (xy 77.061512 -369.370787) (xy 77.015632 -369.341302) (xy 76.974414 -369.305587)
			(xy 76.9387 -369.26437) (xy 76.909214 -369.21849) (xy 76.886558 -369.16888) (xy 76.871193 -369.116552)
			(xy 76.863431 -369.062569) (xy 69.787128 -369.062569) (xy 69.787128 -369.062575) (xy 69.779364 -369.11657)
			(xy 69.763995 -369.168911) (xy 69.741332 -369.218531) (xy 69.711838 -369.26442) (xy 69.676112 -369.305645)
			(xy 69.634884 -369.341365) (xy 69.588991 -369.370854) (xy 69.539368 -369.393511) (xy 69.487025 -369.408874)
			(xy 69.433029 -369.416632) (xy 69.405754 -369.417092) (xy 68.542154 -369.417092) (xy 68.514889 -369.416543)
			(xy 68.460915 -369.408776) (xy 68.408595 -369.393408) (xy 68.358994 -369.370751) (xy 68.313123 -369.341266)
			(xy 68.271914 -369.305554) (xy 68.236206 -369.264341) (xy 68.206727 -369.218465) (xy 68.184076 -369.168862)
			(xy 68.168714 -369.11654) (xy 68.160954 -369.062565) (xy 66.383528 -369.062565) (xy 66.383528 -369.062575)
			(xy 66.375764 -369.11657) (xy 66.360395 -369.168911) (xy 66.337732 -369.218531) (xy 66.308238 -369.26442)
			(xy 66.272512 -369.305645) (xy 66.231284 -369.341365) (xy 66.185391 -369.370854) (xy 66.135768 -369.393511)
			(xy 66.083425 -369.408874) (xy 66.029429 -369.416632) (xy 66.002154 -369.417092) (xy 65.138554 -369.417092)
			(xy 65.111289 -369.416543) (xy 65.057315 -369.408776) (xy 65.004995 -369.393408) (xy 64.955394 -369.370751)
			(xy 64.909523 -369.341266) (xy 64.868314 -369.305554) (xy 64.832606 -369.264341) (xy 64.803127 -369.218465)
			(xy 64.780476 -369.168862) (xy 64.765114 -369.11654) (xy 64.757354 -369.062565) (xy 59.576328 -369.062565)
			(xy 59.576328 -369.062575) (xy 59.568564 -369.11657) (xy 59.553195 -369.168911) (xy 59.530532 -369.218531)
			(xy 59.501038 -369.26442) (xy 59.465312 -369.305645) (xy 59.424084 -369.341365) (xy 59.378191 -369.370854)
			(xy 59.328568 -369.393511) (xy 59.276225 -369.408874) (xy 59.222229 -369.416632) (xy 59.194954 -369.417092)
			(xy 58.331354 -369.417092) (xy 58.304089 -369.416543) (xy 58.250115 -369.408776) (xy 58.197795 -369.393408)
			(xy 58.148194 -369.370751) (xy 58.102323 -369.341266) (xy 58.061114 -369.305554) (xy 58.025406 -369.264341)
			(xy 57.995927 -369.218465) (xy 57.973276 -369.168862) (xy 57.957914 -369.11654) (xy 57.950154 -369.062565)
			(xy 52.769128 -369.062565) (xy 52.769128 -369.062575) (xy 52.761364 -369.11657) (xy 52.745995 -369.168911)
			(xy 52.723332 -369.218531) (xy 52.693838 -369.26442) (xy 52.658112 -369.305645) (xy 52.616884 -369.341365)
			(xy 52.570991 -369.370854) (xy 52.521368 -369.393511) (xy 52.469025 -369.408874) (xy 52.415029 -369.416632)
			(xy 52.387754 -369.417092) (xy 51.524154 -369.417092) (xy 51.496889 -369.416543) (xy 51.442915 -369.408776)
			(xy 51.390595 -369.393408) (xy 51.340994 -369.370751) (xy 51.295123 -369.341266) (xy 51.253914 -369.305554)
			(xy 51.218206 -369.264341) (xy 51.188727 -369.218465) (xy 51.166076 -369.168862) (xy 51.150714 -369.11654)
			(xy 51.142954 -369.062565) (xy 45.961928 -369.062565) (xy 45.961928 -369.062575) (xy 45.954164 -369.11657)
			(xy 45.938795 -369.168911) (xy 45.916132 -369.218531) (xy 45.886638 -369.26442) (xy 45.850912 -369.305645)
			(xy 45.809684 -369.341365) (xy 45.763791 -369.370854) (xy 45.714168 -369.393511) (xy 45.661825 -369.408874)
			(xy 45.607829 -369.416632) (xy 45.580554 -369.417092) (xy 44.716954 -369.417092) (xy 44.689689 -369.416543)
			(xy 44.635715 -369.408776) (xy 44.583395 -369.393408) (xy 44.533794 -369.370751) (xy 44.487923 -369.341266)
			(xy 44.446714 -369.305554) (xy 44.411006 -369.264341) (xy 44.381527 -369.218465) (xy 44.358876 -369.168862)
			(xy 44.343514 -369.11654) (xy 44.335754 -369.062565) (xy 2.509012 -369.062565) (xy 2.509012 -370.206778)
			(xy 138.3665 -370.206778) (xy 138.3665 -369.343178) (xy 138.366986 -369.315909) (xy 138.374748 -369.261925)
			(xy 138.390113 -369.209595) (xy 138.41277 -369.159985) (xy 138.442256 -369.114104) (xy 138.477971 -369.072887)
			(xy 138.519188 -369.037172) (xy 138.565069 -369.007686) (xy 138.614679 -368.985029) (xy 138.667009 -368.969664)
			(xy 138.720993 -368.961902) (xy 138.775531 -368.961902) (xy 138.829515 -368.969664) (xy 138.881845 -368.985029)
			(xy 138.931455 -369.007686) (xy 138.977336 -369.037172) (xy 139.006648 -369.062571) (xy 143.963332 -369.062571)
			(xy 143.963332 -369.008029) (xy 143.971094 -368.954043) (xy 143.986461 -368.901711) (xy 144.009121 -368.852098)
			(xy 144.03861 -368.806216) (xy 144.074329 -368.764998) (xy 144.115551 -368.729284) (xy 144.161437 -368.699799)
			(xy 144.211052 -368.677146) (xy 144.263386 -368.661785) (xy 144.317373 -368.654028) (xy 144.344644 -368.653568)
			(xy 145.208244 -368.653568) (xy 145.235513 -368.653998) (xy 145.289497 -368.661765) (xy 145.341825 -368.677135)
			(xy 145.391433 -368.699796) (xy 145.437312 -368.729285) (xy 145.478528 -368.765003) (xy 145.514241 -368.806223)
			(xy 145.543725 -368.852105) (xy 145.56638 -368.901716) (xy 145.581744 -368.954047) (xy 145.589506 -369.00803)
			(xy 145.589506 -369.06257) (xy 145.589506 -369.062571) (xy 150.770532 -369.062571) (xy 150.770532 -369.008029)
			(xy 150.778294 -368.954043) (xy 150.793661 -368.901711) (xy 150.816321 -368.852098) (xy 150.84581 -368.806216)
			(xy 150.881529 -368.764998) (xy 150.922751 -368.729284) (xy 150.968637 -368.699799) (xy 151.018252 -368.677146)
			(xy 151.070586 -368.661785) (xy 151.124573 -368.654028) (xy 151.151844 -368.653568) (xy 152.015444 -368.653568)
			(xy 152.042713 -368.653998) (xy 152.096697 -368.661765) (xy 152.149025 -368.677135) (xy 152.198633 -368.699796)
			(xy 152.244512 -368.729285) (xy 152.285728 -368.765003) (xy 152.321441 -368.806223) (xy 152.350925 -368.852105)
			(xy 152.37358 -368.901716) (xy 152.388944 -368.954047) (xy 152.396706 -369.00803) (xy 152.396706 -369.06257)
			(xy 152.396706 -369.062571) (xy 157.577732 -369.062571) (xy 157.577732 -369.008029) (xy 157.585494 -368.954043)
			(xy 157.600861 -368.901711) (xy 157.623521 -368.852098) (xy 157.65301 -368.806216) (xy 157.688729 -368.764998)
			(xy 157.729951 -368.729284) (xy 157.775837 -368.699799) (xy 157.825452 -368.677146) (xy 157.877786 -368.661785)
			(xy 157.931773 -368.654028) (xy 157.959044 -368.653568) (xy 158.822644 -368.653568) (xy 158.849913 -368.653998)
			(xy 158.903897 -368.661765) (xy 158.956225 -368.677135) (xy 159.005833 -368.699796) (xy 159.051712 -368.729285)
			(xy 159.092928 -368.765003) (xy 159.128641 -368.806223) (xy 159.158125 -368.852105) (xy 159.18078 -368.901716)
			(xy 159.196144 -368.954047) (xy 159.203906 -369.00803) (xy 159.203906 -369.06257) (xy 159.203906 -369.062571)
			(xy 164.384932 -369.062571) (xy 164.384932 -369.008029) (xy 164.392694 -368.954043) (xy 164.408061 -368.901711)
			(xy 164.430721 -368.852098) (xy 164.46021 -368.806216) (xy 164.495929 -368.764998) (xy 164.537151 -368.729284)
			(xy 164.583037 -368.699799) (xy 164.632652 -368.677146) (xy 164.684986 -368.661785) (xy 164.738973 -368.654028)
			(xy 164.766244 -368.653568) (xy 165.629844 -368.653568) (xy 165.657113 -368.653998) (xy 165.711097 -368.661765)
			(xy 165.763425 -368.677135) (xy 165.813033 -368.699796) (xy 165.858912 -368.729285) (xy 165.900128 -368.765003)
			(xy 165.935841 -368.806223) (xy 165.965325 -368.852105) (xy 165.98798 -368.901716) (xy 166.003344 -368.954047)
			(xy 166.011106 -369.00803) (xy 166.011106 -369.06257) (xy 166.011106 -369.062571) (xy 167.788532 -369.062571)
			(xy 167.788532 -369.008029) (xy 167.796294 -368.954043) (xy 167.811661 -368.901711) (xy 167.834321 -368.852098)
			(xy 167.86381 -368.806216) (xy 167.899529 -368.764998) (xy 167.940751 -368.729284) (xy 167.986637 -368.699799)
			(xy 168.036252 -368.677146) (xy 168.088586 -368.661785) (xy 168.142573 -368.654028) (xy 168.169844 -368.653568)
			(xy 169.033444 -368.653568) (xy 169.060713 -368.653998) (xy 169.114697 -368.661765) (xy 169.167025 -368.677135)
			(xy 169.216633 -368.699796) (xy 169.262512 -368.729285) (xy 169.303728 -368.765003) (xy 169.339441 -368.806223)
			(xy 169.368925 -368.852105) (xy 169.39158 -368.901716) (xy 169.406944 -368.954047) (xy 169.414706 -369.00803)
			(xy 169.414706 -369.06257) (xy 169.406944 -369.116553) (xy 169.39158 -369.168884) (xy 169.368925 -369.218495)
			(xy 169.339441 -369.264377) (xy 169.303728 -369.305597) (xy 169.262512 -369.341315) (xy 169.216633 -369.370804)
			(xy 169.167025 -369.393465) (xy 169.114697 -369.408835) (xy 169.060713 -369.416602) (xy 169.033444 -369.417092)
			(xy 168.169844 -369.417092) (xy 168.142573 -369.416572) (xy 168.088586 -369.408815) (xy 168.036252 -369.393454)
			(xy 167.986637 -369.370801) (xy 167.940751 -369.341316) (xy 167.899529 -369.305602) (xy 167.86381 -369.264384)
			(xy 167.834321 -369.218502) (xy 167.811661 -369.168889) (xy 167.796294 -369.116557) (xy 167.788532 -369.062571)
			(xy 166.011106 -369.062571) (xy 166.003344 -369.116553) (xy 165.98798 -369.168884) (xy 165.965325 -369.218495)
			(xy 165.935841 -369.264377) (xy 165.900128 -369.305597) (xy 165.858912 -369.341315) (xy 165.813033 -369.370804)
			(xy 165.763425 -369.393465) (xy 165.711097 -369.408835) (xy 165.657113 -369.416602) (xy 165.629844 -369.417092)
			(xy 164.766244 -369.417092) (xy 164.738973 -369.416572) (xy 164.684986 -369.408815) (xy 164.632652 -369.393454)
			(xy 164.583037 -369.370801) (xy 164.537151 -369.341316) (xy 164.495929 -369.305602) (xy 164.46021 -369.264384)
			(xy 164.430721 -369.218502) (xy 164.408061 -369.168889) (xy 164.392694 -369.116557) (xy 164.384932 -369.062571)
			(xy 159.203906 -369.062571) (xy 159.196144 -369.116553) (xy 159.18078 -369.168884) (xy 159.158125 -369.218495)
			(xy 159.128641 -369.264377) (xy 159.092928 -369.305597) (xy 159.051712 -369.341315) (xy 159.005833 -369.370804)
			(xy 158.956225 -369.393465) (xy 158.903897 -369.408835) (xy 158.849913 -369.416602) (xy 158.822644 -369.417092)
			(xy 157.959044 -369.417092) (xy 157.931773 -369.416572) (xy 157.877786 -369.408815) (xy 157.825452 -369.393454)
			(xy 157.775837 -369.370801) (xy 157.729951 -369.341316) (xy 157.688729 -369.305602) (xy 157.65301 -369.264384)
			(xy 157.623521 -369.218502) (xy 157.600861 -369.168889) (xy 157.585494 -369.116557) (xy 157.577732 -369.062571)
			(xy 152.396706 -369.062571) (xy 152.388944 -369.116553) (xy 152.37358 -369.168884) (xy 152.350925 -369.218495)
			(xy 152.321441 -369.264377) (xy 152.285728 -369.305597) (xy 152.244512 -369.341315) (xy 152.198633 -369.370804)
			(xy 152.149025 -369.393465) (xy 152.096697 -369.408835) (xy 152.042713 -369.416602) (xy 152.015444 -369.417092)
			(xy 151.151844 -369.417092) (xy 151.124573 -369.416572) (xy 151.070586 -369.408815) (xy 151.018252 -369.393454)
			(xy 150.968637 -369.370801) (xy 150.922751 -369.341316) (xy 150.881529 -369.305602) (xy 150.84581 -369.264384)
			(xy 150.816321 -369.218502) (xy 150.793661 -369.168889) (xy 150.778294 -369.116557) (xy 150.770532 -369.062571)
			(xy 145.589506 -369.062571) (xy 145.581744 -369.116553) (xy 145.56638 -369.168884) (xy 145.543725 -369.218495)
			(xy 145.514241 -369.264377) (xy 145.478528 -369.305597) (xy 145.437312 -369.341315) (xy 145.391433 -369.370804)
			(xy 145.341825 -369.393465) (xy 145.289497 -369.408835) (xy 145.235513 -369.416602) (xy 145.208244 -369.417092)
			(xy 144.344644 -369.417092) (xy 144.317373 -369.416572) (xy 144.263386 -369.408815) (xy 144.211052 -369.393454)
			(xy 144.161437 -369.370801) (xy 144.115551 -369.341316) (xy 144.074329 -369.305602) (xy 144.03861 -369.264384)
			(xy 144.009121 -369.218502) (xy 143.986461 -369.168889) (xy 143.971094 -369.116557) (xy 143.963332 -369.062571)
			(xy 139.006648 -369.062571) (xy 139.018553 -369.072887) (xy 139.054268 -369.114104) (xy 139.083754 -369.159985)
			(xy 139.106411 -369.209595) (xy 139.121776 -369.261925) (xy 139.129538 -369.315909) (xy 139.130024 -369.343178)
			(xy 139.130024 -370.206778) (xy 139.129538 -370.234047) (xy 139.121776 -370.288031) (xy 139.106411 -370.340361)
			(xy 139.083754 -370.389971) (xy 139.071223 -370.40947) (xy 141.572996 -370.40947) (xy 141.572996 -369.54587)
			(xy 141.573482 -369.518619) (xy 141.581238 -369.464671) (xy 141.596593 -369.412376) (xy 141.619235 -369.362799)
			(xy 141.648701 -369.316949) (xy 141.684392 -369.275758) (xy 141.725583 -369.240067) (xy 141.771433 -369.210601)
			(xy 141.82101 -369.187959) (xy 141.873305 -369.172604) (xy 141.927253 -369.164848) (xy 141.981755 -369.164848)
			(xy 142.035703 -369.172604) (xy 142.087998 -369.187959) (xy 142.137575 -369.210601) (xy 142.183425 -369.240067)
			(xy 142.224616 -369.275758) (xy 142.260307 -369.316949) (xy 142.289773 -369.362799) (xy 142.312415 -369.412376)
			(xy 142.32777 -369.464671) (xy 142.335526 -369.518619) (xy 142.336012 -369.54587) (xy 142.336012 -369.62565)
			(xy 175.203103 -369.62565) (xy 175.203103 -369.57115) (xy 175.210859 -369.517206) (xy 175.226214 -369.464914)
			(xy 175.248854 -369.41534) (xy 175.278318 -369.369493) (xy 175.314008 -369.328305) (xy 175.355196 -369.292616)
			(xy 175.401044 -369.263152) (xy 175.450618 -369.240512) (xy 175.50291 -369.225158) (xy 175.556854 -369.217403)
			(xy 175.584104 -369.21694) (xy 176.447704 -369.21694) (xy 176.474958 -369.21733) (xy 176.528913 -369.225088)
			(xy 176.581213 -369.240446) (xy 176.630796 -369.26309) (xy 176.676652 -369.29256) (xy 176.717847 -369.328256)
			(xy 176.753543 -369.369451) (xy 176.783012 -369.415307) (xy 176.805656 -369.46489) (xy 176.821013 -369.517191)
			(xy 176.82877 -369.571146) (xy 176.82877 -369.625654) (xy 176.821013 -369.679609) (xy 176.805656 -369.73191)
			(xy 176.783012 -369.781493) (xy 176.753543 -369.827349) (xy 176.717847 -369.868544) (xy 176.676652 -369.90424)
			(xy 176.630796 -369.93371) (xy 176.581213 -369.956354) (xy 176.528913 -369.971712) (xy 176.474958 -369.97947)
			(xy 176.447704 -369.979956) (xy 175.584104 -369.979956) (xy 175.556854 -369.979397) (xy 175.50291 -369.971642)
			(xy 175.450618 -369.956288) (xy 175.401044 -369.933648) (xy 175.355196 -369.904184) (xy 175.314008 -369.868495)
			(xy 175.278318 -369.827307) (xy 175.248854 -369.78146) (xy 175.226214 -369.731886) (xy 175.210859 -369.679594)
			(xy 175.203103 -369.62565) (xy 142.336012 -369.62565) (xy 142.336012 -370.40947) (xy 142.335526 -370.436721)
			(xy 142.32777 -370.490669) (xy 142.312415 -370.542964) (xy 142.289773 -370.592541) (xy 142.260307 -370.638391)
			(xy 142.224616 -370.679582) (xy 142.183425 -370.715273) (xy 142.137575 -370.744739) (xy 142.087998 -370.767381)
			(xy 142.035703 -370.782736) (xy 141.981755 -370.790492) (xy 141.927253 -370.790492) (xy 141.873305 -370.782736)
			(xy 141.82101 -370.767381) (xy 141.771433 -370.744739) (xy 141.725583 -370.715273) (xy 141.684392 -370.679582)
			(xy 141.648701 -370.638391) (xy 141.619235 -370.592541) (xy 141.596593 -370.542964) (xy 141.581238 -370.490669)
			(xy 141.573482 -370.436721) (xy 141.572996 -370.40947) (xy 139.071223 -370.40947) (xy 139.054268 -370.435852)
			(xy 139.018553 -370.477069) (xy 138.977336 -370.512784) (xy 138.931455 -370.54227) (xy 138.881845 -370.564927)
			(xy 138.829515 -370.580292) (xy 138.775531 -370.588054) (xy 138.720993 -370.588054) (xy 138.667009 -370.580292)
			(xy 138.614679 -370.564927) (xy 138.565069 -370.54227) (xy 138.519188 -370.512784) (xy 138.477971 -370.477069)
			(xy 138.442256 -370.435852) (xy 138.41277 -370.389971) (xy 138.390113 -370.340361) (xy 138.374748 -370.288031)
			(xy 138.366986 -370.234047) (xy 138.3665 -370.206778) (xy 2.509012 -370.206778) (xy 2.509012 -371.526365)
			(xy 42.633954 -371.526365) (xy 42.633954 -371.471835) (xy 42.641714 -371.41786) (xy 42.657076 -371.365538)
			(xy 42.679727 -371.315935) (xy 42.709206 -371.270059) (xy 42.744914 -371.228846) (xy 42.786123 -371.193134)
			(xy 42.831994 -371.163649) (xy 42.881595 -371.140992) (xy 42.933915 -371.125624) (xy 42.987889 -371.117857)
			(xy 43.015154 -371.117368) (xy 43.878754 -371.117368) (xy 43.906029 -371.117768) (xy 43.960025 -371.125526)
			(xy 44.012368 -371.140889) (xy 44.061991 -371.163546) (xy 44.107884 -371.193035) (xy 44.149112 -371.228755)
			(xy 44.184838 -371.26998) (xy 44.214332 -371.315869) (xy 44.236995 -371.365489) (xy 44.252364 -371.41783)
			(xy 44.260128 -371.471825) (xy 44.260128 -371.526365) (xy 49.441154 -371.526365) (xy 49.441154 -371.471835)
			(xy 49.448914 -371.41786) (xy 49.464276 -371.365538) (xy 49.486927 -371.315935) (xy 49.516406 -371.270059)
			(xy 49.552114 -371.228846) (xy 49.593323 -371.193134) (xy 49.639194 -371.163649) (xy 49.688795 -371.140992)
			(xy 49.741115 -371.125624) (xy 49.795089 -371.117857) (xy 49.822354 -371.117368) (xy 50.685954 -371.117368)
			(xy 50.713229 -371.117768) (xy 50.767225 -371.125526) (xy 50.819568 -371.140889) (xy 50.869191 -371.163546)
			(xy 50.915084 -371.193035) (xy 50.956312 -371.228755) (xy 50.992038 -371.26998) (xy 51.021532 -371.315869)
			(xy 51.044195 -371.365489) (xy 51.059564 -371.41783) (xy 51.067328 -371.471825) (xy 51.067328 -371.526365)
			(xy 56.248354 -371.526365) (xy 56.248354 -371.471835) (xy 56.256114 -371.41786) (xy 56.271476 -371.365538)
			(xy 56.294127 -371.315935) (xy 56.323606 -371.270059) (xy 56.359314 -371.228846) (xy 56.400523 -371.193134)
			(xy 56.446394 -371.163649) (xy 56.495995 -371.140992) (xy 56.548315 -371.125624) (xy 56.602289 -371.117857)
			(xy 56.629554 -371.117368) (xy 57.493154 -371.117368) (xy 57.520429 -371.117768) (xy 57.574425 -371.125526)
			(xy 57.626768 -371.140889) (xy 57.676391 -371.163546) (xy 57.722284 -371.193035) (xy 57.763512 -371.228755)
			(xy 57.799238 -371.26998) (xy 57.828732 -371.315869) (xy 57.851395 -371.365489) (xy 57.866764 -371.41783)
			(xy 57.874528 -371.471825) (xy 57.874528 -371.526365) (xy 63.055554 -371.526365) (xy 63.055554 -371.471835)
			(xy 63.063314 -371.41786) (xy 63.078676 -371.365538) (xy 63.101327 -371.315935) (xy 63.130806 -371.270059)
			(xy 63.166514 -371.228846) (xy 63.207723 -371.193134) (xy 63.253594 -371.163649) (xy 63.303195 -371.140992)
			(xy 63.355515 -371.125624) (xy 63.409489 -371.117857) (xy 63.436754 -371.117368) (xy 64.300354 -371.117368)
			(xy 64.327629 -371.117768) (xy 64.381625 -371.125526) (xy 64.433968 -371.140889) (xy 64.483591 -371.163546)
			(xy 64.529484 -371.193035) (xy 64.570712 -371.228755) (xy 64.606438 -371.26998) (xy 64.635932 -371.315869)
			(xy 64.658595 -371.365489) (xy 64.673964 -371.41783) (xy 64.681728 -371.471825) (xy 64.681728 -371.526369)
			(xy 75.161631 -371.526369) (xy 75.161631 -371.471831) (xy 75.169393 -371.417848) (xy 75.184758 -371.36552)
			(xy 75.207414 -371.31591) (xy 75.2369 -371.27003) (xy 75.272614 -371.228813) (xy 75.313832 -371.193098)
			(xy 75.359712 -371.163613) (xy 75.409321 -371.140957) (xy 75.46165 -371.125593) (xy 75.515633 -371.117831)
			(xy 75.542902 -371.117368) (xy 76.406502 -371.117368) (xy 76.433773 -371.117795) (xy 76.487761 -371.125557)
			(xy 76.540094 -371.140924) (xy 76.589708 -371.163582) (xy 76.635593 -371.19307) (xy 76.676813 -371.228788)
			(xy 76.712531 -371.270009) (xy 76.742019 -371.315893) (xy 76.764677 -371.365507) (xy 76.780043 -371.417841)
			(xy 76.787806 -371.471829) (xy 76.787806 -371.526369) (xy 81.968831 -371.526369) (xy 81.968831 -371.471831)
			(xy 81.976593 -371.417848) (xy 81.991958 -371.36552) (xy 82.014614 -371.31591) (xy 82.0441 -371.27003)
			(xy 82.079814 -371.228813) (xy 82.121032 -371.193098) (xy 82.166912 -371.163613) (xy 82.216521 -371.140957)
			(xy 82.26885 -371.125593) (xy 82.322833 -371.117831) (xy 82.350102 -371.117368) (xy 83.213702 -371.117368)
			(xy 83.240973 -371.117795) (xy 83.294961 -371.125557) (xy 83.347294 -371.140924) (xy 83.396908 -371.163582)
			(xy 83.442793 -371.19307) (xy 83.484013 -371.228788) (xy 83.519731 -371.270009) (xy 83.549219 -371.315893)
			(xy 83.571877 -371.365507) (xy 83.587243 -371.417841) (xy 83.595006 -371.471829) (xy 83.595006 -371.526369)
			(xy 88.776031 -371.526369) (xy 88.776031 -371.471831) (xy 88.783793 -371.417848) (xy 88.799158 -371.36552)
			(xy 88.821814 -371.31591) (xy 88.8513 -371.27003) (xy 88.887014 -371.228813) (xy 88.928232 -371.193098)
			(xy 88.974112 -371.163613) (xy 89.023721 -371.140957) (xy 89.07605 -371.125593) (xy 89.130033 -371.117831)
			(xy 89.157302 -371.117368) (xy 90.020902 -371.117368) (xy 90.048173 -371.117795) (xy 90.102161 -371.125557)
			(xy 90.154494 -371.140924) (xy 90.204108 -371.163582) (xy 90.249993 -371.19307) (xy 90.291213 -371.228788)
			(xy 90.326931 -371.270009) (xy 90.356419 -371.315893) (xy 90.379077 -371.365507) (xy 90.394443 -371.417841)
			(xy 90.402206 -371.471829) (xy 90.402206 -371.526369) (xy 95.583231 -371.526369) (xy 95.583231 -371.471831)
			(xy 95.590993 -371.417848) (xy 95.606358 -371.36552) (xy 95.629014 -371.31591) (xy 95.6585 -371.27003)
			(xy 95.694214 -371.228813) (xy 95.735432 -371.193098) (xy 95.781312 -371.163613) (xy 95.830921 -371.140957)
			(xy 95.88325 -371.125593) (xy 95.937233 -371.117831) (xy 95.964502 -371.117368) (xy 96.828102 -371.117368)
			(xy 96.855373 -371.117795) (xy 96.909361 -371.125557) (xy 96.961694 -371.140924) (xy 97.011308 -371.163582)
			(xy 97.057193 -371.19307) (xy 97.098413 -371.228788) (xy 97.134131 -371.270009) (xy 97.163619 -371.315893)
			(xy 97.186277 -371.365507) (xy 97.201643 -371.417841) (xy 97.209406 -371.471829) (xy 97.209406 -371.526367)
			(xy 109.733854 -371.526367) (xy 109.733854 -371.471833) (xy 109.741615 -371.417854) (xy 109.756979 -371.365529)
			(xy 109.779633 -371.315923) (xy 109.809117 -371.270046) (xy 109.844829 -371.228831) (xy 109.886042 -371.193119)
			(xy 109.931919 -371.163635) (xy 109.981525 -371.140981) (xy 110.03385 -371.125616) (xy 110.087829 -371.117855)
			(xy 110.115096 -371.117368) (xy 110.978696 -371.117368) (xy 111.005969 -371.117771) (xy 111.059961 -371.125534)
			(xy 111.112298 -371.140901) (xy 111.161916 -371.16356) (xy 111.207803 -371.19305) (xy 111.249027 -371.22877)
			(xy 111.284748 -371.269993) (xy 111.314238 -371.315881) (xy 111.336898 -371.365498) (xy 111.352266 -371.417835)
			(xy 111.360028 -371.471827) (xy 111.360028 -371.526367) (xy 116.541054 -371.526367) (xy 116.541054 -371.471833)
			(xy 116.548815 -371.417854) (xy 116.564179 -371.365529) (xy 116.586833 -371.315923) (xy 116.616317 -371.270046)
			(xy 116.652029 -371.228831) (xy 116.693242 -371.193119) (xy 116.739119 -371.163635) (xy 116.788725 -371.140981)
			(xy 116.84105 -371.125616) (xy 116.895029 -371.117855) (xy 116.922296 -371.117368) (xy 117.785896 -371.117368)
			(xy 117.813169 -371.117771) (xy 117.867161 -371.125534) (xy 117.919498 -371.140901) (xy 117.969116 -371.16356)
			(xy 118.015003 -371.19305) (xy 118.056227 -371.22877) (xy 118.091948 -371.269993) (xy 118.121438 -371.315881)
			(xy 118.144098 -371.365498) (xy 118.159466 -371.417835) (xy 118.167228 -371.471827) (xy 118.167228 -371.526367)
			(xy 123.348254 -371.526367) (xy 123.348254 -371.471833) (xy 123.356015 -371.417854) (xy 123.371379 -371.365529)
			(xy 123.394033 -371.315923) (xy 123.423517 -371.270046) (xy 123.459229 -371.228831) (xy 123.500442 -371.193119)
			(xy 123.546319 -371.163635) (xy 123.595925 -371.140981) (xy 123.64825 -371.125616) (xy 123.702229 -371.117855)
			(xy 123.729496 -371.117368) (xy 124.593096 -371.117368) (xy 124.620369 -371.117771) (xy 124.674361 -371.125534)
			(xy 124.726698 -371.140901) (xy 124.776316 -371.16356) (xy 124.822203 -371.19305) (xy 124.863427 -371.22877)
			(xy 124.899148 -371.269993) (xy 124.928638 -371.315881) (xy 124.951298 -371.365498) (xy 124.966666 -371.417835)
			(xy 124.974428 -371.471827) (xy 124.974428 -371.526367) (xy 130.155454 -371.526367) (xy 130.155454 -371.471833)
			(xy 130.163215 -371.417854) (xy 130.178579 -371.365529) (xy 130.201233 -371.315923) (xy 130.230717 -371.270046)
			(xy 130.266429 -371.228831) (xy 130.307642 -371.193119) (xy 130.353519 -371.163635) (xy 130.403125 -371.140981)
			(xy 130.45545 -371.125616) (xy 130.509429 -371.117855) (xy 130.536696 -371.117368) (xy 131.400296 -371.117368)
			(xy 131.427569 -371.117771) (xy 131.481561 -371.125534) (xy 131.533898 -371.140901) (xy 131.583516 -371.16356)
			(xy 131.629403 -371.19305) (xy 131.670627 -371.22877) (xy 131.706348 -371.269993) (xy 131.735838 -371.315881)
			(xy 131.758498 -371.365498) (xy 131.773866 -371.417835) (xy 131.781628 -371.471827) (xy 131.781628 -371.526371)
			(xy 142.261532 -371.526371) (xy 142.261532 -371.471829) (xy 142.269294 -371.417843) (xy 142.284661 -371.365511)
			(xy 142.307321 -371.315898) (xy 142.33681 -371.270016) (xy 142.372529 -371.228798) (xy 142.413751 -371.193084)
			(xy 142.459637 -371.163599) (xy 142.509252 -371.140946) (xy 142.561586 -371.125585) (xy 142.615573 -371.117828)
			(xy 142.642844 -371.117368) (xy 143.506444 -371.117368) (xy 143.533713 -371.117798) (xy 143.587697 -371.125565)
			(xy 143.640025 -371.140935) (xy 143.689633 -371.163596) (xy 143.735512 -371.193085) (xy 143.776728 -371.228803)
			(xy 143.812441 -371.270023) (xy 143.841925 -371.315905) (xy 143.86458 -371.365516) (xy 143.879944 -371.417847)
			(xy 143.887706 -371.47183) (xy 143.887706 -371.52637) (xy 143.887706 -371.526371) (xy 149.068732 -371.526371)
			(xy 149.068732 -371.471829) (xy 149.076494 -371.417843) (xy 149.091861 -371.365511) (xy 149.114521 -371.315898)
			(xy 149.14401 -371.270016) (xy 149.179729 -371.228798) (xy 149.220951 -371.193084) (xy 149.266837 -371.163599)
			(xy 149.316452 -371.140946) (xy 149.368786 -371.125585) (xy 149.422773 -371.117828) (xy 149.450044 -371.117368)
			(xy 150.313644 -371.117368) (xy 150.340913 -371.117798) (xy 150.394897 -371.125565) (xy 150.447225 -371.140935)
			(xy 150.496833 -371.163596) (xy 150.542712 -371.193085) (xy 150.583928 -371.228803) (xy 150.619641 -371.270023)
			(xy 150.649125 -371.315905) (xy 150.67178 -371.365516) (xy 150.687144 -371.417847) (xy 150.694906 -371.47183)
			(xy 150.694906 -371.52637) (xy 150.694906 -371.526371) (xy 155.875932 -371.526371) (xy 155.875932 -371.471829)
			(xy 155.883694 -371.417843) (xy 155.899061 -371.365511) (xy 155.921721 -371.315898) (xy 155.95121 -371.270016)
			(xy 155.986929 -371.228798) (xy 156.028151 -371.193084) (xy 156.074037 -371.163599) (xy 156.123652 -371.140946)
			(xy 156.175986 -371.125585) (xy 156.229973 -371.117828) (xy 156.257244 -371.117368) (xy 157.120844 -371.117368)
			(xy 157.148113 -371.117798) (xy 157.202097 -371.125565) (xy 157.254425 -371.140935) (xy 157.304033 -371.163596)
			(xy 157.349912 -371.193085) (xy 157.391128 -371.228803) (xy 157.426841 -371.270023) (xy 157.456325 -371.315905)
			(xy 157.47898 -371.365516) (xy 157.494344 -371.417847) (xy 157.502106 -371.47183) (xy 157.502106 -371.52637)
			(xy 157.502106 -371.526371) (xy 162.683132 -371.526371) (xy 162.683132 -371.471829) (xy 162.690894 -371.417843)
			(xy 162.706261 -371.365511) (xy 162.728921 -371.315898) (xy 162.75841 -371.270016) (xy 162.794129 -371.228798)
			(xy 162.835351 -371.193084) (xy 162.881237 -371.163599) (xy 162.930852 -371.140946) (xy 162.983186 -371.125585)
			(xy 163.037173 -371.117828) (xy 163.064444 -371.117368) (xy 163.928044 -371.117368) (xy 163.955313 -371.117798)
			(xy 164.009297 -371.125565) (xy 164.061625 -371.140935) (xy 164.111233 -371.163596) (xy 164.157112 -371.193085)
			(xy 164.198328 -371.228803) (xy 164.234041 -371.270023) (xy 164.263525 -371.315905) (xy 164.28618 -371.365516)
			(xy 164.301544 -371.417847) (xy 164.309306 -371.47183) (xy 164.309306 -371.52637) (xy 164.301544 -371.580353)
			(xy 164.28618 -371.632684) (xy 164.263525 -371.682295) (xy 164.234041 -371.728177) (xy 164.198328 -371.769397)
			(xy 164.157112 -371.805115) (xy 164.111233 -371.834604) (xy 164.061625 -371.857265) (xy 164.009297 -371.872635)
			(xy 163.955313 -371.880402) (xy 163.928044 -371.880892) (xy 163.064444 -371.880892) (xy 163.037173 -371.880372)
			(xy 162.983186 -371.872615) (xy 162.930852 -371.857254) (xy 162.881237 -371.834601) (xy 162.835351 -371.805116)
			(xy 162.794129 -371.769402) (xy 162.75841 -371.728184) (xy 162.728921 -371.682302) (xy 162.706261 -371.632689)
			(xy 162.690894 -371.580357) (xy 162.683132 -371.526371) (xy 157.502106 -371.526371) (xy 157.494344 -371.580353)
			(xy 157.47898 -371.632684) (xy 157.456325 -371.682295) (xy 157.426841 -371.728177) (xy 157.391128 -371.769397)
			(xy 157.349912 -371.805115) (xy 157.304033 -371.834604) (xy 157.254425 -371.857265) (xy 157.202097 -371.872635)
			(xy 157.148113 -371.880402) (xy 157.120844 -371.880892) (xy 156.257244 -371.880892) (xy 156.229973 -371.880372)
			(xy 156.175986 -371.872615) (xy 156.123652 -371.857254) (xy 156.074037 -371.834601) (xy 156.028151 -371.805116)
			(xy 155.986929 -371.769402) (xy 155.95121 -371.728184) (xy 155.921721 -371.682302) (xy 155.899061 -371.632689)
			(xy 155.883694 -371.580357) (xy 155.875932 -371.526371) (xy 150.694906 -371.526371) (xy 150.687144 -371.580353)
			(xy 150.67178 -371.632684) (xy 150.649125 -371.682295) (xy 150.619641 -371.728177) (xy 150.583928 -371.769397)
			(xy 150.542712 -371.805115) (xy 150.496833 -371.834604) (xy 150.447225 -371.857265) (xy 150.394897 -371.872635)
			(xy 150.340913 -371.880402) (xy 150.313644 -371.880892) (xy 149.450044 -371.880892) (xy 149.422773 -371.880372)
			(xy 149.368786 -371.872615) (xy 149.316452 -371.857254) (xy 149.266837 -371.834601) (xy 149.220951 -371.805116)
			(xy 149.179729 -371.769402) (xy 149.14401 -371.728184) (xy 149.114521 -371.682302) (xy 149.091861 -371.632689)
			(xy 149.076494 -371.580357) (xy 149.068732 -371.526371) (xy 143.887706 -371.526371) (xy 143.879944 -371.580353)
			(xy 143.86458 -371.632684) (xy 143.841925 -371.682295) (xy 143.812441 -371.728177) (xy 143.776728 -371.769397)
			(xy 143.735512 -371.805115) (xy 143.689633 -371.834604) (xy 143.640025 -371.857265) (xy 143.587697 -371.872635)
			(xy 143.533713 -371.880402) (xy 143.506444 -371.880892) (xy 142.642844 -371.880892) (xy 142.615573 -371.880372)
			(xy 142.561586 -371.872615) (xy 142.509252 -371.857254) (xy 142.459637 -371.834601) (xy 142.413751 -371.805116)
			(xy 142.372529 -371.769402) (xy 142.33681 -371.728184) (xy 142.307321 -371.682302) (xy 142.284661 -371.632689)
			(xy 142.269294 -371.580357) (xy 142.261532 -371.526371) (xy 131.781628 -371.526371) (xy 131.781628 -371.526373)
			(xy 131.773866 -371.580365) (xy 131.758498 -371.632702) (xy 131.735838 -371.682319) (xy 131.706348 -371.728207)
			(xy 131.670627 -371.76943) (xy 131.629403 -371.80515) (xy 131.583516 -371.83464) (xy 131.533898 -371.857299)
			(xy 131.481561 -371.872666) (xy 131.427569 -371.880429) (xy 131.400296 -371.880892) (xy 130.536696 -371.880892)
			(xy 130.509429 -371.880345) (xy 130.45545 -371.872584) (xy 130.403125 -371.857219) (xy 130.353519 -371.834565)
			(xy 130.307642 -371.805081) (xy 130.266429 -371.769369) (xy 130.230717 -371.728154) (xy 130.201233 -371.682277)
			(xy 130.178579 -371.632671) (xy 130.163215 -371.580346) (xy 130.155454 -371.526367) (xy 124.974428 -371.526367)
			(xy 124.974428 -371.526373) (xy 124.966666 -371.580365) (xy 124.951298 -371.632702) (xy 124.928638 -371.682319)
			(xy 124.899148 -371.728207) (xy 124.863427 -371.76943) (xy 124.822203 -371.80515) (xy 124.776316 -371.83464)
			(xy 124.726698 -371.857299) (xy 124.674361 -371.872666) (xy 124.620369 -371.880429) (xy 124.593096 -371.880892)
			(xy 123.729496 -371.880892) (xy 123.702229 -371.880345) (xy 123.64825 -371.872584) (xy 123.595925 -371.857219)
			(xy 123.546319 -371.834565) (xy 123.500442 -371.805081) (xy 123.459229 -371.769369) (xy 123.423517 -371.728154)
			(xy 123.394033 -371.682277) (xy 123.371379 -371.632671) (xy 123.356015 -371.580346) (xy 123.348254 -371.526367)
			(xy 118.167228 -371.526367) (xy 118.167228 -371.526373) (xy 118.159466 -371.580365) (xy 118.144098 -371.632702)
			(xy 118.121438 -371.682319) (xy 118.091948 -371.728207) (xy 118.056227 -371.76943) (xy 118.015003 -371.80515)
			(xy 117.969116 -371.83464) (xy 117.919498 -371.857299) (xy 117.867161 -371.872666) (xy 117.813169 -371.880429)
			(xy 117.785896 -371.880892) (xy 116.922296 -371.880892) (xy 116.895029 -371.880345) (xy 116.84105 -371.872584)
			(xy 116.788725 -371.857219) (xy 116.739119 -371.834565) (xy 116.693242 -371.805081) (xy 116.652029 -371.769369)
			(xy 116.616317 -371.728154) (xy 116.586833 -371.682277) (xy 116.564179 -371.632671) (xy 116.548815 -371.580346)
			(xy 116.541054 -371.526367) (xy 111.360028 -371.526367) (xy 111.360028 -371.526373) (xy 111.352266 -371.580365)
			(xy 111.336898 -371.632702) (xy 111.314238 -371.682319) (xy 111.284748 -371.728207) (xy 111.249027 -371.76943)
			(xy 111.207803 -371.80515) (xy 111.161916 -371.83464) (xy 111.112298 -371.857299) (xy 111.059961 -371.872666)
			(xy 111.005969 -371.880429) (xy 110.978696 -371.880892) (xy 110.115096 -371.880892) (xy 110.087829 -371.880345)
			(xy 110.03385 -371.872584) (xy 109.981525 -371.857219) (xy 109.931919 -371.834565) (xy 109.886042 -371.805081)
			(xy 109.844829 -371.769369) (xy 109.809117 -371.728154) (xy 109.779633 -371.682277) (xy 109.756979 -371.632671)
			(xy 109.741615 -371.580346) (xy 109.733854 -371.526367) (xy 97.209406 -371.526367) (xy 97.209406 -371.526371)
			(xy 97.201643 -371.580359) (xy 97.186277 -371.632693) (xy 97.163619 -371.682307) (xy 97.134131 -371.728191)
			(xy 97.098413 -371.769412) (xy 97.057193 -371.80513) (xy 97.011308 -371.834618) (xy 96.961694 -371.857276)
			(xy 96.909361 -371.872643) (xy 96.855373 -371.880405) (xy 96.828102 -371.880892) (xy 95.964502 -371.880892)
			(xy 95.937233 -371.880369) (xy 95.88325 -371.872607) (xy 95.830921 -371.857243) (xy 95.781312 -371.834587)
			(xy 95.735432 -371.805102) (xy 95.694214 -371.769387) (xy 95.6585 -371.72817) (xy 95.629014 -371.68229)
			(xy 95.606358 -371.63268) (xy 95.590993 -371.580352) (xy 95.583231 -371.526369) (xy 90.402206 -371.526369)
			(xy 90.402206 -371.526371) (xy 90.394443 -371.580359) (xy 90.379077 -371.632693) (xy 90.356419 -371.682307)
			(xy 90.326931 -371.728191) (xy 90.291213 -371.769412) (xy 90.249993 -371.80513) (xy 90.204108 -371.834618)
			(xy 90.154494 -371.857276) (xy 90.102161 -371.872643) (xy 90.048173 -371.880405) (xy 90.020902 -371.880892)
			(xy 89.157302 -371.880892) (xy 89.130033 -371.880369) (xy 89.07605 -371.872607) (xy 89.023721 -371.857243)
			(xy 88.974112 -371.834587) (xy 88.928232 -371.805102) (xy 88.887014 -371.769387) (xy 88.8513 -371.72817)
			(xy 88.821814 -371.68229) (xy 88.799158 -371.63268) (xy 88.783793 -371.580352) (xy 88.776031 -371.526369)
			(xy 83.595006 -371.526369) (xy 83.595006 -371.526371) (xy 83.587243 -371.580359) (xy 83.571877 -371.632693)
			(xy 83.549219 -371.682307) (xy 83.519731 -371.728191) (xy 83.484013 -371.769412) (xy 83.442793 -371.80513)
			(xy 83.396908 -371.834618) (xy 83.347294 -371.857276) (xy 83.294961 -371.872643) (xy 83.240973 -371.880405)
			(xy 83.213702 -371.880892) (xy 82.350102 -371.880892) (xy 82.322833 -371.880369) (xy 82.26885 -371.872607)
			(xy 82.216521 -371.857243) (xy 82.166912 -371.834587) (xy 82.121032 -371.805102) (xy 82.079814 -371.769387)
			(xy 82.0441 -371.72817) (xy 82.014614 -371.68229) (xy 81.991958 -371.63268) (xy 81.976593 -371.580352)
			(xy 81.968831 -371.526369) (xy 76.787806 -371.526369) (xy 76.787806 -371.526371) (xy 76.780043 -371.580359)
			(xy 76.764677 -371.632693) (xy 76.742019 -371.682307) (xy 76.712531 -371.728191) (xy 76.676813 -371.769412)
			(xy 76.635593 -371.80513) (xy 76.589708 -371.834618) (xy 76.540094 -371.857276) (xy 76.487761 -371.872643)
			(xy 76.433773 -371.880405) (xy 76.406502 -371.880892) (xy 75.542902 -371.880892) (xy 75.515633 -371.880369)
			(xy 75.46165 -371.872607) (xy 75.409321 -371.857243) (xy 75.359712 -371.834587) (xy 75.313832 -371.805102)
			(xy 75.272614 -371.769387) (xy 75.2369 -371.72817) (xy 75.207414 -371.68229) (xy 75.184758 -371.63268)
			(xy 75.169393 -371.580352) (xy 75.161631 -371.526369) (xy 64.681728 -371.526369) (xy 64.681728 -371.526375)
			(xy 64.673964 -371.58037) (xy 64.658595 -371.632711) (xy 64.635932 -371.682331) (xy 64.606438 -371.72822)
			(xy 64.570712 -371.769445) (xy 64.529484 -371.805165) (xy 64.483591 -371.834654) (xy 64.433968 -371.857311)
			(xy 64.381625 -371.872674) (xy 64.327629 -371.880432) (xy 64.300354 -371.880892) (xy 63.436754 -371.880892)
			(xy 63.409489 -371.880343) (xy 63.355515 -371.872576) (xy 63.303195 -371.857208) (xy 63.253594 -371.834551)
			(xy 63.207723 -371.805066) (xy 63.166514 -371.769354) (xy 63.130806 -371.728141) (xy 63.101327 -371.682265)
			(xy 63.078676 -371.632662) (xy 63.063314 -371.58034) (xy 63.055554 -371.526365) (xy 57.874528 -371.526365)
			(xy 57.874528 -371.526375) (xy 57.866764 -371.58037) (xy 57.851395 -371.632711) (xy 57.828732 -371.682331)
			(xy 57.799238 -371.72822) (xy 57.763512 -371.769445) (xy 57.722284 -371.805165) (xy 57.676391 -371.834654)
			(xy 57.626768 -371.857311) (xy 57.574425 -371.872674) (xy 57.520429 -371.880432) (xy 57.493154 -371.880892)
			(xy 56.629554 -371.880892) (xy 56.602289 -371.880343) (xy 56.548315 -371.872576) (xy 56.495995 -371.857208)
			(xy 56.446394 -371.834551) (xy 56.400523 -371.805066) (xy 56.359314 -371.769354) (xy 56.323606 -371.728141)
			(xy 56.294127 -371.682265) (xy 56.271476 -371.632662) (xy 56.256114 -371.58034) (xy 56.248354 -371.526365)
			(xy 51.067328 -371.526365) (xy 51.067328 -371.526375) (xy 51.059564 -371.58037) (xy 51.044195 -371.632711)
			(xy 51.021532 -371.682331) (xy 50.992038 -371.72822) (xy 50.956312 -371.769445) (xy 50.915084 -371.805165)
			(xy 50.869191 -371.834654) (xy 50.819568 -371.857311) (xy 50.767225 -371.872674) (xy 50.713229 -371.880432)
			(xy 50.685954 -371.880892) (xy 49.822354 -371.880892) (xy 49.795089 -371.880343) (xy 49.741115 -371.872576)
			(xy 49.688795 -371.857208) (xy 49.639194 -371.834551) (xy 49.593323 -371.805066) (xy 49.552114 -371.769354)
			(xy 49.516406 -371.728141) (xy 49.486927 -371.682265) (xy 49.464276 -371.632662) (xy 49.448914 -371.58034)
			(xy 49.441154 -371.526365) (xy 44.260128 -371.526365) (xy 44.260128 -371.526375) (xy 44.252364 -371.58037)
			(xy 44.236995 -371.632711) (xy 44.214332 -371.682331) (xy 44.184838 -371.72822) (xy 44.149112 -371.769445)
			(xy 44.107884 -371.805165) (xy 44.061991 -371.834654) (xy 44.012368 -371.857311) (xy 43.960025 -371.872674)
			(xy 43.906029 -371.880432) (xy 43.878754 -371.880892) (xy 43.015154 -371.880892) (xy 42.987889 -371.880343)
			(xy 42.933915 -371.872576) (xy 42.881595 -371.857208) (xy 42.831994 -371.834551) (xy 42.786123 -371.805066)
			(xy 42.744914 -371.769354) (xy 42.709206 -371.728141) (xy 42.679727 -371.682265) (xy 42.657076 -371.632662)
			(xy 42.641714 -371.58034) (xy 42.633954 -371.526365) (xy 2.509012 -371.526365) (xy 2.509012 -376.489976)
			(xy 31.068784 -376.489976) (xy 31.072756 -376.311733) (xy 31.084664 -376.133844) (xy 31.104485 -375.956662)
			(xy 31.132179 -375.780538) (xy 31.167691 -375.605823) (xy 31.210951 -375.432864) (xy 31.261873 -375.262003)
			(xy 31.320356 -375.093581) (xy 31.386283 -374.927931) (xy 31.459524 -374.765382) (xy 31.539934 -374.606257)
			(xy 31.627352 -374.450872) (xy 31.721605 -374.299536) (xy 31.822506 -374.152548) (xy 31.929855 -374.010201)
			(xy 32.043438 -373.872778) (xy 32.163031 -373.740551) (xy 32.288395 -373.613782) (xy 32.419282 -373.492724)
			(xy 32.555431 -373.377617) (xy 32.696573 -373.268689) (xy 32.842428 -373.166157) (xy 32.992705 -373.070223)
			(xy 33.147106 -372.98108) (xy 33.305325 -372.898903) (xy 33.467048 -372.823855) (xy 33.631953 -372.756087)
			(xy 33.799714 -372.695731) (xy 33.969997 -372.642909) (xy 34.142464 -372.597725) (xy 34.316772 -372.560268)
			(xy 34.492576 -372.530614) (xy 34.669526 -372.508821) (xy 34.847272 -372.494931) (xy 35.025459 -372.488974)
			(xy 35.203736 -372.49096) (xy 35.381747 -372.500886) (xy 35.559139 -372.518732) (xy 35.735559 -372.544462)
			(xy 35.910659 -372.578026) (xy 36.08409 -372.619356) (xy 36.255507 -372.668372) (xy 36.42457 -372.724974)
			(xy 36.590945 -372.789052) (xy 36.754299 -372.860478) (xy 36.91431 -372.93911) (xy 37.070659 -373.024791)
			(xy 37.223036 -373.117353) (xy 37.371139 -373.21661) (xy 37.514673 -373.322367) (xy 37.653353 -373.434412)
			(xy 37.786904 -373.552524) (xy 37.915061 -373.676468) (xy 38.03757 -373.805998) (xy 38.154187 -373.940857)
			(xy 38.193125 -373.990165) (xy 47.739354 -373.990165) (xy 47.739354 -373.935635) (xy 47.747114 -373.88166)
			(xy 47.762476 -373.829338) (xy 47.785127 -373.779735) (xy 47.814606 -373.733859) (xy 47.850314 -373.692646)
			(xy 47.891523 -373.656934) (xy 47.937394 -373.627449) (xy 47.986995 -373.604792) (xy 48.039315 -373.589424)
			(xy 48.093289 -373.581657) (xy 48.120554 -373.581168) (xy 48.984154 -373.581168) (xy 49.011429 -373.581568)
			(xy 49.065425 -373.589326) (xy 49.117768 -373.604689) (xy 49.167391 -373.627346) (xy 49.213284 -373.656835)
			(xy 49.254512 -373.692555) (xy 49.290238 -373.73378) (xy 49.319732 -373.779669) (xy 49.342395 -373.829289)
			(xy 49.357764 -373.88163) (xy 49.365528 -373.935625) (xy 49.365528 -373.990165) (xy 54.546554 -373.990165)
			(xy 54.546554 -373.935635) (xy 54.554314 -373.88166) (xy 54.569676 -373.829338) (xy 54.592327 -373.779735)
			(xy 54.621806 -373.733859) (xy 54.657514 -373.692646) (xy 54.698723 -373.656934) (xy 54.744594 -373.627449)
			(xy 54.794195 -373.604792) (xy 54.846515 -373.589424) (xy 54.900489 -373.581657) (xy 54.927754 -373.581168)
			(xy 55.791354 -373.581168) (xy 55.818629 -373.581568) (xy 55.872625 -373.589326) (xy 55.924968 -373.604689)
			(xy 55.974591 -373.627346) (xy 56.020484 -373.656835) (xy 56.061712 -373.692555) (xy 56.097438 -373.73378)
			(xy 56.126932 -373.779669) (xy 56.149595 -373.829289) (xy 56.164964 -373.88163) (xy 56.172728 -373.935625)
			(xy 56.172728 -373.990165) (xy 61.353754 -373.990165) (xy 61.353754 -373.935635) (xy 61.361514 -373.88166)
			(xy 61.376876 -373.829338) (xy 61.399527 -373.779735) (xy 61.429006 -373.733859) (xy 61.464714 -373.692646)
			(xy 61.505923 -373.656934) (xy 61.551794 -373.627449) (xy 61.601395 -373.604792) (xy 61.653715 -373.589424)
			(xy 61.707689 -373.581657) (xy 61.734954 -373.581168) (xy 62.598554 -373.581168) (xy 62.625829 -373.581568)
			(xy 62.679825 -373.589326) (xy 62.732168 -373.604689) (xy 62.781791 -373.627346) (xy 62.827684 -373.656835)
			(xy 62.868912 -373.692555) (xy 62.904638 -373.73378) (xy 62.934132 -373.779669) (xy 62.956795 -373.829289)
			(xy 62.972164 -373.88163) (xy 62.979928 -373.935625) (xy 62.979928 -373.990169) (xy 80.267031 -373.990169)
			(xy 80.267031 -373.935631) (xy 80.274793 -373.881648) (xy 80.290158 -373.82932) (xy 80.312814 -373.77971)
			(xy 80.3423 -373.73383) (xy 80.378014 -373.692613) (xy 80.419232 -373.656898) (xy 80.465112 -373.627413)
			(xy 80.514721 -373.604757) (xy 80.56705 -373.589393) (xy 80.621033 -373.581631) (xy 80.648302 -373.581168)
			(xy 81.511902 -373.581168) (xy 81.539173 -373.581595) (xy 81.593161 -373.589357) (xy 81.645494 -373.604724)
			(xy 81.695108 -373.627382) (xy 81.740993 -373.65687) (xy 81.782213 -373.692588) (xy 81.817931 -373.733809)
			(xy 81.847419 -373.779693) (xy 81.870077 -373.829307) (xy 81.885443 -373.881641) (xy 81.893206 -373.935629)
			(xy 81.893206 -373.990169) (xy 87.074231 -373.990169) (xy 87.074231 -373.935631) (xy 87.081993 -373.881648)
			(xy 87.097358 -373.82932) (xy 87.120014 -373.77971) (xy 87.1495 -373.73383) (xy 87.185214 -373.692613)
			(xy 87.226432 -373.656898) (xy 87.272312 -373.627413) (xy 87.321921 -373.604757) (xy 87.37425 -373.589393)
			(xy 87.428233 -373.581631) (xy 87.455502 -373.581168) (xy 88.319102 -373.581168) (xy 88.346373 -373.581595)
			(xy 88.400361 -373.589357) (xy 88.452694 -373.604724) (xy 88.502308 -373.627382) (xy 88.548193 -373.65687)
			(xy 88.589413 -373.692588) (xy 88.625131 -373.733809) (xy 88.654619 -373.779693) (xy 88.677277 -373.829307)
			(xy 88.692643 -373.881641) (xy 88.700406 -373.935629) (xy 88.700406 -373.990169) (xy 93.881431 -373.990169)
			(xy 93.881431 -373.935631) (xy 93.889193 -373.881648) (xy 93.904558 -373.82932) (xy 93.927214 -373.77971)
			(xy 93.9567 -373.73383) (xy 93.992414 -373.692613) (xy 94.033632 -373.656898) (xy 94.079512 -373.627413)
			(xy 94.129121 -373.604757) (xy 94.18145 -373.589393) (xy 94.235433 -373.581631) (xy 94.262702 -373.581168)
			(xy 95.126302 -373.581168) (xy 95.153573 -373.581595) (xy 95.207561 -373.589357) (xy 95.259894 -373.604724)
			(xy 95.309508 -373.627382) (xy 95.355393 -373.65687) (xy 95.396613 -373.692588) (xy 95.432331 -373.733809)
			(xy 95.461819 -373.779693) (xy 95.484477 -373.829307) (xy 95.499843 -373.881641) (xy 95.507606 -373.935629)
			(xy 95.507606 -373.990167) (xy 114.839254 -373.990167) (xy 114.839254 -373.935633) (xy 114.847015 -373.881654)
			(xy 114.862379 -373.829329) (xy 114.885033 -373.779723) (xy 114.914517 -373.733846) (xy 114.950229 -373.692631)
			(xy 114.991442 -373.656919) (xy 115.037319 -373.627435) (xy 115.086925 -373.604781) (xy 115.13925 -373.589416)
			(xy 115.193229 -373.581655) (xy 115.220496 -373.581168) (xy 116.084096 -373.581168) (xy 116.111369 -373.581571)
			(xy 116.165361 -373.589334) (xy 116.217698 -373.604701) (xy 116.267316 -373.62736) (xy 116.313203 -373.65685)
			(xy 116.354427 -373.69257) (xy 116.390148 -373.733793) (xy 116.419638 -373.779681) (xy 116.442298 -373.829298)
			(xy 116.457666 -373.881635) (xy 116.465428 -373.935627) (xy 116.465428 -373.990167) (xy 121.646454 -373.990167)
			(xy 121.646454 -373.935633) (xy 121.654215 -373.881654) (xy 121.669579 -373.829329) (xy 121.692233 -373.779723)
			(xy 121.721717 -373.733846) (xy 121.757429 -373.692631) (xy 121.798642 -373.656919) (xy 121.844519 -373.627435)
			(xy 121.894125 -373.604781) (xy 121.94645 -373.589416) (xy 122.000429 -373.581655) (xy 122.027696 -373.581168)
			(xy 122.891296 -373.581168) (xy 122.918569 -373.581571) (xy 122.972561 -373.589334) (xy 123.024898 -373.604701)
			(xy 123.074516 -373.62736) (xy 123.120403 -373.65685) (xy 123.161627 -373.69257) (xy 123.197348 -373.733793)
			(xy 123.226838 -373.779681) (xy 123.249498 -373.829298) (xy 123.264866 -373.881635) (xy 123.272628 -373.935627)
			(xy 123.272628 -373.990167) (xy 128.453654 -373.990167) (xy 128.453654 -373.935633) (xy 128.461415 -373.881654)
			(xy 128.476779 -373.829329) (xy 128.499433 -373.779723) (xy 128.528917 -373.733846) (xy 128.564629 -373.692631)
			(xy 128.605842 -373.656919) (xy 128.651719 -373.627435) (xy 128.701325 -373.604781) (xy 128.75365 -373.589416)
			(xy 128.807629 -373.581655) (xy 128.834896 -373.581168) (xy 129.698496 -373.581168) (xy 129.725769 -373.581571)
			(xy 129.779761 -373.589334) (xy 129.832098 -373.604701) (xy 129.881716 -373.62736) (xy 129.927603 -373.65685)
			(xy 129.968827 -373.69257) (xy 130.004548 -373.733793) (xy 130.034038 -373.779681) (xy 130.056698 -373.829298)
			(xy 130.072066 -373.881635) (xy 130.079828 -373.935627) (xy 130.079828 -373.990171) (xy 147.366932 -373.990171)
			(xy 147.366932 -373.935629) (xy 147.374694 -373.881643) (xy 147.390061 -373.829311) (xy 147.412721 -373.779698)
			(xy 147.44221 -373.733816) (xy 147.477929 -373.692598) (xy 147.519151 -373.656884) (xy 147.565037 -373.627399)
			(xy 147.614652 -373.604746) (xy 147.666986 -373.589385) (xy 147.720973 -373.581628) (xy 147.748244 -373.581168)
			(xy 148.611844 -373.581168) (xy 148.639113 -373.581598) (xy 148.693097 -373.589365) (xy 148.745425 -373.604735)
			(xy 148.795033 -373.627396) (xy 148.840912 -373.656885) (xy 148.882128 -373.692603) (xy 148.917841 -373.733823)
			(xy 148.947325 -373.779705) (xy 148.96998 -373.829316) (xy 148.985344 -373.881647) (xy 148.993106 -373.93563)
			(xy 148.993106 -373.99017) (xy 148.993106 -373.990171) (xy 154.174132 -373.990171) (xy 154.174132 -373.935629)
			(xy 154.181894 -373.881643) (xy 154.197261 -373.829311) (xy 154.219921 -373.779698) (xy 154.24941 -373.733816)
			(xy 154.285129 -373.692598) (xy 154.326351 -373.656884) (xy 154.372237 -373.627399) (xy 154.421852 -373.604746)
			(xy 154.474186 -373.589385) (xy 154.528173 -373.581628) (xy 154.555444 -373.581168) (xy 155.419044 -373.581168)
			(xy 155.446313 -373.581598) (xy 155.500297 -373.589365) (xy 155.552625 -373.604735) (xy 155.602233 -373.627396)
			(xy 155.648112 -373.656885) (xy 155.689328 -373.692603) (xy 155.725041 -373.733823) (xy 155.754525 -373.779705)
			(xy 155.77718 -373.829316) (xy 155.792544 -373.881647) (xy 155.800306 -373.93563) (xy 155.800306 -373.99017)
			(xy 155.800306 -373.990171) (xy 160.981332 -373.990171) (xy 160.981332 -373.935629) (xy 160.989094 -373.881643)
			(xy 161.004461 -373.829311) (xy 161.027121 -373.779698) (xy 161.05661 -373.733816) (xy 161.092329 -373.692598)
			(xy 161.133551 -373.656884) (xy 161.179437 -373.627399) (xy 161.229052 -373.604746) (xy 161.281386 -373.589385)
			(xy 161.335373 -373.581628) (xy 161.362644 -373.581168) (xy 162.226244 -373.581168) (xy 162.253513 -373.581598)
			(xy 162.307497 -373.589365) (xy 162.359825 -373.604735) (xy 162.409433 -373.627396) (xy 162.455312 -373.656885)
			(xy 162.496528 -373.692603) (xy 162.532241 -373.733823) (xy 162.561725 -373.779705) (xy 162.58438 -373.829316)
			(xy 162.599744 -373.881647) (xy 162.607506 -373.93563) (xy 162.607506 -373.99017) (xy 162.599744 -374.044153)
			(xy 162.58438 -374.096484) (xy 162.561725 -374.146095) (xy 162.532241 -374.191977) (xy 162.496528 -374.233197)
			(xy 162.455312 -374.268915) (xy 162.409433 -374.298404) (xy 162.359825 -374.321065) (xy 162.307497 -374.336435)
			(xy 162.253513 -374.344202) (xy 162.226244 -374.344692) (xy 161.362644 -374.344692) (xy 161.335373 -374.344172)
			(xy 161.281386 -374.336415) (xy 161.229052 -374.321054) (xy 161.179437 -374.298401) (xy 161.133551 -374.268916)
			(xy 161.092329 -374.233202) (xy 161.05661 -374.191984) (xy 161.027121 -374.146102) (xy 161.004461 -374.096489)
			(xy 160.989094 -374.044157) (xy 160.981332 -373.990171) (xy 155.800306 -373.990171) (xy 155.792544 -374.044153)
			(xy 155.77718 -374.096484) (xy 155.754525 -374.146095) (xy 155.725041 -374.191977) (xy 155.689328 -374.233197)
			(xy 155.648112 -374.268915) (xy 155.602233 -374.298404) (xy 155.552625 -374.321065) (xy 155.500297 -374.336435)
			(xy 155.446313 -374.344202) (xy 155.419044 -374.344692) (xy 154.555444 -374.344692) (xy 154.528173 -374.344172)
			(xy 154.474186 -374.336415) (xy 154.421852 -374.321054) (xy 154.372237 -374.298401) (xy 154.326351 -374.268916)
			(xy 154.285129 -374.233202) (xy 154.24941 -374.191984) (xy 154.219921 -374.146102) (xy 154.197261 -374.096489)
			(xy 154.181894 -374.044157) (xy 154.174132 -373.990171) (xy 148.993106 -373.990171) (xy 148.985344 -374.044153)
			(xy 148.96998 -374.096484) (xy 148.947325 -374.146095) (xy 148.917841 -374.191977) (xy 148.882128 -374.233197)
			(xy 148.840912 -374.268915) (xy 148.795033 -374.298404) (xy 148.745425 -374.321065) (xy 148.693097 -374.336435)
			(xy 148.639113 -374.344202) (xy 148.611844 -374.344692) (xy 147.748244 -374.344692) (xy 147.720973 -374.344172)
			(xy 147.666986 -374.336415) (xy 147.614652 -374.321054) (xy 147.565037 -374.298401) (xy 147.519151 -374.268916)
			(xy 147.477929 -374.233202) (xy 147.44221 -374.191984) (xy 147.412721 -374.146102) (xy 147.390061 -374.096489)
			(xy 147.374694 -374.044157) (xy 147.366932 -373.990171) (xy 130.079828 -373.990171) (xy 130.079828 -373.990173)
			(xy 130.072066 -374.044165) (xy 130.056698 -374.096502) (xy 130.034038 -374.146119) (xy 130.004548 -374.192007)
			(xy 129.968827 -374.23323) (xy 129.927603 -374.26895) (xy 129.881716 -374.29844) (xy 129.832098 -374.321099)
			(xy 129.779761 -374.336466) (xy 129.725769 -374.344229) (xy 129.698496 -374.344692) (xy 128.834896 -374.344692)
			(xy 128.807629 -374.344145) (xy 128.75365 -374.336384) (xy 128.701325 -374.321019) (xy 128.651719 -374.298365)
			(xy 128.605842 -374.268881) (xy 128.564629 -374.233169) (xy 128.528917 -374.191954) (xy 128.499433 -374.146077)
			(xy 128.476779 -374.096471) (xy 128.461415 -374.044146) (xy 128.453654 -373.990167) (xy 123.272628 -373.990167)
			(xy 123.272628 -373.990173) (xy 123.264866 -374.044165) (xy 123.249498 -374.096502) (xy 123.226838 -374.146119)
			(xy 123.197348 -374.192007) (xy 123.161627 -374.23323) (xy 123.120403 -374.26895) (xy 123.074516 -374.29844)
			(xy 123.024898 -374.321099) (xy 122.972561 -374.336466) (xy 122.918569 -374.344229) (xy 122.891296 -374.344692)
			(xy 122.027696 -374.344692) (xy 122.000429 -374.344145) (xy 121.94645 -374.336384) (xy 121.894125 -374.321019)
			(xy 121.844519 -374.298365) (xy 121.798642 -374.268881) (xy 121.757429 -374.233169) (xy 121.721717 -374.191954)
			(xy 121.692233 -374.146077) (xy 121.669579 -374.096471) (xy 121.654215 -374.044146) (xy 121.646454 -373.990167)
			(xy 116.465428 -373.990167) (xy 116.465428 -373.990173) (xy 116.457666 -374.044165) (xy 116.442298 -374.096502)
			(xy 116.419638 -374.146119) (xy 116.390148 -374.192007) (xy 116.354427 -374.23323) (xy 116.313203 -374.26895)
			(xy 116.267316 -374.29844) (xy 116.217698 -374.321099) (xy 116.165361 -374.336466) (xy 116.111369 -374.344229)
			(xy 116.084096 -374.344692) (xy 115.220496 -374.344692) (xy 115.193229 -374.344145) (xy 115.13925 -374.336384)
			(xy 115.086925 -374.321019) (xy 115.037319 -374.298365) (xy 114.991442 -374.268881) (xy 114.950229 -374.233169)
			(xy 114.914517 -374.191954) (xy 114.885033 -374.146077) (xy 114.862379 -374.096471) (xy 114.847015 -374.044146)
			(xy 114.839254 -373.990167) (xy 95.507606 -373.990167) (xy 95.507606 -373.990171) (xy 95.499843 -374.044159)
			(xy 95.484477 -374.096493) (xy 95.461819 -374.146107) (xy 95.432331 -374.191991) (xy 95.396613 -374.233212)
			(xy 95.355393 -374.26893) (xy 95.309508 -374.298418) (xy 95.259894 -374.321076) (xy 95.207561 -374.336443)
			(xy 95.153573 -374.344205) (xy 95.126302 -374.344692) (xy 94.262702 -374.344692) (xy 94.235433 -374.344169)
			(xy 94.18145 -374.336407) (xy 94.129121 -374.321043) (xy 94.079512 -374.298387) (xy 94.033632 -374.268902)
			(xy 93.992414 -374.233187) (xy 93.9567 -374.19197) (xy 93.927214 -374.14609) (xy 93.904558 -374.09648)
			(xy 93.889193 -374.044152) (xy 93.881431 -373.990169) (xy 88.700406 -373.990169) (xy 88.700406 -373.990171)
			(xy 88.692643 -374.044159) (xy 88.677277 -374.096493) (xy 88.654619 -374.146107) (xy 88.625131 -374.191991)
			(xy 88.589413 -374.233212) (xy 88.548193 -374.26893) (xy 88.502308 -374.298418) (xy 88.452694 -374.321076)
			(xy 88.400361 -374.336443) (xy 88.346373 -374.344205) (xy 88.319102 -374.344692) (xy 87.455502 -374.344692)
			(xy 87.428233 -374.344169) (xy 87.37425 -374.336407) (xy 87.321921 -374.321043) (xy 87.272312 -374.298387)
			(xy 87.226432 -374.268902) (xy 87.185214 -374.233187) (xy 87.1495 -374.19197) (xy 87.120014 -374.14609)
			(xy 87.097358 -374.09648) (xy 87.081993 -374.044152) (xy 87.074231 -373.990169) (xy 81.893206 -373.990169)
			(xy 81.893206 -373.990171) (xy 81.885443 -374.044159) (xy 81.870077 -374.096493) (xy 81.847419 -374.146107)
			(xy 81.817931 -374.191991) (xy 81.782213 -374.233212) (xy 81.740993 -374.26893) (xy 81.695108 -374.298418)
			(xy 81.645494 -374.321076) (xy 81.593161 -374.336443) (xy 81.539173 -374.344205) (xy 81.511902 -374.344692)
			(xy 80.648302 -374.344692) (xy 80.621033 -374.344169) (xy 80.56705 -374.336407) (xy 80.514721 -374.321043)
			(xy 80.465112 -374.298387) (xy 80.419232 -374.268902) (xy 80.378014 -374.233187) (xy 80.3423 -374.19197)
			(xy 80.312814 -374.14609) (xy 80.290158 -374.09648) (xy 80.274793 -374.044152) (xy 80.267031 -373.990169)
			(xy 62.979928 -373.990169) (xy 62.979928 -373.990175) (xy 62.972164 -374.04417) (xy 62.956795 -374.096511)
			(xy 62.934132 -374.146131) (xy 62.904638 -374.19202) (xy 62.868912 -374.233245) (xy 62.827684 -374.268965)
			(xy 62.781791 -374.298454) (xy 62.732168 -374.321111) (xy 62.679825 -374.336474) (xy 62.625829 -374.344232)
			(xy 62.598554 -374.344692) (xy 61.734954 -374.344692) (xy 61.707689 -374.344143) (xy 61.653715 -374.336376)
			(xy 61.601395 -374.321008) (xy 61.551794 -374.298351) (xy 61.505923 -374.268866) (xy 61.464714 -374.233154)
			(xy 61.429006 -374.191941) (xy 61.399527 -374.146065) (xy 61.376876 -374.096462) (xy 61.361514 -374.04414)
			(xy 61.353754 -373.990165) (xy 56.172728 -373.990165) (xy 56.172728 -373.990175) (xy 56.164964 -374.04417)
			(xy 56.149595 -374.096511) (xy 56.126932 -374.146131) (xy 56.097438 -374.19202) (xy 56.061712 -374.233245)
			(xy 56.020484 -374.268965) (xy 55.974591 -374.298454) (xy 55.924968 -374.321111) (xy 55.872625 -374.336474)
			(xy 55.818629 -374.344232) (xy 55.791354 -374.344692) (xy 54.927754 -374.344692) (xy 54.900489 -374.344143)
			(xy 54.846515 -374.336376) (xy 54.794195 -374.321008) (xy 54.744594 -374.298351) (xy 54.698723 -374.268866)
			(xy 54.657514 -374.233154) (xy 54.621806 -374.191941) (xy 54.592327 -374.146065) (xy 54.569676 -374.096462)
			(xy 54.554314 -374.04414) (xy 54.546554 -373.990165) (xy 49.365528 -373.990165) (xy 49.365528 -373.990175)
			(xy 49.357764 -374.04417) (xy 49.342395 -374.096511) (xy 49.319732 -374.146131) (xy 49.290238 -374.19202)
			(xy 49.254512 -374.233245) (xy 49.213284 -374.268965) (xy 49.167391 -374.298454) (xy 49.117768 -374.321111)
			(xy 49.065425 -374.336474) (xy 49.011429 -374.344232) (xy 48.984154 -374.344692) (xy 48.120554 -374.344692)
			(xy 48.093289 -374.344143) (xy 48.039315 -374.336376) (xy 47.986995 -374.321008) (xy 47.937394 -374.298351)
			(xy 47.891523 -374.268866) (xy 47.850314 -374.233154) (xy 47.814606 -374.191941) (xy 47.785127 -374.146065)
			(xy 47.762476 -374.096462) (xy 47.747114 -374.04414) (xy 47.739354 -373.990165) (xy 38.193125 -373.990165)
			(xy 38.26468 -374.080777) (xy 38.368831 -374.22548) (xy 38.466433 -374.374679) (xy 38.557291 -374.528078)
			(xy 38.641225 -374.685372) (xy 38.71807 -374.846248) (xy 38.787671 -375.010389) (xy 38.849892 -375.177466)
			(xy 38.904608 -375.34715) (xy 38.95171 -375.519103) (xy 38.991106 -375.692983) (xy 39.022717 -375.868446)
			(xy 39.046481 -376.045142) (xy 39.062349 -376.222722) (xy 39.070291 -376.400832) (xy 39.070788 -376.489976)
			(xy 39.070291 -376.57912) (xy 39.062349 -376.75723) (xy 39.05568 -376.83186) (xy 41.04894 -376.83186)
			(xy 41.04894 -375.96826) (xy 41.049426 -375.940991) (xy 41.057188 -375.887007) (xy 41.072553 -375.834677)
			(xy 41.09521 -375.785067) (xy 41.124696 -375.739186) (xy 41.160411 -375.697969) (xy 41.201628 -375.662254)
			(xy 41.247509 -375.632768) (xy 41.297119 -375.610111) (xy 41.349449 -375.594746) (xy 41.403433 -375.586984)
			(xy 41.457971 -375.586984) (xy 41.511955 -375.594746) (xy 41.564285 -375.610111) (xy 41.613895 -375.632768)
			(xy 41.659776 -375.662254) (xy 41.700993 -375.697969) (xy 41.736708 -375.739186) (xy 41.766194 -375.785067)
			(xy 41.788851 -375.834677) (xy 41.804216 -375.887007) (xy 41.811978 -375.940991) (xy 41.812464 -375.96826)
			(xy 41.812464 -376.83186) (xy 41.811978 -376.859129) (xy 41.804216 -376.913113) (xy 41.791381 -376.956828)
			(xy 70.895972 -376.956828) (xy 70.895972 -376.093228) (xy 70.896458 -376.065959) (xy 70.90422 -376.011975)
			(xy 70.919585 -375.959645) (xy 70.942242 -375.910035) (xy 70.971728 -375.864154) (xy 71.007443 -375.822937)
			(xy 71.04866 -375.787222) (xy 71.094541 -375.757736) (xy 71.144151 -375.735079) (xy 71.196481 -375.719714)
			(xy 71.250465 -375.711952) (xy 71.305003 -375.711952) (xy 71.358987 -375.719714) (xy 71.411317 -375.735079)
			(xy 71.460927 -375.757736) (xy 71.506808 -375.787222) (xy 71.548025 -375.822937) (xy 71.58374 -375.864154)
			(xy 71.613226 -375.910035) (xy 71.635883 -375.959645) (xy 71.651248 -376.011975) (xy 71.65901 -376.065959)
			(xy 71.659496 -376.093228) (xy 71.659496 -376.83186) (xy 73.576688 -376.83186) (xy 73.576688 -375.96826)
			(xy 73.577174 -375.940991) (xy 73.584936 -375.887007) (xy 73.600301 -375.834677) (xy 73.622958 -375.785067)
			(xy 73.652444 -375.739186) (xy 73.688159 -375.697969) (xy 73.729376 -375.662254) (xy 73.775257 -375.632768)
			(xy 73.824867 -375.610111) (xy 73.877197 -375.594746) (xy 73.931181 -375.586984) (xy 73.985719 -375.586984)
			(xy 74.039703 -375.594746) (xy 74.092033 -375.610111) (xy 74.141643 -375.632768) (xy 74.187524 -375.662254)
			(xy 74.228741 -375.697969) (xy 74.264456 -375.739186) (xy 74.293942 -375.785067) (xy 74.316599 -375.834677)
			(xy 74.331964 -375.887007) (xy 74.339726 -375.940991) (xy 74.340212 -375.96826) (xy 74.340212 -376.83186)
			(xy 74.339726 -376.859129) (xy 74.331964 -376.913113) (xy 74.319129 -376.956828) (xy 103.42372 -376.956828)
			(xy 103.42372 -376.093228) (xy 103.424206 -376.065959) (xy 103.431968 -376.011975) (xy 103.447333 -375.959645)
			(xy 103.46999 -375.910035) (xy 103.499476 -375.864154) (xy 103.535191 -375.822937) (xy 103.576408 -375.787222)
			(xy 103.622289 -375.757736) (xy 103.671899 -375.735079) (xy 103.724229 -375.719714) (xy 103.778213 -375.711952)
			(xy 103.832751 -375.711952) (xy 103.886735 -375.719714) (xy 103.939065 -375.735079) (xy 103.988675 -375.757736)
			(xy 104.034556 -375.787222) (xy 104.075773 -375.822937) (xy 104.111488 -375.864154) (xy 104.140974 -375.910035)
			(xy 104.163631 -375.959645) (xy 104.178996 -376.011975) (xy 104.186758 -376.065959) (xy 104.187244 -376.093228)
			(xy 104.187244 -376.83186) (xy 108.149136 -376.83186) (xy 108.149136 -375.96826) (xy 108.149622 -375.941009)
			(xy 108.157378 -375.887061) (xy 108.172733 -375.834766) (xy 108.195375 -375.785189) (xy 108.224841 -375.739339)
			(xy 108.260532 -375.698148) (xy 108.301723 -375.662457) (xy 108.347573 -375.632991) (xy 108.39715 -375.610349)
			(xy 108.449445 -375.594994) (xy 108.503393 -375.587238) (xy 108.557895 -375.587238) (xy 108.611843 -375.594994)
			(xy 108.664138 -375.610349) (xy 108.713715 -375.632991) (xy 108.759565 -375.662457) (xy 108.800756 -375.698148)
			(xy 108.836447 -375.739339) (xy 108.865913 -375.785189) (xy 108.888555 -375.834766) (xy 108.90391 -375.887061)
			(xy 108.911666 -375.941009) (xy 108.912152 -375.96826) (xy 108.912152 -376.83186) (xy 108.911666 -376.859111)
			(xy 108.90391 -376.913059) (xy 108.891058 -376.956828) (xy 137.996168 -376.956828) (xy 137.996168 -376.093228)
			(xy 137.996654 -376.065977) (xy 138.00441 -376.012029) (xy 138.019765 -375.959734) (xy 138.042407 -375.910157)
			(xy 138.071873 -375.864307) (xy 138.107564 -375.823116) (xy 138.148755 -375.787425) (xy 138.194605 -375.757959)
			(xy 138.244182 -375.735317) (xy 138.296477 -375.719962) (xy 138.350425 -375.712206) (xy 138.404927 -375.712206)
			(xy 138.458875 -375.719962) (xy 138.51117 -375.735317) (xy 138.560747 -375.757959) (xy 138.606597 -375.787425)
			(xy 138.647788 -375.823116) (xy 138.683479 -375.864307) (xy 138.712945 -375.910157) (xy 138.735587 -375.959734)
			(xy 138.750942 -376.012029) (xy 138.758698 -376.065977) (xy 138.759184 -376.093228) (xy 138.759184 -376.83186)
			(xy 140.676884 -376.83186) (xy 140.676884 -375.96826) (xy 140.67737 -375.941009) (xy 140.685126 -375.887061)
			(xy 140.700481 -375.834766) (xy 140.723123 -375.785189) (xy 140.752589 -375.739339) (xy 140.78828 -375.698148)
			(xy 140.829471 -375.662457) (xy 140.875321 -375.632991) (xy 140.924898 -375.610349) (xy 140.977193 -375.594994)
			(xy 141.031141 -375.587238) (xy 141.085643 -375.587238) (xy 141.139591 -375.594994) (xy 141.191886 -375.610349)
			(xy 141.241463 -375.632991) (xy 141.287313 -375.662457) (xy 141.328504 -375.698148) (xy 141.364195 -375.739339)
			(xy 141.393661 -375.785189) (xy 141.416303 -375.834766) (xy 141.431658 -375.887061) (xy 141.439414 -375.941009)
			(xy 141.4399 -375.96826) (xy 141.4399 -376.83186) (xy 141.439414 -376.859111) (xy 141.431658 -376.913059)
			(xy 141.418806 -376.956828) (xy 170.523916 -376.956828) (xy 170.523916 -376.093228) (xy 170.524402 -376.065977)
			(xy 170.532158 -376.012029) (xy 170.547513 -375.959734) (xy 170.570155 -375.910157) (xy 170.599621 -375.864307)
			(xy 170.635312 -375.823116) (xy 170.676503 -375.787425) (xy 170.722353 -375.757959) (xy 170.77193 -375.735317)
			(xy 170.824225 -375.719962) (xy 170.878173 -375.712206) (xy 170.932675 -375.712206) (xy 170.986623 -375.719962)
			(xy 171.038918 -375.735317) (xy 171.088495 -375.757959) (xy 171.134345 -375.787425) (xy 171.175536 -375.823116)
			(xy 171.211227 -375.864307) (xy 171.240693 -375.910157) (xy 171.263335 -375.959734) (xy 171.27869 -376.012029)
			(xy 171.286446 -376.065977) (xy 171.286932 -376.093228) (xy 171.286932 -376.489976) (xy 173.498776 -376.489976)
			(xy 173.502748 -376.311733) (xy 173.514656 -376.133844) (xy 173.534477 -375.956662) (xy 173.562171 -375.780538)
			(xy 173.597683 -375.605823) (xy 173.640943 -375.432864) (xy 173.691865 -375.262003) (xy 173.750348 -375.093581)
			(xy 173.816275 -374.927931) (xy 173.889516 -374.765382) (xy 173.969926 -374.606257) (xy 174.057344 -374.450872)
			(xy 174.151597 -374.299536) (xy 174.252498 -374.152548) (xy 174.359847 -374.010201) (xy 174.47343 -373.872778)
			(xy 174.593023 -373.740551) (xy 174.718387 -373.613782) (xy 174.849274 -373.492724) (xy 174.985423 -373.377617)
			(xy 175.126565 -373.268689) (xy 175.27242 -373.166157) (xy 175.422697 -373.070223) (xy 175.577098 -372.98108)
			(xy 175.735317 -372.898903) (xy 175.89704 -372.823855) (xy 176.061945 -372.756087) (xy 176.229706 -372.695731)
			(xy 176.399989 -372.642909) (xy 176.572456 -372.597725) (xy 176.746764 -372.560268) (xy 176.922568 -372.530614)
			(xy 177.099518 -372.508821) (xy 177.277264 -372.494931) (xy 177.455451 -372.488974) (xy 177.633728 -372.49096)
			(xy 177.811739 -372.500886) (xy 177.989131 -372.518732) (xy 178.165551 -372.544462) (xy 178.340651 -372.578026)
			(xy 178.514082 -372.619356) (xy 178.685499 -372.668372) (xy 178.854562 -372.724974) (xy 179.020937 -372.789052)
			(xy 179.184291 -372.860478) (xy 179.344302 -372.93911) (xy 179.500651 -373.024791) (xy 179.653028 -373.117353)
			(xy 179.801131 -373.21661) (xy 179.944665 -373.322367) (xy 180.083345 -373.434412) (xy 180.216896 -373.552524)
			(xy 180.345053 -373.676468) (xy 180.467562 -373.805998) (xy 180.584179 -373.940857) (xy 180.596796 -373.956834)
			(xy 282.853384 -373.956834) (xy 282.853384 -373.093234) (xy 282.85387 -373.065983) (xy 282.861626 -373.012035)
			(xy 282.876981 -372.95974) (xy 282.899623 -372.910163) (xy 282.929089 -372.864313) (xy 282.96478 -372.823122)
			(xy 283.005971 -372.787431) (xy 283.051821 -372.757965) (xy 283.101398 -372.735323) (xy 283.153693 -372.719968)
			(xy 283.207641 -372.712212) (xy 283.262143 -372.712212) (xy 283.316091 -372.719968) (xy 283.368386 -372.735323)
			(xy 283.417963 -372.757965) (xy 283.463813 -372.787431) (xy 283.505004 -372.823122) (xy 283.540695 -372.864313)
			(xy 283.570161 -372.910163) (xy 283.592803 -372.95974) (xy 283.608158 -373.012035) (xy 283.615914 -373.065983)
			(xy 283.6164 -373.093234) (xy 283.6164 -373.956834) (xy 283.615914 -373.984085) (xy 283.608158 -374.038033)
			(xy 283.592803 -374.090328) (xy 283.570161 -374.139905) (xy 283.540695 -374.185755) (xy 283.505004 -374.226946)
			(xy 283.463813 -374.262637) (xy 283.417963 -374.292103) (xy 283.368386 -374.314745) (xy 283.316091 -374.3301)
			(xy 283.262143 -374.337856) (xy 283.207641 -374.337856) (xy 283.153693 -374.3301) (xy 283.101398 -374.314745)
			(xy 283.051821 -374.292103) (xy 283.005971 -374.262637) (xy 282.96478 -374.226946) (xy 282.929089 -374.185755)
			(xy 282.899623 -374.139905) (xy 282.876981 -374.090328) (xy 282.861626 -374.038033) (xy 282.85387 -373.984085)
			(xy 282.853384 -373.956834) (xy 180.596796 -373.956834) (xy 180.694672 -374.080777) (xy 180.798823 -374.22548)
			(xy 180.896425 -374.374679) (xy 180.987283 -374.528078) (xy 181.071217 -374.685372) (xy 181.148062 -374.846248)
			(xy 181.217663 -375.010389) (xy 181.279884 -375.177466) (xy 181.3346 -375.34715) (xy 181.381702 -375.519103)
			(xy 181.421098 -375.692983) (xy 181.452709 -375.868446) (xy 181.476473 -376.045142) (xy 181.492341 -376.222722)
			(xy 181.500283 -376.400832) (xy 181.50078 -376.489976) (xy 181.500283 -376.57912) (xy 181.492341 -376.75723)
			(xy 181.476473 -376.93481) (xy 181.452709 -377.111506) (xy 181.421098 -377.286969) (xy 181.381702 -377.460849)
			(xy 181.3346 -377.632802) (xy 181.319901 -377.678385) (xy 193.900548 -377.678385) (xy 193.900548 -377.593663)
			(xy 193.908601 -377.509326) (xy 193.924635 -377.426136) (xy 193.948503 -377.344846) (xy 193.979991 -377.266194)
			(xy 194.018813 -377.190891) (xy 194.064616 -377.119619) (xy 194.116987 -377.053023) (xy 194.175452 -376.991708)
			(xy 194.23948 -376.936227) (xy 194.308492 -376.887084) (xy 194.381862 -376.844724) (xy 194.458927 -376.809529)
			(xy 194.538989 -376.78182) (xy 194.621322 -376.761846) (xy 194.705181 -376.749789) (xy 194.789806 -376.745758)
			(xy 194.874431 -376.749789) (xy 194.95829 -376.761846) (xy 195.040623 -376.78182) (xy 195.120685 -376.809529)
			(xy 195.19775 -376.844724) (xy 195.27112 -376.887084) (xy 195.340132 -376.936227) (xy 195.40416 -376.991708)
			(xy 195.462625 -377.053023) (xy 195.514996 -377.119619) (xy 195.560799 -377.190891) (xy 195.599621 -377.266194)
			(xy 195.631109 -377.344846) (xy 195.654977 -377.426136) (xy 195.671011 -377.509326) (xy 195.679064 -377.593663)
			(xy 195.679568 -377.636024) (xy 195.679064 -377.678385) (xy 195.671011 -377.762722) (xy 195.654977 -377.845912)
			(xy 195.631109 -377.927202) (xy 195.599621 -378.005854) (xy 195.560799 -378.081157) (xy 195.514996 -378.152429)
			(xy 195.47531 -378.202895) (xy 199.443082 -378.202895) (xy 199.443082 -378.118173) (xy 199.451135 -378.033836)
			(xy 199.467169 -377.950646) (xy 199.491037 -377.869356) (xy 199.522525 -377.790704) (xy 199.561347 -377.715401)
			(xy 199.60715 -377.644129) (xy 199.659521 -377.577533) (xy 199.717986 -377.516218) (xy 199.782014 -377.460737)
			(xy 199.851026 -377.411594) (xy 199.924396 -377.369234) (xy 200.001461 -377.334039) (xy 200.081523 -377.30633)
			(xy 200.163856 -377.286356) (xy 200.247715 -377.274299) (xy 200.33234 -377.270268) (xy 200.416965 -377.274299)
			(xy 200.500824 -377.286356) (xy 200.583157 -377.30633) (xy 200.663219 -377.334039) (xy 200.740284 -377.369234)
			(xy 200.813654 -377.411594) (xy 200.859958 -377.444567) (xy 300.335454 -377.444567) (xy 300.335454 -377.390033)
			(xy 300.343215 -377.336054) (xy 300.358579 -377.283729) (xy 300.381233 -377.234123) (xy 300.410717 -377.188246)
			(xy 300.446429 -377.147031) (xy 300.487642 -377.111319) (xy 300.533519 -377.081835) (xy 300.583125 -377.059181)
			(xy 300.63545 -377.043816) (xy 300.689429 -377.036055) (xy 300.716696 -377.035568) (xy 301.580296 -377.035568)
			(xy 301.607569 -377.035971) (xy 301.661561 -377.043734) (xy 301.713898 -377.059101) (xy 301.763516 -377.08176)
			(xy 301.809403 -377.11125) (xy 301.850627 -377.14697) (xy 301.886348 -377.188193) (xy 301.915838 -377.234081)
			(xy 301.938498 -377.283698) (xy 301.953866 -377.336035) (xy 301.961628 -377.390027) (xy 301.961628 -377.444567)
			(xy 307.142654 -377.444567) (xy 307.142654 -377.390033) (xy 307.150415 -377.336054) (xy 307.165779 -377.283729)
			(xy 307.188433 -377.234123) (xy 307.217917 -377.188246) (xy 307.253629 -377.147031) (xy 307.294842 -377.111319)
			(xy 307.340719 -377.081835) (xy 307.390325 -377.059181) (xy 307.44265 -377.043816) (xy 307.496629 -377.036055)
			(xy 307.523896 -377.035568) (xy 308.387496 -377.035568) (xy 308.414769 -377.035971) (xy 308.468761 -377.043734)
			(xy 308.521098 -377.059101) (xy 308.570716 -377.08176) (xy 308.616603 -377.11125) (xy 308.657827 -377.14697)
			(xy 308.693548 -377.188193) (xy 308.723038 -377.234081) (xy 308.745698 -377.283698) (xy 308.761066 -377.336035)
			(xy 308.768828 -377.390027) (xy 308.768828 -377.444567) (xy 313.949854 -377.444567) (xy 313.949854 -377.390033)
			(xy 313.957615 -377.336054) (xy 313.972979 -377.283729) (xy 313.995633 -377.234123) (xy 314.025117 -377.188246)
			(xy 314.060829 -377.147031) (xy 314.102042 -377.111319) (xy 314.147919 -377.081835) (xy 314.197525 -377.059181)
			(xy 314.24985 -377.043816) (xy 314.303829 -377.036055) (xy 314.331096 -377.035568) (xy 315.194696 -377.035568)
			(xy 315.221969 -377.035971) (xy 315.275961 -377.043734) (xy 315.328298 -377.059101) (xy 315.377916 -377.08176)
			(xy 315.423803 -377.11125) (xy 315.465027 -377.14697) (xy 315.500748 -377.188193) (xy 315.530238 -377.234081)
			(xy 315.552898 -377.283698) (xy 315.568266 -377.336035) (xy 315.576028 -377.390027) (xy 315.576028 -377.444567)
			(xy 320.757054 -377.444567) (xy 320.757054 -377.390033) (xy 320.764815 -377.336054) (xy 320.780179 -377.283729)
			(xy 320.802833 -377.234123) (xy 320.832317 -377.188246) (xy 320.868029 -377.147031) (xy 320.909242 -377.111319)
			(xy 320.955119 -377.081835) (xy 321.004725 -377.059181) (xy 321.05705 -377.043816) (xy 321.111029 -377.036055)
			(xy 321.138296 -377.035568) (xy 322.001896 -377.035568) (xy 322.029169 -377.035971) (xy 322.083161 -377.043734)
			(xy 322.135498 -377.059101) (xy 322.185116 -377.08176) (xy 322.231003 -377.11125) (xy 322.272227 -377.14697)
			(xy 322.307948 -377.188193) (xy 322.337438 -377.234081) (xy 322.360098 -377.283698) (xy 322.375466 -377.336035)
			(xy 322.383228 -377.390027) (xy 322.383228 -377.444567) (xy 324.160654 -377.444567) (xy 324.160654 -377.390033)
			(xy 324.168415 -377.336054) (xy 324.183779 -377.283729) (xy 324.206433 -377.234123) (xy 324.235917 -377.188246)
			(xy 324.271629 -377.147031) (xy 324.312842 -377.111319) (xy 324.358719 -377.081835) (xy 324.408325 -377.059181)
			(xy 324.46065 -377.043816) (xy 324.514629 -377.036055) (xy 324.541896 -377.035568) (xy 325.405496 -377.035568)
			(xy 325.432769 -377.035971) (xy 325.486761 -377.043734) (xy 325.539098 -377.059101) (xy 325.588716 -377.08176)
			(xy 325.634603 -377.11125) (xy 325.675827 -377.14697) (xy 325.711548 -377.188193) (xy 325.741038 -377.234081)
			(xy 325.763698 -377.283698) (xy 325.779066 -377.336035) (xy 325.786828 -377.390027) (xy 325.786828 -377.444571)
			(xy 332.863132 -377.444571) (xy 332.863132 -377.390029) (xy 332.870894 -377.336043) (xy 332.886261 -377.283711)
			(xy 332.908921 -377.234098) (xy 332.93841 -377.188216) (xy 332.974129 -377.146998) (xy 333.015351 -377.111284)
			(xy 333.061237 -377.081799) (xy 333.110852 -377.059146) (xy 333.163186 -377.043785) (xy 333.217173 -377.036028)
			(xy 333.244444 -377.035568) (xy 334.108044 -377.035568) (xy 334.135313 -377.035998) (xy 334.189297 -377.043765)
			(xy 334.241625 -377.059135) (xy 334.291233 -377.081796) (xy 334.337112 -377.111285) (xy 334.378328 -377.147003)
			(xy 334.414041 -377.188223) (xy 334.443525 -377.234105) (xy 334.46618 -377.283716) (xy 334.481544 -377.336047)
			(xy 334.489306 -377.39003) (xy 334.489306 -377.44457) (xy 334.489306 -377.444571) (xy 339.670332 -377.444571)
			(xy 339.670332 -377.390029) (xy 339.678094 -377.336043) (xy 339.693461 -377.283711) (xy 339.716121 -377.234098)
			(xy 339.74561 -377.188216) (xy 339.781329 -377.146998) (xy 339.822551 -377.111284) (xy 339.868437 -377.081799)
			(xy 339.918052 -377.059146) (xy 339.970386 -377.043785) (xy 340.024373 -377.036028) (xy 340.051644 -377.035568)
			(xy 340.915244 -377.035568) (xy 340.942513 -377.035998) (xy 340.996497 -377.043765) (xy 341.048825 -377.059135)
			(xy 341.098433 -377.081796) (xy 341.144312 -377.111285) (xy 341.185528 -377.147003) (xy 341.221241 -377.188223)
			(xy 341.250725 -377.234105) (xy 341.27338 -377.283716) (xy 341.288744 -377.336047) (xy 341.296506 -377.39003)
			(xy 341.296506 -377.44457) (xy 341.296506 -377.444571) (xy 346.477532 -377.444571) (xy 346.477532 -377.390029)
			(xy 346.485294 -377.336043) (xy 346.500661 -377.283711) (xy 346.523321 -377.234098) (xy 346.55281 -377.188216)
			(xy 346.588529 -377.146998) (xy 346.629751 -377.111284) (xy 346.675637 -377.081799) (xy 346.725252 -377.059146)
			(xy 346.777586 -377.043785) (xy 346.831573 -377.036028) (xy 346.858844 -377.035568) (xy 347.722444 -377.035568)
			(xy 347.749713 -377.035998) (xy 347.803697 -377.043765) (xy 347.856025 -377.059135) (xy 347.905633 -377.081796)
			(xy 347.951512 -377.111285) (xy 347.992728 -377.147003) (xy 348.028441 -377.188223) (xy 348.057925 -377.234105)
			(xy 348.08058 -377.283716) (xy 348.095944 -377.336047) (xy 348.103706 -377.39003) (xy 348.103706 -377.44457)
			(xy 348.103706 -377.444571) (xy 353.284732 -377.444571) (xy 353.284732 -377.390029) (xy 353.292494 -377.336043)
			(xy 353.307861 -377.283711) (xy 353.330521 -377.234098) (xy 353.36001 -377.188216) (xy 353.395729 -377.146998)
			(xy 353.436951 -377.111284) (xy 353.482837 -377.081799) (xy 353.532452 -377.059146) (xy 353.584786 -377.043785)
			(xy 353.638773 -377.036028) (xy 353.666044 -377.035568) (xy 354.529644 -377.035568) (xy 354.556913 -377.035998)
			(xy 354.610897 -377.043765) (xy 354.663225 -377.059135) (xy 354.712833 -377.081796) (xy 354.758712 -377.111285)
			(xy 354.799928 -377.147003) (xy 354.835641 -377.188223) (xy 354.865125 -377.234105) (xy 354.88778 -377.283716)
			(xy 354.903144 -377.336047) (xy 354.910906 -377.39003) (xy 354.910906 -377.44457) (xy 354.910906 -377.444571)
			(xy 356.688332 -377.444571) (xy 356.688332 -377.390029) (xy 356.696094 -377.336043) (xy 356.711461 -377.283711)
			(xy 356.734121 -377.234098) (xy 356.76361 -377.188216) (xy 356.799329 -377.146998) (xy 356.840551 -377.111284)
			(xy 356.886437 -377.081799) (xy 356.936052 -377.059146) (xy 356.988386 -377.043785) (xy 357.042373 -377.036028)
			(xy 357.069644 -377.035568) (xy 357.933244 -377.035568) (xy 357.960513 -377.035998) (xy 358.014497 -377.043765)
			(xy 358.066825 -377.059135) (xy 358.116433 -377.081796) (xy 358.162312 -377.111285) (xy 358.203528 -377.147003)
			(xy 358.239241 -377.188223) (xy 358.268725 -377.234105) (xy 358.29138 -377.283716) (xy 358.306744 -377.336047)
			(xy 358.314506 -377.39003) (xy 358.314506 -377.444567) (xy 367.435654 -377.444567) (xy 367.435654 -377.390033)
			(xy 367.443415 -377.336054) (xy 367.458779 -377.28373) (xy 367.481433 -377.234124) (xy 367.510916 -377.188247)
			(xy 367.546627 -377.147033) (xy 367.587841 -377.11132) (xy 367.633717 -377.081837) (xy 367.683322 -377.059182)
			(xy 367.735647 -377.043817) (xy 367.789625 -377.036055) (xy 367.816892 -377.035568) (xy 368.680492 -377.035568)
			(xy 368.707766 -377.035971) (xy 368.761757 -377.043733) (xy 368.814095 -377.0591) (xy 368.863713 -377.081759)
			(xy 368.909602 -377.111248) (xy 368.950826 -377.146968) (xy 368.986547 -377.188192) (xy 369.016038 -377.23408)
			(xy 369.038698 -377.283697) (xy 369.054065 -377.336035) (xy 369.061828 -377.390026) (xy 369.061828 -377.444567)
			(xy 374.242854 -377.444567) (xy 374.242854 -377.390033) (xy 374.250615 -377.336054) (xy 374.265979 -377.28373)
			(xy 374.288633 -377.234124) (xy 374.318116 -377.188247) (xy 374.353827 -377.147033) (xy 374.395041 -377.11132)
			(xy 374.440917 -377.081837) (xy 374.490522 -377.059182) (xy 374.542847 -377.043817) (xy 374.596825 -377.036055)
			(xy 374.624092 -377.035568) (xy 375.487692 -377.035568) (xy 375.514966 -377.035971) (xy 375.568957 -377.043733)
			(xy 375.621295 -377.0591) (xy 375.670913 -377.081759) (xy 375.716802 -377.111248) (xy 375.758026 -377.146968)
			(xy 375.793747 -377.188192) (xy 375.823238 -377.23408) (xy 375.845898 -377.283697) (xy 375.861265 -377.336035)
			(xy 375.869028 -377.390026) (xy 375.869028 -377.444567) (xy 381.050054 -377.444567) (xy 381.050054 -377.390033)
			(xy 381.057815 -377.336054) (xy 381.073179 -377.28373) (xy 381.095833 -377.234124) (xy 381.125316 -377.188247)
			(xy 381.161027 -377.147033) (xy 381.202241 -377.11132) (xy 381.248117 -377.081837) (xy 381.297722 -377.059182)
			(xy 381.350047 -377.043817) (xy 381.404025 -377.036055) (xy 381.431292 -377.035568) (xy 382.294892 -377.035568)
			(xy 382.322166 -377.035971) (xy 382.376157 -377.043733) (xy 382.428495 -377.0591) (xy 382.478113 -377.081759)
			(xy 382.524002 -377.111248) (xy 382.565226 -377.146968) (xy 382.600947 -377.188192) (xy 382.630438 -377.23408)
			(xy 382.653098 -377.283697) (xy 382.668465 -377.336035) (xy 382.676228 -377.390026) (xy 382.676228 -377.444567)
			(xy 387.857254 -377.444567) (xy 387.857254 -377.390033) (xy 387.865015 -377.336054) (xy 387.880379 -377.28373)
			(xy 387.903033 -377.234124) (xy 387.932516 -377.188247) (xy 387.968227 -377.147033) (xy 388.009441 -377.11132)
			(xy 388.055317 -377.081837) (xy 388.104922 -377.059182) (xy 388.157247 -377.043817) (xy 388.211225 -377.036055)
			(xy 388.238492 -377.035568) (xy 389.102092 -377.035568) (xy 389.129366 -377.035971) (xy 389.183357 -377.043733)
			(xy 389.235695 -377.0591) (xy 389.285313 -377.081759) (xy 389.331202 -377.111248) (xy 389.372426 -377.146968)
			(xy 389.408147 -377.188192) (xy 389.437638 -377.23408) (xy 389.460298 -377.283697) (xy 389.475665 -377.336035)
			(xy 389.483428 -377.390026) (xy 389.483428 -377.444567) (xy 391.260854 -377.444567) (xy 391.260854 -377.390033)
			(xy 391.268615 -377.336054) (xy 391.283979 -377.28373) (xy 391.306633 -377.234124) (xy 391.336116 -377.188247)
			(xy 391.371827 -377.147033) (xy 391.413041 -377.11132) (xy 391.458917 -377.081837) (xy 391.508522 -377.059182)
			(xy 391.560847 -377.043817) (xy 391.614825 -377.036055) (xy 391.642092 -377.035568) (xy 392.505692 -377.035568)
			(xy 392.532966 -377.035971) (xy 392.586957 -377.043733) (xy 392.639295 -377.0591) (xy 392.688913 -377.081759)
			(xy 392.734802 -377.111248) (xy 392.776026 -377.146968) (xy 392.811747 -377.188192) (xy 392.841238 -377.23408)
			(xy 392.863898 -377.283697) (xy 392.879265 -377.336035) (xy 392.887028 -377.390026) (xy 392.887028 -377.444571)
			(xy 399.963332 -377.444571) (xy 399.963332 -377.390029) (xy 399.971094 -377.336043) (xy 399.986461 -377.283711)
			(xy 400.00912 -377.234099) (xy 400.038609 -377.188217) (xy 400.074328 -377.147) (xy 400.11555 -377.111285)
			(xy 400.161435 -377.081801) (xy 400.211049 -377.059147) (xy 400.263382 -377.043786) (xy 400.317369 -377.036029)
			(xy 400.34464 -377.035568) (xy 401.20824 -377.035568) (xy 401.23551 -377.035997) (xy 401.289493 -377.043764)
			(xy 401.341822 -377.059134) (xy 401.391431 -377.081794) (xy 401.437311 -377.111284) (xy 401.478527 -377.147002)
			(xy 401.51424 -377.188222) (xy 401.543725 -377.234104) (xy 401.56638 -377.283716) (xy 401.581744 -377.336046)
			(xy 401.589506 -377.39003) (xy 401.589506 -377.44457) (xy 401.589506 -377.444571) (xy 406.770532 -377.444571)
			(xy 406.770532 -377.390029) (xy 406.778294 -377.336043) (xy 406.793661 -377.283711) (xy 406.81632 -377.234099)
			(xy 406.845809 -377.188217) (xy 406.881528 -377.147) (xy 406.92275 -377.111285) (xy 406.968635 -377.081801)
			(xy 407.018249 -377.059147) (xy 407.070582 -377.043786) (xy 407.124569 -377.036029) (xy 407.15184 -377.035568)
			(xy 408.01544 -377.035568) (xy 408.04271 -377.035997) (xy 408.096693 -377.043764) (xy 408.149022 -377.059134)
			(xy 408.198631 -377.081794) (xy 408.244511 -377.111284) (xy 408.285727 -377.147002) (xy 408.32144 -377.188222)
			(xy 408.350925 -377.234104) (xy 408.37358 -377.283716) (xy 408.388944 -377.336046) (xy 408.396706 -377.39003)
			(xy 408.396706 -377.44457) (xy 408.396706 -377.444571) (xy 413.577732 -377.444571) (xy 413.577732 -377.390029)
			(xy 413.585494 -377.336043) (xy 413.600861 -377.283711) (xy 413.62352 -377.234099) (xy 413.653009 -377.188217)
			(xy 413.688728 -377.147) (xy 413.72995 -377.111285) (xy 413.775835 -377.081801) (xy 413.825449 -377.059147)
			(xy 413.877782 -377.043786) (xy 413.931769 -377.036029) (xy 413.95904 -377.035568) (xy 414.82264 -377.035568)
			(xy 414.84991 -377.035997) (xy 414.903893 -377.043764) (xy 414.956222 -377.059134) (xy 415.005831 -377.081794)
			(xy 415.051711 -377.111284) (xy 415.092927 -377.147002) (xy 415.12864 -377.188222) (xy 415.158125 -377.234104)
			(xy 415.18078 -377.283716) (xy 415.196144 -377.336046) (xy 415.203906 -377.39003) (xy 415.203906 -377.44457)
			(xy 415.203906 -377.444571) (xy 420.384932 -377.444571) (xy 420.384932 -377.390029) (xy 420.392694 -377.336043)
			(xy 420.408061 -377.283711) (xy 420.43072 -377.234099) (xy 420.460209 -377.188217) (xy 420.495928 -377.147)
			(xy 420.53715 -377.111285) (xy 420.583035 -377.081801) (xy 420.632649 -377.059147) (xy 420.684982 -377.043786)
			(xy 420.738969 -377.036029) (xy 420.76624 -377.035568) (xy 421.62984 -377.035568) (xy 421.65711 -377.035997)
			(xy 421.711093 -377.043764) (xy 421.763422 -377.059134) (xy 421.813031 -377.081794) (xy 421.858911 -377.111284)
			(xy 421.900127 -377.147002) (xy 421.93584 -377.188222) (xy 421.965325 -377.234104) (xy 421.98798 -377.283716)
			(xy 422.003344 -377.336046) (xy 422.011106 -377.39003) (xy 422.011106 -377.44457) (xy 422.011106 -377.444571)
			(xy 423.788532 -377.444571) (xy 423.788532 -377.390029) (xy 423.796294 -377.336043) (xy 423.811661 -377.283711)
			(xy 423.83432 -377.234099) (xy 423.863809 -377.188217) (xy 423.899528 -377.147) (xy 423.94075 -377.111285)
			(xy 423.986635 -377.081801) (xy 424.036249 -377.059147) (xy 424.088582 -377.043786) (xy 424.142569 -377.036029)
			(xy 424.16984 -377.035568) (xy 425.03344 -377.035568) (xy 425.06071 -377.035997) (xy 425.114693 -377.043764)
			(xy 425.167022 -377.059134) (xy 425.216631 -377.081794) (xy 425.262511 -377.111284) (xy 425.303727 -377.147002)
			(xy 425.33944 -377.188222) (xy 425.368925 -377.234104) (xy 425.39158 -377.283716) (xy 425.406944 -377.336046)
			(xy 425.414706 -377.39003) (xy 425.414706 -377.44457) (xy 425.406944 -377.498554) (xy 425.39158 -377.550884)
			(xy 425.368925 -377.600496) (xy 425.33944 -377.646378) (xy 425.303727 -377.687598) (xy 425.262511 -377.723316)
			(xy 425.216631 -377.752806) (xy 425.167022 -377.775466) (xy 425.114693 -377.790836) (xy 425.06071 -377.798603)
			(xy 425.03344 -377.799092) (xy 424.16984 -377.799092) (xy 424.142569 -377.798571) (xy 424.088582 -377.790814)
			(xy 424.036249 -377.775453) (xy 423.986635 -377.752799) (xy 423.94075 -377.723315) (xy 423.899528 -377.6876)
			(xy 423.863809 -377.646383) (xy 423.83432 -377.600501) (xy 423.811661 -377.550889) (xy 423.796294 -377.498557)
			(xy 423.788532 -377.444571) (xy 422.011106 -377.444571) (xy 422.003344 -377.498554) (xy 421.98798 -377.550884)
			(xy 421.965325 -377.600496) (xy 421.93584 -377.646378) (xy 421.900127 -377.687598) (xy 421.858911 -377.723316)
			(xy 421.813031 -377.752806) (xy 421.763422 -377.775466) (xy 421.711093 -377.790836) (xy 421.65711 -377.798603)
			(xy 421.62984 -377.799092) (xy 420.76624 -377.799092) (xy 420.738969 -377.798571) (xy 420.684982 -377.790814)
			(xy 420.632649 -377.775453) (xy 420.583035 -377.752799) (xy 420.53715 -377.723315) (xy 420.495928 -377.6876)
			(xy 420.460209 -377.646383) (xy 420.43072 -377.600501) (xy 420.408061 -377.550889) (xy 420.392694 -377.498557)
			(xy 420.384932 -377.444571) (xy 415.203906 -377.444571) (xy 415.196144 -377.498554) (xy 415.18078 -377.550884)
			(xy 415.158125 -377.600496) (xy 415.12864 -377.646378) (xy 415.092927 -377.687598) (xy 415.051711 -377.723316)
			(xy 415.005831 -377.752806) (xy 414.956222 -377.775466) (xy 414.903893 -377.790836) (xy 414.84991 -377.798603)
			(xy 414.82264 -377.799092) (xy 413.95904 -377.799092) (xy 413.931769 -377.798571) (xy 413.877782 -377.790814)
			(xy 413.825449 -377.775453) (xy 413.775835 -377.752799) (xy 413.72995 -377.723315) (xy 413.688728 -377.6876)
			(xy 413.653009 -377.646383) (xy 413.62352 -377.600501) (xy 413.600861 -377.550889) (xy 413.585494 -377.498557)
			(xy 413.577732 -377.444571) (xy 408.396706 -377.444571) (xy 408.388944 -377.498554) (xy 408.37358 -377.550884)
			(xy 408.350925 -377.600496) (xy 408.32144 -377.646378) (xy 408.285727 -377.687598) (xy 408.244511 -377.723316)
			(xy 408.198631 -377.752806) (xy 408.149022 -377.775466) (xy 408.096693 -377.790836) (xy 408.04271 -377.798603)
			(xy 408.01544 -377.799092) (xy 407.15184 -377.799092) (xy 407.124569 -377.798571) (xy 407.070582 -377.790814)
			(xy 407.018249 -377.775453) (xy 406.968635 -377.752799) (xy 406.92275 -377.723315) (xy 406.881528 -377.6876)
			(xy 406.845809 -377.646383) (xy 406.81632 -377.600501) (xy 406.793661 -377.550889) (xy 406.778294 -377.498557)
			(xy 406.770532 -377.444571) (xy 401.589506 -377.444571) (xy 401.581744 -377.498554) (xy 401.56638 -377.550884)
			(xy 401.543725 -377.600496) (xy 401.51424 -377.646378) (xy 401.478527 -377.687598) (xy 401.437311 -377.723316)
			(xy 401.391431 -377.752806) (xy 401.341822 -377.775466) (xy 401.289493 -377.790836) (xy 401.23551 -377.798603)
			(xy 401.20824 -377.799092) (xy 400.34464 -377.799092) (xy 400.317369 -377.798571) (xy 400.263382 -377.790814)
			(xy 400.211049 -377.775453) (xy 400.161435 -377.752799) (xy 400.11555 -377.723315) (xy 400.074328 -377.6876)
			(xy 400.038609 -377.646383) (xy 400.00912 -377.600501) (xy 399.986461 -377.550889) (xy 399.971094 -377.498557)
			(xy 399.963332 -377.444571) (xy 392.887028 -377.444571) (xy 392.887028 -377.444574) (xy 392.879265 -377.498565)
			(xy 392.863898 -377.550903) (xy 392.841238 -377.60052) (xy 392.811747 -377.646408) (xy 392.776026 -377.687632)
			(xy 392.734802 -377.723352) (xy 392.688913 -377.752841) (xy 392.639295 -377.7755) (xy 392.586957 -377.790867)
			(xy 392.532966 -377.798629) (xy 392.505692 -377.799092) (xy 391.642092 -377.799092) (xy 391.614825 -377.798545)
			(xy 391.560847 -377.790783) (xy 391.508522 -377.775418) (xy 391.458917 -377.752763) (xy 391.413041 -377.72328)
			(xy 391.371827 -377.687567) (xy 391.336116 -377.646353) (xy 391.306633 -377.600476) (xy 391.283979 -377.55087)
			(xy 391.268615 -377.498546) (xy 391.260854 -377.444567) (xy 389.483428 -377.444567) (xy 389.483428 -377.444574)
			(xy 389.475665 -377.498565) (xy 389.460298 -377.550903) (xy 389.437638 -377.60052) (xy 389.408147 -377.646408)
			(xy 389.372426 -377.687632) (xy 389.331202 -377.723352) (xy 389.285313 -377.752841) (xy 389.235695 -377.7755)
			(xy 389.183357 -377.790867) (xy 389.129366 -377.798629) (xy 389.102092 -377.799092) (xy 388.238492 -377.799092)
			(xy 388.211225 -377.798545) (xy 388.157247 -377.790783) (xy 388.104922 -377.775418) (xy 388.055317 -377.752763)
			(xy 388.009441 -377.72328) (xy 387.968227 -377.687567) (xy 387.932516 -377.646353) (xy 387.903033 -377.600476)
			(xy 387.880379 -377.55087) (xy 387.865015 -377.498546) (xy 387.857254 -377.444567) (xy 382.676228 -377.444567)
			(xy 382.676228 -377.444574) (xy 382.668465 -377.498565) (xy 382.653098 -377.550903) (xy 382.630438 -377.60052)
			(xy 382.600947 -377.646408) (xy 382.565226 -377.687632) (xy 382.524002 -377.723352) (xy 382.478113 -377.752841)
			(xy 382.428495 -377.7755) (xy 382.376157 -377.790867) (xy 382.322166 -377.798629) (xy 382.294892 -377.799092)
			(xy 381.431292 -377.799092) (xy 381.404025 -377.798545) (xy 381.350047 -377.790783) (xy 381.297722 -377.775418)
			(xy 381.248117 -377.752763) (xy 381.202241 -377.72328) (xy 381.161027 -377.687567) (xy 381.125316 -377.646353)
			(xy 381.095833 -377.600476) (xy 381.073179 -377.55087) (xy 381.057815 -377.498546) (xy 381.050054 -377.444567)
			(xy 375.869028 -377.444567) (xy 375.869028 -377.444574) (xy 375.861265 -377.498565) (xy 375.845898 -377.550903)
			(xy 375.823238 -377.60052) (xy 375.793747 -377.646408) (xy 375.758026 -377.687632) (xy 375.716802 -377.723352)
			(xy 375.670913 -377.752841) (xy 375.621295 -377.7755) (xy 375.568957 -377.790867) (xy 375.514966 -377.798629)
			(xy 375.487692 -377.799092) (xy 374.624092 -377.799092) (xy 374.596825 -377.798545) (xy 374.542847 -377.790783)
			(xy 374.490522 -377.775418) (xy 374.440917 -377.752763) (xy 374.395041 -377.72328) (xy 374.353827 -377.687567)
			(xy 374.318116 -377.646353) (xy 374.288633 -377.600476) (xy 374.265979 -377.55087) (xy 374.250615 -377.498546)
			(xy 374.242854 -377.444567) (xy 369.061828 -377.444567) (xy 369.061828 -377.444574) (xy 369.054065 -377.498565)
			(xy 369.038698 -377.550903) (xy 369.016038 -377.60052) (xy 368.986547 -377.646408) (xy 368.950826 -377.687632)
			(xy 368.909602 -377.723352) (xy 368.863713 -377.752841) (xy 368.814095 -377.7755) (xy 368.761757 -377.790867)
			(xy 368.707766 -377.798629) (xy 368.680492 -377.799092) (xy 367.816892 -377.799092) (xy 367.789625 -377.798545)
			(xy 367.735647 -377.790783) (xy 367.683322 -377.775418) (xy 367.633717 -377.752763) (xy 367.587841 -377.72328)
			(xy 367.546627 -377.687567) (xy 367.510916 -377.646353) (xy 367.481433 -377.600476) (xy 367.458779 -377.55087)
			(xy 367.443415 -377.498546) (xy 367.435654 -377.444567) (xy 358.314506 -377.444567) (xy 358.314506 -377.44457)
			(xy 358.306744 -377.498553) (xy 358.29138 -377.550884) (xy 358.268725 -377.600495) (xy 358.239241 -377.646377)
			(xy 358.203528 -377.687597) (xy 358.162312 -377.723315) (xy 358.116433 -377.752804) (xy 358.066825 -377.775465)
			(xy 358.014497 -377.790835) (xy 357.960513 -377.798602) (xy 357.933244 -377.799092) (xy 357.069644 -377.799092)
			(xy 357.042373 -377.798572) (xy 356.988386 -377.790815) (xy 356.936052 -377.775454) (xy 356.886437 -377.752801)
			(xy 356.840551 -377.723316) (xy 356.799329 -377.687602) (xy 356.76361 -377.646384) (xy 356.734121 -377.600502)
			(xy 356.711461 -377.550889) (xy 356.696094 -377.498557) (xy 356.688332 -377.444571) (xy 354.910906 -377.444571)
			(xy 354.903144 -377.498553) (xy 354.88778 -377.550884) (xy 354.865125 -377.600495) (xy 354.835641 -377.646377)
			(xy 354.799928 -377.687597) (xy 354.758712 -377.723315) (xy 354.712833 -377.752804) (xy 354.663225 -377.775465)
			(xy 354.610897 -377.790835) (xy 354.556913 -377.798602) (xy 354.529644 -377.799092) (xy 353.666044 -377.799092)
			(xy 353.638773 -377.798572) (xy 353.584786 -377.790815) (xy 353.532452 -377.775454) (xy 353.482837 -377.752801)
			(xy 353.436951 -377.723316) (xy 353.395729 -377.687602) (xy 353.36001 -377.646384) (xy 353.330521 -377.600502)
			(xy 353.307861 -377.550889) (xy 353.292494 -377.498557) (xy 353.284732 -377.444571) (xy 348.103706 -377.444571)
			(xy 348.095944 -377.498553) (xy 348.08058 -377.550884) (xy 348.057925 -377.600495) (xy 348.028441 -377.646377)
			(xy 347.992728 -377.687597) (xy 347.951512 -377.723315) (xy 347.905633 -377.752804) (xy 347.856025 -377.775465)
			(xy 347.803697 -377.790835) (xy 347.749713 -377.798602) (xy 347.722444 -377.799092) (xy 346.858844 -377.799092)
			(xy 346.831573 -377.798572) (xy 346.777586 -377.790815) (xy 346.725252 -377.775454) (xy 346.675637 -377.752801)
			(xy 346.629751 -377.723316) (xy 346.588529 -377.687602) (xy 346.55281 -377.646384) (xy 346.523321 -377.600502)
			(xy 346.500661 -377.550889) (xy 346.485294 -377.498557) (xy 346.477532 -377.444571) (xy 341.296506 -377.444571)
			(xy 341.288744 -377.498553) (xy 341.27338 -377.550884) (xy 341.250725 -377.600495) (xy 341.221241 -377.646377)
			(xy 341.185528 -377.687597) (xy 341.144312 -377.723315) (xy 341.098433 -377.752804) (xy 341.048825 -377.775465)
			(xy 340.996497 -377.790835) (xy 340.942513 -377.798602) (xy 340.915244 -377.799092) (xy 340.051644 -377.799092)
			(xy 340.024373 -377.798572) (xy 339.970386 -377.790815) (xy 339.918052 -377.775454) (xy 339.868437 -377.752801)
			(xy 339.822551 -377.723316) (xy 339.781329 -377.687602) (xy 339.74561 -377.646384) (xy 339.716121 -377.600502)
			(xy 339.693461 -377.550889) (xy 339.678094 -377.498557) (xy 339.670332 -377.444571) (xy 334.489306 -377.444571)
			(xy 334.481544 -377.498553) (xy 334.46618 -377.550884) (xy 334.443525 -377.600495) (xy 334.414041 -377.646377)
			(xy 334.378328 -377.687597) (xy 334.337112 -377.723315) (xy 334.291233 -377.752804) (xy 334.241625 -377.775465)
			(xy 334.189297 -377.790835) (xy 334.135313 -377.798602) (xy 334.108044 -377.799092) (xy 333.244444 -377.799092)
			(xy 333.217173 -377.798572) (xy 333.163186 -377.790815) (xy 333.110852 -377.775454) (xy 333.061237 -377.752801)
			(xy 333.015351 -377.723316) (xy 332.974129 -377.687602) (xy 332.93841 -377.646384) (xy 332.908921 -377.600502)
			(xy 332.886261 -377.550889) (xy 332.870894 -377.498557) (xy 332.863132 -377.444571) (xy 325.786828 -377.444571)
			(xy 325.786828 -377.444573) (xy 325.779066 -377.498565) (xy 325.763698 -377.550902) (xy 325.741038 -377.600519)
			(xy 325.711548 -377.646407) (xy 325.675827 -377.68763) (xy 325.634603 -377.72335) (xy 325.588716 -377.75284)
			(xy 325.539098 -377.775499) (xy 325.486761 -377.790866) (xy 325.432769 -377.798629) (xy 325.405496 -377.799092)
			(xy 324.541896 -377.799092) (xy 324.514629 -377.798545) (xy 324.46065 -377.790784) (xy 324.408325 -377.775419)
			(xy 324.358719 -377.752765) (xy 324.312842 -377.723281) (xy 324.271629 -377.687569) (xy 324.235917 -377.646354)
			(xy 324.206433 -377.600477) (xy 324.183779 -377.550871) (xy 324.168415 -377.498546) (xy 324.160654 -377.444567)
			(xy 322.383228 -377.444567) (xy 322.383228 -377.444573) (xy 322.375466 -377.498565) (xy 322.360098 -377.550902)
			(xy 322.337438 -377.600519) (xy 322.307948 -377.646407) (xy 322.272227 -377.68763) (xy 322.231003 -377.72335)
			(xy 322.185116 -377.75284) (xy 322.135498 -377.775499) (xy 322.083161 -377.790866) (xy 322.029169 -377.798629)
			(xy 322.001896 -377.799092) (xy 321.138296 -377.799092) (xy 321.111029 -377.798545) (xy 321.05705 -377.790784)
			(xy 321.004725 -377.775419) (xy 320.955119 -377.752765) (xy 320.909242 -377.723281) (xy 320.868029 -377.687569)
			(xy 320.832317 -377.646354) (xy 320.802833 -377.600477) (xy 320.780179 -377.550871) (xy 320.764815 -377.498546)
			(xy 320.757054 -377.444567) (xy 315.576028 -377.444567) (xy 315.576028 -377.444573) (xy 315.568266 -377.498565)
			(xy 315.552898 -377.550902) (xy 315.530238 -377.600519) (xy 315.500748 -377.646407) (xy 315.465027 -377.68763)
			(xy 315.423803 -377.72335) (xy 315.377916 -377.75284) (xy 315.328298 -377.775499) (xy 315.275961 -377.790866)
			(xy 315.221969 -377.798629) (xy 315.194696 -377.799092) (xy 314.331096 -377.799092) (xy 314.303829 -377.798545)
			(xy 314.24985 -377.790784) (xy 314.197525 -377.775419) (xy 314.147919 -377.752765) (xy 314.102042 -377.723281)
			(xy 314.060829 -377.687569) (xy 314.025117 -377.646354) (xy 313.995633 -377.600477) (xy 313.972979 -377.550871)
			(xy 313.957615 -377.498546) (xy 313.949854 -377.444567) (xy 308.768828 -377.444567) (xy 308.768828 -377.444573)
			(xy 308.761066 -377.498565) (xy 308.745698 -377.550902) (xy 308.723038 -377.600519) (xy 308.693548 -377.646407)
			(xy 308.657827 -377.68763) (xy 308.616603 -377.72335) (xy 308.570716 -377.75284) (xy 308.521098 -377.775499)
			(xy 308.468761 -377.790866) (xy 308.414769 -377.798629) (xy 308.387496 -377.799092) (xy 307.523896 -377.799092)
			(xy 307.496629 -377.798545) (xy 307.44265 -377.790784) (xy 307.390325 -377.775419) (xy 307.340719 -377.752765)
			(xy 307.294842 -377.723281) (xy 307.253629 -377.687569) (xy 307.217917 -377.646354) (xy 307.188433 -377.600477)
			(xy 307.165779 -377.550871) (xy 307.150415 -377.498546) (xy 307.142654 -377.444567) (xy 301.961628 -377.444567)
			(xy 301.961628 -377.444573) (xy 301.953866 -377.498565) (xy 301.938498 -377.550902) (xy 301.915838 -377.600519)
			(xy 301.886348 -377.646407) (xy 301.850627 -377.68763) (xy 301.809403 -377.72335) (xy 301.763516 -377.75284)
			(xy 301.713898 -377.775499) (xy 301.661561 -377.790866) (xy 301.607569 -377.798629) (xy 301.580296 -377.799092)
			(xy 300.716696 -377.799092) (xy 300.689429 -377.798545) (xy 300.63545 -377.790784) (xy 300.583125 -377.775419)
			(xy 300.533519 -377.752765) (xy 300.487642 -377.723281) (xy 300.446429 -377.687569) (xy 300.410717 -377.646354)
			(xy 300.381233 -377.600477) (xy 300.358579 -377.550871) (xy 300.343215 -377.498546) (xy 300.335454 -377.444567)
			(xy 200.859958 -377.444567) (xy 200.882666 -377.460737) (xy 200.946694 -377.516218) (xy 201.005159 -377.577533)
			(xy 201.05753 -377.644129) (xy 201.103333 -377.715401) (xy 201.142155 -377.790704) (xy 201.173643 -377.869356)
			(xy 201.197511 -377.950646) (xy 201.213545 -378.033836) (xy 201.221598 -378.118173) (xy 201.222102 -378.160534)
			(xy 201.221598 -378.202895) (xy 201.213545 -378.287232) (xy 201.197511 -378.370422) (xy 201.173643 -378.451712)
			(xy 201.142155 -378.530364) (xy 201.103333 -378.605667) (xy 201.05753 -378.676939) (xy 201.005159 -378.743535)
			(xy 200.946694 -378.80485) (xy 200.882666 -378.860331) (xy 200.813654 -378.909474) (xy 200.740284 -378.951834)
			(xy 200.663219 -378.987029) (xy 200.583157 -379.014738) (xy 200.500824 -379.034712) (xy 200.416965 -379.046769)
			(xy 200.33234 -379.050801) (xy 200.247715 -379.046769) (xy 200.163856 -379.034712) (xy 200.081523 -379.014738)
			(xy 200.001461 -378.987029) (xy 199.924396 -378.951834) (xy 199.851026 -378.909474) (xy 199.782014 -378.860331)
			(xy 199.717986 -378.80485) (xy 199.659521 -378.743535) (xy 199.60715 -378.676939) (xy 199.561347 -378.605667)
			(xy 199.522525 -378.530364) (xy 199.491037 -378.451712) (xy 199.467169 -378.370422) (xy 199.451135 -378.287232)
			(xy 199.443082 -378.202895) (xy 195.47531 -378.202895) (xy 195.462625 -378.219025) (xy 195.40416 -378.28034)
			(xy 195.340132 -378.335821) (xy 195.27112 -378.384964) (xy 195.19775 -378.427324) (xy 195.120685 -378.462519)
			(xy 195.040623 -378.490228) (xy 194.95829 -378.510202) (xy 194.874431 -378.522259) (xy 194.789806 -378.526291)
			(xy 194.705181 -378.522259) (xy 194.621322 -378.510202) (xy 194.538989 -378.490228) (xy 194.458927 -378.462519)
			(xy 194.381862 -378.427324) (xy 194.308492 -378.384964) (xy 194.23948 -378.335821) (xy 194.175452 -378.28034)
			(xy 194.116987 -378.219025) (xy 194.064616 -378.152429) (xy 194.018813 -378.081157) (xy 193.979991 -378.005854)
			(xy 193.948503 -377.927202) (xy 193.924635 -377.845912) (xy 193.908601 -377.762722) (xy 193.900548 -377.678385)
			(xy 181.319901 -377.678385) (xy 181.279884 -377.802486) (xy 181.217663 -377.969563) (xy 181.148062 -378.133704)
			(xy 181.071217 -378.29458) (xy 180.987283 -378.451874) (xy 180.896425 -378.605273) (xy 180.798823 -378.754472)
			(xy 180.694672 -378.899175) (xy 180.584179 -379.039095) (xy 180.467562 -379.173954) (xy 180.345053 -379.303484)
			(xy 180.216896 -379.427428) (xy 180.083345 -379.54554) (xy 179.944665 -379.657585) (xy 179.801131 -379.763342)
			(xy 179.653028 -379.862599) (xy 179.577684 -379.908367) (xy 298.633654 -379.908367) (xy 298.633654 -379.853833)
			(xy 298.641415 -379.799854) (xy 298.656779 -379.747529) (xy 298.679433 -379.697923) (xy 298.708917 -379.652046)
			(xy 298.744629 -379.610831) (xy 298.785842 -379.575119) (xy 298.831719 -379.545635) (xy 298.881325 -379.522981)
			(xy 298.93365 -379.507616) (xy 298.987629 -379.499855) (xy 299.014896 -379.499368) (xy 299.878496 -379.499368)
			(xy 299.905769 -379.499771) (xy 299.959761 -379.507534) (xy 300.012098 -379.522901) (xy 300.061716 -379.54556)
			(xy 300.107603 -379.57505) (xy 300.148827 -379.61077) (xy 300.184548 -379.651993) (xy 300.214038 -379.697881)
			(xy 300.236698 -379.747498) (xy 300.252066 -379.799835) (xy 300.259828 -379.853827) (xy 300.259828 -379.908367)
			(xy 305.440854 -379.908367) (xy 305.440854 -379.853833) (xy 305.448615 -379.799854) (xy 305.463979 -379.747529)
			(xy 305.486633 -379.697923) (xy 305.516117 -379.652046) (xy 305.551829 -379.610831) (xy 305.593042 -379.575119)
			(xy 305.638919 -379.545635) (xy 305.688525 -379.522981) (xy 305.74085 -379.507616) (xy 305.794829 -379.499855)
			(xy 305.822096 -379.499368) (xy 306.685696 -379.499368) (xy 306.712969 -379.499771) (xy 306.766961 -379.507534)
			(xy 306.819298 -379.522901) (xy 306.868916 -379.54556) (xy 306.914803 -379.57505) (xy 306.956027 -379.61077)
			(xy 306.991748 -379.651993) (xy 307.021238 -379.697881) (xy 307.043898 -379.747498) (xy 307.059266 -379.799835)
			(xy 307.067028 -379.853827) (xy 307.067028 -379.908367) (xy 312.248054 -379.908367) (xy 312.248054 -379.853833)
			(xy 312.255815 -379.799854) (xy 312.271179 -379.747529) (xy 312.293833 -379.697923) (xy 312.323317 -379.652046)
			(xy 312.359029 -379.610831) (xy 312.400242 -379.575119) (xy 312.446119 -379.545635) (xy 312.495725 -379.522981)
			(xy 312.54805 -379.507616) (xy 312.602029 -379.499855) (xy 312.629296 -379.499368) (xy 313.492896 -379.499368)
			(xy 313.520169 -379.499771) (xy 313.574161 -379.507534) (xy 313.626498 -379.522901) (xy 313.676116 -379.54556)
			(xy 313.722003 -379.57505) (xy 313.763227 -379.61077) (xy 313.798948 -379.651993) (xy 313.828438 -379.697881)
			(xy 313.851098 -379.747498) (xy 313.866466 -379.799835) (xy 313.874228 -379.853827) (xy 313.874228 -379.908367)
			(xy 319.055254 -379.908367) (xy 319.055254 -379.853833) (xy 319.063015 -379.799854) (xy 319.078379 -379.747529)
			(xy 319.101033 -379.697923) (xy 319.130517 -379.652046) (xy 319.166229 -379.610831) (xy 319.207442 -379.575119)
			(xy 319.253319 -379.545635) (xy 319.302925 -379.522981) (xy 319.35525 -379.507616) (xy 319.409229 -379.499855)
			(xy 319.436496 -379.499368) (xy 320.300096 -379.499368) (xy 320.327369 -379.499771) (xy 320.381361 -379.507534)
			(xy 320.433698 -379.522901) (xy 320.483316 -379.54556) (xy 320.529203 -379.57505) (xy 320.570427 -379.61077)
			(xy 320.606148 -379.651993) (xy 320.635638 -379.697881) (xy 320.658298 -379.747498) (xy 320.673666 -379.799835)
			(xy 320.681428 -379.853827) (xy 320.681428 -379.908371) (xy 331.161332 -379.908371) (xy 331.161332 -379.853829)
			(xy 331.169094 -379.799843) (xy 331.184461 -379.747511) (xy 331.207121 -379.697898) (xy 331.23661 -379.652016)
			(xy 331.272329 -379.610798) (xy 331.313551 -379.575084) (xy 331.359437 -379.545599) (xy 331.409052 -379.522946)
			(xy 331.461386 -379.507585) (xy 331.515373 -379.499828) (xy 331.542644 -379.499368) (xy 332.406244 -379.499368)
			(xy 332.433513 -379.499798) (xy 332.487497 -379.507565) (xy 332.539825 -379.522935) (xy 332.589433 -379.545596)
			(xy 332.635312 -379.575085) (xy 332.676528 -379.610803) (xy 332.712241 -379.652023) (xy 332.741725 -379.697905)
			(xy 332.76438 -379.747516) (xy 332.779744 -379.799847) (xy 332.787506 -379.85383) (xy 332.787506 -379.90837)
			(xy 332.787506 -379.908371) (xy 337.968532 -379.908371) (xy 337.968532 -379.853829) (xy 337.976294 -379.799843)
			(xy 337.991661 -379.747511) (xy 338.014321 -379.697898) (xy 338.04381 -379.652016) (xy 338.079529 -379.610798)
			(xy 338.120751 -379.575084) (xy 338.166637 -379.545599) (xy 338.216252 -379.522946) (xy 338.268586 -379.507585)
			(xy 338.322573 -379.499828) (xy 338.349844 -379.499368) (xy 339.213444 -379.499368) (xy 339.240713 -379.499798)
			(xy 339.294697 -379.507565) (xy 339.347025 -379.522935) (xy 339.396633 -379.545596) (xy 339.442512 -379.575085)
			(xy 339.483728 -379.610803) (xy 339.519441 -379.652023) (xy 339.548925 -379.697905) (xy 339.57158 -379.747516)
			(xy 339.586944 -379.799847) (xy 339.594706 -379.85383) (xy 339.594706 -379.90837) (xy 339.594706 -379.908371)
			(xy 344.775732 -379.908371) (xy 344.775732 -379.853829) (xy 344.783494 -379.799843) (xy 344.798861 -379.747511)
			(xy 344.821521 -379.697898) (xy 344.85101 -379.652016) (xy 344.886729 -379.610798) (xy 344.927951 -379.575084)
			(xy 344.973837 -379.545599) (xy 345.023452 -379.522946) (xy 345.075786 -379.507585) (xy 345.129773 -379.499828)
			(xy 345.157044 -379.499368) (xy 346.020644 -379.499368) (xy 346.047913 -379.499798) (xy 346.101897 -379.507565)
			(xy 346.154225 -379.522935) (xy 346.203833 -379.545596) (xy 346.249712 -379.575085) (xy 346.290928 -379.610803)
			(xy 346.326641 -379.652023) (xy 346.356125 -379.697905) (xy 346.37878 -379.747516) (xy 346.394144 -379.799847)
			(xy 346.401906 -379.85383) (xy 346.401906 -379.90837) (xy 346.401906 -379.908371) (xy 351.582932 -379.908371)
			(xy 351.582932 -379.853829) (xy 351.590694 -379.799843) (xy 351.606061 -379.747511) (xy 351.628721 -379.697898)
			(xy 351.65821 -379.652016) (xy 351.693929 -379.610798) (xy 351.735151 -379.575084) (xy 351.781037 -379.545599)
			(xy 351.830652 -379.522946) (xy 351.882986 -379.507585) (xy 351.936973 -379.499828) (xy 351.964244 -379.499368)
			(xy 352.827844 -379.499368) (xy 352.855113 -379.499798) (xy 352.909097 -379.507565) (xy 352.961425 -379.522935)
			(xy 353.011033 -379.545596) (xy 353.056912 -379.575085) (xy 353.098128 -379.610803) (xy 353.133841 -379.652023)
			(xy 353.163325 -379.697905) (xy 353.18598 -379.747516) (xy 353.201344 -379.799847) (xy 353.209106 -379.85383)
			(xy 353.209106 -379.908367) (xy 365.733854 -379.908367) (xy 365.733854 -379.853833) (xy 365.741615 -379.799854)
			(xy 365.756979 -379.74753) (xy 365.779633 -379.697924) (xy 365.809116 -379.652047) (xy 365.844827 -379.610833)
			(xy 365.886041 -379.57512) (xy 365.931917 -379.545637) (xy 365.981522 -379.522982) (xy 366.033847 -379.507617)
			(xy 366.087825 -379.499855) (xy 366.115092 -379.499368) (xy 366.978692 -379.499368) (xy 367.005966 -379.499771)
			(xy 367.059957 -379.507533) (xy 367.112295 -379.5229) (xy 367.161913 -379.545559) (xy 367.207802 -379.575048)
			(xy 367.249026 -379.610768) (xy 367.284747 -379.651992) (xy 367.314238 -379.69788) (xy 367.336898 -379.747497)
			(xy 367.352265 -379.799835) (xy 367.360028 -379.853826) (xy 367.360028 -379.908367) (xy 372.541054 -379.908367)
			(xy 372.541054 -379.853833) (xy 372.548815 -379.799854) (xy 372.564179 -379.74753) (xy 372.586833 -379.697924)
			(xy 372.616316 -379.652047) (xy 372.652027 -379.610833) (xy 372.693241 -379.57512) (xy 372.739117 -379.545637)
			(xy 372.788722 -379.522982) (xy 372.841047 -379.507617) (xy 372.895025 -379.499855) (xy 372.922292 -379.499368)
			(xy 373.785892 -379.499368) (xy 373.813166 -379.499771) (xy 373.867157 -379.507533) (xy 373.919495 -379.5229)
			(xy 373.969113 -379.545559) (xy 374.015002 -379.575048) (xy 374.056226 -379.610768) (xy 374.091947 -379.651992)
			(xy 374.121438 -379.69788) (xy 374.144098 -379.747497) (xy 374.159465 -379.799835) (xy 374.167228 -379.853826)
			(xy 374.167228 -379.908367) (xy 379.348254 -379.908367) (xy 379.348254 -379.853833) (xy 379.356015 -379.799854)
			(xy 379.371379 -379.74753) (xy 379.394033 -379.697924) (xy 379.423516 -379.652047) (xy 379.459227 -379.610833)
			(xy 379.500441 -379.57512) (xy 379.546317 -379.545637) (xy 379.595922 -379.522982) (xy 379.648247 -379.507617)
			(xy 379.702225 -379.499855) (xy 379.729492 -379.499368) (xy 380.593092 -379.499368) (xy 380.620366 -379.499771)
			(xy 380.674357 -379.507533) (xy 380.726695 -379.5229) (xy 380.776313 -379.545559) (xy 380.822202 -379.575048)
			(xy 380.863426 -379.610768) (xy 380.899147 -379.651992) (xy 380.928638 -379.69788) (xy 380.951298 -379.747497)
			(xy 380.966665 -379.799835) (xy 380.974428 -379.853826) (xy 380.974428 -379.908367) (xy 386.155454 -379.908367)
			(xy 386.155454 -379.853833) (xy 386.163215 -379.799854) (xy 386.178579 -379.74753) (xy 386.201233 -379.697924)
			(xy 386.230716 -379.652047) (xy 386.266427 -379.610833) (xy 386.307641 -379.57512) (xy 386.353517 -379.545637)
			(xy 386.403122 -379.522982) (xy 386.455447 -379.507617) (xy 386.509425 -379.499855) (xy 386.536692 -379.499368)
			(xy 387.400292 -379.499368) (xy 387.427566 -379.499771) (xy 387.481557 -379.507533) (xy 387.533895 -379.5229)
			(xy 387.583513 -379.545559) (xy 387.629402 -379.575048) (xy 387.670626 -379.610768) (xy 387.706347 -379.651992)
			(xy 387.735838 -379.69788) (xy 387.758498 -379.747497) (xy 387.773865 -379.799835) (xy 387.781628 -379.853826)
			(xy 387.781628 -379.908371) (xy 398.261532 -379.908371) (xy 398.261532 -379.853829) (xy 398.269294 -379.799843)
			(xy 398.284661 -379.747511) (xy 398.30732 -379.697899) (xy 398.336809 -379.652017) (xy 398.372528 -379.6108)
			(xy 398.41375 -379.575085) (xy 398.459635 -379.545601) (xy 398.509249 -379.522947) (xy 398.561582 -379.507586)
			(xy 398.615569 -379.499829) (xy 398.64284 -379.499368) (xy 399.50644 -379.499368) (xy 399.53371 -379.499797)
			(xy 399.587693 -379.507564) (xy 399.640022 -379.522934) (xy 399.689631 -379.545594) (xy 399.735511 -379.575084)
			(xy 399.776727 -379.610802) (xy 399.81244 -379.652022) (xy 399.841925 -379.697904) (xy 399.86458 -379.747516)
			(xy 399.879944 -379.799846) (xy 399.887706 -379.85383) (xy 399.887706 -379.90837) (xy 399.887706 -379.908371)
			(xy 405.068732 -379.908371) (xy 405.068732 -379.853829) (xy 405.076494 -379.799843) (xy 405.091861 -379.747511)
			(xy 405.11452 -379.697899) (xy 405.144009 -379.652017) (xy 405.179728 -379.6108) (xy 405.22095 -379.575085)
			(xy 405.266835 -379.545601) (xy 405.316449 -379.522947) (xy 405.368782 -379.507586) (xy 405.422769 -379.499829)
			(xy 405.45004 -379.499368) (xy 406.31364 -379.499368) (xy 406.34091 -379.499797) (xy 406.394893 -379.507564)
			(xy 406.447222 -379.522934) (xy 406.496831 -379.545594) (xy 406.542711 -379.575084) (xy 406.583927 -379.610802)
			(xy 406.61964 -379.652022) (xy 406.649125 -379.697904) (xy 406.67178 -379.747516) (xy 406.687144 -379.799846)
			(xy 406.694906 -379.85383) (xy 406.694906 -379.90837) (xy 406.694906 -379.908371) (xy 411.875932 -379.908371)
			(xy 411.875932 -379.853829) (xy 411.883694 -379.799843) (xy 411.899061 -379.747511) (xy 411.92172 -379.697899)
			(xy 411.951209 -379.652017) (xy 411.986928 -379.6108) (xy 412.02815 -379.575085) (xy 412.074035 -379.545601)
			(xy 412.123649 -379.522947) (xy 412.175982 -379.507586) (xy 412.229969 -379.499829) (xy 412.25724 -379.499368)
			(xy 413.12084 -379.499368) (xy 413.14811 -379.499797) (xy 413.202093 -379.507564) (xy 413.254422 -379.522934)
			(xy 413.304031 -379.545594) (xy 413.349911 -379.575084) (xy 413.391127 -379.610802) (xy 413.42684 -379.652022)
			(xy 413.456325 -379.697904) (xy 413.47898 -379.747516) (xy 413.494344 -379.799846) (xy 413.502106 -379.85383)
			(xy 413.502106 -379.90837) (xy 413.502106 -379.908371) (xy 418.683132 -379.908371) (xy 418.683132 -379.853829)
			(xy 418.690894 -379.799843) (xy 418.706261 -379.747511) (xy 418.72892 -379.697899) (xy 418.758409 -379.652017)
			(xy 418.794128 -379.6108) (xy 418.83535 -379.575085) (xy 418.881235 -379.545601) (xy 418.930849 -379.522947)
			(xy 418.983182 -379.507586) (xy 419.037169 -379.499829) (xy 419.06444 -379.499368) (xy 419.92804 -379.499368)
			(xy 419.95531 -379.499797) (xy 420.009293 -379.507564) (xy 420.061622 -379.522934) (xy 420.111231 -379.545594)
			(xy 420.157111 -379.575084) (xy 420.198327 -379.610802) (xy 420.23404 -379.652022) (xy 420.263525 -379.697904)
			(xy 420.28618 -379.747516) (xy 420.301544 -379.799846) (xy 420.309306 -379.85383) (xy 420.309306 -379.90837)
			(xy 420.301544 -379.962354) (xy 420.28618 -380.014684) (xy 420.263525 -380.064296) (xy 420.23404 -380.110178)
			(xy 420.198327 -380.151398) (xy 420.157111 -380.187116) (xy 420.111231 -380.216606) (xy 420.061622 -380.239266)
			(xy 420.009293 -380.254636) (xy 419.95531 -380.262403) (xy 419.92804 -380.262892) (xy 419.06444 -380.262892)
			(xy 419.037169 -380.262371) (xy 418.983182 -380.254614) (xy 418.930849 -380.239253) (xy 418.881235 -380.216599)
			(xy 418.83535 -380.187115) (xy 418.794128 -380.1514) (xy 418.758409 -380.110183) (xy 418.72892 -380.064301)
			(xy 418.706261 -380.014689) (xy 418.690894 -379.962357) (xy 418.683132 -379.908371) (xy 413.502106 -379.908371)
			(xy 413.494344 -379.962354) (xy 413.47898 -380.014684) (xy 413.456325 -380.064296) (xy 413.42684 -380.110178)
			(xy 413.391127 -380.151398) (xy 413.349911 -380.187116) (xy 413.304031 -380.216606) (xy 413.254422 -380.239266)
			(xy 413.202093 -380.254636) (xy 413.14811 -380.262403) (xy 413.12084 -380.262892) (xy 412.25724 -380.262892)
			(xy 412.229969 -380.262371) (xy 412.175982 -380.254614) (xy 412.123649 -380.239253) (xy 412.074035 -380.216599)
			(xy 412.02815 -380.187115) (xy 411.986928 -380.1514) (xy 411.951209 -380.110183) (xy 411.92172 -380.064301)
			(xy 411.899061 -380.014689) (xy 411.883694 -379.962357) (xy 411.875932 -379.908371) (xy 406.694906 -379.908371)
			(xy 406.687144 -379.962354) (xy 406.67178 -380.014684) (xy 406.649125 -380.064296) (xy 406.61964 -380.110178)
			(xy 406.583927 -380.151398) (xy 406.542711 -380.187116) (xy 406.496831 -380.216606) (xy 406.447222 -380.239266)
			(xy 406.394893 -380.254636) (xy 406.34091 -380.262403) (xy 406.31364 -380.262892) (xy 405.45004 -380.262892)
			(xy 405.422769 -380.262371) (xy 405.368782 -380.254614) (xy 405.316449 -380.239253) (xy 405.266835 -380.216599)
			(xy 405.22095 -380.187115) (xy 405.179728 -380.1514) (xy 405.144009 -380.110183) (xy 405.11452 -380.064301)
			(xy 405.091861 -380.014689) (xy 405.076494 -379.962357) (xy 405.068732 -379.908371) (xy 399.887706 -379.908371)
			(xy 399.879944 -379.962354) (xy 399.86458 -380.014684) (xy 399.841925 -380.064296) (xy 399.81244 -380.110178)
			(xy 399.776727 -380.151398) (xy 399.735511 -380.187116) (xy 399.689631 -380.216606) (xy 399.640022 -380.239266)
			(xy 399.587693 -380.254636) (xy 399.53371 -380.262403) (xy 399.50644 -380.262892) (xy 398.64284 -380.262892)
			(xy 398.615569 -380.262371) (xy 398.561582 -380.254614) (xy 398.509249 -380.239253) (xy 398.459635 -380.216599)
			(xy 398.41375 -380.187115) (xy 398.372528 -380.1514) (xy 398.336809 -380.110183) (xy 398.30732 -380.064301)
			(xy 398.284661 -380.014689) (xy 398.269294 -379.962357) (xy 398.261532 -379.908371) (xy 387.781628 -379.908371)
			(xy 387.781628 -379.908374) (xy 387.773865 -379.962365) (xy 387.758498 -380.014703) (xy 387.735838 -380.06432)
			(xy 387.706347 -380.110208) (xy 387.670626 -380.151432) (xy 387.629402 -380.187152) (xy 387.583513 -380.216641)
			(xy 387.533895 -380.2393) (xy 387.481557 -380.254667) (xy 387.427566 -380.262429) (xy 387.400292 -380.262892)
			(xy 386.536692 -380.262892) (xy 386.509425 -380.262345) (xy 386.455447 -380.254583) (xy 386.403122 -380.239218)
			(xy 386.353517 -380.216563) (xy 386.307641 -380.18708) (xy 386.266427 -380.151367) (xy 386.230716 -380.110153)
			(xy 386.201233 -380.064276) (xy 386.178579 -380.01467) (xy 386.163215 -379.962346) (xy 386.155454 -379.908367)
			(xy 380.974428 -379.908367) (xy 380.974428 -379.908374) (xy 380.966665 -379.962365) (xy 380.951298 -380.014703)
			(xy 380.928638 -380.06432) (xy 380.899147 -380.110208) (xy 380.863426 -380.151432) (xy 380.822202 -380.187152)
			(xy 380.776313 -380.216641) (xy 380.726695 -380.2393) (xy 380.674357 -380.254667) (xy 380.620366 -380.262429)
			(xy 380.593092 -380.262892) (xy 379.729492 -380.262892) (xy 379.702225 -380.262345) (xy 379.648247 -380.254583)
			(xy 379.595922 -380.239218) (xy 379.546317 -380.216563) (xy 379.500441 -380.18708) (xy 379.459227 -380.151367)
			(xy 379.423516 -380.110153) (xy 379.394033 -380.064276) (xy 379.371379 -380.01467) (xy 379.356015 -379.962346)
			(xy 379.348254 -379.908367) (xy 374.167228 -379.908367) (xy 374.167228 -379.908374) (xy 374.159465 -379.962365)
			(xy 374.144098 -380.014703) (xy 374.121438 -380.06432) (xy 374.091947 -380.110208) (xy 374.056226 -380.151432)
			(xy 374.015002 -380.187152) (xy 373.969113 -380.216641) (xy 373.919495 -380.2393) (xy 373.867157 -380.254667)
			(xy 373.813166 -380.262429) (xy 373.785892 -380.262892) (xy 372.922292 -380.262892) (xy 372.895025 -380.262345)
			(xy 372.841047 -380.254583) (xy 372.788722 -380.239218) (xy 372.739117 -380.216563) (xy 372.693241 -380.18708)
			(xy 372.652027 -380.151367) (xy 372.616316 -380.110153) (xy 372.586833 -380.064276) (xy 372.564179 -380.01467)
			(xy 372.548815 -379.962346) (xy 372.541054 -379.908367) (xy 367.360028 -379.908367) (xy 367.360028 -379.908374)
			(xy 367.352265 -379.962365) (xy 367.336898 -380.014703) (xy 367.314238 -380.06432) (xy 367.284747 -380.110208)
			(xy 367.249026 -380.151432) (xy 367.207802 -380.187152) (xy 367.161913 -380.216641) (xy 367.112295 -380.2393)
			(xy 367.059957 -380.254667) (xy 367.005966 -380.262429) (xy 366.978692 -380.262892) (xy 366.115092 -380.262892)
			(xy 366.087825 -380.262345) (xy 366.033847 -380.254583) (xy 365.981522 -380.239218) (xy 365.931917 -380.216563)
			(xy 365.886041 -380.18708) (xy 365.844827 -380.151367) (xy 365.809116 -380.110153) (xy 365.779633 -380.064276)
			(xy 365.756979 -380.01467) (xy 365.741615 -379.962346) (xy 365.733854 -379.908367) (xy 353.209106 -379.908367)
			(xy 353.209106 -379.90837) (xy 353.201344 -379.962353) (xy 353.18598 -380.014684) (xy 353.163325 -380.064295)
			(xy 353.133841 -380.110177) (xy 353.098128 -380.151397) (xy 353.056912 -380.187115) (xy 353.011033 -380.216604)
			(xy 352.961425 -380.239265) (xy 352.909097 -380.254635) (xy 352.855113 -380.262402) (xy 352.827844 -380.262892)
			(xy 351.964244 -380.262892) (xy 351.936973 -380.262372) (xy 351.882986 -380.254615) (xy 351.830652 -380.239254)
			(xy 351.781037 -380.216601) (xy 351.735151 -380.187116) (xy 351.693929 -380.151402) (xy 351.65821 -380.110184)
			(xy 351.628721 -380.064302) (xy 351.606061 -380.014689) (xy 351.590694 -379.962357) (xy 351.582932 -379.908371)
			(xy 346.401906 -379.908371) (xy 346.394144 -379.962353) (xy 346.37878 -380.014684) (xy 346.356125 -380.064295)
			(xy 346.326641 -380.110177) (xy 346.290928 -380.151397) (xy 346.249712 -380.187115) (xy 346.203833 -380.216604)
			(xy 346.154225 -380.239265) (xy 346.101897 -380.254635) (xy 346.047913 -380.262402) (xy 346.020644 -380.262892)
			(xy 345.157044 -380.262892) (xy 345.129773 -380.262372) (xy 345.075786 -380.254615) (xy 345.023452 -380.239254)
			(xy 344.973837 -380.216601) (xy 344.927951 -380.187116) (xy 344.886729 -380.151402) (xy 344.85101 -380.110184)
			(xy 344.821521 -380.064302) (xy 344.798861 -380.014689) (xy 344.783494 -379.962357) (xy 344.775732 -379.908371)
			(xy 339.594706 -379.908371) (xy 339.586944 -379.962353) (xy 339.57158 -380.014684) (xy 339.548925 -380.064295)
			(xy 339.519441 -380.110177) (xy 339.483728 -380.151397) (xy 339.442512 -380.187115) (xy 339.396633 -380.216604)
			(xy 339.347025 -380.239265) (xy 339.294697 -380.254635) (xy 339.240713 -380.262402) (xy 339.213444 -380.262892)
			(xy 338.349844 -380.262892) (xy 338.322573 -380.262372) (xy 338.268586 -380.254615) (xy 338.216252 -380.239254)
			(xy 338.166637 -380.216601) (xy 338.120751 -380.187116) (xy 338.079529 -380.151402) (xy 338.04381 -380.110184)
			(xy 338.014321 -380.064302) (xy 337.991661 -380.014689) (xy 337.976294 -379.962357) (xy 337.968532 -379.908371)
			(xy 332.787506 -379.908371) (xy 332.779744 -379.962353) (xy 332.76438 -380.014684) (xy 332.741725 -380.064295)
			(xy 332.712241 -380.110177) (xy 332.676528 -380.151397) (xy 332.635312 -380.187115) (xy 332.589433 -380.216604)
			(xy 332.539825 -380.239265) (xy 332.487497 -380.254635) (xy 332.433513 -380.262402) (xy 332.406244 -380.262892)
			(xy 331.542644 -380.262892) (xy 331.515373 -380.262372) (xy 331.461386 -380.254615) (xy 331.409052 -380.239254)
			(xy 331.359437 -380.216601) (xy 331.313551 -380.187116) (xy 331.272329 -380.151402) (xy 331.23661 -380.110184)
			(xy 331.207121 -380.064302) (xy 331.184461 -380.014689) (xy 331.169094 -379.962357) (xy 331.161332 -379.908371)
			(xy 320.681428 -379.908371) (xy 320.681428 -379.908373) (xy 320.673666 -379.962365) (xy 320.658298 -380.014702)
			(xy 320.635638 -380.064319) (xy 320.606148 -380.110207) (xy 320.570427 -380.15143) (xy 320.529203 -380.18715)
			(xy 320.483316 -380.21664) (xy 320.433698 -380.239299) (xy 320.381361 -380.254666) (xy 320.327369 -380.262429)
			(xy 320.300096 -380.262892) (xy 319.436496 -380.262892) (xy 319.409229 -380.262345) (xy 319.35525 -380.254584)
			(xy 319.302925 -380.239219) (xy 319.253319 -380.216565) (xy 319.207442 -380.187081) (xy 319.166229 -380.151369)
			(xy 319.130517 -380.110154) (xy 319.101033 -380.064277) (xy 319.078379 -380.014671) (xy 319.063015 -379.962346)
			(xy 319.055254 -379.908367) (xy 313.874228 -379.908367) (xy 313.874228 -379.908373) (xy 313.866466 -379.962365)
			(xy 313.851098 -380.014702) (xy 313.828438 -380.064319) (xy 313.798948 -380.110207) (xy 313.763227 -380.15143)
			(xy 313.722003 -380.18715) (xy 313.676116 -380.21664) (xy 313.626498 -380.239299) (xy 313.574161 -380.254666)
			(xy 313.520169 -380.262429) (xy 313.492896 -380.262892) (xy 312.629296 -380.262892) (xy 312.602029 -380.262345)
			(xy 312.54805 -380.254584) (xy 312.495725 -380.239219) (xy 312.446119 -380.216565) (xy 312.400242 -380.187081)
			(xy 312.359029 -380.151369) (xy 312.323317 -380.110154) (xy 312.293833 -380.064277) (xy 312.271179 -380.014671)
			(xy 312.255815 -379.962346) (xy 312.248054 -379.908367) (xy 307.067028 -379.908367) (xy 307.067028 -379.908373)
			(xy 307.059266 -379.962365) (xy 307.043898 -380.014702) (xy 307.021238 -380.064319) (xy 306.991748 -380.110207)
			(xy 306.956027 -380.15143) (xy 306.914803 -380.18715) (xy 306.868916 -380.21664) (xy 306.819298 -380.239299)
			(xy 306.766961 -380.254666) (xy 306.712969 -380.262429) (xy 306.685696 -380.262892) (xy 305.822096 -380.262892)
			(xy 305.794829 -380.262345) (xy 305.74085 -380.254584) (xy 305.688525 -380.239219) (xy 305.638919 -380.216565)
			(xy 305.593042 -380.187081) (xy 305.551829 -380.151369) (xy 305.516117 -380.110154) (xy 305.486633 -380.064277)
			(xy 305.463979 -380.014671) (xy 305.448615 -379.962346) (xy 305.440854 -379.908367) (xy 300.259828 -379.908367)
			(xy 300.259828 -379.908373) (xy 300.252066 -379.962365) (xy 300.236698 -380.014702) (xy 300.214038 -380.064319)
			(xy 300.184548 -380.110207) (xy 300.148827 -380.15143) (xy 300.107603 -380.18715) (xy 300.061716 -380.21664)
			(xy 300.012098 -380.239299) (xy 299.959761 -380.254666) (xy 299.905769 -380.262429) (xy 299.878496 -380.262892)
			(xy 299.014896 -380.262892) (xy 298.987629 -380.262345) (xy 298.93365 -380.254584) (xy 298.881325 -380.239219)
			(xy 298.831719 -380.216565) (xy 298.785842 -380.187081) (xy 298.744629 -380.151369) (xy 298.708917 -380.110154)
			(xy 298.679433 -380.064277) (xy 298.656779 -380.014671) (xy 298.641415 -379.962346) (xy 298.633654 -379.908367)
			(xy 179.577684 -379.908367) (xy 179.500651 -379.955161) (xy 179.344302 -380.040842) (xy 179.184291 -380.119474)
			(xy 179.020937 -380.1909) (xy 178.854562 -380.254978) (xy 178.685499 -380.31158) (xy 178.514082 -380.360596)
			(xy 178.340651 -380.401926) (xy 178.165551 -380.43549) (xy 177.989131 -380.46122) (xy 177.811739 -380.479066)
			(xy 177.633728 -380.488992) (xy 177.455451 -380.490978) (xy 177.277264 -380.485021) (xy 177.099518 -380.471131)
			(xy 176.922568 -380.449338) (xy 176.746764 -380.419684) (xy 176.572456 -380.382227) (xy 176.399989 -380.337043)
			(xy 176.229706 -380.284221) (xy 176.061945 -380.223865) (xy 175.89704 -380.156097) (xy 175.735317 -380.081049)
			(xy 175.577098 -379.998872) (xy 175.422697 -379.909729) (xy 175.27242 -379.813795) (xy 175.126565 -379.711263)
			(xy 174.985423 -379.602335) (xy 174.849274 -379.487228) (xy 174.718387 -379.36617) (xy 174.593023 -379.239401)
			(xy 174.47343 -379.107174) (xy 174.359847 -378.969751) (xy 174.252498 -378.827404) (xy 174.151597 -378.680416)
			(xy 174.057344 -378.52908) (xy 173.969926 -378.373695) (xy 173.889516 -378.21457) (xy 173.816275 -378.052021)
			(xy 173.750348 -377.886371) (xy 173.691865 -377.717949) (xy 173.640943 -377.547088) (xy 173.597683 -377.374129)
			(xy 173.562171 -377.199414) (xy 173.534477 -377.02329) (xy 173.514656 -376.846108) (xy 173.502748 -376.668219)
			(xy 173.498776 -376.489976) (xy 171.286932 -376.489976) (xy 171.286932 -376.956828) (xy 171.286446 -376.984079)
			(xy 171.27869 -377.038027) (xy 171.263335 -377.090322) (xy 171.240693 -377.139899) (xy 171.211227 -377.185749)
			(xy 171.175536 -377.22694) (xy 171.134345 -377.262631) (xy 171.088495 -377.292097) (xy 171.038918 -377.314739)
			(xy 170.986623 -377.330094) (xy 170.932675 -377.33785) (xy 170.878173 -377.33785) (xy 170.824225 -377.330094)
			(xy 170.77193 -377.314739) (xy 170.722353 -377.292097) (xy 170.676503 -377.262631) (xy 170.635312 -377.22694)
			(xy 170.599621 -377.185749) (xy 170.570155 -377.139899) (xy 170.547513 -377.090322) (xy 170.532158 -377.038027)
			(xy 170.524402 -376.984079) (xy 170.523916 -376.956828) (xy 141.418806 -376.956828) (xy 141.416303 -376.965354)
			(xy 141.393661 -377.014931) (xy 141.364195 -377.060781) (xy 141.328504 -377.101972) (xy 141.287313 -377.137663)
			(xy 141.241463 -377.167129) (xy 141.191886 -377.189771) (xy 141.139591 -377.205126) (xy 141.085643 -377.212882)
			(xy 141.031141 -377.212882) (xy 140.977193 -377.205126) (xy 140.924898 -377.189771) (xy 140.875321 -377.167129)
			(xy 140.829471 -377.137663) (xy 140.78828 -377.101972) (xy 140.752589 -377.060781) (xy 140.723123 -377.014931)
			(xy 140.700481 -376.965354) (xy 140.685126 -376.913059) (xy 140.67737 -376.859111) (xy 140.676884 -376.83186)
			(xy 138.759184 -376.83186) (xy 138.759184 -376.956828) (xy 138.758698 -376.984079) (xy 138.750942 -377.038027)
			(xy 138.735587 -377.090322) (xy 138.712945 -377.139899) (xy 138.683479 -377.185749) (xy 138.647788 -377.22694)
			(xy 138.606597 -377.262631) (xy 138.560747 -377.292097) (xy 138.51117 -377.314739) (xy 138.458875 -377.330094)
			(xy 138.404927 -377.33785) (xy 138.350425 -377.33785) (xy 138.296477 -377.330094) (xy 138.244182 -377.314739)
			(xy 138.194605 -377.292097) (xy 138.148755 -377.262631) (xy 138.107564 -377.22694) (xy 138.071873 -377.185749)
			(xy 138.042407 -377.139899) (xy 138.019765 -377.090322) (xy 138.00441 -377.038027) (xy 137.996654 -376.984079)
			(xy 137.996168 -376.956828) (xy 108.891058 -376.956828) (xy 108.888555 -376.965354) (xy 108.865913 -377.014931)
			(xy 108.836447 -377.060781) (xy 108.800756 -377.101972) (xy 108.759565 -377.137663) (xy 108.713715 -377.167129)
			(xy 108.664138 -377.189771) (xy 108.611843 -377.205126) (xy 108.557895 -377.212882) (xy 108.503393 -377.212882)
			(xy 108.449445 -377.205126) (xy 108.39715 -377.189771) (xy 108.347573 -377.167129) (xy 108.301723 -377.137663)
			(xy 108.260532 -377.101972) (xy 108.224841 -377.060781) (xy 108.195375 -377.014931) (xy 108.172733 -376.965354)
			(xy 108.157378 -376.913059) (xy 108.149622 -376.859111) (xy 108.149136 -376.83186) (xy 104.187244 -376.83186)
			(xy 104.187244 -376.956828) (xy 104.186758 -376.984097) (xy 104.178996 -377.038081) (xy 104.163631 -377.090411)
			(xy 104.140974 -377.140021) (xy 104.111488 -377.185902) (xy 104.075773 -377.227119) (xy 104.034556 -377.262834)
			(xy 103.988675 -377.29232) (xy 103.939065 -377.314977) (xy 103.886735 -377.330342) (xy 103.832751 -377.338104)
			(xy 103.778213 -377.338104) (xy 103.724229 -377.330342) (xy 103.671899 -377.314977) (xy 103.622289 -377.29232)
			(xy 103.576408 -377.262834) (xy 103.535191 -377.227119) (xy 103.499476 -377.185902) (xy 103.46999 -377.140021)
			(xy 103.447333 -377.090411) (xy 103.431968 -377.038081) (xy 103.424206 -376.984097) (xy 103.42372 -376.956828)
			(xy 74.319129 -376.956828) (xy 74.316599 -376.965443) (xy 74.293942 -377.015053) (xy 74.264456 -377.060934)
			(xy 74.228741 -377.102151) (xy 74.187524 -377.137866) (xy 74.141643 -377.167352) (xy 74.092033 -377.190009)
			(xy 74.039703 -377.205374) (xy 73.985719 -377.213136) (xy 73.931181 -377.213136) (xy 73.877197 -377.205374)
			(xy 73.824867 -377.190009) (xy 73.775257 -377.167352) (xy 73.729376 -377.137866) (xy 73.688159 -377.102151)
			(xy 73.652444 -377.060934) (xy 73.622958 -377.015053) (xy 73.600301 -376.965443) (xy 73.584936 -376.913113)
			(xy 73.577174 -376.859129) (xy 73.576688 -376.83186) (xy 71.659496 -376.83186) (xy 71.659496 -376.956828)
			(xy 71.65901 -376.984097) (xy 71.651248 -377.038081) (xy 71.635883 -377.090411) (xy 71.613226 -377.140021)
			(xy 71.58374 -377.185902) (xy 71.548025 -377.227119) (xy 71.506808 -377.262834) (xy 71.460927 -377.29232)
			(xy 71.411317 -377.314977) (xy 71.358987 -377.330342) (xy 71.305003 -377.338104) (xy 71.250465 -377.338104)
			(xy 71.196481 -377.330342) (xy 71.144151 -377.314977) (xy 71.094541 -377.29232) (xy 71.04866 -377.262834)
			(xy 71.007443 -377.227119) (xy 70.971728 -377.185902) (xy 70.942242 -377.140021) (xy 70.919585 -377.090411)
			(xy 70.90422 -377.038081) (xy 70.896458 -376.984097) (xy 70.895972 -376.956828) (xy 41.791381 -376.956828)
			(xy 41.788851 -376.965443) (xy 41.766194 -377.015053) (xy 41.736708 -377.060934) (xy 41.700993 -377.102151)
			(xy 41.659776 -377.137866) (xy 41.613895 -377.167352) (xy 41.564285 -377.190009) (xy 41.511955 -377.205374)
			(xy 41.457971 -377.213136) (xy 41.403433 -377.213136) (xy 41.349449 -377.205374) (xy 41.297119 -377.190009)
			(xy 41.247509 -377.167352) (xy 41.201628 -377.137866) (xy 41.160411 -377.102151) (xy 41.124696 -377.060934)
			(xy 41.09521 -377.015053) (xy 41.072553 -376.965443) (xy 41.057188 -376.913113) (xy 41.049426 -376.859129)
			(xy 41.04894 -376.83186) (xy 39.05568 -376.83186) (xy 39.046481 -376.93481) (xy 39.022717 -377.111506)
			(xy 38.991106 -377.286969) (xy 38.95171 -377.460849) (xy 38.904608 -377.632802) (xy 38.849892 -377.802486)
			(xy 38.787671 -377.969563) (xy 38.71807 -378.133704) (xy 38.641225 -378.29458) (xy 38.557291 -378.451874)
			(xy 38.466433 -378.605273) (xy 38.368831 -378.754472) (xy 38.26468 -378.899175) (xy 38.154187 -379.039095)
			(xy 38.03757 -379.173954) (xy 37.915061 -379.303484) (xy 37.786904 -379.427428) (xy 37.653353 -379.54554)
			(xy 37.514673 -379.657585) (xy 37.371139 -379.763342) (xy 37.223036 -379.862599) (xy 37.070659 -379.955161)
			(xy 36.91431 -380.040842) (xy 36.754299 -380.119474) (xy 36.590945 -380.1909) (xy 36.42457 -380.254978)
			(xy 36.255507 -380.31158) (xy 36.084678 -380.360428) (xy 70.895972 -380.360428) (xy 70.895972 -379.496828)
			(xy 70.896458 -379.469559) (xy 70.90422 -379.415575) (xy 70.919585 -379.363245) (xy 70.942242 -379.313635)
			(xy 70.971728 -379.267754) (xy 71.007443 -379.226537) (xy 71.04866 -379.190822) (xy 71.094541 -379.161336)
			(xy 71.144151 -379.138679) (xy 71.196481 -379.123314) (xy 71.250465 -379.115552) (xy 71.305003 -379.115552)
			(xy 71.358987 -379.123314) (xy 71.411317 -379.138679) (xy 71.460927 -379.161336) (xy 71.506808 -379.190822)
			(xy 71.548025 -379.226537) (xy 71.58374 -379.267754) (xy 71.613226 -379.313635) (xy 71.635883 -379.363245)
			(xy 71.651248 -379.415575) (xy 71.65901 -379.469559) (xy 71.659496 -379.496828) (xy 71.659496 -380.360428)
			(xy 103.42372 -380.360428) (xy 103.42372 -379.496828) (xy 103.424206 -379.469559) (xy 103.431968 -379.415575)
			(xy 103.447333 -379.363245) (xy 103.46999 -379.313635) (xy 103.499476 -379.267754) (xy 103.535191 -379.226537)
			(xy 103.576408 -379.190822) (xy 103.622289 -379.161336) (xy 103.671899 -379.138679) (xy 103.724229 -379.123314)
			(xy 103.778213 -379.115552) (xy 103.832751 -379.115552) (xy 103.886735 -379.123314) (xy 103.939065 -379.138679)
			(xy 103.988675 -379.161336) (xy 104.034556 -379.190822) (xy 104.075773 -379.226537) (xy 104.111488 -379.267754)
			(xy 104.140974 -379.313635) (xy 104.163631 -379.363245) (xy 104.178996 -379.415575) (xy 104.186758 -379.469559)
			(xy 104.187244 -379.496828) (xy 104.187244 -380.360428) (xy 137.996168 -380.360428) (xy 137.996168 -379.496828)
			(xy 137.996654 -379.469577) (xy 138.00441 -379.415629) (xy 138.019765 -379.363334) (xy 138.042407 -379.313757)
			(xy 138.071873 -379.267907) (xy 138.107564 -379.226716) (xy 138.148755 -379.191025) (xy 138.194605 -379.161559)
			(xy 138.244182 -379.138917) (xy 138.296477 -379.123562) (xy 138.350425 -379.115806) (xy 138.404927 -379.115806)
			(xy 138.458875 -379.123562) (xy 138.51117 -379.138917) (xy 138.560747 -379.161559) (xy 138.606597 -379.191025)
			(xy 138.647788 -379.226716) (xy 138.683479 -379.267907) (xy 138.712945 -379.313757) (xy 138.735587 -379.363334)
			(xy 138.750942 -379.415629) (xy 138.758698 -379.469577) (xy 138.759184 -379.496828) (xy 138.759184 -380.360428)
			(xy 170.523916 -380.360428) (xy 170.523916 -379.496828) (xy 170.524402 -379.469577) (xy 170.532158 -379.415629)
			(xy 170.547513 -379.363334) (xy 170.570155 -379.313757) (xy 170.599621 -379.267907) (xy 170.635312 -379.226716)
			(xy 170.676503 -379.191025) (xy 170.722353 -379.161559) (xy 170.77193 -379.138917) (xy 170.824225 -379.123562)
			(xy 170.878173 -379.115806) (xy 170.932675 -379.115806) (xy 170.986623 -379.123562) (xy 171.038918 -379.138917)
			(xy 171.088495 -379.161559) (xy 171.134345 -379.191025) (xy 171.175536 -379.226716) (xy 171.211227 -379.267907)
			(xy 171.240693 -379.313757) (xy 171.263335 -379.363334) (xy 171.27869 -379.415629) (xy 171.286446 -379.469577)
			(xy 171.286932 -379.496828) (xy 171.286932 -380.360428) (xy 171.286446 -380.387679) (xy 171.27869 -380.441627)
			(xy 171.263335 -380.493922) (xy 171.240693 -380.543499) (xy 171.211227 -380.589349) (xy 171.175536 -380.63054)
			(xy 171.134345 -380.666231) (xy 171.088495 -380.695697) (xy 171.038918 -380.718339) (xy 170.986623 -380.733694)
			(xy 170.932675 -380.74145) (xy 170.878173 -380.74145) (xy 170.824225 -380.733694) (xy 170.77193 -380.718339)
			(xy 170.722353 -380.695697) (xy 170.676503 -380.666231) (xy 170.635312 -380.63054) (xy 170.599621 -380.589349)
			(xy 170.570155 -380.543499) (xy 170.547513 -380.493922) (xy 170.532158 -380.441627) (xy 170.524402 -380.387679)
			(xy 170.523916 -380.360428) (xy 138.759184 -380.360428) (xy 138.758698 -380.387679) (xy 138.750942 -380.441627)
			(xy 138.735587 -380.493922) (xy 138.712945 -380.543499) (xy 138.683479 -380.589349) (xy 138.647788 -380.63054)
			(xy 138.606597 -380.666231) (xy 138.560747 -380.695697) (xy 138.51117 -380.718339) (xy 138.458875 -380.733694)
			(xy 138.404927 -380.74145) (xy 138.350425 -380.74145) (xy 138.296477 -380.733694) (xy 138.244182 -380.718339)
			(xy 138.194605 -380.695697) (xy 138.148755 -380.666231) (xy 138.107564 -380.63054) (xy 138.071873 -380.589349)
			(xy 138.042407 -380.543499) (xy 138.019765 -380.493922) (xy 138.00441 -380.441627) (xy 137.996654 -380.387679)
			(xy 137.996168 -380.360428) (xy 104.187244 -380.360428) (xy 104.186758 -380.387697) (xy 104.178996 -380.441681)
			(xy 104.163631 -380.494011) (xy 104.140974 -380.543621) (xy 104.111488 -380.589502) (xy 104.075773 -380.630719)
			(xy 104.034556 -380.666434) (xy 103.988675 -380.69592) (xy 103.939065 -380.718577) (xy 103.886735 -380.733942)
			(xy 103.832751 -380.741704) (xy 103.778213 -380.741704) (xy 103.724229 -380.733942) (xy 103.671899 -380.718577)
			(xy 103.622289 -380.69592) (xy 103.576408 -380.666434) (xy 103.535191 -380.630719) (xy 103.499476 -380.589502)
			(xy 103.46999 -380.543621) (xy 103.447333 -380.494011) (xy 103.431968 -380.441681) (xy 103.424206 -380.387697)
			(xy 103.42372 -380.360428) (xy 71.659496 -380.360428) (xy 71.65901 -380.387697) (xy 71.651248 -380.441681)
			(xy 71.635883 -380.494011) (xy 71.613226 -380.543621) (xy 71.58374 -380.589502) (xy 71.548025 -380.630719)
			(xy 71.506808 -380.666434) (xy 71.460927 -380.69592) (xy 71.411317 -380.718577) (xy 71.358987 -380.733942)
			(xy 71.305003 -380.741704) (xy 71.250465 -380.741704) (xy 71.196481 -380.733942) (xy 71.144151 -380.718577)
			(xy 71.094541 -380.69592) (xy 71.04866 -380.666434) (xy 71.007443 -380.630719) (xy 70.971728 -380.589502)
			(xy 70.942242 -380.543621) (xy 70.919585 -380.494011) (xy 70.90422 -380.441681) (xy 70.896458 -380.387697)
			(xy 70.895972 -380.360428) (xy 36.084678 -380.360428) (xy 36.08409 -380.360596) (xy 35.910659 -380.401926)
			(xy 35.735559 -380.43549) (xy 35.559139 -380.46122) (xy 35.381747 -380.479066) (xy 35.203736 -380.488992)
			(xy 35.025459 -380.490978) (xy 34.847272 -380.485021) (xy 34.669526 -380.471131) (xy 34.492576 -380.449338)
			(xy 34.316772 -380.419684) (xy 34.142464 -380.382227) (xy 33.969997 -380.337043) (xy 33.799714 -380.284221)
			(xy 33.631953 -380.223865) (xy 33.467048 -380.156097) (xy 33.305325 -380.081049) (xy 33.147106 -379.998872)
			(xy 32.992705 -379.909729) (xy 32.842428 -379.813795) (xy 32.696573 -379.711263) (xy 32.555431 -379.602335)
			(xy 32.419282 -379.487228) (xy 32.288395 -379.36617) (xy 32.163031 -379.239401) (xy 32.043438 -379.107174)
			(xy 31.929855 -378.969751) (xy 31.822506 -378.827404) (xy 31.721605 -378.680416) (xy 31.627352 -378.52908)
			(xy 31.539934 -378.373695) (xy 31.459524 -378.21457) (xy 31.386283 -378.052021) (xy 31.320356 -377.886371)
			(xy 31.261873 -377.717949) (xy 31.210951 -377.547088) (xy 31.167691 -377.374129) (xy 31.132179 -377.199414)
			(xy 31.104485 -377.02329) (xy 31.084664 -376.846108) (xy 31.072756 -376.668219) (xy 31.068784 -376.489976)
			(xy 2.509012 -376.489976) (xy 2.509012 -382.36906) (xy 41.04894 -382.36906) (xy 41.04894 -381.50546)
			(xy 41.049426 -381.478191) (xy 41.057188 -381.424207) (xy 41.072553 -381.371877) (xy 41.09521 -381.322267)
			(xy 41.124696 -381.276386) (xy 41.160411 -381.235169) (xy 41.201628 -381.199454) (xy 41.247509 -381.169968)
			(xy 41.297119 -381.147311) (xy 41.349449 -381.131946) (xy 41.403433 -381.124184) (xy 41.457971 -381.124184)
			(xy 41.511955 -381.131946) (xy 41.564285 -381.147311) (xy 41.613895 -381.169968) (xy 41.659776 -381.199454)
			(xy 41.700993 -381.235169) (xy 41.736708 -381.276386) (xy 41.766194 -381.322267) (xy 41.788851 -381.371877)
			(xy 41.804216 -381.424207) (xy 41.811978 -381.478191) (xy 41.812464 -381.50546) (xy 41.812464 -382.36906)
			(xy 73.576688 -382.36906) (xy 73.576688 -381.50546) (xy 73.577174 -381.478191) (xy 73.584936 -381.424207)
			(xy 73.600301 -381.371877) (xy 73.622958 -381.322267) (xy 73.652444 -381.276386) (xy 73.688159 -381.235169)
			(xy 73.729376 -381.199454) (xy 73.775257 -381.169968) (xy 73.824867 -381.147311) (xy 73.877197 -381.131946)
			(xy 73.931181 -381.124184) (xy 73.985719 -381.124184) (xy 74.039703 -381.131946) (xy 74.092033 -381.147311)
			(xy 74.141643 -381.169968) (xy 74.187524 -381.199454) (xy 74.228741 -381.235169) (xy 74.264456 -381.276386)
			(xy 74.293942 -381.322267) (xy 74.316599 -381.371877) (xy 74.331964 -381.424207) (xy 74.339726 -381.478191)
			(xy 74.340212 -381.50546) (xy 74.340212 -382.36906) (xy 108.149136 -382.36906) (xy 108.149136 -381.50546)
			(xy 108.149622 -381.478209) (xy 108.157378 -381.424261) (xy 108.172733 -381.371966) (xy 108.195375 -381.322389)
			(xy 108.224841 -381.276539) (xy 108.260532 -381.235348) (xy 108.301723 -381.199657) (xy 108.347573 -381.170191)
			(xy 108.39715 -381.147549) (xy 108.449445 -381.132194) (xy 108.503393 -381.124438) (xy 108.557895 -381.124438)
			(xy 108.611843 -381.132194) (xy 108.664138 -381.147549) (xy 108.713715 -381.170191) (xy 108.759565 -381.199657)
			(xy 108.800756 -381.235348) (xy 108.836447 -381.276539) (xy 108.865913 -381.322389) (xy 108.888555 -381.371966)
			(xy 108.90391 -381.424261) (xy 108.911666 -381.478209) (xy 108.912152 -381.50546) (xy 108.912152 -382.36906)
			(xy 140.676884 -382.36906) (xy 140.676884 -381.50546) (xy 140.67737 -381.478209) (xy 140.685126 -381.424261)
			(xy 140.700481 -381.371966) (xy 140.723123 -381.322389) (xy 140.752589 -381.276539) (xy 140.78828 -381.235348)
			(xy 140.829471 -381.199657) (xy 140.875321 -381.170191) (xy 140.924898 -381.147549) (xy 140.977193 -381.132194)
			(xy 141.031141 -381.124438) (xy 141.085643 -381.124438) (xy 141.139591 -381.132194) (xy 141.191886 -381.147549)
			(xy 141.241463 -381.170191) (xy 141.287313 -381.199657) (xy 141.328504 -381.235348) (xy 141.364195 -381.276539)
			(xy 141.393661 -381.322389) (xy 141.416303 -381.371966) (xy 141.431658 -381.424261) (xy 141.439414 -381.478209)
			(xy 141.4399 -381.50546) (xy 141.4399 -382.36906) (xy 141.439414 -382.396311) (xy 141.431658 -382.450259)
			(xy 141.416303 -382.502554) (xy 141.393661 -382.552131) (xy 141.364195 -382.597981) (xy 141.328504 -382.639172)
			(xy 141.287313 -382.674863) (xy 141.241463 -382.704329) (xy 141.191886 -382.726971) (xy 141.139591 -382.742326)
			(xy 141.085643 -382.750082) (xy 141.031141 -382.750082) (xy 140.977193 -382.742326) (xy 140.924898 -382.726971)
			(xy 140.875321 -382.704329) (xy 140.829471 -382.674863) (xy 140.78828 -382.639172) (xy 140.752589 -382.597981)
			(xy 140.723123 -382.552131) (xy 140.700481 -382.502554) (xy 140.685126 -382.450259) (xy 140.67737 -382.396311)
			(xy 140.676884 -382.36906) (xy 108.912152 -382.36906) (xy 108.911666 -382.396311) (xy 108.90391 -382.450259)
			(xy 108.888555 -382.502554) (xy 108.865913 -382.552131) (xy 108.836447 -382.597981) (xy 108.800756 -382.639172)
			(xy 108.759565 -382.674863) (xy 108.713715 -382.704329) (xy 108.664138 -382.726971) (xy 108.611843 -382.742326)
			(xy 108.557895 -382.750082) (xy 108.503393 -382.750082) (xy 108.449445 -382.742326) (xy 108.39715 -382.726971)
			(xy 108.347573 -382.704329) (xy 108.301723 -382.674863) (xy 108.260532 -382.639172) (xy 108.224841 -382.597981)
			(xy 108.195375 -382.552131) (xy 108.172733 -382.502554) (xy 108.157378 -382.450259) (xy 108.149622 -382.396311)
			(xy 108.149136 -382.36906) (xy 74.340212 -382.36906) (xy 74.339726 -382.396329) (xy 74.331964 -382.450313)
			(xy 74.316599 -382.502643) (xy 74.293942 -382.552253) (xy 74.264456 -382.598134) (xy 74.228741 -382.639351)
			(xy 74.187524 -382.675066) (xy 74.141643 -382.704552) (xy 74.092033 -382.727209) (xy 74.039703 -382.742574)
			(xy 73.985719 -382.750336) (xy 73.931181 -382.750336) (xy 73.877197 -382.742574) (xy 73.824867 -382.727209)
			(xy 73.775257 -382.704552) (xy 73.729376 -382.675066) (xy 73.688159 -382.639351) (xy 73.652444 -382.598134)
			(xy 73.622958 -382.552253) (xy 73.600301 -382.502643) (xy 73.584936 -382.450313) (xy 73.577174 -382.396329)
			(xy 73.576688 -382.36906) (xy 41.812464 -382.36906) (xy 41.811978 -382.396329) (xy 41.804216 -382.450313)
			(xy 41.788851 -382.502643) (xy 41.766194 -382.552253) (xy 41.736708 -382.598134) (xy 41.700993 -382.639351)
			(xy 41.659776 -382.675066) (xy 41.613895 -382.704552) (xy 41.564285 -382.727209) (xy 41.511955 -382.742574)
			(xy 41.457971 -382.750336) (xy 41.403433 -382.750336) (xy 41.349449 -382.742574) (xy 41.297119 -382.727209)
			(xy 41.247509 -382.704552) (xy 41.201628 -382.675066) (xy 41.160411 -382.639351) (xy 41.124696 -382.598134)
			(xy 41.09521 -382.552253) (xy 41.072553 -382.502643) (xy 41.057188 -382.450313) (xy 41.049426 -382.396329)
			(xy 41.04894 -382.36906) (xy 2.509012 -382.36906) (xy 2.509012 -385.310888) (xy 47.485808 -385.310888)
			(xy 47.485808 -385.31038) (xy 47.486243 -385.2864) (xy 47.493745 -385.239031) (xy 47.508561 -385.193417)
			(xy 47.530326 -385.15068) (xy 47.558505 -385.111872) (xy 47.592406 -385.077947) (xy 47.631194 -385.04974)
			(xy 47.673915 -385.027944) (xy 47.719518 -385.013096) (xy 47.766882 -385.00556) (xy 47.790862 -385.005072)
			(xy 47.79137 -385.005072) (xy 47.815305 -385.005523) (xy 47.862591 -385.012984) (xy 47.908134 -385.027728)
			(xy 47.950821 -385.049394) (xy 47.989606 -385.077452) (xy 48.023541 -385.111216) (xy 48.051795 -385.149858)
			(xy 48.06315 -385.170934) (xy 48.063658 -385.17195) (xy 48.143964 -385.310888) (xy 48.685704 -385.310888)
			(xy 48.685704 -385.31038) (xy 48.686143 -385.2864) (xy 48.693645 -385.239031) (xy 48.70846 -385.193417)
			(xy 48.730225 -385.150681) (xy 48.758404 -385.111873) (xy 48.792304 -385.077949) (xy 48.831092 -385.049741)
			(xy 48.873812 -385.027945) (xy 48.919415 -385.013097) (xy 48.966779 -385.005561) (xy 48.990758 -385.005072)
			(xy 48.991266 -385.005072) (xy 49.015201 -385.005526) (xy 49.062486 -385.012986) (xy 49.10803 -385.02773)
			(xy 49.150716 -385.049395) (xy 49.189502 -385.077453) (xy 49.223437 -385.111216) (xy 49.251691 -385.149859)
			(xy 49.263046 -385.170934) (xy 49.263554 -385.17195) (xy 49.34386 -385.310888) (xy 49.8856 -385.310888)
			(xy 49.8856 -385.31038) (xy 49.886043 -385.286401) (xy 49.893545 -385.239032) (xy 49.90836 -385.193418)
			(xy 49.930124 -385.150682) (xy 49.958303 -385.111875) (xy 49.992203 -385.07795) (xy 50.030989 -385.049743)
			(xy 50.073709 -385.027946) (xy 50.119312 -385.013097) (xy 50.166675 -385.005561) (xy 50.190654 -385.005072)
			(xy 50.191162 -385.005072) (xy 50.215097 -385.005529) (xy 50.262382 -385.012989) (xy 50.307925 -385.027732)
			(xy 50.350612 -385.049397) (xy 50.389397 -385.077454) (xy 50.423333 -385.111217) (xy 50.451587 -385.149859)
			(xy 50.462942 -385.170934) (xy 50.46345 -385.17195) (xy 50.543756 -385.310888) (xy 51.086004 -385.310888)
			(xy 51.086004 -385.31038) (xy 51.086444 -385.286388) (xy 51.093954 -385.238994) (xy 51.108785 -385.193359)
			(xy 51.130572 -385.150605) (xy 51.158779 -385.111786) (xy 51.192711 -385.077858) (xy 51.231533 -385.049655)
			(xy 51.274288 -385.027872) (xy 51.319925 -385.013046) (xy 51.36732 -385.005542) (xy 51.391312 -385.005072)
			(xy 51.415246 -385.00557) (xy 51.462529 -385.013022) (xy 51.508071 -385.027757) (xy 51.550758 -385.049416)
			(xy 51.589544 -385.077467) (xy 51.62348 -385.111224) (xy 51.651736 -385.149861) (xy 51.663092 -385.170934)
			(xy 51.6636 -385.17195) (xy 51.743906 -385.310888) (xy 52.2859 -385.310888) (xy 52.2859 -385.31038)
			(xy 52.286344 -385.286388) (xy 52.293854 -385.238995) (xy 52.308684 -385.19336) (xy 52.330471 -385.150606)
			(xy 52.358677 -385.111788) (xy 52.392609 -385.077859) (xy 52.43143 -385.049656) (xy 52.474186 -385.027873)
			(xy 52.519822 -385.013047) (xy 52.567216 -385.005542) (xy 52.591208 -385.005072) (xy 52.615141 -385.005573)
			(xy 52.662424 -385.013024) (xy 52.707967 -385.027759) (xy 52.750653 -385.049417) (xy 52.789439 -385.077468)
			(xy 52.823376 -385.111224) (xy 52.851632 -385.149861) (xy 52.862988 -385.170934) (xy 52.863496 -385.17195)
			(xy 52.943802 -385.310888) (xy 53.485796 -385.310888) (xy 53.485796 -385.31038) (xy 53.486243 -385.286401)
			(xy 53.493744 -385.239032) (xy 53.508559 -385.193419) (xy 53.530324 -385.150684) (xy 53.558502 -385.111876)
			(xy 53.592401 -385.077951) (xy 53.631187 -385.049744) (xy 53.673907 -385.027948) (xy 53.719508 -385.013098)
			(xy 53.766871 -385.005561) (xy 53.79085 -385.005072) (xy 53.791358 -385.005072) (xy 53.815293 -385.005532)
			(xy 53.862578 -385.012992) (xy 53.908121 -385.027734) (xy 53.950807 -385.049398) (xy 53.989593 -385.077455)
			(xy 54.023528 -385.111217) (xy 54.051783 -385.149859) (xy 54.063138 -385.170934) (xy 54.063646 -385.17195)
			(xy 54.143952 -385.310888) (xy 54.685692 -385.310888) (xy 54.685692 -385.31038) (xy 54.686143 -385.286401)
			(xy 54.693644 -385.239033) (xy 54.708459 -385.19342) (xy 54.730223 -385.150685) (xy 54.758401 -385.111877)
			(xy 54.792299 -385.077953) (xy 54.831085 -385.049745) (xy 54.873804 -385.027949) (xy 54.919405 -385.013099)
			(xy 54.966767 -385.005562) (xy 54.990746 -385.005072) (xy 54.991254 -385.005072) (xy 55.015189 -385.005536)
			(xy 55.062474 -385.012994) (xy 55.108017 -385.027736) (xy 55.150703 -385.0494) (xy 55.189489 -385.077456)
			(xy 55.223424 -385.111218) (xy 55.251679 -385.149859) (xy 55.263034 -385.170934) (xy 55.263542 -385.17195)
			(xy 55.343848 -385.310888) (xy 55.885588 -385.310888) (xy 55.885588 -385.31038) (xy 55.886043 -385.286401)
			(xy 55.893544 -385.239034) (xy 55.908359 -385.193421) (xy 55.930122 -385.150686) (xy 55.958299 -385.111879)
			(xy 55.992198 -385.077954) (xy 56.030983 -385.049747) (xy 56.073701 -385.02795) (xy 56.119302 -385.0131)
			(xy 56.166663 -385.005562) (xy 56.190642 -385.005072) (xy 56.19115 -385.005072) (xy 56.215085 -385.005539)
			(xy 56.262369 -385.012997) (xy 56.307912 -385.027738) (xy 56.350599 -385.049401) (xy 56.389384 -385.077457)
			(xy 56.42332 -385.111218) (xy 56.451575 -385.149859) (xy 56.46293 -385.170934) (xy 56.463438 -385.17195)
			(xy 56.543744 -385.310888) (xy 57.085992 -385.310888) (xy 57.085992 -385.31038) (xy 57.086444 -385.286388)
			(xy 57.093953 -385.238996) (xy 57.108783 -385.193362) (xy 57.130569 -385.150609) (xy 57.158775 -385.11179)
			(xy 57.192706 -385.077862) (xy 57.231526 -385.049659) (xy 57.27428 -385.027876) (xy 57.319915 -385.013049)
			(xy 57.367308 -385.005543) (xy 57.3913 -385.005072) (xy 57.391554 -385.005072) (xy 57.415489 -385.005536)
			(xy 57.462774 -385.012994) (xy 57.508317 -385.027736) (xy 57.551003 -385.0494) (xy 57.589789 -385.077456)
			(xy 57.623724 -385.111218) (xy 57.651979 -385.149859) (xy 57.663334 -385.170934) (xy 57.663842 -385.17195)
			(xy 57.744148 -385.310888) (xy 58.285888 -385.310888) (xy 58.285888 -385.31038) (xy 58.286344 -385.286388)
			(xy 58.293853 -385.238996) (xy 58.308683 -385.193362) (xy 58.330469 -385.15061) (xy 58.358674 -385.111792)
			(xy 58.392604 -385.077863) (xy 58.431424 -385.04966) (xy 58.474177 -385.027877) (xy 58.519812 -385.013049)
			(xy 58.567204 -385.005543) (xy 58.591196 -385.005072) (xy 58.59145 -385.005072) (xy 58.615385 -385.005539)
			(xy 58.662669 -385.012997) (xy 58.708212 -385.027738) (xy 58.750899 -385.049401) (xy 58.789684 -385.077457)
			(xy 58.82362 -385.111218) (xy 58.851875 -385.149859) (xy 58.86323 -385.170934) (xy 58.863738 -385.17195)
			(xy 58.944044 -385.310888) (xy 59.485784 -385.310888) (xy 59.485784 -385.31038) (xy 59.486221 -385.286374)
			(xy 59.493738 -385.238954) (xy 59.508584 -385.193295) (xy 59.530394 -385.150522) (xy 59.558628 -385.11169)
			(xy 59.592593 -385.077755) (xy 59.63145 -385.049554) (xy 59.674241 -385.027782) (xy 59.719913 -385.012976)
			(xy 59.76734 -385.0055) (xy 59.791346 -385.005072) (xy 59.7916 -385.005072) (xy 59.815533 -385.00558)
			(xy 59.862816 -385.01303) (xy 59.908358 -385.027764) (xy 59.951044 -385.04942) (xy 59.989831 -385.07747)
			(xy 60.023768 -385.111226) (xy 60.052024 -385.149862) (xy 60.06338 -385.170934) (xy 60.063888 -385.17195)
			(xy 60.144194 -385.310888) (xy 60.68568 -385.310888) (xy 60.68568 -385.31038) (xy 60.686121 -385.286374)
			(xy 60.693638 -385.238955) (xy 60.708484 -385.193296) (xy 60.730293 -385.150524) (xy 60.758527 -385.111692)
			(xy 60.792491 -385.077757) (xy 60.831347 -385.049556) (xy 60.874139 -385.027783) (xy 60.91981 -385.012977)
			(xy 60.967236 -385.0055) (xy 60.991242 -385.005072) (xy 60.991496 -385.005072) (xy 61.015432 -385.005502)
			(xy 61.062718 -385.012966) (xy 61.108262 -385.027714) (xy 61.150949 -385.049384) (xy 61.189734 -385.077445)
			(xy 61.223668 -385.111212) (xy 61.251922 -385.149857) (xy 61.263276 -385.170934) (xy 61.263784 -385.17195)
			(xy 61.34409 -385.310888) (xy 61.885576 -385.310888) (xy 61.885576 -385.31038) (xy 61.886021 -385.286374)
			(xy 61.893538 -385.238955) (xy 61.908383 -385.193297) (xy 61.930192 -385.150525) (xy 61.958426 -385.111693)
			(xy 61.992389 -385.077758) (xy 62.031245 -385.049557) (xy 62.074036 -385.027785) (xy 62.119707 -385.012977)
			(xy 62.167132 -385.0055) (xy 62.191138 -385.005072) (xy 62.191392 -385.005072) (xy 62.215328 -385.005505)
			(xy 62.262614 -385.012969) (xy 62.308158 -385.027716) (xy 62.350844 -385.049385) (xy 62.38963 -385.077446)
			(xy 62.423564 -385.111212) (xy 62.451818 -385.149857) (xy 62.463172 -385.170934) (xy 62.46368 -385.17195)
			(xy 62.543986 -385.310888) (xy 63.08598 -385.310888) (xy 63.08598 -385.31038) (xy 63.086444 -385.286389)
			(xy 63.093953 -385.238998) (xy 63.108782 -385.193364) (xy 63.130567 -385.150612) (xy 63.158771 -385.111795)
			(xy 63.192701 -385.077866) (xy 63.231519 -385.049663) (xy 63.274272 -385.027879) (xy 63.319905 -385.013051)
			(xy 63.367297 -385.005543) (xy 63.391288 -385.005072) (xy 63.391542 -385.005072) (xy 63.415476 -385.005545)
			(xy 63.462761 -385.013002) (xy 63.508303 -385.027742) (xy 63.55099 -385.049404) (xy 63.589776 -385.077459)
			(xy 63.623712 -385.11122) (xy 63.651967 -385.14986) (xy 63.663322 -385.170934) (xy 63.66383 -385.17195)
			(xy 63.744136 -385.310888) (xy 64.285876 -385.310888) (xy 64.285876 -385.31038) (xy 64.286344 -385.286389)
			(xy 64.293853 -385.238998) (xy 64.308682 -385.193365) (xy 64.330467 -385.150614) (xy 64.35867 -385.111796)
			(xy 64.392599 -385.077868) (xy 64.431417 -385.049664) (xy 64.474169 -385.02788) (xy 64.519802 -385.013052)
			(xy 64.567193 -385.005544) (xy 64.591184 -385.005072) (xy 64.591438 -385.005072) (xy 64.615372 -385.005549)
			(xy 64.662656 -385.013005) (xy 64.708199 -385.027744) (xy 64.750886 -385.049406) (xy 64.789672 -385.07746)
			(xy 64.823607 -385.11122) (xy 64.851863 -385.14986) (xy 64.863218 -385.170934) (xy 64.863726 -385.17195)
			(xy 64.944032 -385.310888) (xy 65.485772 -385.310888) (xy 65.485772 -385.31038) (xy 65.486221 -385.286375)
			(xy 65.493738 -385.238956) (xy 65.508583 -385.193298) (xy 65.530391 -385.150526) (xy 65.558625 -385.111694)
			(xy 65.592588 -385.07776) (xy 65.631443 -385.049558) (xy 65.674233 -385.027786) (xy 65.719903 -385.012978)
			(xy 65.767328 -385.005501) (xy 65.791334 -385.005072) (xy 65.791588 -385.005072) (xy 65.815524 -385.005508)
			(xy 65.86281 -385.012972) (xy 65.908353 -385.027718) (xy 65.95104 -385.049387) (xy 65.989825 -385.077447)
			(xy 66.02376 -385.111213) (xy 66.052014 -385.149858) (xy 66.063368 -385.170934) (xy 66.063876 -385.17195)
			(xy 66.144182 -385.310888) (xy 80.013556 -385.310888) (xy 80.013556 -385.31038) (xy 80.014043 -385.286403)
			(xy 80.021543 -385.239038) (xy 80.036355 -385.193429) (xy 80.058116 -385.150695) (xy 80.08629 -385.11189)
			(xy 80.120184 -385.077966) (xy 80.158965 -385.049758) (xy 80.201679 -385.027959) (xy 80.247275 -385.013106)
			(xy 80.294633 -385.005564) (xy 80.31861 -385.005072) (xy 80.319118 -385.005072) (xy 80.343052 -385.005565)
			(xy 80.390335 -385.013018) (xy 80.435877 -385.027754) (xy 80.478564 -385.049413) (xy 80.51735 -385.077465)
			(xy 80.551287 -385.111223) (xy 80.579542 -385.149861) (xy 80.590898 -385.170934) (xy 80.591406 -385.17195)
			(xy 80.671712 -385.310888) (xy 81.213452 -385.310888) (xy 81.213452 -385.31038) (xy 81.213943 -385.286403)
			(xy 81.221443 -385.239039) (xy 81.236255 -385.193429) (xy 81.258015 -385.150697) (xy 81.286189 -385.111891)
			(xy 81.320082 -385.077967) (xy 81.358863 -385.049759) (xy 81.401576 -385.02796) (xy 81.447172 -385.013107)
			(xy 81.494529 -385.005565) (xy 81.518506 -385.005072) (xy 81.519014 -385.005072) (xy 81.542948 -385.005568)
			(xy 81.590231 -385.013021) (xy 81.635773 -385.027756) (xy 81.67846 -385.049415) (xy 81.717246 -385.077466)
			(xy 81.751182 -385.111224) (xy 81.779438 -385.149861) (xy 81.790794 -385.170934) (xy 81.791302 -385.17195)
			(xy 81.871608 -385.310888) (xy 82.413348 -385.310888) (xy 82.413348 -385.31038) (xy 82.413843 -385.286403)
			(xy 82.421343 -385.239039) (xy 82.436155 -385.19343) (xy 82.457915 -385.150698) (xy 82.486088 -385.111892)
			(xy 82.519981 -385.077969) (xy 82.55876 -385.04976) (xy 82.601473 -385.027961) (xy 82.647069 -385.013108)
			(xy 82.694426 -385.005565) (xy 82.718402 -385.005072) (xy 82.71891 -385.005072) (xy 82.742843 -385.005571)
			(xy 82.790127 -385.013023) (xy 82.835669 -385.027758) (xy 82.878355 -385.049416) (xy 82.917142 -385.077467)
			(xy 82.951078 -385.111224) (xy 82.979334 -385.149861) (xy 82.99069 -385.170934) (xy 82.991198 -385.17195)
			(xy 83.071504 -385.310888) (xy 83.613752 -385.310888) (xy 83.613752 -385.31038) (xy 83.614244 -385.28639)
			(xy 83.621752 -385.239002) (xy 83.63658 -385.193371) (xy 83.658362 -385.150621) (xy 83.686563 -385.111804)
			(xy 83.720489 -385.077876) (xy 83.759304 -385.049673) (xy 83.802052 -385.027887) (xy 83.847682 -385.013057)
			(xy 83.89507 -385.005546) (xy 83.91906 -385.005072) (xy 83.942995 -385.005531) (xy 83.99028 -385.01299)
			(xy 84.035823 -385.027733) (xy 84.07851 -385.049398) (xy 84.117295 -385.077455) (xy 84.151231 -385.111217)
			(xy 84.179485 -385.149859) (xy 84.19084 -385.170934) (xy 84.191348 -385.17195) (xy 84.271654 -385.310888)
			(xy 84.813648 -385.310888) (xy 84.813648 -385.31038) (xy 84.814144 -385.28639) (xy 84.821652 -385.239002)
			(xy 84.836479 -385.193372) (xy 84.858261 -385.150622) (xy 84.886462 -385.111805) (xy 84.920387 -385.077878)
			(xy 84.959201 -385.049674) (xy 85.001949 -385.027888) (xy 85.047579 -385.013057) (xy 85.094966 -385.005546)
			(xy 85.118956 -385.005072) (xy 85.142891 -385.005534) (xy 85.190176 -385.012993) (xy 85.235719 -385.027735)
			(xy 85.278405 -385.049399) (xy 85.317191 -385.077456) (xy 85.351126 -385.111218) (xy 85.379381 -385.149859)
			(xy 85.390736 -385.170934) (xy 85.391244 -385.17195) (xy 85.47155 -385.310888) (xy 86.013544 -385.310888)
			(xy 86.013544 -385.31038) (xy 86.014043 -385.286403) (xy 86.021543 -385.23904) (xy 86.036354 -385.193431)
			(xy 86.058114 -385.150699) (xy 86.086287 -385.111894) (xy 86.120179 -385.07797) (xy 86.158958 -385.049762)
			(xy 86.20167 -385.027962) (xy 86.247265 -385.013109) (xy 86.294622 -385.005565) (xy 86.318598 -385.005072)
			(xy 86.319106 -385.005072) (xy 86.343039 -385.005575) (xy 86.390322 -385.013026) (xy 86.435864 -385.02776)
			(xy 86.478551 -385.049418) (xy 86.517337 -385.077468) (xy 86.551274 -385.111225) (xy 86.57953 -385.149861)
			(xy 86.590886 -385.170934) (xy 86.591394 -385.17195) (xy 86.6717 -385.310888) (xy 87.21344 -385.310888)
			(xy 87.21344 -385.31038) (xy 87.213843 -385.286399) (xy 87.221346 -385.239026) (xy 87.236164 -385.193409)
			(xy 87.257932 -385.15067) (xy 87.286115 -385.111861) (xy 87.320019 -385.077936) (xy 87.358812 -385.049729)
			(xy 87.401537 -385.027935) (xy 87.447145 -385.013089) (xy 87.494513 -385.005558) (xy 87.518494 -385.005072)
			(xy 87.519002 -385.005072) (xy 87.542935 -385.005578) (xy 87.590218 -385.013028) (xy 87.63576 -385.027763)
			(xy 87.678447 -385.04942) (xy 87.717233 -385.077469) (xy 87.75117 -385.111225) (xy 87.779426 -385.149861)
			(xy 87.790782 -385.170934) (xy 87.79129 -385.17195) (xy 87.871596 -385.310888) (xy 88.413336 -385.310888)
			(xy 88.413336 -385.31038) (xy 88.413743 -385.286399) (xy 88.421246 -385.239027) (xy 88.436063 -385.19341)
			(xy 88.457831 -385.150672) (xy 88.486013 -385.111862) (xy 88.519918 -385.077937) (xy 88.558709 -385.04973)
			(xy 88.601434 -385.027936) (xy 88.647041 -385.01309) (xy 88.694409 -385.005558) (xy 88.71839 -385.005072)
			(xy 88.718898 -385.005072) (xy 88.742834 -385.0055) (xy 88.790121 -385.012965) (xy 88.835664 -385.027713)
			(xy 88.878351 -385.049383) (xy 88.917136 -385.077445) (xy 88.95107 -385.111212) (xy 88.979324 -385.149857)
			(xy 88.990678 -385.170934) (xy 88.991186 -385.17195) (xy 89.071492 -385.310888) (xy 89.61374 -385.310888)
			(xy 89.61374 -385.31038) (xy 89.61412 -385.286384) (xy 89.621631 -385.238983) (xy 89.636465 -385.193341)
			(xy 89.658257 -385.150582) (xy 89.68647 -385.111758) (xy 89.72041 -385.077826) (xy 89.75924 -385.049622)
			(xy 89.802004 -385.027839) (xy 89.847649 -385.013015) (xy 89.895052 -385.005515) (xy 89.919048 -385.005072)
			(xy 89.942983 -385.005541) (xy 89.990267 -385.012998) (xy 90.03581 -385.027739) (xy 90.078497 -385.049402)
			(xy 90.117282 -385.077458) (xy 90.151218 -385.111219) (xy 90.179473 -385.149859) (xy 90.190828 -385.170934)
			(xy 90.191336 -385.17195) (xy 90.271642 -385.310888) (xy 90.813636 -385.310888) (xy 90.813636 -385.31038)
			(xy 90.81402 -385.286384) (xy 90.821531 -385.238984) (xy 90.836365 -385.193342) (xy 90.858157 -385.150583)
			(xy 90.886369 -385.111759) (xy 90.920308 -385.077828) (xy 90.959138 -385.049623) (xy 91.001901 -385.02784)
			(xy 91.047546 -385.013016) (xy 91.094948 -385.005515) (xy 91.118944 -385.005072) (xy 91.142878 -385.005544)
			(xy 91.190163 -385.013001) (xy 91.235706 -385.027741) (xy 91.278392 -385.049404) (xy 91.317178 -385.077459)
			(xy 91.351114 -385.111219) (xy 91.379369 -385.14986) (xy 91.390724 -385.170934) (xy 91.391232 -385.17195)
			(xy 91.471538 -385.310888) (xy 92.013532 -385.310888) (xy 92.013532 -385.31038) (xy 92.013943 -385.286399)
			(xy 92.021446 -385.239027) (xy 92.036263 -385.193411) (xy 92.05803 -385.150673) (xy 92.086212 -385.111864)
			(xy 92.120116 -385.077939) (xy 92.158907 -385.049732) (xy 92.201632 -385.027937) (xy 92.247238 -385.013091)
			(xy 92.294605 -385.005559) (xy 92.318586 -385.005072) (xy 92.319094 -385.005072) (xy 92.34303 -385.005503)
			(xy 92.390316 -385.012968) (xy 92.43586 -385.027715) (xy 92.478547 -385.049385) (xy 92.517332 -385.077446)
			(xy 92.551266 -385.111212) (xy 92.57952 -385.149857) (xy 92.590874 -385.170934) (xy 92.591382 -385.17195)
			(xy 92.671688 -385.310888) (xy 93.213428 -385.310888) (xy 93.213428 -385.31038) (xy 93.213843 -385.286399)
			(xy 93.221346 -385.239028) (xy 93.236162 -385.193412) (xy 93.257929 -385.150674) (xy 93.286111 -385.111865)
			(xy 93.320014 -385.07794) (xy 93.358805 -385.049733) (xy 93.401529 -385.027938) (xy 93.447135 -385.013092)
			(xy 93.494501 -385.005559) (xy 93.518482 -385.005072) (xy 93.51899 -385.005072) (xy 93.542926 -385.005506)
			(xy 93.590212 -385.01297) (xy 93.635756 -385.027717) (xy 93.678442 -385.049386) (xy 93.717227 -385.077447)
			(xy 93.751162 -385.111213) (xy 93.779416 -385.149857) (xy 93.79077 -385.170934) (xy 93.791278 -385.17195)
			(xy 93.871584 -385.310888) (xy 94.413324 -385.310888) (xy 94.413324 -385.31038) (xy 94.413743 -385.286399)
			(xy 94.421245 -385.239028) (xy 94.436062 -385.193413) (xy 94.457829 -385.150675) (xy 94.48601 -385.111866)
			(xy 94.519913 -385.077941) (xy 94.558703 -385.049734) (xy 94.601426 -385.02794) (xy 94.647032 -385.013093)
			(xy 94.694398 -385.005559) (xy 94.718378 -385.005072) (xy 94.718886 -385.005072) (xy 94.742822 -385.00551)
			(xy 94.790108 -385.012973) (xy 94.835651 -385.027719) (xy 94.878338 -385.049388) (xy 94.917123 -385.077448)
			(xy 94.951058 -385.111213) (xy 94.979312 -385.149858) (xy 94.990666 -385.170934) (xy 94.991174 -385.17195)
			(xy 95.07148 -385.310888) (xy 95.613728 -385.310888) (xy 95.613728 -385.31038) (xy 95.61412 -385.286385)
			(xy 95.621631 -385.238985) (xy 95.636464 -385.193344) (xy 95.658255 -385.150585) (xy 95.686467 -385.111762)
			(xy 95.720405 -385.07783) (xy 95.759233 -385.049626) (xy 95.801996 -385.027843) (xy 95.847639 -385.013018)
			(xy 95.89504 -385.005515) (xy 95.919036 -385.005072) (xy 95.94297 -385.00555) (xy 95.990254 -385.013006)
			(xy 96.035797 -385.027745) (xy 96.078484 -385.049407) (xy 96.117269 -385.077461) (xy 96.151205 -385.11122)
			(xy 96.179461 -385.14986) (xy 96.190816 -385.170934) (xy 96.191324 -385.17195) (xy 96.27163 -385.310888)
			(xy 96.813624 -385.310888) (xy 96.813624 -385.31038) (xy 96.81402 -385.286385) (xy 96.821531 -385.238985)
			(xy 96.836364 -385.193345) (xy 96.858154 -385.150586) (xy 96.886366 -385.111764) (xy 96.920303 -385.077832)
			(xy 96.959131 -385.049627) (xy 97.001893 -385.027844) (xy 97.047536 -385.013018) (xy 97.094937 -385.005516)
			(xy 97.118932 -385.005072) (xy 97.142866 -385.005554) (xy 97.19015 -385.013009) (xy 97.235693 -385.027747)
			(xy 97.278379 -385.049408) (xy 97.317165 -385.077462) (xy 97.351101 -385.111221) (xy 97.379357 -385.14986)
			(xy 97.390712 -385.170934) (xy 97.39122 -385.17195) (xy 97.471526 -385.310888) (xy 98.01352 -385.310888)
			(xy 98.01352 -385.31038) (xy 98.013943 -385.2864) (xy 98.021445 -385.239029) (xy 98.036262 -385.193414)
			(xy 98.058028 -385.150676) (xy 98.086209 -385.111868) (xy 98.120111 -385.077943) (xy 98.1589 -385.049736)
			(xy 98.201623 -385.027941) (xy 98.247228 -385.013093) (xy 98.294594 -385.005559) (xy 98.318574 -385.005072)
			(xy 98.319082 -385.005072) (xy 98.343018 -385.005513) (xy 98.390303 -385.012976) (xy 98.435847 -385.027721)
			(xy 98.478534 -385.049389) (xy 98.517319 -385.077449) (xy 98.551254 -385.111214) (xy 98.579508 -385.149858)
			(xy 98.590862 -385.170934) (xy 98.59137 -385.17195) (xy 98.671676 -385.310888) (xy 114.586004 -385.310888)
			(xy 114.586004 -385.31038) (xy 114.586444 -385.286388) (xy 114.593954 -385.238994) (xy 114.608785 -385.193359)
			(xy 114.630572 -385.150605) (xy 114.658779 -385.111786) (xy 114.692711 -385.077858) (xy 114.731533 -385.049655)
			(xy 114.774288 -385.027872) (xy 114.819925 -385.013046) (xy 114.86732 -385.005542) (xy 114.891312 -385.005072)
			(xy 114.915246 -385.00557) (xy 114.962529 -385.013022) (xy 115.008071 -385.027757) (xy 115.050758 -385.049416)
			(xy 115.089544 -385.077467) (xy 115.12348 -385.111224) (xy 115.151736 -385.149861) (xy 115.163092 -385.170934)
			(xy 115.1636 -385.17195) (xy 115.243906 -385.310888) (xy 115.7859 -385.310888) (xy 115.7859 -385.31038)
			(xy 115.786344 -385.286388) (xy 115.793854 -385.238995) (xy 115.808684 -385.19336) (xy 115.830471 -385.150606)
			(xy 115.858677 -385.111788) (xy 115.892609 -385.077859) (xy 115.93143 -385.049656) (xy 115.974186 -385.027873)
			(xy 116.019822 -385.013047) (xy 116.067216 -385.005542) (xy 116.091208 -385.005072) (xy 116.115141 -385.005573)
			(xy 116.162424 -385.013024) (xy 116.207967 -385.027759) (xy 116.250653 -385.049417) (xy 116.289439 -385.077468)
			(xy 116.323376 -385.111224) (xy 116.351632 -385.149861) (xy 116.362988 -385.170934) (xy 116.363496 -385.17195)
			(xy 116.443802 -385.310888) (xy 116.985796 -385.310888) (xy 116.985796 -385.31038) (xy 116.986244 -385.286388)
			(xy 116.993753 -385.238995) (xy 117.008584 -385.193361) (xy 117.03037 -385.150608) (xy 117.058576 -385.111789)
			(xy 117.092507 -385.077861) (xy 117.131328 -385.049658) (xy 117.174083 -385.027875) (xy 117.219719 -385.013048)
			(xy 117.267112 -385.005542) (xy 117.291104 -385.005072) (xy 117.315037 -385.005576) (xy 117.36232 -385.013027)
			(xy 117.407862 -385.027762) (xy 117.450549 -385.049419) (xy 117.489335 -385.077469) (xy 117.523272 -385.111225)
			(xy 117.551528 -385.149861) (xy 117.562884 -385.170934) (xy 117.563392 -385.17195) (xy 117.643698 -385.310888)
			(xy 118.185692 -385.310888) (xy 118.185692 -385.31038) (xy 118.186143 -385.286401) (xy 118.193644 -385.239033)
			(xy 118.208459 -385.19342) (xy 118.230223 -385.150685) (xy 118.258401 -385.111877) (xy 118.292299 -385.077953)
			(xy 118.331085 -385.049745) (xy 118.373804 -385.027949) (xy 118.419405 -385.013099) (xy 118.466767 -385.005562)
			(xy 118.490746 -385.005072) (xy 118.491254 -385.005072) (xy 118.515189 -385.005536) (xy 118.562474 -385.012994)
			(xy 118.608017 -385.027736) (xy 118.650703 -385.0494) (xy 118.689489 -385.077456) (xy 118.723424 -385.111218)
			(xy 118.751679 -385.149859) (xy 118.763034 -385.170934) (xy 118.763542 -385.17195) (xy 118.843848 -385.310888)
			(xy 119.385588 -385.310888) (xy 119.385588 -385.31038) (xy 119.386043 -385.286401) (xy 119.393544 -385.239034)
			(xy 119.408359 -385.193421) (xy 119.430122 -385.150686) (xy 119.458299 -385.111879) (xy 119.492198 -385.077954)
			(xy 119.530983 -385.049747) (xy 119.573701 -385.02795) (xy 119.619302 -385.0131) (xy 119.666663 -385.005562)
			(xy 119.690642 -385.005072) (xy 119.69115 -385.005072) (xy 119.715085 -385.005539) (xy 119.762369 -385.012997)
			(xy 119.807912 -385.027738) (xy 119.850599 -385.049401) (xy 119.889384 -385.077457) (xy 119.92332 -385.111218)
			(xy 119.951575 -385.149859) (xy 119.96293 -385.170934) (xy 119.963438 -385.17195) (xy 120.043744 -385.310888)
			(xy 120.585992 -385.310888) (xy 120.585992 -385.31038) (xy 120.586444 -385.286388) (xy 120.593953 -385.238996)
			(xy 120.608783 -385.193362) (xy 120.630569 -385.150609) (xy 120.658775 -385.11179) (xy 120.692706 -385.077862)
			(xy 120.731526 -385.049659) (xy 120.77428 -385.027876) (xy 120.819915 -385.013049) (xy 120.867308 -385.005543)
			(xy 120.8913 -385.005072) (xy 120.915233 -385.00558) (xy 120.962516 -385.01303) (xy 121.008058 -385.027764)
			(xy 121.050744 -385.04942) (xy 121.089531 -385.07747) (xy 121.123468 -385.111226) (xy 121.151724 -385.149862)
			(xy 121.16308 -385.170934) (xy 121.163588 -385.17195) (xy 121.243894 -385.310888) (xy 121.785888 -385.310888)
			(xy 121.785888 -385.31038) (xy 121.786344 -385.286388) (xy 121.793853 -385.238996) (xy 121.808683 -385.193362)
			(xy 121.830469 -385.15061) (xy 121.858674 -385.111792) (xy 121.892604 -385.077863) (xy 121.931424 -385.04966)
			(xy 121.974177 -385.027877) (xy 122.019812 -385.013049) (xy 122.067204 -385.005543) (xy 122.091196 -385.005072)
			(xy 122.115132 -385.005502) (xy 122.162418 -385.012966) (xy 122.207962 -385.027714) (xy 122.250649 -385.049384)
			(xy 122.289434 -385.077445) (xy 122.323368 -385.111212) (xy 122.351622 -385.149857) (xy 122.362976 -385.170934)
			(xy 122.363484 -385.17195) (xy 122.44379 -385.310888) (xy 122.985784 -385.310888) (xy 122.985784 -385.31038)
			(xy 122.986244 -385.286389) (xy 122.993753 -385.238997) (xy 123.008583 -385.193363) (xy 123.030368 -385.150611)
			(xy 123.058573 -385.111793) (xy 123.092502 -385.077865) (xy 123.131321 -385.049662) (xy 123.174074 -385.027878)
			(xy 123.219709 -385.01305) (xy 123.267101 -385.005543) (xy 123.291092 -385.005072) (xy 123.315028 -385.005505)
			(xy 123.362314 -385.012969) (xy 123.407858 -385.027716) (xy 123.450544 -385.049385) (xy 123.48933 -385.077446)
			(xy 123.523264 -385.111212) (xy 123.551518 -385.149857) (xy 123.562872 -385.170934) (xy 123.56338 -385.17195)
			(xy 123.643686 -385.310888) (xy 124.18568 -385.310888) (xy 124.18568 -385.31038) (xy 124.186143 -385.286402)
			(xy 124.193644 -385.239035) (xy 124.208458 -385.193423) (xy 124.230221 -385.150688) (xy 124.258397 -385.111882)
			(xy 124.292294 -385.077957) (xy 124.331078 -385.049749) (xy 124.373795 -385.027952) (xy 124.419395 -385.013101)
			(xy 124.466756 -385.005562) (xy 124.490734 -385.005072) (xy 124.491242 -385.005072) (xy 124.515176 -385.005545)
			(xy 124.562461 -385.013002) (xy 124.608003 -385.027742) (xy 124.65069 -385.049404) (xy 124.689476 -385.077459)
			(xy 124.723412 -385.11122) (xy 124.751667 -385.14986) (xy 124.763022 -385.170934) (xy 124.76353 -385.17195)
			(xy 124.843836 -385.310888) (xy 125.385576 -385.310888) (xy 125.385576 -385.31038) (xy 125.386043 -385.286402)
			(xy 125.393544 -385.239035) (xy 125.408357 -385.193424) (xy 125.43012 -385.150689) (xy 125.458296 -385.111883)
			(xy 125.492192 -385.077959) (xy 125.530976 -385.049751) (xy 125.573693 -385.027953) (xy 125.619292 -385.013102)
			(xy 125.666652 -385.005563) (xy 125.69063 -385.005072) (xy 125.691138 -385.005072) (xy 125.715072 -385.005549)
			(xy 125.762356 -385.013005) (xy 125.807899 -385.027744) (xy 125.850586 -385.049406) (xy 125.889372 -385.07746)
			(xy 125.923307 -385.11122) (xy 125.951563 -385.14986) (xy 125.962918 -385.170934) (xy 125.963426 -385.17195)
			(xy 126.043732 -385.310888) (xy 126.58598 -385.310888) (xy 126.58598 -385.31038) (xy 126.586444 -385.286389)
			(xy 126.593953 -385.238998) (xy 126.608782 -385.193364) (xy 126.630567 -385.150612) (xy 126.658771 -385.111795)
			(xy 126.692701 -385.077866) (xy 126.731519 -385.049663) (xy 126.774272 -385.027879) (xy 126.819905 -385.013051)
			(xy 126.867297 -385.005543) (xy 126.891288 -385.005072) (xy 126.915224 -385.005508) (xy 126.96251 -385.012972)
			(xy 127.008053 -385.027718) (xy 127.05074 -385.049387) (xy 127.089525 -385.077447) (xy 127.12346 -385.111213)
			(xy 127.151714 -385.149858) (xy 127.163068 -385.170934) (xy 127.163576 -385.17195) (xy 127.243882 -385.310888)
			(xy 127.785876 -385.310888) (xy 127.785876 -385.31038) (xy 127.786344 -385.286389) (xy 127.793853 -385.238998)
			(xy 127.808682 -385.193365) (xy 127.830467 -385.150614) (xy 127.85867 -385.111796) (xy 127.892599 -385.077868)
			(xy 127.931417 -385.049664) (xy 127.974169 -385.02788) (xy 128.019802 -385.013052) (xy 128.067193 -385.005544)
			(xy 128.091184 -385.005072) (xy 128.11512 -385.005511) (xy 128.162406 -385.012974) (xy 128.207949 -385.02772)
			(xy 128.250636 -385.049388) (xy 128.289421 -385.077448) (xy 128.323356 -385.111214) (xy 128.35161 -385.149858)
			(xy 128.362964 -385.170934) (xy 128.363472 -385.17195) (xy 128.443778 -385.310888) (xy 128.985772 -385.310888)
			(xy 128.985772 -385.31038) (xy 128.986244 -385.286389) (xy 128.993753 -385.238999) (xy 129.008581 -385.193366)
			(xy 129.030366 -385.150615) (xy 129.058569 -385.111797) (xy 129.092497 -385.077869) (xy 129.131315 -385.049666)
			(xy 129.174066 -385.027881) (xy 129.219699 -385.013053) (xy 129.267089 -385.005544) (xy 129.29108 -385.005072)
			(xy 129.315016 -385.005515) (xy 129.362301 -385.012977) (xy 129.407845 -385.027722) (xy 129.450531 -385.04939)
			(xy 129.489317 -385.077449) (xy 129.523252 -385.111214) (xy 129.551506 -385.149858) (xy 129.56286 -385.170934)
			(xy 129.563368 -385.17195) (xy 129.643674 -385.310888) (xy 130.185668 -385.310888) (xy 130.185668 -385.31038)
			(xy 130.186143 -385.286402) (xy 130.193643 -385.239036) (xy 130.208457 -385.193426) (xy 130.230218 -385.150692)
			(xy 130.258394 -385.111886) (xy 130.292289 -385.077961) (xy 130.331072 -385.049753) (xy 130.373787 -385.027956)
			(xy 130.419385 -385.013104) (xy 130.466745 -385.005563) (xy 130.490722 -385.005072) (xy 130.49123 -385.005072)
			(xy 130.515164 -385.005555) (xy 130.562448 -385.01301) (xy 130.60799 -385.027748) (xy 130.650677 -385.049409)
			(xy 130.689463 -385.077462) (xy 130.723399 -385.111221) (xy 130.751655 -385.14986) (xy 130.76301 -385.170934)
			(xy 130.763518 -385.17195) (xy 130.843824 -385.310888) (xy 131.385564 -385.310888) (xy 131.385564 -385.31038)
			(xy 131.386043 -385.286402) (xy 131.393543 -385.239037) (xy 131.408356 -385.193427) (xy 131.430118 -385.150693)
			(xy 131.458292 -385.111887) (xy 131.492187 -385.077963) (xy 131.530969 -385.049755) (xy 131.573684 -385.027957)
			(xy 131.619282 -385.013105) (xy 131.666641 -385.005564) (xy 131.690618 -385.005072) (xy 131.691126 -385.005072)
			(xy 131.71506 -385.005558) (xy 131.762344 -385.013013) (xy 131.807886 -385.02775) (xy 131.850573 -385.04941)
			(xy 131.889359 -385.077463) (xy 131.923295 -385.111222) (xy 131.951551 -385.14986) (xy 131.962906 -385.170934)
			(xy 131.963414 -385.17195) (xy 132.04372 -385.310888) (xy 132.585968 -385.310888) (xy 132.585968 -385.31038)
			(xy 132.586444 -385.286389) (xy 132.593952 -385.238999) (xy 132.608781 -385.193367) (xy 132.630565 -385.150616)
			(xy 132.658768 -385.111799) (xy 132.692696 -385.077871) (xy 132.731513 -385.049667) (xy 132.774263 -385.027883)
			(xy 132.819895 -385.013053) (xy 132.867285 -385.005544) (xy 132.891276 -385.005072) (xy 132.915211 -385.005518)
			(xy 132.962497 -385.01298) (xy 133.00804 -385.027724) (xy 133.050727 -385.049391) (xy 133.089512 -385.07745)
			(xy 133.123447 -385.111215) (xy 133.151701 -385.149858) (xy 133.163056 -385.170934) (xy 133.163564 -385.17195)
			(xy 133.24387 -385.310888) (xy 147.113752 -385.310888) (xy 147.113752 -385.31038) (xy 147.114244 -385.28639)
			(xy 147.121752 -385.239002) (xy 147.13658 -385.193371) (xy 147.158362 -385.150621) (xy 147.186563 -385.111804)
			(xy 147.220489 -385.077876) (xy 147.259304 -385.049673) (xy 147.302052 -385.027887) (xy 147.347682 -385.013057)
			(xy 147.39507 -385.005546) (xy 147.41906 -385.005072) (xy 147.442995 -385.005531) (xy 147.49028 -385.01299)
			(xy 147.535823 -385.027733) (xy 147.57851 -385.049398) (xy 147.617295 -385.077455) (xy 147.651231 -385.111217)
			(xy 147.679485 -385.149859) (xy 147.69084 -385.170934) (xy 147.691348 -385.17195) (xy 147.771654 -385.310888)
			(xy 148.313648 -385.310888) (xy 148.313648 -385.31038) (xy 148.314144 -385.28639) (xy 148.321652 -385.239002)
			(xy 148.336479 -385.193372) (xy 148.358261 -385.150622) (xy 148.386462 -385.111805) (xy 148.420387 -385.077878)
			(xy 148.459201 -385.049674) (xy 148.501949 -385.027888) (xy 148.547579 -385.013057) (xy 148.594966 -385.005546)
			(xy 148.618956 -385.005072) (xy 148.642891 -385.005534) (xy 148.690176 -385.012993) (xy 148.735719 -385.027735)
			(xy 148.778405 -385.049399) (xy 148.817191 -385.077456) (xy 148.851126 -385.111218) (xy 148.879381 -385.149859)
			(xy 148.890736 -385.170934) (xy 148.891244 -385.17195) (xy 148.97155 -385.310888) (xy 149.513544 -385.310888)
			(xy 149.513544 -385.31038) (xy 149.514044 -385.286391) (xy 149.521552 -385.239003) (xy 149.536379 -385.193373)
			(xy 149.558161 -385.150623) (xy 149.586361 -385.111807) (xy 149.620286 -385.077879) (xy 149.659099 -385.049675)
			(xy 149.701847 -385.02789) (xy 149.747476 -385.013058) (xy 149.794863 -385.005546) (xy 149.818852 -385.005072)
			(xy 149.842787 -385.005537) (xy 149.890071 -385.012995) (xy 149.935614 -385.027737) (xy 149.978301 -385.049401)
			(xy 150.017087 -385.077457) (xy 150.051022 -385.111218) (xy 150.079277 -385.149859) (xy 150.090632 -385.170934)
			(xy 150.09114 -385.17195) (xy 150.171446 -385.310888) (xy 150.71344 -385.310888) (xy 150.71344 -385.31038)
			(xy 150.713843 -385.286399) (xy 150.721346 -385.239026) (xy 150.736164 -385.193409) (xy 150.757932 -385.15067)
			(xy 150.786115 -385.111861) (xy 150.820019 -385.077936) (xy 150.858812 -385.049729) (xy 150.901537 -385.027935)
			(xy 150.947145 -385.013089) (xy 150.994513 -385.005558) (xy 151.018494 -385.005072) (xy 151.019002 -385.005072)
			(xy 151.042935 -385.005578) (xy 151.090218 -385.013028) (xy 151.13576 -385.027763) (xy 151.178447 -385.04942)
			(xy 151.217233 -385.077469) (xy 151.25117 -385.111225) (xy 151.279426 -385.149861) (xy 151.290782 -385.170934)
			(xy 151.29129 -385.17195) (xy 151.371596 -385.310888) (xy 151.913336 -385.310888) (xy 151.913336 -385.31038)
			(xy 151.913743 -385.286399) (xy 151.921246 -385.239027) (xy 151.936063 -385.19341) (xy 151.957831 -385.150672)
			(xy 151.986013 -385.111862) (xy 152.019918 -385.077937) (xy 152.058709 -385.04973) (xy 152.101434 -385.027936)
			(xy 152.147041 -385.01309) (xy 152.194409 -385.005558) (xy 152.21839 -385.005072) (xy 152.218898 -385.005072)
			(xy 152.242834 -385.0055) (xy 152.290121 -385.012965) (xy 152.335664 -385.027713) (xy 152.378351 -385.049383)
			(xy 152.417136 -385.077445) (xy 152.45107 -385.111212) (xy 152.479324 -385.149857) (xy 152.490678 -385.170934)
			(xy 152.491186 -385.17195) (xy 152.571492 -385.310888) (xy 153.11374 -385.310888) (xy 153.11374 -385.31038)
			(xy 153.11412 -385.286384) (xy 153.121631 -385.238983) (xy 153.136465 -385.193341) (xy 153.158257 -385.150582)
			(xy 153.18647 -385.111758) (xy 153.22041 -385.077826) (xy 153.25924 -385.049622) (xy 153.302004 -385.027839)
			(xy 153.347649 -385.013015) (xy 153.395052 -385.005515) (xy 153.419048 -385.005072) (xy 153.442983 -385.005541)
			(xy 153.490267 -385.012998) (xy 153.53581 -385.027739) (xy 153.578497 -385.049402) (xy 153.617282 -385.077458)
			(xy 153.651218 -385.111219) (xy 153.679473 -385.149859) (xy 153.690828 -385.170934) (xy 153.691336 -385.17195)
			(xy 153.771642 -385.310888) (xy 154.313636 -385.310888) (xy 154.313636 -385.31038) (xy 154.31402 -385.286384)
			(xy 154.321531 -385.238984) (xy 154.336365 -385.193342) (xy 154.358157 -385.150583) (xy 154.386369 -385.111759)
			(xy 154.420308 -385.077828) (xy 154.459138 -385.049623) (xy 154.501901 -385.02784) (xy 154.547546 -385.013016)
			(xy 154.594948 -385.005515) (xy 154.618944 -385.005072) (xy 154.642878 -385.005544) (xy 154.690163 -385.013001)
			(xy 154.735706 -385.027741) (xy 154.778392 -385.049404) (xy 154.817178 -385.077459) (xy 154.851114 -385.111219)
			(xy 154.879369 -385.14986) (xy 154.890724 -385.170934) (xy 154.891232 -385.17195) (xy 154.971538 -385.310888)
			(xy 155.513532 -385.310888) (xy 155.513532 -385.31038) (xy 155.51392 -385.286384) (xy 155.521431 -385.238984)
			(xy 155.536265 -385.193343) (xy 155.558056 -385.150584) (xy 155.586268 -385.111761) (xy 155.620206 -385.077829)
			(xy 155.659035 -385.049624) (xy 155.701798 -385.027842) (xy 155.747443 -385.013017) (xy 155.794844 -385.005515)
			(xy 155.81884 -385.005072) (xy 155.842774 -385.005547) (xy 155.890059 -385.013003) (xy 155.935601 -385.027743)
			(xy 155.978288 -385.049405) (xy 156.017074 -385.07746) (xy 156.05101 -385.11122) (xy 156.079265 -385.14986)
			(xy 156.09062 -385.170934) (xy 156.091128 -385.17195) (xy 156.171434 -385.310888) (xy 156.713428 -385.310888)
			(xy 156.713428 -385.31038) (xy 156.713843 -385.286399) (xy 156.721346 -385.239028) (xy 156.736162 -385.193412)
			(xy 156.757929 -385.150674) (xy 156.786111 -385.111865) (xy 156.820014 -385.07794) (xy 156.858805 -385.049733)
			(xy 156.901529 -385.027938) (xy 156.947135 -385.013092) (xy 156.994501 -385.005559) (xy 157.018482 -385.005072)
			(xy 157.01899 -385.005072) (xy 157.042926 -385.005506) (xy 157.090212 -385.01297) (xy 157.135756 -385.027717)
			(xy 157.178442 -385.049386) (xy 157.217227 -385.077447) (xy 157.251162 -385.111213) (xy 157.279416 -385.149857)
			(xy 157.29077 -385.170934) (xy 157.291278 -385.17195) (xy 157.371584 -385.310888) (xy 157.913324 -385.310888)
			(xy 157.913324 -385.31038) (xy 157.913743 -385.286399) (xy 157.921245 -385.239028) (xy 157.936062 -385.193413)
			(xy 157.957829 -385.150675) (xy 157.98601 -385.111866) (xy 158.019913 -385.077941) (xy 158.058703 -385.049734)
			(xy 158.101426 -385.02794) (xy 158.147032 -385.013093) (xy 158.194398 -385.005559) (xy 158.218378 -385.005072)
			(xy 158.218886 -385.005072) (xy 158.242822 -385.00551) (xy 158.290108 -385.012973) (xy 158.335651 -385.027719)
			(xy 158.378338 -385.049388) (xy 158.417123 -385.077448) (xy 158.451058 -385.111213) (xy 158.479312 -385.149858)
			(xy 158.490666 -385.170934) (xy 158.491174 -385.17195) (xy 158.57148 -385.310888) (xy 159.113728 -385.310888)
			(xy 159.113728 -385.31038) (xy 159.11412 -385.286385) (xy 159.121631 -385.238985) (xy 159.136464 -385.193344)
			(xy 159.158255 -385.150585) (xy 159.186467 -385.111762) (xy 159.220405 -385.07783) (xy 159.259233 -385.049626)
			(xy 159.301996 -385.027843) (xy 159.347639 -385.013018) (xy 159.39504 -385.005515) (xy 159.419036 -385.005072)
			(xy 159.44297 -385.00555) (xy 159.490254 -385.013006) (xy 159.535797 -385.027745) (xy 159.578484 -385.049407)
			(xy 159.617269 -385.077461) (xy 159.651205 -385.11122) (xy 159.679461 -385.14986) (xy 159.690816 -385.170934)
			(xy 159.691324 -385.17195) (xy 159.77163 -385.310888) (xy 160.313624 -385.310888) (xy 160.313624 -385.31038)
			(xy 160.31402 -385.286385) (xy 160.321531 -385.238985) (xy 160.336364 -385.193345) (xy 160.358154 -385.150586)
			(xy 160.386366 -385.111764) (xy 160.420303 -385.077832) (xy 160.459131 -385.049627) (xy 160.501893 -385.027844)
			(xy 160.547536 -385.013018) (xy 160.594937 -385.005516) (xy 160.618932 -385.005072) (xy 160.642866 -385.005554)
			(xy 160.69015 -385.013009) (xy 160.735693 -385.027747) (xy 160.778379 -385.049408) (xy 160.817165 -385.077462)
			(xy 160.851101 -385.111221) (xy 160.879357 -385.14986) (xy 160.890712 -385.170934) (xy 160.89122 -385.17195)
			(xy 160.971526 -385.310888) (xy 161.51352 -385.310888) (xy 161.51352 -385.31038) (xy 161.51392 -385.286385)
			(xy 161.52143 -385.238986) (xy 161.536263 -385.193346) (xy 161.558054 -385.150588) (xy 161.586265 -385.111765)
			(xy 161.620201 -385.077833) (xy 161.659029 -385.049629) (xy 161.70179 -385.027845) (xy 161.747433 -385.013019)
			(xy 161.794833 -385.005516) (xy 161.818828 -385.005072) (xy 161.842762 -385.005557) (xy 161.890046 -385.013011)
			(xy 161.935588 -385.027749) (xy 161.978275 -385.04941) (xy 162.017061 -385.077463) (xy 162.050997 -385.111222)
			(xy 162.079253 -385.14986) (xy 162.090608 -385.170934) (xy 162.091116 -385.17195) (xy 162.171422 -385.310888)
			(xy 162.713416 -385.310888) (xy 162.713416 -385.31038) (xy 162.713843 -385.2864) (xy 162.721345 -385.239029)
			(xy 162.736161 -385.193415) (xy 162.757927 -385.150678) (xy 162.786108 -385.111869) (xy 162.820009 -385.077944)
			(xy 162.858798 -385.049737) (xy 162.90152 -385.027942) (xy 162.947125 -385.013094) (xy 162.99449 -385.00556)
			(xy 163.01847 -385.005072) (xy 163.018978 -385.005072) (xy 163.042913 -385.005516) (xy 163.090199 -385.012978)
			(xy 163.135743 -385.027723) (xy 163.178429 -385.049391) (xy 163.217215 -385.07745) (xy 163.251149 -385.111214)
			(xy 163.279404 -385.149858) (xy 163.290758 -385.170934) (xy 163.291266 -385.17195) (xy 163.371572 -385.310888)
			(xy 163.913312 -385.310888) (xy 163.913312 -385.31038) (xy 163.913743 -385.2864) (xy 163.921245 -385.23903)
			(xy 163.936061 -385.193416) (xy 163.957827 -385.150679) (xy 163.986006 -385.111871) (xy 164.019908 -385.077946)
			(xy 164.058696 -385.049739) (xy 164.101418 -385.027943) (xy 164.147022 -385.013095) (xy 164.194386 -385.00556)
			(xy 164.218366 -385.005072) (xy 164.218874 -385.005072) (xy 164.242809 -385.005519) (xy 164.290095 -385.012981)
			(xy 164.335638 -385.027726) (xy 164.378325 -385.049392) (xy 164.41711 -385.077451) (xy 164.451045 -385.111215)
			(xy 164.479299 -385.149858) (xy 164.490654 -385.170934) (xy 164.491162 -385.17195) (xy 164.571468 -385.310888)
			(xy 165.113716 -385.310888) (xy 165.113716 -385.31038) (xy 165.11412 -385.286385) (xy 165.12163 -385.238987)
			(xy 165.136463 -385.193347) (xy 165.158253 -385.150589) (xy 165.186463 -385.111766) (xy 165.2204 -385.077835)
			(xy 165.259226 -385.04963) (xy 165.301987 -385.027846) (xy 165.347629 -385.01302) (xy 165.395029 -385.005516)
			(xy 165.419024 -385.005072) (xy 165.442958 -385.00556) (xy 165.490242 -385.013014) (xy 165.535784 -385.027751)
			(xy 165.578471 -385.049411) (xy 165.617257 -385.077464) (xy 165.651193 -385.111222) (xy 165.679449 -385.14986)
			(xy 165.690804 -385.170934) (xy 165.691312 -385.17195) (xy 166.083742 -385.850892) (xy 166.096567 -385.874224)
			(xy 166.114787 -385.924247) (xy 166.124047 -385.976673) (xy 166.124636 -386.003292) (xy 166.124131 -386.027269)
			(xy 166.116635 -386.074633) (xy 166.101826 -386.120243) (xy 166.080068 -386.162977) (xy 166.051896 -386.201783)
			(xy 166.018004 -386.235708) (xy 165.979224 -386.263916) (xy 165.936511 -386.285715) (xy 165.890916 -386.300567)
			(xy 165.843558 -386.308108) (xy 165.819582 -386.3086) (xy 165.819074 -386.3086) (xy 165.795499 -386.308227)
			(xy 165.74891 -386.300982) (xy 165.703991 -386.286652) (xy 165.661813 -386.26558) (xy 165.62338 -386.238267)
			(xy 165.589609 -386.205365) (xy 165.561304 -386.167657) (xy 165.549834 -386.147056) (xy 165.549326 -386.146294)
			(xy 165.151562 -385.457954) (xy 165.139704 -385.435268) (xy 165.122846 -385.38694) (xy 165.114266 -385.33648)
			(xy 165.113716 -385.310888) (xy 164.571468 -385.310888) (xy 164.883592 -385.850892) (xy 164.896324 -385.87421)
			(xy 164.914419 -385.924158) (xy 164.923635 -385.976477) (xy 164.924232 -386.003038) (xy 164.924232 -386.003292)
			(xy 164.92373 -386.027282) (xy 164.916226 -386.074671) (xy 164.901401 -386.120303) (xy 164.879621 -386.163054)
			(xy 164.851421 -386.201871) (xy 164.817496 -386.2358) (xy 164.778681 -386.264004) (xy 164.735932 -386.285789)
			(xy 164.690302 -386.300618) (xy 164.642914 -386.308128) (xy 164.618924 -386.3086) (xy 164.595351 -386.308187)
			(xy 164.548763 -386.300949) (xy 164.503845 -386.286627) (xy 164.461667 -386.265561) (xy 164.423233 -386.238255)
			(xy 164.389461 -386.205358) (xy 164.361155 -386.167655) (xy 164.349684 -386.147056) (xy 164.349176 -386.146294)
			(xy 163.951412 -385.457954) (xy 163.939479 -385.435295) (xy 163.922547 -385.386965) (xy 163.913895 -385.336491)
			(xy 163.913312 -385.310888) (xy 163.371572 -385.310888) (xy 163.683696 -385.850892) (xy 163.696428 -385.87421)
			(xy 163.714523 -385.924158) (xy 163.723739 -385.976477) (xy 163.724336 -386.003038) (xy 163.724336 -386.003292)
			(xy 163.72383 -386.027282) (xy 163.716326 -386.07467) (xy 163.701501 -386.120302) (xy 163.679721 -386.163053)
			(xy 163.651522 -386.20187) (xy 163.617597 -386.235798) (xy 163.578783 -386.264002) (xy 163.536035 -386.285788)
			(xy 163.490405 -386.300618) (xy 163.443018 -386.308127) (xy 163.419028 -386.3086) (xy 163.395455 -386.308184)
			(xy 163.348868 -386.300946) (xy 163.30395 -386.286625) (xy 163.261771 -386.26556) (xy 163.223338 -386.238254)
			(xy 163.189565 -386.205357) (xy 163.161259 -386.167654) (xy 163.149788 -386.147056) (xy 163.14928 -386.146294)
			(xy 162.751516 -385.457954) (xy 162.739583 -385.435294) (xy 162.722652 -385.386965) (xy 162.713999 -385.336491)
			(xy 162.713416 -385.310888) (xy 162.171422 -385.310888) (xy 162.483546 -385.850892) (xy 162.496371 -385.874224)
			(xy 162.514591 -385.924247) (xy 162.523851 -385.976673) (xy 162.52444 -386.003292) (xy 162.523931 -386.027269)
			(xy 162.516435 -386.074633) (xy 162.501626 -386.120242) (xy 162.479869 -386.162976) (xy 162.451698 -386.201782)
			(xy 162.417806 -386.235706) (xy 162.379027 -386.263915) (xy 162.336314 -386.285714) (xy 162.290719 -386.300566)
			(xy 162.243362 -386.308108) (xy 162.219386 -386.3086) (xy 162.218878 -386.3086) (xy 162.195303 -386.308224)
			(xy 162.148714 -386.300979) (xy 162.103795 -386.28665) (xy 162.061617 -386.265579) (xy 162.023184 -386.238266)
			(xy 161.989413 -386.205364) (xy 161.961108 -386.167657) (xy 161.949638 -386.147056) (xy 161.94913 -386.146294)
			(xy 161.551366 -385.457954) (xy 161.539508 -385.435268) (xy 161.52265 -385.38694) (xy 161.51407 -385.33648)
			(xy 161.51352 -385.310888) (xy 160.971526 -385.310888) (xy 161.28365 -385.850892) (xy 161.296476 -385.874224)
			(xy 161.314695 -385.924247) (xy 161.323955 -385.976673) (xy 161.324544 -386.003292) (xy 161.324031 -386.027269)
			(xy 161.316535 -386.074632) (xy 161.301727 -386.120241) (xy 161.279969 -386.162974) (xy 161.251799 -386.20178)
			(xy 161.217907 -386.235705) (xy 161.179129 -386.263913) (xy 161.136417 -386.285712) (xy 161.090822 -386.300566)
			(xy 161.043466 -386.308108) (xy 161.01949 -386.3086) (xy 161.018982 -386.3086) (xy 160.995407 -386.308221)
			(xy 160.948819 -386.300977) (xy 160.9039 -386.286648) (xy 160.861721 -386.265577) (xy 160.823288 -386.238265)
			(xy 160.789517 -386.205364) (xy 160.761212 -386.167657) (xy 160.749742 -386.147056) (xy 160.749234 -386.146294)
			(xy 160.35147 -385.457954) (xy 160.339612 -385.435268) (xy 160.322755 -385.386939) (xy 160.314174 -385.33648)
			(xy 160.313624 -385.310888) (xy 159.77163 -385.310888) (xy 160.083754 -385.850892) (xy 160.09658 -385.874224)
			(xy 160.114799 -385.924247) (xy 160.124059 -385.976673) (xy 160.124648 -386.003292) (xy 160.124131 -386.027268)
			(xy 160.116636 -386.074632) (xy 160.101827 -386.12024) (xy 160.08007 -386.162973) (xy 160.0519 -386.201779)
			(xy 160.018009 -386.235703) (xy 159.979231 -386.263912) (xy 159.93652 -386.285711) (xy 159.890926 -386.300565)
			(xy 159.84357 -386.308107) (xy 159.819594 -386.3086) (xy 159.819086 -386.3086) (xy 159.795512 -386.308217)
			(xy 159.748923 -386.300974) (xy 159.704004 -386.286646) (xy 159.661826 -386.265576) (xy 159.623393 -386.238264)
			(xy 159.589621 -386.205363) (xy 159.561316 -386.167656) (xy 159.549846 -386.147056) (xy 159.549338 -386.146294)
			(xy 159.151574 -385.457954) (xy 159.139717 -385.435268) (xy 159.122859 -385.386939) (xy 159.114278 -385.336479)
			(xy 159.113728 -385.310888) (xy 158.57148 -385.310888) (xy 158.883604 -385.850892) (xy 158.896337 -385.87421)
			(xy 158.914431 -385.924158) (xy 158.923647 -385.976477) (xy 158.924244 -386.003038) (xy 158.924244 -386.003292)
			(xy 158.92373 -386.027281) (xy 158.916226 -386.074669) (xy 158.901402 -386.1203) (xy 158.879623 -386.16305)
			(xy 158.851424 -386.201867) (xy 158.817501 -386.235796) (xy 158.778688 -386.264) (xy 158.735941 -386.285785)
			(xy 158.690312 -386.300616) (xy 158.642925 -386.308127) (xy 158.618936 -386.3086) (xy 158.595363 -386.308177)
			(xy 158.548776 -386.300941) (xy 158.503858 -386.286621) (xy 158.46168 -386.265557) (xy 158.423246 -386.238252)
			(xy 158.389474 -386.205356) (xy 158.361167 -386.167654) (xy 158.349696 -386.147056) (xy 158.349188 -386.146294)
			(xy 157.951424 -385.457954) (xy 157.939492 -385.435294) (xy 157.92256 -385.386965) (xy 157.913907 -385.336491)
			(xy 157.913324 -385.310888) (xy 157.371584 -385.310888) (xy 157.683708 -385.850892) (xy 157.696441 -385.87421)
			(xy 157.714535 -385.924158) (xy 157.723751 -385.976477) (xy 157.724348 -386.003038) (xy 157.724348 -386.003292)
			(xy 157.72383 -386.027281) (xy 157.716326 -386.074669) (xy 157.701503 -386.120299) (xy 157.679724 -386.163049)
			(xy 157.651525 -386.201866) (xy 157.617603 -386.235794) (xy 157.57879 -386.263998) (xy 157.536043 -386.285784)
			(xy 157.490415 -386.300615) (xy 157.443029 -386.308126) (xy 157.41904 -386.3086) (xy 157.395467 -386.308174)
			(xy 157.34888 -386.300939) (xy 157.303963 -386.286618) (xy 157.261784 -386.265555) (xy 157.223351 -386.238251)
			(xy 157.189578 -386.205355) (xy 157.161271 -386.167654) (xy 157.1498 -386.147056) (xy 157.149292 -386.146294)
			(xy 156.751528 -385.457954) (xy 156.739596 -385.435294) (xy 156.722664 -385.386965) (xy 156.714011 -385.336491)
			(xy 156.713428 -385.310888) (xy 156.171434 -385.310888) (xy 156.483558 -385.850892) (xy 156.496384 -385.874224)
			(xy 156.514604 -385.924247) (xy 156.523863 -385.976673) (xy 156.524452 -386.003292) (xy 156.523931 -386.027268)
			(xy 156.516436 -386.074631) (xy 156.501627 -386.120239) (xy 156.479871 -386.162972) (xy 156.451701 -386.201778)
			(xy 156.417811 -386.235702) (xy 156.379033 -386.263911) (xy 156.336323 -386.28571) (xy 156.290729 -386.300564)
			(xy 156.243374 -386.308107) (xy 156.219398 -386.3086) (xy 156.21889 -386.3086) (xy 156.195316 -386.308214)
			(xy 156.148727 -386.300971) (xy 156.103808 -386.286644) (xy 156.06163 -386.265574) (xy 156.023197 -386.238263)
			(xy 155.989426 -386.205363) (xy 155.96112 -386.167656) (xy 155.94965 -386.147056) (xy 155.949142 -386.146294)
			(xy 155.551378 -385.457954) (xy 155.539521 -385.435268) (xy 155.522663 -385.386939) (xy 155.514082 -385.336479)
			(xy 155.513532 -385.310888) (xy 154.971538 -385.310888) (xy 155.283662 -385.850892) (xy 155.296489 -385.874224)
			(xy 155.314708 -385.924247) (xy 155.323967 -385.976673) (xy 155.324556 -386.003292) (xy 155.324031 -386.027268)
			(xy 155.316536 -386.07463) (xy 155.301728 -386.120239) (xy 155.279972 -386.162971) (xy 155.251802 -386.201776)
			(xy 155.217912 -386.235701) (xy 155.179135 -386.263909) (xy 155.136425 -386.285709) (xy 155.090832 -386.300563)
			(xy 155.043477 -386.308107) (xy 155.019502 -386.3086) (xy 155.018994 -386.3086) (xy 154.99542 -386.308211)
			(xy 154.948831 -386.300969) (xy 154.903913 -386.286642) (xy 154.861734 -386.265573) (xy 154.823301 -386.238262)
			(xy 154.78953 -386.205362) (xy 154.761224 -386.167656) (xy 154.749754 -386.147056) (xy 154.749246 -386.146294)
			(xy 154.351482 -385.457954) (xy 154.339625 -385.435268) (xy 154.322767 -385.386939) (xy 154.314186 -385.336479)
			(xy 154.313636 -385.310888) (xy 153.771642 -385.310888) (xy 154.083766 -385.850892) (xy 154.096593 -385.874223)
			(xy 154.114812 -385.924247) (xy 154.124071 -385.976673) (xy 154.12466 -386.003292) (xy 154.124231 -386.027273)
			(xy 154.116732 -386.074644) (xy 154.101919 -386.120261) (xy 154.080154 -386.162999) (xy 154.051974 -386.201809)
			(xy 154.018072 -386.235735) (xy 153.979282 -386.263942) (xy 153.936559 -386.285737) (xy 153.890953 -386.300582)
			(xy 153.843586 -386.308114) (xy 153.819606 -386.3086) (xy 153.819098 -386.3086) (xy 153.795524 -386.308208)
			(xy 153.748936 -386.300966) (xy 153.704017 -386.28664) (xy 153.661839 -386.265571) (xy 153.623406 -386.238261)
			(xy 153.589634 -386.205361) (xy 153.561328 -386.167656) (xy 153.549858 -386.147056) (xy 153.54935 -386.146294)
			(xy 153.151586 -385.457954) (xy 153.13973 -385.435267) (xy 153.122871 -385.386939) (xy 153.11429 -385.336479)
			(xy 153.11374 -385.310888) (xy 152.571492 -385.310888) (xy 152.883616 -385.850892) (xy 152.89635 -385.874209)
			(xy 152.914443 -385.924158) (xy 152.923659 -385.976477) (xy 152.924256 -386.003038) (xy 152.924256 -386.003292)
			(xy 152.92373 -386.027281) (xy 152.916227 -386.074667) (xy 152.901403 -386.120297) (xy 152.879625 -386.163047)
			(xy 152.851428 -386.201863) (xy 152.817506 -386.235791) (xy 152.778694 -386.263996) (xy 152.735949 -386.285782)
			(xy 152.690322 -386.300614) (xy 152.642937 -386.308126) (xy 152.618948 -386.3086) (xy 152.595375 -386.308168)
			(xy 152.548789 -386.300933) (xy 152.503871 -386.286614) (xy 152.461693 -386.265552) (xy 152.423259 -386.238248)
			(xy 152.389486 -386.205354) (xy 152.361179 -386.167654) (xy 152.349708 -386.147056) (xy 152.3492 -386.146294)
			(xy 151.951436 -385.457954) (xy 151.939505 -385.435294) (xy 151.922572 -385.386964) (xy 151.913919 -385.336491)
			(xy 151.913336 -385.310888) (xy 151.371596 -385.310888) (xy 151.68372 -385.850892) (xy 151.696454 -385.874209)
			(xy 151.714548 -385.924158) (xy 151.723763 -385.976476) (xy 151.72436 -386.003038) (xy 151.72436 -386.003292)
			(xy 151.723954 -386.027287) (xy 151.716447 -386.074687) (xy 151.701617 -386.120329) (xy 151.679828 -386.163088)
			(xy 151.651618 -386.201912) (xy 151.617682 -386.235844) (xy 151.578854 -386.264049) (xy 151.536092 -386.285832)
			(xy 151.490448 -386.300657) (xy 151.443047 -386.308157) (xy 151.419052 -386.3086) (xy 151.395479 -386.308164)
			(xy 151.348893 -386.300931) (xy 151.303976 -386.286612) (xy 151.261797 -386.265551) (xy 151.223364 -386.238247)
			(xy 151.189591 -386.205354) (xy 151.161283 -386.167653) (xy 151.149812 -386.147056) (xy 151.149304 -386.146294)
			(xy 150.75154 -385.457954) (xy 150.739609 -385.435293) (xy 150.722676 -385.386964) (xy 150.714023 -385.336491)
			(xy 150.71344 -385.310888) (xy 150.171446 -385.310888) (xy 150.48357 -385.850892) (xy 150.496397 -385.874223)
			(xy 150.514616 -385.924247) (xy 150.523875 -385.976673) (xy 150.524464 -386.003292) (xy 150.524031 -386.027273)
			(xy 150.516533 -386.074644) (xy 150.501719 -386.12026) (xy 150.479955 -386.162998) (xy 150.451775 -386.201808)
			(xy 150.417874 -386.235733) (xy 150.379084 -386.263941) (xy 150.336361 -386.285735) (xy 150.290756 -386.300581)
			(xy 150.24339 -386.308114) (xy 150.21941 -386.3086) (xy 150.218902 -386.3086) (xy 150.195328 -386.308205)
			(xy 150.14874 -386.300963) (xy 150.103821 -386.286638) (xy 150.061643 -386.26557) (xy 150.02321 -386.23826)
			(xy 149.989438 -386.205361) (xy 149.961133 -386.167656) (xy 149.949662 -386.147056) (xy 149.949154 -386.146294)
			(xy 149.55139 -385.457954) (xy 149.539534 -385.435267) (xy 149.522675 -385.386939) (xy 149.514094 -385.336479)
			(xy 149.513544 -385.310888) (xy 148.97155 -385.310888) (xy 149.283674 -385.850892) (xy 149.296501 -385.874223)
			(xy 149.31472 -385.924247) (xy 149.323979 -385.976673) (xy 149.324568 -386.003292) (xy 149.324131 -386.027272)
			(xy 149.316633 -386.074643) (xy 149.301819 -386.120259) (xy 149.280055 -386.162997) (xy 149.251876 -386.201806)
			(xy 149.217975 -386.235732) (xy 149.179187 -386.263939) (xy 149.136464 -386.285734) (xy 149.090859 -386.300581)
			(xy 149.043494 -386.308113) (xy 149.019514 -386.3086) (xy 149.019006 -386.3086) (xy 148.995432 -386.308201)
			(xy 148.948844 -386.300961) (xy 148.903926 -386.286636) (xy 148.861747 -386.265568) (xy 148.823314 -386.238259)
			(xy 148.789542 -386.20536) (xy 148.761237 -386.167655) (xy 148.749766 -386.147056) (xy 148.749258 -386.146294)
			(xy 148.351494 -385.457954) (xy 148.339638 -385.435267) (xy 148.322779 -385.386939) (xy 148.314198 -385.336479)
			(xy 148.313648 -385.310888) (xy 147.771654 -385.310888) (xy 148.083778 -385.850892) (xy 148.096606 -385.874223)
			(xy 148.114824 -385.924247) (xy 148.124083 -385.976673) (xy 148.124672 -386.003292) (xy 148.124231 -386.027272)
			(xy 148.116733 -386.074643) (xy 148.10192 -386.120258) (xy 148.080156 -386.162996) (xy 148.051978 -386.201805)
			(xy 148.018077 -386.235731) (xy 147.979289 -386.263938) (xy 147.936567 -386.285733) (xy 147.890963 -386.30058)
			(xy 147.843598 -386.308113) (xy 147.819618 -386.3086) (xy 147.81911 -386.3086) (xy 147.795536 -386.308198)
			(xy 147.748948 -386.300958) (xy 147.70403 -386.286634) (xy 147.661852 -386.265566) (xy 147.623418 -386.238258)
			(xy 147.589647 -386.20536) (xy 147.561341 -386.167655) (xy 147.54987 -386.147056) (xy 147.549362 -386.146294)
			(xy 147.151598 -385.457954) (xy 147.139742 -385.435267) (xy 147.122883 -385.386939) (xy 147.114302 -385.336479)
			(xy 147.113752 -385.310888) (xy 133.24387 -385.310888) (xy 133.555994 -385.850892) (xy 133.568823 -385.874222)
			(xy 133.587041 -385.924246) (xy 133.596299 -385.976673) (xy 133.596888 -386.003292) (xy 133.596431 -386.027271)
			(xy 133.588933 -386.07464) (xy 133.574121 -386.120254) (xy 133.552359 -386.162991) (xy 133.524182 -386.2018)
			(xy 133.490284 -386.235725) (xy 133.451498 -386.263932) (xy 133.408778 -386.285728) (xy 133.363176 -386.300577)
			(xy 133.315813 -386.308112) (xy 133.291834 -386.3086) (xy 133.291326 -386.3086) (xy 133.267753 -386.308185)
			(xy 133.221165 -386.300948) (xy 133.176247 -386.286626) (xy 133.134069 -386.26556) (xy 133.095636 -386.238254)
			(xy 133.061863 -386.205357) (xy 133.033557 -386.167655) (xy 133.022086 -386.147056) (xy 133.021578 -386.146294)
			(xy 132.623814 -385.457954) (xy 132.611952 -385.43527) (xy 132.595097 -385.38694) (xy 132.586517 -385.33648)
			(xy 132.585968 -385.310888) (xy 132.04372 -385.310888) (xy 132.355844 -385.850892) (xy 132.36858 -385.874208)
			(xy 132.386672 -385.924157) (xy 132.395888 -385.976476) (xy 132.396484 -386.003038) (xy 132.396484 -386.003292)
			(xy 132.396054 -386.027286) (xy 132.388548 -386.074684) (xy 132.373719 -386.120323) (xy 132.351933 -386.163081)
			(xy 132.323725 -386.201904) (xy 132.289792 -386.235836) (xy 132.250967 -386.264041) (xy 132.208208 -386.285825)
			(xy 132.162568 -386.300652) (xy 132.11517 -386.308156) (xy 132.091176 -386.3086) (xy 132.067601 -386.308226)
			(xy 132.021012 -386.30098) (xy 131.976093 -386.286651) (xy 131.933915 -386.265579) (xy 131.895482 -386.238267)
			(xy 131.861711 -386.205365) (xy 131.833406 -386.167657) (xy 131.821936 -386.147056) (xy 131.821428 -386.146294)
			(xy 131.423664 -385.457954) (xy 131.411735 -385.435292) (xy 131.394801 -385.386964) (xy 131.386148 -385.336491)
			(xy 131.385564 -385.310888) (xy 130.843824 -385.310888) (xy 131.155948 -385.850892) (xy 131.168685 -385.874208)
			(xy 131.186776 -385.924157) (xy 131.195992 -385.976476) (xy 131.196588 -386.003038) (xy 131.196588 -386.003292)
			(xy 131.196154 -386.027286) (xy 131.188648 -386.074683) (xy 131.17382 -386.120322) (xy 131.152033 -386.16308)
			(xy 131.123826 -386.201902) (xy 131.089893 -386.235834) (xy 131.05107 -386.26404) (xy 131.008311 -386.285824)
			(xy 130.962671 -386.300651) (xy 130.915274 -386.308155) (xy 130.89128 -386.3086) (xy 130.867705 -386.308222)
			(xy 130.821116 -386.300978) (xy 130.776197 -386.286649) (xy 130.734019 -386.265578) (xy 130.695586 -386.238266)
			(xy 130.661815 -386.205364) (xy 130.63351 -386.167657) (xy 130.62204 -386.147056) (xy 130.621532 -386.146294)
			(xy 130.223768 -385.457954) (xy 130.211839 -385.435292) (xy 130.194906 -385.386964) (xy 130.186252 -385.336491)
			(xy 130.185668 -385.310888) (xy 129.643674 -385.310888) (xy 129.955798 -385.850892) (xy 129.968619 -385.874226)
			(xy 129.986842 -385.924248) (xy 129.996103 -385.976674) (xy 129.996692 -386.003292) (xy 129.996231 -386.027271)
			(xy 129.988734 -386.07464) (xy 129.973922 -386.120253) (xy 129.95216 -386.16299) (xy 129.923983 -386.201798)
			(xy 129.890086 -386.235723) (xy 129.8513 -386.263931) (xy 129.808581 -386.285727) (xy 129.762979 -386.300576)
			(xy 129.715617 -386.308112) (xy 129.691638 -386.3086) (xy 129.69113 -386.3086) (xy 129.667557 -386.308182)
			(xy 129.62097 -386.300945) (xy 129.576052 -386.286624) (xy 129.533873 -386.265559) (xy 129.49544 -386.238253)
			(xy 129.461668 -386.205357) (xy 129.433361 -386.167654) (xy 129.42189 -386.147056) (xy 129.421382 -386.146294)
			(xy 129.023618 -385.457954) (xy 129.011756 -385.43527) (xy 128.994901 -385.38694) (xy 128.986321 -385.33648)
			(xy 128.985772 -385.310888) (xy 128.443778 -385.310888) (xy 128.755902 -385.850892) (xy 128.768724 -385.874226)
			(xy 128.786946 -385.924248) (xy 128.796207 -385.976674) (xy 128.796796 -386.003292) (xy 128.796331 -386.027271)
			(xy 128.788834 -386.074639) (xy 128.774022 -386.120252) (xy 128.752261 -386.162989) (xy 128.724085 -386.201797)
			(xy 128.690187 -386.235722) (xy 128.651402 -386.26393) (xy 128.608684 -386.285726) (xy 128.563083 -386.300575)
			(xy 128.515721 -386.308111) (xy 128.491742 -386.3086) (xy 128.491234 -386.3086) (xy 128.467661 -386.308179)
			(xy 128.421074 -386.300942) (xy 128.376156 -386.286622) (xy 128.333978 -386.265557) (xy 128.295544 -386.238252)
			(xy 128.261772 -386.205356) (xy 128.233465 -386.167654) (xy 128.221994 -386.147056) (xy 128.221486 -386.146294)
			(xy 127.823722 -385.457954) (xy 127.811861 -385.43527) (xy 127.795005 -385.38694) (xy 127.786426 -385.33648)
			(xy 127.785876 -385.310888) (xy 127.243882 -385.310888) (xy 127.556006 -385.850892) (xy 127.568828 -385.874226)
			(xy 127.58705 -385.924248) (xy 127.596311 -385.976674) (xy 127.5969 -386.003292) (xy 127.596431 -386.027271)
			(xy 127.588934 -386.074639) (xy 127.574122 -386.120251) (xy 127.552361 -386.162988) (xy 127.524186 -386.201795)
			(xy 127.490289 -386.235721) (xy 127.451504 -386.263928) (xy 127.408786 -386.285725) (xy 127.363186 -386.300574)
			(xy 127.315824 -386.308111) (xy 127.291846 -386.3086) (xy 127.291338 -386.3086) (xy 127.267765 -386.308176)
			(xy 127.221178 -386.30094) (xy 127.17626 -386.28662) (xy 127.134082 -386.265556) (xy 127.095648 -386.238251)
			(xy 127.061876 -386.205356) (xy 127.033569 -386.167654) (xy 127.022098 -386.147056) (xy 127.02159 -386.146294)
			(xy 126.623826 -385.457954) (xy 126.611965 -385.43527) (xy 126.595109 -385.38694) (xy 126.58653 -385.33648)
			(xy 126.58598 -385.310888) (xy 126.043732 -385.310888) (xy 126.355856 -385.850892) (xy 126.368593 -385.874208)
			(xy 126.386685 -385.924157) (xy 126.3959 -385.976476) (xy 126.396496 -386.003038) (xy 126.396496 -386.003292)
			(xy 126.396054 -386.027286) (xy 126.388548 -386.074682) (xy 126.37372 -386.12032) (xy 126.351935 -386.163077)
			(xy 126.323729 -386.2019) (xy 126.289797 -386.235831) (xy 126.250974 -386.264037) (xy 126.208217 -386.285822)
			(xy 126.162578 -386.300649) (xy 126.115182 -386.308155) (xy 126.091188 -386.3086) (xy 126.067614 -386.308216)
			(xy 126.021025 -386.300973) (xy 125.976106 -386.286645) (xy 125.933928 -386.265575) (xy 125.895495 -386.238264)
			(xy 125.861723 -386.205363) (xy 125.833418 -386.167656) (xy 125.821948 -386.147056) (xy 125.82144 -386.146294)
			(xy 125.423676 -385.457954) (xy 125.41174 -385.435296) (xy 125.39481 -385.386965) (xy 125.386159 -385.336492)
			(xy 125.385576 -385.310888) (xy 124.843836 -385.310888) (xy 125.15596 -385.850892) (xy 125.168698 -385.874207)
			(xy 125.186789 -385.924157) (xy 125.196004 -385.976476) (xy 125.1966 -386.003038) (xy 125.1966 -386.003292)
			(xy 125.196154 -386.027285) (xy 125.188649 -386.074681) (xy 125.173821 -386.12032) (xy 125.152036 -386.163076)
			(xy 125.12383 -386.201898) (xy 125.089898 -386.23583) (xy 125.051076 -386.264036) (xy 125.00832 -386.285821)
			(xy 124.962681 -386.300649) (xy 124.915285 -386.308154) (xy 124.891292 -386.3086) (xy 124.867718 -386.308213)
			(xy 124.821129 -386.30097) (xy 124.77621 -386.286643) (xy 124.734032 -386.265573) (xy 124.695599 -386.238263)
			(xy 124.661828 -386.205362) (xy 124.633522 -386.167656) (xy 124.622052 -386.147056) (xy 124.621544 -386.146294)
			(xy 124.22378 -385.457954) (xy 124.211844 -385.435296) (xy 124.194915 -385.386965) (xy 124.186263 -385.336492)
			(xy 124.18568 -385.310888) (xy 123.643686 -385.310888) (xy 123.95581 -385.850892) (xy 123.968632 -385.874226)
			(xy 123.986854 -385.924248) (xy 123.996115 -385.976673) (xy 123.996704 -386.003292) (xy 123.996231 -386.027271)
			(xy 123.988734 -386.074638) (xy 123.973923 -386.120251) (xy 123.952162 -386.162986) (xy 123.923987 -386.201794)
			(xy 123.890091 -386.235719) (xy 123.851307 -386.263927) (xy 123.808589 -386.285724) (xy 123.762989 -386.300574)
			(xy 123.715628 -386.308111) (xy 123.69165 -386.3086) (xy 123.691142 -386.3086) (xy 123.667569 -386.308172)
			(xy 123.620983 -386.300937) (xy 123.576065 -386.286617) (xy 123.533886 -386.265554) (xy 123.495453 -386.23825)
			(xy 123.46168 -386.205355) (xy 123.433373 -386.167654) (xy 123.421902 -386.147056) (xy 123.421394 -386.146294)
			(xy 123.02363 -385.457954) (xy 123.011769 -385.43527) (xy 122.994913 -385.38694) (xy 122.986334 -385.33648)
			(xy 122.985784 -385.310888) (xy 122.44379 -385.310888) (xy 122.755914 -385.850892) (xy 122.768737 -385.874226)
			(xy 122.786958 -385.924248) (xy 122.796219 -385.976673) (xy 122.796808 -386.003292) (xy 122.796331 -386.02727)
			(xy 122.788834 -386.074637) (xy 122.774023 -386.12025) (xy 122.752263 -386.162985) (xy 122.724088 -386.201793)
			(xy 122.690192 -386.235718) (xy 122.651409 -386.263926) (xy 122.608692 -386.285723) (xy 122.563092 -386.300573)
			(xy 122.515732 -386.30811) (xy 122.491754 -386.3086) (xy 122.491246 -386.3086) (xy 122.467673 -386.308169)
			(xy 122.421087 -386.300935) (xy 122.376169 -386.286615) (xy 122.333991 -386.265553) (xy 122.295557 -386.238249)
			(xy 122.261784 -386.205355) (xy 122.233477 -386.167654) (xy 122.222006 -386.147056) (xy 122.221498 -386.146294)
			(xy 121.823734 -385.457954) (xy 121.811874 -385.43527) (xy 121.795018 -385.38694) (xy 121.786438 -385.33648)
			(xy 121.785888 -385.310888) (xy 121.243894 -385.310888) (xy 121.556018 -385.850892) (xy 121.568841 -385.874226)
			(xy 121.587062 -385.924248) (xy 121.596323 -385.976673) (xy 121.596912 -386.003292) (xy 121.596431 -386.02727)
			(xy 121.588934 -386.074637) (xy 121.574124 -386.120249) (xy 121.552364 -386.162984) (xy 121.524189 -386.201791)
			(xy 121.490294 -386.235716) (xy 121.451511 -386.263924) (xy 121.408795 -386.285722) (xy 121.363196 -386.300572)
			(xy 121.315836 -386.30811) (xy 121.291858 -386.3086) (xy 121.29135 -386.3086) (xy 121.267777 -386.308166)
			(xy 121.221191 -386.300932) (xy 121.176273 -386.286613) (xy 121.134095 -386.265551) (xy 121.095661 -386.238248)
			(xy 121.061888 -386.205354) (xy 121.033581 -386.167653) (xy 121.02211 -386.147056) (xy 121.021602 -386.146294)
			(xy 120.623838 -385.457954) (xy 120.611978 -385.435269) (xy 120.595122 -385.38694) (xy 120.586542 -385.33648)
			(xy 120.585992 -385.310888) (xy 120.043744 -385.310888) (xy 120.355868 -385.850892) (xy 120.368606 -385.874207)
			(xy 120.386697 -385.924157) (xy 120.395912 -385.976476) (xy 120.396508 -386.003038) (xy 120.396508 -386.003292)
			(xy 120.396054 -386.027285) (xy 120.388549 -386.07468) (xy 120.373721 -386.120318) (xy 120.351937 -386.163074)
			(xy 120.323732 -386.201896) (xy 120.289802 -386.235827) (xy 120.250981 -386.264033) (xy 120.208225 -386.285818)
			(xy 120.162588 -386.300647) (xy 120.115193 -386.308154) (xy 120.0912 -386.3086) (xy 120.067626 -386.308206)
			(xy 120.021038 -386.300965) (xy 119.976119 -386.286639) (xy 119.933941 -386.26557) (xy 119.895508 -386.238261)
			(xy 119.861736 -386.205361) (xy 119.83343 -386.167656) (xy 119.82196 -386.147056) (xy 119.821452 -386.146294)
			(xy 119.423688 -385.457954) (xy 119.411753 -385.435296) (xy 119.394823 -385.386965) (xy 119.386171 -385.336491)
			(xy 119.385588 -385.310888) (xy 118.843848 -385.310888) (xy 119.155972 -385.850892) (xy 119.168711 -385.874207)
			(xy 119.186801 -385.924157) (xy 119.196016 -385.976476) (xy 119.196612 -386.003038) (xy 119.196612 -386.003292)
			(xy 119.196154 -386.027285) (xy 119.188649 -386.07468) (xy 119.173822 -386.120317) (xy 119.152038 -386.163073)
			(xy 119.123834 -386.201894) (xy 119.089903 -386.235826) (xy 119.051083 -386.264032) (xy 119.008328 -386.285817)
			(xy 118.962691 -386.300646) (xy 118.915297 -386.308154) (xy 118.891304 -386.3086) (xy 118.86773 -386.308203)
			(xy 118.821142 -386.300962) (xy 118.776223 -386.286637) (xy 118.734045 -386.265569) (xy 118.695612 -386.23826)
			(xy 118.66184 -386.205361) (xy 118.633535 -386.167656) (xy 118.622064 -386.147056) (xy 118.621556 -386.146294)
			(xy 118.223792 -385.457954) (xy 118.211857 -385.435295) (xy 118.194927 -385.386965) (xy 118.186275 -385.336491)
			(xy 118.185692 -385.310888) (xy 117.643698 -385.310888) (xy 117.955822 -385.850892) (xy 117.968645 -385.874225)
			(xy 117.986866 -385.924248) (xy 117.996127 -385.976673) (xy 117.996716 -386.003292) (xy 117.996231 -386.02727)
			(xy 117.988734 -386.074636) (xy 117.973924 -386.120248) (xy 117.952164 -386.162983) (xy 117.92399 -386.20179)
			(xy 117.890096 -386.235715) (xy 117.851313 -386.263923) (xy 117.808598 -386.28572) (xy 117.762999 -386.300571)
			(xy 117.71564 -386.30811) (xy 117.691662 -386.3086) (xy 117.691154 -386.3086) (xy 117.667582 -386.308163)
			(xy 117.620995 -386.300929) (xy 117.576078 -386.286611) (xy 117.533899 -386.26555) (xy 117.495466 -386.238247)
			(xy 117.461693 -386.205353) (xy 117.433385 -386.167653) (xy 117.421914 -386.147056) (xy 117.421406 -386.146294)
			(xy 117.023642 -385.457954) (xy 117.011782 -385.435269) (xy 116.994926 -385.38694) (xy 116.986346 -385.33648)
			(xy 116.985796 -385.310888) (xy 116.443802 -385.310888) (xy 116.755926 -385.850892) (xy 116.76875 -385.874225)
			(xy 116.786971 -385.924247) (xy 116.796231 -385.976673) (xy 116.79682 -386.003292) (xy 116.796331 -386.02727)
			(xy 116.788835 -386.074636) (xy 116.774024 -386.120247) (xy 116.752265 -386.162982) (xy 116.724092 -386.201789)
			(xy 116.690197 -386.235713) (xy 116.651416 -386.263922) (xy 116.6087 -386.285719) (xy 116.563102 -386.30057)
			(xy 116.515743 -386.30811) (xy 116.491766 -386.3086) (xy 116.491258 -386.3086) (xy 116.467686 -386.308159)
			(xy 116.4211 -386.300927) (xy 116.376182 -386.286609) (xy 116.334004 -386.265548) (xy 116.29557 -386.238246)
			(xy 116.261797 -386.205353) (xy 116.23349 -386.167653) (xy 116.222018 -386.147056) (xy 116.22151 -386.146294)
			(xy 115.823746 -385.457954) (xy 115.811886 -385.435269) (xy 115.79503 -385.38694) (xy 115.78645 -385.33648)
			(xy 115.7859 -385.310888) (xy 115.243906 -385.310888) (xy 115.55603 -385.850892) (xy 115.568854 -385.874225)
			(xy 115.587075 -385.924247) (xy 115.596335 -385.976673) (xy 115.596924 -386.003292) (xy 115.596431 -386.02727)
			(xy 115.588935 -386.074635) (xy 115.574125 -386.120246) (xy 115.552366 -386.16298) (xy 115.524193 -386.201787)
			(xy 115.490299 -386.235712) (xy 115.451518 -386.26392) (xy 115.408803 -386.285718) (xy 115.363206 -386.30057)
			(xy 115.315847 -386.308109) (xy 115.29187 -386.3086) (xy 115.291362 -386.3086) (xy 115.26779 -386.308156)
			(xy 115.221204 -386.300924) (xy 115.176286 -386.286607) (xy 115.134108 -386.265547) (xy 115.095674 -386.238245)
			(xy 115.061901 -386.205352) (xy 115.033594 -386.167653) (xy 115.022122 -386.147056) (xy 115.021614 -386.146294)
			(xy 114.62385 -385.457954) (xy 114.611991 -385.435269) (xy 114.595134 -385.38694) (xy 114.586554 -385.33648)
			(xy 114.586004 -385.310888) (xy 98.671676 -385.310888) (xy 98.9838 -385.850892) (xy 98.996533 -385.87421)
			(xy 99.014627 -385.924158) (xy 99.023843 -385.976477) (xy 99.02444 -386.003038) (xy 99.02444 -386.003292)
			(xy 99.02393 -386.027281) (xy 99.016426 -386.07467) (xy 99.001602 -386.120301) (xy 98.979822 -386.163051)
			(xy 98.951623 -386.201869) (xy 98.917699 -386.235797) (xy 98.878886 -386.264001) (xy 98.836138 -386.285787)
			(xy 98.790509 -386.300617) (xy 98.743121 -386.308127) (xy 98.719132 -386.3086) (xy 98.695559 -386.30818)
			(xy 98.648972 -386.300944) (xy 98.604054 -386.286623) (xy 98.561875 -386.265558) (xy 98.523442 -386.238253)
			(xy 98.48967 -386.205357) (xy 98.461363 -386.167654) (xy 98.449892 -386.147056) (xy 98.449384 -386.146294)
			(xy 98.05162 -385.457954) (xy 98.039687 -385.435294) (xy 98.022756 -385.386965) (xy 98.014103 -385.336491)
			(xy 98.01352 -385.310888) (xy 97.471526 -385.310888) (xy 97.78365 -385.850892) (xy 97.796476 -385.874224)
			(xy 97.814695 -385.924247) (xy 97.823955 -385.976673) (xy 97.824544 -386.003292) (xy 97.824031 -386.027269)
			(xy 97.816535 -386.074632) (xy 97.801727 -386.120241) (xy 97.779969 -386.162974) (xy 97.751799 -386.20178)
			(xy 97.717907 -386.235705) (xy 97.679129 -386.263913) (xy 97.636417 -386.285712) (xy 97.590822 -386.300566)
			(xy 97.543466 -386.308108) (xy 97.51949 -386.3086) (xy 97.518982 -386.3086) (xy 97.495407 -386.308221)
			(xy 97.448819 -386.300977) (xy 97.4039 -386.286648) (xy 97.361721 -386.265577) (xy 97.323288 -386.238265)
			(xy 97.289517 -386.205364) (xy 97.261212 -386.167657) (xy 97.249742 -386.147056) (xy 97.249234 -386.146294)
			(xy 96.85147 -385.457954) (xy 96.839612 -385.435268) (xy 96.822755 -385.386939) (xy 96.814174 -385.33648)
			(xy 96.813624 -385.310888) (xy 96.27163 -385.310888) (xy 96.583754 -385.850892) (xy 96.59658 -385.874224)
			(xy 96.614799 -385.924247) (xy 96.624059 -385.976673) (xy 96.624648 -386.003292) (xy 96.624131 -386.027268)
			(xy 96.616636 -386.074632) (xy 96.601827 -386.12024) (xy 96.58007 -386.162973) (xy 96.5519 -386.201779)
			(xy 96.518009 -386.235703) (xy 96.479231 -386.263912) (xy 96.43652 -386.285711) (xy 96.390926 -386.300565)
			(xy 96.34357 -386.308107) (xy 96.319594 -386.3086) (xy 96.319086 -386.3086) (xy 96.295512 -386.308217)
			(xy 96.248923 -386.300974) (xy 96.204004 -386.286646) (xy 96.161826 -386.265576) (xy 96.123393 -386.238264)
			(xy 96.089621 -386.205363) (xy 96.061316 -386.167656) (xy 96.049846 -386.147056) (xy 96.049338 -386.146294)
			(xy 95.651574 -385.457954) (xy 95.639717 -385.435268) (xy 95.622859 -385.386939) (xy 95.614278 -385.336479)
			(xy 95.613728 -385.310888) (xy 95.07148 -385.310888) (xy 95.383604 -385.850892) (xy 95.396337 -385.87421)
			(xy 95.414431 -385.924158) (xy 95.423647 -385.976477) (xy 95.424244 -386.003038) (xy 95.424244 -386.003292)
			(xy 95.42373 -386.027281) (xy 95.416226 -386.074669) (xy 95.401402 -386.1203) (xy 95.379623 -386.16305)
			(xy 95.351424 -386.201867) (xy 95.317501 -386.235796) (xy 95.278688 -386.264) (xy 95.235941 -386.285785)
			(xy 95.190312 -386.300616) (xy 95.142925 -386.308127) (xy 95.118936 -386.3086) (xy 95.095363 -386.308177)
			(xy 95.048776 -386.300941) (xy 95.003858 -386.286621) (xy 94.96168 -386.265557) (xy 94.923246 -386.238252)
			(xy 94.889474 -386.205356) (xy 94.861167 -386.167654) (xy 94.849696 -386.147056) (xy 94.849188 -386.146294)
			(xy 94.451424 -385.457954) (xy 94.439492 -385.435294) (xy 94.42256 -385.386965) (xy 94.413907 -385.336491)
			(xy 94.413324 -385.310888) (xy 93.871584 -385.310888) (xy 94.183708 -385.850892) (xy 94.196441 -385.87421)
			(xy 94.214535 -385.924158) (xy 94.223751 -385.976477) (xy 94.224348 -386.003038) (xy 94.224348 -386.003292)
			(xy 94.22383 -386.027281) (xy 94.216326 -386.074669) (xy 94.201503 -386.120299) (xy 94.179724 -386.163049)
			(xy 94.151525 -386.201866) (xy 94.117603 -386.235794) (xy 94.07879 -386.263998) (xy 94.036043 -386.285784)
			(xy 93.990415 -386.300615) (xy 93.943029 -386.308126) (xy 93.91904 -386.3086) (xy 93.895467 -386.308174)
			(xy 93.84888 -386.300939) (xy 93.803963 -386.286618) (xy 93.761784 -386.265555) (xy 93.723351 -386.238251)
			(xy 93.689578 -386.205355) (xy 93.661271 -386.167654) (xy 93.6498 -386.147056) (xy 93.649292 -386.146294)
			(xy 93.251528 -385.457954) (xy 93.239596 -385.435294) (xy 93.222664 -385.386965) (xy 93.214011 -385.336491)
			(xy 93.213428 -385.310888) (xy 92.671688 -385.310888) (xy 92.983812 -385.850892) (xy 92.996546 -385.87421)
			(xy 93.014639 -385.924158) (xy 93.023855 -385.976477) (xy 93.024452 -386.003038) (xy 93.024452 -386.003292)
			(xy 93.02393 -386.027281) (xy 93.016427 -386.074668) (xy 93.001603 -386.120298) (xy 92.979824 -386.163048)
			(xy 92.951627 -386.201865) (xy 92.917704 -386.235793) (xy 92.878892 -386.263997) (xy 92.836146 -386.285783)
			(xy 92.790519 -386.300614) (xy 92.743133 -386.308126) (xy 92.719144 -386.3086) (xy 92.695571 -386.308171)
			(xy 92.648985 -386.300936) (xy 92.604067 -386.286616) (xy 92.561889 -386.265554) (xy 92.523455 -386.238249)
			(xy 92.489682 -386.205355) (xy 92.461375 -386.167654) (xy 92.449904 -386.147056) (xy 92.449396 -386.146294)
			(xy 92.051632 -385.457954) (xy 92.0397 -385.435294) (xy 92.022768 -385.386965) (xy 92.014115 -385.336491)
			(xy 92.013532 -385.310888) (xy 91.471538 -385.310888) (xy 91.783662 -385.850892) (xy 91.796489 -385.874224)
			(xy 91.814708 -385.924247) (xy 91.823967 -385.976673) (xy 91.824556 -386.003292) (xy 91.824031 -386.027268)
			(xy 91.816536 -386.07463) (xy 91.801728 -386.120239) (xy 91.779972 -386.162971) (xy 91.751802 -386.201776)
			(xy 91.717912 -386.235701) (xy 91.679135 -386.263909) (xy 91.636425 -386.285709) (xy 91.590832 -386.300563)
			(xy 91.543477 -386.308107) (xy 91.519502 -386.3086) (xy 91.518994 -386.3086) (xy 91.49542 -386.308211)
			(xy 91.448831 -386.300969) (xy 91.403913 -386.286642) (xy 91.361734 -386.265573) (xy 91.323301 -386.238262)
			(xy 91.28953 -386.205362) (xy 91.261224 -386.167656) (xy 91.249754 -386.147056) (xy 91.249246 -386.146294)
			(xy 90.851482 -385.457954) (xy 90.839625 -385.435268) (xy 90.822767 -385.386939) (xy 90.814186 -385.336479)
			(xy 90.813636 -385.310888) (xy 90.271642 -385.310888) (xy 90.583766 -385.850892) (xy 90.596593 -385.874223)
			(xy 90.614812 -385.924247) (xy 90.624071 -385.976673) (xy 90.62466 -386.003292) (xy 90.624231 -386.027273)
			(xy 90.616732 -386.074644) (xy 90.601919 -386.120261) (xy 90.580154 -386.162999) (xy 90.551974 -386.201809)
			(xy 90.518072 -386.235735) (xy 90.479282 -386.263942) (xy 90.436559 -386.285737) (xy 90.390953 -386.300582)
			(xy 90.343586 -386.308114) (xy 90.319606 -386.3086) (xy 90.319098 -386.3086) (xy 90.295524 -386.308208)
			(xy 90.248936 -386.300966) (xy 90.204017 -386.28664) (xy 90.161839 -386.265571) (xy 90.123406 -386.238261)
			(xy 90.089634 -386.205361) (xy 90.061328 -386.167656) (xy 90.049858 -386.147056) (xy 90.04935 -386.146294)
			(xy 89.651586 -385.457954) (xy 89.63973 -385.435267) (xy 89.622871 -385.386939) (xy 89.61429 -385.336479)
			(xy 89.61374 -385.310888) (xy 89.071492 -385.310888) (xy 89.383616 -385.850892) (xy 89.39635 -385.874209)
			(xy 89.414443 -385.924158) (xy 89.423659 -385.976477) (xy 89.424256 -386.003038) (xy 89.424256 -386.003292)
			(xy 89.42373 -386.027281) (xy 89.416227 -386.074667) (xy 89.401403 -386.120297) (xy 89.379625 -386.163047)
			(xy 89.351428 -386.201863) (xy 89.317506 -386.235791) (xy 89.278694 -386.263996) (xy 89.235949 -386.285782)
			(xy 89.190322 -386.300614) (xy 89.142937 -386.308126) (xy 89.118948 -386.3086) (xy 89.095375 -386.308168)
			(xy 89.048789 -386.300933) (xy 89.003871 -386.286614) (xy 88.961693 -386.265552) (xy 88.923259 -386.238248)
			(xy 88.889486 -386.205354) (xy 88.861179 -386.167654) (xy 88.849708 -386.147056) (xy 88.8492 -386.146294)
			(xy 88.451436 -385.457954) (xy 88.439505 -385.435294) (xy 88.422572 -385.386964) (xy 88.413919 -385.336491)
			(xy 88.413336 -385.310888) (xy 87.871596 -385.310888) (xy 88.18372 -385.850892) (xy 88.196454 -385.874209)
			(xy 88.214548 -385.924158) (xy 88.223763 -385.976476) (xy 88.22436 -386.003038) (xy 88.22436 -386.003292)
			(xy 88.223954 -386.027287) (xy 88.216447 -386.074687) (xy 88.201617 -386.120329) (xy 88.179828 -386.163088)
			(xy 88.151618 -386.201912) (xy 88.117682 -386.235844) (xy 88.078854 -386.264049) (xy 88.036092 -386.285832)
			(xy 87.990448 -386.300657) (xy 87.943047 -386.308157) (xy 87.919052 -386.3086) (xy 87.895479 -386.308164)
			(xy 87.848893 -386.300931) (xy 87.803976 -386.286612) (xy 87.761797 -386.265551) (xy 87.723364 -386.238247)
			(xy 87.689591 -386.205354) (xy 87.661283 -386.167653) (xy 87.649812 -386.147056) (xy 87.649304 -386.146294)
			(xy 87.25154 -385.457954) (xy 87.239609 -385.435293) (xy 87.222676 -385.386964) (xy 87.214023 -385.336491)
			(xy 87.21344 -385.310888) (xy 86.6717 -385.310888) (xy 86.983824 -385.850892) (xy 86.996559 -385.874209)
			(xy 87.014652 -385.924158) (xy 87.023867 -385.976476) (xy 87.024464 -386.003038) (xy 87.024464 -386.003292)
			(xy 87.024054 -386.027287) (xy 87.016547 -386.074687) (xy 87.001717 -386.120328) (xy 86.979929 -386.163087)
			(xy 86.951719 -386.201911) (xy 86.917783 -386.235843) (xy 86.878956 -386.264048) (xy 86.836195 -386.285831)
			(xy 86.790552 -386.300656) (xy 86.743151 -386.308157) (xy 86.719156 -386.3086) (xy 86.695584 -386.308161)
			(xy 86.648997 -386.300928) (xy 86.60408 -386.28661) (xy 86.561902 -386.265549) (xy 86.523468 -386.238246)
			(xy 86.489695 -386.205353) (xy 86.461387 -386.167653) (xy 86.449916 -386.147056) (xy 86.449408 -386.146294)
			(xy 86.051644 -385.457954) (xy 86.039713 -385.435293) (xy 86.02278 -385.386964) (xy 86.014127 -385.336491)
			(xy 86.013544 -385.310888) (xy 85.47155 -385.310888) (xy 85.783674 -385.850892) (xy 85.796501 -385.874223)
			(xy 85.81472 -385.924247) (xy 85.823979 -385.976673) (xy 85.824568 -386.003292) (xy 85.824131 -386.027272)
			(xy 85.816633 -386.074643) (xy 85.801819 -386.120259) (xy 85.780055 -386.162997) (xy 85.751876 -386.201806)
			(xy 85.717975 -386.235732) (xy 85.679187 -386.263939) (xy 85.636464 -386.285734) (xy 85.590859 -386.300581)
			(xy 85.543494 -386.308113) (xy 85.519514 -386.3086) (xy 85.519006 -386.3086) (xy 85.495432 -386.308201)
			(xy 85.448844 -386.300961) (xy 85.403926 -386.286636) (xy 85.361747 -386.265568) (xy 85.323314 -386.238259)
			(xy 85.289542 -386.20536) (xy 85.261237 -386.167655) (xy 85.249766 -386.147056) (xy 85.249258 -386.146294)
			(xy 84.851494 -385.457954) (xy 84.839638 -385.435267) (xy 84.822779 -385.386939) (xy 84.814198 -385.336479)
			(xy 84.813648 -385.310888) (xy 84.271654 -385.310888) (xy 84.583778 -385.850892) (xy 84.596606 -385.874223)
			(xy 84.614824 -385.924247) (xy 84.624083 -385.976673) (xy 84.624672 -386.003292) (xy 84.624231 -386.027272)
			(xy 84.616733 -386.074643) (xy 84.60192 -386.120258) (xy 84.580156 -386.162996) (xy 84.551978 -386.201805)
			(xy 84.518077 -386.235731) (xy 84.479289 -386.263938) (xy 84.436567 -386.285733) (xy 84.390963 -386.30058)
			(xy 84.343598 -386.308113) (xy 84.319618 -386.3086) (xy 84.31911 -386.3086) (xy 84.295536 -386.308198)
			(xy 84.248948 -386.300958) (xy 84.20403 -386.286634) (xy 84.161852 -386.265566) (xy 84.123418 -386.238258)
			(xy 84.089647 -386.20536) (xy 84.061341 -386.167655) (xy 84.04987 -386.147056) (xy 84.049362 -386.146294)
			(xy 83.651598 -385.457954) (xy 83.639742 -385.435267) (xy 83.622883 -385.386939) (xy 83.614302 -385.336479)
			(xy 83.613752 -385.310888) (xy 83.071504 -385.310888) (xy 83.383628 -385.850892) (xy 83.396363 -385.874209)
			(xy 83.414456 -385.924157) (xy 83.423671 -385.976476) (xy 83.424268 -386.003038) (xy 83.424268 -386.003292)
			(xy 83.423854 -386.027287) (xy 83.416348 -386.074686) (xy 83.401518 -386.120327) (xy 83.37973 -386.163086)
			(xy 83.351521 -386.201909) (xy 83.317585 -386.235841) (xy 83.278758 -386.264047) (xy 83.235997 -386.28583)
			(xy 83.190355 -386.300655) (xy 83.142955 -386.308157) (xy 83.11896 -386.3086) (xy 83.095388 -386.308158)
			(xy 83.048802 -386.300925) (xy 83.003884 -386.286608) (xy 82.961706 -386.265548) (xy 82.923272 -386.238245)
			(xy 82.889499 -386.205353) (xy 82.861192 -386.167653) (xy 82.84972 -386.147056) (xy 82.849212 -386.146294)
			(xy 82.451448 -385.457954) (xy 82.439517 -385.435293) (xy 82.422585 -385.386964) (xy 82.413931 -385.336491)
			(xy 82.413348 -385.310888) (xy 81.871608 -385.310888) (xy 82.183732 -385.850892) (xy 82.196467 -385.874209)
			(xy 82.21456 -385.924157) (xy 82.223775 -385.976476) (xy 82.224372 -386.003038) (xy 82.224372 -386.003292)
			(xy 82.223954 -386.027287) (xy 82.216448 -386.074685) (xy 82.201618 -386.120326) (xy 82.179831 -386.163085)
			(xy 82.151622 -386.201908) (xy 82.117687 -386.23584) (xy 82.078861 -386.264045) (xy 82.0361 -386.285829)
			(xy 81.990458 -386.300654) (xy 81.943059 -386.308156) (xy 81.919064 -386.3086) (xy 81.895492 -386.308155)
			(xy 81.848906 -386.300923) (xy 81.803989 -386.286606) (xy 81.76181 -386.265546) (xy 81.723376 -386.238244)
			(xy 81.689603 -386.205352) (xy 81.661296 -386.167653) (xy 81.649824 -386.147056) (xy 81.649316 -386.146294)
			(xy 81.251552 -385.457954) (xy 81.239622 -385.435293) (xy 81.222689 -385.386964) (xy 81.214035 -385.336491)
			(xy 81.213452 -385.310888) (xy 80.671712 -385.310888) (xy 80.983836 -385.850892) (xy 80.996572 -385.874209)
			(xy 81.014664 -385.924157) (xy 81.023879 -385.976476) (xy 81.024476 -386.003038) (xy 81.024476 -386.003292)
			(xy 81.024054 -386.027287) (xy 81.016548 -386.074685) (xy 81.001718 -386.120325) (xy 80.979931 -386.163083)
			(xy 80.951723 -386.201907) (xy 80.917788 -386.235839) (xy 80.878963 -386.264044) (xy 80.836203 -386.285828)
			(xy 80.790561 -386.300653) (xy 80.743163 -386.308156) (xy 80.719168 -386.3086) (xy 80.695596 -386.308151)
			(xy 80.64901 -386.30092) (xy 80.604093 -386.286604) (xy 80.561915 -386.265545) (xy 80.523481 -386.238243)
			(xy 80.489707 -386.205351) (xy 80.4614 -386.167653) (xy 80.449928 -386.147056) (xy 80.44942 -386.146294)
			(xy 80.051656 -385.457954) (xy 80.039726 -385.435293) (xy 80.022793 -385.386964) (xy 80.014139 -385.336491)
			(xy 80.013556 -385.310888) (xy 66.144182 -385.310888) (xy 66.456306 -385.850892) (xy 66.469128 -385.874226)
			(xy 66.48735 -385.924248) (xy 66.496611 -385.976674) (xy 66.4972 -386.003292) (xy 66.496754 -386.027298)
			(xy 66.48924 -386.074718) (xy 66.474396 -386.120378) (xy 66.452589 -386.163152) (xy 66.424356 -386.201985)
			(xy 66.390392 -386.235921) (xy 66.351535 -386.264122) (xy 66.308743 -386.285894) (xy 66.263071 -386.300699)
			(xy 66.215644 -386.308173) (xy 66.191638 -386.3086) (xy 66.191384 -386.3086) (xy 66.16781 -386.308219)
			(xy 66.121221 -386.300975) (xy 66.076302 -386.286647) (xy 66.034123 -386.265576) (xy 65.995691 -386.238265)
			(xy 65.961919 -386.205363) (xy 65.933614 -386.167656) (xy 65.922144 -386.147056) (xy 65.921636 -386.146294)
			(xy 65.523872 -385.457954) (xy 65.511936 -385.435296) (xy 65.495006 -385.386965) (xy 65.486355 -385.336492)
			(xy 65.485772 -385.310888) (xy 64.944032 -385.310888) (xy 65.256156 -385.850892) (xy 65.268893 -385.874208)
			(xy 65.286985 -385.924157) (xy 65.2962 -385.976476) (xy 65.296796 -386.003038) (xy 65.296796 -386.003292)
			(xy 65.296354 -386.027286) (xy 65.288848 -386.074682) (xy 65.27402 -386.12032) (xy 65.252235 -386.163077)
			(xy 65.224029 -386.2019) (xy 65.190097 -386.235831) (xy 65.151274 -386.264037) (xy 65.108517 -386.285822)
			(xy 65.062878 -386.300649) (xy 65.015482 -386.308155) (xy 64.991488 -386.3086) (xy 64.991234 -386.3086)
			(xy 64.967661 -386.308179) (xy 64.921074 -386.300942) (xy 64.876156 -386.286622) (xy 64.833978 -386.265557)
			(xy 64.795544 -386.238252) (xy 64.761772 -386.205356) (xy 64.733465 -386.167654) (xy 64.721994 -386.147056)
			(xy 64.721486 -386.146294) (xy 64.323722 -385.457954) (xy 64.311861 -385.43527) (xy 64.295005 -385.38694)
			(xy 64.286426 -385.33648) (xy 64.285876 -385.310888) (xy 63.744136 -385.310888) (xy 64.05626 -385.850892)
			(xy 64.068998 -385.874207) (xy 64.087089 -385.924157) (xy 64.096304 -385.976476) (xy 64.0969 -386.003038)
			(xy 64.0969 -386.003292) (xy 64.096454 -386.027285) (xy 64.088949 -386.074681) (xy 64.074121 -386.12032)
			(xy 64.052336 -386.163076) (xy 64.02413 -386.201898) (xy 63.990198 -386.23583) (xy 63.951376 -386.264036)
			(xy 63.90862 -386.285821) (xy 63.862981 -386.300649) (xy 63.815585 -386.308154) (xy 63.791592 -386.3086)
			(xy 63.791338 -386.3086) (xy 63.767765 -386.308176) (xy 63.721178 -386.30094) (xy 63.67626 -386.28662)
			(xy 63.634082 -386.265556) (xy 63.595648 -386.238251) (xy 63.561876 -386.205356) (xy 63.533569 -386.167654)
			(xy 63.522098 -386.147056) (xy 63.52159 -386.146294) (xy 63.123826 -385.457954) (xy 63.111965 -385.43527)
			(xy 63.095109 -385.38694) (xy 63.08653 -385.33648) (xy 63.08598 -385.310888) (xy 62.543986 -385.310888)
			(xy 62.85611 -385.850892) (xy 62.868932 -385.874226) (xy 62.887154 -385.924248) (xy 62.896415 -385.976673)
			(xy 62.897004 -386.003292) (xy 62.896554 -386.027298) (xy 62.88904 -386.074718) (xy 62.874197 -386.120377)
			(xy 62.85239 -386.163151) (xy 62.824157 -386.201984) (xy 62.790194 -386.23592) (xy 62.751337 -386.264121)
			(xy 62.708546 -386.285893) (xy 62.662874 -386.300698) (xy 62.615448 -386.308173) (xy 62.591442 -386.3086)
			(xy 62.591188 -386.3086) (xy 62.567614 -386.308216) (xy 62.521025 -386.300973) (xy 62.476106 -386.286645)
			(xy 62.433928 -386.265575) (xy 62.395495 -386.238264) (xy 62.361723 -386.205363) (xy 62.333418 -386.167656)
			(xy 62.321948 -386.147056) (xy 62.32144 -386.146294) (xy 61.923676 -385.457954) (xy 61.91174 -385.435296)
			(xy 61.89481 -385.386965) (xy 61.886159 -385.336492) (xy 61.885576 -385.310888) (xy 61.34409 -385.310888)
			(xy 61.656214 -385.850892) (xy 61.669037 -385.874226) (xy 61.687258 -385.924248) (xy 61.696519 -385.976673)
			(xy 61.697108 -386.003292) (xy 61.696654 -386.027298) (xy 61.68914 -386.074717) (xy 61.674297 -386.120377)
			(xy 61.652491 -386.16315) (xy 61.624258 -386.201983) (xy 61.590295 -386.235918) (xy 61.55144 -386.264119)
			(xy 61.508649 -386.285891) (xy 61.462978 -386.300698) (xy 61.415552 -386.308173) (xy 61.391546 -386.3086)
			(xy 61.391292 -386.3086) (xy 61.367718 -386.308213) (xy 61.321129 -386.30097) (xy 61.27621 -386.286643)
			(xy 61.234032 -386.265573) (xy 61.195599 -386.238263) (xy 61.161828 -386.205362) (xy 61.133522 -386.167656)
			(xy 61.122052 -386.147056) (xy 61.121544 -386.146294) (xy 60.72378 -385.457954) (xy 60.711844 -385.435296)
			(xy 60.694915 -385.386965) (xy 60.686263 -385.336492) (xy 60.68568 -385.310888) (xy 60.144194 -385.310888)
			(xy 60.456318 -385.850892) (xy 60.469141 -385.874226) (xy 60.487362 -385.924248) (xy 60.496623 -385.976673)
			(xy 60.497212 -386.003292) (xy 60.496754 -386.027297) (xy 60.48924 -386.074717) (xy 60.474398 -386.120376)
			(xy 60.452591 -386.163149) (xy 60.424359 -386.201981) (xy 60.390397 -386.235917) (xy 60.351542 -386.264118)
			(xy 60.308752 -386.28589) (xy 60.263081 -386.300697) (xy 60.215656 -386.308172) (xy 60.19165 -386.3086)
			(xy 60.191396 -386.3086) (xy 60.167822 -386.308209) (xy 60.121233 -386.300967) (xy 60.076315 -386.286641)
			(xy 60.034136 -386.265572) (xy 59.995703 -386.238262) (xy 59.961932 -386.205362) (xy 59.933626 -386.167656)
			(xy 59.922156 -386.147056) (xy 59.921648 -386.146294) (xy 59.523884 -385.457954) (xy 59.511948 -385.435296)
			(xy 59.495019 -385.386965) (xy 59.486367 -385.336492) (xy 59.485784 -385.310888) (xy 58.944044 -385.310888)
			(xy 59.256168 -385.850892) (xy 59.268906 -385.874207) (xy 59.286997 -385.924157) (xy 59.296212 -385.976476)
			(xy 59.296808 -386.003038) (xy 59.296808 -386.003292) (xy 59.296354 -386.027285) (xy 59.288849 -386.07468)
			(xy 59.274021 -386.120318) (xy 59.252237 -386.163074) (xy 59.224032 -386.201896) (xy 59.190102 -386.235827)
			(xy 59.151281 -386.264033) (xy 59.108525 -386.285818) (xy 59.062888 -386.300647) (xy 59.015493 -386.308154)
			(xy 58.9915 -386.3086) (xy 58.991246 -386.3086) (xy 58.967673 -386.308169) (xy 58.921087 -386.300935)
			(xy 58.876169 -386.286615) (xy 58.833991 -386.265553) (xy 58.795557 -386.238249) (xy 58.761784 -386.205355)
			(xy 58.733477 -386.167654) (xy 58.722006 -386.147056) (xy 58.721498 -386.146294) (xy 58.323734 -385.457954)
			(xy 58.311874 -385.43527) (xy 58.295018 -385.38694) (xy 58.286438 -385.33648) (xy 58.285888 -385.310888)
			(xy 57.744148 -385.310888) (xy 58.056272 -385.850892) (xy 58.069011 -385.874207) (xy 58.087101 -385.924157)
			(xy 58.096316 -385.976476) (xy 58.096912 -386.003038) (xy 58.096912 -386.003292) (xy 58.096454 -386.027285)
			(xy 58.088949 -386.07468) (xy 58.074122 -386.120317) (xy 58.052338 -386.163073) (xy 58.024134 -386.201894)
			(xy 57.990203 -386.235826) (xy 57.951383 -386.264032) (xy 57.908628 -386.285817) (xy 57.862991 -386.300646)
			(xy 57.815597 -386.308154) (xy 57.791604 -386.3086) (xy 57.79135 -386.3086) (xy 57.767777 -386.308166)
			(xy 57.721191 -386.300932) (xy 57.676273 -386.286613) (xy 57.634095 -386.265551) (xy 57.595661 -386.238248)
			(xy 57.561888 -386.205354) (xy 57.533581 -386.167653) (xy 57.52211 -386.147056) (xy 57.521602 -386.146294)
			(xy 57.123838 -385.457954) (xy 57.111978 -385.435269) (xy 57.095122 -385.38694) (xy 57.086542 -385.33648)
			(xy 57.085992 -385.310888) (xy 56.543744 -385.310888) (xy 56.855868 -385.850892) (xy 56.868606 -385.874207)
			(xy 56.886697 -385.924157) (xy 56.895912 -385.976476) (xy 56.896508 -386.003038) (xy 56.896508 -386.003292)
			(xy 56.896054 -386.027285) (xy 56.888549 -386.07468) (xy 56.873721 -386.120318) (xy 56.851937 -386.163074)
			(xy 56.823732 -386.201896) (xy 56.789802 -386.235827) (xy 56.750981 -386.264033) (xy 56.708225 -386.285818)
			(xy 56.662588 -386.300647) (xy 56.615193 -386.308154) (xy 56.5912 -386.3086) (xy 56.567626 -386.308206)
			(xy 56.521038 -386.300965) (xy 56.476119 -386.286639) (xy 56.433941 -386.26557) (xy 56.395508 -386.238261)
			(xy 56.361736 -386.205361) (xy 56.33343 -386.167656) (xy 56.32196 -386.147056) (xy 56.321452 -386.146294)
			(xy 55.923688 -385.457954) (xy 55.911753 -385.435296) (xy 55.894823 -385.386965) (xy 55.886171 -385.336491)
			(xy 55.885588 -385.310888) (xy 55.343848 -385.310888) (xy 55.655972 -385.850892) (xy 55.668711 -385.874207)
			(xy 55.686801 -385.924157) (xy 55.696016 -385.976476) (xy 55.696612 -386.003038) (xy 55.696612 -386.003292)
			(xy 55.696154 -386.027285) (xy 55.688649 -386.07468) (xy 55.673822 -386.120317) (xy 55.652038 -386.163073)
			(xy 55.623834 -386.201894) (xy 55.589903 -386.235826) (xy 55.551083 -386.264032) (xy 55.508328 -386.285817)
			(xy 55.462691 -386.300646) (xy 55.415297 -386.308154) (xy 55.391304 -386.3086) (xy 55.36773 -386.308203)
			(xy 55.321142 -386.300962) (xy 55.276223 -386.286637) (xy 55.234045 -386.265569) (xy 55.195612 -386.23826)
			(xy 55.16184 -386.205361) (xy 55.133535 -386.167656) (xy 55.122064 -386.147056) (xy 55.121556 -386.146294)
			(xy 54.723792 -385.457954) (xy 54.711857 -385.435295) (xy 54.694927 -385.386965) (xy 54.686275 -385.336491)
			(xy 54.685692 -385.310888) (xy 54.143952 -385.310888) (xy 54.456076 -385.850892) (xy 54.468815 -385.874207)
			(xy 54.486905 -385.924157) (xy 54.49612 -385.976476) (xy 54.496716 -386.003038) (xy 54.496716 -386.003292)
			(xy 54.49623 -386.027283) (xy 54.488725 -386.074673) (xy 54.4739 -386.120306) (xy 54.452118 -386.163059)
			(xy 54.423916 -386.201877) (xy 54.389989 -386.235806) (xy 54.351172 -386.264009) (xy 54.308421 -386.285793)
			(xy 54.262789 -386.300622) (xy 54.215399 -386.308129) (xy 54.191408 -386.3086) (xy 54.167834 -386.3082)
			(xy 54.121246 -386.30096) (xy 54.076328 -386.286635) (xy 54.034149 -386.265567) (xy 53.995716 -386.238259)
			(xy 53.961944 -386.20536) (xy 53.933639 -386.167655) (xy 53.922168 -386.147056) (xy 53.92166 -386.146294)
			(xy 53.523896 -385.457954) (xy 53.511961 -385.435295) (xy 53.495031 -385.386965) (xy 53.486379 -385.336491)
			(xy 53.485796 -385.310888) (xy 52.943802 -385.310888) (xy 53.255926 -385.850892) (xy 53.26875 -385.874225)
			(xy 53.286971 -385.924247) (xy 53.296231 -385.976673) (xy 53.29682 -386.003292) (xy 53.296331 -386.02727)
			(xy 53.288835 -386.074636) (xy 53.274024 -386.120247) (xy 53.252265 -386.162982) (xy 53.224092 -386.201789)
			(xy 53.190197 -386.235713) (xy 53.151416 -386.263922) (xy 53.1087 -386.285719) (xy 53.063102 -386.30057)
			(xy 53.015743 -386.30811) (xy 52.991766 -386.3086) (xy 52.991258 -386.3086) (xy 52.967686 -386.308159)
			(xy 52.9211 -386.300927) (xy 52.876182 -386.286609) (xy 52.834004 -386.265548) (xy 52.79557 -386.238246)
			(xy 52.761797 -386.205353) (xy 52.73349 -386.167653) (xy 52.722018 -386.147056) (xy 52.72151 -386.146294)
			(xy 52.323746 -385.457954) (xy 52.311886 -385.435269) (xy 52.29503 -385.38694) (xy 52.28645 -385.33648)
			(xy 52.2859 -385.310888) (xy 51.743906 -385.310888) (xy 52.05603 -385.850892) (xy 52.068854 -385.874225)
			(xy 52.087075 -385.924247) (xy 52.096335 -385.976673) (xy 52.096924 -386.003292) (xy 52.096431 -386.02727)
			(xy 52.088935 -386.074635) (xy 52.074125 -386.120246) (xy 52.052366 -386.16298) (xy 52.024193 -386.201787)
			(xy 51.990299 -386.235712) (xy 51.951518 -386.26392) (xy 51.908803 -386.285718) (xy 51.863206 -386.30057)
			(xy 51.815847 -386.308109) (xy 51.79187 -386.3086) (xy 51.791362 -386.3086) (xy 51.76779 -386.308156)
			(xy 51.721204 -386.300924) (xy 51.676286 -386.286607) (xy 51.634108 -386.265547) (xy 51.595674 -386.238245)
			(xy 51.561901 -386.205352) (xy 51.533594 -386.167653) (xy 51.522122 -386.147056) (xy 51.521614 -386.146294)
			(xy 51.12385 -385.457954) (xy 51.111991 -385.435269) (xy 51.095134 -385.38694) (xy 51.086554 -385.33648)
			(xy 51.086004 -385.310888) (xy 50.543756 -385.310888) (xy 50.85588 -385.850892) (xy 50.868619 -385.874207)
			(xy 50.886709 -385.924157) (xy 50.895924 -385.976476) (xy 50.89652 -386.003038) (xy 50.89652 -386.003292)
			(xy 50.89603 -386.027282) (xy 50.888526 -386.074673) (xy 50.8737 -386.120306) (xy 50.851918 -386.163057)
			(xy 50.823717 -386.201876) (xy 50.789791 -386.235804) (xy 50.750974 -386.264008) (xy 50.708224 -386.285792)
			(xy 50.662592 -386.300621) (xy 50.615202 -386.308128) (xy 50.591212 -386.3086) (xy 50.567638 -386.308197)
			(xy 50.521051 -386.300957) (xy 50.476132 -386.286633) (xy 50.433954 -386.265566) (xy 50.395521 -386.238258)
			(xy 50.361749 -386.205359) (xy 50.333443 -386.167655) (xy 50.321972 -386.147056) (xy 50.321464 -386.146294)
			(xy 49.9237 -385.457954) (xy 49.911766 -385.435295) (xy 49.894835 -385.386965) (xy 49.886183 -385.336491)
			(xy 49.8856 -385.310888) (xy 49.34386 -385.310888) (xy 49.655984 -385.850892) (xy 49.668715 -385.874211)
			(xy 49.68681 -385.924158) (xy 49.696027 -385.976477) (xy 49.696624 -386.003038) (xy 49.696624 -386.003292)
			(xy 49.69613 -386.027282) (xy 49.688626 -386.074672) (xy 49.6738 -386.120305) (xy 49.652019 -386.163056)
			(xy 49.623818 -386.201874) (xy 49.589892 -386.235803) (xy 49.551077 -386.264007) (xy 49.508327 -386.285791)
			(xy 49.462695 -386.30062) (xy 49.415306 -386.308128) (xy 49.391316 -386.3086) (xy 49.367742 -386.308193)
			(xy 49.321155 -386.300954) (xy 49.276236 -386.286631) (xy 49.234058 -386.265564) (xy 49.195625 -386.238257)
			(xy 49.161853 -386.205359) (xy 49.133547 -386.167655) (xy 49.122076 -386.147056) (xy 49.121568 -386.146294)
			(xy 48.723804 -385.457954) (xy 48.71187 -385.435295) (xy 48.694939 -385.386965) (xy 48.686287 -385.336491)
			(xy 48.685704 -385.310888) (xy 48.143964 -385.310888) (xy 48.456088 -385.850892) (xy 48.46882 -385.874211)
			(xy 48.486915 -385.924158) (xy 48.496131 -385.976477) (xy 48.496728 -386.003038) (xy 48.496728 -386.003292)
			(xy 48.49623 -386.027282) (xy 48.488726 -386.074672) (xy 48.473901 -386.120304) (xy 48.45212 -386.163055)
			(xy 48.42392 -386.201873) (xy 48.389994 -386.235801) (xy 48.351179 -386.264005) (xy 48.30843 -386.28579)
			(xy 48.262799 -386.300619) (xy 48.21541 -386.308128) (xy 48.19142 -386.3086) (xy 48.167847 -386.30819)
			(xy 48.121259 -386.300952) (xy 48.076341 -386.286629) (xy 48.034162 -386.265563) (xy 47.995729 -386.238256)
			(xy 47.961957 -386.205358) (xy 47.933651 -386.167655) (xy 47.92218 -386.147056) (xy 47.921672 -386.146294)
			(xy 47.523908 -385.457954) (xy 47.511974 -385.435295) (xy 47.495043 -385.386965) (xy 47.486391 -385.336491)
			(xy 47.485808 -385.310888) (xy 2.509012 -385.310888) (xy 2.509012 -387.789674) (xy 40.901112 -387.789674)
			(xy 40.901112 -386.926074) (xy 40.901598 -386.898805) (xy 40.90936 -386.844821) (xy 40.924725 -386.792491)
			(xy 40.947382 -386.742881) (xy 40.976868 -386.697) (xy 41.012583 -386.655783) (xy 41.0538 -386.620068)
			(xy 41.099681 -386.590582) (xy 41.149291 -386.567925) (xy 41.201621 -386.55256) (xy 41.255605 -386.544798)
			(xy 41.310143 -386.544798) (xy 41.364127 -386.55256) (xy 41.416457 -386.567925) (xy 41.466067 -386.590582)
			(xy 41.511948 -386.620068) (xy 41.553165 -386.655783) (xy 41.58888 -386.697) (xy 41.618366 -386.742881)
			(xy 41.641023 -386.792491) (xy 41.656388 -386.844821) (xy 41.66415 -386.898805) (xy 41.664636 -386.926074)
			(xy 41.664636 -387.789674) (xy 73.42886 -387.789674) (xy 73.42886 -386.926074) (xy 73.429346 -386.898805)
			(xy 73.437108 -386.844821) (xy 73.452473 -386.792491) (xy 73.47513 -386.742881) (xy 73.504616 -386.697)
			(xy 73.540331 -386.655783) (xy 73.581548 -386.620068) (xy 73.627429 -386.590582) (xy 73.677039 -386.567925)
			(xy 73.729369 -386.55256) (xy 73.783353 -386.544798) (xy 73.837891 -386.544798) (xy 73.891875 -386.55256)
			(xy 73.944205 -386.567925) (xy 73.993815 -386.590582) (xy 74.039696 -386.620068) (xy 74.080913 -386.655783)
			(xy 74.116628 -386.697) (xy 74.146114 -386.742881) (xy 74.168771 -386.792491) (xy 74.184136 -386.844821)
			(xy 74.191898 -386.898805) (xy 74.192384 -386.926074) (xy 74.192384 -387.789674) (xy 108.001308 -387.789674)
			(xy 108.001308 -386.926074) (xy 108.001794 -386.898823) (xy 108.00955 -386.844875) (xy 108.024905 -386.79258)
			(xy 108.047547 -386.743003) (xy 108.077013 -386.697153) (xy 108.112704 -386.655962) (xy 108.153895 -386.620271)
			(xy 108.199745 -386.590805) (xy 108.249322 -386.568163) (xy 108.301617 -386.552808) (xy 108.355565 -386.545052)
			(xy 108.410067 -386.545052) (xy 108.464015 -386.552808) (xy 108.51631 -386.568163) (xy 108.565887 -386.590805)
			(xy 108.611737 -386.620271) (xy 108.652928 -386.655962) (xy 108.688619 -386.697153) (xy 108.718085 -386.743003)
			(xy 108.740727 -386.79258) (xy 108.756082 -386.844875) (xy 108.763838 -386.898823) (xy 108.764324 -386.926074)
			(xy 108.764324 -387.789674) (xy 140.529056 -387.789674) (xy 140.529056 -386.926074) (xy 140.529542 -386.898823)
			(xy 140.537298 -386.844875) (xy 140.552653 -386.79258) (xy 140.575295 -386.743003) (xy 140.604761 -386.697153)
			(xy 140.640452 -386.655962) (xy 140.681643 -386.620271) (xy 140.727493 -386.590805) (xy 140.77707 -386.568163)
			(xy 140.829365 -386.552808) (xy 140.883313 -386.545052) (xy 140.937815 -386.545052) (xy 140.991763 -386.552808)
			(xy 141.044058 -386.568163) (xy 141.093635 -386.590805) (xy 141.139485 -386.620271) (xy 141.180676 -386.655962)
			(xy 141.216367 -386.697153) (xy 141.245833 -386.743003) (xy 141.268475 -386.79258) (xy 141.28383 -386.844875)
			(xy 141.291586 -386.898823) (xy 141.292072 -386.926074) (xy 141.292072 -387.789674) (xy 141.291586 -387.816925)
			(xy 141.28383 -387.870873) (xy 141.268475 -387.923168) (xy 141.245833 -387.972745) (xy 141.216367 -388.018595)
			(xy 141.180676 -388.059786) (xy 141.139485 -388.095477) (xy 141.093635 -388.124943) (xy 141.044058 -388.147585)
			(xy 140.991763 -388.16294) (xy 140.937815 -388.170696) (xy 140.883313 -388.170696) (xy 140.829365 -388.16294)
			(xy 140.77707 -388.147585) (xy 140.727493 -388.124943) (xy 140.681643 -388.095477) (xy 140.640452 -388.059786)
			(xy 140.604761 -388.018595) (xy 140.575295 -387.972745) (xy 140.552653 -387.923168) (xy 140.537298 -387.870873)
			(xy 140.529542 -387.816925) (xy 140.529056 -387.789674) (xy 108.764324 -387.789674) (xy 108.763838 -387.816925)
			(xy 108.756082 -387.870873) (xy 108.740727 -387.923168) (xy 108.718085 -387.972745) (xy 108.688619 -388.018595)
			(xy 108.652928 -388.059786) (xy 108.611737 -388.095477) (xy 108.565887 -388.124943) (xy 108.51631 -388.147585)
			(xy 108.464015 -388.16294) (xy 108.410067 -388.170696) (xy 108.355565 -388.170696) (xy 108.301617 -388.16294)
			(xy 108.249322 -388.147585) (xy 108.199745 -388.124943) (xy 108.153895 -388.095477) (xy 108.112704 -388.059786)
			(xy 108.077013 -388.018595) (xy 108.047547 -387.972745) (xy 108.024905 -387.923168) (xy 108.00955 -387.870873)
			(xy 108.001794 -387.816925) (xy 108.001308 -387.789674) (xy 74.192384 -387.789674) (xy 74.191898 -387.816943)
			(xy 74.184136 -387.870927) (xy 74.168771 -387.923257) (xy 74.146114 -387.972867) (xy 74.116628 -388.018748)
			(xy 74.080913 -388.059965) (xy 74.039696 -388.09568) (xy 73.993815 -388.125166) (xy 73.944205 -388.147823)
			(xy 73.891875 -388.163188) (xy 73.837891 -388.17095) (xy 73.783353 -388.17095) (xy 73.729369 -388.163188)
			(xy 73.677039 -388.147823) (xy 73.627429 -388.125166) (xy 73.581548 -388.09568) (xy 73.540331 -388.059965)
			(xy 73.504616 -388.018748) (xy 73.47513 -387.972867) (xy 73.452473 -387.923257) (xy 73.437108 -387.870927)
			(xy 73.429346 -387.816943) (xy 73.42886 -387.789674) (xy 41.664636 -387.789674) (xy 41.66415 -387.816943)
			(xy 41.656388 -387.870927) (xy 41.641023 -387.923257) (xy 41.618366 -387.972867) (xy 41.58888 -388.018748)
			(xy 41.553165 -388.059965) (xy 41.511948 -388.09568) (xy 41.466067 -388.125166) (xy 41.416457 -388.147823)
			(xy 41.364127 -388.163188) (xy 41.310143 -388.17095) (xy 41.255605 -388.17095) (xy 41.201621 -388.163188)
			(xy 41.149291 -388.147823) (xy 41.099681 -388.125166) (xy 41.0538 -388.09568) (xy 41.012583 -388.059965)
			(xy 40.976868 -388.018748) (xy 40.947382 -387.972867) (xy 40.924725 -387.923257) (xy 40.90936 -387.870927)
			(xy 40.901598 -387.816943) (xy 40.901112 -387.789674) (xy 2.509012 -387.789674) (xy 2.509012 -388.77494)
			(xy 47.485808 -388.77494) (xy 47.485808 -388.774432) (xy 47.486291 -388.750454) (xy 47.493785 -388.703086)
			(xy 47.508594 -388.657473) (xy 47.530352 -388.614736) (xy 47.558526 -388.575927) (xy 47.592422 -388.542002)
			(xy 47.631205 -388.513794) (xy 47.673923 -388.491997) (xy 47.719523 -388.477148) (xy 47.766884 -388.469612)
			(xy 47.790862 -388.469124) (xy 47.79137 -388.469124) (xy 47.815307 -388.469547) (xy 47.862595 -388.477009)
			(xy 47.90814 -388.491756) (xy 47.950828 -388.513426) (xy 47.989613 -388.541489) (xy 48.023547 -388.575259)
			(xy 48.051798 -388.613907) (xy 48.06315 -388.634986) (xy 48.063658 -388.636002) (xy 48.143964 -388.77494)
			(xy 48.685704 -388.77494) (xy 48.685704 -388.774432) (xy 48.686191 -388.750454) (xy 48.693685 -388.703086)
			(xy 48.708493 -388.657473) (xy 48.730252 -388.614737) (xy 48.758425 -388.575929) (xy 48.79232 -388.542003)
			(xy 48.831103 -388.513795) (xy 48.87382 -388.491998) (xy 48.91942 -388.477149) (xy 48.96678 -388.469613)
			(xy 48.990758 -388.469124) (xy 48.991266 -388.469124) (xy 49.015203 -388.46955) (xy 49.06249 -388.477012)
			(xy 49.108036 -388.491758) (xy 49.150724 -388.513428) (xy 49.189509 -388.54149) (xy 49.223443 -388.575259)
			(xy 49.251694 -388.613908) (xy 49.263046 -388.634986) (xy 49.263554 -388.636002) (xy 49.34386 -388.77494)
			(xy 49.8856 -388.77494) (xy 49.8856 -388.774432) (xy 49.886091 -388.750454) (xy 49.893585 -388.703087)
			(xy 49.908393 -388.657474) (xy 49.930151 -388.614738) (xy 49.958324 -388.57593) (xy 49.992219 -388.542005)
			(xy 50.031001 -388.513796) (xy 50.073717 -388.491999) (xy 50.119316 -388.47715) (xy 50.166676 -388.469613)
			(xy 50.190654 -388.469124) (xy 50.191162 -388.469124) (xy 50.215098 -388.469553) (xy 50.262386 -388.477014)
			(xy 50.307931 -388.49176) (xy 50.350619 -388.513429) (xy 50.389405 -388.541491) (xy 50.423338 -388.57526)
			(xy 50.45159 -388.613908) (xy 50.462942 -388.634986) (xy 50.46345 -388.636002) (xy 50.543756 -388.77494)
			(xy 51.086004 -388.77494) (xy 51.086004 -388.774432) (xy 51.086468 -388.750439) (xy 51.09397 -388.703044)
			(xy 51.108795 -388.657405) (xy 51.130577 -388.614648) (xy 51.158781 -388.575826) (xy 51.192711 -388.541894)
			(xy 51.231531 -388.513688) (xy 51.274287 -388.491903) (xy 51.319924 -388.477075) (xy 51.367319 -388.469569)
			(xy 51.391312 -388.469124) (xy 51.415247 -388.469594) (xy 51.462533 -388.477047) (xy 51.508077 -388.491786)
			(xy 51.550765 -388.513448) (xy 51.589551 -388.541504) (xy 51.623486 -388.575267) (xy 51.651739 -388.61391)
			(xy 51.663092 -388.634986) (xy 51.6636 -388.636002) (xy 51.743906 -388.77494) (xy 52.2859 -388.77494)
			(xy 52.2859 -388.774432) (xy 52.286368 -388.750439) (xy 52.29387 -388.703044) (xy 52.308695 -388.657406)
			(xy 52.330477 -388.61465) (xy 52.35868 -388.575827) (xy 52.392609 -388.541895) (xy 52.431429 -388.513689)
			(xy 52.474184 -388.491904) (xy 52.519821 -388.477076) (xy 52.567215 -388.46957) (xy 52.591208 -388.469124)
			(xy 52.615143 -388.469597) (xy 52.662429 -388.47705) (xy 52.707973 -388.491788) (xy 52.750661 -388.51345)
			(xy 52.789447 -388.541505) (xy 52.823382 -388.575268) (xy 52.851635 -388.61391) (xy 52.862988 -388.634986)
			(xy 52.863496 -388.636002) (xy 52.943802 -388.77494) (xy 53.485796 -388.77494) (xy 53.485796 -388.774432)
			(xy 53.486291 -388.750454) (xy 53.493785 -388.703088) (xy 53.508592 -388.657475) (xy 53.53035 -388.61474)
			(xy 53.558523 -388.575932) (xy 53.592417 -388.542006) (xy 53.631199 -388.513798) (xy 53.673914 -388.492001)
			(xy 53.719513 -388.477151) (xy 53.766873 -388.469613) (xy 53.79085 -388.469124) (xy 53.791358 -388.469124)
			(xy 53.815294 -388.469556) (xy 53.862582 -388.477017) (xy 53.908127 -388.491762) (xy 53.950815 -388.513431)
			(xy 53.9896 -388.541492) (xy 54.023534 -388.57526) (xy 54.051786 -388.613908) (xy 54.063138 -388.634986)
			(xy 54.063646 -388.636002) (xy 54.143952 -388.77494) (xy 54.685692 -388.77494) (xy 54.685692 -388.774432)
			(xy 54.686191 -388.750454) (xy 54.693684 -388.703088) (xy 54.708492 -388.657476) (xy 54.730249 -388.614741)
			(xy 54.758422 -388.575933) (xy 54.792315 -388.542008) (xy 54.831097 -388.513799) (xy 54.873812 -388.492002)
			(xy 54.91941 -388.477151) (xy 54.966769 -388.469614) (xy 54.990746 -388.469124) (xy 54.991254 -388.469124)
			(xy 55.01519 -388.46956) (xy 55.062478 -388.47702) (xy 55.108023 -388.491764) (xy 55.150711 -388.513432)
			(xy 55.189496 -388.541493) (xy 55.22343 -388.575261) (xy 55.251681 -388.613908) (xy 55.263034 -388.634986)
			(xy 55.263542 -388.636002) (xy 55.343848 -388.77494) (xy 55.885588 -388.77494) (xy 55.885588 -388.774432)
			(xy 55.886091 -388.750455) (xy 55.893584 -388.703089) (xy 55.908392 -388.657477) (xy 55.930149 -388.614742)
			(xy 55.95832 -388.575934) (xy 55.992213 -388.542009) (xy 56.030994 -388.513801) (xy 56.073709 -388.492003)
			(xy 56.119306 -388.477152) (xy 56.166665 -388.469614) (xy 56.190642 -388.469124) (xy 56.19115 -388.469124)
			(xy 56.215086 -388.469563) (xy 56.262373 -388.477022) (xy 56.307918 -388.491766) (xy 56.350606 -388.513434)
			(xy 56.389392 -388.541494) (xy 56.423326 -388.575262) (xy 56.451577 -388.613908) (xy 56.46293 -388.634986)
			(xy 56.463438 -388.636002) (xy 56.543744 -388.77494) (xy 57.085992 -388.77494) (xy 57.085992 -388.774432)
			(xy 57.086468 -388.75044) (xy 57.09397 -388.703045) (xy 57.108794 -388.657408) (xy 57.130575 -388.614652)
			(xy 57.158777 -388.57583) (xy 57.192706 -388.541898) (xy 57.231525 -388.513692) (xy 57.274279 -388.491906)
			(xy 57.319914 -388.477077) (xy 57.367308 -388.46957) (xy 57.3913 -388.469124) (xy 57.415235 -388.469603)
			(xy 57.46252 -388.477055) (xy 57.508064 -388.491792) (xy 57.550752 -388.513453) (xy 57.589538 -388.541507)
			(xy 57.623473 -388.575269) (xy 57.651726 -388.613911) (xy 57.66308 -388.634986) (xy 57.663588 -388.636002)
			(xy 57.743894 -388.77494) (xy 58.285888 -388.77494) (xy 58.285888 -388.774432) (xy 58.286368 -388.75044)
			(xy 58.29387 -388.703046) (xy 58.308693 -388.657409) (xy 58.330474 -388.614653) (xy 58.358676 -388.575831)
			(xy 58.392604 -388.5419) (xy 58.431423 -388.513693) (xy 58.474176 -388.491907) (xy 58.519811 -388.477078)
			(xy 58.567204 -388.469571) (xy 58.591196 -388.469124) (xy 58.615133 -388.469526) (xy 58.662423 -388.476992)
			(xy 58.707968 -388.491742) (xy 58.750656 -388.513416) (xy 58.789441 -388.541483) (xy 58.823374 -388.575255)
			(xy 58.851624 -388.613906) (xy 58.862976 -388.634986) (xy 58.863484 -388.636002) (xy 58.94379 -388.77494)
			(xy 59.485784 -388.77494) (xy 59.485784 -388.774432) (xy 59.486291 -388.750455) (xy 59.493784 -388.703089)
			(xy 59.508591 -388.657478) (xy 59.530348 -388.614743) (xy 59.558519 -388.575936) (xy 59.592412 -388.54201)
			(xy 59.631192 -388.513802) (xy 59.673906 -388.492004) (xy 59.719503 -388.477153) (xy 59.766861 -388.469614)
			(xy 59.790838 -388.469124) (xy 59.791346 -388.469124) (xy 59.815282 -388.469566) (xy 59.862569 -388.477025)
			(xy 59.908114 -388.491768) (xy 59.950802 -388.513435) (xy 59.989587 -388.541495) (xy 60.023522 -388.575262)
			(xy 60.051773 -388.613909) (xy 60.063126 -388.634986) (xy 60.063634 -388.636002) (xy 60.14394 -388.77494)
			(xy 60.68568 -388.77494) (xy 60.68568 -388.774432) (xy 60.686191 -388.750455) (xy 60.693684 -388.70309)
			(xy 60.708491 -388.657479) (xy 60.730247 -388.614744) (xy 60.758418 -388.575937) (xy 60.79231 -388.542012)
			(xy 60.83109 -388.513803) (xy 60.873803 -388.492005) (xy 60.9194 -388.477154) (xy 60.966757 -388.469614)
			(xy 60.990734 -388.469124) (xy 60.991242 -388.469124) (xy 61.015178 -388.469569) (xy 61.062465 -388.477028)
			(xy 61.10801 -388.49177) (xy 61.150697 -388.513437) (xy 61.189483 -388.541496) (xy 61.223417 -388.575263)
			(xy 61.251669 -388.613909) (xy 61.263022 -388.634986) (xy 61.26353 -388.636002) (xy 61.343836 -388.77494)
			(xy 61.885576 -388.77494) (xy 61.885576 -388.774432) (xy 61.886091 -388.750455) (xy 61.893584 -388.70309)
			(xy 61.908391 -388.65748) (xy 61.930147 -388.614746) (xy 61.958317 -388.575938) (xy 61.992208 -388.542013)
			(xy 62.030988 -388.513805) (xy 62.073701 -388.492006) (xy 62.119296 -388.477155) (xy 62.166654 -388.469615)
			(xy 62.19063 -388.469124) (xy 62.191138 -388.469124) (xy 62.215074 -388.469573) (xy 62.262361 -388.47703)
			(xy 62.307905 -388.491772) (xy 62.350593 -388.513438) (xy 62.389379 -388.541498) (xy 62.423313 -388.575263)
			(xy 62.451565 -388.613909) (xy 62.462918 -388.634986) (xy 62.463426 -388.636002) (xy 62.543732 -388.77494)
			(xy 63.08598 -388.77494) (xy 63.08598 -388.774432) (xy 63.086468 -388.75044) (xy 63.093969 -388.703047)
			(xy 63.108793 -388.657411) (xy 63.130573 -388.614656) (xy 63.158774 -388.575834) (xy 63.192701 -388.541902)
			(xy 63.231518 -388.513696) (xy 63.27427 -388.49191) (xy 63.319904 -388.47708) (xy 63.367296 -388.469571)
			(xy 63.391288 -388.469124) (xy 63.415225 -388.469532) (xy 63.462514 -388.476997) (xy 63.50806 -388.491747)
			(xy 63.550747 -388.513419) (xy 63.589533 -388.541485) (xy 63.623466 -388.575256) (xy 63.651716 -388.613907)
			(xy 63.663068 -388.634986) (xy 63.663576 -388.636002) (xy 63.743882 -388.77494) (xy 64.285876 -388.77494)
			(xy 64.285876 -388.774432) (xy 64.286368 -388.750441) (xy 64.293869 -388.703048) (xy 64.308692 -388.657412)
			(xy 64.330472 -388.614657) (xy 64.358673 -388.575836) (xy 64.392599 -388.541904) (xy 64.431416 -388.513697)
			(xy 64.474167 -388.491911) (xy 64.519801 -388.47708) (xy 64.567193 -388.469571) (xy 64.591184 -388.469124)
			(xy 64.615121 -388.469535) (xy 64.66241 -388.477) (xy 64.707955 -388.491749) (xy 64.750643 -388.513421)
			(xy 64.789428 -388.541486) (xy 64.823361 -388.575257) (xy 64.851612 -388.613907) (xy 64.862964 -388.634986)
			(xy 64.863472 -388.636002) (xy 64.943778 -388.77494) (xy 65.485772 -388.77494) (xy 65.485772 -388.774432)
			(xy 65.486291 -388.750455) (xy 65.493784 -388.703091) (xy 65.50859 -388.657481) (xy 65.530346 -388.614747)
			(xy 65.558516 -388.57594) (xy 65.592407 -388.542015) (xy 65.631185 -388.513806) (xy 65.673898 -388.492007)
			(xy 65.719493 -388.477155) (xy 65.76685 -388.469615) (xy 65.790826 -388.469124) (xy 65.791334 -388.469124)
			(xy 65.81527 -388.469576) (xy 65.862556 -388.477033) (xy 65.908101 -388.491774) (xy 65.950789 -388.51344)
			(xy 65.989575 -388.541499) (xy 66.023509 -388.575264) (xy 66.051761 -388.613909) (xy 66.063114 -388.634986)
			(xy 66.063622 -388.636002) (xy 66.130256 -388.751285) (xy 80.01394 -388.751285) (xy 80.021272 -388.703738)
			(xy 80.035965 -388.657927) (xy 80.057656 -388.614986) (xy 80.085809 -388.575975) (xy 80.119729 -388.541859)
			(xy 80.158577 -388.51348) (xy 80.201392 -388.491541) (xy 80.247116 -388.476583) (xy 80.29462 -388.468977)
			(xy 80.342729 -388.46891) (xy 80.390254 -388.476384) (xy 80.43602 -388.491214) (xy 80.478896 -388.513033)
			(xy 80.517823 -388.541304) (xy 80.551837 -388.575325) (xy 80.5801 -388.614258) (xy 80.591406 -388.635494)
			(xy 80.591914 -388.636764) (xy 80.658096 -388.751285) (xy 81.213844 -388.751285) (xy 81.221175 -388.703738)
			(xy 81.235868 -388.657929) (xy 81.257559 -388.614988) (xy 81.285712 -388.575977) (xy 81.319631 -388.541862)
			(xy 81.358478 -388.513483) (xy 81.401293 -388.491544) (xy 81.447017 -388.476587) (xy 81.49452 -388.46898)
			(xy 81.542628 -388.468913) (xy 81.590152 -388.476387) (xy 81.635918 -388.491217) (xy 81.678793 -388.513036)
			(xy 81.717719 -388.541305) (xy 81.751734 -388.575326) (xy 81.779996 -388.614258) (xy 81.791302 -388.635494)
			(xy 81.79181 -388.636764) (xy 81.857992 -388.751285) (xy 82.413748 -388.751285) (xy 82.421079 -388.703739)
			(xy 82.435771 -388.65793) (xy 82.457462 -388.61499) (xy 82.485615 -388.57598) (xy 82.519533 -388.541864)
			(xy 82.55838 -388.513487) (xy 82.601194 -388.491548) (xy 82.646917 -388.47659) (xy 82.694419 -388.468984)
			(xy 82.742527 -388.468917) (xy 82.79005 -388.47639) (xy 82.835815 -388.491219) (xy 82.87869 -388.513038)
			(xy 82.917616 -388.541307) (xy 82.95163 -388.575327) (xy 82.979892 -388.614258) (xy 82.991198 -388.635494)
			(xy 82.991706 -388.636764) (xy 83.057889 -388.751287) (xy 83.613803 -388.751287) (xy 83.621135 -388.703732)
			(xy 83.635829 -388.657915) (xy 83.657524 -388.614967) (xy 83.685682 -388.57595) (xy 83.719607 -388.541829)
			(xy 83.75846 -388.513446) (xy 83.801282 -388.491504) (xy 83.847014 -388.476545) (xy 83.894525 -388.468939)
			(xy 83.942642 -388.468873) (xy 83.990174 -388.47635) (xy 84.035946 -388.491184) (xy 84.078828 -388.513009)
			(xy 84.117759 -388.541285) (xy 84.151777 -388.575314) (xy 84.180041 -388.614254) (xy 84.191348 -388.635494)
			(xy 84.191856 -388.636764) (xy 84.258039 -388.751287) (xy 84.813706 -388.751287) (xy 84.821038 -388.703733)
			(xy 84.835733 -388.657916) (xy 84.857427 -388.614969) (xy 84.885584 -388.575952) (xy 84.919509 -388.541831)
			(xy 84.958362 -388.513449) (xy 85.001183 -388.491508) (xy 85.046914 -388.476549) (xy 85.094425 -388.468942)
			(xy 85.14254 -388.468877) (xy 85.190072 -388.476353) (xy 85.235844 -388.491187) (xy 85.278725 -388.513011)
			(xy 85.317655 -388.541287) (xy 85.351673 -388.575315) (xy 85.379937 -388.614254) (xy 85.391244 -388.635494)
			(xy 85.391752 -388.636764) (xy 85.457933 -388.751284) (xy 86.013951 -388.751284) (xy 86.021282 -388.703739)
			(xy 86.035975 -388.657931) (xy 86.057665 -388.614992) (xy 86.085817 -388.575982) (xy 86.119735 -388.541867)
			(xy 86.158581 -388.51349) (xy 86.201394 -388.491551) (xy 86.247117 -388.476594) (xy 86.294619 -388.468988)
			(xy 86.342725 -388.46892) (xy 86.390248 -388.476393) (xy 86.436013 -388.491222) (xy 86.478887 -388.513041)
			(xy 86.517813 -388.541309) (xy 86.551826 -388.575329) (xy 86.580088 -388.614259) (xy 86.591394 -388.635494)
			(xy 86.591902 -388.636764) (xy 86.658083 -388.751284) (xy 87.213855 -388.751284) (xy 87.221186 -388.70374)
			(xy 87.235878 -388.657932) (xy 87.257568 -388.614993) (xy 87.28572 -388.575985) (xy 87.319638 -388.54187)
			(xy 87.358483 -388.513493) (xy 87.401295 -388.491555) (xy 87.447017 -388.476598) (xy 87.494518 -388.468991)
			(xy 87.542624 -388.468924) (xy 87.590147 -388.476397) (xy 87.63591 -388.491225) (xy 87.678784 -388.513043)
			(xy 87.717709 -388.541311) (xy 87.751722 -388.57533) (xy 87.779984 -388.614259) (xy 87.79129 -388.635494)
			(xy 87.791798 -388.636764) (xy 87.857979 -388.751284) (xy 88.413758 -388.751284) (xy 88.42109 -388.70374)
			(xy 88.435782 -388.657933) (xy 88.457471 -388.614995) (xy 88.485623 -388.575987) (xy 88.51954 -388.541873)
			(xy 88.558384 -388.513496) (xy 88.601196 -388.491558) (xy 88.646917 -388.476601) (xy 88.694418 -388.468995)
			(xy 88.742523 -388.468927) (xy 88.790045 -388.4764) (xy 88.835808 -388.491228) (xy 88.878681 -388.513045)
			(xy 88.917606 -388.541312) (xy 88.951619 -388.575331) (xy 88.97988 -388.614259) (xy 88.991186 -388.635494)
			(xy 88.991694 -388.636764) (xy 89.057877 -388.751286) (xy 89.613813 -388.751286) (xy 89.621145 -388.703734)
			(xy 89.63584 -388.657918) (xy 89.657533 -388.614972) (xy 89.68569 -388.575957) (xy 89.719613 -388.541837)
			(xy 89.758465 -388.513456) (xy 89.801285 -388.491515) (xy 89.847015 -388.476556) (xy 89.894524 -388.46895)
			(xy 89.942638 -388.468884) (xy 89.990168 -388.476359) (xy 90.035939 -388.491192) (xy 90.078819 -388.513016)
			(xy 90.117749 -388.54129) (xy 90.151766 -388.575317) (xy 90.180029 -388.614255) (xy 90.191336 -388.635494)
			(xy 90.191844 -388.636764) (xy 90.258027 -388.751286) (xy 90.813717 -388.751286) (xy 90.821049 -388.703734)
			(xy 90.835743 -388.65792) (xy 90.857436 -388.614974) (xy 90.885592 -388.57596) (xy 90.919515 -388.54184)
			(xy 90.958366 -388.513459) (xy 91.001186 -388.491518) (xy 91.046915 -388.47656) (xy 91.094423 -388.468953)
			(xy 91.142537 -388.468887) (xy 91.190066 -388.476363) (xy 91.235836 -388.491195) (xy 91.278716 -388.513018)
			(xy 91.317645 -388.541292) (xy 91.351662 -388.575318) (xy 91.379925 -388.614255) (xy 91.391232 -388.635494)
			(xy 91.39174 -388.636764) (xy 91.457921 -388.751284) (xy 92.013962 -388.751284) (xy 92.021293 -388.703741)
			(xy 92.035985 -388.657935) (xy 92.057674 -388.614997) (xy 92.085825 -388.575989) (xy 92.119742 -388.541876)
			(xy 92.158586 -388.5135) (xy 92.201397 -388.491562) (xy 92.247118 -388.476605) (xy 92.294617 -388.468999)
			(xy 92.342722 -388.468931) (xy 92.390243 -388.476403) (xy 92.436005 -388.491231) (xy 92.478878 -388.513048)
			(xy 92.517802 -388.541314) (xy 92.551815 -388.575332) (xy 92.580076 -388.61426) (xy 92.591382 -388.635494)
			(xy 92.59189 -388.636764) (xy 92.658071 -388.751284) (xy 93.213865 -388.751284) (xy 93.221197 -388.703741)
			(xy 93.235888 -388.657936) (xy 93.257577 -388.614999) (xy 93.285728 -388.575992) (xy 93.319644 -388.541879)
			(xy 93.358487 -388.513503) (xy 93.401298 -388.491565) (xy 93.447018 -388.476609) (xy 93.494517 -388.469002)
			(xy 93.542621 -388.468934) (xy 93.590141 -388.476406) (xy 93.635903 -388.491234) (xy 93.678775 -388.51305)
			(xy 93.717699 -388.541316) (xy 93.751711 -388.575333) (xy 93.779972 -388.61426) (xy 93.791278 -388.635494)
			(xy 93.791786 -388.636764) (xy 93.884953 -388.797979) (xy 94.413811 -388.797979) (xy 94.414059 -388.747044)
			(xy 94.422753 -388.696855) (xy 94.43965 -388.648804) (xy 94.464283 -388.604221) (xy 94.49597 -388.564341)
			(xy 94.533833 -388.530269) (xy 94.576822 -388.502949) (xy 94.623747 -388.483138) (xy 94.673308 -388.471385)
			(xy 94.724132 -388.468014) (xy 94.774811 -388.47312) (xy 94.823942 -388.486562) (xy 94.870162 -388.507966)
			(xy 94.912192 -388.536739) (xy 94.948868 -388.572086) (xy 94.979173 -388.613025) (xy 94.991174 -388.635494)
			(xy 94.991682 -388.636764) (xy 95.057865 -388.751286) (xy 95.613824 -388.751286) (xy 95.621156 -388.703735)
			(xy 95.63585 -388.657922) (xy 95.657542 -388.614978) (xy 95.685697 -388.575964) (xy 95.719619 -388.541846)
			(xy 95.75847 -388.513466) (xy 95.801288 -388.491525) (xy 95.847015 -388.476567) (xy 95.894522 -388.468961)
			(xy 95.942634 -388.468894) (xy 95.990162 -388.476369) (xy 96.035931 -388.491201) (xy 96.07881 -388.513023)
			(xy 96.117738 -388.541296) (xy 96.151754 -388.57532) (xy 96.180017 -388.614256) (xy 96.191324 -388.635494)
			(xy 96.191832 -388.636764) (xy 96.258014 -388.751285) (xy 96.813728 -388.751285) (xy 96.821059 -388.703736)
			(xy 96.835753 -388.657923) (xy 96.857445 -388.61498) (xy 96.8856 -388.575967) (xy 96.919522 -388.541849)
			(xy 96.958371 -388.513469) (xy 97.001189 -388.491529) (xy 97.046916 -388.476571) (xy 97.094422 -388.468964)
			(xy 97.142533 -388.468898) (xy 97.19006 -388.476372) (xy 97.235829 -388.491204) (xy 97.278707 -388.513025)
			(xy 97.317635 -388.541297) (xy 97.351651 -388.575321) (xy 97.379913 -388.614256) (xy 97.39122 -388.635494)
			(xy 97.391728 -388.636764) (xy 97.484894 -388.797978) (xy 98.014014 -388.797978) (xy 98.014263 -388.747044)
			(xy 98.022956 -388.696856) (xy 98.039853 -388.648805) (xy 98.064486 -388.604223) (xy 98.096173 -388.564344)
			(xy 98.134034 -388.530272) (xy 98.177023 -388.502953) (xy 98.223948 -388.483142) (xy 98.273508 -388.471388)
			(xy 98.324331 -388.468018) (xy 98.37501 -388.473124) (xy 98.424139 -388.486565) (xy 98.470359 -388.507968)
			(xy 98.512389 -388.536741) (xy 98.549064 -388.572087) (xy 98.579369 -388.613026) (xy 98.59137 -388.635494)
			(xy 98.591878 -388.636764) (xy 98.67173 -388.77494) (xy 114.586004 -388.77494) (xy 114.586004 -388.774432)
			(xy 114.586468 -388.750439) (xy 114.59397 -388.703044) (xy 114.608795 -388.657405) (xy 114.630577 -388.614648)
			(xy 114.658781 -388.575826) (xy 114.692711 -388.541894) (xy 114.731531 -388.513688) (xy 114.774287 -388.491903)
			(xy 114.819924 -388.477075) (xy 114.867319 -388.469569) (xy 114.891312 -388.469124) (xy 114.915247 -388.469594)
			(xy 114.962533 -388.477047) (xy 115.008077 -388.491786) (xy 115.050765 -388.513448) (xy 115.089551 -388.541504)
			(xy 115.123486 -388.575267) (xy 115.151739 -388.61391) (xy 115.163092 -388.634986) (xy 115.1636 -388.636002)
			(xy 115.243906 -388.77494) (xy 115.7859 -388.77494) (xy 115.7859 -388.774432) (xy 115.786368 -388.750439)
			(xy 115.79387 -388.703044) (xy 115.808695 -388.657406) (xy 115.830477 -388.61465) (xy 115.85868 -388.575827)
			(xy 115.892609 -388.541895) (xy 115.931429 -388.513689) (xy 115.974184 -388.491904) (xy 116.019821 -388.477076)
			(xy 116.067215 -388.46957) (xy 116.091208 -388.469124) (xy 116.115143 -388.469597) (xy 116.162429 -388.47705)
			(xy 116.207973 -388.491788) (xy 116.250661 -388.51345) (xy 116.289447 -388.541505) (xy 116.323382 -388.575268)
			(xy 116.351635 -388.61391) (xy 116.362988 -388.634986) (xy 116.363496 -388.636002) (xy 116.443802 -388.77494)
			(xy 116.985796 -388.77494) (xy 116.985796 -388.774432) (xy 116.986268 -388.75044) (xy 116.99377 -388.703045)
			(xy 117.008594 -388.657407) (xy 117.030376 -388.614651) (xy 117.058578 -388.575829) (xy 117.092507 -388.541897)
			(xy 117.131327 -388.513691) (xy 117.174081 -388.491905) (xy 117.219717 -388.477076) (xy 117.267112 -388.46957)
			(xy 117.291104 -388.469124) (xy 117.315039 -388.4696) (xy 117.362324 -388.477053) (xy 117.407868 -388.49179)
			(xy 117.450556 -388.513451) (xy 117.489342 -388.541506) (xy 117.523277 -388.575268) (xy 117.551531 -388.61391)
			(xy 117.562884 -388.634986) (xy 117.563392 -388.636002) (xy 117.643698 -388.77494) (xy 118.185692 -388.77494)
			(xy 118.185692 -388.774432) (xy 118.186191 -388.750454) (xy 118.193684 -388.703088) (xy 118.208492 -388.657476)
			(xy 118.230249 -388.614741) (xy 118.258422 -388.575933) (xy 118.292315 -388.542008) (xy 118.331097 -388.513799)
			(xy 118.373812 -388.492002) (xy 118.41941 -388.477151) (xy 118.466769 -388.469614) (xy 118.490746 -388.469124)
			(xy 118.491254 -388.469124) (xy 118.51519 -388.46956) (xy 118.562478 -388.47702) (xy 118.608023 -388.491764)
			(xy 118.650711 -388.513432) (xy 118.689496 -388.541493) (xy 118.72343 -388.575261) (xy 118.751681 -388.613908)
			(xy 118.763034 -388.634986) (xy 118.763542 -388.636002) (xy 118.843848 -388.77494) (xy 119.385588 -388.77494)
			(xy 119.385588 -388.774432) (xy 119.386091 -388.750455) (xy 119.393584 -388.703089) (xy 119.408392 -388.657477)
			(xy 119.430149 -388.614742) (xy 119.45832 -388.575934) (xy 119.492213 -388.542009) (xy 119.530994 -388.513801)
			(xy 119.573709 -388.492003) (xy 119.619306 -388.477152) (xy 119.666665 -388.469614) (xy 119.690642 -388.469124)
			(xy 119.69115 -388.469124) (xy 119.715086 -388.469563) (xy 119.762373 -388.477022) (xy 119.807918 -388.491766)
			(xy 119.850606 -388.513434) (xy 119.889392 -388.541494) (xy 119.923326 -388.575262) (xy 119.951577 -388.613908)
			(xy 119.96293 -388.634986) (xy 119.963438 -388.636002) (xy 120.043744 -388.77494) (xy 120.585992 -388.77494)
			(xy 120.585992 -388.774432) (xy 120.586468 -388.75044) (xy 120.59397 -388.703045) (xy 120.608794 -388.657408)
			(xy 120.630575 -388.614652) (xy 120.658777 -388.57583) (xy 120.692706 -388.541898) (xy 120.731525 -388.513692)
			(xy 120.774279 -388.491906) (xy 120.819914 -388.477077) (xy 120.867308 -388.46957) (xy 120.8913 -388.469124)
			(xy 120.915235 -388.469603) (xy 120.96252 -388.477055) (xy 121.008064 -388.491792) (xy 121.050752 -388.513453)
			(xy 121.089538 -388.541507) (xy 121.123473 -388.575269) (xy 121.151726 -388.613911) (xy 121.16308 -388.634986)
			(xy 121.163588 -388.636002) (xy 121.243894 -388.77494) (xy 121.785888 -388.77494) (xy 121.785888 -388.774432)
			(xy 121.786368 -388.75044) (xy 121.79387 -388.703046) (xy 121.808693 -388.657409) (xy 121.830474 -388.614653)
			(xy 121.858676 -388.575831) (xy 121.892604 -388.5419) (xy 121.931423 -388.513693) (xy 121.974176 -388.491907)
			(xy 122.019811 -388.477078) (xy 122.067204 -388.469571) (xy 122.091196 -388.469124) (xy 122.115133 -388.469526)
			(xy 122.162423 -388.476992) (xy 122.207968 -388.491742) (xy 122.250656 -388.513416) (xy 122.289441 -388.541483)
			(xy 122.323374 -388.575255) (xy 122.351624 -388.613906) (xy 122.362976 -388.634986) (xy 122.363484 -388.636002)
			(xy 122.44379 -388.77494) (xy 122.985784 -388.77494) (xy 122.985784 -388.774432) (xy 122.986268 -388.75044)
			(xy 122.993769 -388.703046) (xy 123.008593 -388.65741) (xy 123.030374 -388.614654) (xy 123.058575 -388.575833)
			(xy 123.092502 -388.541901) (xy 123.13132 -388.513695) (xy 123.174073 -388.491908) (xy 123.219708 -388.477079)
			(xy 123.2671 -388.469571) (xy 123.291092 -388.469124) (xy 123.315029 -388.469529) (xy 123.362318 -388.476995)
			(xy 123.407864 -388.491745) (xy 123.450552 -388.513418) (xy 123.489337 -388.541484) (xy 123.52327 -388.575256)
			(xy 123.55152 -388.613906) (xy 123.562872 -388.634986) (xy 123.56338 -388.636002) (xy 123.643686 -388.77494)
			(xy 124.18568 -388.77494) (xy 124.18568 -388.774432) (xy 124.186191 -388.750455) (xy 124.193684 -388.70309)
			(xy 124.208491 -388.657479) (xy 124.230247 -388.614744) (xy 124.258418 -388.575937) (xy 124.29231 -388.542012)
			(xy 124.33109 -388.513803) (xy 124.373803 -388.492005) (xy 124.4194 -388.477154) (xy 124.466757 -388.469614)
			(xy 124.490734 -388.469124) (xy 124.491242 -388.469124) (xy 124.515178 -388.469569) (xy 124.562465 -388.477028)
			(xy 124.60801 -388.49177) (xy 124.650697 -388.513437) (xy 124.689483 -388.541496) (xy 124.723417 -388.575263)
			(xy 124.751669 -388.613909) (xy 124.763022 -388.634986) (xy 124.76353 -388.636002) (xy 124.843836 -388.77494)
			(xy 125.385576 -388.77494) (xy 125.385576 -388.774432) (xy 125.386091 -388.750455) (xy 125.393584 -388.70309)
			(xy 125.408391 -388.65748) (xy 125.430147 -388.614746) (xy 125.458317 -388.575938) (xy 125.492208 -388.542013)
			(xy 125.530988 -388.513805) (xy 125.573701 -388.492006) (xy 125.619296 -388.477155) (xy 125.666654 -388.469615)
			(xy 125.69063 -388.469124) (xy 125.691138 -388.469124) (xy 125.715074 -388.469573) (xy 125.762361 -388.47703)
			(xy 125.807905 -388.491772) (xy 125.850593 -388.513438) (xy 125.889379 -388.541498) (xy 125.923313 -388.575263)
			(xy 125.951565 -388.613909) (xy 125.962918 -388.634986) (xy 125.963426 -388.636002) (xy 126.043732 -388.77494)
			(xy 126.58598 -388.77494) (xy 126.58598 -388.774432) (xy 126.586468 -388.75044) (xy 126.593969 -388.703047)
			(xy 126.608793 -388.657411) (xy 126.630573 -388.614656) (xy 126.658774 -388.575834) (xy 126.692701 -388.541902)
			(xy 126.731518 -388.513696) (xy 126.77427 -388.49191) (xy 126.819904 -388.47708) (xy 126.867296 -388.469571)
			(xy 126.891288 -388.469124) (xy 126.915225 -388.469532) (xy 126.962514 -388.476997) (xy 127.00806 -388.491747)
			(xy 127.050747 -388.513419) (xy 127.089533 -388.541485) (xy 127.123466 -388.575256) (xy 127.151716 -388.613907)
			(xy 127.163068 -388.634986) (xy 127.163576 -388.636002) (xy 127.243882 -388.77494) (xy 127.785876 -388.77494)
			(xy 127.785876 -388.774432) (xy 127.786368 -388.750441) (xy 127.793869 -388.703048) (xy 127.808692 -388.657412)
			(xy 127.830472 -388.614657) (xy 127.858673 -388.575836) (xy 127.892599 -388.541904) (xy 127.931416 -388.513697)
			(xy 127.974167 -388.491911) (xy 128.019801 -388.47708) (xy 128.067193 -388.469571) (xy 128.091184 -388.469124)
			(xy 128.115121 -388.469535) (xy 128.16241 -388.477) (xy 128.207955 -388.491749) (xy 128.250643 -388.513421)
			(xy 128.289428 -388.541486) (xy 128.323361 -388.575257) (xy 128.351612 -388.613907) (xy 128.362964 -388.634986)
			(xy 128.363472 -388.636002) (xy 128.443778 -388.77494) (xy 128.985772 -388.77494) (xy 128.985772 -388.774432)
			(xy 128.986268 -388.750441) (xy 128.993769 -388.703048) (xy 129.008592 -388.657413) (xy 129.030372 -388.614658)
			(xy 129.058571 -388.575837) (xy 129.092497 -388.541905) (xy 129.131314 -388.513699) (xy 129.174065 -388.491912)
			(xy 129.219698 -388.477081) (xy 129.267089 -388.469572) (xy 129.29108 -388.469124) (xy 129.315017 -388.469539)
			(xy 129.362305 -388.477002) (xy 129.407851 -388.491751) (xy 129.450539 -388.513422) (xy 129.489324 -388.541487)
			(xy 129.523257 -388.575257) (xy 129.551508 -388.613907) (xy 129.56286 -388.634986) (xy 129.563368 -388.636002)
			(xy 129.643674 -388.77494) (xy 130.185668 -388.77494) (xy 130.185668 -388.774432) (xy 130.186191 -388.750456)
			(xy 130.193684 -388.703092) (xy 130.20849 -388.657482) (xy 130.230245 -388.614748) (xy 130.258415 -388.575941)
			(xy 130.292305 -388.542016) (xy 130.331083 -388.513807) (xy 130.373795 -388.492009) (xy 130.41939 -388.477156)
			(xy 130.466746 -388.469615) (xy 130.490722 -388.469124) (xy 130.49123 -388.469124) (xy 130.515165 -388.469579)
			(xy 130.562452 -388.477035) (xy 130.607997 -388.491776) (xy 130.650684 -388.513441) (xy 130.68947 -388.5415)
			(xy 130.723405 -388.575264) (xy 130.751657 -388.613909) (xy 130.76301 -388.634986) (xy 130.763518 -388.636002)
			(xy 130.843824 -388.77494) (xy 131.385564 -388.77494) (xy 131.385564 -388.774432) (xy 131.386091 -388.750456)
			(xy 131.393583 -388.703092) (xy 131.408389 -388.657483) (xy 131.430144 -388.614749) (xy 131.458313 -388.575943)
			(xy 131.492203 -388.542018) (xy 131.530981 -388.513809) (xy 131.573692 -388.49201) (xy 131.619286 -388.477157)
			(xy 131.666642 -388.469616) (xy 131.690618 -388.469124) (xy 131.691126 -388.469124) (xy 131.715061 -388.469582)
			(xy 131.762348 -388.477038) (xy 131.807892 -388.491778) (xy 131.85058 -388.513443) (xy 131.889366 -388.541501)
			(xy 131.923301 -388.575265) (xy 131.951553 -388.613909) (xy 131.962906 -388.634986) (xy 131.963414 -388.636002)
			(xy 132.04372 -388.77494) (xy 132.585968 -388.77494) (xy 132.585968 -388.774432) (xy 132.586468 -388.750441)
			(xy 132.593969 -388.703049) (xy 132.608792 -388.657414) (xy 132.630571 -388.614659) (xy 132.65877 -388.575838)
			(xy 132.692696 -388.541907) (xy 132.731511 -388.5137) (xy 132.774262 -388.491913) (xy 132.819894 -388.477082)
			(xy 132.867285 -388.469572) (xy 132.891276 -388.469124) (xy 132.915213 -388.469542) (xy 132.962501 -388.477005)
			(xy 133.008047 -388.491753) (xy 133.050734 -388.513424) (xy 133.08952 -388.541488) (xy 133.123453 -388.575258)
			(xy 133.151704 -388.613907) (xy 133.163056 -388.634986) (xy 133.163564 -388.636002) (xy 133.24387 -388.77494)
			(xy 147.113752 -388.77494) (xy 147.113752 -388.774432) (xy 147.114292 -388.750444) (xy 147.121792 -388.703057)
			(xy 147.136613 -388.657427) (xy 147.158389 -388.614677) (xy 147.186584 -388.57586) (xy 147.220505 -388.541931)
			(xy 147.259315 -388.513726) (xy 147.30206 -388.49194) (xy 147.347687 -388.477109) (xy 147.395072 -388.469598)
			(xy 147.41906 -388.469124) (xy 147.442996 -388.469555) (xy 147.490284 -388.477016) (xy 147.535829 -388.491761)
			(xy 147.578517 -388.51343) (xy 147.617303 -388.541492) (xy 147.651236 -388.57526) (xy 147.679488 -388.613908)
			(xy 147.69084 -388.634986) (xy 147.691348 -388.636002) (xy 147.771654 -388.77494) (xy 148.313648 -388.77494)
			(xy 148.313648 -388.774432) (xy 148.314192 -388.750444) (xy 148.321692 -388.703057) (xy 148.336512 -388.657428)
			(xy 148.358288 -388.614678) (xy 148.386483 -388.575861) (xy 148.420403 -388.541933) (xy 148.459213 -388.513728)
			(xy 148.501957 -388.491941) (xy 148.547583 -388.47711) (xy 148.594968 -388.469598) (xy 148.618956 -388.469124)
			(xy 148.642892 -388.469558) (xy 148.69018 -388.477018) (xy 148.735725 -388.491763) (xy 148.778413 -388.513431)
			(xy 148.817198 -388.541493) (xy 148.851132 -388.575261) (xy 148.879383 -388.613908) (xy 148.890736 -388.634986)
			(xy 148.891244 -388.636002) (xy 148.97155 -388.77494) (xy 149.513544 -388.77494) (xy 149.513544 -388.774432)
			(xy 149.514092 -388.750444) (xy 149.521592 -388.703058) (xy 149.536412 -388.657429) (xy 149.558187 -388.614679)
			(xy 149.586382 -388.575862) (xy 149.620301 -388.541934) (xy 149.659111 -388.513729) (xy 149.701855 -388.491943)
			(xy 149.74748 -388.477111) (xy 149.794864 -388.469598) (xy 149.818852 -388.469124) (xy 149.842788 -388.469561)
			(xy 149.890076 -388.477021) (xy 149.935621 -388.491765) (xy 149.978308 -388.513433) (xy 150.017094 -388.541494)
			(xy 150.051028 -388.575261) (xy 150.079279 -388.613908) (xy 150.090632 -388.634986) (xy 150.09114 -388.636002)
			(xy 150.171446 -388.77494) (xy 150.71344 -388.77494) (xy 150.71344 -388.774432) (xy 150.713891 -388.750452)
			(xy 150.721386 -388.703081) (xy 150.736197 -388.657465) (xy 150.757958 -388.614726) (xy 150.786136 -388.575917)
			(xy 150.820035 -388.54199) (xy 150.858823 -388.513783) (xy 150.901545 -388.491988) (xy 150.947149 -388.477142)
			(xy 150.994514 -388.46961) (xy 151.018494 -388.469124) (xy 151.019002 -388.469124) (xy 151.042937 -388.469602)
			(xy 151.090222 -388.477054) (xy 151.135766 -388.491791) (xy 151.178454 -388.513452) (xy 151.21724 -388.541507)
			(xy 151.251175 -388.575268) (xy 151.279429 -388.61391) (xy 151.290782 -388.634986) (xy 151.29129 -388.636002)
			(xy 151.371596 -388.77494) (xy 151.913336 -388.77494) (xy 151.913336 -388.774432) (xy 151.913791 -388.750452)
			(xy 151.921286 -388.703082) (xy 151.936096 -388.657466) (xy 151.957858 -388.614728) (xy 151.986034 -388.575918)
			(xy 152.019934 -388.541992) (xy 152.058721 -388.513784) (xy 152.101442 -388.491989) (xy 152.147046 -388.477143)
			(xy 152.19441 -388.46961) (xy 152.21839 -388.469124) (xy 152.218898 -388.469124) (xy 152.242835 -388.469524)
			(xy 152.290125 -388.476991) (xy 152.335671 -388.491741) (xy 152.378358 -388.513415) (xy 152.417143 -388.541482)
			(xy 152.451076 -388.575255) (xy 152.479326 -388.613906) (xy 152.490678 -388.634986) (xy 152.491186 -388.636002)
			(xy 152.571492 -388.77494) (xy 153.11374 -388.77494) (xy 153.11374 -388.774432) (xy 153.114168 -388.750437)
			(xy 153.121671 -388.703038) (xy 153.136498 -388.657397) (xy 153.158284 -388.614638) (xy 153.186491 -388.575814)
			(xy 153.220426 -388.541881) (xy 153.259251 -388.513676) (xy 153.302012 -388.491892) (xy 153.347654 -388.477068)
			(xy 153.395053 -388.469567) (xy 153.419048 -388.469124) (xy 153.442984 -388.469565) (xy 153.490271 -388.477024)
			(xy 153.535816 -388.491767) (xy 153.578504 -388.513434) (xy 153.61729 -388.541495) (xy 153.651224 -388.575262)
			(xy 153.679475 -388.613908) (xy 153.690828 -388.634986) (xy 153.691336 -388.636002) (xy 153.771642 -388.77494)
			(xy 154.313636 -388.77494) (xy 154.313636 -388.774432) (xy 154.314068 -388.750438) (xy 154.321571 -388.703039)
			(xy 154.336398 -388.657398) (xy 154.358183 -388.614639) (xy 154.38639 -388.575815) (xy 154.420324 -388.541882)
			(xy 154.459149 -388.513677) (xy 154.501909 -388.491893) (xy 154.547551 -388.477068) (xy 154.59495 -388.469567)
			(xy 154.618944 -388.469124) (xy 154.64288 -388.469568) (xy 154.690167 -388.477026) (xy 154.735712 -388.491769)
			(xy 154.7784 -388.513436) (xy 154.817185 -388.541496) (xy 154.851119 -388.575262) (xy 154.879371 -388.613909)
			(xy 154.890724 -388.634986) (xy 154.891232 -388.636002) (xy 154.971538 -388.77494) (xy 155.513532 -388.77494)
			(xy 155.513532 -388.774432) (xy 155.513968 -388.750438) (xy 155.521471 -388.703039) (xy 155.536298 -388.657399)
			(xy 155.558083 -388.61464) (xy 155.586289 -388.575816) (xy 155.620222 -388.541884) (xy 155.659047 -388.513678)
			(xy 155.701806 -388.491895) (xy 155.747447 -388.477069) (xy 155.794846 -388.469567) (xy 155.81884 -388.469124)
			(xy 155.842776 -388.469571) (xy 155.890063 -388.477029) (xy 155.935608 -388.491771) (xy 155.978295 -388.513437)
			(xy 156.017081 -388.541497) (xy 156.051015 -388.575263) (xy 156.079267 -388.613909) (xy 156.09062 -388.634986)
			(xy 156.091128 -388.636002) (xy 156.171434 -388.77494) (xy 156.713428 -388.77494) (xy 156.713428 -388.774432)
			(xy 156.713891 -388.750453) (xy 156.721386 -388.703083) (xy 156.736196 -388.657468) (xy 156.757956 -388.61473)
			(xy 156.786132 -388.575921) (xy 156.82003 -388.541995) (xy 156.858817 -388.513787) (xy 156.901537 -388.491991)
			(xy 156.947139 -388.477144) (xy 156.994503 -388.469611) (xy 157.018482 -388.469124) (xy 157.01899 -388.469124)
			(xy 157.042927 -388.46953) (xy 157.090216 -388.476996) (xy 157.135762 -388.491746) (xy 157.17845 -388.513419)
			(xy 157.217235 -388.541484) (xy 157.251168 -388.575256) (xy 157.279418 -388.613907) (xy 157.29077 -388.634986)
			(xy 157.291278 -388.636002) (xy 157.371584 -388.77494) (xy 157.913324 -388.77494) (xy 157.913324 -388.774432)
			(xy 157.913791 -388.750453) (xy 157.921286 -388.703083) (xy 157.936095 -388.657469) (xy 157.957855 -388.614731)
			(xy 157.986031 -388.575922) (xy 158.019929 -388.541996) (xy 158.058714 -388.513788) (xy 158.101434 -388.491993)
			(xy 158.147036 -388.477145) (xy 158.194399 -388.469611) (xy 158.218378 -388.469124) (xy 158.218886 -388.469124)
			(xy 158.242823 -388.469534) (xy 158.290112 -388.476998) (xy 158.335657 -388.491748) (xy 158.378345 -388.51342)
			(xy 158.41713 -388.541485) (xy 158.451064 -388.575256) (xy 158.479314 -388.613907) (xy 158.490666 -388.634986)
			(xy 158.491174 -388.636002) (xy 158.57148 -388.77494) (xy 159.113728 -388.77494) (xy 159.113728 -388.774432)
			(xy 159.114168 -388.750438) (xy 159.121671 -388.70304) (xy 159.136497 -388.6574) (xy 159.158282 -388.614641)
			(xy 159.186488 -388.575818) (xy 159.220421 -388.541885) (xy 159.259245 -388.51368) (xy 159.302004 -388.491896)
			(xy 159.347644 -388.47707) (xy 159.395042 -388.469568) (xy 159.419036 -388.469124) (xy 159.442972 -388.469574)
			(xy 159.490258 -388.477031) (xy 159.535803 -388.491773) (xy 159.578491 -388.513439) (xy 159.617277 -388.541498)
			(xy 159.651211 -388.575264) (xy 159.679463 -388.613909) (xy 159.690816 -388.634986) (xy 159.691324 -388.636002)
			(xy 159.77163 -388.77494) (xy 160.313624 -388.77494) (xy 160.313624 -388.774432) (xy 160.314068 -388.750438)
			(xy 160.321571 -388.703041) (xy 160.336397 -388.657401) (xy 160.358181 -388.614643) (xy 160.386387 -388.575819)
			(xy 160.420319 -388.541887) (xy 160.459143 -388.513681) (xy 160.501901 -388.491897) (xy 160.547541 -388.477071)
			(xy 160.594938 -388.469568) (xy 160.618932 -388.469124) (xy 160.642868 -388.469578) (xy 160.690154 -388.477034)
			(xy 160.735699 -388.491775) (xy 160.778387 -388.51344) (xy 160.817172 -388.541499) (xy 160.851107 -388.575264)
			(xy 160.879359 -388.613909) (xy 160.890712 -388.634986) (xy 160.89122 -388.636002) (xy 160.971526 -388.77494)
			(xy 161.51352 -388.77494) (xy 161.51352 -388.774432) (xy 161.513968 -388.750438) (xy 161.521471 -388.703041)
			(xy 161.536297 -388.657402) (xy 161.55808 -388.614644) (xy 161.586286 -388.57582) (xy 161.620217 -388.541888)
			(xy 161.65904 -388.513682) (xy 161.701798 -388.491898) (xy 161.747437 -388.477072) (xy 161.794834 -388.469568)
			(xy 161.818828 -388.469124) (xy 161.842763 -388.469581) (xy 161.89005 -388.477037) (xy 161.935595 -388.491777)
			(xy 161.978282 -388.513442) (xy 162.017068 -388.5415) (xy 162.051003 -388.575265) (xy 162.079255 -388.613909)
			(xy 162.090608 -388.634986) (xy 162.091116 -388.636002) (xy 162.171422 -388.77494) (xy 162.713416 -388.77494)
			(xy 162.713416 -388.774432) (xy 162.713891 -388.750453) (xy 162.721385 -388.703085) (xy 162.736194 -388.657471)
			(xy 162.757954 -388.614734) (xy 162.786129 -388.575925) (xy 162.820025 -388.541999) (xy 162.85881 -388.513791)
			(xy 162.901528 -388.491995) (xy 162.947129 -388.477147) (xy 162.994492 -388.469612) (xy 163.01847 -388.469124)
			(xy 163.018978 -388.469124) (xy 163.042915 -388.46954) (xy 163.090203 -388.477004) (xy 163.135749 -388.491752)
			(xy 163.178437 -388.513423) (xy 163.217222 -388.541487) (xy 163.251155 -388.575258) (xy 163.279406 -388.613907)
			(xy 163.290758 -388.634986) (xy 163.291266 -388.636002) (xy 163.371572 -388.77494) (xy 163.913312 -388.77494)
			(xy 163.913312 -388.774432) (xy 163.913791 -388.750453) (xy 163.921285 -388.703085) (xy 163.936094 -388.657472)
			(xy 163.957853 -388.614735) (xy 163.986027 -388.575926) (xy 164.019924 -388.542) (xy 164.058708 -388.513792)
			(xy 164.101425 -388.491996) (xy 164.147026 -388.477147) (xy 164.194388 -388.469612) (xy 164.218366 -388.469124)
			(xy 164.218874 -388.469124) (xy 164.242811 -388.469543) (xy 164.290099 -388.477006) (xy 164.335644 -388.491754)
			(xy 164.378332 -388.513425) (xy 164.417118 -388.541488) (xy 164.451051 -388.575258) (xy 164.479302 -388.613907)
			(xy 164.490654 -388.634986) (xy 164.491162 -388.636002) (xy 164.571468 -388.77494) (xy 165.113716 -388.77494)
			(xy 165.113716 -388.774432) (xy 165.114168 -388.750439) (xy 165.121671 -388.703042) (xy 165.136496 -388.657403)
			(xy 165.15828 -388.614645) (xy 165.186484 -388.575822) (xy 165.220416 -388.54189) (xy 165.259238 -388.513684)
			(xy 165.301995 -388.491899) (xy 165.347634 -388.477072) (xy 165.395031 -388.469568) (xy 165.419024 -388.469124)
			(xy 165.442959 -388.469584) (xy 165.490246 -388.477039) (xy 165.53579 -388.491779) (xy 165.578478 -388.513444)
			(xy 165.617264 -388.541501) (xy 165.651198 -388.575265) (xy 165.679451 -388.61391) (xy 165.690804 -388.634986)
			(xy 165.691312 -388.636002) (xy 165.744132 -388.727385) (xy 193.900548 -388.727385) (xy 193.900548 -388.642663)
			(xy 193.908601 -388.558326) (xy 193.924635 -388.475136) (xy 193.948503 -388.393846) (xy 193.979991 -388.315194)
			(xy 194.018813 -388.239891) (xy 194.064616 -388.168619) (xy 194.116987 -388.102023) (xy 194.175452 -388.040708)
			(xy 194.23948 -387.985227) (xy 194.308492 -387.936084) (xy 194.381862 -387.893724) (xy 194.458927 -387.858529)
			(xy 194.538989 -387.83082) (xy 194.621322 -387.810846) (xy 194.705181 -387.798789) (xy 194.789806 -387.794758)
			(xy 194.874431 -387.798789) (xy 194.95829 -387.810846) (xy 195.040623 -387.83082) (xy 195.120685 -387.858529)
			(xy 195.19775 -387.893724) (xy 195.27112 -387.936084) (xy 195.340132 -387.985227) (xy 195.40416 -388.040708)
			(xy 195.462625 -388.102023) (xy 195.514996 -388.168619) (xy 195.560799 -388.239891) (xy 195.599621 -388.315194)
			(xy 195.631109 -388.393846) (xy 195.654977 -388.475136) (xy 195.671011 -388.558326) (xy 195.679064 -388.642663)
			(xy 195.679568 -388.685024) (xy 195.679064 -388.727385) (xy 195.671011 -388.811722) (xy 195.654977 -388.894912)
			(xy 195.631109 -388.976202) (xy 195.599621 -389.054854) (xy 195.560799 -389.130157) (xy 195.514996 -389.201429)
			(xy 195.462625 -389.268025) (xy 195.40416 -389.32934) (xy 195.340132 -389.384821) (xy 195.27112 -389.433964)
			(xy 195.19775 -389.476324) (xy 195.120685 -389.511519) (xy 195.040623 -389.539228) (xy 194.95829 -389.559202)
			(xy 194.874431 -389.571259) (xy 194.789806 -389.575291) (xy 194.705181 -389.571259) (xy 194.621322 -389.559202)
			(xy 194.538989 -389.539228) (xy 194.458927 -389.511519) (xy 194.381862 -389.476324) (xy 194.308492 -389.433964)
			(xy 194.23948 -389.384821) (xy 194.175452 -389.32934) (xy 194.116987 -389.268025) (xy 194.064616 -389.201429)
			(xy 194.018813 -389.130157) (xy 193.979991 -389.054854) (xy 193.948503 -388.976202) (xy 193.924635 -388.894912)
			(xy 193.908601 -388.811722) (xy 193.900548 -388.727385) (xy 165.744132 -388.727385) (xy 166.083742 -389.314944)
			(xy 166.096549 -389.338286) (xy 166.114776 -389.388304) (xy 166.124043 -389.440727) (xy 166.124636 -389.467344)
			(xy 166.124179 -389.491322) (xy 166.116675 -389.538688) (xy 166.101859 -389.584299) (xy 166.080095 -389.627033)
			(xy 166.051917 -389.665839) (xy 166.01802 -389.699762) (xy 165.979236 -389.72797) (xy 165.936519 -389.749768)
			(xy 165.89092 -389.76462) (xy 165.84356 -389.77216) (xy 165.819582 -389.772652) (xy 165.819074 -389.772652)
			(xy 165.795501 -389.772252) (xy 165.748914 -389.765008) (xy 165.703997 -389.750681) (xy 165.66182 -389.729613)
			(xy 165.623387 -389.702305) (xy 165.589614 -389.669408) (xy 165.561306 -389.631706) (xy 165.549834 -389.611108)
			(xy 165.549326 -389.610346) (xy 165.151562 -388.922006) (xy 165.139686 -388.899329) (xy 165.122835 -388.850996)
			(xy 165.114262 -388.800533) (xy 165.113716 -388.77494) (xy 164.571468 -388.77494) (xy 164.883592 -389.314944)
			(xy 164.896306 -389.338272) (xy 164.914407 -389.388215) (xy 164.923631 -389.44053) (xy 164.924232 -389.46709)
			(xy 164.924232 -389.467344) (xy 164.923778 -389.491335) (xy 164.916266 -389.538726) (xy 164.901434 -389.584359)
			(xy 164.879647 -389.62711) (xy 164.851442 -389.665927) (xy 164.817512 -389.699855) (xy 164.778693 -389.728058)
			(xy 164.73594 -389.749842) (xy 164.690307 -389.764671) (xy 164.642915 -389.77218) (xy 164.618924 -389.772652)
			(xy 164.595352 -389.772211) (xy 164.548767 -389.764975) (xy 164.503851 -389.750656) (xy 164.461674 -389.729594)
			(xy 164.423241 -389.702292) (xy 164.389467 -389.669401) (xy 164.361157 -389.631704) (xy 164.349684 -389.611108)
			(xy 164.349176 -389.610346) (xy 163.951412 -388.922006) (xy 163.939498 -388.899337) (xy 163.92256 -388.851012)
			(xy 163.9139 -388.800542) (xy 163.913312 -388.77494) (xy 163.371572 -388.77494) (xy 163.683696 -389.314944)
			(xy 163.69641 -389.338271) (xy 163.714511 -389.388215) (xy 163.723735 -389.44053) (xy 163.724336 -389.46709)
			(xy 163.724336 -389.467344) (xy 163.723878 -389.491335) (xy 163.716366 -389.538726) (xy 163.701535 -389.584358)
			(xy 163.679748 -389.627109) (xy 163.651543 -389.665926) (xy 163.617613 -389.699853) (xy 163.578795 -389.728056)
			(xy 163.536043 -389.749841) (xy 163.49041 -389.76467) (xy 163.443019 -389.772179) (xy 163.419028 -389.772652)
			(xy 163.395456 -389.772208) (xy 163.348872 -389.764972) (xy 163.303956 -389.750653) (xy 163.261778 -389.729592)
			(xy 163.223345 -389.702291) (xy 163.189571 -389.6694) (xy 163.161261 -389.631704) (xy 163.149788 -389.611108)
			(xy 163.14928 -389.610346) (xy 162.751516 -388.922006) (xy 162.739602 -388.899337) (xy 162.722664 -388.851012)
			(xy 162.714004 -388.800542) (xy 162.713416 -388.77494) (xy 162.171422 -388.77494) (xy 162.483546 -389.314944)
			(xy 162.496353 -389.338286) (xy 162.51458 -389.388304) (xy 162.523847 -389.440727) (xy 162.52444 -389.467344)
			(xy 162.523979 -389.491322) (xy 162.516475 -389.538688) (xy 162.501659 -389.584298) (xy 162.479895 -389.627032)
			(xy 162.451718 -389.665837) (xy 162.417822 -389.699761) (xy 162.379038 -389.727969) (xy 162.336322 -389.749767)
			(xy 162.290724 -389.764619) (xy 162.243364 -389.77216) (xy 162.219386 -389.772652) (xy 162.218878 -389.772652)
			(xy 162.195305 -389.772249) (xy 162.148718 -389.765005) (xy 162.103801 -389.750679) (xy 162.061624 -389.729611)
			(xy 162.023191 -389.702304) (xy 161.989418 -389.669408) (xy 161.96111 -389.631706) (xy 161.949638 -389.611108)
			(xy 161.94913 -389.610346) (xy 161.551366 -388.922006) (xy 161.539491 -388.899329) (xy 161.522639 -388.850996)
			(xy 161.514066 -388.800533) (xy 161.51352 -388.77494) (xy 160.971526 -388.77494) (xy 161.28365 -389.314944)
			(xy 161.296457 -389.338285) (xy 161.314684 -389.388304) (xy 161.323951 -389.440726) (xy 161.324544 -389.467344)
			(xy 161.324079 -389.491322) (xy 161.316576 -389.538687) (xy 161.30176 -389.584297) (xy 161.279996 -389.62703)
			(xy 161.25182 -389.665836) (xy 161.217923 -389.69976) (xy 161.17914 -389.727967) (xy 161.136425 -389.749765)
			(xy 161.090827 -389.764618) (xy 161.043468 -389.77216) (xy 161.01949 -389.772652) (xy 161.018982 -389.772652)
			(xy 160.995409 -389.772245) (xy 160.948822 -389.765003) (xy 160.903906 -389.750677) (xy 160.861728 -389.72961)
			(xy 160.823295 -389.702303) (xy 160.789523 -389.669407) (xy 160.761214 -389.631706) (xy 160.749742 -389.611108)
			(xy 160.749234 -389.610346) (xy 160.35147 -388.922006) (xy 160.339595 -388.899329) (xy 160.322743 -388.850996)
			(xy 160.31417 -388.800533) (xy 160.313624 -388.77494) (xy 159.77163 -388.77494) (xy 160.083754 -389.314944)
			(xy 160.096562 -389.338285) (xy 160.114788 -389.388304) (xy 160.124055 -389.440726) (xy 160.124648 -389.467344)
			(xy 160.124179 -389.491322) (xy 160.116676 -389.538687) (xy 160.10186 -389.584296) (xy 160.080097 -389.627029)
			(xy 160.051921 -389.665835) (xy 160.018025 -389.699758) (xy 159.979243 -389.727966) (xy 159.936528 -389.749764)
			(xy 159.89093 -389.764617) (xy 159.843571 -389.772159) (xy 159.819594 -389.772652) (xy 159.819086 -389.772652)
			(xy 159.795513 -389.772242) (xy 159.748927 -389.765) (xy 159.70401 -389.750675) (xy 159.661833 -389.729608)
			(xy 159.6234 -389.702302) (xy 159.589627 -389.669406) (xy 159.561319 -389.631705) (xy 159.549846 -389.611108)
			(xy 159.549338 -389.610346) (xy 159.151574 -388.922006) (xy 159.139699 -388.899329) (xy 159.122848 -388.850996)
			(xy 159.114274 -388.800533) (xy 159.113728 -388.77494) (xy 158.57148 -388.77494) (xy 158.883604 -389.314944)
			(xy 158.896319 -389.338271) (xy 158.91442 -389.388214) (xy 158.923643 -389.44053) (xy 158.924244 -389.46709)
			(xy 158.924244 -389.467344) (xy 158.923778 -389.491335) (xy 158.916267 -389.538724) (xy 158.901435 -389.584356)
			(xy 158.879649 -389.627106) (xy 158.851445 -389.665923) (xy 158.817517 -389.69985) (xy 158.778699 -389.728054)
			(xy 158.735949 -389.749838) (xy 158.690317 -389.764668) (xy 158.642927 -389.772179) (xy 158.618936 -389.772652)
			(xy 158.595364 -389.772202) (xy 158.54878 -389.764967) (xy 158.503864 -389.750649) (xy 158.461687 -389.729589)
			(xy 158.423253 -389.702289) (xy 158.389479 -389.669399) (xy 158.361169 -389.631703) (xy 158.349696 -389.611108)
			(xy 158.349188 -389.610346) (xy 157.951424 -388.922006) (xy 157.939511 -388.899337) (xy 157.922572 -388.851012)
			(xy 157.913912 -388.800542) (xy 157.913324 -388.77494) (xy 157.371584 -388.77494) (xy 157.683708 -389.314944)
			(xy 157.696423 -389.338271) (xy 157.714524 -389.388214) (xy 157.723747 -389.44053) (xy 157.724348 -389.46709)
			(xy 157.724348 -389.467344) (xy 157.723878 -389.491334) (xy 157.716367 -389.538724) (xy 157.701536 -389.584355)
			(xy 157.67975 -389.627105) (xy 157.651546 -389.665922) (xy 157.617618 -389.699849) (xy 157.578802 -389.728052)
			(xy 157.536051 -389.749837) (xy 157.49042 -389.764668) (xy 157.44303 -389.772178) (xy 157.41904 -389.772652)
			(xy 157.395469 -389.772199) (xy 157.348884 -389.764965) (xy 157.303969 -389.750647) (xy 157.261791 -389.729588)
			(xy 157.223358 -389.702288) (xy 157.189583 -389.669399) (xy 157.161273 -389.631703) (xy 157.1498 -389.611108)
			(xy 157.149292 -389.610346) (xy 156.751528 -388.922006) (xy 156.739615 -388.899337) (xy 156.722676 -388.851012)
			(xy 156.714016 -388.800542) (xy 156.713428 -388.77494) (xy 156.171434 -388.77494) (xy 156.483558 -389.314944)
			(xy 156.496366 -389.338285) (xy 156.514592 -389.388304) (xy 156.523859 -389.440726) (xy 156.524452 -389.467344)
			(xy 156.523979 -389.491322) (xy 156.516476 -389.538686) (xy 156.501661 -389.584295) (xy 156.479898 -389.627028)
			(xy 156.451722 -389.665833) (xy 156.417827 -389.699757) (xy 156.379045 -389.727965) (xy 156.33633 -389.749763)
			(xy 156.290733 -389.764616) (xy 156.243375 -389.772159) (xy 156.219398 -389.772652) (xy 156.21889 -389.772652)
			(xy 156.195317 -389.772239) (xy 156.148731 -389.764997) (xy 156.103814 -389.750673) (xy 156.061637 -389.729607)
			(xy 156.023204 -389.702301) (xy 155.989431 -389.669406) (xy 155.961123 -389.631705) (xy 155.94965 -389.611108)
			(xy 155.949142 -389.610346) (xy 155.551378 -388.922006) (xy 155.539503 -388.899328) (xy 155.522652 -388.850996)
			(xy 155.514078 -388.800533) (xy 155.513532 -388.77494) (xy 154.971538 -388.77494) (xy 155.283662 -389.314944)
			(xy 155.29647 -389.338285) (xy 155.314696 -389.388304) (xy 155.323963 -389.440726) (xy 155.324556 -389.467344)
			(xy 155.324079 -389.491321) (xy 155.316576 -389.538686) (xy 155.301761 -389.584295) (xy 155.279998 -389.627027)
			(xy 155.251823 -389.665832) (xy 155.217928 -389.699755) (xy 155.179147 -389.727963) (xy 155.136433 -389.749762)
			(xy 155.090837 -389.764616) (xy 155.043479 -389.772159) (xy 155.019502 -389.772652) (xy 155.018994 -389.772652)
			(xy 154.995421 -389.772236) (xy 154.948835 -389.764995) (xy 154.903919 -389.750671) (xy 154.861741 -389.729605)
			(xy 154.823308 -389.7023) (xy 154.789535 -389.669405) (xy 154.761227 -389.631705) (xy 154.749754 -389.611108)
			(xy 154.749246 -389.610346) (xy 154.351482 -388.922006) (xy 154.339608 -388.899328) (xy 154.322756 -388.850996)
			(xy 154.314182 -388.800533) (xy 154.313636 -388.77494) (xy 153.771642 -388.77494) (xy 154.083766 -389.314944)
			(xy 154.096575 -389.338285) (xy 154.1148 -389.388303) (xy 154.124067 -389.440726) (xy 154.12466 -389.467344)
			(xy 154.124279 -389.491326) (xy 154.116773 -389.5387) (xy 154.101952 -389.584317) (xy 154.080181 -389.627055)
			(xy 154.051995 -389.665865) (xy 154.018088 -389.69979) (xy 153.979294 -389.727996) (xy 153.936567 -389.74979)
			(xy 153.890957 -389.764635) (xy 153.843588 -389.772166) (xy 153.819606 -389.772652) (xy 153.819098 -389.772652)
			(xy 153.795525 -389.772232) (xy 153.74894 -389.764992) (xy 153.704023 -389.750669) (xy 153.661846 -389.729604)
			(xy 153.623413 -389.702299) (xy 153.589639 -389.669405) (xy 153.561331 -389.631705) (xy 153.549858 -389.611108)
			(xy 153.54935 -389.610346) (xy 153.151586 -388.922006) (xy 153.139712 -388.899328) (xy 153.12286 -388.850996)
			(xy 153.114286 -388.800533) (xy 153.11374 -388.77494) (xy 152.571492 -388.77494) (xy 152.883616 -389.314944)
			(xy 152.896332 -389.338271) (xy 152.914432 -389.388214) (xy 152.923655 -389.44053) (xy 152.924256 -389.46709)
			(xy 152.924256 -389.467344) (xy 152.923778 -389.491334) (xy 152.916267 -389.538723) (xy 152.901436 -389.584353)
			(xy 152.879652 -389.627103) (xy 152.851449 -389.665919) (xy 152.817522 -389.699846) (xy 152.778706 -389.72805)
			(xy 152.735957 -389.749835) (xy 152.690327 -389.764666) (xy 152.642938 -389.772178) (xy 152.618948 -389.772652)
			(xy 152.595377 -389.772192) (xy 152.548793 -389.764959) (xy 152.503877 -389.750643) (xy 152.4617 -389.729585)
			(xy 152.423266 -389.702286) (xy 152.389492 -389.669398) (xy 152.361182 -389.631703) (xy 152.349708 -389.611108)
			(xy 152.3492 -389.610346) (xy 151.951436 -388.922006) (xy 151.939523 -388.899336) (xy 151.922584 -388.851012)
			(xy 151.913924 -388.800542) (xy 151.913336 -388.77494) (xy 151.371596 -388.77494) (xy 151.68372 -389.314944)
			(xy 151.696436 -389.33827) (xy 151.714536 -389.388214) (xy 151.723759 -389.44053) (xy 151.72436 -389.46709)
			(xy 151.72436 -389.467344) (xy 151.724002 -389.491341) (xy 151.716487 -389.538742) (xy 151.70165 -389.584385)
			(xy 151.679855 -389.627144) (xy 151.651639 -389.665968) (xy 151.617698 -389.699899) (xy 151.578866 -389.728103)
			(xy 151.5361 -389.749885) (xy 151.490453 -389.764709) (xy 151.443049 -389.772209) (xy 151.419052 -389.772652)
			(xy 151.395481 -389.772189) (xy 151.348897 -389.764957) (xy 151.303982 -389.750641) (xy 151.261804 -389.729583)
			(xy 151.223371 -389.702285) (xy 151.189596 -389.669397) (xy 151.161286 -389.631703) (xy 151.149812 -389.611108)
			(xy 151.149304 -389.610346) (xy 150.75154 -388.922006) (xy 150.739628 -388.899336) (xy 150.722688 -388.851012)
			(xy 150.714028 -388.800542) (xy 150.71344 -388.77494) (xy 150.171446 -388.77494) (xy 150.48357 -389.314944)
			(xy 150.496379 -389.338285) (xy 150.514604 -389.388303) (xy 150.523871 -389.440726) (xy 150.524464 -389.467344)
			(xy 150.524079 -389.491326) (xy 150.516573 -389.538699) (xy 150.501752 -389.584316) (xy 150.479981 -389.627054)
			(xy 150.451796 -389.665863) (xy 150.41789 -389.699788) (xy 150.379096 -389.727994) (xy 150.336369 -389.749788)
			(xy 150.290761 -389.764634) (xy 150.243392 -389.772166) (xy 150.21941 -389.772652) (xy 150.218902 -389.772652)
			(xy 150.195329 -389.772229) (xy 150.148744 -389.76499) (xy 150.103827 -389.750667) (xy 150.06165 -389.729602)
			(xy 150.023217 -389.702298) (xy 149.989444 -389.669404) (xy 149.961135 -389.631705) (xy 149.949662 -389.611108)
			(xy 149.949154 -389.610346) (xy 149.55139 -388.922006) (xy 149.539516 -388.899328) (xy 149.522664 -388.850995)
			(xy 149.51409 -388.800533) (xy 149.513544 -388.77494) (xy 148.97155 -388.77494) (xy 149.283674 -389.314944)
			(xy 149.296483 -389.338284) (xy 149.314708 -389.388303) (xy 149.323975 -389.440726) (xy 149.324568 -389.467344)
			(xy 149.324179 -389.491326) (xy 149.316673 -389.538698) (xy 149.301852 -389.584315) (xy 149.280082 -389.627053)
			(xy 149.251897 -389.665862) (xy 149.217991 -389.699787) (xy 149.179198 -389.727993) (xy 149.136472 -389.749787)
			(xy 149.090864 -389.764633) (xy 149.043495 -389.772165) (xy 149.019514 -389.772652) (xy 149.019006 -389.772652)
			(xy 148.995434 -389.772226) (xy 148.948848 -389.764987) (xy 148.903932 -389.750665) (xy 148.861754 -389.729601)
			(xy 148.823321 -389.702297) (xy 148.789548 -389.669404) (xy 148.761239 -389.631705) (xy 148.749766 -389.611108)
			(xy 148.749258 -389.610346) (xy 148.351494 -388.922006) (xy 148.339621 -388.899328) (xy 148.322768 -388.850995)
			(xy 148.314194 -388.800532) (xy 148.313648 -388.77494) (xy 147.771654 -388.77494) (xy 148.083778 -389.314944)
			(xy 148.096588 -389.338284) (xy 148.114813 -389.388303) (xy 148.124079 -389.440726) (xy 148.124672 -389.467344)
			(xy 148.124279 -389.491326) (xy 148.116773 -389.538698) (xy 148.101953 -389.584314) (xy 148.080183 -389.627052)
			(xy 148.051999 -389.665861) (xy 148.018093 -389.699785) (xy 147.9793 -389.727992) (xy 147.936575 -389.749786)
			(xy 147.890967 -389.764632) (xy 147.843599 -389.772165) (xy 147.819618 -389.772652) (xy 147.81911 -389.772652)
			(xy 147.795538 -389.772223) (xy 147.748952 -389.764984) (xy 147.704036 -389.750663) (xy 147.661859 -389.729599)
			(xy 147.623425 -389.702296) (xy 147.589652 -389.669403) (xy 147.561343 -389.631704) (xy 147.54987 -389.611108)
			(xy 147.549362 -389.610346) (xy 147.151598 -388.922006) (xy 147.139725 -388.899328) (xy 147.122872 -388.850995)
			(xy 147.114298 -388.800532) (xy 147.113752 -388.77494) (xy 133.24387 -388.77494) (xy 133.555994 -389.314944)
			(xy 133.568805 -389.338283) (xy 133.587029 -389.388303) (xy 133.596295 -389.440726) (xy 133.596888 -389.467344)
			(xy 133.596479 -389.491325) (xy 133.588974 -389.538695) (xy 133.574154 -389.58431) (xy 133.552386 -389.627047)
			(xy 133.524203 -389.665855) (xy 133.4903 -389.69978) (xy 133.451509 -389.727986) (xy 133.408786 -389.749782)
			(xy 133.36318 -389.764629) (xy 133.315814 -389.772164) (xy 133.291834 -389.772652) (xy 133.291326 -389.772652)
			(xy 133.267754 -389.77221) (xy 133.221169 -389.764974) (xy 133.176253 -389.750654) (xy 133.134076 -389.729593)
			(xy 133.095643 -389.702292) (xy 133.061869 -389.669401) (xy 133.033559 -389.631704) (xy 133.022086 -389.611108)
			(xy 133.021578 -389.610346) (xy 132.623814 -388.922006) (xy 132.611935 -388.899331) (xy 132.595086 -388.850997)
			(xy 132.586514 -388.800533) (xy 132.585968 -388.77494) (xy 132.04372 -388.77494) (xy 132.355844 -389.314944)
			(xy 132.368562 -389.338269) (xy 132.386661 -389.388214) (xy 132.395883 -389.44053) (xy 132.396484 -389.46709)
			(xy 132.396484 -389.467344) (xy 132.396078 -389.491338) (xy 132.388564 -389.538733) (xy 132.37373 -389.58437)
			(xy 132.351938 -389.627124) (xy 132.323728 -389.665943) (xy 132.289792 -389.699872) (xy 132.250966 -389.728074)
			(xy 132.208207 -389.749856) (xy 132.162567 -389.76468) (xy 132.11517 -389.772183) (xy 132.091176 -389.772652)
			(xy 132.067603 -389.77225) (xy 132.021016 -389.765007) (xy 131.976099 -389.75068) (xy 131.933922 -389.729612)
			(xy 131.895489 -389.702305) (xy 131.861716 -389.669408) (xy 131.833408 -389.631706) (xy 131.821936 -389.611108)
			(xy 131.821428 -389.610346) (xy 131.423664 -388.922006) (xy 131.411754 -388.899335) (xy 131.394814 -388.851011)
			(xy 131.386152 -388.800542) (xy 131.385564 -388.77494) (xy 130.843824 -388.77494) (xy 131.155948 -389.314944)
			(xy 131.168667 -389.338269) (xy 131.186765 -389.388214) (xy 131.195987 -389.44053) (xy 131.196588 -389.46709)
			(xy 131.196588 -389.467344) (xy 131.196178 -389.491337) (xy 131.188665 -389.538733) (xy 131.17383 -389.584369)
			(xy 131.152039 -389.627123) (xy 131.123829 -389.665942) (xy 131.089893 -389.69987) (xy 131.051068 -389.728073)
			(xy 131.00831 -389.749854) (xy 130.96267 -389.76468) (xy 130.915274 -389.772183) (xy 130.89128 -389.772652)
			(xy 130.867707 -389.772247) (xy 130.82112 -389.765004) (xy 130.776203 -389.750678) (xy 130.734026 -389.729611)
			(xy 130.695593 -389.702304) (xy 130.661821 -389.669407) (xy 130.633512 -389.631706) (xy 130.62204 -389.611108)
			(xy 130.621532 -389.610346) (xy 130.223768 -388.922006) (xy 130.211858 -388.899335) (xy 130.194918 -388.851011)
			(xy 130.186256 -388.800542) (xy 130.185668 -388.77494) (xy 129.643674 -388.77494) (xy 129.955798 -389.314944)
			(xy 129.968601 -389.338288) (xy 129.98683 -389.388305) (xy 129.996099 -389.440727) (xy 129.996692 -389.467344)
			(xy 129.996279 -389.491325) (xy 129.988774 -389.538695) (xy 129.973955 -389.584309) (xy 129.952187 -389.627046)
			(xy 129.924004 -389.665854) (xy 129.890101 -389.699778) (xy 129.851312 -389.727985) (xy 129.808589 -389.74978)
			(xy 129.762984 -389.764628) (xy 129.715618 -389.772164) (xy 129.691638 -389.772652) (xy 129.69113 -389.772652)
			(xy 129.667558 -389.772207) (xy 129.620974 -389.764971) (xy 129.576058 -389.750652) (xy 129.53388 -389.729592)
			(xy 129.495447 -389.702291) (xy 129.461673 -389.6694) (xy 129.433363 -389.631704) (xy 129.42189 -389.611108)
			(xy 129.421382 -389.610346) (xy 129.023618 -388.922006) (xy 129.011739 -388.899331) (xy 128.99489 -388.850997)
			(xy 128.986318 -388.800533) (xy 128.985772 -388.77494) (xy 128.443778 -388.77494) (xy 128.755902 -389.314944)
			(xy 128.768705 -389.338288) (xy 128.786934 -389.388305) (xy 128.796203 -389.440727) (xy 128.796796 -389.467344)
			(xy 128.796379 -389.491324) (xy 128.788874 -389.538694) (xy 128.774055 -389.584308) (xy 128.752287 -389.627045)
			(xy 128.724106 -389.665852) (xy 128.690203 -389.699777) (xy 128.651414 -389.727984) (xy 128.608692 -389.749779)
			(xy 128.563087 -389.764628) (xy 128.515722 -389.772163) (xy 128.491742 -389.772652) (xy 128.491234 -389.772652)
			(xy 128.467662 -389.772203) (xy 128.421078 -389.764969) (xy 128.376162 -389.75065) (xy 128.333985 -389.72959)
			(xy 128.295551 -389.70229) (xy 128.261777 -389.6694) (xy 128.233467 -389.631703) (xy 128.221994 -389.611108)
			(xy 128.221486 -389.610346) (xy 127.823722 -388.922006) (xy 127.811843 -388.899331) (xy 127.794994 -388.850996)
			(xy 127.786422 -388.800533) (xy 127.785876 -388.77494) (xy 127.243882 -388.77494) (xy 127.556006 -389.314944)
			(xy 127.56881 -389.338287) (xy 127.587038 -389.388304) (xy 127.596307 -389.440727) (xy 127.5969 -389.467344)
			(xy 127.596479 -389.491324) (xy 127.588974 -389.538694) (xy 127.574156 -389.584307) (xy 127.552388 -389.627044)
			(xy 127.524207 -389.665851) (xy 127.490305 -389.699775) (xy 127.451516 -389.727982) (xy 127.408794 -389.749778)
			(xy 127.36319 -389.764627) (xy 127.315826 -389.772163) (xy 127.291846 -389.772652) (xy 127.291338 -389.772652)
			(xy 127.267766 -389.7722) (xy 127.221182 -389.764966) (xy 127.176266 -389.750648) (xy 127.134089 -389.729589)
			(xy 127.095656 -389.702289) (xy 127.061881 -389.669399) (xy 127.033571 -389.631703) (xy 127.022098 -389.611108)
			(xy 127.02159 -389.610346) (xy 126.623826 -388.922006) (xy 126.611947 -388.89933) (xy 126.595098 -388.850996)
			(xy 126.586526 -388.800533) (xy 126.58598 -388.77494) (xy 126.043732 -388.77494) (xy 126.355856 -389.314944)
			(xy 126.368575 -389.338269) (xy 126.386673 -389.388214) (xy 126.395895 -389.440529) (xy 126.396496 -389.46709)
			(xy 126.396496 -389.467344) (xy 126.396078 -389.491337) (xy 126.388565 -389.538731) (xy 126.373731 -389.584367)
			(xy 126.351941 -389.627121) (xy 126.323731 -389.665939) (xy 126.289797 -389.699868) (xy 126.250973 -389.72807)
			(xy 126.208215 -389.749852) (xy 126.162577 -389.764678) (xy 126.115181 -389.772182) (xy 126.091188 -389.772652)
			(xy 126.067615 -389.772241) (xy 126.021029 -389.764999) (xy 125.976112 -389.750674) (xy 125.933935 -389.729608)
			(xy 125.895502 -389.702301) (xy 125.861729 -389.669406) (xy 125.833421 -389.631705) (xy 125.821948 -389.611108)
			(xy 125.82144 -389.610346) (xy 125.423676 -388.922006) (xy 125.411759 -388.899339) (xy 125.394823 -388.851013)
			(xy 125.386163 -388.800542) (xy 125.385576 -388.77494) (xy 124.843836 -388.77494) (xy 125.15596 -389.314944)
			(xy 125.16868 -389.338269) (xy 125.186777 -389.388214) (xy 125.195999 -389.440529) (xy 125.1966 -389.46709)
			(xy 125.1966 -389.467344) (xy 125.196178 -389.491337) (xy 125.188665 -389.538731) (xy 125.173831 -389.584366)
			(xy 125.152041 -389.627119) (xy 125.123832 -389.665938) (xy 125.089898 -389.699866) (xy 125.051075 -389.728069)
			(xy 125.008318 -389.749851) (xy 124.96268 -389.764677) (xy 124.915285 -389.772182) (xy 124.891292 -389.772652)
			(xy 124.867719 -389.772237) (xy 124.821133 -389.764996) (xy 124.776216 -389.750672) (xy 124.734039 -389.729606)
			(xy 124.695606 -389.7023) (xy 124.661833 -389.669406) (xy 124.633525 -389.631705) (xy 124.622052 -389.611108)
			(xy 124.621544 -389.610346) (xy 124.22378 -388.922006) (xy 124.211863 -388.899339) (xy 124.194927 -388.851013)
			(xy 124.186267 -388.800542) (xy 124.18568 -388.77494) (xy 123.643686 -388.77494) (xy 123.95581 -389.314944)
			(xy 123.968614 -389.338287) (xy 123.986843 -389.388304) (xy 123.996111 -389.440727) (xy 123.996704 -389.467344)
			(xy 123.996279 -389.491324) (xy 123.988774 -389.538693) (xy 123.973956 -389.584307) (xy 123.952189 -389.627042)
			(xy 123.924008 -389.66585) (xy 123.890106 -389.699774) (xy 123.851318 -389.727981) (xy 123.808597 -389.749777)
			(xy 123.762994 -389.764626) (xy 123.71563 -389.772163) (xy 123.69165 -389.772652) (xy 123.691142 -389.772652)
			(xy 123.667571 -389.772197) (xy 123.620986 -389.764963) (xy 123.576071 -389.750646) (xy 123.533893 -389.729587)
			(xy 123.49546 -389.702288) (xy 123.461686 -389.669398) (xy 123.433376 -389.631703) (xy 123.421902 -389.611108)
			(xy 123.421394 -389.610346) (xy 123.02363 -388.922006) (xy 123.011752 -388.89933) (xy 122.994902 -388.850996)
			(xy 122.98633 -388.800533) (xy 122.985784 -388.77494) (xy 122.44379 -388.77494) (xy 122.755914 -389.314944)
			(xy 122.768718 -389.338287) (xy 122.786947 -389.388304) (xy 122.796215 -389.440727) (xy 122.796808 -389.467344)
			(xy 122.796379 -389.491324) (xy 122.788874 -389.538693) (xy 122.774056 -389.584306) (xy 122.752289 -389.627041)
			(xy 122.724109 -389.665848) (xy 122.690208 -389.699772) (xy 122.65142 -389.72798) (xy 122.6087 -389.749776)
			(xy 122.563097 -389.764625) (xy 122.515733 -389.772162) (xy 122.491754 -389.772652) (xy 122.491246 -389.772652)
			(xy 122.467675 -389.772194) (xy 122.421091 -389.764961) (xy 122.376175 -389.750644) (xy 122.333998 -389.729586)
			(xy 122.295564 -389.702287) (xy 122.26179 -389.669398) (xy 122.23348 -389.631703) (xy 122.222006 -389.611108)
			(xy 122.221498 -389.610346) (xy 121.823734 -388.922006) (xy 121.811856 -388.89933) (xy 121.795006 -388.850996)
			(xy 121.786434 -388.800533) (xy 121.785888 -388.77494) (xy 121.243894 -388.77494) (xy 121.556018 -389.314944)
			(xy 121.568823 -389.338287) (xy 121.587051 -389.388304) (xy 121.596319 -389.440727) (xy 121.596912 -389.467344)
			(xy 121.596479 -389.491324) (xy 121.588974 -389.538692) (xy 121.574157 -389.584305) (xy 121.55239 -389.62704)
			(xy 121.52421 -389.665847) (xy 121.49031 -389.699771) (xy 121.451523 -389.727978) (xy 121.408803 -389.749775)
			(xy 121.3632 -389.764624) (xy 121.315837 -389.772162) (xy 121.291858 -389.772652) (xy 121.29135 -389.772652)
			(xy 121.267779 -389.772191) (xy 121.221195 -389.764958) (xy 121.176279 -389.750642) (xy 121.134102 -389.729584)
			(xy 121.095668 -389.702286) (xy 121.061894 -389.669397) (xy 121.033584 -389.631703) (xy 121.02211 -389.611108)
			(xy 121.021602 -389.610346) (xy 120.623838 -388.922006) (xy 120.61196 -388.89933) (xy 120.595111 -388.850996)
			(xy 120.586538 -388.800533) (xy 120.585992 -388.77494) (xy 120.043744 -388.77494) (xy 120.355868 -389.314944)
			(xy 120.368588 -389.338268) (xy 120.386686 -389.388213) (xy 120.395908 -389.440529) (xy 120.396508 -389.46709)
			(xy 120.396508 -389.467344) (xy 120.396078 -389.491336) (xy 120.388565 -389.53873) (xy 120.373732 -389.584364)
			(xy 120.351943 -389.627117) (xy 120.323735 -389.665935) (xy 120.289802 -389.699863) (xy 120.250979 -389.728066)
			(xy 120.208224 -389.749849) (xy 120.162587 -389.764676) (xy 120.115192 -389.772181) (xy 120.0912 -389.772652)
			(xy 120.067627 -389.772231) (xy 120.021042 -389.764991) (xy 119.976125 -389.750668) (xy 119.933948 -389.729603)
			(xy 119.895515 -389.702298) (xy 119.861742 -389.669404) (xy 119.833433 -389.631705) (xy 119.82196 -389.611108)
			(xy 119.821452 -389.610346) (xy 119.423688 -388.922006) (xy 119.411772 -388.899338) (xy 119.394835 -388.851013)
			(xy 119.386175 -388.800542) (xy 119.385588 -388.77494) (xy 118.843848 -388.77494) (xy 119.155972 -389.314944)
			(xy 119.168693 -389.338268) (xy 119.18679 -389.388213) (xy 119.196012 -389.440529) (xy 119.196612 -389.46709)
			(xy 119.196612 -389.467344) (xy 119.196178 -389.491336) (xy 119.188665 -389.538729) (xy 119.173832 -389.584363)
			(xy 119.152044 -389.627116) (xy 119.123836 -389.665934) (xy 119.089903 -389.699862) (xy 119.051082 -389.728065)
			(xy 119.008326 -389.749848) (xy 118.96269 -389.764675) (xy 118.915296 -389.772181) (xy 118.891304 -389.772652)
			(xy 118.867732 -389.772228) (xy 118.821146 -389.764988) (xy 118.776229 -389.750666) (xy 118.734052 -389.729602)
			(xy 118.695619 -389.702297) (xy 118.661846 -389.669404) (xy 118.633537 -389.631705) (xy 118.622064 -389.611108)
			(xy 118.621556 -389.610346) (xy 118.223792 -388.922006) (xy 118.211876 -388.899338) (xy 118.194939 -388.851012)
			(xy 118.186279 -388.800542) (xy 118.185692 -388.77494) (xy 117.643698 -388.77494) (xy 117.955822 -389.314944)
			(xy 117.968627 -389.338287) (xy 117.986855 -389.388304) (xy 117.996123 -389.440727) (xy 117.996716 -389.467344)
			(xy 117.996279 -389.491323) (xy 117.988775 -389.538691) (xy 117.973957 -389.584304) (xy 117.952191 -389.627039)
			(xy 117.924011 -389.665846) (xy 117.890112 -389.69977) (xy 117.851325 -389.727977) (xy 117.808605 -389.749773)
			(xy 117.763004 -389.764624) (xy 117.715641 -389.772162) (xy 117.691662 -389.772652) (xy 117.691154 -389.772652)
			(xy 117.667583 -389.772187) (xy 117.620999 -389.764955) (xy 117.576084 -389.75064) (xy 117.533906 -389.729583)
			(xy 117.495473 -389.702285) (xy 117.461698 -389.669397) (xy 117.433388 -389.631702) (xy 117.421914 -389.611108)
			(xy 117.421406 -389.610346) (xy 117.023642 -388.922006) (xy 117.011765 -388.89933) (xy 116.994915 -388.850996)
			(xy 116.986342 -388.800533) (xy 116.985796 -388.77494) (xy 116.443802 -388.77494) (xy 116.755926 -389.314944)
			(xy 116.768731 -389.338286) (xy 116.786959 -389.388304) (xy 116.796227 -389.440727) (xy 116.79682 -389.467344)
			(xy 116.796379 -389.491323) (xy 116.788875 -389.538691) (xy 116.774057 -389.584303) (xy 116.752292 -389.627038)
			(xy 116.724113 -389.665844) (xy 116.690213 -389.699768) (xy 116.651427 -389.727975) (xy 116.608708 -389.749772)
			(xy 116.563107 -389.764623) (xy 116.515745 -389.772162) (xy 116.491766 -389.772652) (xy 116.491258 -389.772652)
			(xy 116.467687 -389.772184) (xy 116.421104 -389.764953) (xy 116.376188 -389.750638) (xy 116.334011 -389.729581)
			(xy 116.295577 -389.702284) (xy 116.261802 -389.669396) (xy 116.233492 -389.631702) (xy 116.222018 -389.611108)
			(xy 116.22151 -389.610346) (xy 115.823746 -388.922006) (xy 115.811869 -388.89933) (xy 115.795019 -388.850996)
			(xy 115.786446 -388.800533) (xy 115.7859 -388.77494) (xy 115.243906 -388.77494) (xy 115.55603 -389.314944)
			(xy 115.568836 -389.338286) (xy 115.587063 -389.388304) (xy 115.596331 -389.440727) (xy 115.596924 -389.467344)
			(xy 115.596479 -389.491323) (xy 115.588975 -389.53869) (xy 115.574158 -389.584302) (xy 115.552392 -389.627036)
			(xy 115.524214 -389.665843) (xy 115.490315 -389.699767) (xy 115.451529 -389.727974) (xy 115.408811 -389.749771)
			(xy 115.36321 -389.764622) (xy 115.315849 -389.772161) (xy 115.29187 -389.772652) (xy 115.291362 -389.772652)
			(xy 115.267791 -389.772181) (xy 115.221208 -389.76495) (xy 115.176292 -389.750636) (xy 115.134115 -389.72958)
			(xy 115.095681 -389.702283) (xy 115.061907 -389.669396) (xy 115.033596 -389.631702) (xy 115.022122 -389.611108)
			(xy 115.021614 -389.610346) (xy 114.62385 -388.922006) (xy 114.611973 -388.899329) (xy 114.595123 -388.850996)
			(xy 114.58655 -388.800533) (xy 114.586004 -388.77494) (xy 98.67173 -388.77494) (xy 98.9838 -389.314944)
			(xy 98.984054 -389.315452) (xy 98.984308 -389.315452) (xy 98.985578 -389.317992) (xy 98.997808 -389.340918)
			(xy 99.01513 -389.389903) (xy 99.023918 -389.441111) (xy 99.02444 -389.46709) (xy 99.02444 -389.467344)
			(xy 99.023978 -389.491335) (xy 99.016466 -389.538725) (xy 99.001635 -389.584357) (xy 98.979849 -389.627107)
			(xy 98.951644 -389.665924) (xy 98.917715 -389.699852) (xy 98.878897 -389.728055) (xy 98.836146 -389.74984)
			(xy 98.790513 -389.764669) (xy 98.743123 -389.772179) (xy 98.719132 -389.772652) (xy 98.695469 -389.772187)
			(xy 98.648709 -389.764881) (xy 98.603634 -389.750455) (xy 98.561321 -389.729253) (xy 98.522783 -389.701782)
			(xy 98.48894 -389.668699) (xy 98.460601 -389.630794) (xy 98.44913 -389.610092) (xy 98.448876 -389.60933)
			(xy 98.05162 -388.922006) (xy 98.039413 -388.898734) (xy 98.022297 -388.849053) (xy 98.017584 -388.8232)
			(xy 98.014014 -388.797978) (xy 97.484894 -388.797978) (xy 97.78365 -389.314944) (xy 97.783904 -389.315452)
			(xy 97.784158 -389.315452) (xy 97.785428 -389.317992) (xy 97.797701 -389.340907) (xy 97.815106 -389.389885)
			(xy 97.82398 -389.441101) (xy 97.824544 -389.46709) (xy 97.824544 -389.467344) (xy 97.824079 -389.491322)
			(xy 97.816576 -389.538687) (xy 97.80176 -389.584297) (xy 97.779996 -389.62703) (xy 97.75182 -389.665836)
			(xy 97.717923 -389.69976) (xy 97.67914 -389.727967) (xy 97.636425 -389.749765) (xy 97.590827 -389.764618)
			(xy 97.543468 -389.77216) (xy 97.51949 -389.772652) (xy 97.518982 -389.772652) (xy 97.495317 -389.772227)
			(xy 97.448555 -389.764914) (xy 97.40348 -389.75048) (xy 97.361167 -389.729272) (xy 97.322629 -389.701795)
			(xy 97.288787 -389.668706) (xy 97.26045 -389.630797) (xy 97.24898 -389.610092) (xy 97.248726 -389.60933)
			(xy 96.85147 -388.922006) (xy 96.839259 -388.898736) (xy 96.822146 -388.849053) (xy 96.817434 -388.8232)
			(xy 96.813939 -388.799396) (xy 96.813728 -388.751285) (xy 96.258014 -388.751285) (xy 96.583754 -389.314944)
			(xy 96.584008 -389.315452) (xy 96.584262 -389.315452) (xy 96.585532 -389.317992) (xy 96.597806 -389.340907)
			(xy 96.615211 -389.389885) (xy 96.624084 -389.441101) (xy 96.624648 -389.46709) (xy 96.624648 -389.467344)
			(xy 96.624179 -389.491322) (xy 96.616676 -389.538687) (xy 96.60186 -389.584296) (xy 96.580097 -389.627029)
			(xy 96.551921 -389.665835) (xy 96.518025 -389.699758) (xy 96.479243 -389.727966) (xy 96.436528 -389.749764)
			(xy 96.39093 -389.764617) (xy 96.343571 -389.772159) (xy 96.319594 -389.772652) (xy 96.319086 -389.772652)
			(xy 96.295421 -389.772224) (xy 96.24866 -389.764911) (xy 96.203584 -389.750478) (xy 96.161272 -389.72927)
			(xy 96.122734 -389.701794) (xy 96.088892 -389.668705) (xy 96.060554 -389.630796) (xy 96.049084 -389.610092)
			(xy 96.04883 -389.60933) (xy 95.651574 -388.922006) (xy 95.639364 -388.898736) (xy 95.62225 -388.849053)
			(xy 95.617538 -388.8232) (xy 95.614036 -388.799397) (xy 95.613824 -388.751286) (xy 95.057865 -388.751286)
			(xy 95.383604 -389.314944) (xy 95.383858 -389.315452) (xy 95.384112 -389.315452) (xy 95.385382 -389.317992)
			(xy 95.397612 -389.340918) (xy 95.414934 -389.389903) (xy 95.423722 -389.441111) (xy 95.424244 -389.46709)
			(xy 95.424244 -389.467344) (xy 95.423778 -389.491335) (xy 95.416267 -389.538724) (xy 95.401435 -389.584356)
			(xy 95.379649 -389.627106) (xy 95.351445 -389.665923) (xy 95.317517 -389.69985) (xy 95.278699 -389.728054)
			(xy 95.235949 -389.749838) (xy 95.190317 -389.764668) (xy 95.142927 -389.772179) (xy 95.118936 -389.772652)
			(xy 95.095273 -389.772184) (xy 95.048513 -389.764878) (xy 95.003438 -389.750453) (xy 94.961126 -389.729251)
			(xy 94.922587 -389.701781) (xy 94.888744 -389.668698) (xy 94.860405 -389.630794) (xy 94.848934 -389.610092)
			(xy 94.84868 -389.60933) (xy 94.451424 -388.922006) (xy 94.439217 -388.898734) (xy 94.422101 -388.849053)
			(xy 94.417388 -388.8232) (xy 94.413811 -388.797979) (xy 93.884953 -388.797979) (xy 94.183708 -389.314944)
			(xy 94.183962 -389.315452) (xy 94.184216 -389.315452) (xy 94.185486 -389.317992) (xy 94.197717 -389.340917)
			(xy 94.215038 -389.389902) (xy 94.223826 -389.441111) (xy 94.224348 -389.46709) (xy 94.224348 -389.467344)
			(xy 94.223878 -389.491334) (xy 94.216367 -389.538724) (xy 94.201536 -389.584355) (xy 94.17975 -389.627105)
			(xy 94.151546 -389.665922) (xy 94.117618 -389.699849) (xy 94.078802 -389.728052) (xy 94.036051 -389.749837)
			(xy 93.99042 -389.764668) (xy 93.94303 -389.772178) (xy 93.91904 -389.772652) (xy 93.895377 -389.77218)
			(xy 93.848617 -389.764876) (xy 93.803542 -389.750451) (xy 93.76123 -389.72925) (xy 93.722692 -389.70178)
			(xy 93.688848 -389.668698) (xy 93.660509 -389.630794) (xy 93.649038 -389.610092) (xy 93.648784 -389.60933)
			(xy 93.251528 -388.922006) (xy 93.239321 -388.898734) (xy 93.222205 -388.849053) (xy 93.217492 -388.8232)
			(xy 93.214076 -388.799387) (xy 93.213865 -388.751284) (xy 92.658071 -388.751284) (xy 92.983812 -389.314944)
			(xy 92.984066 -389.315452) (xy 92.98432 -389.315452) (xy 92.98559 -389.317992) (xy 92.997821 -389.340917)
			(xy 93.015142 -389.389902) (xy 93.02393 -389.441111) (xy 93.024452 -389.46709) (xy 93.024452 -389.467344)
			(xy 93.023978 -389.491334) (xy 93.016467 -389.538723) (xy 93.001636 -389.584354) (xy 92.979851 -389.627104)
			(xy 92.951648 -389.66592) (xy 92.91772 -389.699848) (xy 92.878904 -389.728051) (xy 92.836154 -389.749836)
			(xy 92.790523 -389.764667) (xy 92.743134 -389.772178) (xy 92.719144 -389.772652) (xy 92.695481 -389.772177)
			(xy 92.648721 -389.764873) (xy 92.603647 -389.750449) (xy 92.561334 -389.729248) (xy 92.522796 -389.701779)
			(xy 92.488952 -389.668697) (xy 92.460613 -389.630794) (xy 92.449142 -389.610092) (xy 92.448888 -389.60933)
			(xy 92.051632 -388.922006) (xy 92.039425 -388.898734) (xy 92.022309 -388.849053) (xy 92.017596 -388.8232)
			(xy 92.014173 -388.799388) (xy 92.013962 -388.751284) (xy 91.457921 -388.751284) (xy 91.783662 -389.314944)
			(xy 91.783916 -389.315452) (xy 91.78417 -389.315452) (xy 91.78544 -389.317992) (xy 91.797714 -389.340906)
			(xy 91.815119 -389.389885) (xy 91.823992 -389.441101) (xy 91.824556 -389.46709) (xy 91.824556 -389.467344)
			(xy 91.824079 -389.491321) (xy 91.816576 -389.538686) (xy 91.801761 -389.584295) (xy 91.779998 -389.627027)
			(xy 91.751823 -389.665832) (xy 91.717928 -389.699755) (xy 91.679147 -389.727963) (xy 91.636433 -389.749762)
			(xy 91.590837 -389.764616) (xy 91.543479 -389.772159) (xy 91.519502 -389.772652) (xy 91.518994 -389.772652)
			(xy 91.495329 -389.772217) (xy 91.448568 -389.764906) (xy 91.403493 -389.750474) (xy 91.36118 -389.729267)
			(xy 91.322642 -389.701792) (xy 91.2888 -389.668704) (xy 91.260462 -389.630796) (xy 91.248992 -389.610092)
			(xy 91.248738 -389.60933) (xy 90.851482 -388.922006) (xy 90.839272 -388.898735) (xy 90.822158 -388.849053)
			(xy 90.817446 -388.8232) (xy 90.813929 -388.799399) (xy 90.813717 -388.751286) (xy 90.258027 -388.751286)
			(xy 90.583766 -389.314944) (xy 90.58402 -389.315452) (xy 90.584274 -389.315452) (xy 90.585544 -389.317992)
			(xy 90.597819 -389.340906) (xy 90.615223 -389.389885) (xy 90.624096 -389.441101) (xy 90.62466 -389.46709)
			(xy 90.62466 -389.467344) (xy 90.624279 -389.491326) (xy 90.616773 -389.5387) (xy 90.601952 -389.584317)
			(xy 90.580181 -389.627055) (xy 90.551995 -389.665865) (xy 90.518088 -389.69979) (xy 90.479294 -389.727996)
			(xy 90.436567 -389.74979) (xy 90.390957 -389.764635) (xy 90.343588 -389.772166) (xy 90.319606 -389.772652)
			(xy 90.319098 -389.772652) (xy 90.295434 -389.772214) (xy 90.248672 -389.764903) (xy 90.203597 -389.750472)
			(xy 90.161285 -389.729266) (xy 90.122747 -389.701791) (xy 90.088904 -389.668704) (xy 90.060566 -389.630796)
			(xy 90.049096 -389.610092) (xy 90.048842 -389.60933) (xy 89.651586 -388.922006) (xy 89.639376 -388.898735)
			(xy 89.622262 -388.849053) (xy 89.61755 -388.8232) (xy 89.614025 -388.7994) (xy 89.613813 -388.751286)
			(xy 89.057877 -388.751286) (xy 89.383616 -389.314944) (xy 89.38387 -389.315452) (xy 89.384124 -389.315452)
			(xy 89.385394 -389.317992) (xy 89.397625 -389.340917) (xy 89.414946 -389.389902) (xy 89.423734 -389.441111)
			(xy 89.424256 -389.46709) (xy 89.424256 -389.467344) (xy 89.423778 -389.491334) (xy 89.416267 -389.538723)
			(xy 89.401436 -389.584353) (xy 89.379652 -389.627103) (xy 89.351449 -389.665919) (xy 89.317522 -389.699846)
			(xy 89.278706 -389.72805) (xy 89.235957 -389.749835) (xy 89.190327 -389.764666) (xy 89.142938 -389.772178)
			(xy 89.118948 -389.772652) (xy 89.095285 -389.772174) (xy 89.048526 -389.764871) (xy 89.003451 -389.750447)
			(xy 88.961139 -389.729247) (xy 88.9226 -389.701778) (xy 88.888757 -389.668697) (xy 88.860417 -389.630794)
			(xy 88.848946 -389.610092) (xy 88.848692 -389.60933) (xy 88.451436 -388.922006) (xy 88.439223 -388.898737)
			(xy 88.422112 -388.849054) (xy 88.4174 -388.8232) (xy 88.413969 -388.799389) (xy 88.413758 -388.751284)
			(xy 87.857979 -388.751284) (xy 88.18372 -389.314944) (xy 88.183974 -389.315452) (xy 88.184228 -389.315452)
			(xy 88.185498 -389.317992) (xy 88.197729 -389.340917) (xy 88.21505 -389.389902) (xy 88.223838 -389.441111)
			(xy 88.22436 -389.46709) (xy 88.22436 -389.467344) (xy 88.224002 -389.491341) (xy 88.216487 -389.538742)
			(xy 88.20165 -389.584385) (xy 88.179855 -389.627144) (xy 88.151639 -389.665968) (xy 88.117698 -389.699899)
			(xy 88.078866 -389.728103) (xy 88.0361 -389.749885) (xy 87.990453 -389.764709) (xy 87.943049 -389.772209)
			(xy 87.919052 -389.772652) (xy 87.895389 -389.772171) (xy 87.84863 -389.764868) (xy 87.803556 -389.750445)
			(xy 87.761243 -389.729245) (xy 87.722705 -389.701777) (xy 87.688861 -389.668696) (xy 87.660521 -389.630793)
			(xy 87.64905 -389.610092) (xy 87.648796 -389.60933) (xy 87.25154 -388.922006) (xy 87.239327 -388.898737)
			(xy 87.222216 -388.849054) (xy 87.217504 -388.8232) (xy 87.214066 -388.79939) (xy 87.213855 -388.751284)
			(xy 86.658083 -388.751284) (xy 86.983824 -389.314944) (xy 86.984078 -389.315452) (xy 86.984332 -389.315452)
			(xy 86.985602 -389.317992) (xy 86.997834 -389.340917) (xy 87.015155 -389.389902) (xy 87.023942 -389.441111)
			(xy 87.024464 -389.46709) (xy 87.024464 -389.467344) (xy 87.024078 -389.491339) (xy 87.016564 -389.538736)
			(xy 87.001728 -389.584375) (xy 86.979935 -389.62713) (xy 86.951722 -389.66595) (xy 86.917783 -389.699879)
			(xy 86.878955 -389.728081) (xy 86.836193 -389.749861) (xy 86.79055 -389.764684) (xy 86.743151 -389.772185)
			(xy 86.719156 -389.772652) (xy 86.695493 -389.772167) (xy 86.648734 -389.764865) (xy 86.60366 -389.750443)
			(xy 86.561348 -389.729244) (xy 86.522809 -389.701776) (xy 86.488965 -389.668695) (xy 86.460625 -389.630793)
			(xy 86.449154 -389.610092) (xy 86.4489 -389.60933) (xy 86.051644 -388.922006) (xy 86.039432 -388.898737)
			(xy 86.02232 -388.849054) (xy 86.017608 -388.8232) (xy 86.014162 -388.799391) (xy 86.013951 -388.751284)
			(xy 85.457933 -388.751284) (xy 85.783674 -389.314944) (xy 85.783928 -389.315452) (xy 85.784182 -389.315452)
			(xy 85.785452 -389.317992) (xy 85.797727 -389.340906) (xy 85.815131 -389.389885) (xy 85.824004 -389.441101)
			(xy 85.824568 -389.46709) (xy 85.824568 -389.467344) (xy 85.824179 -389.491326) (xy 85.816673 -389.538698)
			(xy 85.801852 -389.584315) (xy 85.780082 -389.627053) (xy 85.751897 -389.665862) (xy 85.717991 -389.699787)
			(xy 85.679198 -389.727993) (xy 85.636472 -389.749787) (xy 85.590864 -389.764633) (xy 85.543495 -389.772165)
			(xy 85.519514 -389.772652) (xy 85.519006 -389.772652) (xy 85.495342 -389.772208) (xy 85.448581 -389.764898)
			(xy 85.403506 -389.750468) (xy 85.361193 -389.729263) (xy 85.322655 -389.701789) (xy 85.288813 -389.668703)
			(xy 85.260474 -389.630795) (xy 85.249004 -389.610092) (xy 85.24875 -389.60933) (xy 84.851494 -388.922006)
			(xy 84.839285 -388.898735) (xy 84.822171 -388.849053) (xy 84.817458 -388.8232) (xy 84.813918 -388.799402)
			(xy 84.813706 -388.751287) (xy 84.258039 -388.751287) (xy 84.583778 -389.314944) (xy 84.584032 -389.315452)
			(xy 84.584286 -389.315452) (xy 84.585556 -389.317992) (xy 84.597831 -389.340906) (xy 84.615235 -389.389885)
			(xy 84.624108 -389.441101) (xy 84.624672 -389.46709) (xy 84.624672 -389.467344) (xy 84.624279 -389.491326)
			(xy 84.616773 -389.538698) (xy 84.601953 -389.584314) (xy 84.580183 -389.627052) (xy 84.551999 -389.665861)
			(xy 84.518093 -389.699785) (xy 84.4793 -389.727992) (xy 84.436575 -389.749786) (xy 84.390967 -389.764632)
			(xy 84.343599 -389.772165) (xy 84.319618 -389.772652) (xy 84.31911 -389.772652) (xy 84.295446 -389.772205)
			(xy 84.248685 -389.764896) (xy 84.20361 -389.750466) (xy 84.161298 -389.729261) (xy 84.122759 -389.701788)
			(xy 84.088917 -389.668702) (xy 84.060578 -389.630795) (xy 84.049108 -389.610092) (xy 84.048854 -389.60933)
			(xy 83.651598 -388.922006) (xy 83.639389 -388.898735) (xy 83.622275 -388.849053) (xy 83.617562 -388.8232)
			(xy 83.614015 -388.799402) (xy 83.613803 -388.751287) (xy 83.057889 -388.751287) (xy 83.383628 -389.314944)
			(xy 83.383882 -389.315452) (xy 83.384136 -389.315452) (xy 83.385406 -389.317992) (xy 83.397638 -389.340917)
			(xy 83.414959 -389.389902) (xy 83.423746 -389.441111) (xy 83.424268 -389.46709) (xy 83.424268 -389.467344)
			(xy 83.423878 -389.491338) (xy 83.416364 -389.538735) (xy 83.401528 -389.584374) (xy 83.379736 -389.627129)
			(xy 83.351523 -389.665949) (xy 83.317585 -389.699878) (xy 83.278757 -389.728079) (xy 83.235996 -389.74986)
			(xy 83.190354 -389.764684) (xy 83.142955 -389.772184) (xy 83.11896 -389.772652) (xy 83.095297 -389.772164)
			(xy 83.048539 -389.764863) (xy 83.003464 -389.75044) (xy 82.961152 -389.729242) (xy 82.922613 -389.701775)
			(xy 82.888769 -389.668695) (xy 82.860429 -389.630793) (xy 82.848958 -389.610092) (xy 82.848704 -389.60933)
			(xy 82.451448 -388.922006) (xy 82.439236 -388.898737) (xy 82.422124 -388.849054) (xy 82.417412 -388.8232)
			(xy 82.413959 -388.799392) (xy 82.413748 -388.751285) (xy 81.857992 -388.751285) (xy 82.183732 -389.314944)
			(xy 82.183986 -389.315452) (xy 82.18424 -389.315452) (xy 82.18551 -389.317992) (xy 82.197742 -389.340916)
			(xy 82.215063 -389.389902) (xy 82.22385 -389.441111) (xy 82.224372 -389.46709) (xy 82.224372 -389.467344)
			(xy 82.223978 -389.491338) (xy 82.216464 -389.538735) (xy 82.201628 -389.584373) (xy 82.179836 -389.627128)
			(xy 82.151624 -389.665948) (xy 82.117687 -389.699876) (xy 82.078859 -389.728078) (xy 82.036099 -389.749859)
			(xy 81.990457 -389.764683) (xy 81.943058 -389.772184) (xy 81.919064 -389.772652) (xy 81.895401 -389.772161)
			(xy 81.848643 -389.76486) (xy 81.803569 -389.750438) (xy 81.761256 -389.729241) (xy 81.722717 -389.701774)
			(xy 81.688873 -389.668694) (xy 81.660533 -389.630793) (xy 81.649062 -389.610092) (xy 81.648808 -389.60933)
			(xy 81.251552 -388.922006) (xy 81.23934 -388.898736) (xy 81.222228 -388.849054) (xy 81.217516 -388.8232)
			(xy 81.214055 -388.799392) (xy 81.213844 -388.751285) (xy 80.658096 -388.751285) (xy 80.983836 -389.314944)
			(xy 80.98409 -389.315452) (xy 80.984344 -389.315452) (xy 80.985614 -389.317992) (xy 80.997847 -389.340916)
			(xy 81.015167 -389.389902) (xy 81.023954 -389.441111) (xy 81.024476 -389.46709) (xy 81.024476 -389.467344)
			(xy 81.024078 -389.491338) (xy 81.016564 -389.538734) (xy 81.001729 -389.584372) (xy 80.979937 -389.627127)
			(xy 80.951725 -389.665946) (xy 80.917788 -389.699875) (xy 80.878962 -389.728077) (xy 80.836201 -389.749858)
			(xy 80.79056 -389.764682) (xy 80.743162 -389.772184) (xy 80.719168 -389.772652) (xy 80.695506 -389.772158)
			(xy 80.648747 -389.764857) (xy 80.603673 -389.750436) (xy 80.561361 -389.729239) (xy 80.522822 -389.701773)
			(xy 80.488978 -389.668694) (xy 80.460637 -389.630793) (xy 80.449166 -389.610092) (xy 80.448912 -389.60933)
			(xy 80.051656 -388.922006) (xy 80.039444 -388.898736) (xy 80.022332 -388.849054) (xy 80.01762 -388.8232)
			(xy 80.014152 -388.799393) (xy 80.01394 -388.751285) (xy 66.130256 -388.751285) (xy 66.456052 -389.314944)
			(xy 66.468771 -389.338269) (xy 66.486869 -389.388214) (xy 66.496091 -389.44053) (xy 66.496692 -389.46709)
			(xy 66.496692 -389.467344) (xy 66.496278 -389.491337) (xy 66.488765 -389.538732) (xy 66.47393 -389.584368)
			(xy 66.45214 -389.627122) (xy 66.42393 -389.665941) (xy 66.389995 -389.699869) (xy 66.351171 -389.728071)
			(xy 66.308412 -389.749853) (xy 66.262774 -389.764679) (xy 66.215377 -389.772183) (xy 66.191384 -389.772652)
			(xy 66.167811 -389.772244) (xy 66.121225 -389.765001) (xy 66.076308 -389.750676) (xy 66.034131 -389.729609)
			(xy 65.995698 -389.702302) (xy 65.961925 -389.669407) (xy 65.933616 -389.631706) (xy 65.922144 -389.611108)
			(xy 65.921636 -389.610346) (xy 65.523872 -388.922006) (xy 65.511954 -388.899339) (xy 65.495018 -388.851013)
			(xy 65.486359 -388.800542) (xy 65.485772 -388.77494) (xy 64.943778 -388.77494) (xy 65.255902 -389.314944)
			(xy 65.268705 -389.338288) (xy 65.286934 -389.388305) (xy 65.296203 -389.440727) (xy 65.296796 -389.467344)
			(xy 65.296379 -389.491324) (xy 65.288874 -389.538694) (xy 65.274055 -389.584308) (xy 65.252287 -389.627045)
			(xy 65.224106 -389.665852) (xy 65.190203 -389.699777) (xy 65.151414 -389.727984) (xy 65.108692 -389.749779)
			(xy 65.063087 -389.764628) (xy 65.015722 -389.772163) (xy 64.991742 -389.772652) (xy 64.991234 -389.772652)
			(xy 64.967662 -389.772203) (xy 64.921078 -389.764969) (xy 64.876162 -389.75065) (xy 64.833985 -389.72959)
			(xy 64.795551 -389.70229) (xy 64.761777 -389.6694) (xy 64.733467 -389.631703) (xy 64.721994 -389.611108)
			(xy 64.721486 -389.610346) (xy 64.323722 -388.922006) (xy 64.311843 -388.899331) (xy 64.294994 -388.850996)
			(xy 64.286422 -388.800533) (xy 64.285876 -388.77494) (xy 63.743882 -388.77494) (xy 64.056006 -389.314944)
			(xy 64.06881 -389.338287) (xy 64.087038 -389.388304) (xy 64.096307 -389.440727) (xy 64.0969 -389.467344)
			(xy 64.096479 -389.491324) (xy 64.088974 -389.538694) (xy 64.074156 -389.584307) (xy 64.052388 -389.627044)
			(xy 64.024207 -389.665851) (xy 63.990305 -389.699775) (xy 63.951516 -389.727982) (xy 63.908794 -389.749778)
			(xy 63.86319 -389.764627) (xy 63.815826 -389.772163) (xy 63.791846 -389.772652) (xy 63.791338 -389.772652)
			(xy 63.767766 -389.7722) (xy 63.721182 -389.764966) (xy 63.676266 -389.750648) (xy 63.634089 -389.729589)
			(xy 63.595656 -389.702289) (xy 63.561881 -389.669399) (xy 63.533571 -389.631703) (xy 63.522098 -389.611108)
			(xy 63.52159 -389.610346) (xy 63.123826 -388.922006) (xy 63.111947 -388.89933) (xy 63.095098 -388.850996)
			(xy 63.086526 -388.800533) (xy 63.08598 -388.77494) (xy 62.543732 -388.77494) (xy 62.855856 -389.314944)
			(xy 62.868575 -389.338269) (xy 62.886673 -389.388214) (xy 62.895895 -389.440529) (xy 62.896496 -389.46709)
			(xy 62.896496 -389.467344) (xy 62.896078 -389.491337) (xy 62.888565 -389.538731) (xy 62.873731 -389.584367)
			(xy 62.851941 -389.627121) (xy 62.823731 -389.665939) (xy 62.789797 -389.699868) (xy 62.750973 -389.72807)
			(xy 62.708215 -389.749852) (xy 62.662577 -389.764678) (xy 62.615181 -389.772182) (xy 62.591188 -389.772652)
			(xy 62.567615 -389.772241) (xy 62.521029 -389.764999) (xy 62.476112 -389.750674) (xy 62.433935 -389.729608)
			(xy 62.395502 -389.702301) (xy 62.361729 -389.669406) (xy 62.333421 -389.631705) (xy 62.321948 -389.611108)
			(xy 62.32144 -389.610346) (xy 61.923676 -388.922006) (xy 61.911759 -388.899339) (xy 61.894823 -388.851013)
			(xy 61.886163 -388.800542) (xy 61.885576 -388.77494) (xy 61.343836 -388.77494) (xy 61.65596 -389.314944)
			(xy 61.66868 -389.338269) (xy 61.686777 -389.388214) (xy 61.695999 -389.440529) (xy 61.6966 -389.46709)
			(xy 61.6966 -389.467344) (xy 61.696178 -389.491337) (xy 61.688665 -389.538731) (xy 61.673831 -389.584366)
			(xy 61.652041 -389.627119) (xy 61.623832 -389.665938) (xy 61.589898 -389.699866) (xy 61.551075 -389.728069)
			(xy 61.508318 -389.749851) (xy 61.46268 -389.764677) (xy 61.415285 -389.772182) (xy 61.391292 -389.772652)
			(xy 61.367719 -389.772237) (xy 61.321133 -389.764996) (xy 61.276216 -389.750672) (xy 61.234039 -389.729606)
			(xy 61.195606 -389.7023) (xy 61.161833 -389.669406) (xy 61.133525 -389.631705) (xy 61.122052 -389.611108)
			(xy 61.121544 -389.610346) (xy 60.72378 -388.922006) (xy 60.711863 -388.899339) (xy 60.694927 -388.851013)
			(xy 60.686267 -388.800542) (xy 60.68568 -388.77494) (xy 60.14394 -388.77494) (xy 60.456064 -389.314944)
			(xy 60.468784 -389.338268) (xy 60.486881 -389.388213) (xy 60.496104 -389.440529) (xy 60.496704 -389.46709)
			(xy 60.496704 -389.467344) (xy 60.496278 -389.491337) (xy 60.488765 -389.53873) (xy 60.473931 -389.584365)
			(xy 60.452142 -389.627118) (xy 60.423933 -389.665937) (xy 60.39 -389.699865) (xy 60.351177 -389.728067)
			(xy 60.308421 -389.74985) (xy 60.262783 -389.764676) (xy 60.215389 -389.772182) (xy 60.191396 -389.772652)
			(xy 60.167823 -389.772234) (xy 60.121237 -389.764993) (xy 60.076321 -389.75067) (xy 60.034144 -389.729605)
			(xy 59.99571 -389.702299) (xy 59.961937 -389.669405) (xy 59.933629 -389.631705) (xy 59.922156 -389.611108)
			(xy 59.921648 -389.610346) (xy 59.523884 -388.922006) (xy 59.511967 -388.899338) (xy 59.495031 -388.851013)
			(xy 59.486371 -388.800542) (xy 59.485784 -388.77494) (xy 58.94379 -388.77494) (xy 59.255914 -389.314944)
			(xy 59.268718 -389.338287) (xy 59.286947 -389.388304) (xy 59.296215 -389.440727) (xy 59.296808 -389.467344)
			(xy 59.296379 -389.491324) (xy 59.288874 -389.538693) (xy 59.274056 -389.584306) (xy 59.252289 -389.627041)
			(xy 59.224109 -389.665848) (xy 59.190208 -389.699772) (xy 59.15142 -389.72798) (xy 59.1087 -389.749776)
			(xy 59.063097 -389.764625) (xy 59.015733 -389.772162) (xy 58.991754 -389.772652) (xy 58.991246 -389.772652)
			(xy 58.967675 -389.772194) (xy 58.921091 -389.764961) (xy 58.876175 -389.750644) (xy 58.833998 -389.729586)
			(xy 58.795564 -389.702287) (xy 58.76179 -389.669398) (xy 58.73348 -389.631703) (xy 58.722006 -389.611108)
			(xy 58.721498 -389.610346) (xy 58.323734 -388.922006) (xy 58.311856 -388.89933) (xy 58.295006 -388.850996)
			(xy 58.286434 -388.800533) (xy 58.285888 -388.77494) (xy 57.743894 -388.77494) (xy 58.056018 -389.314944)
			(xy 58.068823 -389.338287) (xy 58.087051 -389.388304) (xy 58.096319 -389.440727) (xy 58.096912 -389.467344)
			(xy 58.096479 -389.491324) (xy 58.088974 -389.538692) (xy 58.074157 -389.584305) (xy 58.05239 -389.62704)
			(xy 58.02421 -389.665847) (xy 57.99031 -389.699771) (xy 57.951523 -389.727978) (xy 57.908803 -389.749775)
			(xy 57.8632 -389.764624) (xy 57.815837 -389.772162) (xy 57.791858 -389.772652) (xy 57.79135 -389.772652)
			(xy 57.767779 -389.772191) (xy 57.721195 -389.764958) (xy 57.676279 -389.750642) (xy 57.634102 -389.729584)
			(xy 57.595668 -389.702286) (xy 57.561894 -389.669397) (xy 57.533584 -389.631703) (xy 57.52211 -389.611108)
			(xy 57.521602 -389.610346) (xy 57.123838 -388.922006) (xy 57.11196 -388.89933) (xy 57.095111 -388.850996)
			(xy 57.086538 -388.800533) (xy 57.085992 -388.77494) (xy 56.543744 -388.77494) (xy 56.855868 -389.314944)
			(xy 56.868588 -389.338268) (xy 56.886686 -389.388213) (xy 56.895908 -389.440529) (xy 56.896508 -389.46709)
			(xy 56.896508 -389.467344) (xy 56.896078 -389.491336) (xy 56.888565 -389.53873) (xy 56.873732 -389.584364)
			(xy 56.851943 -389.627117) (xy 56.823735 -389.665935) (xy 56.789802 -389.699863) (xy 56.750979 -389.728066)
			(xy 56.708224 -389.749849) (xy 56.662587 -389.764676) (xy 56.615192 -389.772181) (xy 56.5912 -389.772652)
			(xy 56.567627 -389.772231) (xy 56.521042 -389.764991) (xy 56.476125 -389.750668) (xy 56.433948 -389.729603)
			(xy 56.395515 -389.702298) (xy 56.361742 -389.669404) (xy 56.333433 -389.631705) (xy 56.32196 -389.611108)
			(xy 56.321452 -389.610346) (xy 55.923688 -388.922006) (xy 55.911772 -388.899338) (xy 55.894835 -388.851013)
			(xy 55.886175 -388.800542) (xy 55.885588 -388.77494) (xy 55.343848 -388.77494) (xy 55.655972 -389.314944)
			(xy 55.668693 -389.338268) (xy 55.68679 -389.388213) (xy 55.696012 -389.440529) (xy 55.696612 -389.46709)
			(xy 55.696612 -389.467344) (xy 55.696178 -389.491336) (xy 55.688665 -389.538729) (xy 55.673832 -389.584363)
			(xy 55.652044 -389.627116) (xy 55.623836 -389.665934) (xy 55.589903 -389.699862) (xy 55.551082 -389.728065)
			(xy 55.508326 -389.749848) (xy 55.46269 -389.764675) (xy 55.415296 -389.772181) (xy 55.391304 -389.772652)
			(xy 55.367732 -389.772228) (xy 55.321146 -389.764988) (xy 55.276229 -389.750666) (xy 55.234052 -389.729602)
			(xy 55.195619 -389.702297) (xy 55.161846 -389.669404) (xy 55.133537 -389.631705) (xy 55.122064 -389.611108)
			(xy 55.121556 -389.610346) (xy 54.723792 -388.922006) (xy 54.711876 -388.899338) (xy 54.694939 -388.851012)
			(xy 54.686279 -388.800542) (xy 54.685692 -388.77494) (xy 54.143952 -388.77494) (xy 54.456076 -389.314944)
			(xy 54.468797 -389.338268) (xy 54.486894 -389.388213) (xy 54.496116 -389.440529) (xy 54.496716 -389.46709)
			(xy 54.496716 -389.467344) (xy 54.496278 -389.491336) (xy 54.488766 -389.538728) (xy 54.473933 -389.584362)
			(xy 54.452144 -389.627115) (xy 54.423937 -389.665932) (xy 54.390005 -389.69986) (xy 54.351184 -389.728063)
			(xy 54.308429 -389.749846) (xy 54.262793 -389.764674) (xy 54.2154 -389.772181) (xy 54.191408 -389.772652)
			(xy 54.167836 -389.772224) (xy 54.12125 -389.764986) (xy 54.076334 -389.750664) (xy 54.034157 -389.7296)
			(xy 53.995723 -389.702296) (xy 53.96195 -389.669403) (xy 53.933641 -389.631704) (xy 53.922168 -389.611108)
			(xy 53.92166 -389.610346) (xy 53.523896 -388.922006) (xy 53.51198 -388.899338) (xy 53.495043 -388.851012)
			(xy 53.486383 -388.800542) (xy 53.485796 -388.77494) (xy 52.943802 -388.77494) (xy 53.255926 -389.314944)
			(xy 53.268731 -389.338286) (xy 53.286959 -389.388304) (xy 53.296227 -389.440727) (xy 53.29682 -389.467344)
			(xy 53.296379 -389.491323) (xy 53.288875 -389.538691) (xy 53.274057 -389.584303) (xy 53.252292 -389.627038)
			(xy 53.224113 -389.665844) (xy 53.190213 -389.699768) (xy 53.151427 -389.727975) (xy 53.108708 -389.749772)
			(xy 53.063107 -389.764623) (xy 53.015745 -389.772162) (xy 52.991766 -389.772652) (xy 52.991258 -389.772652)
			(xy 52.967687 -389.772184) (xy 52.921104 -389.764953) (xy 52.876188 -389.750638) (xy 52.834011 -389.729581)
			(xy 52.795577 -389.702284) (xy 52.761802 -389.669396) (xy 52.733492 -389.631702) (xy 52.722018 -389.611108)
			(xy 52.72151 -389.610346) (xy 52.323746 -388.922006) (xy 52.311869 -388.89933) (xy 52.295019 -388.850996)
			(xy 52.286446 -388.800533) (xy 52.2859 -388.77494) (xy 51.743906 -388.77494) (xy 52.05603 -389.314944)
			(xy 52.068836 -389.338286) (xy 52.087063 -389.388304) (xy 52.096331 -389.440727) (xy 52.096924 -389.467344)
			(xy 52.096479 -389.491323) (xy 52.088975 -389.53869) (xy 52.074158 -389.584302) (xy 52.052392 -389.627036)
			(xy 52.024214 -389.665843) (xy 51.990315 -389.699767) (xy 51.951529 -389.727974) (xy 51.908811 -389.749771)
			(xy 51.86321 -389.764622) (xy 51.815849 -389.772161) (xy 51.79187 -389.772652) (xy 51.791362 -389.772652)
			(xy 51.767791 -389.772181) (xy 51.721208 -389.76495) (xy 51.676292 -389.750636) (xy 51.634115 -389.72958)
			(xy 51.595681 -389.702283) (xy 51.561907 -389.669396) (xy 51.533596 -389.631702) (xy 51.522122 -389.611108)
			(xy 51.521614 -389.610346) (xy 51.12385 -388.922006) (xy 51.111973 -388.899329) (xy 51.095123 -388.850996)
			(xy 51.08655 -388.800533) (xy 51.086004 -388.77494) (xy 50.543756 -388.77494) (xy 50.85588 -389.314944)
			(xy 50.868601 -389.338268) (xy 50.886698 -389.388213) (xy 50.89592 -389.440529) (xy 50.89652 -389.46709)
			(xy 50.89652 -389.467344) (xy 50.896078 -389.491336) (xy 50.888566 -389.538728) (xy 50.873733 -389.584362)
			(xy 50.851945 -389.627113) (xy 50.823738 -389.665931) (xy 50.789807 -389.699859) (xy 50.750986 -389.728062)
			(xy 50.708232 -389.749845) (xy 50.662597 -389.764673) (xy 50.615204 -389.772181) (xy 50.591212 -389.772652)
			(xy 50.56764 -389.772221) (xy 50.521054 -389.764983) (xy 50.476138 -389.750662) (xy 50.433961 -389.729599)
			(xy 50.395528 -389.702295) (xy 50.361754 -389.669403) (xy 50.333445 -389.631704) (xy 50.321972 -389.611108)
			(xy 50.321464 -389.610346) (xy 49.9237 -388.922006) (xy 49.911785 -388.899338) (xy 49.894847 -388.851012)
			(xy 49.886188 -388.800542) (xy 49.8856 -388.77494) (xy 49.34386 -388.77494) (xy 49.655984 -389.314944)
			(xy 49.668697 -389.338272) (xy 49.686799 -389.388215) (xy 49.696023 -389.44053) (xy 49.696624 -389.46709)
			(xy 49.696624 -389.467344) (xy 49.696178 -389.491336) (xy 49.688666 -389.538727) (xy 49.673833 -389.584361)
			(xy 49.652046 -389.627112) (xy 49.623839 -389.66593) (xy 49.589908 -389.699858) (xy 49.551088 -389.72806)
			(xy 49.508335 -389.749844) (xy 49.4627 -389.764672) (xy 49.415308 -389.77218) (xy 49.391316 -389.772652)
			(xy 49.367744 -389.772218) (xy 49.321159 -389.76498) (xy 49.276242 -389.75066) (xy 49.234065 -389.729597)
			(xy 49.195632 -389.702294) (xy 49.161858 -389.669402) (xy 49.133549 -389.631704) (xy 49.122076 -389.611108)
			(xy 49.121568 -389.610346) (xy 48.723804 -388.922006) (xy 48.711889 -388.899338) (xy 48.694951 -388.851012)
			(xy 48.686292 -388.800542) (xy 48.685704 -388.77494) (xy 48.143964 -388.77494) (xy 48.456088 -389.314944)
			(xy 48.468802 -389.338272) (xy 48.486903 -389.388215) (xy 48.496127 -389.44053) (xy 48.496728 -389.46709)
			(xy 48.496728 -389.467344) (xy 48.496278 -389.491335) (xy 48.488766 -389.538727) (xy 48.473934 -389.58436)
			(xy 48.452147 -389.627111) (xy 48.423941 -389.665928) (xy 48.39001 -389.699856) (xy 48.351191 -389.728059)
			(xy 48.308437 -389.749843) (xy 48.262803 -389.764672) (xy 48.215411 -389.77218) (xy 48.19142 -389.772652)
			(xy 48.167848 -389.772215) (xy 48.121263 -389.764978) (xy 48.076347 -389.750658) (xy 48.03417 -389.729595)
			(xy 47.995736 -389.702293) (xy 47.961962 -389.669402) (xy 47.933653 -389.631704) (xy 47.92218 -389.611108)
			(xy 47.921672 -389.610346) (xy 47.523908 -388.922006) (xy 47.511993 -388.899337) (xy 47.495055 -388.851012)
			(xy 47.486396 -388.800542) (xy 47.485808 -388.77494) (xy 2.509012 -388.77494) (xy 2.509012 -393.292838)
			(xy 47.435008 -393.292838) (xy 47.435008 -392.429238) (xy 47.435494 -392.401987) (xy 47.44325 -392.348039)
			(xy 47.458605 -392.295744) (xy 47.481247 -392.246167) (xy 47.510713 -392.200317) (xy 47.546404 -392.159126)
			(xy 47.587595 -392.123435) (xy 47.633445 -392.093969) (xy 47.683022 -392.071327) (xy 47.735317 -392.055972)
			(xy 47.789265 -392.048216) (xy 47.843767 -392.048216) (xy 47.897715 -392.055972) (xy 47.95001 -392.071327)
			(xy 47.999587 -392.093969) (xy 48.045437 -392.123435) (xy 48.086628 -392.159126) (xy 48.122319 -392.200317)
			(xy 48.151785 -392.246167) (xy 48.174427 -392.295744) (xy 48.189782 -392.348039) (xy 48.197538 -392.401987)
			(xy 48.198024 -392.429238) (xy 48.198024 -393.292838) (xy 48.634904 -393.292838) (xy 48.634904 -392.429238)
			(xy 48.63539 -392.401987) (xy 48.643146 -392.348039) (xy 48.658501 -392.295744) (xy 48.681143 -392.246167)
			(xy 48.710609 -392.200317) (xy 48.7463 -392.159126) (xy 48.787491 -392.123435) (xy 48.833341 -392.093969)
			(xy 48.882918 -392.071327) (xy 48.935213 -392.055972) (xy 48.989161 -392.048216) (xy 49.043663 -392.048216)
			(xy 49.097611 -392.055972) (xy 49.149906 -392.071327) (xy 49.199483 -392.093969) (xy 49.245333 -392.123435)
			(xy 49.286524 -392.159126) (xy 49.322215 -392.200317) (xy 49.351681 -392.246167) (xy 49.374323 -392.295744)
			(xy 49.389678 -392.348039) (xy 49.397434 -392.401987) (xy 49.39792 -392.429238) (xy 49.39792 -393.292838)
			(xy 49.8348 -393.292838) (xy 49.8348 -392.429238) (xy 49.835286 -392.401969) (xy 49.843048 -392.347985)
			(xy 49.858413 -392.295655) (xy 49.88107 -392.246045) (xy 49.910556 -392.200164) (xy 49.946271 -392.158947)
			(xy 49.987488 -392.123232) (xy 50.033369 -392.093746) (xy 50.082979 -392.071089) (xy 50.135309 -392.055724)
			(xy 50.189293 -392.047962) (xy 50.243831 -392.047962) (xy 50.297815 -392.055724) (xy 50.350145 -392.071089)
			(xy 50.399755 -392.093746) (xy 50.445636 -392.123232) (xy 50.486853 -392.158947) (xy 50.522568 -392.200164)
			(xy 50.552054 -392.246045) (xy 50.574711 -392.295655) (xy 50.590076 -392.347985) (xy 50.597838 -392.401969)
			(xy 50.598324 -392.429238) (xy 50.598324 -393.292838) (xy 51.034696 -393.292838) (xy 51.034696 -392.429238)
			(xy 51.035182 -392.401969) (xy 51.042944 -392.347985) (xy 51.058309 -392.295655) (xy 51.080966 -392.246045)
			(xy 51.110452 -392.200164) (xy 51.146167 -392.158947) (xy 51.187384 -392.123232) (xy 51.233265 -392.093746)
			(xy 51.282875 -392.071089) (xy 51.335205 -392.055724) (xy 51.389189 -392.047962) (xy 51.443727 -392.047962)
			(xy 51.497711 -392.055724) (xy 51.550041 -392.071089) (xy 51.599651 -392.093746) (xy 51.645532 -392.123232)
			(xy 51.686749 -392.158947) (xy 51.722464 -392.200164) (xy 51.75195 -392.246045) (xy 51.774607 -392.295655)
			(xy 51.789972 -392.347985) (xy 51.797734 -392.401969) (xy 51.79822 -392.429238) (xy 51.79822 -393.292838)
			(xy 52.2351 -393.292838) (xy 52.2351 -392.429238) (xy 52.235586 -392.401987) (xy 52.243342 -392.348039)
			(xy 52.258697 -392.295744) (xy 52.281339 -392.246167) (xy 52.310805 -392.200317) (xy 52.346496 -392.159126)
			(xy 52.387687 -392.123435) (xy 52.433537 -392.093969) (xy 52.483114 -392.071327) (xy 52.535409 -392.055972)
			(xy 52.589357 -392.048216) (xy 52.643859 -392.048216) (xy 52.697807 -392.055972) (xy 52.750102 -392.071327)
			(xy 52.799679 -392.093969) (xy 52.845529 -392.123435) (xy 52.88672 -392.159126) (xy 52.922411 -392.200317)
			(xy 52.951877 -392.246167) (xy 52.974519 -392.295744) (xy 52.989874 -392.348039) (xy 52.99763 -392.401987)
			(xy 52.998116 -392.429238) (xy 52.998116 -393.292838) (xy 53.434996 -393.292838) (xy 53.434996 -392.429238)
			(xy 53.435482 -392.401987) (xy 53.443238 -392.348039) (xy 53.458593 -392.295744) (xy 53.481235 -392.246167)
			(xy 53.510701 -392.200317) (xy 53.546392 -392.159126) (xy 53.587583 -392.123435) (xy 53.633433 -392.093969)
			(xy 53.68301 -392.071327) (xy 53.735305 -392.055972) (xy 53.789253 -392.048216) (xy 53.843755 -392.048216)
			(xy 53.897703 -392.055972) (xy 53.949998 -392.071327) (xy 53.999575 -392.093969) (xy 54.045425 -392.123435)
			(xy 54.086616 -392.159126) (xy 54.122307 -392.200317) (xy 54.151773 -392.246167) (xy 54.174415 -392.295744)
			(xy 54.18977 -392.348039) (xy 54.197526 -392.401987) (xy 54.198012 -392.429238) (xy 54.198012 -393.292838)
			(xy 54.634892 -393.292838) (xy 54.634892 -392.429238) (xy 54.635378 -392.401969) (xy 54.64314 -392.347985)
			(xy 54.658505 -392.295655) (xy 54.681162 -392.246045) (xy 54.710648 -392.200164) (xy 54.746363 -392.158947)
			(xy 54.78758 -392.123232) (xy 54.833461 -392.093746) (xy 54.883071 -392.071089) (xy 54.935401 -392.055724)
			(xy 54.989385 -392.047962) (xy 55.043923 -392.047962) (xy 55.097907 -392.055724) (xy 55.150237 -392.071089)
			(xy 55.199847 -392.093746) (xy 55.245728 -392.123232) (xy 55.286945 -392.158947) (xy 55.32266 -392.200164)
			(xy 55.352146 -392.246045) (xy 55.374803 -392.295655) (xy 55.390168 -392.347985) (xy 55.39793 -392.401969)
			(xy 55.398416 -392.429238) (xy 55.398416 -393.292838) (xy 55.834788 -393.292838) (xy 55.834788 -392.429238)
			(xy 55.835274 -392.401969) (xy 55.843036 -392.347985) (xy 55.858401 -392.295655) (xy 55.881058 -392.246045)
			(xy 55.910544 -392.200164) (xy 55.946259 -392.158947) (xy 55.987476 -392.123232) (xy 56.033357 -392.093746)
			(xy 56.082967 -392.071089) (xy 56.135297 -392.055724) (xy 56.189281 -392.047962) (xy 56.243819 -392.047962)
			(xy 56.297803 -392.055724) (xy 56.350133 -392.071089) (xy 56.399743 -392.093746) (xy 56.445624 -392.123232)
			(xy 56.486841 -392.158947) (xy 56.522556 -392.200164) (xy 56.552042 -392.246045) (xy 56.574699 -392.295655)
			(xy 56.590064 -392.347985) (xy 56.597826 -392.401969) (xy 56.598312 -392.429238) (xy 56.598312 -393.292838)
			(xy 57.035192 -393.292838) (xy 57.035192 -392.429238) (xy 57.035678 -392.401987) (xy 57.043434 -392.348039)
			(xy 57.058789 -392.295744) (xy 57.081431 -392.246167) (xy 57.110897 -392.200317) (xy 57.146588 -392.159126)
			(xy 57.187779 -392.123435) (xy 57.233629 -392.093969) (xy 57.283206 -392.071327) (xy 57.335501 -392.055972)
			(xy 57.389449 -392.048216) (xy 57.443951 -392.048216) (xy 57.497899 -392.055972) (xy 57.550194 -392.071327)
			(xy 57.599771 -392.093969) (xy 57.645621 -392.123435) (xy 57.686812 -392.159126) (xy 57.722503 -392.200317)
			(xy 57.751969 -392.246167) (xy 57.774611 -392.295744) (xy 57.789966 -392.348039) (xy 57.797722 -392.401987)
			(xy 57.798208 -392.429238) (xy 57.798208 -393.292838) (xy 58.235088 -393.292838) (xy 58.235088 -392.429238)
			(xy 58.235574 -392.401987) (xy 58.24333 -392.348039) (xy 58.258685 -392.295744) (xy 58.281327 -392.246167)
			(xy 58.310793 -392.200317) (xy 58.346484 -392.159126) (xy 58.387675 -392.123435) (xy 58.433525 -392.093969)
			(xy 58.483102 -392.071327) (xy 58.535397 -392.055972) (xy 58.589345 -392.048216) (xy 58.643847 -392.048216)
			(xy 58.697795 -392.055972) (xy 58.75009 -392.071327) (xy 58.799667 -392.093969) (xy 58.845517 -392.123435)
			(xy 58.886708 -392.159126) (xy 58.922399 -392.200317) (xy 58.951865 -392.246167) (xy 58.974507 -392.295744)
			(xy 58.989862 -392.348039) (xy 58.997618 -392.401987) (xy 58.998104 -392.429238) (xy 58.998104 -393.292838)
			(xy 59.434984 -393.292838) (xy 59.434984 -392.429238) (xy 59.43547 -392.401969) (xy 59.443232 -392.347985)
			(xy 59.458597 -392.295655) (xy 59.481254 -392.246045) (xy 59.51074 -392.200164) (xy 59.546455 -392.158947)
			(xy 59.587672 -392.123232) (xy 59.633553 -392.093746) (xy 59.683163 -392.071089) (xy 59.735493 -392.055724)
			(xy 59.789477 -392.047962) (xy 59.844015 -392.047962) (xy 59.897999 -392.055724) (xy 59.950329 -392.071089)
			(xy 59.999939 -392.093746) (xy 60.04582 -392.123232) (xy 60.087037 -392.158947) (xy 60.122752 -392.200164)
			(xy 60.152238 -392.246045) (xy 60.174895 -392.295655) (xy 60.19026 -392.347985) (xy 60.198022 -392.401969)
			(xy 60.198508 -392.429238) (xy 60.198508 -393.292838) (xy 60.63488 -393.292838) (xy 60.63488 -392.429238)
			(xy 60.635366 -392.401969) (xy 60.643128 -392.347985) (xy 60.658493 -392.295655) (xy 60.68115 -392.246045)
			(xy 60.710636 -392.200164) (xy 60.746351 -392.158947) (xy 60.787568 -392.123232) (xy 60.833449 -392.093746)
			(xy 60.883059 -392.071089) (xy 60.935389 -392.055724) (xy 60.989373 -392.047962) (xy 61.043911 -392.047962)
			(xy 61.097895 -392.055724) (xy 61.150225 -392.071089) (xy 61.199835 -392.093746) (xy 61.245716 -392.123232)
			(xy 61.286933 -392.158947) (xy 61.322648 -392.200164) (xy 61.352134 -392.246045) (xy 61.374791 -392.295655)
			(xy 61.390156 -392.347985) (xy 61.397918 -392.401969) (xy 61.398404 -392.429238) (xy 61.398404 -393.292838)
			(xy 61.834776 -393.292838) (xy 61.834776 -392.429238) (xy 61.835262 -392.401969) (xy 61.843024 -392.347985)
			(xy 61.858389 -392.295655) (xy 61.881046 -392.246045) (xy 61.910532 -392.200164) (xy 61.946247 -392.158947)
			(xy 61.987464 -392.123232) (xy 62.033345 -392.093746) (xy 62.082955 -392.071089) (xy 62.135285 -392.055724)
			(xy 62.189269 -392.047962) (xy 62.243807 -392.047962) (xy 62.297791 -392.055724) (xy 62.350121 -392.071089)
			(xy 62.399731 -392.093746) (xy 62.445612 -392.123232) (xy 62.486829 -392.158947) (xy 62.522544 -392.200164)
			(xy 62.55203 -392.246045) (xy 62.574687 -392.295655) (xy 62.590052 -392.347985) (xy 62.597814 -392.401969)
			(xy 62.5983 -392.429238) (xy 62.5983 -393.292838) (xy 63.034672 -393.292838) (xy 63.034672 -392.429238)
			(xy 63.035158 -392.401969) (xy 63.04292 -392.347985) (xy 63.058285 -392.295655) (xy 63.080942 -392.246045)
			(xy 63.110428 -392.200164) (xy 63.146143 -392.158947) (xy 63.18736 -392.123232) (xy 63.233241 -392.093746)
			(xy 63.282851 -392.071089) (xy 63.335181 -392.055724) (xy 63.389165 -392.047962) (xy 63.443703 -392.047962)
			(xy 63.497687 -392.055724) (xy 63.550017 -392.071089) (xy 63.599627 -392.093746) (xy 63.645508 -392.123232)
			(xy 63.686725 -392.158947) (xy 63.72244 -392.200164) (xy 63.751926 -392.246045) (xy 63.774583 -392.295655)
			(xy 63.789948 -392.347985) (xy 63.79771 -392.401969) (xy 63.798196 -392.429238) (xy 63.798196 -393.292838)
			(xy 64.235076 -393.292838) (xy 64.235076 -392.429238) (xy 64.235562 -392.401987) (xy 64.243318 -392.348039)
			(xy 64.258673 -392.295744) (xy 64.281315 -392.246167) (xy 64.310781 -392.200317) (xy 64.346472 -392.159126)
			(xy 64.387663 -392.123435) (xy 64.433513 -392.093969) (xy 64.48309 -392.071327) (xy 64.535385 -392.055972)
			(xy 64.589333 -392.048216) (xy 64.643835 -392.048216) (xy 64.697783 -392.055972) (xy 64.750078 -392.071327)
			(xy 64.799655 -392.093969) (xy 64.845505 -392.123435) (xy 64.886696 -392.159126) (xy 64.922387 -392.200317)
			(xy 64.951853 -392.246167) (xy 64.974495 -392.295744) (xy 64.98985 -392.348039) (xy 64.997606 -392.401987)
			(xy 64.998092 -392.429238) (xy 64.998092 -393.292838) (xy 65.434972 -393.292838) (xy 65.434972 -392.429238)
			(xy 65.435458 -392.401987) (xy 65.443214 -392.348039) (xy 65.458569 -392.295744) (xy 65.481211 -392.246167)
			(xy 65.510677 -392.200317) (xy 65.546368 -392.159126) (xy 65.587559 -392.123435) (xy 65.633409 -392.093969)
			(xy 65.682986 -392.071327) (xy 65.735281 -392.055972) (xy 65.789229 -392.048216) (xy 65.843731 -392.048216)
			(xy 65.897679 -392.055972) (xy 65.949974 -392.071327) (xy 65.999551 -392.093969) (xy 66.045401 -392.123435)
			(xy 66.086592 -392.159126) (xy 66.122283 -392.200317) (xy 66.151749 -392.246167) (xy 66.174391 -392.295744)
			(xy 66.189746 -392.348039) (xy 66.197502 -392.401987) (xy 66.197988 -392.429238) (xy 66.197988 -393.292838)
			(xy 79.962756 -393.292838) (xy 79.962756 -392.429238) (xy 79.963242 -392.401987) (xy 79.970998 -392.348039)
			(xy 79.986353 -392.295744) (xy 80.008995 -392.246167) (xy 80.038461 -392.200317) (xy 80.074152 -392.159126)
			(xy 80.115343 -392.123435) (xy 80.161193 -392.093969) (xy 80.21077 -392.071327) (xy 80.263065 -392.055972)
			(xy 80.317013 -392.048216) (xy 80.371515 -392.048216) (xy 80.425463 -392.055972) (xy 80.477758 -392.071327)
			(xy 80.527335 -392.093969) (xy 80.573185 -392.123435) (xy 80.614376 -392.159126) (xy 80.650067 -392.200317)
			(xy 80.679533 -392.246167) (xy 80.702175 -392.295744) (xy 80.71753 -392.348039) (xy 80.725286 -392.401987)
			(xy 80.725772 -392.429238) (xy 80.725772 -393.292838) (xy 81.162652 -393.292838) (xy 81.162652 -392.429238)
			(xy 81.163138 -392.401987) (xy 81.170894 -392.348039) (xy 81.186249 -392.295744) (xy 81.208891 -392.246167)
			(xy 81.238357 -392.200317) (xy 81.274048 -392.159126) (xy 81.315239 -392.123435) (xy 81.361089 -392.093969)
			(xy 81.410666 -392.071327) (xy 81.462961 -392.055972) (xy 81.516909 -392.048216) (xy 81.571411 -392.048216)
			(xy 81.625359 -392.055972) (xy 81.677654 -392.071327) (xy 81.727231 -392.093969) (xy 81.773081 -392.123435)
			(xy 81.814272 -392.159126) (xy 81.849963 -392.200317) (xy 81.879429 -392.246167) (xy 81.902071 -392.295744)
			(xy 81.917426 -392.348039) (xy 81.925182 -392.401987) (xy 81.925668 -392.429238) (xy 81.925668 -393.292838)
			(xy 82.362548 -393.292838) (xy 82.362548 -392.429238) (xy 82.363034 -392.401969) (xy 82.370796 -392.347985)
			(xy 82.386161 -392.295655) (xy 82.408818 -392.246045) (xy 82.438304 -392.200164) (xy 82.474019 -392.158947)
			(xy 82.515236 -392.123232) (xy 82.561117 -392.093746) (xy 82.610727 -392.071089) (xy 82.663057 -392.055724)
			(xy 82.717041 -392.047962) (xy 82.771579 -392.047962) (xy 82.825563 -392.055724) (xy 82.877893 -392.071089)
			(xy 82.927503 -392.093746) (xy 82.973384 -392.123232) (xy 83.014601 -392.158947) (xy 83.050316 -392.200164)
			(xy 83.079802 -392.246045) (xy 83.102459 -392.295655) (xy 83.117824 -392.347985) (xy 83.125586 -392.401969)
			(xy 83.126072 -392.429238) (xy 83.126072 -393.292838) (xy 83.562444 -393.292838) (xy 83.562444 -392.429238)
			(xy 83.56293 -392.401969) (xy 83.570692 -392.347985) (xy 83.586057 -392.295655) (xy 83.608714 -392.246045)
			(xy 83.6382 -392.200164) (xy 83.673915 -392.158947) (xy 83.715132 -392.123232) (xy 83.761013 -392.093746)
			(xy 83.810623 -392.071089) (xy 83.862953 -392.055724) (xy 83.916937 -392.047962) (xy 83.971475 -392.047962)
			(xy 84.025459 -392.055724) (xy 84.077789 -392.071089) (xy 84.127399 -392.093746) (xy 84.17328 -392.123232)
			(xy 84.214497 -392.158947) (xy 84.250212 -392.200164) (xy 84.279698 -392.246045) (xy 84.302355 -392.295655)
			(xy 84.31772 -392.347985) (xy 84.325482 -392.401969) (xy 84.325968 -392.429238) (xy 84.325968 -393.292838)
			(xy 84.762848 -393.292838) (xy 84.762848 -392.429238) (xy 84.763334 -392.401987) (xy 84.77109 -392.348039)
			(xy 84.786445 -392.295744) (xy 84.809087 -392.246167) (xy 84.838553 -392.200317) (xy 84.874244 -392.159126)
			(xy 84.915435 -392.123435) (xy 84.961285 -392.093969) (xy 85.010862 -392.071327) (xy 85.063157 -392.055972)
			(xy 85.117105 -392.048216) (xy 85.171607 -392.048216) (xy 85.225555 -392.055972) (xy 85.27785 -392.071327)
			(xy 85.327427 -392.093969) (xy 85.373277 -392.123435) (xy 85.414468 -392.159126) (xy 85.450159 -392.200317)
			(xy 85.479625 -392.246167) (xy 85.502267 -392.295744) (xy 85.517622 -392.348039) (xy 85.525378 -392.401987)
			(xy 85.525864 -392.429238) (xy 85.525864 -393.292838) (xy 85.962744 -393.292838) (xy 85.962744 -392.429238)
			(xy 85.96323 -392.401987) (xy 85.970986 -392.348039) (xy 85.986341 -392.295744) (xy 86.008983 -392.246167)
			(xy 86.038449 -392.200317) (xy 86.07414 -392.159126) (xy 86.115331 -392.123435) (xy 86.161181 -392.093969)
			(xy 86.210758 -392.071327) (xy 86.263053 -392.055972) (xy 86.317001 -392.048216) (xy 86.371503 -392.048216)
			(xy 86.425451 -392.055972) (xy 86.477746 -392.071327) (xy 86.527323 -392.093969) (xy 86.573173 -392.123435)
			(xy 86.614364 -392.159126) (xy 86.650055 -392.200317) (xy 86.679521 -392.246167) (xy 86.702163 -392.295744)
			(xy 86.717518 -392.348039) (xy 86.725274 -392.401987) (xy 86.72576 -392.429238) (xy 86.72576 -393.292838)
			(xy 87.16264 -393.292838) (xy 87.16264 -392.429238) (xy 87.163126 -392.401969) (xy 87.170888 -392.347985)
			(xy 87.186253 -392.295655) (xy 87.20891 -392.246045) (xy 87.238396 -392.200164) (xy 87.274111 -392.158947)
			(xy 87.315328 -392.123232) (xy 87.361209 -392.093746) (xy 87.410819 -392.071089) (xy 87.463149 -392.055724)
			(xy 87.517133 -392.047962) (xy 87.571671 -392.047962) (xy 87.625655 -392.055724) (xy 87.677985 -392.071089)
			(xy 87.727595 -392.093746) (xy 87.773476 -392.123232) (xy 87.814693 -392.158947) (xy 87.850408 -392.200164)
			(xy 87.879894 -392.246045) (xy 87.902551 -392.295655) (xy 87.917916 -392.347985) (xy 87.925678 -392.401969)
			(xy 87.926164 -392.429238) (xy 87.926164 -393.292838) (xy 88.362536 -393.292838) (xy 88.362536 -392.429238)
			(xy 88.363022 -392.401969) (xy 88.370784 -392.347985) (xy 88.386149 -392.295655) (xy 88.408806 -392.246045)
			(xy 88.438292 -392.200164) (xy 88.474007 -392.158947) (xy 88.515224 -392.123232) (xy 88.561105 -392.093746)
			(xy 88.610715 -392.071089) (xy 88.663045 -392.055724) (xy 88.717029 -392.047962) (xy 88.771567 -392.047962)
			(xy 88.825551 -392.055724) (xy 88.877881 -392.071089) (xy 88.927491 -392.093746) (xy 88.973372 -392.123232)
			(xy 89.014589 -392.158947) (xy 89.050304 -392.200164) (xy 89.07979 -392.246045) (xy 89.102447 -392.295655)
			(xy 89.117812 -392.347985) (xy 89.125574 -392.401969) (xy 89.12606 -392.429238) (xy 89.12606 -393.292838)
			(xy 89.56294 -393.292838) (xy 89.56294 -392.429238) (xy 89.563426 -392.401987) (xy 89.571182 -392.348039)
			(xy 89.586537 -392.295744) (xy 89.609179 -392.246167) (xy 89.638645 -392.200317) (xy 89.674336 -392.159126)
			(xy 89.715527 -392.123435) (xy 89.761377 -392.093969) (xy 89.810954 -392.071327) (xy 89.863249 -392.055972)
			(xy 89.917197 -392.048216) (xy 89.971699 -392.048216) (xy 90.025647 -392.055972) (xy 90.077942 -392.071327)
			(xy 90.127519 -392.093969) (xy 90.173369 -392.123435) (xy 90.21456 -392.159126) (xy 90.250251 -392.200317)
			(xy 90.279717 -392.246167) (xy 90.302359 -392.295744) (xy 90.317714 -392.348039) (xy 90.32547 -392.401987)
			(xy 90.325956 -392.429238) (xy 90.325956 -393.292838) (xy 90.762836 -393.292838) (xy 90.762836 -392.429238)
			(xy 90.763322 -392.401987) (xy 90.771078 -392.348039) (xy 90.786433 -392.295744) (xy 90.809075 -392.246167)
			(xy 90.838541 -392.200317) (xy 90.874232 -392.159126) (xy 90.915423 -392.123435) (xy 90.961273 -392.093969)
			(xy 91.01085 -392.071327) (xy 91.063145 -392.055972) (xy 91.117093 -392.048216) (xy 91.171595 -392.048216)
			(xy 91.225543 -392.055972) (xy 91.277838 -392.071327) (xy 91.327415 -392.093969) (xy 91.373265 -392.123435)
			(xy 91.414456 -392.159126) (xy 91.450147 -392.200317) (xy 91.479613 -392.246167) (xy 91.502255 -392.295744)
			(xy 91.51761 -392.348039) (xy 91.525366 -392.401987) (xy 91.525852 -392.429238) (xy 91.525852 -393.292838)
			(xy 91.962732 -393.292838) (xy 91.962732 -392.429238) (xy 91.963218 -392.401969) (xy 91.97098 -392.347985)
			(xy 91.986345 -392.295655) (xy 92.009002 -392.246045) (xy 92.038488 -392.200164) (xy 92.074203 -392.158947)
			(xy 92.11542 -392.123232) (xy 92.161301 -392.093746) (xy 92.210911 -392.071089) (xy 92.263241 -392.055724)
			(xy 92.317225 -392.047962) (xy 92.371763 -392.047962) (xy 92.425747 -392.055724) (xy 92.478077 -392.071089)
			(xy 92.527687 -392.093746) (xy 92.573568 -392.123232) (xy 92.614785 -392.158947) (xy 92.6505 -392.200164)
			(xy 92.679986 -392.246045) (xy 92.702643 -392.295655) (xy 92.718008 -392.347985) (xy 92.72577 -392.401969)
			(xy 92.726256 -392.429238) (xy 92.726256 -393.292838) (xy 93.162628 -393.292838) (xy 93.162628 -392.429238)
			(xy 93.163114 -392.401969) (xy 93.170876 -392.347985) (xy 93.186241 -392.295655) (xy 93.208898 -392.246045)
			(xy 93.238384 -392.200164) (xy 93.274099 -392.158947) (xy 93.315316 -392.123232) (xy 93.361197 -392.093746)
			(xy 93.410807 -392.071089) (xy 93.463137 -392.055724) (xy 93.517121 -392.047962) (xy 93.571659 -392.047962)
			(xy 93.625643 -392.055724) (xy 93.677973 -392.071089) (xy 93.727583 -392.093746) (xy 93.773464 -392.123232)
			(xy 93.814681 -392.158947) (xy 93.850396 -392.200164) (xy 93.879882 -392.246045) (xy 93.902539 -392.295655)
			(xy 93.917904 -392.347985) (xy 93.925666 -392.401969) (xy 93.926152 -392.429238) (xy 93.926152 -393.292838)
			(xy 94.362524 -393.292838) (xy 94.362524 -392.429238) (xy 94.36301 -392.401969) (xy 94.370772 -392.347985)
			(xy 94.386137 -392.295655) (xy 94.408794 -392.246045) (xy 94.43828 -392.200164) (xy 94.473995 -392.158947)
			(xy 94.515212 -392.123232) (xy 94.561093 -392.093746) (xy 94.610703 -392.071089) (xy 94.663033 -392.055724)
			(xy 94.717017 -392.047962) (xy 94.771555 -392.047962) (xy 94.825539 -392.055724) (xy 94.877869 -392.071089)
			(xy 94.927479 -392.093746) (xy 94.97336 -392.123232) (xy 95.014577 -392.158947) (xy 95.050292 -392.200164)
			(xy 95.079778 -392.246045) (xy 95.102435 -392.295655) (xy 95.1178 -392.347985) (xy 95.125562 -392.401969)
			(xy 95.126048 -392.429238) (xy 95.126048 -393.292838) (xy 95.56242 -393.292838) (xy 95.56242 -392.429238)
			(xy 95.562906 -392.401969) (xy 95.570668 -392.347985) (xy 95.586033 -392.295655) (xy 95.60869 -392.246045)
			(xy 95.638176 -392.200164) (xy 95.673891 -392.158947) (xy 95.715108 -392.123232) (xy 95.760989 -392.093746)
			(xy 95.810599 -392.071089) (xy 95.862929 -392.055724) (xy 95.916913 -392.047962) (xy 95.971451 -392.047962)
			(xy 96.025435 -392.055724) (xy 96.077765 -392.071089) (xy 96.127375 -392.093746) (xy 96.173256 -392.123232)
			(xy 96.214473 -392.158947) (xy 96.250188 -392.200164) (xy 96.279674 -392.246045) (xy 96.302331 -392.295655)
			(xy 96.317696 -392.347985) (xy 96.325458 -392.401969) (xy 96.325944 -392.429238) (xy 96.325944 -393.292838)
			(xy 96.762824 -393.292838) (xy 96.762824 -392.429238) (xy 96.76331 -392.401987) (xy 96.771066 -392.348039)
			(xy 96.786421 -392.295744) (xy 96.809063 -392.246167) (xy 96.838529 -392.200317) (xy 96.87422 -392.159126)
			(xy 96.915411 -392.123435) (xy 96.961261 -392.093969) (xy 97.010838 -392.071327) (xy 97.063133 -392.055972)
			(xy 97.117081 -392.048216) (xy 97.171583 -392.048216) (xy 97.225531 -392.055972) (xy 97.277826 -392.071327)
			(xy 97.327403 -392.093969) (xy 97.373253 -392.123435) (xy 97.414444 -392.159126) (xy 97.450135 -392.200317)
			(xy 97.479601 -392.246167) (xy 97.502243 -392.295744) (xy 97.517598 -392.348039) (xy 97.525354 -392.401987)
			(xy 97.52584 -392.429238) (xy 97.52584 -393.292838) (xy 97.96272 -393.292838) (xy 97.96272 -392.429238)
			(xy 97.963206 -392.401987) (xy 97.970962 -392.348039) (xy 97.986317 -392.295744) (xy 98.008959 -392.246167)
			(xy 98.038425 -392.200317) (xy 98.074116 -392.159126) (xy 98.115307 -392.123435) (xy 98.161157 -392.093969)
			(xy 98.210734 -392.071327) (xy 98.263029 -392.055972) (xy 98.316977 -392.048216) (xy 98.371479 -392.048216)
			(xy 98.425427 -392.055972) (xy 98.477722 -392.071327) (xy 98.527299 -392.093969) (xy 98.573149 -392.123435)
			(xy 98.61434 -392.159126) (xy 98.650031 -392.200317) (xy 98.679497 -392.246167) (xy 98.702139 -392.295744)
			(xy 98.717494 -392.348039) (xy 98.72525 -392.401987) (xy 98.725736 -392.429238) (xy 98.725736 -393.292838)
			(xy 114.534696 -393.292838) (xy 114.534696 -392.429238) (xy 114.535182 -392.401969) (xy 114.542944 -392.347985)
			(xy 114.558309 -392.295655) (xy 114.580966 -392.246045) (xy 114.610452 -392.200164) (xy 114.646167 -392.158947)
			(xy 114.687384 -392.123232) (xy 114.733265 -392.093746) (xy 114.782875 -392.071089) (xy 114.835205 -392.055724)
			(xy 114.889189 -392.047962) (xy 114.943727 -392.047962) (xy 114.997711 -392.055724) (xy 115.050041 -392.071089)
			(xy 115.099651 -392.093746) (xy 115.145532 -392.123232) (xy 115.186749 -392.158947) (xy 115.222464 -392.200164)
			(xy 115.25195 -392.246045) (xy 115.274607 -392.295655) (xy 115.289972 -392.347985) (xy 115.297734 -392.401969)
			(xy 115.29822 -392.429238) (xy 115.29822 -393.292838) (xy 115.734592 -393.292838) (xy 115.734592 -392.429238)
			(xy 115.735078 -392.401969) (xy 115.74284 -392.347985) (xy 115.758205 -392.295655) (xy 115.780862 -392.246045)
			(xy 115.810348 -392.200164) (xy 115.846063 -392.158947) (xy 115.88728 -392.123232) (xy 115.933161 -392.093746)
			(xy 115.982771 -392.071089) (xy 116.035101 -392.055724) (xy 116.089085 -392.047962) (xy 116.143623 -392.047962)
			(xy 116.197607 -392.055724) (xy 116.249937 -392.071089) (xy 116.299547 -392.093746) (xy 116.345428 -392.123232)
			(xy 116.386645 -392.158947) (xy 116.42236 -392.200164) (xy 116.451846 -392.246045) (xy 116.474503 -392.295655)
			(xy 116.489868 -392.347985) (xy 116.49763 -392.401969) (xy 116.498116 -392.429238) (xy 116.498116 -393.292838)
			(xy 116.934996 -393.292838) (xy 116.934996 -392.429238) (xy 116.935482 -392.401987) (xy 116.943238 -392.348039)
			(xy 116.958593 -392.295744) (xy 116.981235 -392.246167) (xy 117.010701 -392.200317) (xy 117.046392 -392.159126)
			(xy 117.087583 -392.123435) (xy 117.133433 -392.093969) (xy 117.18301 -392.071327) (xy 117.235305 -392.055972)
			(xy 117.289253 -392.048216) (xy 117.343755 -392.048216) (xy 117.397703 -392.055972) (xy 117.449998 -392.071327)
			(xy 117.499575 -392.093969) (xy 117.545425 -392.123435) (xy 117.586616 -392.159126) (xy 117.622307 -392.200317)
			(xy 117.651773 -392.246167) (xy 117.674415 -392.295744) (xy 117.68977 -392.348039) (xy 117.697526 -392.401987)
			(xy 117.698012 -392.429238) (xy 117.698012 -393.292838) (xy 118.134892 -393.292838) (xy 118.134892 -392.429238)
			(xy 118.135378 -392.401987) (xy 118.143134 -392.348039) (xy 118.158489 -392.295744) (xy 118.181131 -392.246167)
			(xy 118.210597 -392.200317) (xy 118.246288 -392.159126) (xy 118.287479 -392.123435) (xy 118.333329 -392.093969)
			(xy 118.382906 -392.071327) (xy 118.435201 -392.055972) (xy 118.489149 -392.048216) (xy 118.543651 -392.048216)
			(xy 118.597599 -392.055972) (xy 118.649894 -392.071327) (xy 118.699471 -392.093969) (xy 118.745321 -392.123435)
			(xy 118.786512 -392.159126) (xy 118.822203 -392.200317) (xy 118.851669 -392.246167) (xy 118.874311 -392.295744)
			(xy 118.889666 -392.348039) (xy 118.897422 -392.401987) (xy 118.897908 -392.429238) (xy 118.897908 -393.292838)
			(xy 119.334788 -393.292838) (xy 119.334788 -392.429238) (xy 119.335274 -392.401969) (xy 119.343036 -392.347985)
			(xy 119.358401 -392.295655) (xy 119.381058 -392.246045) (xy 119.410544 -392.200164) (xy 119.446259 -392.158947)
			(xy 119.487476 -392.123232) (xy 119.533357 -392.093746) (xy 119.582967 -392.071089) (xy 119.635297 -392.055724)
			(xy 119.689281 -392.047962) (xy 119.743819 -392.047962) (xy 119.797803 -392.055724) (xy 119.850133 -392.071089)
			(xy 119.899743 -392.093746) (xy 119.945624 -392.123232) (xy 119.986841 -392.158947) (xy 120.022556 -392.200164)
			(xy 120.052042 -392.246045) (xy 120.074699 -392.295655) (xy 120.090064 -392.347985) (xy 120.097826 -392.401969)
			(xy 120.098312 -392.429238) (xy 120.098312 -393.292838) (xy 120.534684 -393.292838) (xy 120.534684 -392.429238)
			(xy 120.53517 -392.401969) (xy 120.542932 -392.347985) (xy 120.558297 -392.295655) (xy 120.580954 -392.246045)
			(xy 120.61044 -392.200164) (xy 120.646155 -392.158947) (xy 120.687372 -392.123232) (xy 120.733253 -392.093746)
			(xy 120.782863 -392.071089) (xy 120.835193 -392.055724) (xy 120.889177 -392.047962) (xy 120.943715 -392.047962)
			(xy 120.997699 -392.055724) (xy 121.050029 -392.071089) (xy 121.099639 -392.093746) (xy 121.14552 -392.123232)
			(xy 121.186737 -392.158947) (xy 121.222452 -392.200164) (xy 121.251938 -392.246045) (xy 121.274595 -392.295655)
			(xy 121.28996 -392.347985) (xy 121.297722 -392.401969) (xy 121.298208 -392.429238) (xy 121.298208 -393.292838)
			(xy 121.735088 -393.292838) (xy 121.735088 -392.429238) (xy 121.735574 -392.401987) (xy 121.74333 -392.348039)
			(xy 121.758685 -392.295744) (xy 121.781327 -392.246167) (xy 121.810793 -392.200317) (xy 121.846484 -392.159126)
			(xy 121.887675 -392.123435) (xy 121.933525 -392.093969) (xy 121.983102 -392.071327) (xy 122.035397 -392.055972)
			(xy 122.089345 -392.048216) (xy 122.143847 -392.048216) (xy 122.197795 -392.055972) (xy 122.25009 -392.071327)
			(xy 122.299667 -392.093969) (xy 122.345517 -392.123435) (xy 122.386708 -392.159126) (xy 122.422399 -392.200317)
			(xy 122.451865 -392.246167) (xy 122.474507 -392.295744) (xy 122.489862 -392.348039) (xy 122.497618 -392.401987)
			(xy 122.498104 -392.429238) (xy 122.498104 -393.292838) (xy 122.934984 -393.292838) (xy 122.934984 -392.429238)
			(xy 122.93547 -392.401987) (xy 122.943226 -392.348039) (xy 122.958581 -392.295744) (xy 122.981223 -392.246167)
			(xy 123.010689 -392.200317) (xy 123.04638 -392.159126) (xy 123.087571 -392.123435) (xy 123.133421 -392.093969)
			(xy 123.182998 -392.071327) (xy 123.235293 -392.055972) (xy 123.289241 -392.048216) (xy 123.343743 -392.048216)
			(xy 123.397691 -392.055972) (xy 123.449986 -392.071327) (xy 123.499563 -392.093969) (xy 123.545413 -392.123435)
			(xy 123.586604 -392.159126) (xy 123.622295 -392.200317) (xy 123.651761 -392.246167) (xy 123.674403 -392.295744)
			(xy 123.689758 -392.348039) (xy 123.697514 -392.401987) (xy 123.698 -392.429238) (xy 123.698 -393.292838)
			(xy 124.13488 -393.292838) (xy 124.13488 -392.429238) (xy 124.135366 -392.401969) (xy 124.143128 -392.347985)
			(xy 124.158493 -392.295655) (xy 124.18115 -392.246045) (xy 124.210636 -392.200164) (xy 124.246351 -392.158947)
			(xy 124.287568 -392.123232) (xy 124.333449 -392.093746) (xy 124.383059 -392.071089) (xy 124.435389 -392.055724)
			(xy 124.489373 -392.047962) (xy 124.543911 -392.047962) (xy 124.597895 -392.055724) (xy 124.650225 -392.071089)
			(xy 124.699835 -392.093746) (xy 124.745716 -392.123232) (xy 124.786933 -392.158947) (xy 124.822648 -392.200164)
			(xy 124.852134 -392.246045) (xy 124.874791 -392.295655) (xy 124.890156 -392.347985) (xy 124.897918 -392.401969)
			(xy 124.898404 -392.429238) (xy 124.898404 -393.292838) (xy 125.334776 -393.292838) (xy 125.334776 -392.429238)
			(xy 125.335262 -392.401969) (xy 125.343024 -392.347985) (xy 125.358389 -392.295655) (xy 125.381046 -392.246045)
			(xy 125.410532 -392.200164) (xy 125.446247 -392.158947) (xy 125.487464 -392.123232) (xy 125.533345 -392.093746)
			(xy 125.582955 -392.071089) (xy 125.635285 -392.055724) (xy 125.689269 -392.047962) (xy 125.743807 -392.047962)
			(xy 125.797791 -392.055724) (xy 125.850121 -392.071089) (xy 125.899731 -392.093746) (xy 125.945612 -392.123232)
			(xy 125.986829 -392.158947) (xy 126.022544 -392.200164) (xy 126.05203 -392.246045) (xy 126.074687 -392.295655)
			(xy 126.090052 -392.347985) (xy 126.097814 -392.401969) (xy 126.0983 -392.429238) (xy 126.0983 -393.292838)
			(xy 126.53518 -393.292838) (xy 126.53518 -392.429238) (xy 126.535666 -392.401987) (xy 126.543422 -392.348039)
			(xy 126.558777 -392.295744) (xy 126.581419 -392.246167) (xy 126.610885 -392.200317) (xy 126.646576 -392.159126)
			(xy 126.687767 -392.123435) (xy 126.733617 -392.093969) (xy 126.783194 -392.071327) (xy 126.835489 -392.055972)
			(xy 126.889437 -392.048216) (xy 126.943939 -392.048216) (xy 126.997887 -392.055972) (xy 127.050182 -392.071327)
			(xy 127.099759 -392.093969) (xy 127.145609 -392.123435) (xy 127.1868 -392.159126) (xy 127.222491 -392.200317)
			(xy 127.251957 -392.246167) (xy 127.274599 -392.295744) (xy 127.289954 -392.348039) (xy 127.29771 -392.401987)
			(xy 127.298196 -392.429238) (xy 127.298196 -393.292838) (xy 127.735076 -393.292838) (xy 127.735076 -392.429238)
			(xy 127.735562 -392.401987) (xy 127.743318 -392.348039) (xy 127.758673 -392.295744) (xy 127.781315 -392.246167)
			(xy 127.810781 -392.200317) (xy 127.846472 -392.159126) (xy 127.887663 -392.123435) (xy 127.933513 -392.093969)
			(xy 127.98309 -392.071327) (xy 128.035385 -392.055972) (xy 128.089333 -392.048216) (xy 128.143835 -392.048216)
			(xy 128.197783 -392.055972) (xy 128.250078 -392.071327) (xy 128.299655 -392.093969) (xy 128.345505 -392.123435)
			(xy 128.386696 -392.159126) (xy 128.422387 -392.200317) (xy 128.451853 -392.246167) (xy 128.474495 -392.295744)
			(xy 128.48985 -392.348039) (xy 128.497606 -392.401987) (xy 128.498092 -392.429238) (xy 128.498092 -393.292838)
			(xy 128.934972 -393.292838) (xy 128.934972 -392.429238) (xy 128.935458 -392.401987) (xy 128.943214 -392.348039)
			(xy 128.958569 -392.295744) (xy 128.981211 -392.246167) (xy 129.010677 -392.200317) (xy 129.046368 -392.159126)
			(xy 129.087559 -392.123435) (xy 129.133409 -392.093969) (xy 129.182986 -392.071327) (xy 129.235281 -392.055972)
			(xy 129.289229 -392.048216) (xy 129.343731 -392.048216) (xy 129.397679 -392.055972) (xy 129.449974 -392.071327)
			(xy 129.499551 -392.093969) (xy 129.545401 -392.123435) (xy 129.586592 -392.159126) (xy 129.622283 -392.200317)
			(xy 129.651749 -392.246167) (xy 129.674391 -392.295744) (xy 129.689746 -392.348039) (xy 129.697502 -392.401987)
			(xy 129.697988 -392.429238) (xy 129.697988 -393.292838) (xy 130.134868 -393.292838) (xy 130.134868 -392.429238)
			(xy 130.135354 -392.401987) (xy 130.14311 -392.348039) (xy 130.158465 -392.295744) (xy 130.181107 -392.246167)
			(xy 130.210573 -392.200317) (xy 130.246264 -392.159126) (xy 130.287455 -392.123435) (xy 130.333305 -392.093969)
			(xy 130.382882 -392.071327) (xy 130.435177 -392.055972) (xy 130.489125 -392.048216) (xy 130.543627 -392.048216)
			(xy 130.597575 -392.055972) (xy 130.64987 -392.071327) (xy 130.699447 -392.093969) (xy 130.745297 -392.123435)
			(xy 130.786488 -392.159126) (xy 130.822179 -392.200317) (xy 130.851645 -392.246167) (xy 130.874287 -392.295744)
			(xy 130.889642 -392.348039) (xy 130.897398 -392.401987) (xy 130.897884 -392.429238) (xy 130.897884 -393.292838)
			(xy 131.334764 -393.292838) (xy 131.334764 -392.429238) (xy 131.33525 -392.401969) (xy 131.343012 -392.347985)
			(xy 131.358377 -392.295655) (xy 131.381034 -392.246045) (xy 131.41052 -392.200164) (xy 131.446235 -392.158947)
			(xy 131.487452 -392.123232) (xy 131.533333 -392.093746) (xy 131.582943 -392.071089) (xy 131.635273 -392.055724)
			(xy 131.689257 -392.047962) (xy 131.743795 -392.047962) (xy 131.797779 -392.055724) (xy 131.850109 -392.071089)
			(xy 131.899719 -392.093746) (xy 131.9456 -392.123232) (xy 131.986817 -392.158947) (xy 132.022532 -392.200164)
			(xy 132.052018 -392.246045) (xy 132.074675 -392.295655) (xy 132.09004 -392.347985) (xy 132.097802 -392.401969)
			(xy 132.098288 -392.429238) (xy 132.098288 -393.292838) (xy 132.53466 -393.292838) (xy 132.53466 -392.429238)
			(xy 132.535146 -392.401969) (xy 132.542908 -392.347985) (xy 132.558273 -392.295655) (xy 132.58093 -392.246045)
			(xy 132.610416 -392.200164) (xy 132.646131 -392.158947) (xy 132.687348 -392.123232) (xy 132.733229 -392.093746)
			(xy 132.782839 -392.071089) (xy 132.835169 -392.055724) (xy 132.889153 -392.047962) (xy 132.943691 -392.047962)
			(xy 132.997675 -392.055724) (xy 133.050005 -392.071089) (xy 133.099615 -392.093746) (xy 133.145496 -392.123232)
			(xy 133.186713 -392.158947) (xy 133.222428 -392.200164) (xy 133.251914 -392.246045) (xy 133.274571 -392.295655)
			(xy 133.289936 -392.347985) (xy 133.297698 -392.401969) (xy 133.298184 -392.429238) (xy 133.298184 -393.292838)
			(xy 147.062444 -393.292838) (xy 147.062444 -392.429238) (xy 147.06293 -392.401969) (xy 147.070692 -392.347985)
			(xy 147.086057 -392.295655) (xy 147.108714 -392.246045) (xy 147.1382 -392.200164) (xy 147.173915 -392.158947)
			(xy 147.215132 -392.123232) (xy 147.261013 -392.093746) (xy 147.310623 -392.071089) (xy 147.362953 -392.055724)
			(xy 147.416937 -392.047962) (xy 147.471475 -392.047962) (xy 147.525459 -392.055724) (xy 147.577789 -392.071089)
			(xy 147.627399 -392.093746) (xy 147.67328 -392.123232) (xy 147.714497 -392.158947) (xy 147.750212 -392.200164)
			(xy 147.779698 -392.246045) (xy 147.802355 -392.295655) (xy 147.81772 -392.347985) (xy 147.825482 -392.401969)
			(xy 147.825968 -392.429238) (xy 147.825968 -393.292838) (xy 148.26234 -393.292838) (xy 148.26234 -392.429238)
			(xy 148.262826 -392.401969) (xy 148.270588 -392.347985) (xy 148.285953 -392.295655) (xy 148.30861 -392.246045)
			(xy 148.338096 -392.200164) (xy 148.373811 -392.158947) (xy 148.415028 -392.123232) (xy 148.460909 -392.093746)
			(xy 148.510519 -392.071089) (xy 148.562849 -392.055724) (xy 148.616833 -392.047962) (xy 148.671371 -392.047962)
			(xy 148.725355 -392.055724) (xy 148.777685 -392.071089) (xy 148.827295 -392.093746) (xy 148.873176 -392.123232)
			(xy 148.914393 -392.158947) (xy 148.950108 -392.200164) (xy 148.979594 -392.246045) (xy 149.002251 -392.295655)
			(xy 149.017616 -392.347985) (xy 149.025378 -392.401969) (xy 149.025864 -392.429238) (xy 149.025864 -393.292838)
			(xy 149.462744 -393.292838) (xy 149.462744 -392.429238) (xy 149.46323 -392.401987) (xy 149.470986 -392.348039)
			(xy 149.486341 -392.295744) (xy 149.508983 -392.246167) (xy 149.538449 -392.200317) (xy 149.57414 -392.159126)
			(xy 149.615331 -392.123435) (xy 149.661181 -392.093969) (xy 149.710758 -392.071327) (xy 149.763053 -392.055972)
			(xy 149.817001 -392.048216) (xy 149.871503 -392.048216) (xy 149.925451 -392.055972) (xy 149.977746 -392.071327)
			(xy 150.027323 -392.093969) (xy 150.073173 -392.123435) (xy 150.114364 -392.159126) (xy 150.150055 -392.200317)
			(xy 150.179521 -392.246167) (xy 150.202163 -392.295744) (xy 150.217518 -392.348039) (xy 150.225274 -392.401987)
			(xy 150.22576 -392.429238) (xy 150.22576 -393.292838) (xy 150.66264 -393.292838) (xy 150.66264 -392.429238)
			(xy 150.663126 -392.401987) (xy 150.670882 -392.348039) (xy 150.686237 -392.295744) (xy 150.708879 -392.246167)
			(xy 150.738345 -392.200317) (xy 150.774036 -392.159126) (xy 150.815227 -392.123435) (xy 150.861077 -392.093969)
			(xy 150.910654 -392.071327) (xy 150.962949 -392.055972) (xy 151.016897 -392.048216) (xy 151.071399 -392.048216)
			(xy 151.125347 -392.055972) (xy 151.177642 -392.071327) (xy 151.227219 -392.093969) (xy 151.273069 -392.123435)
			(xy 151.31426 -392.159126) (xy 151.349951 -392.200317) (xy 151.379417 -392.246167) (xy 151.402059 -392.295744)
			(xy 151.417414 -392.348039) (xy 151.42517 -392.401987) (xy 151.425656 -392.429238) (xy 151.425656 -393.292838)
			(xy 151.862536 -393.292838) (xy 151.862536 -392.429238) (xy 151.863022 -392.401969) (xy 151.870784 -392.347985)
			(xy 151.886149 -392.295655) (xy 151.908806 -392.246045) (xy 151.938292 -392.200164) (xy 151.974007 -392.158947)
			(xy 152.015224 -392.123232) (xy 152.061105 -392.093746) (xy 152.110715 -392.071089) (xy 152.163045 -392.055724)
			(xy 152.217029 -392.047962) (xy 152.271567 -392.047962) (xy 152.325551 -392.055724) (xy 152.377881 -392.071089)
			(xy 152.427491 -392.093746) (xy 152.473372 -392.123232) (xy 152.514589 -392.158947) (xy 152.550304 -392.200164)
			(xy 152.57979 -392.246045) (xy 152.602447 -392.295655) (xy 152.617812 -392.347985) (xy 152.625574 -392.401969)
			(xy 152.62606 -392.429238) (xy 152.62606 -393.292838) (xy 153.062432 -393.292838) (xy 153.062432 -392.429238)
			(xy 153.062918 -392.401969) (xy 153.07068 -392.347985) (xy 153.086045 -392.295655) (xy 153.108702 -392.246045)
			(xy 153.138188 -392.200164) (xy 153.173903 -392.158947) (xy 153.21512 -392.123232) (xy 153.261001 -392.093746)
			(xy 153.310611 -392.071089) (xy 153.362941 -392.055724) (xy 153.416925 -392.047962) (xy 153.471463 -392.047962)
			(xy 153.525447 -392.055724) (xy 153.577777 -392.071089) (xy 153.627387 -392.093746) (xy 153.673268 -392.123232)
			(xy 153.714485 -392.158947) (xy 153.7502 -392.200164) (xy 153.779686 -392.246045) (xy 153.802343 -392.295655)
			(xy 153.817708 -392.347985) (xy 153.82547 -392.401969) (xy 153.825956 -392.429238) (xy 153.825956 -393.292838)
			(xy 154.262836 -393.292838) (xy 154.262836 -392.429238) (xy 154.263322 -392.401987) (xy 154.271078 -392.348039)
			(xy 154.286433 -392.295744) (xy 154.309075 -392.246167) (xy 154.338541 -392.200317) (xy 154.374232 -392.159126)
			(xy 154.415423 -392.123435) (xy 154.461273 -392.093969) (xy 154.51085 -392.071327) (xy 154.563145 -392.055972)
			(xy 154.617093 -392.048216) (xy 154.671595 -392.048216) (xy 154.725543 -392.055972) (xy 154.777838 -392.071327)
			(xy 154.827415 -392.093969) (xy 154.873265 -392.123435) (xy 154.914456 -392.159126) (xy 154.950147 -392.200317)
			(xy 154.979613 -392.246167) (xy 155.002255 -392.295744) (xy 155.01761 -392.348039) (xy 155.025366 -392.401987)
			(xy 155.025852 -392.429238) (xy 155.025852 -393.292838) (xy 155.462732 -393.292838) (xy 155.462732 -392.429238)
			(xy 155.463218 -392.401987) (xy 155.470974 -392.348039) (xy 155.486329 -392.295744) (xy 155.508971 -392.246167)
			(xy 155.538437 -392.200317) (xy 155.574128 -392.159126) (xy 155.615319 -392.123435) (xy 155.661169 -392.093969)
			(xy 155.710746 -392.071327) (xy 155.763041 -392.055972) (xy 155.816989 -392.048216) (xy 155.871491 -392.048216)
			(xy 155.925439 -392.055972) (xy 155.977734 -392.071327) (xy 156.027311 -392.093969) (xy 156.073161 -392.123435)
			(xy 156.114352 -392.159126) (xy 156.150043 -392.200317) (xy 156.179509 -392.246167) (xy 156.202151 -392.295744)
			(xy 156.217506 -392.348039) (xy 156.225262 -392.401987) (xy 156.225748 -392.429238) (xy 156.225748 -393.292838)
			(xy 156.662628 -393.292838) (xy 156.662628 -392.429238) (xy 156.663114 -392.401969) (xy 156.670876 -392.347985)
			(xy 156.686241 -392.295655) (xy 156.708898 -392.246045) (xy 156.738384 -392.200164) (xy 156.774099 -392.158947)
			(xy 156.815316 -392.123232) (xy 156.861197 -392.093746) (xy 156.910807 -392.071089) (xy 156.963137 -392.055724)
			(xy 157.017121 -392.047962) (xy 157.071659 -392.047962) (xy 157.125643 -392.055724) (xy 157.177973 -392.071089)
			(xy 157.227583 -392.093746) (xy 157.273464 -392.123232) (xy 157.314681 -392.158947) (xy 157.350396 -392.200164)
			(xy 157.379882 -392.246045) (xy 157.402539 -392.295655) (xy 157.417904 -392.347985) (xy 157.425666 -392.401969)
			(xy 157.426152 -392.429238) (xy 157.426152 -393.292838) (xy 157.862524 -393.292838) (xy 157.862524 -392.429238)
			(xy 157.86301 -392.401969) (xy 157.870772 -392.347985) (xy 157.886137 -392.295655) (xy 157.908794 -392.246045)
			(xy 157.93828 -392.200164) (xy 157.973995 -392.158947) (xy 158.015212 -392.123232) (xy 158.061093 -392.093746)
			(xy 158.110703 -392.071089) (xy 158.163033 -392.055724) (xy 158.217017 -392.047962) (xy 158.271555 -392.047962)
			(xy 158.325539 -392.055724) (xy 158.377869 -392.071089) (xy 158.427479 -392.093746) (xy 158.47336 -392.123232)
			(xy 158.514577 -392.158947) (xy 158.550292 -392.200164) (xy 158.579778 -392.246045) (xy 158.602435 -392.295655)
			(xy 158.6178 -392.347985) (xy 158.625562 -392.401969) (xy 158.626048 -392.429238) (xy 158.626048 -393.292838)
			(xy 159.062928 -393.292838) (xy 159.062928 -392.429238) (xy 159.063414 -392.401987) (xy 159.07117 -392.348039)
			(xy 159.086525 -392.295744) (xy 159.109167 -392.246167) (xy 159.138633 -392.200317) (xy 159.174324 -392.159126)
			(xy 159.215515 -392.123435) (xy 159.261365 -392.093969) (xy 159.310942 -392.071327) (xy 159.363237 -392.055972)
			(xy 159.417185 -392.048216) (xy 159.471687 -392.048216) (xy 159.525635 -392.055972) (xy 159.57793 -392.071327)
			(xy 159.627507 -392.093969) (xy 159.673357 -392.123435) (xy 159.714548 -392.159126) (xy 159.750239 -392.200317)
			(xy 159.779705 -392.246167) (xy 159.802347 -392.295744) (xy 159.817702 -392.348039) (xy 159.825458 -392.401987)
			(xy 159.825944 -392.429238) (xy 159.825944 -393.292838) (xy 160.262824 -393.292838) (xy 160.262824 -392.429238)
			(xy 160.26331 -392.401987) (xy 160.271066 -392.348039) (xy 160.286421 -392.295744) (xy 160.309063 -392.246167)
			(xy 160.338529 -392.200317) (xy 160.37422 -392.159126) (xy 160.415411 -392.123435) (xy 160.461261 -392.093969)
			(xy 160.510838 -392.071327) (xy 160.563133 -392.055972) (xy 160.617081 -392.048216) (xy 160.671583 -392.048216)
			(xy 160.725531 -392.055972) (xy 160.777826 -392.071327) (xy 160.827403 -392.093969) (xy 160.873253 -392.123435)
			(xy 160.914444 -392.159126) (xy 160.950135 -392.200317) (xy 160.979601 -392.246167) (xy 161.002243 -392.295744)
			(xy 161.017598 -392.348039) (xy 161.025354 -392.401987) (xy 161.02584 -392.429238) (xy 161.02584 -393.292838)
			(xy 161.46272 -393.292838) (xy 161.46272 -392.429238) (xy 161.463206 -392.401987) (xy 161.470962 -392.348039)
			(xy 161.486317 -392.295744) (xy 161.508959 -392.246167) (xy 161.538425 -392.200317) (xy 161.574116 -392.159126)
			(xy 161.615307 -392.123435) (xy 161.661157 -392.093969) (xy 161.710734 -392.071327) (xy 161.763029 -392.055972)
			(xy 161.816977 -392.048216) (xy 161.871479 -392.048216) (xy 161.925427 -392.055972) (xy 161.977722 -392.071327)
			(xy 162.027299 -392.093969) (xy 162.073149 -392.123435) (xy 162.11434 -392.159126) (xy 162.150031 -392.200317)
			(xy 162.179497 -392.246167) (xy 162.202139 -392.295744) (xy 162.217494 -392.348039) (xy 162.22525 -392.401987)
			(xy 162.225736 -392.429238) (xy 162.225736 -393.292838) (xy 162.662616 -393.292838) (xy 162.662616 -392.429238)
			(xy 162.663102 -392.401987) (xy 162.670858 -392.348039) (xy 162.686213 -392.295744) (xy 162.708855 -392.246167)
			(xy 162.738321 -392.200317) (xy 162.774012 -392.159126) (xy 162.815203 -392.123435) (xy 162.861053 -392.093969)
			(xy 162.91063 -392.071327) (xy 162.962925 -392.055972) (xy 163.016873 -392.048216) (xy 163.071375 -392.048216)
			(xy 163.125323 -392.055972) (xy 163.177618 -392.071327) (xy 163.227195 -392.093969) (xy 163.273045 -392.123435)
			(xy 163.314236 -392.159126) (xy 163.349927 -392.200317) (xy 163.379393 -392.246167) (xy 163.402035 -392.295744)
			(xy 163.41739 -392.348039) (xy 163.425146 -392.401987) (xy 163.425632 -392.429238) (xy 163.425632 -393.292838)
			(xy 163.862512 -393.292838) (xy 163.862512 -392.429238) (xy 163.862998 -392.401969) (xy 163.87076 -392.347985)
			(xy 163.886125 -392.295655) (xy 163.908782 -392.246045) (xy 163.938268 -392.200164) (xy 163.973983 -392.158947)
			(xy 164.0152 -392.123232) (xy 164.061081 -392.093746) (xy 164.110691 -392.071089) (xy 164.163021 -392.055724)
			(xy 164.217005 -392.047962) (xy 164.271543 -392.047962) (xy 164.325527 -392.055724) (xy 164.377857 -392.071089)
			(xy 164.427467 -392.093746) (xy 164.473348 -392.123232) (xy 164.514565 -392.158947) (xy 164.55028 -392.200164)
			(xy 164.579766 -392.246045) (xy 164.602423 -392.295655) (xy 164.617788 -392.347985) (xy 164.62555 -392.401969)
			(xy 164.626036 -392.429238) (xy 164.626036 -393.292838) (xy 165.062408 -393.292838) (xy 165.062408 -392.429238)
			(xy 165.062894 -392.401969) (xy 165.070656 -392.347985) (xy 165.086021 -392.295655) (xy 165.108678 -392.246045)
			(xy 165.138164 -392.200164) (xy 165.173879 -392.158947) (xy 165.215096 -392.123232) (xy 165.260977 -392.093746)
			(xy 165.310587 -392.071089) (xy 165.362917 -392.055724) (xy 165.416901 -392.047962) (xy 165.471439 -392.047962)
			(xy 165.525423 -392.055724) (xy 165.577753 -392.071089) (xy 165.627363 -392.093746) (xy 165.673244 -392.123232)
			(xy 165.714461 -392.158947) (xy 165.750176 -392.200164) (xy 165.779662 -392.246045) (xy 165.802319 -392.295655)
			(xy 165.817684 -392.347985) (xy 165.825446 -392.401969) (xy 165.825932 -392.429238) (xy 165.825932 -393.292838)
			(xy 165.825446 -393.320107) (xy 165.817684 -393.374091) (xy 165.802319 -393.426421) (xy 165.779662 -393.476031)
			(xy 165.750176 -393.521912) (xy 165.714461 -393.563129) (xy 165.673244 -393.598844) (xy 165.627363 -393.62833)
			(xy 165.577753 -393.650987) (xy 165.525423 -393.666352) (xy 165.471439 -393.674114) (xy 165.416901 -393.674114)
			(xy 165.362917 -393.666352) (xy 165.310587 -393.650987) (xy 165.260977 -393.62833) (xy 165.215096 -393.598844)
			(xy 165.173879 -393.563129) (xy 165.138164 -393.521912) (xy 165.108678 -393.476031) (xy 165.086021 -393.426421)
			(xy 165.070656 -393.374091) (xy 165.062894 -393.320107) (xy 165.062408 -393.292838) (xy 164.626036 -393.292838)
			(xy 164.62555 -393.320107) (xy 164.617788 -393.374091) (xy 164.602423 -393.426421) (xy 164.579766 -393.476031)
			(xy 164.55028 -393.521912) (xy 164.514565 -393.563129) (xy 164.473348 -393.598844) (xy 164.427467 -393.62833)
			(xy 164.377857 -393.650987) (xy 164.325527 -393.666352) (xy 164.271543 -393.674114) (xy 164.217005 -393.674114)
			(xy 164.163021 -393.666352) (xy 164.110691 -393.650987) (xy 164.061081 -393.62833) (xy 164.0152 -393.598844)
			(xy 163.973983 -393.563129) (xy 163.938268 -393.521912) (xy 163.908782 -393.476031) (xy 163.886125 -393.426421)
			(xy 163.87076 -393.374091) (xy 163.862998 -393.320107) (xy 163.862512 -393.292838) (xy 163.425632 -393.292838)
			(xy 163.425146 -393.320089) (xy 163.41739 -393.374037) (xy 163.402035 -393.426332) (xy 163.379393 -393.475909)
			(xy 163.349927 -393.521759) (xy 163.314236 -393.56295) (xy 163.273045 -393.598641) (xy 163.227195 -393.628107)
			(xy 163.177618 -393.650749) (xy 163.125323 -393.666104) (xy 163.071375 -393.67386) (xy 163.016873 -393.67386)
			(xy 162.962925 -393.666104) (xy 162.91063 -393.650749) (xy 162.861053 -393.628107) (xy 162.815203 -393.598641)
			(xy 162.774012 -393.56295) (xy 162.738321 -393.521759) (xy 162.708855 -393.475909) (xy 162.686213 -393.426332)
			(xy 162.670858 -393.374037) (xy 162.663102 -393.320089) (xy 162.662616 -393.292838) (xy 162.225736 -393.292838)
			(xy 162.22525 -393.320089) (xy 162.217494 -393.374037) (xy 162.202139 -393.426332) (xy 162.179497 -393.475909)
			(xy 162.150031 -393.521759) (xy 162.11434 -393.56295) (xy 162.073149 -393.598641) (xy 162.027299 -393.628107)
			(xy 161.977722 -393.650749) (xy 161.925427 -393.666104) (xy 161.871479 -393.67386) (xy 161.816977 -393.67386)
			(xy 161.763029 -393.666104) (xy 161.710734 -393.650749) (xy 161.661157 -393.628107) (xy 161.615307 -393.598641)
			(xy 161.574116 -393.56295) (xy 161.538425 -393.521759) (xy 161.508959 -393.475909) (xy 161.486317 -393.426332)
			(xy 161.470962 -393.374037) (xy 161.463206 -393.320089) (xy 161.46272 -393.292838) (xy 161.02584 -393.292838)
			(xy 161.025354 -393.320089) (xy 161.017598 -393.374037) (xy 161.002243 -393.426332) (xy 160.979601 -393.475909)
			(xy 160.950135 -393.521759) (xy 160.914444 -393.56295) (xy 160.873253 -393.598641) (xy 160.827403 -393.628107)
			(xy 160.777826 -393.650749) (xy 160.725531 -393.666104) (xy 160.671583 -393.67386) (xy 160.617081 -393.67386)
			(xy 160.563133 -393.666104) (xy 160.510838 -393.650749) (xy 160.461261 -393.628107) (xy 160.415411 -393.598641)
			(xy 160.37422 -393.56295) (xy 160.338529 -393.521759) (xy 160.309063 -393.475909) (xy 160.286421 -393.426332)
			(xy 160.271066 -393.374037) (xy 160.26331 -393.320089) (xy 160.262824 -393.292838) (xy 159.825944 -393.292838)
			(xy 159.825458 -393.320089) (xy 159.817702 -393.374037) (xy 159.802347 -393.426332) (xy 159.779705 -393.475909)
			(xy 159.750239 -393.521759) (xy 159.714548 -393.56295) (xy 159.673357 -393.598641) (xy 159.627507 -393.628107)
			(xy 159.57793 -393.650749) (xy 159.525635 -393.666104) (xy 159.471687 -393.67386) (xy 159.417185 -393.67386)
			(xy 159.363237 -393.666104) (xy 159.310942 -393.650749) (xy 159.261365 -393.628107) (xy 159.215515 -393.598641)
			(xy 159.174324 -393.56295) (xy 159.138633 -393.521759) (xy 159.109167 -393.475909) (xy 159.086525 -393.426332)
			(xy 159.07117 -393.374037) (xy 159.063414 -393.320089) (xy 159.062928 -393.292838) (xy 158.626048 -393.292838)
			(xy 158.625562 -393.320107) (xy 158.6178 -393.374091) (xy 158.602435 -393.426421) (xy 158.579778 -393.476031)
			(xy 158.550292 -393.521912) (xy 158.514577 -393.563129) (xy 158.47336 -393.598844) (xy 158.427479 -393.62833)
			(xy 158.377869 -393.650987) (xy 158.325539 -393.666352) (xy 158.271555 -393.674114) (xy 158.217017 -393.674114)
			(xy 158.163033 -393.666352) (xy 158.110703 -393.650987) (xy 158.061093 -393.62833) (xy 158.015212 -393.598844)
			(xy 157.973995 -393.563129) (xy 157.93828 -393.521912) (xy 157.908794 -393.476031) (xy 157.886137 -393.426421)
			(xy 157.870772 -393.374091) (xy 157.86301 -393.320107) (xy 157.862524 -393.292838) (xy 157.426152 -393.292838)
			(xy 157.425666 -393.320107) (xy 157.417904 -393.374091) (xy 157.402539 -393.426421) (xy 157.379882 -393.476031)
			(xy 157.350396 -393.521912) (xy 157.314681 -393.563129) (xy 157.273464 -393.598844) (xy 157.227583 -393.62833)
			(xy 157.177973 -393.650987) (xy 157.125643 -393.666352) (xy 157.071659 -393.674114) (xy 157.017121 -393.674114)
			(xy 156.963137 -393.666352) (xy 156.910807 -393.650987) (xy 156.861197 -393.62833) (xy 156.815316 -393.598844)
			(xy 156.774099 -393.563129) (xy 156.738384 -393.521912) (xy 156.708898 -393.476031) (xy 156.686241 -393.426421)
			(xy 156.670876 -393.374091) (xy 156.663114 -393.320107) (xy 156.662628 -393.292838) (xy 156.225748 -393.292838)
			(xy 156.225262 -393.320089) (xy 156.217506 -393.374037) (xy 156.202151 -393.426332) (xy 156.179509 -393.475909)
			(xy 156.150043 -393.521759) (xy 156.114352 -393.56295) (xy 156.073161 -393.598641) (xy 156.027311 -393.628107)
			(xy 155.977734 -393.650749) (xy 155.925439 -393.666104) (xy 155.871491 -393.67386) (xy 155.816989 -393.67386)
			(xy 155.763041 -393.666104) (xy 155.710746 -393.650749) (xy 155.661169 -393.628107) (xy 155.615319 -393.598641)
			(xy 155.574128 -393.56295) (xy 155.538437 -393.521759) (xy 155.508971 -393.475909) (xy 155.486329 -393.426332)
			(xy 155.470974 -393.374037) (xy 155.463218 -393.320089) (xy 155.462732 -393.292838) (xy 155.025852 -393.292838)
			(xy 155.025366 -393.320089) (xy 155.01761 -393.374037) (xy 155.002255 -393.426332) (xy 154.979613 -393.475909)
			(xy 154.950147 -393.521759) (xy 154.914456 -393.56295) (xy 154.873265 -393.598641) (xy 154.827415 -393.628107)
			(xy 154.777838 -393.650749) (xy 154.725543 -393.666104) (xy 154.671595 -393.67386) (xy 154.617093 -393.67386)
			(xy 154.563145 -393.666104) (xy 154.51085 -393.650749) (xy 154.461273 -393.628107) (xy 154.415423 -393.598641)
			(xy 154.374232 -393.56295) (xy 154.338541 -393.521759) (xy 154.309075 -393.475909) (xy 154.286433 -393.426332)
			(xy 154.271078 -393.374037) (xy 154.263322 -393.320089) (xy 154.262836 -393.292838) (xy 153.825956 -393.292838)
			(xy 153.82547 -393.320107) (xy 153.817708 -393.374091) (xy 153.802343 -393.426421) (xy 153.779686 -393.476031)
			(xy 153.7502 -393.521912) (xy 153.714485 -393.563129) (xy 153.673268 -393.598844) (xy 153.627387 -393.62833)
			(xy 153.577777 -393.650987) (xy 153.525447 -393.666352) (xy 153.471463 -393.674114) (xy 153.416925 -393.674114)
			(xy 153.362941 -393.666352) (xy 153.310611 -393.650987) (xy 153.261001 -393.62833) (xy 153.21512 -393.598844)
			(xy 153.173903 -393.563129) (xy 153.138188 -393.521912) (xy 153.108702 -393.476031) (xy 153.086045 -393.426421)
			(xy 153.07068 -393.374091) (xy 153.062918 -393.320107) (xy 153.062432 -393.292838) (xy 152.62606 -393.292838)
			(xy 152.625574 -393.320107) (xy 152.617812 -393.374091) (xy 152.602447 -393.426421) (xy 152.57979 -393.476031)
			(xy 152.550304 -393.521912) (xy 152.514589 -393.563129) (xy 152.473372 -393.598844) (xy 152.427491 -393.62833)
			(xy 152.377881 -393.650987) (xy 152.325551 -393.666352) (xy 152.271567 -393.674114) (xy 152.217029 -393.674114)
			(xy 152.163045 -393.666352) (xy 152.110715 -393.650987) (xy 152.061105 -393.62833) (xy 152.015224 -393.598844)
			(xy 151.974007 -393.563129) (xy 151.938292 -393.521912) (xy 151.908806 -393.476031) (xy 151.886149 -393.426421)
			(xy 151.870784 -393.374091) (xy 151.863022 -393.320107) (xy 151.862536 -393.292838) (xy 151.425656 -393.292838)
			(xy 151.42517 -393.320089) (xy 151.417414 -393.374037) (xy 151.402059 -393.426332) (xy 151.379417 -393.475909)
			(xy 151.349951 -393.521759) (xy 151.31426 -393.56295) (xy 151.273069 -393.598641) (xy 151.227219 -393.628107)
			(xy 151.177642 -393.650749) (xy 151.125347 -393.666104) (xy 151.071399 -393.67386) (xy 151.016897 -393.67386)
			(xy 150.962949 -393.666104) (xy 150.910654 -393.650749) (xy 150.861077 -393.628107) (xy 150.815227 -393.598641)
			(xy 150.774036 -393.56295) (xy 150.738345 -393.521759) (xy 150.708879 -393.475909) (xy 150.686237 -393.426332)
			(xy 150.670882 -393.374037) (xy 150.663126 -393.320089) (xy 150.66264 -393.292838) (xy 150.22576 -393.292838)
			(xy 150.225274 -393.320089) (xy 150.217518 -393.374037) (xy 150.202163 -393.426332) (xy 150.179521 -393.475909)
			(xy 150.150055 -393.521759) (xy 150.114364 -393.56295) (xy 150.073173 -393.598641) (xy 150.027323 -393.628107)
			(xy 149.977746 -393.650749) (xy 149.925451 -393.666104) (xy 149.871503 -393.67386) (xy 149.817001 -393.67386)
			(xy 149.763053 -393.666104) (xy 149.710758 -393.650749) (xy 149.661181 -393.628107) (xy 149.615331 -393.598641)
			(xy 149.57414 -393.56295) (xy 149.538449 -393.521759) (xy 149.508983 -393.475909) (xy 149.486341 -393.426332)
			(xy 149.470986 -393.374037) (xy 149.46323 -393.320089) (xy 149.462744 -393.292838) (xy 149.025864 -393.292838)
			(xy 149.025378 -393.320107) (xy 149.017616 -393.374091) (xy 149.002251 -393.426421) (xy 148.979594 -393.476031)
			(xy 148.950108 -393.521912) (xy 148.914393 -393.563129) (xy 148.873176 -393.598844) (xy 148.827295 -393.62833)
			(xy 148.777685 -393.650987) (xy 148.725355 -393.666352) (xy 148.671371 -393.674114) (xy 148.616833 -393.674114)
			(xy 148.562849 -393.666352) (xy 148.510519 -393.650987) (xy 148.460909 -393.62833) (xy 148.415028 -393.598844)
			(xy 148.373811 -393.563129) (xy 148.338096 -393.521912) (xy 148.30861 -393.476031) (xy 148.285953 -393.426421)
			(xy 148.270588 -393.374091) (xy 148.262826 -393.320107) (xy 148.26234 -393.292838) (xy 147.825968 -393.292838)
			(xy 147.825482 -393.320107) (xy 147.81772 -393.374091) (xy 147.802355 -393.426421) (xy 147.779698 -393.476031)
			(xy 147.750212 -393.521912) (xy 147.714497 -393.563129) (xy 147.67328 -393.598844) (xy 147.627399 -393.62833)
			(xy 147.577789 -393.650987) (xy 147.525459 -393.666352) (xy 147.471475 -393.674114) (xy 147.416937 -393.674114)
			(xy 147.362953 -393.666352) (xy 147.310623 -393.650987) (xy 147.261013 -393.62833) (xy 147.215132 -393.598844)
			(xy 147.173915 -393.563129) (xy 147.1382 -393.521912) (xy 147.108714 -393.476031) (xy 147.086057 -393.426421)
			(xy 147.070692 -393.374091) (xy 147.06293 -393.320107) (xy 147.062444 -393.292838) (xy 133.298184 -393.292838)
			(xy 133.297698 -393.320107) (xy 133.289936 -393.374091) (xy 133.274571 -393.426421) (xy 133.251914 -393.476031)
			(xy 133.222428 -393.521912) (xy 133.186713 -393.563129) (xy 133.145496 -393.598844) (xy 133.099615 -393.62833)
			(xy 133.050005 -393.650987) (xy 132.997675 -393.666352) (xy 132.943691 -393.674114) (xy 132.889153 -393.674114)
			(xy 132.835169 -393.666352) (xy 132.782839 -393.650987) (xy 132.733229 -393.62833) (xy 132.687348 -393.598844)
			(xy 132.646131 -393.563129) (xy 132.610416 -393.521912) (xy 132.58093 -393.476031) (xy 132.558273 -393.426421)
			(xy 132.542908 -393.374091) (xy 132.535146 -393.320107) (xy 132.53466 -393.292838) (xy 132.098288 -393.292838)
			(xy 132.097802 -393.320107) (xy 132.09004 -393.374091) (xy 132.074675 -393.426421) (xy 132.052018 -393.476031)
			(xy 132.022532 -393.521912) (xy 131.986817 -393.563129) (xy 131.9456 -393.598844) (xy 131.899719 -393.62833)
			(xy 131.850109 -393.650987) (xy 131.797779 -393.666352) (xy 131.743795 -393.674114) (xy 131.689257 -393.674114)
			(xy 131.635273 -393.666352) (xy 131.582943 -393.650987) (xy 131.533333 -393.62833) (xy 131.487452 -393.598844)
			(xy 131.446235 -393.563129) (xy 131.41052 -393.521912) (xy 131.381034 -393.476031) (xy 131.358377 -393.426421)
			(xy 131.343012 -393.374091) (xy 131.33525 -393.320107) (xy 131.334764 -393.292838) (xy 130.897884 -393.292838)
			(xy 130.897398 -393.320089) (xy 130.889642 -393.374037) (xy 130.874287 -393.426332) (xy 130.851645 -393.475909)
			(xy 130.822179 -393.521759) (xy 130.786488 -393.56295) (xy 130.745297 -393.598641) (xy 130.699447 -393.628107)
			(xy 130.64987 -393.650749) (xy 130.597575 -393.666104) (xy 130.543627 -393.67386) (xy 130.489125 -393.67386)
			(xy 130.435177 -393.666104) (xy 130.382882 -393.650749) (xy 130.333305 -393.628107) (xy 130.287455 -393.598641)
			(xy 130.246264 -393.56295) (xy 130.210573 -393.521759) (xy 130.181107 -393.475909) (xy 130.158465 -393.426332)
			(xy 130.14311 -393.374037) (xy 130.135354 -393.320089) (xy 130.134868 -393.292838) (xy 129.697988 -393.292838)
			(xy 129.697502 -393.320089) (xy 129.689746 -393.374037) (xy 129.674391 -393.426332) (xy 129.651749 -393.475909)
			(xy 129.622283 -393.521759) (xy 129.586592 -393.56295) (xy 129.545401 -393.598641) (xy 129.499551 -393.628107)
			(xy 129.449974 -393.650749) (xy 129.397679 -393.666104) (xy 129.343731 -393.67386) (xy 129.289229 -393.67386)
			(xy 129.235281 -393.666104) (xy 129.182986 -393.650749) (xy 129.133409 -393.628107) (xy 129.087559 -393.598641)
			(xy 129.046368 -393.56295) (xy 129.010677 -393.521759) (xy 128.981211 -393.475909) (xy 128.958569 -393.426332)
			(xy 128.943214 -393.374037) (xy 128.935458 -393.320089) (xy 128.934972 -393.292838) (xy 128.498092 -393.292838)
			(xy 128.497606 -393.320089) (xy 128.48985 -393.374037) (xy 128.474495 -393.426332) (xy 128.451853 -393.475909)
			(xy 128.422387 -393.521759) (xy 128.386696 -393.56295) (xy 128.345505 -393.598641) (xy 128.299655 -393.628107)
			(xy 128.250078 -393.650749) (xy 128.197783 -393.666104) (xy 128.143835 -393.67386) (xy 128.089333 -393.67386)
			(xy 128.035385 -393.666104) (xy 127.98309 -393.650749) (xy 127.933513 -393.628107) (xy 127.887663 -393.598641)
			(xy 127.846472 -393.56295) (xy 127.810781 -393.521759) (xy 127.781315 -393.475909) (xy 127.758673 -393.426332)
			(xy 127.743318 -393.374037) (xy 127.735562 -393.320089) (xy 127.735076 -393.292838) (xy 127.298196 -393.292838)
			(xy 127.29771 -393.320089) (xy 127.289954 -393.374037) (xy 127.274599 -393.426332) (xy 127.251957 -393.475909)
			(xy 127.222491 -393.521759) (xy 127.1868 -393.56295) (xy 127.145609 -393.598641) (xy 127.099759 -393.628107)
			(xy 127.050182 -393.650749) (xy 126.997887 -393.666104) (xy 126.943939 -393.67386) (xy 126.889437 -393.67386)
			(xy 126.835489 -393.666104) (xy 126.783194 -393.650749) (xy 126.733617 -393.628107) (xy 126.687767 -393.598641)
			(xy 126.646576 -393.56295) (xy 126.610885 -393.521759) (xy 126.581419 -393.475909) (xy 126.558777 -393.426332)
			(xy 126.543422 -393.374037) (xy 126.535666 -393.320089) (xy 126.53518 -393.292838) (xy 126.0983 -393.292838)
			(xy 126.097814 -393.320107) (xy 126.090052 -393.374091) (xy 126.074687 -393.426421) (xy 126.05203 -393.476031)
			(xy 126.022544 -393.521912) (xy 125.986829 -393.563129) (xy 125.945612 -393.598844) (xy 125.899731 -393.62833)
			(xy 125.850121 -393.650987) (xy 125.797791 -393.666352) (xy 125.743807 -393.674114) (xy 125.689269 -393.674114)
			(xy 125.635285 -393.666352) (xy 125.582955 -393.650987) (xy 125.533345 -393.62833) (xy 125.487464 -393.598844)
			(xy 125.446247 -393.563129) (xy 125.410532 -393.521912) (xy 125.381046 -393.476031) (xy 125.358389 -393.426421)
			(xy 125.343024 -393.374091) (xy 125.335262 -393.320107) (xy 125.334776 -393.292838) (xy 124.898404 -393.292838)
			(xy 124.897918 -393.320107) (xy 124.890156 -393.374091) (xy 124.874791 -393.426421) (xy 124.852134 -393.476031)
			(xy 124.822648 -393.521912) (xy 124.786933 -393.563129) (xy 124.745716 -393.598844) (xy 124.699835 -393.62833)
			(xy 124.650225 -393.650987) (xy 124.597895 -393.666352) (xy 124.543911 -393.674114) (xy 124.489373 -393.674114)
			(xy 124.435389 -393.666352) (xy 124.383059 -393.650987) (xy 124.333449 -393.62833) (xy 124.287568 -393.598844)
			(xy 124.246351 -393.563129) (xy 124.210636 -393.521912) (xy 124.18115 -393.476031) (xy 124.158493 -393.426421)
			(xy 124.143128 -393.374091) (xy 124.135366 -393.320107) (xy 124.13488 -393.292838) (xy 123.698 -393.292838)
			(xy 123.697514 -393.320089) (xy 123.689758 -393.374037) (xy 123.674403 -393.426332) (xy 123.651761 -393.475909)
			(xy 123.622295 -393.521759) (xy 123.586604 -393.56295) (xy 123.545413 -393.598641) (xy 123.499563 -393.628107)
			(xy 123.449986 -393.650749) (xy 123.397691 -393.666104) (xy 123.343743 -393.67386) (xy 123.289241 -393.67386)
			(xy 123.235293 -393.666104) (xy 123.182998 -393.650749) (xy 123.133421 -393.628107) (xy 123.087571 -393.598641)
			(xy 123.04638 -393.56295) (xy 123.010689 -393.521759) (xy 122.981223 -393.475909) (xy 122.958581 -393.426332)
			(xy 122.943226 -393.374037) (xy 122.93547 -393.320089) (xy 122.934984 -393.292838) (xy 122.498104 -393.292838)
			(xy 122.497618 -393.320089) (xy 122.489862 -393.374037) (xy 122.474507 -393.426332) (xy 122.451865 -393.475909)
			(xy 122.422399 -393.521759) (xy 122.386708 -393.56295) (xy 122.345517 -393.598641) (xy 122.299667 -393.628107)
			(xy 122.25009 -393.650749) (xy 122.197795 -393.666104) (xy 122.143847 -393.67386) (xy 122.089345 -393.67386)
			(xy 122.035397 -393.666104) (xy 121.983102 -393.650749) (xy 121.933525 -393.628107) (xy 121.887675 -393.598641)
			(xy 121.846484 -393.56295) (xy 121.810793 -393.521759) (xy 121.781327 -393.475909) (xy 121.758685 -393.426332)
			(xy 121.74333 -393.374037) (xy 121.735574 -393.320089) (xy 121.735088 -393.292838) (xy 121.298208 -393.292838)
			(xy 121.297722 -393.320107) (xy 121.28996 -393.374091) (xy 121.274595 -393.426421) (xy 121.251938 -393.476031)
			(xy 121.222452 -393.521912) (xy 121.186737 -393.563129) (xy 121.14552 -393.598844) (xy 121.099639 -393.62833)
			(xy 121.050029 -393.650987) (xy 120.997699 -393.666352) (xy 120.943715 -393.674114) (xy 120.889177 -393.674114)
			(xy 120.835193 -393.666352) (xy 120.782863 -393.650987) (xy 120.733253 -393.62833) (xy 120.687372 -393.598844)
			(xy 120.646155 -393.563129) (xy 120.61044 -393.521912) (xy 120.580954 -393.476031) (xy 120.558297 -393.426421)
			(xy 120.542932 -393.374091) (xy 120.53517 -393.320107) (xy 120.534684 -393.292838) (xy 120.098312 -393.292838)
			(xy 120.097826 -393.320107) (xy 120.090064 -393.374091) (xy 120.074699 -393.426421) (xy 120.052042 -393.476031)
			(xy 120.022556 -393.521912) (xy 119.986841 -393.563129) (xy 119.945624 -393.598844) (xy 119.899743 -393.62833)
			(xy 119.850133 -393.650987) (xy 119.797803 -393.666352) (xy 119.743819 -393.674114) (xy 119.689281 -393.674114)
			(xy 119.635297 -393.666352) (xy 119.582967 -393.650987) (xy 119.533357 -393.62833) (xy 119.487476 -393.598844)
			(xy 119.446259 -393.563129) (xy 119.410544 -393.521912) (xy 119.381058 -393.476031) (xy 119.358401 -393.426421)
			(xy 119.343036 -393.374091) (xy 119.335274 -393.320107) (xy 119.334788 -393.292838) (xy 118.897908 -393.292838)
			(xy 118.897422 -393.320089) (xy 118.889666 -393.374037) (xy 118.874311 -393.426332) (xy 118.851669 -393.475909)
			(xy 118.822203 -393.521759) (xy 118.786512 -393.56295) (xy 118.745321 -393.598641) (xy 118.699471 -393.628107)
			(xy 118.649894 -393.650749) (xy 118.597599 -393.666104) (xy 118.543651 -393.67386) (xy 118.489149 -393.67386)
			(xy 118.435201 -393.666104) (xy 118.382906 -393.650749) (xy 118.333329 -393.628107) (xy 118.287479 -393.598641)
			(xy 118.246288 -393.56295) (xy 118.210597 -393.521759) (xy 118.181131 -393.475909) (xy 118.158489 -393.426332)
			(xy 118.143134 -393.374037) (xy 118.135378 -393.320089) (xy 118.134892 -393.292838) (xy 117.698012 -393.292838)
			(xy 117.697526 -393.320089) (xy 117.68977 -393.374037) (xy 117.674415 -393.426332) (xy 117.651773 -393.475909)
			(xy 117.622307 -393.521759) (xy 117.586616 -393.56295) (xy 117.545425 -393.598641) (xy 117.499575 -393.628107)
			(xy 117.449998 -393.650749) (xy 117.397703 -393.666104) (xy 117.343755 -393.67386) (xy 117.289253 -393.67386)
			(xy 117.235305 -393.666104) (xy 117.18301 -393.650749) (xy 117.133433 -393.628107) (xy 117.087583 -393.598641)
			(xy 117.046392 -393.56295) (xy 117.010701 -393.521759) (xy 116.981235 -393.475909) (xy 116.958593 -393.426332)
			(xy 116.943238 -393.374037) (xy 116.935482 -393.320089) (xy 116.934996 -393.292838) (xy 116.498116 -393.292838)
			(xy 116.49763 -393.320107) (xy 116.489868 -393.374091) (xy 116.474503 -393.426421) (xy 116.451846 -393.476031)
			(xy 116.42236 -393.521912) (xy 116.386645 -393.563129) (xy 116.345428 -393.598844) (xy 116.299547 -393.62833)
			(xy 116.249937 -393.650987) (xy 116.197607 -393.666352) (xy 116.143623 -393.674114) (xy 116.089085 -393.674114)
			(xy 116.035101 -393.666352) (xy 115.982771 -393.650987) (xy 115.933161 -393.62833) (xy 115.88728 -393.598844)
			(xy 115.846063 -393.563129) (xy 115.810348 -393.521912) (xy 115.780862 -393.476031) (xy 115.758205 -393.426421)
			(xy 115.74284 -393.374091) (xy 115.735078 -393.320107) (xy 115.734592 -393.292838) (xy 115.29822 -393.292838)
			(xy 115.297734 -393.320107) (xy 115.289972 -393.374091) (xy 115.274607 -393.426421) (xy 115.25195 -393.476031)
			(xy 115.222464 -393.521912) (xy 115.186749 -393.563129) (xy 115.145532 -393.598844) (xy 115.099651 -393.62833)
			(xy 115.050041 -393.650987) (xy 114.997711 -393.666352) (xy 114.943727 -393.674114) (xy 114.889189 -393.674114)
			(xy 114.835205 -393.666352) (xy 114.782875 -393.650987) (xy 114.733265 -393.62833) (xy 114.687384 -393.598844)
			(xy 114.646167 -393.563129) (xy 114.610452 -393.521912) (xy 114.580966 -393.476031) (xy 114.558309 -393.426421)
			(xy 114.542944 -393.374091) (xy 114.535182 -393.320107) (xy 114.534696 -393.292838) (xy 98.725736 -393.292838)
			(xy 98.72525 -393.320089) (xy 98.717494 -393.374037) (xy 98.702139 -393.426332) (xy 98.679497 -393.475909)
			(xy 98.650031 -393.521759) (xy 98.61434 -393.56295) (xy 98.573149 -393.598641) (xy 98.527299 -393.628107)
			(xy 98.477722 -393.650749) (xy 98.425427 -393.666104) (xy 98.371479 -393.67386) (xy 98.316977 -393.67386)
			(xy 98.263029 -393.666104) (xy 98.210734 -393.650749) (xy 98.161157 -393.628107) (xy 98.115307 -393.598641)
			(xy 98.074116 -393.56295) (xy 98.038425 -393.521759) (xy 98.008959 -393.475909) (xy 97.986317 -393.426332)
			(xy 97.970962 -393.374037) (xy 97.963206 -393.320089) (xy 97.96272 -393.292838) (xy 97.52584 -393.292838)
			(xy 97.525354 -393.320089) (xy 97.517598 -393.374037) (xy 97.502243 -393.426332) (xy 97.479601 -393.475909)
			(xy 97.450135 -393.521759) (xy 97.414444 -393.56295) (xy 97.373253 -393.598641) (xy 97.327403 -393.628107)
			(xy 97.277826 -393.650749) (xy 97.225531 -393.666104) (xy 97.171583 -393.67386) (xy 97.117081 -393.67386)
			(xy 97.063133 -393.666104) (xy 97.010838 -393.650749) (xy 96.961261 -393.628107) (xy 96.915411 -393.598641)
			(xy 96.87422 -393.56295) (xy 96.838529 -393.521759) (xy 96.809063 -393.475909) (xy 96.786421 -393.426332)
			(xy 96.771066 -393.374037) (xy 96.76331 -393.320089) (xy 96.762824 -393.292838) (xy 96.325944 -393.292838)
			(xy 96.325458 -393.320107) (xy 96.317696 -393.374091) (xy 96.302331 -393.426421) (xy 96.279674 -393.476031)
			(xy 96.250188 -393.521912) (xy 96.214473 -393.563129) (xy 96.173256 -393.598844) (xy 96.127375 -393.62833)
			(xy 96.077765 -393.650987) (xy 96.025435 -393.666352) (xy 95.971451 -393.674114) (xy 95.916913 -393.674114)
			(xy 95.862929 -393.666352) (xy 95.810599 -393.650987) (xy 95.760989 -393.62833) (xy 95.715108 -393.598844)
			(xy 95.673891 -393.563129) (xy 95.638176 -393.521912) (xy 95.60869 -393.476031) (xy 95.586033 -393.426421)
			(xy 95.570668 -393.374091) (xy 95.562906 -393.320107) (xy 95.56242 -393.292838) (xy 95.126048 -393.292838)
			(xy 95.125562 -393.320107) (xy 95.1178 -393.374091) (xy 95.102435 -393.426421) (xy 95.079778 -393.476031)
			(xy 95.050292 -393.521912) (xy 95.014577 -393.563129) (xy 94.97336 -393.598844) (xy 94.927479 -393.62833)
			(xy 94.877869 -393.650987) (xy 94.825539 -393.666352) (xy 94.771555 -393.674114) (xy 94.717017 -393.674114)
			(xy 94.663033 -393.666352) (xy 94.610703 -393.650987) (xy 94.561093 -393.62833) (xy 94.515212 -393.598844)
			(xy 94.473995 -393.563129) (xy 94.43828 -393.521912) (xy 94.408794 -393.476031) (xy 94.386137 -393.426421)
			(xy 94.370772 -393.374091) (xy 94.36301 -393.320107) (xy 94.362524 -393.292838) (xy 93.926152 -393.292838)
			(xy 93.925666 -393.320107) (xy 93.917904 -393.374091) (xy 93.902539 -393.426421) (xy 93.879882 -393.476031)
			(xy 93.850396 -393.521912) (xy 93.814681 -393.563129) (xy 93.773464 -393.598844) (xy 93.727583 -393.62833)
			(xy 93.677973 -393.650987) (xy 93.625643 -393.666352) (xy 93.571659 -393.674114) (xy 93.517121 -393.674114)
			(xy 93.463137 -393.666352) (xy 93.410807 -393.650987) (xy 93.361197 -393.62833) (xy 93.315316 -393.598844)
			(xy 93.274099 -393.563129) (xy 93.238384 -393.521912) (xy 93.208898 -393.476031) (xy 93.186241 -393.426421)
			(xy 93.170876 -393.374091) (xy 93.163114 -393.320107) (xy 93.162628 -393.292838) (xy 92.726256 -393.292838)
			(xy 92.72577 -393.320107) (xy 92.718008 -393.374091) (xy 92.702643 -393.426421) (xy 92.679986 -393.476031)
			(xy 92.6505 -393.521912) (xy 92.614785 -393.563129) (xy 92.573568 -393.598844) (xy 92.527687 -393.62833)
			(xy 92.478077 -393.650987) (xy 92.425747 -393.666352) (xy 92.371763 -393.674114) (xy 92.317225 -393.674114)
			(xy 92.263241 -393.666352) (xy 92.210911 -393.650987) (xy 92.161301 -393.62833) (xy 92.11542 -393.598844)
			(xy 92.074203 -393.563129) (xy 92.038488 -393.521912) (xy 92.009002 -393.476031) (xy 91.986345 -393.426421)
			(xy 91.97098 -393.374091) (xy 91.963218 -393.320107) (xy 91.962732 -393.292838) (xy 91.525852 -393.292838)
			(xy 91.525366 -393.320089) (xy 91.51761 -393.374037) (xy 91.502255 -393.426332) (xy 91.479613 -393.475909)
			(xy 91.450147 -393.521759) (xy 91.414456 -393.56295) (xy 91.373265 -393.598641) (xy 91.327415 -393.628107)
			(xy 91.277838 -393.650749) (xy 91.225543 -393.666104) (xy 91.171595 -393.67386) (xy 91.117093 -393.67386)
			(xy 91.063145 -393.666104) (xy 91.01085 -393.650749) (xy 90.961273 -393.628107) (xy 90.915423 -393.598641)
			(xy 90.874232 -393.56295) (xy 90.838541 -393.521759) (xy 90.809075 -393.475909) (xy 90.786433 -393.426332)
			(xy 90.771078 -393.374037) (xy 90.763322 -393.320089) (xy 90.762836 -393.292838) (xy 90.325956 -393.292838)
			(xy 90.32547 -393.320089) (xy 90.317714 -393.374037) (xy 90.302359 -393.426332) (xy 90.279717 -393.475909)
			(xy 90.250251 -393.521759) (xy 90.21456 -393.56295) (xy 90.173369 -393.598641) (xy 90.127519 -393.628107)
			(xy 90.077942 -393.650749) (xy 90.025647 -393.666104) (xy 89.971699 -393.67386) (xy 89.917197 -393.67386)
			(xy 89.863249 -393.666104) (xy 89.810954 -393.650749) (xy 89.761377 -393.628107) (xy 89.715527 -393.598641)
			(xy 89.674336 -393.56295) (xy 89.638645 -393.521759) (xy 89.609179 -393.475909) (xy 89.586537 -393.426332)
			(xy 89.571182 -393.374037) (xy 89.563426 -393.320089) (xy 89.56294 -393.292838) (xy 89.12606 -393.292838)
			(xy 89.125574 -393.320107) (xy 89.117812 -393.374091) (xy 89.102447 -393.426421) (xy 89.07979 -393.476031)
			(xy 89.050304 -393.521912) (xy 89.014589 -393.563129) (xy 88.973372 -393.598844) (xy 88.927491 -393.62833)
			(xy 88.877881 -393.650987) (xy 88.825551 -393.666352) (xy 88.771567 -393.674114) (xy 88.717029 -393.674114)
			(xy 88.663045 -393.666352) (xy 88.610715 -393.650987) (xy 88.561105 -393.62833) (xy 88.515224 -393.598844)
			(xy 88.474007 -393.563129) (xy 88.438292 -393.521912) (xy 88.408806 -393.476031) (xy 88.386149 -393.426421)
			(xy 88.370784 -393.374091) (xy 88.363022 -393.320107) (xy 88.362536 -393.292838) (xy 87.926164 -393.292838)
			(xy 87.925678 -393.320107) (xy 87.917916 -393.374091) (xy 87.902551 -393.426421) (xy 87.879894 -393.476031)
			(xy 87.850408 -393.521912) (xy 87.814693 -393.563129) (xy 87.773476 -393.598844) (xy 87.727595 -393.62833)
			(xy 87.677985 -393.650987) (xy 87.625655 -393.666352) (xy 87.571671 -393.674114) (xy 87.517133 -393.674114)
			(xy 87.463149 -393.666352) (xy 87.410819 -393.650987) (xy 87.361209 -393.62833) (xy 87.315328 -393.598844)
			(xy 87.274111 -393.563129) (xy 87.238396 -393.521912) (xy 87.20891 -393.476031) (xy 87.186253 -393.426421)
			(xy 87.170888 -393.374091) (xy 87.163126 -393.320107) (xy 87.16264 -393.292838) (xy 86.72576 -393.292838)
			(xy 86.725274 -393.320089) (xy 86.717518 -393.374037) (xy 86.702163 -393.426332) (xy 86.679521 -393.475909)
			(xy 86.650055 -393.521759) (xy 86.614364 -393.56295) (xy 86.573173 -393.598641) (xy 86.527323 -393.628107)
			(xy 86.477746 -393.650749) (xy 86.425451 -393.666104) (xy 86.371503 -393.67386) (xy 86.317001 -393.67386)
			(xy 86.263053 -393.666104) (xy 86.210758 -393.650749) (xy 86.161181 -393.628107) (xy 86.115331 -393.598641)
			(xy 86.07414 -393.56295) (xy 86.038449 -393.521759) (xy 86.008983 -393.475909) (xy 85.986341 -393.426332)
			(xy 85.970986 -393.374037) (xy 85.96323 -393.320089) (xy 85.962744 -393.292838) (xy 85.525864 -393.292838)
			(xy 85.525378 -393.320089) (xy 85.517622 -393.374037) (xy 85.502267 -393.426332) (xy 85.479625 -393.475909)
			(xy 85.450159 -393.521759) (xy 85.414468 -393.56295) (xy 85.373277 -393.598641) (xy 85.327427 -393.628107)
			(xy 85.27785 -393.650749) (xy 85.225555 -393.666104) (xy 85.171607 -393.67386) (xy 85.117105 -393.67386)
			(xy 85.063157 -393.666104) (xy 85.010862 -393.650749) (xy 84.961285 -393.628107) (xy 84.915435 -393.598641)
			(xy 84.874244 -393.56295) (xy 84.838553 -393.521759) (xy 84.809087 -393.475909) (xy 84.786445 -393.426332)
			(xy 84.77109 -393.374037) (xy 84.763334 -393.320089) (xy 84.762848 -393.292838) (xy 84.325968 -393.292838)
			(xy 84.325482 -393.320107) (xy 84.31772 -393.374091) (xy 84.302355 -393.426421) (xy 84.279698 -393.476031)
			(xy 84.250212 -393.521912) (xy 84.214497 -393.563129) (xy 84.17328 -393.598844) (xy 84.127399 -393.62833)
			(xy 84.077789 -393.650987) (xy 84.025459 -393.666352) (xy 83.971475 -393.674114) (xy 83.916937 -393.674114)
			(xy 83.862953 -393.666352) (xy 83.810623 -393.650987) (xy 83.761013 -393.62833) (xy 83.715132 -393.598844)
			(xy 83.673915 -393.563129) (xy 83.6382 -393.521912) (xy 83.608714 -393.476031) (xy 83.586057 -393.426421)
			(xy 83.570692 -393.374091) (xy 83.56293 -393.320107) (xy 83.562444 -393.292838) (xy 83.126072 -393.292838)
			(xy 83.125586 -393.320107) (xy 83.117824 -393.374091) (xy 83.102459 -393.426421) (xy 83.079802 -393.476031)
			(xy 83.050316 -393.521912) (xy 83.014601 -393.563129) (xy 82.973384 -393.598844) (xy 82.927503 -393.62833)
			(xy 82.877893 -393.650987) (xy 82.825563 -393.666352) (xy 82.771579 -393.674114) (xy 82.717041 -393.674114)
			(xy 82.663057 -393.666352) (xy 82.610727 -393.650987) (xy 82.561117 -393.62833) (xy 82.515236 -393.598844)
			(xy 82.474019 -393.563129) (xy 82.438304 -393.521912) (xy 82.408818 -393.476031) (xy 82.386161 -393.426421)
			(xy 82.370796 -393.374091) (xy 82.363034 -393.320107) (xy 82.362548 -393.292838) (xy 81.925668 -393.292838)
			(xy 81.925182 -393.320089) (xy 81.917426 -393.374037) (xy 81.902071 -393.426332) (xy 81.879429 -393.475909)
			(xy 81.849963 -393.521759) (xy 81.814272 -393.56295) (xy 81.773081 -393.598641) (xy 81.727231 -393.628107)
			(xy 81.677654 -393.650749) (xy 81.625359 -393.666104) (xy 81.571411 -393.67386) (xy 81.516909 -393.67386)
			(xy 81.462961 -393.666104) (xy 81.410666 -393.650749) (xy 81.361089 -393.628107) (xy 81.315239 -393.598641)
			(xy 81.274048 -393.56295) (xy 81.238357 -393.521759) (xy 81.208891 -393.475909) (xy 81.186249 -393.426332)
			(xy 81.170894 -393.374037) (xy 81.163138 -393.320089) (xy 81.162652 -393.292838) (xy 80.725772 -393.292838)
			(xy 80.725286 -393.320089) (xy 80.71753 -393.374037) (xy 80.702175 -393.426332) (xy 80.679533 -393.475909)
			(xy 80.650067 -393.521759) (xy 80.614376 -393.56295) (xy 80.573185 -393.598641) (xy 80.527335 -393.628107)
			(xy 80.477758 -393.650749) (xy 80.425463 -393.666104) (xy 80.371515 -393.67386) (xy 80.317013 -393.67386)
			(xy 80.263065 -393.666104) (xy 80.21077 -393.650749) (xy 80.161193 -393.628107) (xy 80.115343 -393.598641)
			(xy 80.074152 -393.56295) (xy 80.038461 -393.521759) (xy 80.008995 -393.475909) (xy 79.986353 -393.426332)
			(xy 79.970998 -393.374037) (xy 79.963242 -393.320089) (xy 79.962756 -393.292838) (xy 66.197988 -393.292838)
			(xy 66.197502 -393.320089) (xy 66.189746 -393.374037) (xy 66.174391 -393.426332) (xy 66.151749 -393.475909)
			(xy 66.122283 -393.521759) (xy 66.086592 -393.56295) (xy 66.045401 -393.598641) (xy 65.999551 -393.628107)
			(xy 65.949974 -393.650749) (xy 65.897679 -393.666104) (xy 65.843731 -393.67386) (xy 65.789229 -393.67386)
			(xy 65.735281 -393.666104) (xy 65.682986 -393.650749) (xy 65.633409 -393.628107) (xy 65.587559 -393.598641)
			(xy 65.546368 -393.56295) (xy 65.510677 -393.521759) (xy 65.481211 -393.475909) (xy 65.458569 -393.426332)
			(xy 65.443214 -393.374037) (xy 65.435458 -393.320089) (xy 65.434972 -393.292838) (xy 64.998092 -393.292838)
			(xy 64.997606 -393.320089) (xy 64.98985 -393.374037) (xy 64.974495 -393.426332) (xy 64.951853 -393.475909)
			(xy 64.922387 -393.521759) (xy 64.886696 -393.56295) (xy 64.845505 -393.598641) (xy 64.799655 -393.628107)
			(xy 64.750078 -393.650749) (xy 64.697783 -393.666104) (xy 64.643835 -393.67386) (xy 64.589333 -393.67386)
			(xy 64.535385 -393.666104) (xy 64.48309 -393.650749) (xy 64.433513 -393.628107) (xy 64.387663 -393.598641)
			(xy 64.346472 -393.56295) (xy 64.310781 -393.521759) (xy 64.281315 -393.475909) (xy 64.258673 -393.426332)
			(xy 64.243318 -393.374037) (xy 64.235562 -393.320089) (xy 64.235076 -393.292838) (xy 63.798196 -393.292838)
			(xy 63.79771 -393.320107) (xy 63.789948 -393.374091) (xy 63.774583 -393.426421) (xy 63.751926 -393.476031)
			(xy 63.72244 -393.521912) (xy 63.686725 -393.563129) (xy 63.645508 -393.598844) (xy 63.599627 -393.62833)
			(xy 63.550017 -393.650987) (xy 63.497687 -393.666352) (xy 63.443703 -393.674114) (xy 63.389165 -393.674114)
			(xy 63.335181 -393.666352) (xy 63.282851 -393.650987) (xy 63.233241 -393.62833) (xy 63.18736 -393.598844)
			(xy 63.146143 -393.563129) (xy 63.110428 -393.521912) (xy 63.080942 -393.476031) (xy 63.058285 -393.426421)
			(xy 63.04292 -393.374091) (xy 63.035158 -393.320107) (xy 63.034672 -393.292838) (xy 62.5983 -393.292838)
			(xy 62.597814 -393.320107) (xy 62.590052 -393.374091) (xy 62.574687 -393.426421) (xy 62.55203 -393.476031)
			(xy 62.522544 -393.521912) (xy 62.486829 -393.563129) (xy 62.445612 -393.598844) (xy 62.399731 -393.62833)
			(xy 62.350121 -393.650987) (xy 62.297791 -393.666352) (xy 62.243807 -393.674114) (xy 62.189269 -393.674114)
			(xy 62.135285 -393.666352) (xy 62.082955 -393.650987) (xy 62.033345 -393.62833) (xy 61.987464 -393.598844)
			(xy 61.946247 -393.563129) (xy 61.910532 -393.521912) (xy 61.881046 -393.476031) (xy 61.858389 -393.426421)
			(xy 61.843024 -393.374091) (xy 61.835262 -393.320107) (xy 61.834776 -393.292838) (xy 61.398404 -393.292838)
			(xy 61.397918 -393.320107) (xy 61.390156 -393.374091) (xy 61.374791 -393.426421) (xy 61.352134 -393.476031)
			(xy 61.322648 -393.521912) (xy 61.286933 -393.563129) (xy 61.245716 -393.598844) (xy 61.199835 -393.62833)
			(xy 61.150225 -393.650987) (xy 61.097895 -393.666352) (xy 61.043911 -393.674114) (xy 60.989373 -393.674114)
			(xy 60.935389 -393.666352) (xy 60.883059 -393.650987) (xy 60.833449 -393.62833) (xy 60.787568 -393.598844)
			(xy 60.746351 -393.563129) (xy 60.710636 -393.521912) (xy 60.68115 -393.476031) (xy 60.658493 -393.426421)
			(xy 60.643128 -393.374091) (xy 60.635366 -393.320107) (xy 60.63488 -393.292838) (xy 60.198508 -393.292838)
			(xy 60.198022 -393.320107) (xy 60.19026 -393.374091) (xy 60.174895 -393.426421) (xy 60.152238 -393.476031)
			(xy 60.122752 -393.521912) (xy 60.087037 -393.563129) (xy 60.04582 -393.598844) (xy 59.999939 -393.62833)
			(xy 59.950329 -393.650987) (xy 59.897999 -393.666352) (xy 59.844015 -393.674114) (xy 59.789477 -393.674114)
			(xy 59.735493 -393.666352) (xy 59.683163 -393.650987) (xy 59.633553 -393.62833) (xy 59.587672 -393.598844)
			(xy 59.546455 -393.563129) (xy 59.51074 -393.521912) (xy 59.481254 -393.476031) (xy 59.458597 -393.426421)
			(xy 59.443232 -393.374091) (xy 59.43547 -393.320107) (xy 59.434984 -393.292838) (xy 58.998104 -393.292838)
			(xy 58.997618 -393.320089) (xy 58.989862 -393.374037) (xy 58.974507 -393.426332) (xy 58.951865 -393.475909)
			(xy 58.922399 -393.521759) (xy 58.886708 -393.56295) (xy 58.845517 -393.598641) (xy 58.799667 -393.628107)
			(xy 58.75009 -393.650749) (xy 58.697795 -393.666104) (xy 58.643847 -393.67386) (xy 58.589345 -393.67386)
			(xy 58.535397 -393.666104) (xy 58.483102 -393.650749) (xy 58.433525 -393.628107) (xy 58.387675 -393.598641)
			(xy 58.346484 -393.56295) (xy 58.310793 -393.521759) (xy 58.281327 -393.475909) (xy 58.258685 -393.426332)
			(xy 58.24333 -393.374037) (xy 58.235574 -393.320089) (xy 58.235088 -393.292838) (xy 57.798208 -393.292838)
			(xy 57.797722 -393.320089) (xy 57.789966 -393.374037) (xy 57.774611 -393.426332) (xy 57.751969 -393.475909)
			(xy 57.722503 -393.521759) (xy 57.686812 -393.56295) (xy 57.645621 -393.598641) (xy 57.599771 -393.628107)
			(xy 57.550194 -393.650749) (xy 57.497899 -393.666104) (xy 57.443951 -393.67386) (xy 57.389449 -393.67386)
			(xy 57.335501 -393.666104) (xy 57.283206 -393.650749) (xy 57.233629 -393.628107) (xy 57.187779 -393.598641)
			(xy 57.146588 -393.56295) (xy 57.110897 -393.521759) (xy 57.081431 -393.475909) (xy 57.058789 -393.426332)
			(xy 57.043434 -393.374037) (xy 57.035678 -393.320089) (xy 57.035192 -393.292838) (xy 56.598312 -393.292838)
			(xy 56.597826 -393.320107) (xy 56.590064 -393.374091) (xy 56.574699 -393.426421) (xy 56.552042 -393.476031)
			(xy 56.522556 -393.521912) (xy 56.486841 -393.563129) (xy 56.445624 -393.598844) (xy 56.399743 -393.62833)
			(xy 56.350133 -393.650987) (xy 56.297803 -393.666352) (xy 56.243819 -393.674114) (xy 56.189281 -393.674114)
			(xy 56.135297 -393.666352) (xy 56.082967 -393.650987) (xy 56.033357 -393.62833) (xy 55.987476 -393.598844)
			(xy 55.946259 -393.563129) (xy 55.910544 -393.521912) (xy 55.881058 -393.476031) (xy 55.858401 -393.426421)
			(xy 55.843036 -393.374091) (xy 55.835274 -393.320107) (xy 55.834788 -393.292838) (xy 55.398416 -393.292838)
			(xy 55.39793 -393.320107) (xy 55.390168 -393.374091) (xy 55.374803 -393.426421) (xy 55.352146 -393.476031)
			(xy 55.32266 -393.521912) (xy 55.286945 -393.563129) (xy 55.245728 -393.598844) (xy 55.199847 -393.62833)
			(xy 55.150237 -393.650987) (xy 55.097907 -393.666352) (xy 55.043923 -393.674114) (xy 54.989385 -393.674114)
			(xy 54.935401 -393.666352) (xy 54.883071 -393.650987) (xy 54.833461 -393.62833) (xy 54.78758 -393.598844)
			(xy 54.746363 -393.563129) (xy 54.710648 -393.521912) (xy 54.681162 -393.476031) (xy 54.658505 -393.426421)
			(xy 54.64314 -393.374091) (xy 54.635378 -393.320107) (xy 54.634892 -393.292838) (xy 54.198012 -393.292838)
			(xy 54.197526 -393.320089) (xy 54.18977 -393.374037) (xy 54.174415 -393.426332) (xy 54.151773 -393.475909)
			(xy 54.122307 -393.521759) (xy 54.086616 -393.56295) (xy 54.045425 -393.598641) (xy 53.999575 -393.628107)
			(xy 53.949998 -393.650749) (xy 53.897703 -393.666104) (xy 53.843755 -393.67386) (xy 53.789253 -393.67386)
			(xy 53.735305 -393.666104) (xy 53.68301 -393.650749) (xy 53.633433 -393.628107) (xy 53.587583 -393.598641)
			(xy 53.546392 -393.56295) (xy 53.510701 -393.521759) (xy 53.481235 -393.475909) (xy 53.458593 -393.426332)
			(xy 53.443238 -393.374037) (xy 53.435482 -393.320089) (xy 53.434996 -393.292838) (xy 52.998116 -393.292838)
			(xy 52.99763 -393.320089) (xy 52.989874 -393.374037) (xy 52.974519 -393.426332) (xy 52.951877 -393.475909)
			(xy 52.922411 -393.521759) (xy 52.88672 -393.56295) (xy 52.845529 -393.598641) (xy 52.799679 -393.628107)
			(xy 52.750102 -393.650749) (xy 52.697807 -393.666104) (xy 52.643859 -393.67386) (xy 52.589357 -393.67386)
			(xy 52.535409 -393.666104) (xy 52.483114 -393.650749) (xy 52.433537 -393.628107) (xy 52.387687 -393.598641)
			(xy 52.346496 -393.56295) (xy 52.310805 -393.521759) (xy 52.281339 -393.475909) (xy 52.258697 -393.426332)
			(xy 52.243342 -393.374037) (xy 52.235586 -393.320089) (xy 52.2351 -393.292838) (xy 51.79822 -393.292838)
			(xy 51.797734 -393.320107) (xy 51.789972 -393.374091) (xy 51.774607 -393.426421) (xy 51.75195 -393.476031)
			(xy 51.722464 -393.521912) (xy 51.686749 -393.563129) (xy 51.645532 -393.598844) (xy 51.599651 -393.62833)
			(xy 51.550041 -393.650987) (xy 51.497711 -393.666352) (xy 51.443727 -393.674114) (xy 51.389189 -393.674114)
			(xy 51.335205 -393.666352) (xy 51.282875 -393.650987) (xy 51.233265 -393.62833) (xy 51.187384 -393.598844)
			(xy 51.146167 -393.563129) (xy 51.110452 -393.521912) (xy 51.080966 -393.476031) (xy 51.058309 -393.426421)
			(xy 51.042944 -393.374091) (xy 51.035182 -393.320107) (xy 51.034696 -393.292838) (xy 50.598324 -393.292838)
			(xy 50.597838 -393.320107) (xy 50.590076 -393.374091) (xy 50.574711 -393.426421) (xy 50.552054 -393.476031)
			(xy 50.522568 -393.521912) (xy 50.486853 -393.563129) (xy 50.445636 -393.598844) (xy 50.399755 -393.62833)
			(xy 50.350145 -393.650987) (xy 50.297815 -393.666352) (xy 50.243831 -393.674114) (xy 50.189293 -393.674114)
			(xy 50.135309 -393.666352) (xy 50.082979 -393.650987) (xy 50.033369 -393.62833) (xy 49.987488 -393.598844)
			(xy 49.946271 -393.563129) (xy 49.910556 -393.521912) (xy 49.88107 -393.476031) (xy 49.858413 -393.426421)
			(xy 49.843048 -393.374091) (xy 49.835286 -393.320107) (xy 49.8348 -393.292838) (xy 49.39792 -393.292838)
			(xy 49.397434 -393.320089) (xy 49.389678 -393.374037) (xy 49.374323 -393.426332) (xy 49.351681 -393.475909)
			(xy 49.322215 -393.521759) (xy 49.286524 -393.56295) (xy 49.245333 -393.598641) (xy 49.199483 -393.628107)
			(xy 49.149906 -393.650749) (xy 49.097611 -393.666104) (xy 49.043663 -393.67386) (xy 48.989161 -393.67386)
			(xy 48.935213 -393.666104) (xy 48.882918 -393.650749) (xy 48.833341 -393.628107) (xy 48.787491 -393.598641)
			(xy 48.7463 -393.56295) (xy 48.710609 -393.521759) (xy 48.681143 -393.475909) (xy 48.658501 -393.426332)
			(xy 48.643146 -393.374037) (xy 48.63539 -393.320089) (xy 48.634904 -393.292838) (xy 48.198024 -393.292838)
			(xy 48.197538 -393.320089) (xy 48.189782 -393.374037) (xy 48.174427 -393.426332) (xy 48.151785 -393.475909)
			(xy 48.122319 -393.521759) (xy 48.086628 -393.56295) (xy 48.045437 -393.598641) (xy 47.999587 -393.628107)
			(xy 47.95001 -393.650749) (xy 47.897715 -393.666104) (xy 47.843767 -393.67386) (xy 47.789265 -393.67386)
			(xy 47.735317 -393.666104) (xy 47.683022 -393.650749) (xy 47.633445 -393.628107) (xy 47.587595 -393.598641)
			(xy 47.546404 -393.56295) (xy 47.510713 -393.521759) (xy 47.481247 -393.475909) (xy 47.458605 -393.426332)
			(xy 47.44325 -393.374037) (xy 47.435494 -393.320089) (xy 47.435008 -393.292838) (xy 2.509012 -393.292838)
			(xy 2.509012 -400.50847) (xy 103.485188 -400.50847) (xy 103.485723 -400.479553) (xy 103.494444 -400.422381)
			(xy 103.511697 -400.367182) (xy 103.537085 -400.315219) (xy 103.570027 -400.267685) (xy 103.609768 -400.225669)
			(xy 103.632254 -400.20748) (xy 103.64103 -400.199932) (xy 103.651203 -400.179162) (xy 103.651812 -400.167602)
			(xy 103.651812 -400.087338) (xy 103.651216 -400.075774) (xy 103.641039 -400.055003) (xy 103.632254 -400.04746)
			(xy 103.609742 -400.029303) (xy 103.57001 -399.987275) (xy 103.537076 -399.939733) (xy 103.511693 -399.887765)
			(xy 103.494443 -399.832562) (xy 103.48572 -399.775388) (xy 103.485188 -399.74647) (xy 103.485674 -399.719201)
			(xy 103.493436 -399.665217) (xy 103.508801 -399.612887) (xy 103.531458 -399.563277) (xy 103.560944 -399.517396)
			(xy 103.596659 -399.476179) (xy 103.637876 -399.440464) (xy 103.683757 -399.410978) (xy 103.733367 -399.388321)
			(xy 103.785697 -399.372956) (xy 103.839681 -399.365194) (xy 103.894219 -399.365194) (xy 103.948203 -399.372956)
			(xy 104.000533 -399.388321) (xy 104.050143 -399.410978) (xy 104.096024 -399.440464) (xy 104.137241 -399.476179)
			(xy 104.172956 -399.517396) (xy 104.202442 -399.563277) (xy 104.225099 -399.612887) (xy 104.240464 -399.665217)
			(xy 104.248226 -399.719201) (xy 104.248712 -399.74647) (xy 104.248206 -399.775388) (xy 104.239479 -399.832561)
			(xy 104.222221 -399.887762) (xy 104.196827 -399.939724) (xy 104.16388 -399.987257) (xy 104.124134 -400.029272)
			(xy 104.101646 -400.04746) (xy 104.092897 -400.055034) (xy 104.082709 -400.075784) (xy 104.082088 -400.087338)
			(xy 104.082088 -400.167602) (xy 104.082662 -400.179169) (xy 104.092854 -400.19994) (xy 104.101646 -400.20748)
			(xy 104.124129 -400.225671) (xy 104.163863 -400.267692) (xy 104.1968 -400.315227) (xy 104.222188 -400.367188)
			(xy 104.239445 -400.422385) (xy 104.248176 -400.479554) (xy 104.248712 -400.50847) (xy 104.248226 -400.535739)
			(xy 104.240464 -400.589723) (xy 104.225099 -400.642053) (xy 104.202442 -400.691663) (xy 104.172956 -400.737544)
			(xy 104.137241 -400.778761) (xy 104.096024 -400.814476) (xy 104.050143 -400.843962) (xy 104.000533 -400.866619)
			(xy 103.948203 -400.881984) (xy 103.894219 -400.889746) (xy 103.839681 -400.889746) (xy 103.785697 -400.881984)
			(xy 103.733367 -400.866619) (xy 103.683757 -400.843962) (xy 103.637876 -400.814476) (xy 103.596659 -400.778761)
			(xy 103.560944 -400.737544) (xy 103.531458 -400.691663) (xy 103.508801 -400.642053) (xy 103.493436 -400.589723)
			(xy 103.485674 -400.535739) (xy 103.485188 -400.50847) (xy 2.509012 -400.50847) (xy 2.509012 -403.371812)
			(xy 2.5095 -403.425034) (xy 2.517117 -403.531207) (xy 2.532283 -403.636566) (xy 2.554922 -403.740575)
			(xy 2.584919 -403.842706) (xy 2.622121 -403.942439) (xy 2.666338 -404.039266) (xy 2.717346 -404.132693)
			(xy 2.774884 -404.222247) (xy 2.838661 -404.307471) (xy 2.908351 -404.387931) (xy 2.945638 -404.425912)
			(xy 3.30962 -404.789894) (xy 37.568898 -404.789894) (xy 37.57287 -404.611651) (xy 37.584778 -404.433762)
			(xy 37.604599 -404.25658) (xy 37.632293 -404.080456) (xy 37.667805 -403.905741) (xy 37.711065 -403.732782)
			(xy 37.761987 -403.561921) (xy 37.82047 -403.393499) (xy 37.886397 -403.227849) (xy 37.959638 -403.0653)
			(xy 38.040048 -402.906175) (xy 38.127466 -402.75079) (xy 38.221719 -402.599454) (xy 38.32262 -402.452466)
			(xy 38.429969 -402.310119) (xy 38.543552 -402.172696) (xy 38.663145 -402.040469) (xy 38.788509 -401.9137)
			(xy 38.919396 -401.792642) (xy 39.055545 -401.677535) (xy 39.196687 -401.568607) (xy 39.342542 -401.466075)
			(xy 39.492819 -401.370141) (xy 39.64722 -401.280998) (xy 39.805439 -401.198821) (xy 39.967162 -401.123773)
			(xy 40.132067 -401.056005) (xy 40.299828 -400.995649) (xy 40.470111 -400.942827) (xy 40.642578 -400.897643)
			(xy 40.816886 -400.860186) (xy 40.99269 -400.830532) (xy 41.16964 -400.808739) (xy 41.347386 -400.794849)
			(xy 41.525573 -400.788892) (xy 41.70385 -400.790878) (xy 41.881861 -400.800804) (xy 42.059253 -400.81865)
			(xy 42.235673 -400.84438) (xy 42.410773 -400.877944) (xy 42.584204 -400.919274) (xy 42.755621 -400.96829)
			(xy 42.924684 -401.024892) (xy 43.091059 -401.08897) (xy 43.254413 -401.160396) (xy 43.414424 -401.239028)
			(xy 43.570773 -401.324709) (xy 43.72315 -401.417271) (xy 43.871253 -401.516528) (xy 44.014787 -401.622285)
			(xy 44.153467 -401.73433) (xy 44.287018 -401.852442) (xy 44.415175 -401.976386) (xy 44.537684 -402.105916)
			(xy 44.654301 -402.240775) (xy 44.764794 -402.380695) (xy 44.868945 -402.525398) (xy 44.966547 -402.674597)
			(xy 45.057405 -402.827996) (xy 45.141339 -402.98529) (xy 45.218184 -403.146166) (xy 45.287785 -403.310307)
			(xy 45.350006 -403.477384) (xy 45.404722 -403.647068) (xy 45.451824 -403.819021) (xy 45.49122 -403.992901)
			(xy 45.522831 -404.168364) (xy 45.546595 -404.34506) (xy 45.559703 -404.491748) (xy 47.413198 -404.491748)
			(xy 47.413198 -404.437252) (xy 47.420953 -404.38331) (xy 47.436306 -404.331021) (xy 47.458943 -404.281449)
			(xy 47.488404 -404.235603) (xy 47.52409 -404.194416) (xy 47.565274 -404.158726) (xy 47.611117 -404.12926)
			(xy 47.660687 -404.106618) (xy 47.712975 -404.091261) (xy 47.766916 -404.083501) (xy 47.794164 -404.083012)
			(xy 48.657764 -404.083012) (xy 48.68502 -404.083432) (xy 48.738978 -404.091186) (xy 48.791283 -404.106539)
			(xy 48.84087 -404.129181) (xy 48.88673 -404.15865) (xy 48.927929 -404.194345) (xy 48.963629 -404.235541)
			(xy 48.993102 -404.281398) (xy 49.015748 -404.330984) (xy 49.031107 -404.383287) (xy 49.038865 -404.437244)
			(xy 49.038865 -404.491752) (xy 50.476375 -404.491752) (xy 50.476375 -404.437248) (xy 50.484132 -404.3833)
			(xy 50.499487 -404.331005) (xy 50.522129 -404.281427) (xy 50.551596 -404.235576) (xy 50.587288 -404.194385)
			(xy 50.628479 -404.158693) (xy 50.67433 -404.129227) (xy 50.723908 -404.106586) (xy 50.776204 -404.091231)
			(xy 50.830152 -404.083475) (xy 50.857404 -404.083012) (xy 51.721004 -404.083012) (xy 51.748256 -404.083458)
			(xy 51.802207 -404.091215) (xy 51.854504 -404.106572) (xy 51.904083 -404.129214) (xy 51.949935 -404.158682)
			(xy 51.991127 -404.194376) (xy 52.02682 -404.235568) (xy 52.056288 -404.281421) (xy 52.07893 -404.331)
			(xy 52.094285 -404.383297) (xy 52.102042 -404.437248) (xy 52.102042 -404.491752) (xy 52.102042 -404.491753)
			(xy 53.539575 -404.491753) (xy 53.539575 -404.437247) (xy 53.547333 -404.383295) (xy 53.562691 -404.330996)
			(xy 53.585335 -404.281416) (xy 53.614806 -404.235563) (xy 53.650502 -404.194371) (xy 53.691698 -404.158679)
			(xy 53.737554 -404.129214) (xy 53.787137 -404.106575) (xy 53.839438 -404.091224) (xy 53.893391 -404.083472)
			(xy 53.920644 -404.083012) (xy 54.784244 -404.083012) (xy 54.811495 -404.083461) (xy 54.86544 -404.091223)
			(xy 54.917733 -404.106583) (xy 54.967307 -404.129227) (xy 55.013154 -404.158696) (xy 55.054341 -404.19439)
			(xy 55.09003 -404.235581) (xy 55.119494 -404.281432) (xy 55.142133 -404.331009) (xy 55.157487 -404.383303)
			(xy 55.165242 -404.437249) (xy 55.165242 -404.491749) (xy 56.602898 -404.491749) (xy 56.602898 -404.437251)
			(xy 56.610654 -404.383308) (xy 56.626007 -404.331017) (xy 56.648646 -404.281443) (xy 56.678109 -404.235596)
			(xy 56.713797 -404.194409) (xy 56.754983 -404.158719) (xy 56.800829 -404.129254) (xy 56.850402 -404.106613)
			(xy 56.902692 -404.091257) (xy 56.956635 -404.083499) (xy 56.983884 -404.083012) (xy 57.847484 -404.083012)
			(xy 57.874739 -404.083434) (xy 57.928695 -404.091189) (xy 57.980997 -404.106545) (xy 58.030582 -404.129188)
			(xy 58.07644 -404.158657) (xy 58.117636 -404.194352) (xy 58.153334 -404.235548) (xy 58.182805 -404.281404)
			(xy 58.20545 -404.330988) (xy 58.220807 -404.38329) (xy 58.228565 -404.437245) (xy 58.228565 -404.491753)
			(xy 59.666075 -404.491753) (xy 59.666075 -404.437247) (xy 59.673833 -404.383297) (xy 59.689189 -404.331)
			(xy 59.711832 -404.281421) (xy 59.741301 -404.235569) (xy 59.776995 -404.194378) (xy 59.818188 -404.158686)
			(xy 59.864042 -404.129221) (xy 59.913623 -404.106581) (xy 59.965921 -404.091227) (xy 60.019871 -404.083474)
			(xy 60.047124 -404.083012) (xy 60.910724 -404.083012) (xy 60.937976 -404.083459) (xy 60.991924 -404.091219)
			(xy 61.044218 -404.106577) (xy 61.093795 -404.129221) (xy 61.139645 -404.158689) (xy 61.180834 -404.194383)
			(xy 61.216525 -404.235575) (xy 61.245991 -404.281426) (xy 61.268631 -404.331004) (xy 61.283986 -404.3833)
			(xy 61.291742 -404.437248) (xy 61.291742 -404.491748) (xy 62.729398 -404.491748) (xy 62.729398 -404.437252)
			(xy 62.737153 -404.38331) (xy 62.752506 -404.331021) (xy 62.775143 -404.281449) (xy 62.804604 -404.235603)
			(xy 62.84029 -404.194416) (xy 62.881474 -404.158726) (xy 62.927317 -404.12926) (xy 62.976887 -404.106618)
			(xy 63.029175 -404.091261) (xy 63.083116 -404.083501) (xy 63.110364 -404.083012) (xy 63.973964 -404.083012)
			(xy 64.00122 -404.083432) (xy 64.055178 -404.091186) (xy 64.107483 -404.106539) (xy 64.15707 -404.129181)
			(xy 64.20293 -404.15865) (xy 64.244129 -404.194345) (xy 64.279829 -404.235541) (xy 64.309302 -404.281398)
			(xy 64.331948 -404.330984) (xy 64.347307 -404.383287) (xy 64.355065 -404.437244) (xy 64.355065 -404.491752)
			(xy 65.792575 -404.491752) (xy 65.792575 -404.437248) (xy 65.800332 -404.3833) (xy 65.815687 -404.331005)
			(xy 65.838329 -404.281427) (xy 65.867796 -404.235576) (xy 65.903488 -404.194385) (xy 65.944679 -404.158693)
			(xy 65.99053 -404.129227) (xy 66.040108 -404.106586) (xy 66.092404 -404.091231) (xy 66.146352 -404.083475)
			(xy 66.173604 -404.083012) (xy 67.037204 -404.083012) (xy 67.064456 -404.083458) (xy 67.118407 -404.091215)
			(xy 67.170704 -404.106572) (xy 67.220283 -404.129214) (xy 67.266135 -404.158682) (xy 67.307327 -404.194376)
			(xy 67.34302 -404.235568) (xy 67.372488 -404.281421) (xy 67.39513 -404.331) (xy 67.410485 -404.383297)
			(xy 67.418242 -404.437248) (xy 67.418242 -404.491752) (xy 67.418242 -404.491753) (xy 68.855775 -404.491753)
			(xy 68.855775 -404.437247) (xy 68.863533 -404.383295) (xy 68.878891 -404.330996) (xy 68.901535 -404.281416)
			(xy 68.931006 -404.235563) (xy 68.966702 -404.194371) (xy 69.007898 -404.158679) (xy 69.053754 -404.129214)
			(xy 69.103337 -404.106575) (xy 69.155638 -404.091224) (xy 69.209591 -404.083472) (xy 69.236844 -404.083012)
			(xy 70.100444 -404.083012) (xy 70.127695 -404.083461) (xy 70.18164 -404.091223) (xy 70.233933 -404.106583)
			(xy 70.283507 -404.129227) (xy 70.329354 -404.158696) (xy 70.370541 -404.19439) (xy 70.40623 -404.235581)
			(xy 70.435694 -404.281432) (xy 70.458333 -404.331009) (xy 70.473687 -404.383303) (xy 70.481442 -404.437249)
			(xy 70.481442 -404.491749) (xy 71.919098 -404.491749) (xy 71.919098 -404.437251) (xy 71.926854 -404.383308)
			(xy 71.942207 -404.331017) (xy 71.964846 -404.281443) (xy 71.994309 -404.235596) (xy 72.029997 -404.194409)
			(xy 72.071183 -404.158719) (xy 72.117029 -404.129254) (xy 72.166602 -404.106613) (xy 72.218892 -404.091257)
			(xy 72.272835 -404.083499) (xy 72.300084 -404.083012) (xy 73.163684 -404.083012) (xy 73.190939 -404.083434)
			(xy 73.244895 -404.091189) (xy 73.297197 -404.106545) (xy 73.346782 -404.129188) (xy 73.39264 -404.158657)
			(xy 73.433836 -404.194352) (xy 73.469534 -404.235548) (xy 73.499005 -404.281404) (xy 73.52165 -404.330988)
			(xy 73.537007 -404.38329) (xy 73.544765 -404.437245) (xy 73.544765 -404.491753) (xy 74.982275 -404.491753)
			(xy 74.982275 -404.437247) (xy 74.990033 -404.383297) (xy 75.005389 -404.331) (xy 75.028032 -404.281421)
			(xy 75.057501 -404.235569) (xy 75.093195 -404.194378) (xy 75.134388 -404.158686) (xy 75.180242 -404.129221)
			(xy 75.229823 -404.106581) (xy 75.282121 -404.091227) (xy 75.336071 -404.083474) (xy 75.363324 -404.083012)
			(xy 76.226924 -404.083012) (xy 76.254176 -404.083459) (xy 76.308124 -404.091219) (xy 76.360418 -404.106577)
			(xy 76.409995 -404.129221) (xy 76.455845 -404.158689) (xy 76.497034 -404.194383) (xy 76.532725 -404.235575)
			(xy 76.562191 -404.281426) (xy 76.584831 -404.331004) (xy 76.600186 -404.3833) (xy 76.607942 -404.437248)
			(xy 76.607942 -404.491748) (xy 78.045598 -404.491748) (xy 78.045598 -404.437252) (xy 78.053353 -404.38331)
			(xy 78.068706 -404.331021) (xy 78.091343 -404.281449) (xy 78.120804 -404.235603) (xy 78.15649 -404.194416)
			(xy 78.197674 -404.158726) (xy 78.243517 -404.12926) (xy 78.293087 -404.106618) (xy 78.345375 -404.091261)
			(xy 78.399316 -404.083501) (xy 78.426564 -404.083012) (xy 79.290164 -404.083012) (xy 79.31742 -404.083432)
			(xy 79.371378 -404.091186) (xy 79.423683 -404.106539) (xy 79.47327 -404.129181) (xy 79.51913 -404.15865)
			(xy 79.560329 -404.194345) (xy 79.596029 -404.235541) (xy 79.625502 -404.281398) (xy 79.648148 -404.330984)
			(xy 79.663507 -404.383287) (xy 79.671265 -404.437244) (xy 79.671265 -404.491752) (xy 81.108775 -404.491752)
			(xy 81.108775 -404.437248) (xy 81.116532 -404.3833) (xy 81.131887 -404.331005) (xy 81.154529 -404.281427)
			(xy 81.183996 -404.235576) (xy 81.219688 -404.194385) (xy 81.260879 -404.158693) (xy 81.30673 -404.129227)
			(xy 81.356308 -404.106586) (xy 81.408604 -404.091231) (xy 81.462552 -404.083475) (xy 81.489804 -404.083012)
			(xy 82.353404 -404.083012) (xy 82.380656 -404.083458) (xy 82.434607 -404.091215) (xy 82.486904 -404.106572)
			(xy 82.536483 -404.129214) (xy 82.582335 -404.158682) (xy 82.623527 -404.194376) (xy 82.65922 -404.235568)
			(xy 82.688688 -404.281421) (xy 82.71133 -404.331) (xy 82.726685 -404.383297) (xy 82.734442 -404.437248)
			(xy 82.734442 -404.491752) (xy 82.734442 -404.491753) (xy 84.171975 -404.491753) (xy 84.171975 -404.437247)
			(xy 84.179733 -404.383295) (xy 84.195091 -404.330996) (xy 84.217735 -404.281416) (xy 84.247206 -404.235563)
			(xy 84.282902 -404.194371) (xy 84.324098 -404.158679) (xy 84.369954 -404.129214) (xy 84.419537 -404.106575)
			(xy 84.471838 -404.091224) (xy 84.525791 -404.083472) (xy 84.553044 -404.083012) (xy 85.416644 -404.083012)
			(xy 85.443895 -404.083461) (xy 85.49784 -404.091223) (xy 85.550133 -404.106583) (xy 85.599707 -404.129227)
			(xy 85.645554 -404.158696) (xy 85.686741 -404.19439) (xy 85.72243 -404.235581) (xy 85.751894 -404.281432)
			(xy 85.774533 -404.331009) (xy 85.789887 -404.383303) (xy 85.797642 -404.437249) (xy 85.797642 -404.491749)
			(xy 87.235298 -404.491749) (xy 87.235298 -404.437251) (xy 87.243054 -404.383308) (xy 87.258407 -404.331017)
			(xy 87.281046 -404.281443) (xy 87.310509 -404.235596) (xy 87.346197 -404.194409) (xy 87.387383 -404.158719)
			(xy 87.433229 -404.129254) (xy 87.482802 -404.106613) (xy 87.535092 -404.091257) (xy 87.589035 -404.083499)
			(xy 87.616284 -404.083012) (xy 88.479884 -404.083012) (xy 88.507139 -404.083434) (xy 88.561095 -404.091189)
			(xy 88.613397 -404.106545) (xy 88.662982 -404.129188) (xy 88.70884 -404.158657) (xy 88.750036 -404.194352)
			(xy 88.785734 -404.235548) (xy 88.815205 -404.281404) (xy 88.83785 -404.330988) (xy 88.853207 -404.38329)
			(xy 88.860965 -404.437245) (xy 88.860965 -404.491753) (xy 90.298475 -404.491753) (xy 90.298475 -404.437247)
			(xy 90.306233 -404.383297) (xy 90.321589 -404.331) (xy 90.344232 -404.281421) (xy 90.373701 -404.235569)
			(xy 90.409395 -404.194378) (xy 90.450588 -404.158686) (xy 90.496442 -404.129221) (xy 90.546023 -404.106581)
			(xy 90.598321 -404.091227) (xy 90.652271 -404.083474) (xy 90.679524 -404.083012) (xy 91.543124 -404.083012)
			(xy 91.570376 -404.083459) (xy 91.624324 -404.091219) (xy 91.676618 -404.106577) (xy 91.726195 -404.129221)
			(xy 91.772045 -404.158689) (xy 91.813234 -404.194383) (xy 91.848925 -404.235575) (xy 91.878391 -404.281426)
			(xy 91.901031 -404.331004) (xy 91.916386 -404.3833) (xy 91.924142 -404.437248) (xy 91.924142 -404.491748)
			(xy 93.361798 -404.491748) (xy 93.361798 -404.437252) (xy 93.369553 -404.38331) (xy 93.384906 -404.331021)
			(xy 93.407543 -404.281449) (xy 93.437004 -404.235603) (xy 93.47269 -404.194416) (xy 93.513874 -404.158726)
			(xy 93.559717 -404.12926) (xy 93.609287 -404.106618) (xy 93.661575 -404.091261) (xy 93.715516 -404.083501)
			(xy 93.742764 -404.083012) (xy 94.606364 -404.083012) (xy 94.63362 -404.083432) (xy 94.687578 -404.091186)
			(xy 94.739883 -404.106539) (xy 94.78947 -404.129181) (xy 94.83533 -404.15865) (xy 94.876529 -404.194345)
			(xy 94.912229 -404.235541) (xy 94.941702 -404.281398) (xy 94.964348 -404.330984) (xy 94.979707 -404.383287)
			(xy 94.987465 -404.437244) (xy 94.987465 -404.491752) (xy 114.513075 -404.491752) (xy 114.513075 -404.437248)
			(xy 114.520832 -404.3833) (xy 114.536188 -404.331004) (xy 114.558829 -404.281426) (xy 114.588296 -404.235575)
			(xy 114.623989 -404.194384) (xy 114.66518 -404.158693) (xy 114.711031 -404.129226) (xy 114.76061 -404.106585)
			(xy 114.812906 -404.091231) (xy 114.866854 -404.083475) (xy 114.894106 -404.083012) (xy 115.757706 -404.083012)
			(xy 115.784958 -404.083458) (xy 115.838908 -404.091216) (xy 115.891205 -404.106572) (xy 115.940784 -404.129215)
			(xy 115.986636 -404.158683) (xy 116.027828 -404.194376) (xy 116.063521 -404.235569) (xy 116.092988 -404.281421)
			(xy 116.11563 -404.331001) (xy 116.130985 -404.383298) (xy 116.138742 -404.437248) (xy 116.138742 -404.491752)
			(xy 116.138742 -404.491754) (xy 117.576275 -404.491754) (xy 117.576275 -404.437246) (xy 117.584033 -404.383294)
			(xy 117.599391 -404.330996) (xy 117.622035 -404.281415) (xy 117.651506 -404.235562) (xy 117.687203 -404.19437)
			(xy 117.728399 -404.158679) (xy 117.774255 -404.129213) (xy 117.823839 -404.106575) (xy 117.876139 -404.091223)
			(xy 117.930092 -404.083472) (xy 117.957346 -404.083012) (xy 118.820946 -404.083012) (xy 118.848197 -404.083461)
			(xy 118.902142 -404.091223) (xy 118.954434 -404.106583) (xy 119.004008 -404.129228) (xy 119.049855 -404.158697)
			(xy 119.091042 -404.194391) (xy 119.12673 -404.235582) (xy 119.156194 -404.281432) (xy 119.178833 -404.331009)
			(xy 119.194187 -404.383303) (xy 119.201942 -404.437249) (xy 119.201942 -404.491749) (xy 120.639598 -404.491749)
			(xy 120.639598 -404.437251) (xy 120.647354 -404.383307) (xy 120.662708 -404.331016) (xy 120.685346 -404.281443)
			(xy 120.71481 -404.235596) (xy 120.750498 -404.194408) (xy 120.791684 -404.158718) (xy 120.83753 -404.129253)
			(xy 120.887103 -404.106612) (xy 120.939394 -404.091257) (xy 120.993337 -404.083499) (xy 121.020586 -404.083012)
			(xy 121.884186 -404.083012) (xy 121.911441 -404.083434) (xy 121.965396 -404.09119) (xy 122.017699 -404.106545)
			(xy 122.067283 -404.129188) (xy 122.113141 -404.158657) (xy 122.154337 -404.194353) (xy 122.190034 -404.235548)
			(xy 122.219505 -404.281405) (xy 122.24215 -404.330988) (xy 122.257507 -404.38329) (xy 122.265265 -404.437245)
			(xy 122.265265 -404.491753) (xy 123.702775 -404.491753) (xy 123.702775 -404.437247) (xy 123.710533 -404.383297)
			(xy 123.725889 -404.331) (xy 123.748532 -404.281421) (xy 123.778001 -404.235569) (xy 123.813696 -404.194377)
			(xy 123.854889 -404.158686) (xy 123.900743 -404.12922) (xy 123.950324 -404.10658) (xy 124.002622 -404.091227)
			(xy 124.056573 -404.083474) (xy 124.083826 -404.083012) (xy 124.947426 -404.083012) (xy 124.974677 -404.08346)
			(xy 125.028625 -404.09122) (xy 125.08092 -404.106578) (xy 125.130496 -404.129222) (xy 125.176346 -404.15869)
			(xy 125.217535 -404.194383) (xy 125.253226 -404.235575) (xy 125.282691 -404.281427) (xy 125.305331 -404.331005)
			(xy 125.320686 -404.3833) (xy 125.328442 -404.437249) (xy 125.328442 -404.491748) (xy 126.766098 -404.491748)
			(xy 126.766098 -404.437252) (xy 126.773853 -404.38331) (xy 126.789206 -404.331021) (xy 126.811843 -404.281448)
			(xy 126.841305 -404.235602) (xy 126.876991 -404.194415) (xy 126.918175 -404.158725) (xy 126.964018 -404.12926)
			(xy 127.013589 -404.106618) (xy 127.065877 -404.091261) (xy 127.119818 -404.083501) (xy 127.147066 -404.083012)
			(xy 128.010666 -404.083012) (xy 128.037922 -404.083433) (xy 128.091879 -404.091186) (xy 128.144184 -404.10654)
			(xy 128.193771 -404.129182) (xy 128.239631 -404.15865) (xy 128.28083 -404.194346) (xy 128.316529 -404.235542)
			(xy 128.346002 -404.281399) (xy 128.368648 -404.330984) (xy 128.384007 -404.383287) (xy 128.391765 -404.437244)
			(xy 128.391765 -404.491752) (xy 129.829275 -404.491752) (xy 129.829275 -404.437248) (xy 129.837032 -404.3833)
			(xy 129.852388 -404.331004) (xy 129.875029 -404.281426) (xy 129.904496 -404.235575) (xy 129.940189 -404.194384)
			(xy 129.98138 -404.158693) (xy 130.027231 -404.129226) (xy 130.07681 -404.106585) (xy 130.129106 -404.091231)
			(xy 130.183054 -404.083475) (xy 130.210306 -404.083012) (xy 131.073906 -404.083012) (xy 131.101158 -404.083458)
			(xy 131.155108 -404.091216) (xy 131.207405 -404.106572) (xy 131.256984 -404.129215) (xy 131.302836 -404.158683)
			(xy 131.344028 -404.194376) (xy 131.379721 -404.235569) (xy 131.409188 -404.281421) (xy 131.43183 -404.331001)
			(xy 131.447185 -404.383298) (xy 131.454942 -404.437248) (xy 131.454942 -404.491752) (xy 131.454942 -404.491754)
			(xy 132.892475 -404.491754) (xy 132.892475 -404.437246) (xy 132.900233 -404.383294) (xy 132.915591 -404.330996)
			(xy 132.938235 -404.281415) (xy 132.967706 -404.235562) (xy 133.003403 -404.19437) (xy 133.044599 -404.158679)
			(xy 133.090455 -404.129213) (xy 133.140039 -404.106575) (xy 133.192339 -404.091223) (xy 133.246292 -404.083472)
			(xy 133.273546 -404.083012) (xy 134.137146 -404.083012) (xy 134.164397 -404.083461) (xy 134.218342 -404.091223)
			(xy 134.270634 -404.106583) (xy 134.320208 -404.129228) (xy 134.366055 -404.158697) (xy 134.407242 -404.194391)
			(xy 134.44293 -404.235582) (xy 134.472394 -404.281432) (xy 134.495033 -404.331009) (xy 134.510387 -404.383303)
			(xy 134.518142 -404.437249) (xy 134.518142 -404.491749) (xy 135.955798 -404.491749) (xy 135.955798 -404.437251)
			(xy 135.963554 -404.383307) (xy 135.978908 -404.331016) (xy 136.001546 -404.281443) (xy 136.03101 -404.235596)
			(xy 136.066698 -404.194408) (xy 136.107884 -404.158718) (xy 136.15373 -404.129253) (xy 136.203303 -404.106612)
			(xy 136.255594 -404.091257) (xy 136.309537 -404.083499) (xy 136.336786 -404.083012) (xy 137.200386 -404.083012)
			(xy 137.227641 -404.083434) (xy 137.281596 -404.09119) (xy 137.333899 -404.106545) (xy 137.383483 -404.129188)
			(xy 137.429341 -404.158657) (xy 137.470537 -404.194353) (xy 137.506234 -404.235548) (xy 137.535705 -404.281405)
			(xy 137.55835 -404.330988) (xy 137.573707 -404.38329) (xy 137.581465 -404.437245) (xy 137.581465 -404.491753)
			(xy 139.018975 -404.491753) (xy 139.018975 -404.437247) (xy 139.026733 -404.383297) (xy 139.042089 -404.331)
			(xy 139.064732 -404.281421) (xy 139.094201 -404.235569) (xy 139.129896 -404.194377) (xy 139.171089 -404.158686)
			(xy 139.216943 -404.12922) (xy 139.266524 -404.10658) (xy 139.318822 -404.091227) (xy 139.372773 -404.083474)
			(xy 139.400026 -404.083012) (xy 140.263626 -404.083012) (xy 140.290877 -404.08346) (xy 140.344825 -404.09122)
			(xy 140.39712 -404.106578) (xy 140.446696 -404.129222) (xy 140.492546 -404.15869) (xy 140.533735 -404.194383)
			(xy 140.569426 -404.235575) (xy 140.598891 -404.281427) (xy 140.621531 -404.331005) (xy 140.636886 -404.3833)
			(xy 140.644642 -404.437249) (xy 140.644642 -404.491748) (xy 142.082298 -404.491748) (xy 142.082298 -404.437252)
			(xy 142.090053 -404.38331) (xy 142.105406 -404.331021) (xy 142.128043 -404.281448) (xy 142.157505 -404.235602)
			(xy 142.193191 -404.194415) (xy 142.234375 -404.158725) (xy 142.280218 -404.12926) (xy 142.329789 -404.106618)
			(xy 142.382077 -404.091261) (xy 142.436018 -404.083501) (xy 142.463266 -404.083012) (xy 143.326866 -404.083012)
			(xy 143.354122 -404.083433) (xy 143.408079 -404.091186) (xy 143.460384 -404.10654) (xy 143.509971 -404.129182)
			(xy 143.555831 -404.15865) (xy 143.59703 -404.194346) (xy 143.632729 -404.235542) (xy 143.662202 -404.281399)
			(xy 143.684848 -404.330984) (xy 143.700207 -404.383287) (xy 143.707965 -404.437244) (xy 143.707965 -404.491752)
			(xy 145.145475 -404.491752) (xy 145.145475 -404.437248) (xy 145.153232 -404.3833) (xy 145.168588 -404.331004)
			(xy 145.191229 -404.281426) (xy 145.220696 -404.235575) (xy 145.256389 -404.194384) (xy 145.29758 -404.158693)
			(xy 145.343431 -404.129226) (xy 145.39301 -404.106585) (xy 145.445306 -404.091231) (xy 145.499254 -404.083475)
			(xy 145.526506 -404.083012) (xy 146.390106 -404.083012) (xy 146.417358 -404.083458) (xy 146.471308 -404.091216)
			(xy 146.523605 -404.106572) (xy 146.573184 -404.129215) (xy 146.619036 -404.158683) (xy 146.660228 -404.194376)
			(xy 146.695921 -404.235569) (xy 146.725388 -404.281421) (xy 146.74803 -404.331001) (xy 146.763385 -404.383298)
			(xy 146.771142 -404.437248) (xy 146.771142 -404.491752) (xy 146.771142 -404.491754) (xy 148.208675 -404.491754)
			(xy 148.208675 -404.437246) (xy 148.216433 -404.383294) (xy 148.231791 -404.330996) (xy 148.254435 -404.281415)
			(xy 148.283906 -404.235562) (xy 148.319603 -404.19437) (xy 148.360799 -404.158679) (xy 148.406655 -404.129213)
			(xy 148.456239 -404.106575) (xy 148.508539 -404.091223) (xy 148.562492 -404.083472) (xy 148.589746 -404.083012)
			(xy 149.453346 -404.083012) (xy 149.480597 -404.083461) (xy 149.534542 -404.091223) (xy 149.586834 -404.106583)
			(xy 149.636408 -404.129228) (xy 149.682255 -404.158697) (xy 149.723442 -404.194391) (xy 149.75913 -404.235582)
			(xy 149.788594 -404.281432) (xy 149.811233 -404.331009) (xy 149.826587 -404.383303) (xy 149.834342 -404.437249)
			(xy 149.834342 -404.491749) (xy 151.271998 -404.491749) (xy 151.271998 -404.437251) (xy 151.279754 -404.383307)
			(xy 151.295108 -404.331016) (xy 151.317746 -404.281443) (xy 151.34721 -404.235596) (xy 151.382898 -404.194408)
			(xy 151.424084 -404.158718) (xy 151.46993 -404.129253) (xy 151.519503 -404.106612) (xy 151.571794 -404.091257)
			(xy 151.625737 -404.083499) (xy 151.652986 -404.083012) (xy 152.516586 -404.083012) (xy 152.543841 -404.083434)
			(xy 152.597796 -404.09119) (xy 152.650099 -404.106545) (xy 152.699683 -404.129188) (xy 152.745541 -404.158657)
			(xy 152.786737 -404.194353) (xy 152.822434 -404.235548) (xy 152.851905 -404.281405) (xy 152.87455 -404.330988)
			(xy 152.889907 -404.38329) (xy 152.897665 -404.437245) (xy 152.897665 -404.491753) (xy 154.335175 -404.491753)
			(xy 154.335175 -404.437247) (xy 154.342933 -404.383297) (xy 154.358289 -404.331) (xy 154.380932 -404.281421)
			(xy 154.410401 -404.235569) (xy 154.446096 -404.194377) (xy 154.487289 -404.158686) (xy 154.533143 -404.12922)
			(xy 154.582724 -404.10658) (xy 154.635022 -404.091227) (xy 154.688973 -404.083474) (xy 154.716226 -404.083012)
			(xy 155.579826 -404.083012) (xy 155.607077 -404.08346) (xy 155.661025 -404.09122) (xy 155.71332 -404.106578)
			(xy 155.762896 -404.129222) (xy 155.808746 -404.15869) (xy 155.849935 -404.194383) (xy 155.885626 -404.235575)
			(xy 155.915091 -404.281427) (xy 155.937731 -404.331005) (xy 155.953086 -404.3833) (xy 155.960842 -404.437249)
			(xy 155.960842 -404.491748) (xy 157.398498 -404.491748) (xy 157.398498 -404.437252) (xy 157.406253 -404.38331)
			(xy 157.421606 -404.331021) (xy 157.444243 -404.281448) (xy 157.473705 -404.235602) (xy 157.509391 -404.194415)
			(xy 157.550575 -404.158725) (xy 157.596418 -404.12926) (xy 157.645989 -404.106618) (xy 157.698277 -404.091261)
			(xy 157.752218 -404.083501) (xy 157.779466 -404.083012) (xy 158.643066 -404.083012) (xy 158.670322 -404.083433)
			(xy 158.724279 -404.091186) (xy 158.776584 -404.10654) (xy 158.826171 -404.129182) (xy 158.872031 -404.15865)
			(xy 158.91323 -404.194346) (xy 158.948929 -404.235542) (xy 158.978402 -404.281399) (xy 159.001048 -404.330984)
			(xy 159.016407 -404.383287) (xy 159.024165 -404.437244) (xy 159.024165 -404.491752) (xy 160.461675 -404.491752)
			(xy 160.461675 -404.437248) (xy 160.469432 -404.3833) (xy 160.484788 -404.331004) (xy 160.507429 -404.281426)
			(xy 160.536896 -404.235575) (xy 160.572589 -404.194384) (xy 160.61378 -404.158693) (xy 160.659631 -404.129226)
			(xy 160.70921 -404.106585) (xy 160.761506 -404.091231) (xy 160.815454 -404.083475) (xy 160.842706 -404.083012)
			(xy 161.706306 -404.083012) (xy 161.733558 -404.083458) (xy 161.787508 -404.091216) (xy 161.839805 -404.106572)
			(xy 161.889384 -404.129215) (xy 161.935236 -404.158683) (xy 161.976428 -404.194376) (xy 162.012121 -404.235569)
			(xy 162.041588 -404.281421) (xy 162.06423 -404.331001) (xy 162.079585 -404.383298) (xy 162.087342 -404.437248)
			(xy 162.087342 -404.491752) (xy 162.079585 -404.545702) (xy 162.06423 -404.597999) (xy 162.041588 -404.647579)
			(xy 162.012121 -404.693431) (xy 161.976428 -404.734624) (xy 161.935236 -404.770317) (xy 161.904774 -404.789894)
			(xy 166.998662 -404.789894) (xy 167.002634 -404.611651) (xy 167.014542 -404.433762) (xy 167.034363 -404.25658)
			(xy 167.062057 -404.080456) (xy 167.097569 -403.905741) (xy 167.140829 -403.732782) (xy 167.191751 -403.561921)
			(xy 167.250234 -403.393499) (xy 167.316161 -403.227849) (xy 167.389402 -403.0653) (xy 167.469812 -402.906175)
			(xy 167.55723 -402.75079) (xy 167.651483 -402.599454) (xy 167.752384 -402.452466) (xy 167.859733 -402.310119)
			(xy 167.973316 -402.172696) (xy 168.092909 -402.040469) (xy 168.218273 -401.9137) (xy 168.34916 -401.792642)
			(xy 168.485309 -401.677535) (xy 168.626451 -401.568607) (xy 168.772306 -401.466075) (xy 168.922583 -401.370141)
			(xy 169.076984 -401.280998) (xy 169.235203 -401.198821) (xy 169.396926 -401.123773) (xy 169.561831 -401.056005)
			(xy 169.729592 -400.995649) (xy 169.899875 -400.942827) (xy 170.072342 -400.897643) (xy 170.24665 -400.860186)
			(xy 170.422454 -400.830532) (xy 170.599404 -400.808739) (xy 170.77715 -400.794849) (xy 170.955337 -400.788892)
			(xy 171.133614 -400.790878) (xy 171.311625 -400.800804) (xy 171.489017 -400.81865) (xy 171.665437 -400.84438)
			(xy 171.840537 -400.877944) (xy 172.013968 -400.919274) (xy 172.185385 -400.96829) (xy 172.354448 -401.024892)
			(xy 172.520823 -401.08897) (xy 172.684177 -401.160396) (xy 172.844188 -401.239028) (xy 173.000537 -401.324709)
			(xy 173.152914 -401.417271) (xy 173.301017 -401.516528) (xy 173.444551 -401.622285) (xy 173.583231 -401.73433)
			(xy 173.716782 -401.852442) (xy 173.844939 -401.976386) (xy 173.967448 -402.105916) (xy 174.084065 -402.240775)
			(xy 174.194558 -402.380695) (xy 174.298709 -402.525398) (xy 174.396311 -402.674597) (xy 174.487169 -402.827996)
			(xy 174.571103 -402.98529) (xy 174.647948 -403.146166) (xy 174.717549 -403.310307) (xy 174.77977 -403.477384)
			(xy 174.834486 -403.647068) (xy 174.881588 -403.819021) (xy 174.920984 -403.992901) (xy 174.952595 -404.168364)
			(xy 174.976359 -404.34506) (xy 174.992227 -404.52264) (xy 175.000169 -404.70075) (xy 175.000666 -404.789894)
			(xy 175.000169 -404.879038) (xy 174.992227 -405.057148) (xy 174.976359 -405.234728) (xy 174.952595 -405.411424)
			(xy 174.920984 -405.586887) (xy 174.881588 -405.760767) (xy 174.834486 -405.93272) (xy 174.77977 -406.102404)
			(xy 174.717549 -406.269481) (xy 174.647948 -406.433622) (xy 174.571103 -406.594498) (xy 174.487169 -406.751792)
			(xy 174.396311 -406.905191) (xy 174.298709 -407.05439) (xy 174.194558 -407.199093) (xy 174.084065 -407.339013)
			(xy 173.967448 -407.473872) (xy 173.844939 -407.603402) (xy 173.716782 -407.727346) (xy 173.583231 -407.845458)
			(xy 173.444551 -407.957503) (xy 173.301017 -408.06326) (xy 173.152914 -408.162517) (xy 173.000537 -408.255079)
			(xy 172.844188 -408.34076) (xy 172.684177 -408.419392) (xy 172.520823 -408.490818) (xy 172.354448 -408.554896)
			(xy 172.185385 -408.611498) (xy 172.013968 -408.660514) (xy 171.840537 -408.701844) (xy 171.665437 -408.735408)
			(xy 171.489017 -408.761138) (xy 171.311625 -408.778984) (xy 171.133614 -408.78891) (xy 170.955337 -408.790896)
			(xy 170.77715 -408.784939) (xy 170.599404 -408.771049) (xy 170.422454 -408.749256) (xy 170.24665 -408.719602)
			(xy 170.072342 -408.682145) (xy 169.899875 -408.636961) (xy 169.729592 -408.584139) (xy 169.561831 -408.523783)
			(xy 169.396926 -408.456015) (xy 169.235203 -408.380967) (xy 169.076984 -408.29879) (xy 168.922583 -408.209647)
			(xy 168.772306 -408.113713) (xy 168.626451 -408.011181) (xy 168.485309 -407.902253) (xy 168.34916 -407.787146)
			(xy 168.218273 -407.666088) (xy 168.092909 -407.539319) (xy 167.973316 -407.407092) (xy 167.859733 -407.269669)
			(xy 167.752384 -407.127322) (xy 167.651483 -406.980334) (xy 167.55723 -406.828998) (xy 167.469812 -406.673613)
			(xy 167.389402 -406.514488) (xy 167.316161 -406.351939) (xy 167.250234 -406.186289) (xy 167.191751 -406.017867)
			(xy 167.140829 -405.847006) (xy 167.097569 -405.674047) (xy 167.062057 -405.499332) (xy 167.034363 -405.323208)
			(xy 167.014542 -405.146026) (xy 167.002634 -404.968137) (xy 166.998662 -404.789894) (xy 161.904774 -404.789894)
			(xy 161.889384 -404.799785) (xy 161.839805 -404.822428) (xy 161.787508 -404.837784) (xy 161.733558 -404.845542)
			(xy 161.706306 -404.846028) (xy 160.842706 -404.846028) (xy 160.815454 -404.845525) (xy 160.761506 -404.837769)
			(xy 160.70921 -404.822415) (xy 160.659631 -404.799774) (xy 160.61378 -404.770307) (xy 160.572589 -404.734616)
			(xy 160.536896 -404.693425) (xy 160.507429 -404.647574) (xy 160.484788 -404.597996) (xy 160.469432 -404.5457)
			(xy 160.461675 -404.491752) (xy 159.024165 -404.491752) (xy 159.024165 -404.491756) (xy 159.016407 -404.545713)
			(xy 159.001048 -404.598016) (xy 158.978402 -404.647601) (xy 158.948929 -404.693458) (xy 158.91323 -404.734654)
			(xy 158.872031 -404.77035) (xy 158.826171 -404.799818) (xy 158.776584 -404.82246) (xy 158.724279 -404.837814)
			(xy 158.670322 -404.845567) (xy 158.643066 -404.846028) (xy 157.779466 -404.846028) (xy 157.752218 -404.845499)
			(xy 157.698277 -404.837739) (xy 157.645989 -404.822382) (xy 157.596418 -404.79974) (xy 157.550575 -404.770275)
			(xy 157.509391 -404.734585) (xy 157.473705 -404.693398) (xy 157.444243 -404.647552) (xy 157.421606 -404.597979)
			(xy 157.406253 -404.54569) (xy 157.398498 -404.491748) (xy 155.960842 -404.491748) (xy 155.960842 -404.491751)
			(xy 155.953086 -404.5457) (xy 155.937731 -404.597995) (xy 155.915091 -404.647573) (xy 155.885626 -404.693425)
			(xy 155.849935 -404.734617) (xy 155.808746 -404.77031) (xy 155.762896 -404.799778) (xy 155.71332 -404.822422)
			(xy 155.661025 -404.83778) (xy 155.607077 -404.84554) (xy 155.579826 -404.846028) (xy 154.716226 -404.846028)
			(xy 154.688973 -404.845526) (xy 154.635022 -404.837773) (xy 154.582724 -404.82242) (xy 154.533143 -404.79978)
			(xy 154.487289 -404.770314) (xy 154.446096 -404.734623) (xy 154.410401 -404.693431) (xy 154.380932 -404.647579)
			(xy 154.358289 -404.598) (xy 154.342933 -404.545703) (xy 154.335175 -404.491753) (xy 152.897665 -404.491753)
			(xy 152.897665 -404.491755) (xy 152.889907 -404.54571) (xy 152.87455 -404.598012) (xy 152.851905 -404.647595)
			(xy 152.822434 -404.693452) (xy 152.786737 -404.734647) (xy 152.745541 -404.770343) (xy 152.699683 -404.799812)
			(xy 152.650099 -404.822455) (xy 152.597796 -404.83781) (xy 152.543841 -404.845566) (xy 152.516586 -404.846028)
			(xy 151.652986 -404.846028) (xy 151.625737 -404.845501) (xy 151.571794 -404.837743) (xy 151.519503 -404.822388)
			(xy 151.46993 -404.799747) (xy 151.424084 -404.770282) (xy 151.382898 -404.734592) (xy 151.34721 -404.693404)
			(xy 151.317746 -404.647557) (xy 151.295108 -404.597984) (xy 151.279754 -404.545693) (xy 151.271998 -404.491749)
			(xy 149.834342 -404.491749) (xy 149.834342 -404.491751) (xy 149.826587 -404.545697) (xy 149.811233 -404.597991)
			(xy 149.788594 -404.647568) (xy 149.75913 -404.693418) (xy 149.723442 -404.734609) (xy 149.682255 -404.770303)
			(xy 149.636408 -404.799772) (xy 149.586834 -404.822417) (xy 149.534542 -404.837777) (xy 149.480597 -404.845539)
			(xy 149.453346 -404.846028) (xy 148.589746 -404.846028) (xy 148.562492 -404.845528) (xy 148.508539 -404.837777)
			(xy 148.456239 -404.822425) (xy 148.406655 -404.799787) (xy 148.360799 -404.770321) (xy 148.319603 -404.73463)
			(xy 148.283906 -404.693438) (xy 148.254435 -404.647585) (xy 148.231791 -404.598004) (xy 148.216433 -404.545706)
			(xy 148.208675 -404.491754) (xy 146.771142 -404.491754) (xy 146.763385 -404.545702) (xy 146.74803 -404.597999)
			(xy 146.725388 -404.647579) (xy 146.695921 -404.693431) (xy 146.660228 -404.734624) (xy 146.619036 -404.770317)
			(xy 146.573184 -404.799785) (xy 146.523605 -404.822428) (xy 146.471308 -404.837784) (xy 146.417358 -404.845542)
			(xy 146.390106 -404.846028) (xy 145.526506 -404.846028) (xy 145.499254 -404.845525) (xy 145.445306 -404.837769)
			(xy 145.39301 -404.822415) (xy 145.343431 -404.799774) (xy 145.29758 -404.770307) (xy 145.256389 -404.734616)
			(xy 145.220696 -404.693425) (xy 145.191229 -404.647574) (xy 145.168588 -404.597996) (xy 145.153232 -404.5457)
			(xy 145.145475 -404.491752) (xy 143.707965 -404.491752) (xy 143.707965 -404.491756) (xy 143.700207 -404.545713)
			(xy 143.684848 -404.598016) (xy 143.662202 -404.647601) (xy 143.632729 -404.693458) (xy 143.59703 -404.734654)
			(xy 143.555831 -404.77035) (xy 143.509971 -404.799818) (xy 143.460384 -404.82246) (xy 143.408079 -404.837814)
			(xy 143.354122 -404.845567) (xy 143.326866 -404.846028) (xy 142.463266 -404.846028) (xy 142.436018 -404.845499)
			(xy 142.382077 -404.837739) (xy 142.329789 -404.822382) (xy 142.280218 -404.79974) (xy 142.234375 -404.770275)
			(xy 142.193191 -404.734585) (xy 142.157505 -404.693398) (xy 142.128043 -404.647552) (xy 142.105406 -404.597979)
			(xy 142.090053 -404.54569) (xy 142.082298 -404.491748) (xy 140.644642 -404.491748) (xy 140.644642 -404.491751)
			(xy 140.636886 -404.5457) (xy 140.621531 -404.597995) (xy 140.598891 -404.647573) (xy 140.569426 -404.693425)
			(xy 140.533735 -404.734617) (xy 140.492546 -404.77031) (xy 140.446696 -404.799778) (xy 140.39712 -404.822422)
			(xy 140.344825 -404.83778) (xy 140.290877 -404.84554) (xy 140.263626 -404.846028) (xy 139.400026 -404.846028)
			(xy 139.372773 -404.845526) (xy 139.318822 -404.837773) (xy 139.266524 -404.82242) (xy 139.216943 -404.79978)
			(xy 139.171089 -404.770314) (xy 139.129896 -404.734623) (xy 139.094201 -404.693431) (xy 139.064732 -404.647579)
			(xy 139.042089 -404.598) (xy 139.026733 -404.545703) (xy 139.018975 -404.491753) (xy 137.581465 -404.491753)
			(xy 137.581465 -404.491755) (xy 137.573707 -404.54571) (xy 137.55835 -404.598012) (xy 137.535705 -404.647595)
			(xy 137.506234 -404.693452) (xy 137.470537 -404.734647) (xy 137.429341 -404.770343) (xy 137.383483 -404.799812)
			(xy 137.333899 -404.822455) (xy 137.281596 -404.83781) (xy 137.227641 -404.845566) (xy 137.200386 -404.846028)
			(xy 136.336786 -404.846028) (xy 136.309537 -404.845501) (xy 136.255594 -404.837743) (xy 136.203303 -404.822388)
			(xy 136.15373 -404.799747) (xy 136.107884 -404.770282) (xy 136.066698 -404.734592) (xy 136.03101 -404.693404)
			(xy 136.001546 -404.647557) (xy 135.978908 -404.597984) (xy 135.963554 -404.545693) (xy 135.955798 -404.491749)
			(xy 134.518142 -404.491749) (xy 134.518142 -404.491751) (xy 134.510387 -404.545697) (xy 134.495033 -404.597991)
			(xy 134.472394 -404.647568) (xy 134.44293 -404.693418) (xy 134.407242 -404.734609) (xy 134.366055 -404.770303)
			(xy 134.320208 -404.799772) (xy 134.270634 -404.822417) (xy 134.218342 -404.837777) (xy 134.164397 -404.845539)
			(xy 134.137146 -404.846028) (xy 133.273546 -404.846028) (xy 133.246292 -404.845528) (xy 133.192339 -404.837777)
			(xy 133.140039 -404.822425) (xy 133.090455 -404.799787) (xy 133.044599 -404.770321) (xy 133.003403 -404.73463)
			(xy 132.967706 -404.693438) (xy 132.938235 -404.647585) (xy 132.915591 -404.598004) (xy 132.900233 -404.545706)
			(xy 132.892475 -404.491754) (xy 131.454942 -404.491754) (xy 131.447185 -404.545702) (xy 131.43183 -404.597999)
			(xy 131.409188 -404.647579) (xy 131.379721 -404.693431) (xy 131.344028 -404.734624) (xy 131.302836 -404.770317)
			(xy 131.256984 -404.799785) (xy 131.207405 -404.822428) (xy 131.155108 -404.837784) (xy 131.101158 -404.845542)
			(xy 131.073906 -404.846028) (xy 130.210306 -404.846028) (xy 130.183054 -404.845525) (xy 130.129106 -404.837769)
			(xy 130.07681 -404.822415) (xy 130.027231 -404.799774) (xy 129.98138 -404.770307) (xy 129.940189 -404.734616)
			(xy 129.904496 -404.693425) (xy 129.875029 -404.647574) (xy 129.852388 -404.597996) (xy 129.837032 -404.5457)
			(xy 129.829275 -404.491752) (xy 128.391765 -404.491752) (xy 128.391765 -404.491756) (xy 128.384007 -404.545713)
			(xy 128.368648 -404.598016) (xy 128.346002 -404.647601) (xy 128.316529 -404.693458) (xy 128.28083 -404.734654)
			(xy 128.239631 -404.77035) (xy 128.193771 -404.799818) (xy 128.144184 -404.82246) (xy 128.091879 -404.837814)
			(xy 128.037922 -404.845567) (xy 128.010666 -404.846028) (xy 127.147066 -404.846028) (xy 127.119818 -404.845499)
			(xy 127.065877 -404.837739) (xy 127.013589 -404.822382) (xy 126.964018 -404.79974) (xy 126.918175 -404.770275)
			(xy 126.876991 -404.734585) (xy 126.841305 -404.693398) (xy 126.811843 -404.647552) (xy 126.789206 -404.597979)
			(xy 126.773853 -404.54569) (xy 126.766098 -404.491748) (xy 125.328442 -404.491748) (xy 125.328442 -404.491751)
			(xy 125.320686 -404.5457) (xy 125.305331 -404.597995) (xy 125.282691 -404.647573) (xy 125.253226 -404.693425)
			(xy 125.217535 -404.734617) (xy 125.176346 -404.77031) (xy 125.130496 -404.799778) (xy 125.08092 -404.822422)
			(xy 125.028625 -404.83778) (xy 124.974677 -404.84554) (xy 124.947426 -404.846028) (xy 124.083826 -404.846028)
			(xy 124.056573 -404.845526) (xy 124.002622 -404.837773) (xy 123.950324 -404.82242) (xy 123.900743 -404.79978)
			(xy 123.854889 -404.770314) (xy 123.813696 -404.734623) (xy 123.778001 -404.693431) (xy 123.748532 -404.647579)
			(xy 123.725889 -404.598) (xy 123.710533 -404.545703) (xy 123.702775 -404.491753) (xy 122.265265 -404.491753)
			(xy 122.265265 -404.491755) (xy 122.257507 -404.54571) (xy 122.24215 -404.598012) (xy 122.219505 -404.647595)
			(xy 122.190034 -404.693452) (xy 122.154337 -404.734647) (xy 122.113141 -404.770343) (xy 122.067283 -404.799812)
			(xy 122.017699 -404.822455) (xy 121.965396 -404.83781) (xy 121.911441 -404.845566) (xy 121.884186 -404.846028)
			(xy 121.020586 -404.846028) (xy 120.993337 -404.845501) (xy 120.939394 -404.837743) (xy 120.887103 -404.822388)
			(xy 120.83753 -404.799747) (xy 120.791684 -404.770282) (xy 120.750498 -404.734592) (xy 120.71481 -404.693404)
			(xy 120.685346 -404.647557) (xy 120.662708 -404.597984) (xy 120.647354 -404.545693) (xy 120.639598 -404.491749)
			(xy 119.201942 -404.491749) (xy 119.201942 -404.491751) (xy 119.194187 -404.545697) (xy 119.178833 -404.597991)
			(xy 119.156194 -404.647568) (xy 119.12673 -404.693418) (xy 119.091042 -404.734609) (xy 119.049855 -404.770303)
			(xy 119.004008 -404.799772) (xy 118.954434 -404.822417) (xy 118.902142 -404.837777) (xy 118.848197 -404.845539)
			(xy 118.820946 -404.846028) (xy 117.957346 -404.846028) (xy 117.930092 -404.845528) (xy 117.876139 -404.837777)
			(xy 117.823839 -404.822425) (xy 117.774255 -404.799787) (xy 117.728399 -404.770321) (xy 117.687203 -404.73463)
			(xy 117.651506 -404.693438) (xy 117.622035 -404.647585) (xy 117.599391 -404.598004) (xy 117.584033 -404.545706)
			(xy 117.576275 -404.491754) (xy 116.138742 -404.491754) (xy 116.130985 -404.545702) (xy 116.11563 -404.597999)
			(xy 116.092988 -404.647579) (xy 116.063521 -404.693431) (xy 116.027828 -404.734624) (xy 115.986636 -404.770317)
			(xy 115.940784 -404.799785) (xy 115.891205 -404.822428) (xy 115.838908 -404.837784) (xy 115.784958 -404.845542)
			(xy 115.757706 -404.846028) (xy 114.894106 -404.846028) (xy 114.866854 -404.845525) (xy 114.812906 -404.837769)
			(xy 114.76061 -404.822415) (xy 114.711031 -404.799774) (xy 114.66518 -404.770307) (xy 114.623989 -404.734616)
			(xy 114.588296 -404.693425) (xy 114.558829 -404.647574) (xy 114.536188 -404.597996) (xy 114.520832 -404.5457)
			(xy 114.513075 -404.491752) (xy 94.987465 -404.491752) (xy 94.987465 -404.491756) (xy 94.979707 -404.545713)
			(xy 94.964348 -404.598016) (xy 94.941702 -404.647602) (xy 94.912229 -404.693459) (xy 94.876529 -404.734655)
			(xy 94.83533 -404.77035) (xy 94.78947 -404.799819) (xy 94.739883 -404.822461) (xy 94.687578 -404.837814)
			(xy 94.63362 -404.845568) (xy 94.606364 -404.846028) (xy 93.742764 -404.846028) (xy 93.715516 -404.845499)
			(xy 93.661575 -404.837739) (xy 93.609287 -404.822382) (xy 93.559717 -404.79974) (xy 93.513874 -404.770274)
			(xy 93.47269 -404.734584) (xy 93.437004 -404.693397) (xy 93.407543 -404.647551) (xy 93.384906 -404.597979)
			(xy 93.369553 -404.54569) (xy 93.361798 -404.491748) (xy 91.924142 -404.491748) (xy 91.924142 -404.491752)
			(xy 91.916386 -404.5457) (xy 91.901031 -404.597996) (xy 91.878391 -404.647574) (xy 91.848925 -404.693425)
			(xy 91.813234 -404.734617) (xy 91.772045 -404.770311) (xy 91.726195 -404.799779) (xy 91.676618 -404.822423)
			(xy 91.624324 -404.837781) (xy 91.570376 -404.845541) (xy 91.543124 -404.846028) (xy 90.679524 -404.846028)
			(xy 90.652271 -404.845526) (xy 90.598321 -404.837773) (xy 90.546023 -404.822419) (xy 90.496442 -404.799779)
			(xy 90.450588 -404.770314) (xy 90.409395 -404.734622) (xy 90.373701 -404.693431) (xy 90.344232 -404.647579)
			(xy 90.321589 -404.598) (xy 90.306233 -404.545703) (xy 90.298475 -404.491753) (xy 88.860965 -404.491753)
			(xy 88.860965 -404.491755) (xy 88.853207 -404.54571) (xy 88.83785 -404.598012) (xy 88.815205 -404.647596)
			(xy 88.785734 -404.693452) (xy 88.750036 -404.734648) (xy 88.70884 -404.770343) (xy 88.662982 -404.799812)
			(xy 88.613397 -404.822455) (xy 88.561095 -404.837811) (xy 88.507139 -404.845566) (xy 88.479884 -404.846028)
			(xy 87.616284 -404.846028) (xy 87.589035 -404.845501) (xy 87.535092 -404.837743) (xy 87.482802 -404.822387)
			(xy 87.433229 -404.799746) (xy 87.387383 -404.770281) (xy 87.346197 -404.734591) (xy 87.310509 -404.693404)
			(xy 87.281046 -404.647557) (xy 87.258407 -404.597983) (xy 87.243054 -404.545692) (xy 87.235298 -404.491749)
			(xy 85.797642 -404.491749) (xy 85.797642 -404.491751) (xy 85.789887 -404.545697) (xy 85.774533 -404.597991)
			(xy 85.751894 -404.647568) (xy 85.72243 -404.693419) (xy 85.686741 -404.73461) (xy 85.645554 -404.770304)
			(xy 85.599707 -404.799773) (xy 85.550133 -404.822417) (xy 85.49784 -404.837777) (xy 85.443895 -404.845539)
			(xy 85.416644 -404.846028) (xy 84.553044 -404.846028) (xy 84.525791 -404.845528) (xy 84.471838 -404.837776)
			(xy 84.419537 -404.822425) (xy 84.369954 -404.799786) (xy 84.324098 -404.770321) (xy 84.282902 -404.734629)
			(xy 84.247206 -404.693437) (xy 84.217735 -404.647584) (xy 84.195091 -404.598004) (xy 84.179733 -404.545705)
			(xy 84.171975 -404.491753) (xy 82.734442 -404.491753) (xy 82.726685 -404.545703) (xy 82.71133 -404.598)
			(xy 82.688688 -404.647579) (xy 82.65922 -404.693432) (xy 82.623527 -404.734624) (xy 82.582335 -404.770318)
			(xy 82.536483 -404.799786) (xy 82.486904 -404.822428) (xy 82.434607 -404.837785) (xy 82.380656 -404.845542)
			(xy 82.353404 -404.846028) (xy 81.489804 -404.846028) (xy 81.462552 -404.845525) (xy 81.408604 -404.837769)
			(xy 81.356308 -404.822414) (xy 81.30673 -404.799773) (xy 81.260879 -404.770307) (xy 81.219688 -404.734615)
			(xy 81.183996 -404.693424) (xy 81.154529 -404.647573) (xy 81.131887 -404.597995) (xy 81.116532 -404.5457)
			(xy 81.108775 -404.491752) (xy 79.671265 -404.491752) (xy 79.671265 -404.491756) (xy 79.663507 -404.545713)
			(xy 79.648148 -404.598016) (xy 79.625502 -404.647602) (xy 79.596029 -404.693459) (xy 79.560329 -404.734655)
			(xy 79.51913 -404.77035) (xy 79.47327 -404.799819) (xy 79.423683 -404.822461) (xy 79.371378 -404.837814)
			(xy 79.31742 -404.845568) (xy 79.290164 -404.846028) (xy 78.426564 -404.846028) (xy 78.399316 -404.845499)
			(xy 78.345375 -404.837739) (xy 78.293087 -404.822382) (xy 78.243517 -404.79974) (xy 78.197674 -404.770274)
			(xy 78.15649 -404.734584) (xy 78.120804 -404.693397) (xy 78.091343 -404.647551) (xy 78.068706 -404.597979)
			(xy 78.053353 -404.54569) (xy 78.045598 -404.491748) (xy 76.607942 -404.491748) (xy 76.607942 -404.491752)
			(xy 76.600186 -404.5457) (xy 76.584831 -404.597996) (xy 76.562191 -404.647574) (xy 76.532725 -404.693425)
			(xy 76.497034 -404.734617) (xy 76.455845 -404.770311) (xy 76.409995 -404.799779) (xy 76.360418 -404.822423)
			(xy 76.308124 -404.837781) (xy 76.254176 -404.845541) (xy 76.226924 -404.846028) (xy 75.363324 -404.846028)
			(xy 75.336071 -404.845526) (xy 75.282121 -404.837773) (xy 75.229823 -404.822419) (xy 75.180242 -404.799779)
			(xy 75.134388 -404.770314) (xy 75.093195 -404.734622) (xy 75.057501 -404.693431) (xy 75.028032 -404.647579)
			(xy 75.005389 -404.598) (xy 74.990033 -404.545703) (xy 74.982275 -404.491753) (xy 73.544765 -404.491753)
			(xy 73.544765 -404.491755) (xy 73.537007 -404.54571) (xy 73.52165 -404.598012) (xy 73.499005 -404.647596)
			(xy 73.469534 -404.693452) (xy 73.433836 -404.734648) (xy 73.39264 -404.770343) (xy 73.346782 -404.799812)
			(xy 73.297197 -404.822455) (xy 73.244895 -404.837811) (xy 73.190939 -404.845566) (xy 73.163684 -404.846028)
			(xy 72.300084 -404.846028) (xy 72.272835 -404.845501) (xy 72.218892 -404.837743) (xy 72.166602 -404.822387)
			(xy 72.117029 -404.799746) (xy 72.071183 -404.770281) (xy 72.029997 -404.734591) (xy 71.994309 -404.693404)
			(xy 71.964846 -404.647557) (xy 71.942207 -404.597983) (xy 71.926854 -404.545692) (xy 71.919098 -404.491749)
			(xy 70.481442 -404.491749) (xy 70.481442 -404.491751) (xy 70.473687 -404.545697) (xy 70.458333 -404.597991)
			(xy 70.435694 -404.647568) (xy 70.40623 -404.693419) (xy 70.370541 -404.73461) (xy 70.329354 -404.770304)
			(xy 70.283507 -404.799773) (xy 70.233933 -404.822417) (xy 70.18164 -404.837777) (xy 70.127695 -404.845539)
			(xy 70.100444 -404.846028) (xy 69.236844 -404.846028) (xy 69.209591 -404.845528) (xy 69.155638 -404.837776)
			(xy 69.103337 -404.822425) (xy 69.053754 -404.799786) (xy 69.007898 -404.770321) (xy 68.966702 -404.734629)
			(xy 68.931006 -404.693437) (xy 68.901535 -404.647584) (xy 68.878891 -404.598004) (xy 68.863533 -404.545705)
			(xy 68.855775 -404.491753) (xy 67.418242 -404.491753) (xy 67.410485 -404.545703) (xy 67.39513 -404.598)
			(xy 67.372488 -404.647579) (xy 67.34302 -404.693432) (xy 67.307327 -404.734624) (xy 67.266135 -404.770318)
			(xy 67.220283 -404.799786) (xy 67.170704 -404.822428) (xy 67.118407 -404.837785) (xy 67.064456 -404.845542)
			(xy 67.037204 -404.846028) (xy 66.173604 -404.846028) (xy 66.146352 -404.845525) (xy 66.092404 -404.837769)
			(xy 66.040108 -404.822414) (xy 65.99053 -404.799773) (xy 65.944679 -404.770307) (xy 65.903488 -404.734615)
			(xy 65.867796 -404.693424) (xy 65.838329 -404.647573) (xy 65.815687 -404.597995) (xy 65.800332 -404.5457)
			(xy 65.792575 -404.491752) (xy 64.355065 -404.491752) (xy 64.355065 -404.491756) (xy 64.347307 -404.545713)
			(xy 64.331948 -404.598016) (xy 64.309302 -404.647602) (xy 64.279829 -404.693459) (xy 64.244129 -404.734655)
			(xy 64.20293 -404.77035) (xy 64.15707 -404.799819) (xy 64.107483 -404.822461) (xy 64.055178 -404.837814)
			(xy 64.00122 -404.845568) (xy 63.973964 -404.846028) (xy 63.110364 -404.846028) (xy 63.083116 -404.845499)
			(xy 63.029175 -404.837739) (xy 62.976887 -404.822382) (xy 62.927317 -404.79974) (xy 62.881474 -404.770274)
			(xy 62.84029 -404.734584) (xy 62.804604 -404.693397) (xy 62.775143 -404.647551) (xy 62.752506 -404.597979)
			(xy 62.737153 -404.54569) (xy 62.729398 -404.491748) (xy 61.291742 -404.491748) (xy 61.291742 -404.491752)
			(xy 61.283986 -404.5457) (xy 61.268631 -404.597996) (xy 61.245991 -404.647574) (xy 61.216525 -404.693425)
			(xy 61.180834 -404.734617) (xy 61.139645 -404.770311) (xy 61.093795 -404.799779) (xy 61.044218 -404.822423)
			(xy 60.991924 -404.837781) (xy 60.937976 -404.845541) (xy 60.910724 -404.846028) (xy 60.047124 -404.846028)
			(xy 60.019871 -404.845526) (xy 59.965921 -404.837773) (xy 59.913623 -404.822419) (xy 59.864042 -404.799779)
			(xy 59.818188 -404.770314) (xy 59.776995 -404.734622) (xy 59.741301 -404.693431) (xy 59.711832 -404.647579)
			(xy 59.689189 -404.598) (xy 59.673833 -404.545703) (xy 59.666075 -404.491753) (xy 58.228565 -404.491753)
			(xy 58.228565 -404.491755) (xy 58.220807 -404.54571) (xy 58.20545 -404.598012) (xy 58.182805 -404.647596)
			(xy 58.153334 -404.693452) (xy 58.117636 -404.734648) (xy 58.07644 -404.770343) (xy 58.030582 -404.799812)
			(xy 57.980997 -404.822455) (xy 57.928695 -404.837811) (xy 57.874739 -404.845566) (xy 57.847484 -404.846028)
			(xy 56.983884 -404.846028) (xy 56.956635 -404.845501) (xy 56.902692 -404.837743) (xy 56.850402 -404.822387)
			(xy 56.800829 -404.799746) (xy 56.754983 -404.770281) (xy 56.713797 -404.734591) (xy 56.678109 -404.693404)
			(xy 56.648646 -404.647557) (xy 56.626007 -404.597983) (xy 56.610654 -404.545692) (xy 56.602898 -404.491749)
			(xy 55.165242 -404.491749) (xy 55.165242 -404.491751) (xy 55.157487 -404.545697) (xy 55.142133 -404.597991)
			(xy 55.119494 -404.647568) (xy 55.09003 -404.693419) (xy 55.054341 -404.73461) (xy 55.013154 -404.770304)
			(xy 54.967307 -404.799773) (xy 54.917733 -404.822417) (xy 54.86544 -404.837777) (xy 54.811495 -404.845539)
			(xy 54.784244 -404.846028) (xy 53.920644 -404.846028) (xy 53.893391 -404.845528) (xy 53.839438 -404.837776)
			(xy 53.787137 -404.822425) (xy 53.737554 -404.799786) (xy 53.691698 -404.770321) (xy 53.650502 -404.734629)
			(xy 53.614806 -404.693437) (xy 53.585335 -404.647584) (xy 53.562691 -404.598004) (xy 53.547333 -404.545705)
			(xy 53.539575 -404.491753) (xy 52.102042 -404.491753) (xy 52.094285 -404.545703) (xy 52.07893 -404.598)
			(xy 52.056288 -404.647579) (xy 52.02682 -404.693432) (xy 51.991127 -404.734624) (xy 51.949935 -404.770318)
			(xy 51.904083 -404.799786) (xy 51.854504 -404.822428) (xy 51.802207 -404.837785) (xy 51.748256 -404.845542)
			(xy 51.721004 -404.846028) (xy 50.857404 -404.846028) (xy 50.830152 -404.845525) (xy 50.776204 -404.837769)
			(xy 50.723908 -404.822414) (xy 50.67433 -404.799773) (xy 50.628479 -404.770307) (xy 50.587288 -404.734615)
			(xy 50.551596 -404.693424) (xy 50.522129 -404.647573) (xy 50.499487 -404.597995) (xy 50.484132 -404.5457)
			(xy 50.476375 -404.491752) (xy 49.038865 -404.491752) (xy 49.038865 -404.491756) (xy 49.031107 -404.545713)
			(xy 49.015748 -404.598016) (xy 48.993102 -404.647602) (xy 48.963629 -404.693459) (xy 48.927929 -404.734655)
			(xy 48.88673 -404.77035) (xy 48.84087 -404.799819) (xy 48.791283 -404.822461) (xy 48.738978 -404.837814)
			(xy 48.68502 -404.845568) (xy 48.657764 -404.846028) (xy 47.794164 -404.846028) (xy 47.766916 -404.845499)
			(xy 47.712975 -404.837739) (xy 47.660687 -404.822382) (xy 47.611117 -404.79974) (xy 47.565274 -404.770274)
			(xy 47.52409 -404.734584) (xy 47.488404 -404.693397) (xy 47.458943 -404.647551) (xy 47.436306 -404.597979)
			(xy 47.420953 -404.54569) (xy 47.413198 -404.491748) (xy 45.559703 -404.491748) (xy 45.562463 -404.52264)
			(xy 45.570405 -404.70075) (xy 45.570902 -404.789894) (xy 45.570405 -404.879038) (xy 45.562463 -405.057148)
			(xy 45.546595 -405.234728) (xy 45.522831 -405.411424) (xy 45.49122 -405.586887) (xy 45.479552 -405.638385)
			(xy 104.009796 -405.638385) (xy 104.013672 -405.584006) (xy 104.025246 -405.530732) (xy 104.044281 -405.479646)
			(xy 104.070391 -405.431789) (xy 104.103044 -405.388132) (xy 104.121966 -405.368506) (xy 104.732582 -404.757636)
			(xy 104.75423 -404.736857) (xy 104.802784 -404.701606) (xy 104.856253 -404.67438) (xy 104.91332 -404.655848)
			(xy 104.972583 -404.646465) (xy 105.002584 -404.645876) (xy 105.029856 -404.646316) (xy 105.083846 -404.654077)
			(xy 105.136181 -404.669444) (xy 105.185797 -404.692102) (xy 105.231683 -404.721592) (xy 105.272904 -404.757312)
			(xy 105.308622 -404.798535) (xy 105.338108 -404.844422) (xy 105.360764 -404.894039) (xy 105.376127 -404.946376)
			(xy 105.383885 -405.000366) (xy 105.384346 -405.027638) (xy 105.383744 -405.057639) (xy 105.374371 -405.116904)
			(xy 105.355845 -405.173974) (xy 105.328623 -405.227445) (xy 105.29971 -405.267273) (xy 106.824184 -405.267273)
			(xy 106.824184 -405.212727) (xy 106.831947 -405.158735) (xy 106.847315 -405.106398) (xy 106.869976 -405.05678)
			(xy 106.899467 -405.010893) (xy 106.935189 -404.969671) (xy 106.976414 -404.933951) (xy 107.022303 -404.904463)
			(xy 107.071922 -404.881806) (xy 107.12426 -404.866441) (xy 107.178252 -404.858682) (xy 107.205526 -404.85822)
			(xy 108.069126 -404.85822) (xy 108.096393 -404.858744) (xy 108.150371 -404.866508) (xy 108.202695 -404.881875)
			(xy 108.2523 -404.904532) (xy 108.298175 -404.934017) (xy 108.339388 -404.969731) (xy 108.375098 -405.010946)
			(xy 108.404581 -405.056823) (xy 108.427234 -405.106429) (xy 108.442597 -405.158754) (xy 108.450358 -405.212733)
			(xy 108.450358 -405.267267) (xy 108.442597 -405.321246) (xy 108.427234 -405.373571) (xy 108.404581 -405.423177)
			(xy 108.375098 -405.469054) (xy 108.339388 -405.510269) (xy 108.298175 -405.545983) (xy 108.2523 -405.575468)
			(xy 108.202695 -405.598125) (xy 108.150371 -405.613492) (xy 108.096393 -405.621256) (xy 108.069126 -405.621744)
			(xy 107.205526 -405.621744) (xy 107.178252 -405.621318) (xy 107.12426 -405.613559) (xy 107.071922 -405.598194)
			(xy 107.022303 -405.575537) (xy 106.976414 -405.546049) (xy 106.935189 -405.510329) (xy 106.899467 -405.469107)
			(xy 106.869976 -405.42322) (xy 106.847315 -405.373602) (xy 106.831947 -405.321265) (xy 106.824184 -405.267273)
			(xy 105.29971 -405.267273) (xy 105.293374 -405.276001) (xy 105.272586 -405.29764) (xy 104.661716 -405.908256)
			(xy 104.642167 -405.927256) (xy 104.598511 -405.959909) (xy 104.550654 -405.986019) (xy 104.499568 -406.005054)
			(xy 104.446294 -406.016628) (xy 104.391915 -406.020504) (xy 104.337538 -406.016603) (xy 104.284269 -406.005006)
			(xy 104.233192 -405.985949) (xy 104.185346 -405.959818) (xy 104.141704 -405.927145) (xy 104.103155 -405.888596)
			(xy 104.070482 -405.844954) (xy 104.044351 -405.797108) (xy 104.025294 -405.746031) (xy 104.013697 -405.692762)
			(xy 104.009796 -405.638385) (xy 45.479552 -405.638385) (xy 45.451824 -405.760767) (xy 45.404722 -405.93272)
			(xy 45.350006 -406.102404) (xy 45.287785 -406.269481) (xy 45.218184 -406.433622) (xy 45.141339 -406.594498)
			(xy 45.057405 -406.751792) (xy 44.966547 -406.905191) (xy 44.883756 -407.031749) (xy 48.944798 -407.031749)
			(xy 48.944798 -406.977251) (xy 48.952554 -406.923308) (xy 48.967907 -406.871017) (xy 48.990546 -406.821443)
			(xy 49.020009 -406.775596) (xy 49.055697 -406.734409) (xy 49.096883 -406.698719) (xy 49.142729 -406.669254)
			(xy 49.192302 -406.646613) (xy 49.244592 -406.631257) (xy 49.298535 -406.623499) (xy 49.325784 -406.623012)
			(xy 50.189384 -406.623012) (xy 50.216639 -406.623434) (xy 50.270595 -406.631189) (xy 50.322897 -406.646545)
			(xy 50.372482 -406.669188) (xy 50.41834 -406.698657) (xy 50.459536 -406.734352) (xy 50.495234 -406.775548)
			(xy 50.524705 -406.821404) (xy 50.54735 -406.870988) (xy 50.562707 -406.92329) (xy 50.570465 -406.977245)
			(xy 50.570465 -407.031753) (xy 52.007975 -407.031753) (xy 52.007975 -406.977247) (xy 52.015733 -406.923297)
			(xy 52.031089 -406.871) (xy 52.053732 -406.821421) (xy 52.083201 -406.775569) (xy 52.118895 -406.734378)
			(xy 52.160088 -406.698686) (xy 52.205942 -406.669221) (xy 52.255523 -406.646581) (xy 52.307821 -406.631227)
			(xy 52.361771 -406.623474) (xy 52.389024 -406.623012) (xy 53.252624 -406.623012) (xy 53.279876 -406.623459)
			(xy 53.333824 -406.631219) (xy 53.386118 -406.646577) (xy 53.435695 -406.669221) (xy 53.481545 -406.698689)
			(xy 53.522734 -406.734383) (xy 53.558425 -406.775575) (xy 53.587891 -406.821426) (xy 53.610531 -406.871004)
			(xy 53.625886 -406.9233) (xy 53.633642 -406.977248) (xy 53.633642 -407.031748) (xy 55.071298 -407.031748)
			(xy 55.071298 -406.977252) (xy 55.079053 -406.92331) (xy 55.094406 -406.871021) (xy 55.117043 -406.821449)
			(xy 55.146504 -406.775603) (xy 55.18219 -406.734416) (xy 55.223374 -406.698726) (xy 55.269217 -406.66926)
			(xy 55.318787 -406.646618) (xy 55.371075 -406.631261) (xy 55.425016 -406.623501) (xy 55.452264 -406.623012)
			(xy 56.315864 -406.623012) (xy 56.34312 -406.623432) (xy 56.397078 -406.631186) (xy 56.449383 -406.646539)
			(xy 56.49897 -406.669181) (xy 56.54483 -406.69865) (xy 56.586029 -406.734345) (xy 56.621729 -406.775541)
			(xy 56.651202 -406.821398) (xy 56.673848 -406.870984) (xy 56.689207 -406.923287) (xy 56.696965 -406.977244)
			(xy 56.696965 -407.031752) (xy 58.134475 -407.031752) (xy 58.134475 -406.977248) (xy 58.142232 -406.9233)
			(xy 58.157587 -406.871005) (xy 58.180229 -406.821427) (xy 58.209696 -406.775576) (xy 58.245388 -406.734385)
			(xy 58.286579 -406.698693) (xy 58.33243 -406.669227) (xy 58.382008 -406.646586) (xy 58.434304 -406.631231)
			(xy 58.488252 -406.623475) (xy 58.515504 -406.623012) (xy 59.379104 -406.623012) (xy 59.406356 -406.623458)
			(xy 59.460307 -406.631215) (xy 59.512604 -406.646572) (xy 59.562183 -406.669214) (xy 59.608035 -406.698682)
			(xy 59.649227 -406.734376) (xy 59.68492 -406.775568) (xy 59.714388 -406.821421) (xy 59.73703 -406.871)
			(xy 59.752385 -406.923297) (xy 59.760142 -406.977248) (xy 59.760142 -407.031752) (xy 59.760142 -407.031753)
			(xy 61.197675 -407.031753) (xy 61.197675 -406.977247) (xy 61.205433 -406.923295) (xy 61.220791 -406.870996)
			(xy 61.243435 -406.821416) (xy 61.272906 -406.775563) (xy 61.308602 -406.734371) (xy 61.349798 -406.698679)
			(xy 61.395654 -406.669214) (xy 61.445237 -406.646575) (xy 61.497538 -406.631224) (xy 61.551491 -406.623472)
			(xy 61.578744 -406.623012) (xy 62.442344 -406.623012) (xy 62.469595 -406.623461) (xy 62.52354 -406.631223)
			(xy 62.575833 -406.646583) (xy 62.625407 -406.669227) (xy 62.671254 -406.698696) (xy 62.712441 -406.73439)
			(xy 62.74813 -406.775581) (xy 62.777594 -406.821432) (xy 62.800233 -406.871009) (xy 62.815587 -406.923303)
			(xy 62.823342 -406.977249) (xy 62.823342 -407.031749) (xy 64.260998 -407.031749) (xy 64.260998 -406.977251)
			(xy 64.268754 -406.923308) (xy 64.284107 -406.871017) (xy 64.306746 -406.821443) (xy 64.336209 -406.775596)
			(xy 64.371897 -406.734409) (xy 64.413083 -406.698719) (xy 64.458929 -406.669254) (xy 64.508502 -406.646613)
			(xy 64.560792 -406.631257) (xy 64.614735 -406.623499) (xy 64.641984 -406.623012) (xy 65.505584 -406.623012)
			(xy 65.532839 -406.623434) (xy 65.586795 -406.631189) (xy 65.639097 -406.646545) (xy 65.688682 -406.669188)
			(xy 65.73454 -406.698657) (xy 65.775736 -406.734352) (xy 65.811434 -406.775548) (xy 65.840905 -406.821404)
			(xy 65.86355 -406.870988) (xy 65.878907 -406.92329) (xy 65.886665 -406.977245) (xy 65.886665 -407.031753)
			(xy 67.324175 -407.031753) (xy 67.324175 -406.977247) (xy 67.331933 -406.923297) (xy 67.347289 -406.871)
			(xy 67.369932 -406.821421) (xy 67.399401 -406.775569) (xy 67.435095 -406.734378) (xy 67.476288 -406.698686)
			(xy 67.522142 -406.669221) (xy 67.571723 -406.646581) (xy 67.624021 -406.631227) (xy 67.677971 -406.623474)
			(xy 67.705224 -406.623012) (xy 68.568824 -406.623012) (xy 68.596076 -406.623459) (xy 68.650024 -406.631219)
			(xy 68.702318 -406.646577) (xy 68.751895 -406.669221) (xy 68.797745 -406.698689) (xy 68.838934 -406.734383)
			(xy 68.874625 -406.775575) (xy 68.904091 -406.821426) (xy 68.926731 -406.871004) (xy 68.942086 -406.9233)
			(xy 68.949842 -406.977248) (xy 68.949842 -407.031748) (xy 70.387498 -407.031748) (xy 70.387498 -406.977252)
			(xy 70.395253 -406.92331) (xy 70.410606 -406.871021) (xy 70.433243 -406.821449) (xy 70.462704 -406.775603)
			(xy 70.49839 -406.734416) (xy 70.539574 -406.698726) (xy 70.585417 -406.66926) (xy 70.634987 -406.646618)
			(xy 70.687275 -406.631261) (xy 70.741216 -406.623501) (xy 70.768464 -406.623012) (xy 71.632064 -406.623012)
			(xy 71.65932 -406.623432) (xy 71.713278 -406.631186) (xy 71.765583 -406.646539) (xy 71.81517 -406.669181)
			(xy 71.86103 -406.69865) (xy 71.902229 -406.734345) (xy 71.937929 -406.775541) (xy 71.967402 -406.821398)
			(xy 71.990048 -406.870984) (xy 72.005407 -406.923287) (xy 72.013165 -406.977244) (xy 72.013165 -407.031752)
			(xy 73.450675 -407.031752) (xy 73.450675 -406.977248) (xy 73.458432 -406.9233) (xy 73.473787 -406.871005)
			(xy 73.496429 -406.821427) (xy 73.525896 -406.775576) (xy 73.561588 -406.734385) (xy 73.602779 -406.698693)
			(xy 73.64863 -406.669227) (xy 73.698208 -406.646586) (xy 73.750504 -406.631231) (xy 73.804452 -406.623475)
			(xy 73.831704 -406.623012) (xy 74.695304 -406.623012) (xy 74.722556 -406.623458) (xy 74.776507 -406.631215)
			(xy 74.828804 -406.646572) (xy 74.878383 -406.669214) (xy 74.924235 -406.698682) (xy 74.965427 -406.734376)
			(xy 75.00112 -406.775568) (xy 75.030588 -406.821421) (xy 75.05323 -406.871) (xy 75.068585 -406.923297)
			(xy 75.076342 -406.977248) (xy 75.076342 -407.031752) (xy 75.076342 -407.031753) (xy 76.513875 -407.031753)
			(xy 76.513875 -406.977247) (xy 76.521633 -406.923295) (xy 76.536991 -406.870996) (xy 76.559635 -406.821416)
			(xy 76.589106 -406.775563) (xy 76.624802 -406.734371) (xy 76.665998 -406.698679) (xy 76.711854 -406.669214)
			(xy 76.761437 -406.646575) (xy 76.813738 -406.631224) (xy 76.867691 -406.623472) (xy 76.894944 -406.623012)
			(xy 77.758544 -406.623012) (xy 77.785795 -406.623461) (xy 77.83974 -406.631223) (xy 77.892033 -406.646583)
			(xy 77.941607 -406.669227) (xy 77.987454 -406.698696) (xy 78.028641 -406.73439) (xy 78.06433 -406.775581)
			(xy 78.093794 -406.821432) (xy 78.116433 -406.871009) (xy 78.131787 -406.923303) (xy 78.139542 -406.977249)
			(xy 78.139542 -407.031749) (xy 79.577198 -407.031749) (xy 79.577198 -406.977251) (xy 79.584954 -406.923308)
			(xy 79.600307 -406.871017) (xy 79.622946 -406.821443) (xy 79.652409 -406.775596) (xy 79.688097 -406.734409)
			(xy 79.729283 -406.698719) (xy 79.775129 -406.669254) (xy 79.824702 -406.646613) (xy 79.876992 -406.631257)
			(xy 79.930935 -406.623499) (xy 79.958184 -406.623012) (xy 80.821784 -406.623012) (xy 80.849039 -406.623434)
			(xy 80.902995 -406.631189) (xy 80.955297 -406.646545) (xy 81.004882 -406.669188) (xy 81.05074 -406.698657)
			(xy 81.091936 -406.734352) (xy 81.127634 -406.775548) (xy 81.157105 -406.821404) (xy 81.17975 -406.870988)
			(xy 81.195107 -406.92329) (xy 81.202865 -406.977245) (xy 81.202865 -407.031753) (xy 82.640375 -407.031753)
			(xy 82.640375 -406.977247) (xy 82.648133 -406.923297) (xy 82.663489 -406.871) (xy 82.686132 -406.821421)
			(xy 82.715601 -406.775569) (xy 82.751295 -406.734378) (xy 82.792488 -406.698686) (xy 82.838342 -406.669221)
			(xy 82.887923 -406.646581) (xy 82.940221 -406.631227) (xy 82.994171 -406.623474) (xy 83.021424 -406.623012)
			(xy 83.885024 -406.623012) (xy 83.912276 -406.623459) (xy 83.966224 -406.631219) (xy 84.018518 -406.646577)
			(xy 84.068095 -406.669221) (xy 84.113945 -406.698689) (xy 84.155134 -406.734383) (xy 84.190825 -406.775575)
			(xy 84.220291 -406.821426) (xy 84.242931 -406.871004) (xy 84.258286 -406.9233) (xy 84.266042 -406.977248)
			(xy 84.266042 -407.031748) (xy 85.703698 -407.031748) (xy 85.703698 -406.977252) (xy 85.711453 -406.92331)
			(xy 85.726806 -406.871021) (xy 85.749443 -406.821449) (xy 85.778904 -406.775603) (xy 85.81459 -406.734416)
			(xy 85.855774 -406.698726) (xy 85.901617 -406.66926) (xy 85.951187 -406.646618) (xy 86.003475 -406.631261)
			(xy 86.057416 -406.623501) (xy 86.084664 -406.623012) (xy 86.948264 -406.623012) (xy 86.97552 -406.623432)
			(xy 87.029478 -406.631186) (xy 87.081783 -406.646539) (xy 87.13137 -406.669181) (xy 87.17723 -406.69865)
			(xy 87.218429 -406.734345) (xy 87.254129 -406.775541) (xy 87.283602 -406.821398) (xy 87.306248 -406.870984)
			(xy 87.321607 -406.923287) (xy 87.329365 -406.977244) (xy 87.329365 -407.031752) (xy 88.766875 -407.031752)
			(xy 88.766875 -406.977248) (xy 88.774632 -406.9233) (xy 88.789987 -406.871005) (xy 88.812629 -406.821427)
			(xy 88.842096 -406.775576) (xy 88.877788 -406.734385) (xy 88.918979 -406.698693) (xy 88.96483 -406.669227)
			(xy 89.014408 -406.646586) (xy 89.066704 -406.631231) (xy 89.120652 -406.623475) (xy 89.147904 -406.623012)
			(xy 90.011504 -406.623012) (xy 90.038756 -406.623458) (xy 90.092707 -406.631215) (xy 90.145004 -406.646572)
			(xy 90.194583 -406.669214) (xy 90.240435 -406.698682) (xy 90.281627 -406.734376) (xy 90.31732 -406.775568)
			(xy 90.346788 -406.821421) (xy 90.36943 -406.871) (xy 90.384785 -406.923297) (xy 90.392542 -406.977248)
			(xy 90.392542 -407.031752) (xy 90.392542 -407.031753) (xy 91.830075 -407.031753) (xy 91.830075 -406.977247)
			(xy 91.837833 -406.923295) (xy 91.853191 -406.870996) (xy 91.875835 -406.821416) (xy 91.905306 -406.775563)
			(xy 91.941002 -406.734371) (xy 91.982198 -406.698679) (xy 92.028054 -406.669214) (xy 92.077637 -406.646575)
			(xy 92.129938 -406.631224) (xy 92.183891 -406.623472) (xy 92.211144 -406.623012) (xy 93.074744 -406.623012)
			(xy 93.101995 -406.623461) (xy 93.15594 -406.631223) (xy 93.208233 -406.646583) (xy 93.257807 -406.669227)
			(xy 93.303654 -406.698696) (xy 93.344841 -406.73439) (xy 93.38053 -406.775581) (xy 93.409994 -406.821432)
			(xy 93.432633 -406.871009) (xy 93.447987 -406.923303) (xy 93.455742 -406.977249) (xy 93.455742 -407.031749)
			(xy 94.893398 -407.031749) (xy 94.893398 -406.977251) (xy 94.901154 -406.923308) (xy 94.916507 -406.871017)
			(xy 94.939146 -406.821443) (xy 94.968609 -406.775596) (xy 95.004297 -406.734409) (xy 95.045483 -406.698719)
			(xy 95.091329 -406.669254) (xy 95.140902 -406.646613) (xy 95.193192 -406.631257) (xy 95.247135 -406.623499)
			(xy 95.274384 -406.623012) (xy 96.137984 -406.623012) (xy 96.165239 -406.623434) (xy 96.219195 -406.631189)
			(xy 96.271497 -406.646545) (xy 96.321082 -406.669188) (xy 96.36694 -406.698657) (xy 96.408136 -406.734352)
			(xy 96.443834 -406.775548) (xy 96.473305 -406.821404) (xy 96.49595 -406.870988) (xy 96.511307 -406.92329)
			(xy 96.519065 -406.977245) (xy 96.519065 -407.031753) (xy 116.044675 -407.031753) (xy 116.044675 -406.977247)
			(xy 116.052433 -406.923297) (xy 116.067789 -406.871) (xy 116.090432 -406.821421) (xy 116.119901 -406.775569)
			(xy 116.155596 -406.734377) (xy 116.196789 -406.698686) (xy 116.242643 -406.66922) (xy 116.292224 -406.64658)
			(xy 116.344522 -406.631227) (xy 116.398473 -406.623474) (xy 116.425726 -406.623012) (xy 117.289326 -406.623012)
			(xy 117.316577 -406.62346) (xy 117.370525 -406.63122) (xy 117.42282 -406.646578) (xy 117.472396 -406.669222)
			(xy 117.518246 -406.69869) (xy 117.559435 -406.734383) (xy 117.595126 -406.775575) (xy 117.624591 -406.821427)
			(xy 117.647231 -406.871005) (xy 117.662586 -406.9233) (xy 117.670342 -406.977249) (xy 117.670342 -407.031748)
			(xy 119.107998 -407.031748) (xy 119.107998 -406.977252) (xy 119.115753 -406.92331) (xy 119.131106 -406.871021)
			(xy 119.153743 -406.821448) (xy 119.183205 -406.775602) (xy 119.218891 -406.734415) (xy 119.260075 -406.698725)
			(xy 119.305918 -406.66926) (xy 119.355489 -406.646618) (xy 119.407777 -406.631261) (xy 119.461718 -406.623501)
			(xy 119.488966 -406.623012) (xy 120.352566 -406.623012) (xy 120.379822 -406.623433) (xy 120.433779 -406.631186)
			(xy 120.486084 -406.64654) (xy 120.535671 -406.669182) (xy 120.581531 -406.69865) (xy 120.62273 -406.734346)
			(xy 120.658429 -406.775542) (xy 120.687902 -406.821399) (xy 120.710548 -406.870984) (xy 120.725907 -406.923287)
			(xy 120.733665 -406.977244) (xy 120.733665 -407.031752) (xy 122.171175 -407.031752) (xy 122.171175 -406.977248)
			(xy 122.178932 -406.9233) (xy 122.194288 -406.871004) (xy 122.216929 -406.821426) (xy 122.246396 -406.775575)
			(xy 122.282089 -406.734384) (xy 122.32328 -406.698693) (xy 122.369131 -406.669226) (xy 122.41871 -406.646585)
			(xy 122.471006 -406.631231) (xy 122.524954 -406.623475) (xy 122.552206 -406.623012) (xy 123.415806 -406.623012)
			(xy 123.443058 -406.623458) (xy 123.497008 -406.631216) (xy 123.549305 -406.646572) (xy 123.598884 -406.669215)
			(xy 123.644736 -406.698683) (xy 123.685928 -406.734376) (xy 123.721621 -406.775569) (xy 123.751088 -406.821421)
			(xy 123.77373 -406.871001) (xy 123.789085 -406.923298) (xy 123.796842 -406.977248) (xy 123.796842 -407.031752)
			(xy 123.796842 -407.031754) (xy 125.234375 -407.031754) (xy 125.234375 -406.977246) (xy 125.242133 -406.923294)
			(xy 125.257491 -406.870996) (xy 125.280135 -406.821415) (xy 125.309606 -406.775562) (xy 125.345303 -406.73437)
			(xy 125.386499 -406.698679) (xy 125.432355 -406.669213) (xy 125.481939 -406.646575) (xy 125.534239 -406.631223)
			(xy 125.588192 -406.623472) (xy 125.615446 -406.623012) (xy 126.479046 -406.623012) (xy 126.506297 -406.623461)
			(xy 126.560242 -406.631223) (xy 126.612534 -406.646583) (xy 126.662108 -406.669228) (xy 126.707955 -406.698697)
			(xy 126.749142 -406.734391) (xy 126.78483 -406.775582) (xy 126.814294 -406.821432) (xy 126.836933 -406.871009)
			(xy 126.852287 -406.923303) (xy 126.860042 -406.977249) (xy 126.860042 -407.031749) (xy 128.297698 -407.031749)
			(xy 128.297698 -406.977251) (xy 128.305454 -406.923307) (xy 128.320808 -406.871016) (xy 128.343446 -406.821443)
			(xy 128.37291 -406.775596) (xy 128.408598 -406.734408) (xy 128.449784 -406.698718) (xy 128.49563 -406.669253)
			(xy 128.545203 -406.646612) (xy 128.597494 -406.631257) (xy 128.651437 -406.623499) (xy 128.678686 -406.623012)
			(xy 129.542286 -406.623012) (xy 129.569541 -406.623434) (xy 129.623496 -406.63119) (xy 129.675799 -406.646545)
			(xy 129.725383 -406.669188) (xy 129.771241 -406.698657) (xy 129.812437 -406.734353) (xy 129.848134 -406.775548)
			(xy 129.877605 -406.821405) (xy 129.90025 -406.870988) (xy 129.915607 -406.92329) (xy 129.923365 -406.977245)
			(xy 129.923365 -407.031753) (xy 131.360875 -407.031753) (xy 131.360875 -406.977247) (xy 131.368633 -406.923297)
			(xy 131.383989 -406.871) (xy 131.406632 -406.821421) (xy 131.436101 -406.775569) (xy 131.471796 -406.734377)
			(xy 131.512989 -406.698686) (xy 131.558843 -406.66922) (xy 131.608424 -406.64658) (xy 131.660722 -406.631227)
			(xy 131.714673 -406.623474) (xy 131.741926 -406.623012) (xy 132.605526 -406.623012) (xy 132.632777 -406.62346)
			(xy 132.686725 -406.63122) (xy 132.73902 -406.646578) (xy 132.788596 -406.669222) (xy 132.834446 -406.69869)
			(xy 132.875635 -406.734383) (xy 132.911326 -406.775575) (xy 132.940791 -406.821427) (xy 132.963431 -406.871005)
			(xy 132.978786 -406.9233) (xy 132.986542 -406.977249) (xy 132.986542 -407.031748) (xy 134.424198 -407.031748)
			(xy 134.424198 -406.977252) (xy 134.431953 -406.92331) (xy 134.447306 -406.871021) (xy 134.469943 -406.821448)
			(xy 134.499405 -406.775602) (xy 134.535091 -406.734415) (xy 134.576275 -406.698725) (xy 134.622118 -406.66926)
			(xy 134.671689 -406.646618) (xy 134.723977 -406.631261) (xy 134.777918 -406.623501) (xy 134.805166 -406.623012)
			(xy 135.668766 -406.623012) (xy 135.696022 -406.623433) (xy 135.749979 -406.631186) (xy 135.802284 -406.64654)
			(xy 135.851871 -406.669182) (xy 135.897731 -406.69865) (xy 135.93893 -406.734346) (xy 135.974629 -406.775542)
			(xy 136.004102 -406.821399) (xy 136.026748 -406.870984) (xy 136.042107 -406.923287) (xy 136.049865 -406.977244)
			(xy 136.049865 -407.031752) (xy 137.487375 -407.031752) (xy 137.487375 -406.977248) (xy 137.495132 -406.9233)
			(xy 137.510488 -406.871004) (xy 137.533129 -406.821426) (xy 137.562596 -406.775575) (xy 137.598289 -406.734384)
			(xy 137.63948 -406.698693) (xy 137.685331 -406.669226) (xy 137.73491 -406.646585) (xy 137.787206 -406.631231)
			(xy 137.841154 -406.623475) (xy 137.868406 -406.623012) (xy 138.732006 -406.623012) (xy 138.759258 -406.623458)
			(xy 138.813208 -406.631216) (xy 138.865505 -406.646572) (xy 138.915084 -406.669215) (xy 138.960936 -406.698683)
			(xy 139.002128 -406.734376) (xy 139.037821 -406.775569) (xy 139.067288 -406.821421) (xy 139.08993 -406.871001)
			(xy 139.105285 -406.923298) (xy 139.113042 -406.977248) (xy 139.113042 -407.031752) (xy 139.113042 -407.031754)
			(xy 140.550575 -407.031754) (xy 140.550575 -406.977246) (xy 140.558333 -406.923294) (xy 140.573691 -406.870996)
			(xy 140.596335 -406.821415) (xy 140.625806 -406.775562) (xy 140.661503 -406.73437) (xy 140.702699 -406.698679)
			(xy 140.748555 -406.669213) (xy 140.798139 -406.646575) (xy 140.850439 -406.631223) (xy 140.904392 -406.623472)
			(xy 140.931646 -406.623012) (xy 141.795246 -406.623012) (xy 141.822497 -406.623461) (xy 141.876442 -406.631223)
			(xy 141.928734 -406.646583) (xy 141.978308 -406.669228) (xy 142.024155 -406.698697) (xy 142.065342 -406.734391)
			(xy 142.10103 -406.775582) (xy 142.130494 -406.821432) (xy 142.153133 -406.871009) (xy 142.168487 -406.923303)
			(xy 142.176242 -406.977249) (xy 142.176242 -407.031749) (xy 143.613898 -407.031749) (xy 143.613898 -406.977251)
			(xy 143.621654 -406.923307) (xy 143.637008 -406.871016) (xy 143.659646 -406.821443) (xy 143.68911 -406.775596)
			(xy 143.724798 -406.734408) (xy 143.765984 -406.698718) (xy 143.81183 -406.669253) (xy 143.861403 -406.646612)
			(xy 143.913694 -406.631257) (xy 143.967637 -406.623499) (xy 143.994886 -406.623012) (xy 144.858486 -406.623012)
			(xy 144.885741 -406.623434) (xy 144.939696 -406.63119) (xy 144.991999 -406.646545) (xy 145.041583 -406.669188)
			(xy 145.087441 -406.698657) (xy 145.128637 -406.734353) (xy 145.164334 -406.775548) (xy 145.193805 -406.821405)
			(xy 145.21645 -406.870988) (xy 145.231807 -406.92329) (xy 145.239565 -406.977245) (xy 145.239565 -407.031753)
			(xy 146.677075 -407.031753) (xy 146.677075 -406.977247) (xy 146.684833 -406.923297) (xy 146.700189 -406.871)
			(xy 146.722832 -406.821421) (xy 146.752301 -406.775569) (xy 146.787996 -406.734377) (xy 146.829189 -406.698686)
			(xy 146.875043 -406.66922) (xy 146.924624 -406.64658) (xy 146.976922 -406.631227) (xy 147.030873 -406.623474)
			(xy 147.058126 -406.623012) (xy 147.921726 -406.623012) (xy 147.948977 -406.62346) (xy 148.002925 -406.63122)
			(xy 148.05522 -406.646578) (xy 148.104796 -406.669222) (xy 148.150646 -406.69869) (xy 148.191835 -406.734383)
			(xy 148.227526 -406.775575) (xy 148.256991 -406.821427) (xy 148.279631 -406.871005) (xy 148.294986 -406.9233)
			(xy 148.302742 -406.977249) (xy 148.302742 -407.031748) (xy 149.740398 -407.031748) (xy 149.740398 -406.977252)
			(xy 149.748153 -406.92331) (xy 149.763506 -406.871021) (xy 149.786143 -406.821448) (xy 149.815605 -406.775602)
			(xy 149.851291 -406.734415) (xy 149.892475 -406.698725) (xy 149.938318 -406.66926) (xy 149.987889 -406.646618)
			(xy 150.040177 -406.631261) (xy 150.094118 -406.623501) (xy 150.121366 -406.623012) (xy 150.984966 -406.623012)
			(xy 151.012222 -406.623433) (xy 151.066179 -406.631186) (xy 151.118484 -406.64654) (xy 151.168071 -406.669182)
			(xy 151.213931 -406.69865) (xy 151.25513 -406.734346) (xy 151.290829 -406.775542) (xy 151.320302 -406.821399)
			(xy 151.342948 -406.870984) (xy 151.358307 -406.923287) (xy 151.366065 -406.977244) (xy 151.366065 -407.031752)
			(xy 152.803575 -407.031752) (xy 152.803575 -406.977248) (xy 152.811332 -406.9233) (xy 152.826688 -406.871004)
			(xy 152.849329 -406.821426) (xy 152.878796 -406.775575) (xy 152.914489 -406.734384) (xy 152.95568 -406.698693)
			(xy 153.001531 -406.669226) (xy 153.05111 -406.646585) (xy 153.103406 -406.631231) (xy 153.157354 -406.623475)
			(xy 153.184606 -406.623012) (xy 154.048206 -406.623012) (xy 154.075458 -406.623458) (xy 154.129408 -406.631216)
			(xy 154.181705 -406.646572) (xy 154.231284 -406.669215) (xy 154.277136 -406.698683) (xy 154.318328 -406.734376)
			(xy 154.354021 -406.775569) (xy 154.383488 -406.821421) (xy 154.40613 -406.871001) (xy 154.421485 -406.923298)
			(xy 154.429242 -406.977248) (xy 154.429242 -407.031752) (xy 154.429242 -407.031754) (xy 155.866775 -407.031754)
			(xy 155.866775 -406.977246) (xy 155.874533 -406.923294) (xy 155.889891 -406.870996) (xy 155.912535 -406.821415)
			(xy 155.942006 -406.775562) (xy 155.977703 -406.73437) (xy 156.018899 -406.698679) (xy 156.064755 -406.669213)
			(xy 156.114339 -406.646575) (xy 156.166639 -406.631223) (xy 156.220592 -406.623472) (xy 156.247846 -406.623012)
			(xy 157.111446 -406.623012) (xy 157.138697 -406.623461) (xy 157.192642 -406.631223) (xy 157.244934 -406.646583)
			(xy 157.294508 -406.669228) (xy 157.340355 -406.698697) (xy 157.381542 -406.734391) (xy 157.41723 -406.775582)
			(xy 157.446694 -406.821432) (xy 157.469333 -406.871009) (xy 157.484687 -406.923303) (xy 157.492442 -406.977249)
			(xy 157.492442 -407.031749) (xy 158.930098 -407.031749) (xy 158.930098 -406.977251) (xy 158.937854 -406.923307)
			(xy 158.953208 -406.871016) (xy 158.975846 -406.821443) (xy 159.00531 -406.775596) (xy 159.040998 -406.734408)
			(xy 159.082184 -406.698718) (xy 159.12803 -406.669253) (xy 159.177603 -406.646612) (xy 159.229894 -406.631257)
			(xy 159.283837 -406.623499) (xy 159.311086 -406.623012) (xy 160.174686 -406.623012) (xy 160.201941 -406.623434)
			(xy 160.255896 -406.63119) (xy 160.308199 -406.646545) (xy 160.357783 -406.669188) (xy 160.403641 -406.698657)
			(xy 160.444837 -406.734353) (xy 160.480534 -406.775548) (xy 160.510005 -406.821405) (xy 160.53265 -406.870988)
			(xy 160.548007 -406.92329) (xy 160.555765 -406.977245) (xy 160.555765 -407.031753) (xy 161.993275 -407.031753)
			(xy 161.993275 -406.977247) (xy 162.001033 -406.923297) (xy 162.016389 -406.871) (xy 162.039032 -406.821421)
			(xy 162.068501 -406.775569) (xy 162.104196 -406.734377) (xy 162.145389 -406.698686) (xy 162.191243 -406.66922)
			(xy 162.240824 -406.64658) (xy 162.293122 -406.631227) (xy 162.347073 -406.623474) (xy 162.374326 -406.623012)
			(xy 163.237926 -406.623012) (xy 163.265177 -406.62346) (xy 163.319125 -406.63122) (xy 163.37142 -406.646578)
			(xy 163.420996 -406.669222) (xy 163.466846 -406.69869) (xy 163.508035 -406.734383) (xy 163.543726 -406.775575)
			(xy 163.573191 -406.821427) (xy 163.595831 -406.871005) (xy 163.611186 -406.9233) (xy 163.618942 -406.977249)
			(xy 163.618942 -407.031751) (xy 163.611186 -407.0857) (xy 163.595831 -407.137995) (xy 163.573191 -407.187573)
			(xy 163.543726 -407.233425) (xy 163.508035 -407.274617) (xy 163.466846 -407.31031) (xy 163.420996 -407.339778)
			(xy 163.37142 -407.362422) (xy 163.319125 -407.37778) (xy 163.265177 -407.38554) (xy 163.237926 -407.386028)
			(xy 162.374326 -407.386028) (xy 162.347073 -407.385526) (xy 162.293122 -407.377773) (xy 162.240824 -407.36242)
			(xy 162.191243 -407.33978) (xy 162.145389 -407.310314) (xy 162.104196 -407.274623) (xy 162.068501 -407.233431)
			(xy 162.039032 -407.187579) (xy 162.016389 -407.138) (xy 162.001033 -407.085703) (xy 161.993275 -407.031753)
			(xy 160.555765 -407.031753) (xy 160.555765 -407.031755) (xy 160.548007 -407.08571) (xy 160.53265 -407.138012)
			(xy 160.510005 -407.187595) (xy 160.480534 -407.233452) (xy 160.444837 -407.274647) (xy 160.403641 -407.310343)
			(xy 160.357783 -407.339812) (xy 160.308199 -407.362455) (xy 160.255896 -407.37781) (xy 160.201941 -407.385566)
			(xy 160.174686 -407.386028) (xy 159.311086 -407.386028) (xy 159.283837 -407.385501) (xy 159.229894 -407.377743)
			(xy 159.177603 -407.362388) (xy 159.12803 -407.339747) (xy 159.082184 -407.310282) (xy 159.040998 -407.274592)
			(xy 159.00531 -407.233404) (xy 158.975846 -407.187557) (xy 158.953208 -407.137984) (xy 158.937854 -407.085693)
			(xy 158.930098 -407.031749) (xy 157.492442 -407.031749) (xy 157.492442 -407.031751) (xy 157.484687 -407.085697)
			(xy 157.469333 -407.137991) (xy 157.446694 -407.187568) (xy 157.41723 -407.233418) (xy 157.381542 -407.274609)
			(xy 157.340355 -407.310303) (xy 157.294508 -407.339772) (xy 157.244934 -407.362417) (xy 157.192642 -407.377777)
			(xy 157.138697 -407.385539) (xy 157.111446 -407.386028) (xy 156.247846 -407.386028) (xy 156.220592 -407.385528)
			(xy 156.166639 -407.377777) (xy 156.114339 -407.362425) (xy 156.064755 -407.339787) (xy 156.018899 -407.310321)
			(xy 155.977703 -407.27463) (xy 155.942006 -407.233438) (xy 155.912535 -407.187585) (xy 155.889891 -407.138004)
			(xy 155.874533 -407.085706) (xy 155.866775 -407.031754) (xy 154.429242 -407.031754) (xy 154.421485 -407.085702)
			(xy 154.40613 -407.137999) (xy 154.383488 -407.187579) (xy 154.354021 -407.233431) (xy 154.318328 -407.274624)
			(xy 154.277136 -407.310317) (xy 154.231284 -407.339785) (xy 154.181705 -407.362428) (xy 154.129408 -407.377784)
			(xy 154.075458 -407.385542) (xy 154.048206 -407.386028) (xy 153.184606 -407.386028) (xy 153.157354 -407.385525)
			(xy 153.103406 -407.377769) (xy 153.05111 -407.362415) (xy 153.001531 -407.339774) (xy 152.95568 -407.310307)
			(xy 152.914489 -407.274616) (xy 152.878796 -407.233425) (xy 152.849329 -407.187574) (xy 152.826688 -407.137996)
			(xy 152.811332 -407.0857) (xy 152.803575 -407.031752) (xy 151.366065 -407.031752) (xy 151.366065 -407.031756)
			(xy 151.358307 -407.085713) (xy 151.342948 -407.138016) (xy 151.320302 -407.187601) (xy 151.290829 -407.233458)
			(xy 151.25513 -407.274654) (xy 151.213931 -407.31035) (xy 151.168071 -407.339818) (xy 151.118484 -407.36246)
			(xy 151.066179 -407.377814) (xy 151.012222 -407.385567) (xy 150.984966 -407.386028) (xy 150.121366 -407.386028)
			(xy 150.094118 -407.385499) (xy 150.040177 -407.377739) (xy 149.987889 -407.362382) (xy 149.938318 -407.33974)
			(xy 149.892475 -407.310275) (xy 149.851291 -407.274585) (xy 149.815605 -407.233398) (xy 149.786143 -407.187552)
			(xy 149.763506 -407.137979) (xy 149.748153 -407.08569) (xy 149.740398 -407.031748) (xy 148.302742 -407.031748)
			(xy 148.302742 -407.031751) (xy 148.294986 -407.0857) (xy 148.279631 -407.137995) (xy 148.256991 -407.187573)
			(xy 148.227526 -407.233425) (xy 148.191835 -407.274617) (xy 148.150646 -407.31031) (xy 148.104796 -407.339778)
			(xy 148.05522 -407.362422) (xy 148.002925 -407.37778) (xy 147.948977 -407.38554) (xy 147.921726 -407.386028)
			(xy 147.058126 -407.386028) (xy 147.030873 -407.385526) (xy 146.976922 -407.377773) (xy 146.924624 -407.36242)
			(xy 146.875043 -407.33978) (xy 146.829189 -407.310314) (xy 146.787996 -407.274623) (xy 146.752301 -407.233431)
			(xy 146.722832 -407.187579) (xy 146.700189 -407.138) (xy 146.684833 -407.085703) (xy 146.677075 -407.031753)
			(xy 145.239565 -407.031753) (xy 145.239565 -407.031755) (xy 145.231807 -407.08571) (xy 145.21645 -407.138012)
			(xy 145.193805 -407.187595) (xy 145.164334 -407.233452) (xy 145.128637 -407.274647) (xy 145.087441 -407.310343)
			(xy 145.041583 -407.339812) (xy 144.991999 -407.362455) (xy 144.939696 -407.37781) (xy 144.885741 -407.385566)
			(xy 144.858486 -407.386028) (xy 143.994886 -407.386028) (xy 143.967637 -407.385501) (xy 143.913694 -407.377743)
			(xy 143.861403 -407.362388) (xy 143.81183 -407.339747) (xy 143.765984 -407.310282) (xy 143.724798 -407.274592)
			(xy 143.68911 -407.233404) (xy 143.659646 -407.187557) (xy 143.637008 -407.137984) (xy 143.621654 -407.085693)
			(xy 143.613898 -407.031749) (xy 142.176242 -407.031749) (xy 142.176242 -407.031751) (xy 142.168487 -407.085697)
			(xy 142.153133 -407.137991) (xy 142.130494 -407.187568) (xy 142.10103 -407.233418) (xy 142.065342 -407.274609)
			(xy 142.024155 -407.310303) (xy 141.978308 -407.339772) (xy 141.928734 -407.362417) (xy 141.876442 -407.377777)
			(xy 141.822497 -407.385539) (xy 141.795246 -407.386028) (xy 140.931646 -407.386028) (xy 140.904392 -407.385528)
			(xy 140.850439 -407.377777) (xy 140.798139 -407.362425) (xy 140.748555 -407.339787) (xy 140.702699 -407.310321)
			(xy 140.661503 -407.27463) (xy 140.625806 -407.233438) (xy 140.596335 -407.187585) (xy 140.573691 -407.138004)
			(xy 140.558333 -407.085706) (xy 140.550575 -407.031754) (xy 139.113042 -407.031754) (xy 139.105285 -407.085702)
			(xy 139.08993 -407.137999) (xy 139.067288 -407.187579) (xy 139.037821 -407.233431) (xy 139.002128 -407.274624)
			(xy 138.960936 -407.310317) (xy 138.915084 -407.339785) (xy 138.865505 -407.362428) (xy 138.813208 -407.377784)
			(xy 138.759258 -407.385542) (xy 138.732006 -407.386028) (xy 137.868406 -407.386028) (xy 137.841154 -407.385525)
			(xy 137.787206 -407.377769) (xy 137.73491 -407.362415) (xy 137.685331 -407.339774) (xy 137.63948 -407.310307)
			(xy 137.598289 -407.274616) (xy 137.562596 -407.233425) (xy 137.533129 -407.187574) (xy 137.510488 -407.137996)
			(xy 137.495132 -407.0857) (xy 137.487375 -407.031752) (xy 136.049865 -407.031752) (xy 136.049865 -407.031756)
			(xy 136.042107 -407.085713) (xy 136.026748 -407.138016) (xy 136.004102 -407.187601) (xy 135.974629 -407.233458)
			(xy 135.93893 -407.274654) (xy 135.897731 -407.31035) (xy 135.851871 -407.339818) (xy 135.802284 -407.36246)
			(xy 135.749979 -407.377814) (xy 135.696022 -407.385567) (xy 135.668766 -407.386028) (xy 134.805166 -407.386028)
			(xy 134.777918 -407.385499) (xy 134.723977 -407.377739) (xy 134.671689 -407.362382) (xy 134.622118 -407.33974)
			(xy 134.576275 -407.310275) (xy 134.535091 -407.274585) (xy 134.499405 -407.233398) (xy 134.469943 -407.187552)
			(xy 134.447306 -407.137979) (xy 134.431953 -407.08569) (xy 134.424198 -407.031748) (xy 132.986542 -407.031748)
			(xy 132.986542 -407.031751) (xy 132.978786 -407.0857) (xy 132.963431 -407.137995) (xy 132.940791 -407.187573)
			(xy 132.911326 -407.233425) (xy 132.875635 -407.274617) (xy 132.834446 -407.31031) (xy 132.788596 -407.339778)
			(xy 132.73902 -407.362422) (xy 132.686725 -407.37778) (xy 132.632777 -407.38554) (xy 132.605526 -407.386028)
			(xy 131.741926 -407.386028) (xy 131.714673 -407.385526) (xy 131.660722 -407.377773) (xy 131.608424 -407.36242)
			(xy 131.558843 -407.33978) (xy 131.512989 -407.310314) (xy 131.471796 -407.274623) (xy 131.436101 -407.233431)
			(xy 131.406632 -407.187579) (xy 131.383989 -407.138) (xy 131.368633 -407.085703) (xy 131.360875 -407.031753)
			(xy 129.923365 -407.031753) (xy 129.923365 -407.031755) (xy 129.915607 -407.08571) (xy 129.90025 -407.138012)
			(xy 129.877605 -407.187595) (xy 129.848134 -407.233452) (xy 129.812437 -407.274647) (xy 129.771241 -407.310343)
			(xy 129.725383 -407.339812) (xy 129.675799 -407.362455) (xy 129.623496 -407.37781) (xy 129.569541 -407.385566)
			(xy 129.542286 -407.386028) (xy 128.678686 -407.386028) (xy 128.651437 -407.385501) (xy 128.597494 -407.377743)
			(xy 128.545203 -407.362388) (xy 128.49563 -407.339747) (xy 128.449784 -407.310282) (xy 128.408598 -407.274592)
			(xy 128.37291 -407.233404) (xy 128.343446 -407.187557) (xy 128.320808 -407.137984) (xy 128.305454 -407.085693)
			(xy 128.297698 -407.031749) (xy 126.860042 -407.031749) (xy 126.860042 -407.031751) (xy 126.852287 -407.085697)
			(xy 126.836933 -407.137991) (xy 126.814294 -407.187568) (xy 126.78483 -407.233418) (xy 126.749142 -407.274609)
			(xy 126.707955 -407.310303) (xy 126.662108 -407.339772) (xy 126.612534 -407.362417) (xy 126.560242 -407.377777)
			(xy 126.506297 -407.385539) (xy 126.479046 -407.386028) (xy 125.615446 -407.386028) (xy 125.588192 -407.385528)
			(xy 125.534239 -407.377777) (xy 125.481939 -407.362425) (xy 125.432355 -407.339787) (xy 125.386499 -407.310321)
			(xy 125.345303 -407.27463) (xy 125.309606 -407.233438) (xy 125.280135 -407.187585) (xy 125.257491 -407.138004)
			(xy 125.242133 -407.085706) (xy 125.234375 -407.031754) (xy 123.796842 -407.031754) (xy 123.789085 -407.085702)
			(xy 123.77373 -407.137999) (xy 123.751088 -407.187579) (xy 123.721621 -407.233431) (xy 123.685928 -407.274624)
			(xy 123.644736 -407.310317) (xy 123.598884 -407.339785) (xy 123.549305 -407.362428) (xy 123.497008 -407.377784)
			(xy 123.443058 -407.385542) (xy 123.415806 -407.386028) (xy 122.552206 -407.386028) (xy 122.524954 -407.385525)
			(xy 122.471006 -407.377769) (xy 122.41871 -407.362415) (xy 122.369131 -407.339774) (xy 122.32328 -407.310307)
			(xy 122.282089 -407.274616) (xy 122.246396 -407.233425) (xy 122.216929 -407.187574) (xy 122.194288 -407.137996)
			(xy 122.178932 -407.0857) (xy 122.171175 -407.031752) (xy 120.733665 -407.031752) (xy 120.733665 -407.031756)
			(xy 120.725907 -407.085713) (xy 120.710548 -407.138016) (xy 120.687902 -407.187601) (xy 120.658429 -407.233458)
			(xy 120.62273 -407.274654) (xy 120.581531 -407.31035) (xy 120.535671 -407.339818) (xy 120.486084 -407.36246)
			(xy 120.433779 -407.377814) (xy 120.379822 -407.385567) (xy 120.352566 -407.386028) (xy 119.488966 -407.386028)
			(xy 119.461718 -407.385499) (xy 119.407777 -407.377739) (xy 119.355489 -407.362382) (xy 119.305918 -407.33974)
			(xy 119.260075 -407.310275) (xy 119.218891 -407.274585) (xy 119.183205 -407.233398) (xy 119.153743 -407.187552)
			(xy 119.131106 -407.137979) (xy 119.115753 -407.08569) (xy 119.107998 -407.031748) (xy 117.670342 -407.031748)
			(xy 117.670342 -407.031751) (xy 117.662586 -407.0857) (xy 117.647231 -407.137995) (xy 117.624591 -407.187573)
			(xy 117.595126 -407.233425) (xy 117.559435 -407.274617) (xy 117.518246 -407.31031) (xy 117.472396 -407.339778)
			(xy 117.42282 -407.362422) (xy 117.370525 -407.37778) (xy 117.316577 -407.38554) (xy 117.289326 -407.386028)
			(xy 116.425726 -407.386028) (xy 116.398473 -407.385526) (xy 116.344522 -407.377773) (xy 116.292224 -407.36242)
			(xy 116.242643 -407.33978) (xy 116.196789 -407.310314) (xy 116.155596 -407.274623) (xy 116.119901 -407.233431)
			(xy 116.090432 -407.187579) (xy 116.067789 -407.138) (xy 116.052433 -407.085703) (xy 116.044675 -407.031753)
			(xy 96.519065 -407.031753) (xy 96.519065 -407.031755) (xy 96.511307 -407.08571) (xy 96.49595 -407.138012)
			(xy 96.473305 -407.187596) (xy 96.443834 -407.233452) (xy 96.408136 -407.274648) (xy 96.36694 -407.310343)
			(xy 96.321082 -407.339812) (xy 96.271497 -407.362455) (xy 96.219195 -407.377811) (xy 96.165239 -407.385566)
			(xy 96.137984 -407.386028) (xy 95.274384 -407.386028) (xy 95.247135 -407.385501) (xy 95.193192 -407.377743)
			(xy 95.140902 -407.362387) (xy 95.091329 -407.339746) (xy 95.045483 -407.310281) (xy 95.004297 -407.274591)
			(xy 94.968609 -407.233404) (xy 94.939146 -407.187557) (xy 94.916507 -407.137983) (xy 94.901154 -407.085692)
			(xy 94.893398 -407.031749) (xy 93.455742 -407.031749) (xy 93.455742 -407.031751) (xy 93.447987 -407.085697)
			(xy 93.432633 -407.137991) (xy 93.409994 -407.187568) (xy 93.38053 -407.233419) (xy 93.344841 -407.27461)
			(xy 93.303654 -407.310304) (xy 93.257807 -407.339773) (xy 93.208233 -407.362417) (xy 93.15594 -407.377777)
			(xy 93.101995 -407.385539) (xy 93.074744 -407.386028) (xy 92.211144 -407.386028) (xy 92.183891 -407.385528)
			(xy 92.129938 -407.377776) (xy 92.077637 -407.362425) (xy 92.028054 -407.339786) (xy 91.982198 -407.310321)
			(xy 91.941002 -407.274629) (xy 91.905306 -407.233437) (xy 91.875835 -407.187584) (xy 91.853191 -407.138004)
			(xy 91.837833 -407.085705) (xy 91.830075 -407.031753) (xy 90.392542 -407.031753) (xy 90.384785 -407.085703)
			(xy 90.36943 -407.138) (xy 90.346788 -407.187579) (xy 90.31732 -407.233432) (xy 90.281627 -407.274624)
			(xy 90.240435 -407.310318) (xy 90.194583 -407.339786) (xy 90.145004 -407.362428) (xy 90.092707 -407.377785)
			(xy 90.038756 -407.385542) (xy 90.011504 -407.386028) (xy 89.147904 -407.386028) (xy 89.120652 -407.385525)
			(xy 89.066704 -407.377769) (xy 89.014408 -407.362414) (xy 88.96483 -407.339773) (xy 88.918979 -407.310307)
			(xy 88.877788 -407.274615) (xy 88.842096 -407.233424) (xy 88.812629 -407.187573) (xy 88.789987 -407.137995)
			(xy 88.774632 -407.0857) (xy 88.766875 -407.031752) (xy 87.329365 -407.031752) (xy 87.329365 -407.031756)
			(xy 87.321607 -407.085713) (xy 87.306248 -407.138016) (xy 87.283602 -407.187602) (xy 87.254129 -407.233459)
			(xy 87.218429 -407.274655) (xy 87.17723 -407.31035) (xy 87.13137 -407.339819) (xy 87.081783 -407.362461)
			(xy 87.029478 -407.377814) (xy 86.97552 -407.385568) (xy 86.948264 -407.386028) (xy 86.084664 -407.386028)
			(xy 86.057416 -407.385499) (xy 86.003475 -407.377739) (xy 85.951187 -407.362382) (xy 85.901617 -407.33974)
			(xy 85.855774 -407.310274) (xy 85.81459 -407.274584) (xy 85.778904 -407.233397) (xy 85.749443 -407.187551)
			(xy 85.726806 -407.137979) (xy 85.711453 -407.08569) (xy 85.703698 -407.031748) (xy 84.266042 -407.031748)
			(xy 84.266042 -407.031752) (xy 84.258286 -407.0857) (xy 84.242931 -407.137996) (xy 84.220291 -407.187574)
			(xy 84.190825 -407.233425) (xy 84.155134 -407.274617) (xy 84.113945 -407.310311) (xy 84.068095 -407.339779)
			(xy 84.018518 -407.362423) (xy 83.966224 -407.377781) (xy 83.912276 -407.385541) (xy 83.885024 -407.386028)
			(xy 83.021424 -407.386028) (xy 82.994171 -407.385526) (xy 82.940221 -407.377773) (xy 82.887923 -407.362419)
			(xy 82.838342 -407.339779) (xy 82.792488 -407.310314) (xy 82.751295 -407.274622) (xy 82.715601 -407.233431)
			(xy 82.686132 -407.187579) (xy 82.663489 -407.138) (xy 82.648133 -407.085703) (xy 82.640375 -407.031753)
			(xy 81.202865 -407.031753) (xy 81.202865 -407.031755) (xy 81.195107 -407.08571) (xy 81.17975 -407.138012)
			(xy 81.157105 -407.187596) (xy 81.127634 -407.233452) (xy 81.091936 -407.274648) (xy 81.05074 -407.310343)
			(xy 81.004882 -407.339812) (xy 80.955297 -407.362455) (xy 80.902995 -407.377811) (xy 80.849039 -407.385566)
			(xy 80.821784 -407.386028) (xy 79.958184 -407.386028) (xy 79.930935 -407.385501) (xy 79.876992 -407.377743)
			(xy 79.824702 -407.362387) (xy 79.775129 -407.339746) (xy 79.729283 -407.310281) (xy 79.688097 -407.274591)
			(xy 79.652409 -407.233404) (xy 79.622946 -407.187557) (xy 79.600307 -407.137983) (xy 79.584954 -407.085692)
			(xy 79.577198 -407.031749) (xy 78.139542 -407.031749) (xy 78.139542 -407.031751) (xy 78.131787 -407.085697)
			(xy 78.116433 -407.137991) (xy 78.093794 -407.187568) (xy 78.06433 -407.233419) (xy 78.028641 -407.27461)
			(xy 77.987454 -407.310304) (xy 77.941607 -407.339773) (xy 77.892033 -407.362417) (xy 77.83974 -407.377777)
			(xy 77.785795 -407.385539) (xy 77.758544 -407.386028) (xy 76.894944 -407.386028) (xy 76.867691 -407.385528)
			(xy 76.813738 -407.377776) (xy 76.761437 -407.362425) (xy 76.711854 -407.339786) (xy 76.665998 -407.310321)
			(xy 76.624802 -407.274629) (xy 76.589106 -407.233437) (xy 76.559635 -407.187584) (xy 76.536991 -407.138004)
			(xy 76.521633 -407.085705) (xy 76.513875 -407.031753) (xy 75.076342 -407.031753) (xy 75.068585 -407.085703)
			(xy 75.05323 -407.138) (xy 75.030588 -407.187579) (xy 75.00112 -407.233432) (xy 74.965427 -407.274624)
			(xy 74.924235 -407.310318) (xy 74.878383 -407.339786) (xy 74.828804 -407.362428) (xy 74.776507 -407.377785)
			(xy 74.722556 -407.385542) (xy 74.695304 -407.386028) (xy 73.831704 -407.386028) (xy 73.804452 -407.385525)
			(xy 73.750504 -407.377769) (xy 73.698208 -407.362414) (xy 73.64863 -407.339773) (xy 73.602779 -407.310307)
			(xy 73.561588 -407.274615) (xy 73.525896 -407.233424) (xy 73.496429 -407.187573) (xy 73.473787 -407.137995)
			(xy 73.458432 -407.0857) (xy 73.450675 -407.031752) (xy 72.013165 -407.031752) (xy 72.013165 -407.031756)
			(xy 72.005407 -407.085713) (xy 71.990048 -407.138016) (xy 71.967402 -407.187602) (xy 71.937929 -407.233459)
			(xy 71.902229 -407.274655) (xy 71.86103 -407.31035) (xy 71.81517 -407.339819) (xy 71.765583 -407.362461)
			(xy 71.713278 -407.377814) (xy 71.65932 -407.385568) (xy 71.632064 -407.386028) (xy 70.768464 -407.386028)
			(xy 70.741216 -407.385499) (xy 70.687275 -407.377739) (xy 70.634987 -407.362382) (xy 70.585417 -407.33974)
			(xy 70.539574 -407.310274) (xy 70.49839 -407.274584) (xy 70.462704 -407.233397) (xy 70.433243 -407.187551)
			(xy 70.410606 -407.137979) (xy 70.395253 -407.08569) (xy 70.387498 -407.031748) (xy 68.949842 -407.031748)
			(xy 68.949842 -407.031752) (xy 68.942086 -407.0857) (xy 68.926731 -407.137996) (xy 68.904091 -407.187574)
			(xy 68.874625 -407.233425) (xy 68.838934 -407.274617) (xy 68.797745 -407.310311) (xy 68.751895 -407.339779)
			(xy 68.702318 -407.362423) (xy 68.650024 -407.377781) (xy 68.596076 -407.385541) (xy 68.568824 -407.386028)
			(xy 67.705224 -407.386028) (xy 67.677971 -407.385526) (xy 67.624021 -407.377773) (xy 67.571723 -407.362419)
			(xy 67.522142 -407.339779) (xy 67.476288 -407.310314) (xy 67.435095 -407.274622) (xy 67.399401 -407.233431)
			(xy 67.369932 -407.187579) (xy 67.347289 -407.138) (xy 67.331933 -407.085703) (xy 67.324175 -407.031753)
			(xy 65.886665 -407.031753) (xy 65.886665 -407.031755) (xy 65.878907 -407.08571) (xy 65.86355 -407.138012)
			(xy 65.840905 -407.187596) (xy 65.811434 -407.233452) (xy 65.775736 -407.274648) (xy 65.73454 -407.310343)
			(xy 65.688682 -407.339812) (xy 65.639097 -407.362455) (xy 65.586795 -407.377811) (xy 65.532839 -407.385566)
			(xy 65.505584 -407.386028) (xy 64.641984 -407.386028) (xy 64.614735 -407.385501) (xy 64.560792 -407.377743)
			(xy 64.508502 -407.362387) (xy 64.458929 -407.339746) (xy 64.413083 -407.310281) (xy 64.371897 -407.274591)
			(xy 64.336209 -407.233404) (xy 64.306746 -407.187557) (xy 64.284107 -407.137983) (xy 64.268754 -407.085692)
			(xy 64.260998 -407.031749) (xy 62.823342 -407.031749) (xy 62.823342 -407.031751) (xy 62.815587 -407.085697)
			(xy 62.800233 -407.137991) (xy 62.777594 -407.187568) (xy 62.74813 -407.233419) (xy 62.712441 -407.27461)
			(xy 62.671254 -407.310304) (xy 62.625407 -407.339773) (xy 62.575833 -407.362417) (xy 62.52354 -407.377777)
			(xy 62.469595 -407.385539) (xy 62.442344 -407.386028) (xy 61.578744 -407.386028) (xy 61.551491 -407.385528)
			(xy 61.497538 -407.377776) (xy 61.445237 -407.362425) (xy 61.395654 -407.339786) (xy 61.349798 -407.310321)
			(xy 61.308602 -407.274629) (xy 61.272906 -407.233437) (xy 61.243435 -407.187584) (xy 61.220791 -407.138004)
			(xy 61.205433 -407.085705) (xy 61.197675 -407.031753) (xy 59.760142 -407.031753) (xy 59.752385 -407.085703)
			(xy 59.73703 -407.138) (xy 59.714388 -407.187579) (xy 59.68492 -407.233432) (xy 59.649227 -407.274624)
			(xy 59.608035 -407.310318) (xy 59.562183 -407.339786) (xy 59.512604 -407.362428) (xy 59.460307 -407.377785)
			(xy 59.406356 -407.385542) (xy 59.379104 -407.386028) (xy 58.515504 -407.386028) (xy 58.488252 -407.385525)
			(xy 58.434304 -407.377769) (xy 58.382008 -407.362414) (xy 58.33243 -407.339773) (xy 58.286579 -407.310307)
			(xy 58.245388 -407.274615) (xy 58.209696 -407.233424) (xy 58.180229 -407.187573) (xy 58.157587 -407.137995)
			(xy 58.142232 -407.0857) (xy 58.134475 -407.031752) (xy 56.696965 -407.031752) (xy 56.696965 -407.031756)
			(xy 56.689207 -407.085713) (xy 56.673848 -407.138016) (xy 56.651202 -407.187602) (xy 56.621729 -407.233459)
			(xy 56.586029 -407.274655) (xy 56.54483 -407.31035) (xy 56.49897 -407.339819) (xy 56.449383 -407.362461)
			(xy 56.397078 -407.377814) (xy 56.34312 -407.385568) (xy 56.315864 -407.386028) (xy 55.452264 -407.386028)
			(xy 55.425016 -407.385499) (xy 55.371075 -407.377739) (xy 55.318787 -407.362382) (xy 55.269217 -407.33974)
			(xy 55.223374 -407.310274) (xy 55.18219 -407.274584) (xy 55.146504 -407.233397) (xy 55.117043 -407.187551)
			(xy 55.094406 -407.137979) (xy 55.079053 -407.08569) (xy 55.071298 -407.031748) (xy 53.633642 -407.031748)
			(xy 53.633642 -407.031752) (xy 53.625886 -407.0857) (xy 53.610531 -407.137996) (xy 53.587891 -407.187574)
			(xy 53.558425 -407.233425) (xy 53.522734 -407.274617) (xy 53.481545 -407.310311) (xy 53.435695 -407.339779)
			(xy 53.386118 -407.362423) (xy 53.333824 -407.377781) (xy 53.279876 -407.385541) (xy 53.252624 -407.386028)
			(xy 52.389024 -407.386028) (xy 52.361771 -407.385526) (xy 52.307821 -407.377773) (xy 52.255523 -407.362419)
			(xy 52.205942 -407.339779) (xy 52.160088 -407.310314) (xy 52.118895 -407.274622) (xy 52.083201 -407.233431)
			(xy 52.053732 -407.187579) (xy 52.031089 -407.138) (xy 52.015733 -407.085703) (xy 52.007975 -407.031753)
			(xy 50.570465 -407.031753) (xy 50.570465 -407.031755) (xy 50.562707 -407.08571) (xy 50.54735 -407.138012)
			(xy 50.524705 -407.187596) (xy 50.495234 -407.233452) (xy 50.459536 -407.274648) (xy 50.41834 -407.310343)
			(xy 50.372482 -407.339812) (xy 50.322897 -407.362455) (xy 50.270595 -407.377811) (xy 50.216639 -407.385566)
			(xy 50.189384 -407.386028) (xy 49.325784 -407.386028) (xy 49.298535 -407.385501) (xy 49.244592 -407.377743)
			(xy 49.192302 -407.362387) (xy 49.142729 -407.339746) (xy 49.096883 -407.310281) (xy 49.055697 -407.274591)
			(xy 49.020009 -407.233404) (xy 48.990546 -407.187557) (xy 48.967907 -407.137983) (xy 48.952554 -407.085692)
			(xy 48.944798 -407.031749) (xy 44.883756 -407.031749) (xy 44.868945 -407.05439) (xy 44.764794 -407.199093)
			(xy 44.654301 -407.339013) (xy 44.537684 -407.473872) (xy 44.415175 -407.603402) (xy 44.287018 -407.727346)
			(xy 44.153467 -407.845458) (xy 44.014787 -407.957503) (xy 43.871253 -408.06326) (xy 43.72315 -408.162517)
			(xy 43.570773 -408.255079) (xy 43.414424 -408.34076) (xy 43.254413 -408.419392) (xy 43.091059 -408.490818)
			(xy 42.924684 -408.554896) (xy 42.755621 -408.611498) (xy 42.584204 -408.660514) (xy 42.410773 -408.701844)
			(xy 42.235673 -408.735408) (xy 42.059253 -408.761138) (xy 41.881861 -408.778984) (xy 41.70385 -408.78891)
			(xy 41.525573 -408.790896) (xy 41.347386 -408.784939) (xy 41.16964 -408.771049) (xy 40.99269 -408.749256)
			(xy 40.816886 -408.719602) (xy 40.642578 -408.682145) (xy 40.470111 -408.636961) (xy 40.299828 -408.584139)
			(xy 40.132067 -408.523783) (xy 39.967162 -408.456015) (xy 39.805439 -408.380967) (xy 39.64722 -408.29879)
			(xy 39.492819 -408.209647) (xy 39.342542 -408.113713) (xy 39.196687 -408.011181) (xy 39.055545 -407.902253)
			(xy 38.919396 -407.787146) (xy 38.788509 -407.666088) (xy 38.663145 -407.539319) (xy 38.543552 -407.407092)
			(xy 38.429969 -407.269669) (xy 38.32262 -407.127322) (xy 38.221719 -406.980334) (xy 38.127466 -406.828998)
			(xy 38.040048 -406.673613) (xy 37.959638 -406.514488) (xy 37.886397 -406.351939) (xy 37.82047 -406.186289)
			(xy 37.761987 -406.017867) (xy 37.711065 -405.847006) (xy 37.667805 -405.674047) (xy 37.632293 -405.499332)
			(xy 37.604599 -405.323208) (xy 37.584778 -405.146026) (xy 37.57287 -404.968137) (xy 37.568898 -404.789894)
			(xy 3.30962 -404.789894) (xy 6.274054 -407.754328) (xy 6.323479 -407.804444) (xy 6.417291 -407.909404)
			(xy 6.50507 -408.019459) (xy 6.58654 -408.134261) (xy 6.661445 -408.253452) (xy 6.72955 -408.376654)
			(xy 6.79064 -408.503481) (xy 6.844523 -408.633534) (xy 6.891029 -408.766403) (xy 6.930013 -408.901671)
			(xy 6.961351 -409.038912) (xy 6.984945 -409.177694) (xy 7.00072 -409.31758) (xy 7.008628 -409.458131)
			(xy 7.00913 -409.528518) (xy 7.00913 -409.563824) (xy 102.192836 -409.563824) (xy 102.192836 -408.700224)
			(xy 102.193322 -408.672955) (xy 102.201084 -408.618971) (xy 102.216449 -408.566641) (xy 102.239106 -408.517031)
			(xy 102.268592 -408.47115) (xy 102.304307 -408.429933) (xy 102.345524 -408.394218) (xy 102.391405 -408.364732)
			(xy 102.441015 -408.342075) (xy 102.493345 -408.32671) (xy 102.547329 -408.318948) (xy 102.601867 -408.318948)
			(xy 102.655851 -408.32671) (xy 102.708181 -408.342075) (xy 102.757791 -408.364732) (xy 102.803672 -408.394218)
			(xy 102.844889 -408.429933) (xy 102.880604 -408.47115) (xy 102.91009 -408.517031) (xy 102.932747 -408.566641)
			(xy 102.948112 -408.618971) (xy 102.955874 -408.672955) (xy 102.95636 -408.700224) (xy 102.95636 -409.563824)
			(xy 102.955874 -409.591093) (xy 102.948112 -409.645077) (xy 102.932747 -409.697407) (xy 102.91009 -409.747017)
			(xy 102.880604 -409.792898) (xy 102.844889 -409.834115) (xy 102.803672 -409.86983) (xy 102.757791 -409.899316)
			(xy 102.748244 -409.903676) (xy 110.559596 -409.903676) (xy 110.559596 -409.040076) (xy 110.560082 -409.012825)
			(xy 110.567838 -408.958877) (xy 110.583193 -408.906582) (xy 110.605835 -408.857005) (xy 110.635301 -408.811155)
			(xy 110.670992 -408.769964) (xy 110.712183 -408.734273) (xy 110.758033 -408.704807) (xy 110.80761 -408.682165)
			(xy 110.859905 -408.66681) (xy 110.913853 -408.659054) (xy 110.968355 -408.659054) (xy 111.022303 -408.66681)
			(xy 111.074598 -408.682165) (xy 111.124175 -408.704807) (xy 111.170025 -408.734273) (xy 111.211216 -408.769964)
			(xy 111.246907 -408.811155) (xy 111.276373 -408.857005) (xy 111.299015 -408.906582) (xy 111.31437 -408.958877)
			(xy 111.322126 -409.012825) (xy 111.322612 -409.040076) (xy 111.322612 -409.903676) (xy 111.322126 -409.930927)
			(xy 111.31437 -409.984875) (xy 111.299015 -410.03717) (xy 111.28975 -410.057456) (xy 116.044623 -410.057456)
			(xy 116.044623 -410.002944) (xy 116.052381 -409.948986) (xy 116.06774 -409.896681) (xy 116.090386 -409.847095)
			(xy 116.119859 -409.801237) (xy 116.155559 -409.76004) (xy 116.196758 -409.724344) (xy 116.242618 -409.694874)
			(xy 116.292206 -409.672231) (xy 116.344511 -409.656876) (xy 116.39847 -409.649121) (xy 116.425726 -409.64866)
			(xy 117.289326 -409.64866) (xy 117.316574 -409.649212) (xy 117.370514 -409.656971) (xy 117.422801 -409.672327)
			(xy 117.472371 -409.694968) (xy 117.518214 -409.724432) (xy 117.559398 -409.760121) (xy 117.595084 -409.801307)
			(xy 117.624545 -409.847152) (xy 117.647182 -409.896723) (xy 117.662535 -409.949011) (xy 117.67029 -410.002952)
			(xy 117.67029 -410.057448) (xy 117.670289 -410.057452) (xy 119.107946 -410.057452) (xy 119.107946 -410.002948)
			(xy 119.115702 -409.948999) (xy 119.131057 -409.896702) (xy 119.153697 -409.847123) (xy 119.183163 -409.801271)
			(xy 119.218854 -409.760078) (xy 119.260043 -409.724383) (xy 119.305893 -409.694914) (xy 119.35547 -409.672269)
			(xy 119.407765 -409.656909) (xy 119.461714 -409.649148) (xy 119.488966 -409.64866) (xy 120.352566 -409.64866)
			(xy 120.379818 -409.649185) (xy 120.433768 -409.656937) (xy 120.486066 -409.672289) (xy 120.535646 -409.694928)
			(xy 120.5815 -409.724392) (xy 120.622693 -409.760083) (xy 120.658387 -409.801273) (xy 120.687856 -409.847124)
			(xy 120.710499 -409.896702) (xy 120.725855 -409.948999) (xy 120.733613 -410.002948) (xy 120.733613 -410.057452)
			(xy 120.733613 -410.057455) (xy 122.171123 -410.057455) (xy 122.171123 -410.002945) (xy 122.178881 -409.948989)
			(xy 122.194238 -409.896686) (xy 122.216883 -409.847101) (xy 122.246354 -409.801244) (xy 122.282052 -409.760047)
			(xy 122.323249 -409.724351) (xy 122.369106 -409.69488) (xy 122.418691 -409.672236) (xy 122.470994 -409.656879)
			(xy 122.524951 -409.649123) (xy 122.552206 -409.64866) (xy 123.415806 -409.64866) (xy 123.443055 -409.649211)
			(xy 123.496997 -409.656967) (xy 123.549287 -409.672321) (xy 123.598859 -409.694961) (xy 123.644705 -409.724425)
			(xy 123.685891 -409.760113) (xy 123.721579 -409.8013) (xy 123.751042 -409.847146) (xy 123.773681 -409.896719)
			(xy 123.789034 -409.949009) (xy 123.79679 -410.002951) (xy 123.79679 -410.057449) (xy 123.796789 -410.057457)
			(xy 125.234323 -410.057457) (xy 125.234323 -410.002943) (xy 125.242082 -409.948983) (xy 125.257442 -409.896677)
			(xy 125.280089 -409.84709) (xy 125.309564 -409.801231) (xy 125.345266 -409.760033) (xy 125.386467 -409.724337)
			(xy 125.43233 -409.694867) (xy 125.48192 -409.672225) (xy 125.534228 -409.656872) (xy 125.588189 -409.64912)
			(xy 125.615446 -409.64866) (xy 126.479046 -409.64866) (xy 126.506293 -409.649213) (xy 126.560231 -409.656975)
			(xy 126.612516 -409.672332) (xy 126.662083 -409.694974) (xy 126.707924 -409.724439) (xy 126.749105 -409.760128)
			(xy 126.784788 -409.801313) (xy 126.814248 -409.847157) (xy 126.836884 -409.896727) (xy 126.852235 -409.949014)
			(xy 126.85999 -410.002953) (xy 126.85999 -410.057447) (xy 126.859989 -410.057453) (xy 128.297646 -410.057453)
			(xy 128.297646 -410.002947) (xy 128.305403 -409.948996) (xy 128.320758 -409.896698) (xy 128.3434 -409.847118)
			(xy 128.372868 -409.801264) (xy 128.408561 -409.760071) (xy 128.449753 -409.724376) (xy 128.495605 -409.694907)
			(xy 128.545185 -409.672263) (xy 128.597482 -409.656906) (xy 128.651433 -409.649147) (xy 128.678686 -409.64866)
			(xy 129.542286 -409.64866) (xy 129.569537 -409.649186) (xy 129.623485 -409.656941) (xy 129.67578 -409.672295)
			(xy 129.725358 -409.694934) (xy 129.771209 -409.724399) (xy 129.8124 -409.76009) (xy 129.848092 -409.80128)
			(xy 129.877559 -409.84713) (xy 129.900201 -409.896707) (xy 129.915556 -409.949001) (xy 129.923313 -410.002949)
			(xy 129.923313 -410.057451) (xy 129.923312 -410.057456) (xy 131.360823 -410.057456) (xy 131.360823 -410.002944)
			(xy 131.368581 -409.948986) (xy 131.38394 -409.896681) (xy 131.406586 -409.847095) (xy 131.436059 -409.801237)
			(xy 131.471759 -409.76004) (xy 131.512958 -409.724344) (xy 131.558818 -409.694874) (xy 131.608406 -409.672231)
			(xy 131.660711 -409.656876) (xy 131.71467 -409.649121) (xy 131.741926 -409.64866) (xy 132.605526 -409.64866)
			(xy 132.632774 -409.649212) (xy 132.686714 -409.656971) (xy 132.739001 -409.672327) (xy 132.788571 -409.694968)
			(xy 132.834414 -409.724432) (xy 132.875598 -409.760121) (xy 132.911284 -409.801307) (xy 132.940745 -409.847152)
			(xy 132.963382 -409.896723) (xy 132.978735 -409.949011) (xy 132.98649 -410.002952) (xy 132.98649 -410.057448)
			(xy 132.986489 -410.057452) (xy 134.424146 -410.057452) (xy 134.424146 -410.002948) (xy 134.431902 -409.948999)
			(xy 134.447257 -409.896702) (xy 134.469897 -409.847123) (xy 134.499363 -409.801271) (xy 134.535054 -409.760078)
			(xy 134.576243 -409.724383) (xy 134.622093 -409.694914) (xy 134.67167 -409.672269) (xy 134.723965 -409.656909)
			(xy 134.777914 -409.649148) (xy 134.805166 -409.64866) (xy 135.668766 -409.64866) (xy 135.696018 -409.649185)
			(xy 135.749968 -409.656937) (xy 135.802266 -409.672289) (xy 135.851846 -409.694928) (xy 135.8977 -409.724392)
			(xy 135.938893 -409.760083) (xy 135.974587 -409.801273) (xy 136.004056 -409.847124) (xy 136.026699 -409.896702)
			(xy 136.042055 -409.948999) (xy 136.049813 -410.002948) (xy 136.049813 -410.057452) (xy 136.049813 -410.057455)
			(xy 137.487323 -410.057455) (xy 137.487323 -410.002945) (xy 137.495081 -409.948989) (xy 137.510438 -409.896686)
			(xy 137.533083 -409.847101) (xy 137.562554 -409.801244) (xy 137.598252 -409.760047) (xy 137.639449 -409.724351)
			(xy 137.685306 -409.69488) (xy 137.734891 -409.672236) (xy 137.787194 -409.656879) (xy 137.841151 -409.649123)
			(xy 137.868406 -409.64866) (xy 138.732006 -409.64866) (xy 138.759255 -409.649211) (xy 138.813197 -409.656967)
			(xy 138.865487 -409.672321) (xy 138.915059 -409.694961) (xy 138.960905 -409.724425) (xy 139.002091 -409.760113)
			(xy 139.037779 -409.8013) (xy 139.067242 -409.847146) (xy 139.089881 -409.896719) (xy 139.105234 -409.949009)
			(xy 139.11299 -410.002951) (xy 139.11299 -410.057449) (xy 139.112989 -410.057457) (xy 140.550523 -410.057457)
			(xy 140.550523 -410.002943) (xy 140.558282 -409.948983) (xy 140.573642 -409.896677) (xy 140.596289 -409.84709)
			(xy 140.625764 -409.801231) (xy 140.661466 -409.760033) (xy 140.702667 -409.724337) (xy 140.74853 -409.694867)
			(xy 140.79812 -409.672225) (xy 140.850428 -409.656872) (xy 140.904389 -409.64912) (xy 140.931646 -409.64866)
			(xy 141.795246 -409.64866) (xy 141.822493 -409.649213) (xy 141.876431 -409.656975) (xy 141.928716 -409.672332)
			(xy 141.978283 -409.694974) (xy 142.024124 -409.724439) (xy 142.065305 -409.760128) (xy 142.100988 -409.801313)
			(xy 142.130448 -409.847157) (xy 142.153084 -409.896727) (xy 142.168435 -409.949014) (xy 142.17619 -410.002953)
			(xy 142.17619 -410.057447) (xy 142.176189 -410.057453) (xy 143.613846 -410.057453) (xy 143.613846 -410.002947)
			(xy 143.621603 -409.948996) (xy 143.636958 -409.896698) (xy 143.6596 -409.847118) (xy 143.689068 -409.801264)
			(xy 143.724761 -409.760071) (xy 143.765953 -409.724376) (xy 143.811805 -409.694907) (xy 143.861385 -409.672263)
			(xy 143.913682 -409.656906) (xy 143.967633 -409.649147) (xy 143.994886 -409.64866) (xy 144.858486 -409.64866)
			(xy 144.885737 -409.649186) (xy 144.939685 -409.656941) (xy 144.99198 -409.672295) (xy 145.041558 -409.694934)
			(xy 145.087409 -409.724399) (xy 145.1286 -409.76009) (xy 145.164292 -409.80128) (xy 145.193759 -409.84713)
			(xy 145.216401 -409.896707) (xy 145.231756 -409.949001) (xy 145.239513 -410.002949) (xy 145.239513 -410.057451)
			(xy 145.239512 -410.057456) (xy 146.677023 -410.057456) (xy 146.677023 -410.002944) (xy 146.684781 -409.948986)
			(xy 146.70014 -409.896681) (xy 146.722786 -409.847095) (xy 146.752259 -409.801237) (xy 146.787959 -409.76004)
			(xy 146.829158 -409.724344) (xy 146.875018 -409.694874) (xy 146.924606 -409.672231) (xy 146.976911 -409.656876)
			(xy 147.03087 -409.649121) (xy 147.058126 -409.64866) (xy 147.921726 -409.64866) (xy 147.948974 -409.649212)
			(xy 148.002914 -409.656971) (xy 148.055201 -409.672327) (xy 148.104771 -409.694968) (xy 148.150614 -409.724432)
			(xy 148.191798 -409.760121) (xy 148.227484 -409.801307) (xy 148.256945 -409.847152) (xy 148.279582 -409.896723)
			(xy 148.294935 -409.949011) (xy 148.30269 -410.002952) (xy 148.30269 -410.057448) (xy 148.302689 -410.057452)
			(xy 149.740346 -410.057452) (xy 149.740346 -410.002948) (xy 149.748102 -409.948999) (xy 149.763457 -409.896702)
			(xy 149.786097 -409.847123) (xy 149.815563 -409.801271) (xy 149.851254 -409.760078) (xy 149.892443 -409.724383)
			(xy 149.938293 -409.694914) (xy 149.98787 -409.672269) (xy 150.040165 -409.656909) (xy 150.094114 -409.649148)
			(xy 150.121366 -409.64866) (xy 150.984966 -409.64866) (xy 151.012218 -409.649185) (xy 151.066168 -409.656937)
			(xy 151.118466 -409.672289) (xy 151.168046 -409.694928) (xy 151.2139 -409.724392) (xy 151.255093 -409.760083)
			(xy 151.290787 -409.801273) (xy 151.320256 -409.847124) (xy 151.342899 -409.896702) (xy 151.358255 -409.948999)
			(xy 151.366013 -410.002948) (xy 151.366013 -410.057452) (xy 151.366013 -410.057455) (xy 152.803523 -410.057455)
			(xy 152.803523 -410.002945) (xy 152.811281 -409.948989) (xy 152.826638 -409.896686) (xy 152.849283 -409.847101)
			(xy 152.878754 -409.801244) (xy 152.914452 -409.760047) (xy 152.955649 -409.724351) (xy 153.001506 -409.69488)
			(xy 153.051091 -409.672236) (xy 153.103394 -409.656879) (xy 153.157351 -409.649123) (xy 153.184606 -409.64866)
			(xy 154.048206 -409.64866) (xy 154.075455 -409.649211) (xy 154.129397 -409.656967) (xy 154.181687 -409.672321)
			(xy 154.231259 -409.694961) (xy 154.277105 -409.724425) (xy 154.318291 -409.760113) (xy 154.353979 -409.8013)
			(xy 154.383442 -409.847146) (xy 154.406081 -409.896719) (xy 154.421434 -409.949009) (xy 154.42919 -410.002951)
			(xy 154.42919 -410.057449) (xy 154.429189 -410.057457) (xy 155.866723 -410.057457) (xy 155.866723 -410.002943)
			(xy 155.874482 -409.948983) (xy 155.889842 -409.896677) (xy 155.912489 -409.84709) (xy 155.941964 -409.801231)
			(xy 155.977666 -409.760033) (xy 156.018867 -409.724337) (xy 156.06473 -409.694867) (xy 156.11432 -409.672225)
			(xy 156.166628 -409.656872) (xy 156.220589 -409.64912) (xy 156.247846 -409.64866) (xy 157.111446 -409.64866)
			(xy 157.138693 -409.649213) (xy 157.192631 -409.656975) (xy 157.244916 -409.672332) (xy 157.294483 -409.694974)
			(xy 157.340324 -409.724439) (xy 157.381505 -409.760128) (xy 157.417188 -409.801313) (xy 157.446648 -409.847157)
			(xy 157.469284 -409.896727) (xy 157.484635 -409.949014) (xy 157.49239 -410.002953) (xy 157.49239 -410.057447)
			(xy 157.492389 -410.057453) (xy 158.930046 -410.057453) (xy 158.930046 -410.002947) (xy 158.937803 -409.948996)
			(xy 158.953158 -409.896698) (xy 158.9758 -409.847118) (xy 159.005268 -409.801264) (xy 159.040961 -409.760071)
			(xy 159.082153 -409.724376) (xy 159.128005 -409.694907) (xy 159.177585 -409.672263) (xy 159.229882 -409.656906)
			(xy 159.283833 -409.649147) (xy 159.311086 -409.64866) (xy 160.174686 -409.64866) (xy 160.201937 -409.649186)
			(xy 160.255885 -409.656941) (xy 160.30818 -409.672295) (xy 160.357758 -409.694934) (xy 160.403609 -409.724399)
			(xy 160.4448 -409.76009) (xy 160.480492 -409.80128) (xy 160.509959 -409.84713) (xy 160.532601 -409.896707)
			(xy 160.547956 -409.949001) (xy 160.555713 -410.002949) (xy 160.555713 -410.057451) (xy 160.555712 -410.057456)
			(xy 161.993223 -410.057456) (xy 161.993223 -410.002944) (xy 162.000981 -409.948986) (xy 162.01634 -409.896681)
			(xy 162.038986 -409.847095) (xy 162.068459 -409.801237) (xy 162.104159 -409.76004) (xy 162.145358 -409.724344)
			(xy 162.191218 -409.694874) (xy 162.240806 -409.672231) (xy 162.293111 -409.656876) (xy 162.34707 -409.649121)
			(xy 162.374326 -409.64866) (xy 163.237926 -409.64866) (xy 163.265174 -409.649212) (xy 163.319114 -409.656971)
			(xy 163.371401 -409.672327) (xy 163.420971 -409.694968) (xy 163.466814 -409.724432) (xy 163.507998 -409.760121)
			(xy 163.543684 -409.801307) (xy 163.573145 -409.847152) (xy 163.595782 -409.896723) (xy 163.611135 -409.949011)
			(xy 163.61889 -410.002952) (xy 163.61889 -410.057448) (xy 163.611135 -410.111389) (xy 163.595782 -410.163677)
			(xy 163.573145 -410.213248) (xy 163.543684 -410.259093) (xy 163.507998 -410.300279) (xy 163.466814 -410.335968)
			(xy 163.420971 -410.365432) (xy 163.371401 -410.388073) (xy 163.319114 -410.403429) (xy 163.265174 -410.411188)
			(xy 163.237926 -410.411676) (xy 162.374326 -410.411676) (xy 162.34707 -410.411279) (xy 162.293111 -410.403524)
			(xy 162.240806 -410.388169) (xy 162.191218 -410.365526) (xy 162.145358 -410.336056) (xy 162.104159 -410.30036)
			(xy 162.068459 -410.259163) (xy 162.038986 -410.213305) (xy 162.01634 -410.163719) (xy 162.000981 -410.111414)
			(xy 161.993223 -410.057456) (xy 160.555712 -410.057456) (xy 160.547956 -410.111399) (xy 160.532601 -410.163693)
			(xy 160.509959 -410.21327) (xy 160.480492 -410.25912) (xy 160.4448 -410.30031) (xy 160.403609 -410.336001)
			(xy 160.357758 -410.365466) (xy 160.30818 -410.388105) (xy 160.255885 -410.403459) (xy 160.201937 -410.411214)
			(xy 160.174686 -410.411676) (xy 159.311086 -410.411676) (xy 159.283833 -410.411253) (xy 159.229882 -410.403494)
			(xy 159.177585 -410.388137) (xy 159.128005 -410.365493) (xy 159.082153 -410.336024) (xy 159.040961 -410.300329)
			(xy 159.005268 -410.259136) (xy 158.9758 -410.213282) (xy 158.953158 -410.163702) (xy 158.937803 -410.111404)
			(xy 158.930046 -410.057453) (xy 157.492389 -410.057453) (xy 157.484635 -410.111386) (xy 157.469284 -410.163673)
			(xy 157.446648 -410.213243) (xy 157.417188 -410.259087) (xy 157.381505 -410.300272) (xy 157.340324 -410.335961)
			(xy 157.294483 -410.365426) (xy 157.244916 -410.388068) (xy 157.192631 -410.403425) (xy 157.138693 -410.411187)
			(xy 157.111446 -410.411676) (xy 156.247846 -410.411676) (xy 156.220589 -410.41128) (xy 156.166628 -410.403528)
			(xy 156.11432 -410.388175) (xy 156.06473 -410.365533) (xy 156.018867 -410.336063) (xy 155.977666 -410.300367)
			(xy 155.941964 -410.259169) (xy 155.912489 -410.21331) (xy 155.889842 -410.163723) (xy 155.874482 -410.111417)
			(xy 155.866723 -410.057457) (xy 154.429189 -410.057457) (xy 154.421434 -410.111391) (xy 154.406081 -410.163681)
			(xy 154.383442 -410.213254) (xy 154.353979 -410.2591) (xy 154.318291 -410.300287) (xy 154.277105 -410.335975)
			(xy 154.231259 -410.365439) (xy 154.181687 -410.388079) (xy 154.129397 -410.403433) (xy 154.075455 -410.411189)
			(xy 154.048206 -410.411676) (xy 153.184606 -410.411676) (xy 153.157351 -410.411277) (xy 153.103394 -410.403521)
			(xy 153.051091 -410.388164) (xy 153.001506 -410.36552) (xy 152.955649 -410.336049) (xy 152.914452 -410.300353)
			(xy 152.878754 -410.259156) (xy 152.849283 -410.213299) (xy 152.826638 -410.163714) (xy 152.811281 -410.111411)
			(xy 152.803523 -410.057455) (xy 151.366013 -410.057455) (xy 151.358255 -410.111402) (xy 151.342899 -410.163698)
			(xy 151.320256 -410.213276) (xy 151.290787 -410.259127) (xy 151.255093 -410.300317) (xy 151.2139 -410.336008)
			(xy 151.168046 -410.365472) (xy 151.118466 -410.388111) (xy 151.066168 -410.403463) (xy 151.012218 -410.411215)
			(xy 150.984966 -410.411676) (xy 150.121366 -410.411676) (xy 150.094114 -410.411252) (xy 150.040165 -410.403491)
			(xy 149.98787 -410.388131) (xy 149.938293 -410.365486) (xy 149.892443 -410.336017) (xy 149.851254 -410.300322)
			(xy 149.815563 -410.259129) (xy 149.786097 -410.213277) (xy 149.763457 -410.163698) (xy 149.748102 -410.111401)
			(xy 149.740346 -410.057452) (xy 148.302689 -410.057452) (xy 148.294935 -410.111389) (xy 148.279582 -410.163677)
			(xy 148.256945 -410.213248) (xy 148.227484 -410.259093) (xy 148.191798 -410.300279) (xy 148.150614 -410.335968)
			(xy 148.104771 -410.365432) (xy 148.055201 -410.388073) (xy 148.002914 -410.403429) (xy 147.948974 -410.411188)
			(xy 147.921726 -410.411676) (xy 147.058126 -410.411676) (xy 147.03087 -410.411279) (xy 146.976911 -410.403524)
			(xy 146.924606 -410.388169) (xy 146.875018 -410.365526) (xy 146.829158 -410.336056) (xy 146.787959 -410.30036)
			(xy 146.752259 -410.259163) (xy 146.722786 -410.213305) (xy 146.70014 -410.163719) (xy 146.684781 -410.111414)
			(xy 146.677023 -410.057456) (xy 145.239512 -410.057456) (xy 145.231756 -410.111399) (xy 145.216401 -410.163693)
			(xy 145.193759 -410.21327) (xy 145.164292 -410.25912) (xy 145.1286 -410.30031) (xy 145.087409 -410.336001)
			(xy 145.041558 -410.365466) (xy 144.99198 -410.388105) (xy 144.939685 -410.403459) (xy 144.885737 -410.411214)
			(xy 144.858486 -410.411676) (xy 143.994886 -410.411676) (xy 143.967633 -410.411253) (xy 143.913682 -410.403494)
			(xy 143.861385 -410.388137) (xy 143.811805 -410.365493) (xy 143.765953 -410.336024) (xy 143.724761 -410.300329)
			(xy 143.689068 -410.259136) (xy 143.6596 -410.213282) (xy 143.636958 -410.163702) (xy 143.621603 -410.111404)
			(xy 143.613846 -410.057453) (xy 142.176189 -410.057453) (xy 142.168435 -410.111386) (xy 142.153084 -410.163673)
			(xy 142.130448 -410.213243) (xy 142.100988 -410.259087) (xy 142.065305 -410.300272) (xy 142.024124 -410.335961)
			(xy 141.978283 -410.365426) (xy 141.928716 -410.388068) (xy 141.876431 -410.403425) (xy 141.822493 -410.411187)
			(xy 141.795246 -410.411676) (xy 140.931646 -410.411676) (xy 140.904389 -410.41128) (xy 140.850428 -410.403528)
			(xy 140.79812 -410.388175) (xy 140.74853 -410.365533) (xy 140.702667 -410.336063) (xy 140.661466 -410.300367)
			(xy 140.625764 -410.259169) (xy 140.596289 -410.21331) (xy 140.573642 -410.163723) (xy 140.558282 -410.111417)
			(xy 140.550523 -410.057457) (xy 139.112989 -410.057457) (xy 139.105234 -410.111391) (xy 139.089881 -410.163681)
			(xy 139.067242 -410.213254) (xy 139.037779 -410.2591) (xy 139.002091 -410.300287) (xy 138.960905 -410.335975)
			(xy 138.915059 -410.365439) (xy 138.865487 -410.388079) (xy 138.813197 -410.403433) (xy 138.759255 -410.411189)
			(xy 138.732006 -410.411676) (xy 137.868406 -410.411676) (xy 137.841151 -410.411277) (xy 137.787194 -410.403521)
			(xy 137.734891 -410.388164) (xy 137.685306 -410.36552) (xy 137.639449 -410.336049) (xy 137.598252 -410.300353)
			(xy 137.562554 -410.259156) (xy 137.533083 -410.213299) (xy 137.510438 -410.163714) (xy 137.495081 -410.111411)
			(xy 137.487323 -410.057455) (xy 136.049813 -410.057455) (xy 136.042055 -410.111402) (xy 136.026699 -410.163698)
			(xy 136.004056 -410.213276) (xy 135.974587 -410.259127) (xy 135.938893 -410.300317) (xy 135.8977 -410.336008)
			(xy 135.851846 -410.365472) (xy 135.802266 -410.388111) (xy 135.749968 -410.403463) (xy 135.696018 -410.411215)
			(xy 135.668766 -410.411676) (xy 134.805166 -410.411676) (xy 134.777914 -410.411252) (xy 134.723965 -410.403491)
			(xy 134.67167 -410.388131) (xy 134.622093 -410.365486) (xy 134.576243 -410.336017) (xy 134.535054 -410.300322)
			(xy 134.499363 -410.259129) (xy 134.469897 -410.213277) (xy 134.447257 -410.163698) (xy 134.431902 -410.111401)
			(xy 134.424146 -410.057452) (xy 132.986489 -410.057452) (xy 132.978735 -410.111389) (xy 132.963382 -410.163677)
			(xy 132.940745 -410.213248) (xy 132.911284 -410.259093) (xy 132.875598 -410.300279) (xy 132.834414 -410.335968)
			(xy 132.788571 -410.365432) (xy 132.739001 -410.388073) (xy 132.686714 -410.403429) (xy 132.632774 -410.411188)
			(xy 132.605526 -410.411676) (xy 131.741926 -410.411676) (xy 131.71467 -410.411279) (xy 131.660711 -410.403524)
			(xy 131.608406 -410.388169) (xy 131.558818 -410.365526) (xy 131.512958 -410.336056) (xy 131.471759 -410.30036)
			(xy 131.436059 -410.259163) (xy 131.406586 -410.213305) (xy 131.38394 -410.163719) (xy 131.368581 -410.111414)
			(xy 131.360823 -410.057456) (xy 129.923312 -410.057456) (xy 129.915556 -410.111399) (xy 129.900201 -410.163693)
			(xy 129.877559 -410.21327) (xy 129.848092 -410.25912) (xy 129.8124 -410.30031) (xy 129.771209 -410.336001)
			(xy 129.725358 -410.365466) (xy 129.67578 -410.388105) (xy 129.623485 -410.403459) (xy 129.569537 -410.411214)
			(xy 129.542286 -410.411676) (xy 128.678686 -410.411676) (xy 128.651433 -410.411253) (xy 128.597482 -410.403494)
			(xy 128.545185 -410.388137) (xy 128.495605 -410.365493) (xy 128.449753 -410.336024) (xy 128.408561 -410.300329)
			(xy 128.372868 -410.259136) (xy 128.3434 -410.213282) (xy 128.320758 -410.163702) (xy 128.305403 -410.111404)
			(xy 128.297646 -410.057453) (xy 126.859989 -410.057453) (xy 126.852235 -410.111386) (xy 126.836884 -410.163673)
			(xy 126.814248 -410.213243) (xy 126.784788 -410.259087) (xy 126.749105 -410.300272) (xy 126.707924 -410.335961)
			(xy 126.662083 -410.365426) (xy 126.612516 -410.388068) (xy 126.560231 -410.403425) (xy 126.506293 -410.411187)
			(xy 126.479046 -410.411676) (xy 125.615446 -410.411676) (xy 125.588189 -410.41128) (xy 125.534228 -410.403528)
			(xy 125.48192 -410.388175) (xy 125.43233 -410.365533) (xy 125.386467 -410.336063) (xy 125.345266 -410.300367)
			(xy 125.309564 -410.259169) (xy 125.280089 -410.21331) (xy 125.257442 -410.163723) (xy 125.242082 -410.111417)
			(xy 125.234323 -410.057457) (xy 123.796789 -410.057457) (xy 123.789034 -410.111391) (xy 123.773681 -410.163681)
			(xy 123.751042 -410.213254) (xy 123.721579 -410.2591) (xy 123.685891 -410.300287) (xy 123.644705 -410.335975)
			(xy 123.598859 -410.365439) (xy 123.549287 -410.388079) (xy 123.496997 -410.403433) (xy 123.443055 -410.411189)
			(xy 123.415806 -410.411676) (xy 122.552206 -410.411676) (xy 122.524951 -410.411277) (xy 122.470994 -410.403521)
			(xy 122.418691 -410.388164) (xy 122.369106 -410.36552) (xy 122.323249 -410.336049) (xy 122.282052 -410.300353)
			(xy 122.246354 -410.259156) (xy 122.216883 -410.213299) (xy 122.194238 -410.163714) (xy 122.178881 -410.111411)
			(xy 122.171123 -410.057455) (xy 120.733613 -410.057455) (xy 120.725855 -410.111402) (xy 120.710499 -410.163698)
			(xy 120.687856 -410.213276) (xy 120.658387 -410.259127) (xy 120.622693 -410.300317) (xy 120.5815 -410.336008)
			(xy 120.535646 -410.365472) (xy 120.486066 -410.388111) (xy 120.433768 -410.403463) (xy 120.379818 -410.411215)
			(xy 120.352566 -410.411676) (xy 119.488966 -410.411676) (xy 119.461714 -410.411252) (xy 119.407765 -410.403491)
			(xy 119.35547 -410.388131) (xy 119.305893 -410.365486) (xy 119.260043 -410.336017) (xy 119.218854 -410.300322)
			(xy 119.183163 -410.259129) (xy 119.153697 -410.213277) (xy 119.131057 -410.163698) (xy 119.115702 -410.111401)
			(xy 119.107946 -410.057452) (xy 117.670289 -410.057452) (xy 117.662535 -410.111389) (xy 117.647182 -410.163677)
			(xy 117.624545 -410.213248) (xy 117.595084 -410.259093) (xy 117.559398 -410.300279) (xy 117.518214 -410.335968)
			(xy 117.472371 -410.365432) (xy 117.422801 -410.388073) (xy 117.370514 -410.403429) (xy 117.316574 -410.411188)
			(xy 117.289326 -410.411676) (xy 116.425726 -410.411676) (xy 116.39847 -410.411279) (xy 116.344511 -410.403524)
			(xy 116.292206 -410.388169) (xy 116.242618 -410.365526) (xy 116.196758 -410.336056) (xy 116.155559 -410.30036)
			(xy 116.119859 -410.259163) (xy 116.090386 -410.213305) (xy 116.06774 -410.163719) (xy 116.052381 -410.111414)
			(xy 116.044623 -410.057456) (xy 111.28975 -410.057456) (xy 111.276373 -410.086747) (xy 111.246907 -410.132597)
			(xy 111.211216 -410.173788) (xy 111.170025 -410.209479) (xy 111.124175 -410.238945) (xy 111.074598 -410.261587)
			(xy 111.022303 -410.276942) (xy 110.968355 -410.284698) (xy 110.913853 -410.284698) (xy 110.859905 -410.276942)
			(xy 110.80761 -410.261587) (xy 110.758033 -410.238945) (xy 110.712183 -410.209479) (xy 110.670992 -410.173788)
			(xy 110.635301 -410.132597) (xy 110.605835 -410.086747) (xy 110.583193 -410.03717) (xy 110.567838 -409.984875)
			(xy 110.560082 -409.930927) (xy 110.559596 -409.903676) (xy 102.748244 -409.903676) (xy 102.708181 -409.921973)
			(xy 102.655851 -409.937338) (xy 102.601867 -409.9451) (xy 102.547329 -409.9451) (xy 102.493345 -409.937338)
			(xy 102.441015 -409.921973) (xy 102.391405 -409.899316) (xy 102.345524 -409.86983) (xy 102.304307 -409.834115)
			(xy 102.268592 -409.792898) (xy 102.239106 -409.747017) (xy 102.216449 -409.697407) (xy 102.201084 -409.645077)
			(xy 102.193322 -409.591093) (xy 102.192836 -409.563824) (xy 7.00913 -409.563824) (xy 7.00913 -410.057453)
			(xy 48.944746 -410.057453) (xy 48.944746 -410.002947) (xy 48.952503 -409.948996) (xy 48.967858 -409.896698)
			(xy 48.9905 -409.847118) (xy 49.019967 -409.801265) (xy 49.05566 -409.760071) (xy 49.096852 -409.724377)
			(xy 49.142704 -409.694908) (xy 49.192283 -409.672264) (xy 49.244581 -409.656906) (xy 49.298531 -409.649147)
			(xy 49.325784 -409.64866) (xy 50.189384 -409.64866) (xy 50.216635 -409.649186) (xy 50.270583 -409.656941)
			(xy 50.322879 -409.672294) (xy 50.372457 -409.694934) (xy 50.418308 -409.724399) (xy 50.459499 -409.760089)
			(xy 50.495192 -409.801279) (xy 50.524659 -409.847129) (xy 50.5473 -409.896706) (xy 50.562656 -409.949001)
			(xy 50.570413 -410.002949) (xy 50.570413 -410.057451) (xy 50.570412 -410.057456) (xy 52.007923 -410.057456)
			(xy 52.007923 -410.002944) (xy 52.015681 -409.948986) (xy 52.03104 -409.896682) (xy 52.053686 -409.847096)
			(xy 52.083159 -409.801238) (xy 52.118858 -409.760041) (xy 52.160057 -409.724344) (xy 52.205917 -409.694874)
			(xy 52.255504 -409.672231) (xy 52.30781 -409.656876) (xy 52.361768 -409.649121) (xy 52.389024 -409.64866)
			(xy 53.252624 -409.64866) (xy 53.279872 -409.649212) (xy 53.333812 -409.65697) (xy 53.3861 -409.672326)
			(xy 53.43567 -409.694967) (xy 53.481513 -409.724431) (xy 53.522697 -409.76012) (xy 53.558383 -409.801306)
			(xy 53.587845 -409.847151) (xy 53.610482 -409.896723) (xy 53.625835 -409.949011) (xy 53.63359 -410.002952)
			(xy 53.63359 -410.057448) (xy 53.633589 -410.057452) (xy 55.071246 -410.057452) (xy 55.071246 -410.002948)
			(xy 55.079002 -409.948999) (xy 55.094357 -409.896703) (xy 55.116997 -409.847124) (xy 55.146462 -409.801271)
			(xy 55.182153 -409.760079) (xy 55.223342 -409.724384) (xy 55.269192 -409.694914) (xy 55.318769 -409.672269)
			(xy 55.371064 -409.65691) (xy 55.425012 -409.649148) (xy 55.452264 -409.64866) (xy 56.315864 -409.64866)
			(xy 56.343116 -409.649185) (xy 56.397067 -409.656937) (xy 56.449364 -409.672289) (xy 56.498945 -409.694927)
			(xy 56.544799 -409.724392) (xy 56.585992 -409.760082) (xy 56.621687 -409.801273) (xy 56.651156 -409.847124)
			(xy 56.673799 -409.896702) (xy 56.689155 -409.948998) (xy 56.696913 -410.002948) (xy 56.696913 -410.057452)
			(xy 56.696913 -410.057455) (xy 58.134423 -410.057455) (xy 58.134423 -410.002945) (xy 58.142181 -409.948989)
			(xy 58.157538 -409.896686) (xy 58.180183 -409.847102) (xy 58.209654 -409.801244) (xy 58.245351 -409.760048)
			(xy 58.286548 -409.724351) (xy 58.332405 -409.694881) (xy 58.38199 -409.672237) (xy 58.434293 -409.65688)
			(xy 58.488249 -409.649123) (xy 58.515504 -409.64866) (xy 59.379104 -409.64866) (xy 59.406353 -409.64921)
			(xy 59.460295 -409.656967) (xy 59.512585 -409.672321) (xy 59.562158 -409.69496) (xy 59.608004 -409.724424)
			(xy 59.64919 -409.760113) (xy 59.684878 -409.801299) (xy 59.714342 -409.847146) (xy 59.73698 -409.896718)
			(xy 59.752334 -409.949008) (xy 59.76009 -410.002951) (xy 59.76009 -410.057449) (xy 59.760089 -410.057457)
			(xy 61.197623 -410.057457) (xy 61.197623 -410.002943) (xy 61.205382 -409.948983) (xy 61.220741 -409.896678)
			(xy 61.243389 -409.84709) (xy 61.272864 -409.801231) (xy 61.308565 -409.760034) (xy 61.349767 -409.724337)
			(xy 61.395629 -409.694868) (xy 61.445219 -409.672226) (xy 61.497527 -409.656872) (xy 61.551487 -409.64912)
			(xy 61.578744 -409.64866) (xy 62.442344 -409.64866) (xy 62.469591 -409.649213) (xy 62.523529 -409.656974)
			(xy 62.575814 -409.672332) (xy 62.625382 -409.694973) (xy 62.671223 -409.724438) (xy 62.712404 -409.760127)
			(xy 62.748088 -409.801313) (xy 62.777548 -409.847157) (xy 62.800184 -409.896727) (xy 62.815535 -409.949014)
			(xy 62.82329 -410.002953) (xy 62.82329 -410.057447) (xy 62.823289 -410.057453) (xy 64.260946 -410.057453)
			(xy 64.260946 -410.002947) (xy 64.268703 -409.948996) (xy 64.284058 -409.896698) (xy 64.3067 -409.847118)
			(xy 64.336167 -409.801265) (xy 64.37186 -409.760071) (xy 64.413052 -409.724377) (xy 64.458904 -409.694908)
			(xy 64.508483 -409.672264) (xy 64.560781 -409.656906) (xy 64.614731 -409.649147) (xy 64.641984 -409.64866)
			(xy 65.505584 -409.64866) (xy 65.532835 -409.649186) (xy 65.586783 -409.656941) (xy 65.639079 -409.672294)
			(xy 65.688657 -409.694934) (xy 65.734508 -409.724399) (xy 65.775699 -409.760089) (xy 65.811392 -409.801279)
			(xy 65.840859 -409.847129) (xy 65.8635 -409.896706) (xy 65.878856 -409.949001) (xy 65.886613 -410.002949)
			(xy 65.886613 -410.057451) (xy 65.886612 -410.057456) (xy 67.324123 -410.057456) (xy 67.324123 -410.002944)
			(xy 67.331881 -409.948986) (xy 67.34724 -409.896682) (xy 67.369886 -409.847096) (xy 67.399359 -409.801238)
			(xy 67.435058 -409.760041) (xy 67.476257 -409.724344) (xy 67.522117 -409.694874) (xy 67.571704 -409.672231)
			(xy 67.62401 -409.656876) (xy 67.677968 -409.649121) (xy 67.705224 -409.64866) (xy 68.568824 -409.64866)
			(xy 68.596072 -409.649212) (xy 68.650012 -409.65697) (xy 68.7023 -409.672326) (xy 68.75187 -409.694967)
			(xy 68.797713 -409.724431) (xy 68.838897 -409.76012) (xy 68.874583 -409.801306) (xy 68.904045 -409.847151)
			(xy 68.926682 -409.896723) (xy 68.942035 -409.949011) (xy 68.94979 -410.002952) (xy 68.94979 -410.057448)
			(xy 68.949789 -410.057452) (xy 70.387446 -410.057452) (xy 70.387446 -410.002948) (xy 70.395202 -409.948999)
			(xy 70.410557 -409.896703) (xy 70.433197 -409.847124) (xy 70.462662 -409.801271) (xy 70.498353 -409.760079)
			(xy 70.539542 -409.724384) (xy 70.585392 -409.694914) (xy 70.634969 -409.672269) (xy 70.687264 -409.65691)
			(xy 70.741212 -409.649148) (xy 70.768464 -409.64866) (xy 71.632064 -409.64866) (xy 71.659316 -409.649185)
			(xy 71.713267 -409.656937) (xy 71.765564 -409.672289) (xy 71.815145 -409.694927) (xy 71.860999 -409.724392)
			(xy 71.902192 -409.760082) (xy 71.937887 -409.801273) (xy 71.967356 -409.847124) (xy 71.989999 -409.896702)
			(xy 72.005355 -409.948998) (xy 72.013113 -410.002948) (xy 72.013113 -410.057452) (xy 72.013113 -410.057455)
			(xy 73.450623 -410.057455) (xy 73.450623 -410.002945) (xy 73.458381 -409.948989) (xy 73.473738 -409.896686)
			(xy 73.496383 -409.847102) (xy 73.525854 -409.801244) (xy 73.561551 -409.760048) (xy 73.602748 -409.724351)
			(xy 73.648605 -409.694881) (xy 73.69819 -409.672237) (xy 73.750493 -409.65688) (xy 73.804449 -409.649123)
			(xy 73.831704 -409.64866) (xy 74.695304 -409.64866) (xy 74.722553 -409.64921) (xy 74.776495 -409.656967)
			(xy 74.828785 -409.672321) (xy 74.878358 -409.69496) (xy 74.924204 -409.724424) (xy 74.96539 -409.760113)
			(xy 75.001078 -409.801299) (xy 75.030542 -409.847146) (xy 75.05318 -409.896718) (xy 75.068534 -409.949008)
			(xy 75.07629 -410.002951) (xy 75.07629 -410.057449) (xy 75.076289 -410.057457) (xy 76.513823 -410.057457)
			(xy 76.513823 -410.002943) (xy 76.521582 -409.948983) (xy 76.536941 -409.896678) (xy 76.559589 -409.84709)
			(xy 76.589064 -409.801231) (xy 76.624765 -409.760034) (xy 76.665967 -409.724337) (xy 76.711829 -409.694868)
			(xy 76.761419 -409.672226) (xy 76.813727 -409.656872) (xy 76.867687 -409.64912) (xy 76.894944 -409.64866)
			(xy 77.758544 -409.64866) (xy 77.785791 -409.649213) (xy 77.839729 -409.656974) (xy 77.892014 -409.672332)
			(xy 77.941582 -409.694973) (xy 77.987423 -409.724438) (xy 78.028604 -409.760127) (xy 78.064288 -409.801313)
			(xy 78.093748 -409.847157) (xy 78.116384 -409.896727) (xy 78.131735 -409.949014) (xy 78.13949 -410.002953)
			(xy 78.13949 -410.057447) (xy 78.139489 -410.057453) (xy 79.577146 -410.057453) (xy 79.577146 -410.002947)
			(xy 79.584903 -409.948996) (xy 79.600258 -409.896698) (xy 79.6229 -409.847118) (xy 79.652367 -409.801265)
			(xy 79.68806 -409.760071) (xy 79.729252 -409.724377) (xy 79.775104 -409.694908) (xy 79.824683 -409.672264)
			(xy 79.876981 -409.656906) (xy 79.930931 -409.649147) (xy 79.958184 -409.64866) (xy 80.821784 -409.64866)
			(xy 80.849035 -409.649186) (xy 80.902983 -409.656941) (xy 80.955279 -409.672294) (xy 81.004857 -409.694934)
			(xy 81.050708 -409.724399) (xy 81.091899 -409.760089) (xy 81.127592 -409.801279) (xy 81.157059 -409.847129)
			(xy 81.1797 -409.896706) (xy 81.195056 -409.949001) (xy 81.202813 -410.002949) (xy 81.202813 -410.057451)
			(xy 81.202812 -410.057456) (xy 82.640323 -410.057456) (xy 82.640323 -410.002944) (xy 82.648081 -409.948986)
			(xy 82.66344 -409.896682) (xy 82.686086 -409.847096) (xy 82.715559 -409.801238) (xy 82.751258 -409.760041)
			(xy 82.792457 -409.724344) (xy 82.838317 -409.694874) (xy 82.887904 -409.672231) (xy 82.94021 -409.656876)
			(xy 82.994168 -409.649121) (xy 83.021424 -409.64866) (xy 83.885024 -409.64866) (xy 83.912272 -409.649212)
			(xy 83.966212 -409.65697) (xy 84.0185 -409.672326) (xy 84.06807 -409.694967) (xy 84.113913 -409.724431)
			(xy 84.155097 -409.76012) (xy 84.190783 -409.801306) (xy 84.220245 -409.847151) (xy 84.242882 -409.896723)
			(xy 84.258235 -409.949011) (xy 84.26599 -410.002952) (xy 84.26599 -410.057448) (xy 84.265989 -410.057452)
			(xy 85.703646 -410.057452) (xy 85.703646 -410.002948) (xy 85.711402 -409.948999) (xy 85.726757 -409.896703)
			(xy 85.749397 -409.847124) (xy 85.778862 -409.801271) (xy 85.814553 -409.760079) (xy 85.855742 -409.724384)
			(xy 85.901592 -409.694914) (xy 85.951169 -409.672269) (xy 86.003464 -409.65691) (xy 86.057412 -409.649148)
			(xy 86.084664 -409.64866) (xy 86.948264 -409.64866) (xy 86.975516 -409.649185) (xy 87.029467 -409.656937)
			(xy 87.081764 -409.672289) (xy 87.131345 -409.694927) (xy 87.177199 -409.724392) (xy 87.218392 -409.760082)
			(xy 87.254087 -409.801273) (xy 87.283556 -409.847124) (xy 87.306199 -409.896702) (xy 87.321555 -409.948998)
			(xy 87.329313 -410.002948) (xy 87.329313 -410.057452) (xy 87.329313 -410.057455) (xy 88.766823 -410.057455)
			(xy 88.766823 -410.002945) (xy 88.774581 -409.948989) (xy 88.789938 -409.896686) (xy 88.812583 -409.847102)
			(xy 88.842054 -409.801244) (xy 88.877751 -409.760048) (xy 88.918948 -409.724351) (xy 88.964805 -409.694881)
			(xy 89.01439 -409.672237) (xy 89.066693 -409.65688) (xy 89.120649 -409.649123) (xy 89.147904 -409.64866)
			(xy 90.011504 -409.64866) (xy 90.038753 -409.64921) (xy 90.092695 -409.656967) (xy 90.144985 -409.672321)
			(xy 90.194558 -409.69496) (xy 90.240404 -409.724424) (xy 90.28159 -409.760113) (xy 90.317278 -409.801299)
			(xy 90.346742 -409.847146) (xy 90.36938 -409.896718) (xy 90.384734 -409.949008) (xy 90.39249 -410.002951)
			(xy 90.39249 -410.057449) (xy 90.392489 -410.057457) (xy 91.830023 -410.057457) (xy 91.830023 -410.002943)
			(xy 91.837782 -409.948983) (xy 91.853141 -409.896678) (xy 91.875789 -409.84709) (xy 91.905264 -409.801231)
			(xy 91.940965 -409.760034) (xy 91.982167 -409.724337) (xy 92.028029 -409.694868) (xy 92.077619 -409.672226)
			(xy 92.129927 -409.656872) (xy 92.183887 -409.64912) (xy 92.211144 -409.64866) (xy 93.074744 -409.64866)
			(xy 93.101991 -409.649213) (xy 93.155929 -409.656974) (xy 93.208214 -409.672332) (xy 93.257782 -409.694973)
			(xy 93.303623 -409.724438) (xy 93.344804 -409.760127) (xy 93.380488 -409.801313) (xy 93.409948 -409.847157)
			(xy 93.432584 -409.896727) (xy 93.447935 -409.949014) (xy 93.45569 -410.002953) (xy 93.45569 -410.057447)
			(xy 93.455689 -410.057453) (xy 94.893346 -410.057453) (xy 94.893346 -410.002947) (xy 94.901103 -409.948996)
			(xy 94.916458 -409.896698) (xy 94.9391 -409.847118) (xy 94.968567 -409.801265) (xy 95.00426 -409.760071)
			(xy 95.045452 -409.724377) (xy 95.091304 -409.694908) (xy 95.140883 -409.672264) (xy 95.193181 -409.656906)
			(xy 95.247131 -409.649147) (xy 95.274384 -409.64866) (xy 96.137984 -409.64866) (xy 96.165235 -409.649186)
			(xy 96.219183 -409.656941) (xy 96.271479 -409.672294) (xy 96.321057 -409.694934) (xy 96.366908 -409.724399)
			(xy 96.408099 -409.760089) (xy 96.443792 -409.801279) (xy 96.473259 -409.847129) (xy 96.4959 -409.896706)
			(xy 96.511256 -409.949001) (xy 96.519013 -410.002949) (xy 96.519013 -410.057451) (xy 96.511256 -410.111399)
			(xy 96.4959 -410.163694) (xy 96.473259 -410.213271) (xy 96.443792 -410.259121) (xy 96.408099 -410.300311)
			(xy 96.366908 -410.336001) (xy 96.321057 -410.365466) (xy 96.271479 -410.388106) (xy 96.219183 -410.403459)
			(xy 96.165235 -410.411214) (xy 96.137984 -410.411676) (xy 95.274384 -410.411676) (xy 95.247131 -410.411253)
			(xy 95.193181 -410.403494) (xy 95.140883 -410.388136) (xy 95.091304 -410.365492) (xy 95.045452 -410.336023)
			(xy 95.00426 -410.300329) (xy 94.968567 -410.259135) (xy 94.9391 -410.213282) (xy 94.916458 -410.163702)
			(xy 94.901103 -410.111404) (xy 94.893346 -410.057453) (xy 93.455689 -410.057453) (xy 93.447935 -410.111386)
			(xy 93.432584 -410.163673) (xy 93.409948 -410.213243) (xy 93.380488 -410.259087) (xy 93.344804 -410.300273)
			(xy 93.303623 -410.335962) (xy 93.257782 -410.365427) (xy 93.208214 -410.388068) (xy 93.155929 -410.403426)
			(xy 93.101991 -410.411187) (xy 93.074744 -410.411676) (xy 92.211144 -410.411676) (xy 92.183887 -410.41128)
			(xy 92.129927 -410.403528) (xy 92.077619 -410.388174) (xy 92.028029 -410.365532) (xy 91.982167 -410.336063)
			(xy 91.940965 -410.300366) (xy 91.905264 -410.259169) (xy 91.875789 -410.21331) (xy 91.853141 -410.163722)
			(xy 91.837782 -410.111417) (xy 91.830023 -410.057457) (xy 90.392489 -410.057457) (xy 90.384734 -410.111392)
			(xy 90.36938 -410.163682) (xy 90.346742 -410.213254) (xy 90.317278 -410.259101) (xy 90.28159 -410.300287)
			(xy 90.240404 -410.335976) (xy 90.194558 -410.36544) (xy 90.144985 -410.388079) (xy 90.092695 -410.403433)
			(xy 90.038753 -410.41119) (xy 90.011504 -410.411676) (xy 89.147904 -410.411676) (xy 89.120649 -410.411277)
			(xy 89.066693 -410.40352) (xy 89.01439 -410.388163) (xy 88.964805 -410.365519) (xy 88.918948 -410.336049)
			(xy 88.877751 -410.300352) (xy 88.842054 -410.259156) (xy 88.812583 -410.213298) (xy 88.789938 -410.163714)
			(xy 88.774581 -410.111411) (xy 88.766823 -410.057455) (xy 87.329313 -410.057455) (xy 87.321555 -410.111402)
			(xy 87.306199 -410.163698) (xy 87.283556 -410.213276) (xy 87.254087 -410.259127) (xy 87.218392 -410.300318)
			(xy 87.177199 -410.336008) (xy 87.131345 -410.365473) (xy 87.081764 -410.388111) (xy 87.029467 -410.403463)
			(xy 86.975516 -410.411215) (xy 86.948264 -410.411676) (xy 86.084664 -410.411676) (xy 86.057412 -410.411252)
			(xy 86.003464 -410.40349) (xy 85.951169 -410.388131) (xy 85.901592 -410.365486) (xy 85.855742 -410.336016)
			(xy 85.814553 -410.300321) (xy 85.778862 -410.259129) (xy 85.749397 -410.213276) (xy 85.726757 -410.163697)
			(xy 85.711402 -410.111401) (xy 85.703646 -410.057452) (xy 84.265989 -410.057452) (xy 84.258235 -410.111389)
			(xy 84.242882 -410.163677) (xy 84.220245 -410.213249) (xy 84.190783 -410.259094) (xy 84.155097 -410.30028)
			(xy 84.113913 -410.335969) (xy 84.06807 -410.365433) (xy 84.0185 -410.388074) (xy 83.966212 -410.40343)
			(xy 83.912272 -410.411188) (xy 83.885024 -410.411676) (xy 83.021424 -410.411676) (xy 82.994168 -410.411279)
			(xy 82.94021 -410.403524) (xy 82.887904 -410.388169) (xy 82.838317 -410.365526) (xy 82.792457 -410.336056)
			(xy 82.751258 -410.300359) (xy 82.715559 -410.259162) (xy 82.686086 -410.213304) (xy 82.66344 -410.163718)
			(xy 82.648081 -410.111414) (xy 82.640323 -410.057456) (xy 81.202812 -410.057456) (xy 81.195056 -410.111399)
			(xy 81.1797 -410.163694) (xy 81.157059 -410.213271) (xy 81.127592 -410.259121) (xy 81.091899 -410.300311)
			(xy 81.050708 -410.336001) (xy 81.004857 -410.365466) (xy 80.955279 -410.388106) (xy 80.902983 -410.403459)
			(xy 80.849035 -410.411214) (xy 80.821784 -410.411676) (xy 79.958184 -410.411676) (xy 79.930931 -410.411253)
			(xy 79.876981 -410.403494) (xy 79.824683 -410.388136) (xy 79.775104 -410.365492) (xy 79.729252 -410.336023)
			(xy 79.68806 -410.300329) (xy 79.652367 -410.259135) (xy 79.6229 -410.213282) (xy 79.600258 -410.163702)
			(xy 79.584903 -410.111404) (xy 79.577146 -410.057453) (xy 78.139489 -410.057453) (xy 78.131735 -410.111386)
			(xy 78.116384 -410.163673) (xy 78.093748 -410.213243) (xy 78.064288 -410.259087) (xy 78.028604 -410.300273)
			(xy 77.987423 -410.335962) (xy 77.941582 -410.365427) (xy 77.892014 -410.388068) (xy 77.839729 -410.403426)
			(xy 77.785791 -410.411187) (xy 77.758544 -410.411676) (xy 76.894944 -410.411676) (xy 76.867687 -410.41128)
			(xy 76.813727 -410.403528) (xy 76.761419 -410.388174) (xy 76.711829 -410.365532) (xy 76.665967 -410.336063)
			(xy 76.624765 -410.300366) (xy 76.589064 -410.259169) (xy 76.559589 -410.21331) (xy 76.536941 -410.163722)
			(xy 76.521582 -410.111417) (xy 76.513823 -410.057457) (xy 75.076289 -410.057457) (xy 75.068534 -410.111392)
			(xy 75.05318 -410.163682) (xy 75.030542 -410.213254) (xy 75.001078 -410.259101) (xy 74.96539 -410.300287)
			(xy 74.924204 -410.335976) (xy 74.878358 -410.36544) (xy 74.828785 -410.388079) (xy 74.776495 -410.403433)
			(xy 74.722553 -410.41119) (xy 74.695304 -410.411676) (xy 73.831704 -410.411676) (xy 73.804449 -410.411277)
			(xy 73.750493 -410.40352) (xy 73.69819 -410.388163) (xy 73.648605 -410.365519) (xy 73.602748 -410.336049)
			(xy 73.561551 -410.300352) (xy 73.525854 -410.259156) (xy 73.496383 -410.213298) (xy 73.473738 -410.163714)
			(xy 73.458381 -410.111411) (xy 73.450623 -410.057455) (xy 72.013113 -410.057455) (xy 72.005355 -410.111402)
			(xy 71.989999 -410.163698) (xy 71.967356 -410.213276) (xy 71.937887 -410.259127) (xy 71.902192 -410.300318)
			(xy 71.860999 -410.336008) (xy 71.815145 -410.365473) (xy 71.765564 -410.388111) (xy 71.713267 -410.403463)
			(xy 71.659316 -410.411215) (xy 71.632064 -410.411676) (xy 70.768464 -410.411676) (xy 70.741212 -410.411252)
			(xy 70.687264 -410.40349) (xy 70.634969 -410.388131) (xy 70.585392 -410.365486) (xy 70.539542 -410.336016)
			(xy 70.498353 -410.300321) (xy 70.462662 -410.259129) (xy 70.433197 -410.213276) (xy 70.410557 -410.163697)
			(xy 70.395202 -410.111401) (xy 70.387446 -410.057452) (xy 68.949789 -410.057452) (xy 68.942035 -410.111389)
			(xy 68.926682 -410.163677) (xy 68.904045 -410.213249) (xy 68.874583 -410.259094) (xy 68.838897 -410.30028)
			(xy 68.797713 -410.335969) (xy 68.75187 -410.365433) (xy 68.7023 -410.388074) (xy 68.650012 -410.40343)
			(xy 68.596072 -410.411188) (xy 68.568824 -410.411676) (xy 67.705224 -410.411676) (xy 67.677968 -410.411279)
			(xy 67.62401 -410.403524) (xy 67.571704 -410.388169) (xy 67.522117 -410.365526) (xy 67.476257 -410.336056)
			(xy 67.435058 -410.300359) (xy 67.399359 -410.259162) (xy 67.369886 -410.213304) (xy 67.34724 -410.163718)
			(xy 67.331881 -410.111414) (xy 67.324123 -410.057456) (xy 65.886612 -410.057456) (xy 65.878856 -410.111399)
			(xy 65.8635 -410.163694) (xy 65.840859 -410.213271) (xy 65.811392 -410.259121) (xy 65.775699 -410.300311)
			(xy 65.734508 -410.336001) (xy 65.688657 -410.365466) (xy 65.639079 -410.388106) (xy 65.586783 -410.403459)
			(xy 65.532835 -410.411214) (xy 65.505584 -410.411676) (xy 64.641984 -410.411676) (xy 64.614731 -410.411253)
			(xy 64.560781 -410.403494) (xy 64.508483 -410.388136) (xy 64.458904 -410.365492) (xy 64.413052 -410.336023)
			(xy 64.37186 -410.300329) (xy 64.336167 -410.259135) (xy 64.3067 -410.213282) (xy 64.284058 -410.163702)
			(xy 64.268703 -410.111404) (xy 64.260946 -410.057453) (xy 62.823289 -410.057453) (xy 62.815535 -410.111386)
			(xy 62.800184 -410.163673) (xy 62.777548 -410.213243) (xy 62.748088 -410.259087) (xy 62.712404 -410.300273)
			(xy 62.671223 -410.335962) (xy 62.625382 -410.365427) (xy 62.575814 -410.388068) (xy 62.523529 -410.403426)
			(xy 62.469591 -410.411187) (xy 62.442344 -410.411676) (xy 61.578744 -410.411676) (xy 61.551487 -410.41128)
			(xy 61.497527 -410.403528) (xy 61.445219 -410.388174) (xy 61.395629 -410.365532) (xy 61.349767 -410.336063)
			(xy 61.308565 -410.300366) (xy 61.272864 -410.259169) (xy 61.243389 -410.21331) (xy 61.220741 -410.163722)
			(xy 61.205382 -410.111417) (xy 61.197623 -410.057457) (xy 59.760089 -410.057457) (xy 59.752334 -410.111392)
			(xy 59.73698 -410.163682) (xy 59.714342 -410.213254) (xy 59.684878 -410.259101) (xy 59.64919 -410.300287)
			(xy 59.608004 -410.335976) (xy 59.562158 -410.36544) (xy 59.512585 -410.388079) (xy 59.460295 -410.403433)
			(xy 59.406353 -410.41119) (xy 59.379104 -410.411676) (xy 58.515504 -410.411676) (xy 58.488249 -410.411277)
			(xy 58.434293 -410.40352) (xy 58.38199 -410.388163) (xy 58.332405 -410.365519) (xy 58.286548 -410.336049)
			(xy 58.245351 -410.300352) (xy 58.209654 -410.259156) (xy 58.180183 -410.213298) (xy 58.157538 -410.163714)
			(xy 58.142181 -410.111411) (xy 58.134423 -410.057455) (xy 56.696913 -410.057455) (xy 56.689155 -410.111402)
			(xy 56.673799 -410.163698) (xy 56.651156 -410.213276) (xy 56.621687 -410.259127) (xy 56.585992 -410.300318)
			(xy 56.544799 -410.336008) (xy 56.498945 -410.365473) (xy 56.449364 -410.388111) (xy 56.397067 -410.403463)
			(xy 56.343116 -410.411215) (xy 56.315864 -410.411676) (xy 55.452264 -410.411676) (xy 55.425012 -410.411252)
			(xy 55.371064 -410.40349) (xy 55.318769 -410.388131) (xy 55.269192 -410.365486) (xy 55.223342 -410.336016)
			(xy 55.182153 -410.300321) (xy 55.146462 -410.259129) (xy 55.116997 -410.213276) (xy 55.094357 -410.163697)
			(xy 55.079002 -410.111401) (xy 55.071246 -410.057452) (xy 53.633589 -410.057452) (xy 53.625835 -410.111389)
			(xy 53.610482 -410.163677) (xy 53.587845 -410.213249) (xy 53.558383 -410.259094) (xy 53.522697 -410.30028)
			(xy 53.481513 -410.335969) (xy 53.43567 -410.365433) (xy 53.3861 -410.388074) (xy 53.333812 -410.40343)
			(xy 53.279872 -410.411188) (xy 53.252624 -410.411676) (xy 52.389024 -410.411676) (xy 52.361768 -410.411279)
			(xy 52.30781 -410.403524) (xy 52.255504 -410.388169) (xy 52.205917 -410.365526) (xy 52.160057 -410.336056)
			(xy 52.118858 -410.300359) (xy 52.083159 -410.259162) (xy 52.053686 -410.213304) (xy 52.03104 -410.163718)
			(xy 52.015681 -410.111414) (xy 52.007923 -410.057456) (xy 50.570412 -410.057456) (xy 50.562656 -410.111399)
			(xy 50.5473 -410.163694) (xy 50.524659 -410.213271) (xy 50.495192 -410.259121) (xy 50.459499 -410.300311)
			(xy 50.418308 -410.336001) (xy 50.372457 -410.365466) (xy 50.322879 -410.388106) (xy 50.270583 -410.403459)
			(xy 50.216635 -410.411214) (xy 50.189384 -410.411676) (xy 49.325784 -410.411676) (xy 49.298531 -410.411253)
			(xy 49.244581 -410.403494) (xy 49.192283 -410.388136) (xy 49.142704 -410.365492) (xy 49.096852 -410.336023)
			(xy 49.05566 -410.300329) (xy 49.019967 -410.259135) (xy 48.9905 -410.213282) (xy 48.967858 -410.163702)
			(xy 48.952503 -410.111404) (xy 48.944746 -410.057453) (xy 7.00913 -410.057453) (xy 7.00913 -410.708348)
			(xy 183.940958 -410.708348) (xy 183.940958 -400.09572) (xy 183.941483 -400.070772) (xy 183.94929 -400.021491)
			(xy 183.964701 -399.974034) (xy 183.987336 -399.929568) (xy 184.01664 -399.889183) (xy 184.033922 -399.871184)
			(xy 184.239408 -399.665698) (xy 184.257395 -399.648399) (xy 184.297773 -399.619076) (xy 184.342241 -399.59643)
			(xy 184.389704 -399.581018) (xy 184.438993 -399.57322) (xy 184.463944 -399.572734) (xy 188.119004 -399.572734)
			(xy 188.143952 -399.57325) (xy 188.193234 -399.581061) (xy 188.24069 -399.596474) (xy 188.285156 -399.619111)
			(xy 188.32554 -399.648416) (xy 188.34354 -399.665698) (xy 188.528452 -399.85061) (xy 188.545762 -399.868588)
			(xy 188.575091 -399.908966) (xy 188.597741 -399.953436) (xy 188.613156 -400.000901) (xy 188.620956 -400.050193)
			(xy 188.621416 -400.075146) (xy 188.621416 -402.753322) (xy 188.621826 -402.763393) (xy 188.629557 -402.781991)
			(xy 188.636402 -402.78939) (xy 191.190372 -405.34336) (xy 191.197792 -405.350175) (xy 191.216376 -405.35791)
			(xy 191.22644 -405.358346) (xy 195.26631 -405.358346) (xy 195.276382 -405.35794) (xy 195.29498 -405.350207)
			(xy 195.302378 -405.34336) (xy 197.179184 -403.466554) (xy 197.185991 -403.459128) (xy 197.193731 -403.440549)
			(xy 197.19417 -403.430486) (xy 197.19417 -400.104356) (xy 197.194651 -400.079406) (xy 197.202469 -400.030123)
			(xy 197.217889 -399.982665) (xy 197.240534 -399.9382) (xy 197.269848 -399.897818) (xy 197.287134 -399.87982)
			(xy 197.53961 -399.627344) (xy 197.557604 -399.610052) (xy 197.597979 -399.580727) (xy 197.642445 -399.558078)
			(xy 197.689907 -399.542665) (xy 197.739195 -399.534866) (xy 197.764146 -399.53438) (xy 201.33818 -399.53438)
			(xy 201.363128 -399.534898) (xy 201.41241 -399.542706) (xy 201.459867 -399.558118) (xy 201.504334 -399.580755)
			(xy 201.544717 -399.610061) (xy 201.562716 -399.627344) (xy 201.823066 -399.887694) (xy 201.840352 -399.905693)
			(xy 201.869678 -399.946068) (xy 201.892327 -399.990532) (xy 201.907742 -400.037992) (xy 201.915543 -400.08728)
			(xy 201.91603 -400.11223) (xy 201.91603 -403.422612) (xy 201.916441 -403.432683) (xy 201.924171 -403.451281)
			(xy 201.931016 -403.45868) (xy 202.036172 -403.563836) (xy 202.053479 -403.581816) (xy 202.082802 -403.622195)
			(xy 202.105447 -403.666665) (xy 202.120857 -403.714129) (xy 202.128652 -403.76342) (xy 202.129136 -403.788372)
			(xy 202.129136 -406.516078) (xy 202.129564 -406.526147) (xy 202.137282 -406.544745) (xy 202.144122 -406.552146)
			(xy 203.391008 -407.799032) (xy 203.39839 -407.805645) (xy 203.416673 -407.813238) (xy 203.426568 -407.813764)
			(xy 203.457048 -407.814018) (xy 203.466471 -407.813752) (xy 203.484091 -407.807093) (xy 203.491338 -407.801064)
			(xy 203.512428 -407.782761) (xy 203.558955 -407.751881) (xy 203.609485 -407.728114) (xy 203.662941 -407.711966)
			(xy 203.71818 -407.703783) (xy 203.7461 -407.703274) (xy 203.772675 -407.703742) (xy 203.825312 -407.711107)
			(xy 203.876417 -407.72571) (xy 203.924999 -407.747267) (xy 203.970118 -407.77536) (xy 204.010899 -407.809446)
			(xy 204.046552 -407.848864) (xy 204.076387 -407.89285) (xy 204.099826 -407.940552) (xy 204.108558 -407.965656)
			(xy 204.112315 -407.97567) (xy 204.126611 -407.991551) (xy 204.146134 -408.00024) (xy 204.156818 -408.000708)
			(xy 205.795372 -408.000708) (xy 205.805443 -408.000292) (xy 205.824042 -407.992567) (xy 205.83144 -407.985722)
			(xy 207.658716 -406.158446) (xy 207.66553 -406.151026) (xy 207.673264 -406.132442) (xy 207.673702 -406.122378)
			(xy 207.673702 -403.722586) (xy 207.674193 -403.697637) (xy 207.682006 -403.648353) (xy 207.697424 -403.600896)
			(xy 207.720068 -403.55643) (xy 207.74938 -403.516048) (xy 207.766666 -403.49805) (xy 207.847184 -403.417532)
			(xy 207.854 -403.410113) (xy 207.861735 -403.391528) (xy 207.86217 -403.381464) (xy 207.86217 -400.079464)
			(xy 207.862656 -400.054515) (xy 207.870472 -400.005231) (xy 207.885892 -399.957774) (xy 207.908536 -399.913308)
			(xy 207.937848 -399.872926) (xy 207.955134 -399.854928) (xy 208.201514 -399.608548) (xy 208.21949 -399.591236)
			(xy 208.259869 -399.561908) (xy 208.304339 -399.539258) (xy 208.351805 -399.523843) (xy 208.401097 -399.516044)
			(xy 208.42605 -399.515584) (xy 211.971128 -399.515584) (xy 211.996077 -399.516071) (xy 212.045361 -399.523886)
			(xy 212.092818 -399.539306) (xy 212.137284 -399.561949) (xy 212.177666 -399.591262) (xy 212.195664 -399.608548)
			(xy 212.507576 -399.92046) (xy 212.524847 -399.938473) (xy 212.554175 -399.978843) (xy 212.576826 -400.023305)
			(xy 212.592245 -400.070762) (xy 212.600051 -400.120047) (xy 212.60054 -400.144996) (xy 212.60054 -403.480016)
			(xy 212.600947 -403.490088) (xy 212.608679 -403.508686) (xy 212.615526 -403.516084) (xy 212.638894 -403.539452)
			(xy 212.656213 -403.557421) (xy 212.685533 -403.597804) (xy 212.708176 -403.642276) (xy 212.723583 -403.689743)
			(xy 212.731376 -403.739036) (xy 212.731858 -403.763988) (xy 212.731858 -406.258014) (xy 212.732261 -406.268086)
			(xy 212.739995 -406.286685) (xy 212.746844 -406.294082) (xy 214.186008 -407.733246) (xy 214.193923 -407.74035)
			(xy 214.21371 -407.748063) (xy 214.234927 -407.747127) (xy 214.244682 -407.742898) (xy 214.271123 -407.730432)
			(xy 214.326854 -407.712801) (xy 214.38462 -407.703855) (xy 214.413846 -407.703274) (xy 214.4141 -407.703274)
			(xy 214.441972 -407.70378) (xy 214.497125 -407.71188) (xy 214.550512 -407.727922) (xy 214.600994 -407.751564)
			(xy 214.647498 -407.782303) (xy 214.689031 -407.819484) (xy 214.72471 -407.862315) (xy 214.753774 -407.909883)
			(xy 214.775604 -407.961175) (xy 214.783162 -407.988008) (xy 214.78748 -408.004772) (xy 214.814912 -408.025854)
			(xy 216.38895 -408.025854) (xy 216.399018 -408.025415) (xy 216.417617 -408.017705) (xy 216.425018 -408.010868)
			(xy 218.335098 -406.100788) (xy 218.341936 -406.093386) (xy 218.349657 -406.074788) (xy 218.350084 -406.06472)
			(xy 218.350084 -403.755606) (xy 218.350592 -403.730657) (xy 218.358403 -403.681375) (xy 218.373817 -403.633918)
			(xy 218.396456 -403.589452) (xy 218.425764 -403.549069) (xy 218.443048 -403.53107) (xy 218.50731 -403.466808)
			(xy 218.51414 -403.4594) (xy 218.521865 -403.440807) (xy 218.522296 -403.43074) (xy 218.522296 -400.095974)
			(xy 218.522781 -400.071024) (xy 218.530596 -400.021741) (xy 218.546016 -399.974283) (xy 218.56866 -399.929817)
			(xy 218.597974 -399.889436) (xy 218.61526 -399.871438) (xy 218.820746 -399.665952) (xy 218.838709 -399.648625)
			(xy 218.879091 -399.619299) (xy 218.923564 -399.596652) (xy 218.971033 -399.581241) (xy 219.020328 -399.573446)
			(xy 219.045282 -399.572988) (xy 222.709232 -399.572988) (xy 222.734182 -399.573471) (xy 222.783465 -399.581288)
			(xy 222.830923 -399.596707) (xy 222.875388 -399.619352) (xy 222.91577 -399.648666) (xy 222.933768 -399.665952)
			(xy 223.130618 -399.862802) (xy 223.147917 -399.880789) (xy 223.177239 -399.921168) (xy 223.199885 -399.965636)
			(xy 223.215297 -400.013098) (xy 223.223096 -400.062387) (xy 223.223582 -400.087338) (xy 223.223582 -403.455124)
			(xy 223.223973 -403.465198) (xy 223.231716 -403.483796) (xy 223.238568 -403.491192) (xy 223.323658 -403.576282)
			(xy 223.340937 -403.594288) (xy 223.370264 -403.63466) (xy 223.392915 -403.679123) (xy 223.408331 -403.726582)
			(xy 223.416134 -403.775868) (xy 223.416622 -403.800818) (xy 223.416622 -406.262078) (xy 223.417053 -406.272147)
			(xy 223.424769 -406.290745) (xy 223.431608 -406.298146) (xy 224.874328 -407.740866) (xy 224.905824 -407.7462)
			(xy 224.920302 -407.739342) (xy 224.945735 -407.727945) (xy 224.999097 -407.71187) (xy 225.054234 -407.703754)
			(xy 225.0821 -407.703274) (xy 225.111289 -407.703848) (xy 225.168987 -407.712721) (xy 225.224657 -407.730289)
			(xy 225.276997 -407.756142) (xy 225.324782 -407.789675) (xy 225.366893 -407.830104) (xy 225.402346 -407.876481)
			(xy 225.430312 -407.927723) (xy 225.440748 -407.954988) (xy 225.444773 -407.964592) (xy 225.459011 -407.979756)
			(xy 225.4781 -407.988017) (xy 225.4885 -407.988516) (xy 227.066094 -407.988516) (xy 227.076166 -407.98811)
			(xy 227.094765 -407.980378) (xy 227.102162 -407.97353) (xy 228.999288 -406.076404) (xy 229.006117 -406.068995)
			(xy 229.013844 -406.050403) (xy 229.014274 -406.040336) (xy 229.014274 -403.768052) (xy 229.014751 -403.743102)
			(xy 229.02257 -403.693818) (xy 229.037991 -403.646361) (xy 229.060637 -403.601896) (xy 229.089951 -403.561514)
			(xy 229.107238 -403.543516) (xy 229.183692 -403.467062) (xy 229.19054 -403.459668) (xy 229.198255 -403.441064)
			(xy 229.198678 -403.430994) (xy 229.198678 -400.11223) (xy 229.199203 -400.087282) (xy 229.20701 -400.038)
			(xy 229.22242 -399.990544) (xy 229.245055 -399.946077) (xy 229.27436 -399.905693) (xy 229.291642 -399.887694)
			(xy 229.521766 -399.65757) (xy 229.539767 -399.640284) (xy 229.580139 -399.610952) (xy 229.624602 -399.588297)
			(xy 229.672062 -399.572876) (xy 229.721351 -399.56507) (xy 229.746302 -399.564606) (xy 233.352594 -399.564606)
			(xy 233.377543 -399.565108) (xy 233.426826 -399.572919) (xy 233.474284 -399.588334) (xy 233.51875 -399.610975)
			(xy 233.559132 -399.640285) (xy 233.57713 -399.65757) (xy 233.798872 -399.879312) (xy 233.816168 -399.897302)
			(xy 233.845492 -399.937679) (xy 233.868139 -399.982146) (xy 233.883552 -400.029608) (xy 233.89135 -400.078897)
			(xy 233.891836 -400.103848) (xy 233.891836 -403.52091) (xy 233.892247 -403.530981) (xy 233.899977 -403.549579)
			(xy 233.906822 -403.556978) (xy 234.044998 -403.695154) (xy 234.062318 -403.713122) (xy 234.091638 -403.753505)
			(xy 234.114281 -403.797978) (xy 234.129687 -403.845445) (xy 234.13748 -403.894737) (xy 234.137962 -403.91969)
			(xy 234.137962 -404.702518) (xy 234.138361 -404.712591) (xy 234.146098 -404.731189) (xy 234.152948 -404.738586)
			(xy 234.63885 -405.224488) (xy 234.646275 -405.231297) (xy 234.664855 -405.239035) (xy 234.674918 -405.239474)
			(xy 238.514382 -405.239474) (xy 238.524405 -405.239065) (xy 238.542927 -405.231396) (xy 238.557101 -405.21722)
			(xy 238.564767 -405.198697) (xy 238.565182 -405.188674) (xy 238.565182 -394.001498) (xy 238.565686 -393.976549)
			(xy 238.573497 -393.927266) (xy 238.588912 -393.879809) (xy 238.611553 -393.835343) (xy 238.640862 -393.79496)
			(xy 238.658146 -393.776962) (xy 238.727234 -393.707874) (xy 238.733961 -393.700496) (xy 238.741558 -393.682047)
			(xy 238.741546 -393.662096) (xy 238.733929 -393.643656) (xy 238.727234 -393.636246) (xy 238.579914 -393.488672)
			(xy 238.553014 -393.461125) (xy 238.504928 -393.400988) (xy 238.463885 -393.33584) (xy 238.430403 -393.266502)
			(xy 238.404904 -393.193848) (xy 238.387709 -393.118794) (xy 238.379036 -393.042285) (xy 238.378492 -393.003786)
			(xy 238.378492 -384.337306) (xy 238.379215 -384.306679) (xy 238.390978 -384.246564) (xy 238.40186 -384.217926)
			(xy 238.457994 -384.079496) (xy 238.466633 -384.059188) (xy 238.488684 -384.020961) (xy 238.515818 -383.986157)
			(xy 238.5314 -383.97053) (xy 238.583216 -383.920746) (xy 238.583724 -383.920238) (xy 239.05718 -383.446782)
			(xy 239.084743 -383.419899) (xy 239.144878 -383.371812) (xy 239.210023 -383.330768) (xy 239.279359 -383.297284)
			(xy 239.35201 -383.271782) (xy 239.427061 -383.254584) (xy 239.503568 -383.245906) (xy 239.542066 -383.24536)
			(xy 273.481546 -383.24536) (xy 273.512174 -383.24607) (xy 273.572289 -383.257841) (xy 273.600926 -383.268728)
			(xy 273.739356 -383.324862) (xy 273.759667 -383.333494) (xy 273.797892 -383.355549) (xy 273.832695 -383.382685)
			(xy 273.848322 -383.398268) (xy 273.898106 -383.450084) (xy 273.898614 -383.450592) (xy 274.11807 -383.670048)
			(xy 274.141946 -383.69494) (xy 274.148804 -383.70256) (xy 274.167854 -383.71145) (xy 274.251674 -383.713482)
			(xy 274.262067 -383.713236) (xy 274.281342 -383.705512) (xy 274.289012 -383.698496) (xy 274.649184 -383.338324)
			(xy 274.667186 -383.321041) (xy 274.70756 -383.291715) (xy 274.752024 -383.269066) (xy 274.799483 -383.25365)
			(xy 274.84877 -383.245848) (xy 274.87372 -383.24536) (xy 280.202132 -383.24536) (xy 280.227081 -383.245851)
			(xy 280.276364 -383.253667) (xy 280.323821 -383.269085) (xy 280.368287 -383.291728) (xy 280.40867 -383.321039)
			(xy 280.426668 -383.338324) (xy 281.135836 -384.047492) (xy 281.153135 -384.065481) (xy 281.182465 -384.105856)
			(xy 281.205118 -384.150322) (xy 281.220536 -384.197785) (xy 281.228338 -384.247076) (xy 281.2288 -384.272028)
			(xy 281.2288 -384.869944) (xy 287.06878 -384.869944) (xy 287.072752 -384.691701) (xy 287.08466 -384.513812)
			(xy 287.104481 -384.33663) (xy 287.132175 -384.160506) (xy 287.167687 -383.985791) (xy 287.210947 -383.812832)
			(xy 287.261869 -383.641971) (xy 287.320352 -383.473549) (xy 287.386279 -383.307899) (xy 287.45952 -383.14535)
			(xy 287.53993 -382.986225) (xy 287.627348 -382.83084) (xy 287.721601 -382.679504) (xy 287.822502 -382.532516)
			(xy 287.929851 -382.390169) (xy 288.043434 -382.252746) (xy 288.163027 -382.120519) (xy 288.288391 -381.99375)
			(xy 288.419278 -381.872692) (xy 288.555427 -381.757585) (xy 288.696569 -381.648657) (xy 288.842424 -381.546125)
			(xy 288.992701 -381.450191) (xy 289.147102 -381.361048) (xy 289.305321 -381.278871) (xy 289.467044 -381.203823)
			(xy 289.631949 -381.136055) (xy 289.79971 -381.075699) (xy 289.969993 -381.022877) (xy 290.14246 -380.977693)
			(xy 290.316768 -380.940236) (xy 290.492572 -380.910582) (xy 290.669522 -380.888789) (xy 290.847268 -380.874899)
			(xy 291.025455 -380.868942) (xy 291.203732 -380.870928) (xy 291.381743 -380.880854) (xy 291.559135 -380.8987)
			(xy 291.735555 -380.92443) (xy 291.910655 -380.957994) (xy 292.084086 -380.999324) (xy 292.255503 -381.04834)
			(xy 292.424566 -381.104942) (xy 292.590941 -381.16902) (xy 292.754295 -381.240446) (xy 292.914306 -381.319078)
			(xy 293.070655 -381.404759) (xy 293.223032 -381.497321) (xy 293.371135 -381.596578) (xy 293.514669 -381.702335)
			(xy 293.653349 -381.81438) (xy 293.7869 -381.932492) (xy 293.915057 -382.056436) (xy 294.037566 -382.185966)
			(xy 294.154183 -382.320825) (xy 294.194727 -382.372167) (xy 303.739054 -382.372167) (xy 303.739054 -382.317633)
			(xy 303.746815 -382.263654) (xy 303.762179 -382.211329) (xy 303.784833 -382.161723) (xy 303.814317 -382.115846)
			(xy 303.850029 -382.074631) (xy 303.891242 -382.038919) (xy 303.937119 -382.009435) (xy 303.986725 -381.986781)
			(xy 304.03905 -381.971416) (xy 304.093029 -381.963655) (xy 304.120296 -381.963168) (xy 304.983896 -381.963168)
			(xy 305.011169 -381.963571) (xy 305.065161 -381.971334) (xy 305.117498 -381.986701) (xy 305.167116 -382.00936)
			(xy 305.213003 -382.03885) (xy 305.254227 -382.07457) (xy 305.289948 -382.115793) (xy 305.319438 -382.161681)
			(xy 305.342098 -382.211298) (xy 305.357466 -382.263635) (xy 305.365228 -382.317627) (xy 305.365228 -382.372167)
			(xy 310.546254 -382.372167) (xy 310.546254 -382.317633) (xy 310.554015 -382.263654) (xy 310.569379 -382.211329)
			(xy 310.592033 -382.161723) (xy 310.621517 -382.115846) (xy 310.657229 -382.074631) (xy 310.698442 -382.038919)
			(xy 310.744319 -382.009435) (xy 310.793925 -381.986781) (xy 310.84625 -381.971416) (xy 310.900229 -381.963655)
			(xy 310.927496 -381.963168) (xy 311.791096 -381.963168) (xy 311.818369 -381.963571) (xy 311.872361 -381.971334)
			(xy 311.924698 -381.986701) (xy 311.974316 -382.00936) (xy 312.020203 -382.03885) (xy 312.061427 -382.07457)
			(xy 312.097148 -382.115793) (xy 312.126638 -382.161681) (xy 312.149298 -382.211298) (xy 312.164666 -382.263635)
			(xy 312.172428 -382.317627) (xy 312.172428 -382.372167) (xy 317.353454 -382.372167) (xy 317.353454 -382.317633)
			(xy 317.361215 -382.263654) (xy 317.376579 -382.211329) (xy 317.399233 -382.161723) (xy 317.428717 -382.115846)
			(xy 317.464429 -382.074631) (xy 317.505642 -382.038919) (xy 317.551519 -382.009435) (xy 317.601125 -381.986781)
			(xy 317.65345 -381.971416) (xy 317.707429 -381.963655) (xy 317.734696 -381.963168) (xy 318.598296 -381.963168)
			(xy 318.625569 -381.963571) (xy 318.679561 -381.971334) (xy 318.731898 -381.986701) (xy 318.781516 -382.00936)
			(xy 318.827403 -382.03885) (xy 318.868627 -382.07457) (xy 318.904348 -382.115793) (xy 318.933838 -382.161681)
			(xy 318.956498 -382.211298) (xy 318.971866 -382.263635) (xy 318.979628 -382.317627) (xy 318.979628 -382.372171)
			(xy 336.266732 -382.372171) (xy 336.266732 -382.317629) (xy 336.274494 -382.263643) (xy 336.289861 -382.211311)
			(xy 336.312521 -382.161698) (xy 336.34201 -382.115816) (xy 336.377729 -382.074598) (xy 336.418951 -382.038884)
			(xy 336.464837 -382.009399) (xy 336.514452 -381.986746) (xy 336.566786 -381.971385) (xy 336.620773 -381.963628)
			(xy 336.648044 -381.963168) (xy 337.511644 -381.963168) (xy 337.538913 -381.963598) (xy 337.592897 -381.971365)
			(xy 337.645225 -381.986735) (xy 337.694833 -382.009396) (xy 337.740712 -382.038885) (xy 337.781928 -382.074603)
			(xy 337.817641 -382.115823) (xy 337.847125 -382.161705) (xy 337.86978 -382.211316) (xy 337.885144 -382.263647)
			(xy 337.892906 -382.31763) (xy 337.892906 -382.37217) (xy 337.892906 -382.372171) (xy 343.073932 -382.372171)
			(xy 343.073932 -382.317629) (xy 343.081694 -382.263643) (xy 343.097061 -382.211311) (xy 343.119721 -382.161698)
			(xy 343.14921 -382.115816) (xy 343.184929 -382.074598) (xy 343.226151 -382.038884) (xy 343.272037 -382.009399)
			(xy 343.321652 -381.986746) (xy 343.373986 -381.971385) (xy 343.427973 -381.963628) (xy 343.455244 -381.963168)
			(xy 344.318844 -381.963168) (xy 344.346113 -381.963598) (xy 344.400097 -381.971365) (xy 344.452425 -381.986735)
			(xy 344.502033 -382.009396) (xy 344.547912 -382.038885) (xy 344.589128 -382.074603) (xy 344.624841 -382.115823)
			(xy 344.654325 -382.161705) (xy 344.67698 -382.211316) (xy 344.692344 -382.263647) (xy 344.700106 -382.31763)
			(xy 344.700106 -382.37217) (xy 344.700106 -382.372171) (xy 349.881132 -382.372171) (xy 349.881132 -382.317629)
			(xy 349.888894 -382.263643) (xy 349.904261 -382.211311) (xy 349.926921 -382.161698) (xy 349.95641 -382.115816)
			(xy 349.992129 -382.074598) (xy 350.033351 -382.038884) (xy 350.079237 -382.009399) (xy 350.128852 -381.986746)
			(xy 350.181186 -381.971385) (xy 350.235173 -381.963628) (xy 350.262444 -381.963168) (xy 351.126044 -381.963168)
			(xy 351.153313 -381.963598) (xy 351.207297 -381.971365) (xy 351.259625 -381.986735) (xy 351.309233 -382.009396)
			(xy 351.355112 -382.038885) (xy 351.396328 -382.074603) (xy 351.432041 -382.115823) (xy 351.461525 -382.161705)
			(xy 351.48418 -382.211316) (xy 351.499544 -382.263647) (xy 351.507306 -382.31763) (xy 351.507306 -382.372167)
			(xy 370.839254 -382.372167) (xy 370.839254 -382.317633) (xy 370.847015 -382.263654) (xy 370.862379 -382.21133)
			(xy 370.885033 -382.161724) (xy 370.914516 -382.115847) (xy 370.950227 -382.074633) (xy 370.991441 -382.03892)
			(xy 371.037317 -382.009437) (xy 371.086922 -381.986782) (xy 371.139247 -381.971417) (xy 371.193225 -381.963655)
			(xy 371.220492 -381.963168) (xy 372.084092 -381.963168) (xy 372.111366 -381.963571) (xy 372.165357 -381.971333)
			(xy 372.217695 -381.9867) (xy 372.267313 -382.009359) (xy 372.313202 -382.038848) (xy 372.354426 -382.074568)
			(xy 372.390147 -382.115792) (xy 372.419638 -382.16168) (xy 372.442298 -382.211297) (xy 372.457665 -382.263635)
			(xy 372.465428 -382.317626) (xy 372.465428 -382.372167) (xy 377.646454 -382.372167) (xy 377.646454 -382.317633)
			(xy 377.654215 -382.263654) (xy 377.669579 -382.21133) (xy 377.692233 -382.161724) (xy 377.721716 -382.115847)
			(xy 377.757427 -382.074633) (xy 377.798641 -382.03892) (xy 377.844517 -382.009437) (xy 377.894122 -381.986782)
			(xy 377.946447 -381.971417) (xy 378.000425 -381.963655) (xy 378.027692 -381.963168) (xy 378.891292 -381.963168)
			(xy 378.918566 -381.963571) (xy 378.972557 -381.971333) (xy 379.024895 -381.9867) (xy 379.074513 -382.009359)
			(xy 379.120402 -382.038848) (xy 379.161626 -382.074568) (xy 379.197347 -382.115792) (xy 379.226838 -382.16168)
			(xy 379.249498 -382.211297) (xy 379.264865 -382.263635) (xy 379.272628 -382.317626) (xy 379.272628 -382.372167)
			(xy 384.453654 -382.372167) (xy 384.453654 -382.317633) (xy 384.461415 -382.263654) (xy 384.476779 -382.21133)
			(xy 384.499433 -382.161724) (xy 384.528916 -382.115847) (xy 384.564627 -382.074633) (xy 384.605841 -382.03892)
			(xy 384.651717 -382.009437) (xy 384.701322 -381.986782) (xy 384.753647 -381.971417) (xy 384.807625 -381.963655)
			(xy 384.834892 -381.963168) (xy 385.698492 -381.963168) (xy 385.725766 -381.963571) (xy 385.779757 -381.971333)
			(xy 385.832095 -381.9867) (xy 385.881713 -382.009359) (xy 385.927602 -382.038848) (xy 385.968826 -382.074568)
			(xy 386.004547 -382.115792) (xy 386.034038 -382.16168) (xy 386.056698 -382.211297) (xy 386.072065 -382.263635)
			(xy 386.079828 -382.317626) (xy 386.079828 -382.372171) (xy 403.366932 -382.372171) (xy 403.366932 -382.317629)
			(xy 403.374694 -382.263643) (xy 403.390061 -382.211311) (xy 403.41272 -382.161699) (xy 403.442209 -382.115817)
			(xy 403.477928 -382.0746) (xy 403.51915 -382.038885) (xy 403.565035 -382.009401) (xy 403.614649 -381.986747)
			(xy 403.666982 -381.971386) (xy 403.720969 -381.963629) (xy 403.74824 -381.963168) (xy 404.61184 -381.963168)
			(xy 404.63911 -381.963597) (xy 404.693093 -381.971364) (xy 404.745422 -381.986734) (xy 404.795031 -382.009394)
			(xy 404.840911 -382.038884) (xy 404.882127 -382.074602) (xy 404.91784 -382.115822) (xy 404.947325 -382.161704)
			(xy 404.96998 -382.211316) (xy 404.985344 -382.263646) (xy 404.993106 -382.31763) (xy 404.993106 -382.37217)
			(xy 404.993106 -382.372171) (xy 410.174132 -382.372171) (xy 410.174132 -382.317629) (xy 410.181894 -382.263643)
			(xy 410.197261 -382.211311) (xy 410.21992 -382.161699) (xy 410.249409 -382.115817) (xy 410.285128 -382.0746)
			(xy 410.32635 -382.038885) (xy 410.372235 -382.009401) (xy 410.421849 -381.986747) (xy 410.474182 -381.971386)
			(xy 410.528169 -381.963629) (xy 410.55544 -381.963168) (xy 411.41904 -381.963168) (xy 411.44631 -381.963597)
			(xy 411.500293 -381.971364) (xy 411.552622 -381.986734) (xy 411.602231 -382.009394) (xy 411.648111 -382.038884)
			(xy 411.689327 -382.074602) (xy 411.72504 -382.115822) (xy 411.754525 -382.161704) (xy 411.77718 -382.211316)
			(xy 411.792544 -382.263646) (xy 411.800306 -382.31763) (xy 411.800306 -382.37217) (xy 411.800306 -382.372171)
			(xy 416.981332 -382.372171) (xy 416.981332 -382.317629) (xy 416.989094 -382.263643) (xy 417.004461 -382.211311)
			(xy 417.02712 -382.161699) (xy 417.056609 -382.115817) (xy 417.092328 -382.0746) (xy 417.13355 -382.038885)
			(xy 417.179435 -382.009401) (xy 417.229049 -381.986747) (xy 417.281382 -381.971386) (xy 417.335369 -381.963629)
			(xy 417.36264 -381.963168) (xy 418.22624 -381.963168) (xy 418.25351 -381.963597) (xy 418.307493 -381.971364)
			(xy 418.359822 -381.986734) (xy 418.409431 -382.009394) (xy 418.455311 -382.038884) (xy 418.496527 -382.074602)
			(xy 418.53224 -382.115822) (xy 418.561725 -382.161704) (xy 418.58438 -382.211316) (xy 418.599744 -382.263646)
			(xy 418.607506 -382.31763) (xy 418.607506 -382.37217) (xy 418.599744 -382.426154) (xy 418.58438 -382.478484)
			(xy 418.561725 -382.528096) (xy 418.53224 -382.573978) (xy 418.496527 -382.615198) (xy 418.455311 -382.650916)
			(xy 418.409431 -382.680406) (xy 418.359822 -382.703066) (xy 418.307493 -382.718436) (xy 418.25351 -382.726203)
			(xy 418.22624 -382.726692) (xy 417.36264 -382.726692) (xy 417.335369 -382.726171) (xy 417.281382 -382.718414)
			(xy 417.229049 -382.703053) (xy 417.179435 -382.680399) (xy 417.13355 -382.650915) (xy 417.092328 -382.6152)
			(xy 417.056609 -382.573983) (xy 417.02712 -382.528101) (xy 417.004461 -382.478489) (xy 416.989094 -382.426157)
			(xy 416.981332 -382.372171) (xy 411.800306 -382.372171) (xy 411.792544 -382.426154) (xy 411.77718 -382.478484)
			(xy 411.754525 -382.528096) (xy 411.72504 -382.573978) (xy 411.689327 -382.615198) (xy 411.648111 -382.650916)
			(xy 411.602231 -382.680406) (xy 411.552622 -382.703066) (xy 411.500293 -382.718436) (xy 411.44631 -382.726203)
			(xy 411.41904 -382.726692) (xy 410.55544 -382.726692) (xy 410.528169 -382.726171) (xy 410.474182 -382.718414)
			(xy 410.421849 -382.703053) (xy 410.372235 -382.680399) (xy 410.32635 -382.650915) (xy 410.285128 -382.6152)
			(xy 410.249409 -382.573983) (xy 410.21992 -382.528101) (xy 410.197261 -382.478489) (xy 410.181894 -382.426157)
			(xy 410.174132 -382.372171) (xy 404.993106 -382.372171) (xy 404.985344 -382.426154) (xy 404.96998 -382.478484)
			(xy 404.947325 -382.528096) (xy 404.91784 -382.573978) (xy 404.882127 -382.615198) (xy 404.840911 -382.650916)
			(xy 404.795031 -382.680406) (xy 404.745422 -382.703066) (xy 404.693093 -382.718436) (xy 404.63911 -382.726203)
			(xy 404.61184 -382.726692) (xy 403.74824 -382.726692) (xy 403.720969 -382.726171) (xy 403.666982 -382.718414)
			(xy 403.614649 -382.703053) (xy 403.565035 -382.680399) (xy 403.51915 -382.650915) (xy 403.477928 -382.6152)
			(xy 403.442209 -382.573983) (xy 403.41272 -382.528101) (xy 403.390061 -382.478489) (xy 403.374694 -382.426157)
			(xy 403.366932 -382.372171) (xy 386.079828 -382.372171) (xy 386.079828 -382.372174) (xy 386.072065 -382.426165)
			(xy 386.056698 -382.478503) (xy 386.034038 -382.52812) (xy 386.004547 -382.574008) (xy 385.968826 -382.615232)
			(xy 385.927602 -382.650952) (xy 385.881713 -382.680441) (xy 385.832095 -382.7031) (xy 385.779757 -382.718467)
			(xy 385.725766 -382.726229) (xy 385.698492 -382.726692) (xy 384.834892 -382.726692) (xy 384.807625 -382.726145)
			(xy 384.753647 -382.718383) (xy 384.701322 -382.703018) (xy 384.651717 -382.680363) (xy 384.605841 -382.65088)
			(xy 384.564627 -382.615167) (xy 384.528916 -382.573953) (xy 384.499433 -382.528076) (xy 384.476779 -382.47847)
			(xy 384.461415 -382.426146) (xy 384.453654 -382.372167) (xy 379.272628 -382.372167) (xy 379.272628 -382.372174)
			(xy 379.264865 -382.426165) (xy 379.249498 -382.478503) (xy 379.226838 -382.52812) (xy 379.197347 -382.574008)
			(xy 379.161626 -382.615232) (xy 379.120402 -382.650952) (xy 379.074513 -382.680441) (xy 379.024895 -382.7031)
			(xy 378.972557 -382.718467) (xy 378.918566 -382.726229) (xy 378.891292 -382.726692) (xy 378.027692 -382.726692)
			(xy 378.000425 -382.726145) (xy 377.946447 -382.718383) (xy 377.894122 -382.703018) (xy 377.844517 -382.680363)
			(xy 377.798641 -382.65088) (xy 377.757427 -382.615167) (xy 377.721716 -382.573953) (xy 377.692233 -382.528076)
			(xy 377.669579 -382.47847) (xy 377.654215 -382.426146) (xy 377.646454 -382.372167) (xy 372.465428 -382.372167)
			(xy 372.465428 -382.372174) (xy 372.457665 -382.426165) (xy 372.442298 -382.478503) (xy 372.419638 -382.52812)
			(xy 372.390147 -382.574008) (xy 372.354426 -382.615232) (xy 372.313202 -382.650952) (xy 372.267313 -382.680441)
			(xy 372.217695 -382.7031) (xy 372.165357 -382.718467) (xy 372.111366 -382.726229) (xy 372.084092 -382.726692)
			(xy 371.220492 -382.726692) (xy 371.193225 -382.726145) (xy 371.139247 -382.718383) (xy 371.086922 -382.703018)
			(xy 371.037317 -382.680363) (xy 370.991441 -382.65088) (xy 370.950227 -382.615167) (xy 370.914516 -382.573953)
			(xy 370.885033 -382.528076) (xy 370.862379 -382.47847) (xy 370.847015 -382.426146) (xy 370.839254 -382.372167)
			(xy 351.507306 -382.372167) (xy 351.507306 -382.37217) (xy 351.499544 -382.426153) (xy 351.48418 -382.478484)
			(xy 351.461525 -382.528095) (xy 351.432041 -382.573977) (xy 351.396328 -382.615197) (xy 351.355112 -382.650915)
			(xy 351.309233 -382.680404) (xy 351.259625 -382.703065) (xy 351.207297 -382.718435) (xy 351.153313 -382.726202)
			(xy 351.126044 -382.726692) (xy 350.262444 -382.726692) (xy 350.235173 -382.726172) (xy 350.181186 -382.718415)
			(xy 350.128852 -382.703054) (xy 350.079237 -382.680401) (xy 350.033351 -382.650916) (xy 349.992129 -382.615202)
			(xy 349.95641 -382.573984) (xy 349.926921 -382.528102) (xy 349.904261 -382.478489) (xy 349.888894 -382.426157)
			(xy 349.881132 -382.372171) (xy 344.700106 -382.372171) (xy 344.692344 -382.426153) (xy 344.67698 -382.478484)
			(xy 344.654325 -382.528095) (xy 344.624841 -382.573977) (xy 344.589128 -382.615197) (xy 344.547912 -382.650915)
			(xy 344.502033 -382.680404) (xy 344.452425 -382.703065) (xy 344.400097 -382.718435) (xy 344.346113 -382.726202)
			(xy 344.318844 -382.726692) (xy 343.455244 -382.726692) (xy 343.427973 -382.726172) (xy 343.373986 -382.718415)
			(xy 343.321652 -382.703054) (xy 343.272037 -382.680401) (xy 343.226151 -382.650916) (xy 343.184929 -382.615202)
			(xy 343.14921 -382.573984) (xy 343.119721 -382.528102) (xy 343.097061 -382.478489) (xy 343.081694 -382.426157)
			(xy 343.073932 -382.372171) (xy 337.892906 -382.372171) (xy 337.885144 -382.426153) (xy 337.86978 -382.478484)
			(xy 337.847125 -382.528095) (xy 337.817641 -382.573977) (xy 337.781928 -382.615197) (xy 337.740712 -382.650915)
			(xy 337.694833 -382.680404) (xy 337.645225 -382.703065) (xy 337.592897 -382.718435) (xy 337.538913 -382.726202)
			(xy 337.511644 -382.726692) (xy 336.648044 -382.726692) (xy 336.620773 -382.726172) (xy 336.566786 -382.718415)
			(xy 336.514452 -382.703054) (xy 336.464837 -382.680401) (xy 336.418951 -382.650916) (xy 336.377729 -382.615202)
			(xy 336.34201 -382.573984) (xy 336.312521 -382.528102) (xy 336.289861 -382.478489) (xy 336.274494 -382.426157)
			(xy 336.266732 -382.372171) (xy 318.979628 -382.372171) (xy 318.979628 -382.372173) (xy 318.971866 -382.426165)
			(xy 318.956498 -382.478502) (xy 318.933838 -382.528119) (xy 318.904348 -382.574007) (xy 318.868627 -382.61523)
			(xy 318.827403 -382.65095) (xy 318.781516 -382.68044) (xy 318.731898 -382.703099) (xy 318.679561 -382.718466)
			(xy 318.625569 -382.726229) (xy 318.598296 -382.726692) (xy 317.734696 -382.726692) (xy 317.707429 -382.726145)
			(xy 317.65345 -382.718384) (xy 317.601125 -382.703019) (xy 317.551519 -382.680365) (xy 317.505642 -382.650881)
			(xy 317.464429 -382.615169) (xy 317.428717 -382.573954) (xy 317.399233 -382.528077) (xy 317.376579 -382.478471)
			(xy 317.361215 -382.426146) (xy 317.353454 -382.372167) (xy 312.172428 -382.372167) (xy 312.172428 -382.372173)
			(xy 312.164666 -382.426165) (xy 312.149298 -382.478502) (xy 312.126638 -382.528119) (xy 312.097148 -382.574007)
			(xy 312.061427 -382.61523) (xy 312.020203 -382.65095) (xy 311.974316 -382.68044) (xy 311.924698 -382.703099)
			(xy 311.872361 -382.718466) (xy 311.818369 -382.726229) (xy 311.791096 -382.726692) (xy 310.927496 -382.726692)
			(xy 310.900229 -382.726145) (xy 310.84625 -382.718384) (xy 310.793925 -382.703019) (xy 310.744319 -382.680365)
			(xy 310.698442 -382.650881) (xy 310.657229 -382.615169) (xy 310.621517 -382.573954) (xy 310.592033 -382.528077)
			(xy 310.569379 -382.478471) (xy 310.554015 -382.426146) (xy 310.546254 -382.372167) (xy 305.365228 -382.372167)
			(xy 305.365228 -382.372173) (xy 305.357466 -382.426165) (xy 305.342098 -382.478502) (xy 305.319438 -382.528119)
			(xy 305.289948 -382.574007) (xy 305.254227 -382.61523) (xy 305.213003 -382.65095) (xy 305.167116 -382.68044)
			(xy 305.117498 -382.703099) (xy 305.065161 -382.718466) (xy 305.011169 -382.726229) (xy 304.983896 -382.726692)
			(xy 304.120296 -382.726692) (xy 304.093029 -382.726145) (xy 304.03905 -382.718384) (xy 303.986725 -382.703019)
			(xy 303.937119 -382.680365) (xy 303.891242 -382.650881) (xy 303.850029 -382.615169) (xy 303.814317 -382.573954)
			(xy 303.784833 -382.528077) (xy 303.762179 -382.478471) (xy 303.746815 -382.426146) (xy 303.739054 -382.372167)
			(xy 294.194727 -382.372167) (xy 294.264676 -382.460745) (xy 294.368827 -382.605448) (xy 294.466429 -382.754647)
			(xy 294.557287 -382.908046) (xy 294.641221 -383.06534) (xy 294.718066 -383.226216) (xy 294.787667 -383.390357)
			(xy 294.849888 -383.557434) (xy 294.904604 -383.727118) (xy 294.951706 -383.899071) (xy 294.991102 -384.072951)
			(xy 295.022713 -384.248414) (xy 295.046477 -384.42511) (xy 295.062345 -384.60269) (xy 295.070287 -384.7808)
			(xy 295.070784 -384.869944) (xy 295.070287 -384.959088) (xy 295.062345 -385.137198) (xy 295.055495 -385.21386)
			(xy 297.048936 -385.21386) (xy 297.048936 -384.35026) (xy 297.049422 -384.323009) (xy 297.057178 -384.269061)
			(xy 297.072533 -384.216766) (xy 297.095175 -384.167189) (xy 297.124641 -384.121339) (xy 297.160332 -384.080148)
			(xy 297.201523 -384.044457) (xy 297.247373 -384.014991) (xy 297.29695 -383.992349) (xy 297.349245 -383.976994)
			(xy 297.403193 -383.969238) (xy 297.457695 -383.969238) (xy 297.511643 -383.976994) (xy 297.563938 -383.992349)
			(xy 297.613515 -384.014991) (xy 297.659365 -384.044457) (xy 297.700556 -384.080148) (xy 297.736247 -384.121339)
			(xy 297.765713 -384.167189) (xy 297.788355 -384.216766) (xy 297.80371 -384.269061) (xy 297.811466 -384.323009)
			(xy 297.811952 -384.35026) (xy 297.811952 -385.21386) (xy 297.811466 -385.241111) (xy 297.80371 -385.295059)
			(xy 297.790858 -385.338828) (xy 326.895968 -385.338828) (xy 326.895968 -384.475228) (xy 326.896454 -384.447977)
			(xy 326.90421 -384.394029) (xy 326.919565 -384.341734) (xy 326.942207 -384.292157) (xy 326.971673 -384.246307)
			(xy 327.007364 -384.205116) (xy 327.048555 -384.169425) (xy 327.094405 -384.139959) (xy 327.143982 -384.117317)
			(xy 327.196277 -384.101962) (xy 327.250225 -384.094206) (xy 327.304727 -384.094206) (xy 327.358675 -384.101962)
			(xy 327.41097 -384.117317) (xy 327.460547 -384.139959) (xy 327.506397 -384.169425) (xy 327.547588 -384.205116)
			(xy 327.583279 -384.246307) (xy 327.612745 -384.292157) (xy 327.635387 -384.341734) (xy 327.650742 -384.394029)
			(xy 327.658498 -384.447977) (xy 327.658984 -384.475228) (xy 327.658984 -385.21386) (xy 329.576684 -385.21386)
			(xy 329.576684 -384.35026) (xy 329.57717 -384.323009) (xy 329.584926 -384.269061) (xy 329.600281 -384.216766)
			(xy 329.622923 -384.167189) (xy 329.652389 -384.121339) (xy 329.68808 -384.080148) (xy 329.729271 -384.044457)
			(xy 329.775121 -384.014991) (xy 329.824698 -383.992349) (xy 329.876993 -383.976994) (xy 329.930941 -383.969238)
			(xy 329.985443 -383.969238) (xy 330.039391 -383.976994) (xy 330.091686 -383.992349) (xy 330.141263 -384.014991)
			(xy 330.187113 -384.044457) (xy 330.228304 -384.080148) (xy 330.263995 -384.121339) (xy 330.293461 -384.167189)
			(xy 330.316103 -384.216766) (xy 330.331458 -384.269061) (xy 330.339214 -384.323009) (xy 330.3397 -384.35026)
			(xy 330.3397 -385.21386) (xy 330.339214 -385.241111) (xy 330.331458 -385.295059) (xy 330.318606 -385.338828)
			(xy 359.423716 -385.338828) (xy 359.423716 -384.475228) (xy 359.424202 -384.447977) (xy 359.431958 -384.394029)
			(xy 359.447313 -384.341734) (xy 359.469955 -384.292157) (xy 359.499421 -384.246307) (xy 359.535112 -384.205116)
			(xy 359.576303 -384.169425) (xy 359.622153 -384.139959) (xy 359.67173 -384.117317) (xy 359.724025 -384.101962)
			(xy 359.777973 -384.094206) (xy 359.832475 -384.094206) (xy 359.886423 -384.101962) (xy 359.938718 -384.117317)
			(xy 359.988295 -384.139959) (xy 360.034145 -384.169425) (xy 360.075336 -384.205116) (xy 360.111027 -384.246307)
			(xy 360.140493 -384.292157) (xy 360.163135 -384.341734) (xy 360.17849 -384.394029) (xy 360.186246 -384.447977)
			(xy 360.186732 -384.475228) (xy 360.186732 -385.21386) (xy 364.149132 -385.21386) (xy 364.149132 -384.35026)
			(xy 364.149618 -384.323009) (xy 364.157374 -384.269061) (xy 364.172729 -384.216766) (xy 364.195371 -384.167189)
			(xy 364.224837 -384.121339) (xy 364.260528 -384.080148) (xy 364.301719 -384.044457) (xy 364.347569 -384.014991)
			(xy 364.397146 -383.992349) (xy 364.449441 -383.976994) (xy 364.503389 -383.969238) (xy 364.557891 -383.969238)
			(xy 364.611839 -383.976994) (xy 364.664134 -383.992349) (xy 364.713711 -384.014991) (xy 364.759561 -384.044457)
			(xy 364.800752 -384.080148) (xy 364.836443 -384.121339) (xy 364.865909 -384.167189) (xy 364.888551 -384.216766)
			(xy 364.903906 -384.269061) (xy 364.911662 -384.323009) (xy 364.912148 -384.35026) (xy 364.912148 -385.21386)
			(xy 364.911662 -385.241111) (xy 364.903906 -385.295059) (xy 364.891054 -385.338828) (xy 393.996164 -385.338828)
			(xy 393.996164 -384.475228) (xy 393.99665 -384.447977) (xy 394.004406 -384.394029) (xy 394.019761 -384.341734)
			(xy 394.042403 -384.292157) (xy 394.071869 -384.246307) (xy 394.10756 -384.205116) (xy 394.148751 -384.169425)
			(xy 394.194601 -384.139959) (xy 394.244178 -384.117317) (xy 394.296473 -384.101962) (xy 394.350421 -384.094206)
			(xy 394.404923 -384.094206) (xy 394.458871 -384.101962) (xy 394.511166 -384.117317) (xy 394.560743 -384.139959)
			(xy 394.606593 -384.169425) (xy 394.647784 -384.205116) (xy 394.683475 -384.246307) (xy 394.712941 -384.292157)
			(xy 394.735583 -384.341734) (xy 394.750938 -384.394029) (xy 394.758694 -384.447977) (xy 394.75918 -384.475228)
			(xy 394.75918 -385.21386) (xy 396.67688 -385.21386) (xy 396.67688 -384.35026) (xy 396.677366 -384.323009)
			(xy 396.685122 -384.269061) (xy 396.700477 -384.216766) (xy 396.723119 -384.167189) (xy 396.752585 -384.121339)
			(xy 396.788276 -384.080148) (xy 396.829467 -384.044457) (xy 396.875317 -384.014991) (xy 396.924894 -383.992349)
			(xy 396.977189 -383.976994) (xy 397.031137 -383.969238) (xy 397.085639 -383.969238) (xy 397.139587 -383.976994)
			(xy 397.191882 -383.992349) (xy 397.241459 -384.014991) (xy 397.287309 -384.044457) (xy 397.3285 -384.080148)
			(xy 397.364191 -384.121339) (xy 397.393657 -384.167189) (xy 397.416299 -384.216766) (xy 397.431654 -384.269061)
			(xy 397.43941 -384.323009) (xy 397.439896 -384.35026) (xy 397.439896 -385.21386) (xy 397.43941 -385.241111)
			(xy 397.431654 -385.295059) (xy 397.418802 -385.338828) (xy 426.523912 -385.338828) (xy 426.523912 -384.475228)
			(xy 426.524398 -384.447977) (xy 426.532154 -384.394029) (xy 426.547509 -384.341734) (xy 426.570151 -384.292157)
			(xy 426.599617 -384.246307) (xy 426.635308 -384.205116) (xy 426.676499 -384.169425) (xy 426.722349 -384.139959)
			(xy 426.771926 -384.117317) (xy 426.824221 -384.101962) (xy 426.878169 -384.094206) (xy 426.932671 -384.094206)
			(xy 426.986619 -384.101962) (xy 427.038914 -384.117317) (xy 427.088491 -384.139959) (xy 427.134341 -384.169425)
			(xy 427.175532 -384.205116) (xy 427.211223 -384.246307) (xy 427.240689 -384.292157) (xy 427.263331 -384.341734)
			(xy 427.278686 -384.394029) (xy 427.286442 -384.447977) (xy 427.286928 -384.475228) (xy 427.286928 -384.869944)
			(xy 429.498772 -384.869944) (xy 429.502744 -384.691701) (xy 429.514652 -384.513812) (xy 429.534473 -384.33663)
			(xy 429.562167 -384.160506) (xy 429.597679 -383.985791) (xy 429.640939 -383.812832) (xy 429.691861 -383.641971)
			(xy 429.750344 -383.473549) (xy 429.816271 -383.307899) (xy 429.889512 -383.14535) (xy 429.969922 -382.986225)
			(xy 430.05734 -382.83084) (xy 430.151593 -382.679504) (xy 430.252494 -382.532516) (xy 430.359843 -382.390169)
			(xy 430.473426 -382.252746) (xy 430.593019 -382.120519) (xy 430.718383 -381.99375) (xy 430.84927 -381.872692)
			(xy 430.985419 -381.757585) (xy 431.126561 -381.648657) (xy 431.272416 -381.546125) (xy 431.422693 -381.450191)
			(xy 431.577094 -381.361048) (xy 431.735313 -381.278871) (xy 431.897036 -381.203823) (xy 432.061941 -381.136055)
			(xy 432.229702 -381.075699) (xy 432.399985 -381.022877) (xy 432.572452 -380.977693) (xy 432.74676 -380.940236)
			(xy 432.922564 -380.910582) (xy 433.099514 -380.888789) (xy 433.27726 -380.874899) (xy 433.455447 -380.868942)
			(xy 433.633724 -380.870928) (xy 433.811735 -380.880854) (xy 433.989127 -380.8987) (xy 434.165547 -380.92443)
			(xy 434.340647 -380.957994) (xy 434.514078 -380.999324) (xy 434.685495 -381.04834) (xy 434.854558 -381.104942)
			(xy 435.020933 -381.16902) (xy 435.184287 -381.240446) (xy 435.344298 -381.319078) (xy 435.500647 -381.404759)
			(xy 435.653024 -381.497321) (xy 435.801127 -381.596578) (xy 435.944661 -381.702335) (xy 436.083341 -381.81438)
			(xy 436.216892 -381.932492) (xy 436.345049 -382.056436) (xy 436.467558 -382.185966) (xy 436.584175 -382.320825)
			(xy 436.694668 -382.460745) (xy 436.798819 -382.605448) (xy 436.896421 -382.754647) (xy 436.987279 -382.908046)
			(xy 437.071213 -383.06534) (xy 437.148058 -383.226216) (xy 437.217659 -383.390357) (xy 437.27988 -383.557434)
			(xy 437.334596 -383.727118) (xy 437.381698 -383.899071) (xy 437.421094 -384.072951) (xy 437.452705 -384.248414)
			(xy 437.476469 -384.42511) (xy 437.492337 -384.60269) (xy 437.500279 -384.7808) (xy 437.500776 -384.869944)
			(xy 437.500279 -384.959088) (xy 437.492337 -385.137198) (xy 437.476469 -385.314778) (xy 437.452705 -385.491474)
			(xy 437.421094 -385.666937) (xy 437.381698 -385.840817) (xy 437.334596 -386.01277) (xy 437.27988 -386.182454)
			(xy 437.217659 -386.349531) (xy 437.148058 -386.513672) (xy 437.071213 -386.674548) (xy 436.987279 -386.831842)
			(xy 436.896421 -386.985241) (xy 436.798819 -387.13444) (xy 436.694668 -387.279143) (xy 436.584175 -387.419063)
			(xy 436.467558 -387.553922) (xy 436.345049 -387.683452) (xy 436.216892 -387.807396) (xy 436.083341 -387.925508)
			(xy 435.944661 -388.037553) (xy 435.801127 -388.14331) (xy 435.653024 -388.242567) (xy 435.500647 -388.335129)
			(xy 435.344298 -388.42081) (xy 435.184287 -388.499442) (xy 435.020933 -388.570868) (xy 434.854558 -388.634946)
			(xy 434.685495 -388.691548) (xy 434.514078 -388.740564) (xy 434.340647 -388.781894) (xy 434.165547 -388.815458)
			(xy 433.989127 -388.841188) (xy 433.811735 -388.859034) (xy 433.633724 -388.86896) (xy 433.455447 -388.870946)
			(xy 433.27726 -388.864989) (xy 433.099514 -388.851099) (xy 432.922564 -388.829306) (xy 432.74676 -388.799652)
			(xy 432.572452 -388.762195) (xy 432.399985 -388.717011) (xy 432.229702 -388.664189) (xy 432.061941 -388.603833)
			(xy 431.897036 -388.536065) (xy 431.735313 -388.461017) (xy 431.577094 -388.37884) (xy 431.422693 -388.289697)
			(xy 431.272416 -388.193763) (xy 431.126561 -388.091231) (xy 430.985419 -387.982303) (xy 430.84927 -387.867196)
			(xy 430.718383 -387.746138) (xy 430.593019 -387.619369) (xy 430.473426 -387.487142) (xy 430.359843 -387.349719)
			(xy 430.252494 -387.207372) (xy 430.151593 -387.060384) (xy 430.05734 -386.909048) (xy 429.969922 -386.753663)
			(xy 429.889512 -386.594538) (xy 429.816271 -386.431989) (xy 429.750344 -386.266339) (xy 429.691861 -386.097917)
			(xy 429.640939 -385.927056) (xy 429.597679 -385.754097) (xy 429.562167 -385.579382) (xy 429.534473 -385.403258)
			(xy 429.514652 -385.226076) (xy 429.502744 -385.048187) (xy 429.498772 -384.869944) (xy 427.286928 -384.869944)
			(xy 427.286928 -385.338828) (xy 427.286442 -385.366079) (xy 427.278686 -385.420027) (xy 427.263331 -385.472322)
			(xy 427.240689 -385.521899) (xy 427.211223 -385.567749) (xy 427.175532 -385.60894) (xy 427.134341 -385.644631)
			(xy 427.088491 -385.674097) (xy 427.038914 -385.696739) (xy 426.986619 -385.712094) (xy 426.932671 -385.71985)
			(xy 426.878169 -385.71985) (xy 426.824221 -385.712094) (xy 426.771926 -385.696739) (xy 426.722349 -385.674097)
			(xy 426.676499 -385.644631) (xy 426.635308 -385.60894) (xy 426.599617 -385.567749) (xy 426.570151 -385.521899)
			(xy 426.547509 -385.472322) (xy 426.532154 -385.420027) (xy 426.524398 -385.366079) (xy 426.523912 -385.338828)
			(xy 397.418802 -385.338828) (xy 397.416299 -385.347354) (xy 397.393657 -385.396931) (xy 397.364191 -385.442781)
			(xy 397.3285 -385.483972) (xy 397.287309 -385.519663) (xy 397.241459 -385.549129) (xy 397.191882 -385.571771)
			(xy 397.139587 -385.587126) (xy 397.085639 -385.594882) (xy 397.031137 -385.594882) (xy 396.977189 -385.587126)
			(xy 396.924894 -385.571771) (xy 396.875317 -385.549129) (xy 396.829467 -385.519663) (xy 396.788276 -385.483972)
			(xy 396.752585 -385.442781) (xy 396.723119 -385.396931) (xy 396.700477 -385.347354) (xy 396.685122 -385.295059)
			(xy 396.677366 -385.241111) (xy 396.67688 -385.21386) (xy 394.75918 -385.21386) (xy 394.75918 -385.338828)
			(xy 394.758694 -385.366079) (xy 394.750938 -385.420027) (xy 394.735583 -385.472322) (xy 394.712941 -385.521899)
			(xy 394.683475 -385.567749) (xy 394.647784 -385.60894) (xy 394.606593 -385.644631) (xy 394.560743 -385.674097)
			(xy 394.511166 -385.696739) (xy 394.458871 -385.712094) (xy 394.404923 -385.71985) (xy 394.350421 -385.71985)
			(xy 394.296473 -385.712094) (xy 394.244178 -385.696739) (xy 394.194601 -385.674097) (xy 394.148751 -385.644631)
			(xy 394.10756 -385.60894) (xy 394.071869 -385.567749) (xy 394.042403 -385.521899) (xy 394.019761 -385.472322)
			(xy 394.004406 -385.420027) (xy 393.99665 -385.366079) (xy 393.996164 -385.338828) (xy 364.891054 -385.338828)
			(xy 364.888551 -385.347354) (xy 364.865909 -385.396931) (xy 364.836443 -385.442781) (xy 364.800752 -385.483972)
			(xy 364.759561 -385.519663) (xy 364.713711 -385.549129) (xy 364.664134 -385.571771) (xy 364.611839 -385.587126)
			(xy 364.557891 -385.594882) (xy 364.503389 -385.594882) (xy 364.449441 -385.587126) (xy 364.397146 -385.571771)
			(xy 364.347569 -385.549129) (xy 364.301719 -385.519663) (xy 364.260528 -385.483972) (xy 364.224837 -385.442781)
			(xy 364.195371 -385.396931) (xy 364.172729 -385.347354) (xy 364.157374 -385.295059) (xy 364.149618 -385.241111)
			(xy 364.149132 -385.21386) (xy 360.186732 -385.21386) (xy 360.186732 -385.338828) (xy 360.186246 -385.366079)
			(xy 360.17849 -385.420027) (xy 360.163135 -385.472322) (xy 360.140493 -385.521899) (xy 360.111027 -385.567749)
			(xy 360.075336 -385.60894) (xy 360.034145 -385.644631) (xy 359.988295 -385.674097) (xy 359.938718 -385.696739)
			(xy 359.886423 -385.712094) (xy 359.832475 -385.71985) (xy 359.777973 -385.71985) (xy 359.724025 -385.712094)
			(xy 359.67173 -385.696739) (xy 359.622153 -385.674097) (xy 359.576303 -385.644631) (xy 359.535112 -385.60894)
			(xy 359.499421 -385.567749) (xy 359.469955 -385.521899) (xy 359.447313 -385.472322) (xy 359.431958 -385.420027)
			(xy 359.424202 -385.366079) (xy 359.423716 -385.338828) (xy 330.318606 -385.338828) (xy 330.316103 -385.347354)
			(xy 330.293461 -385.396931) (xy 330.263995 -385.442781) (xy 330.228304 -385.483972) (xy 330.187113 -385.519663)
			(xy 330.141263 -385.549129) (xy 330.091686 -385.571771) (xy 330.039391 -385.587126) (xy 329.985443 -385.594882)
			(xy 329.930941 -385.594882) (xy 329.876993 -385.587126) (xy 329.824698 -385.571771) (xy 329.775121 -385.549129)
			(xy 329.729271 -385.519663) (xy 329.68808 -385.483972) (xy 329.652389 -385.442781) (xy 329.622923 -385.396931)
			(xy 329.600281 -385.347354) (xy 329.584926 -385.295059) (xy 329.57717 -385.241111) (xy 329.576684 -385.21386)
			(xy 327.658984 -385.21386) (xy 327.658984 -385.338828) (xy 327.658498 -385.366079) (xy 327.650742 -385.420027)
			(xy 327.635387 -385.472322) (xy 327.612745 -385.521899) (xy 327.583279 -385.567749) (xy 327.547588 -385.60894)
			(xy 327.506397 -385.644631) (xy 327.460547 -385.674097) (xy 327.41097 -385.696739) (xy 327.358675 -385.712094)
			(xy 327.304727 -385.71985) (xy 327.250225 -385.71985) (xy 327.196277 -385.712094) (xy 327.143982 -385.696739)
			(xy 327.094405 -385.674097) (xy 327.048555 -385.644631) (xy 327.007364 -385.60894) (xy 326.971673 -385.567749)
			(xy 326.942207 -385.521899) (xy 326.919565 -385.472322) (xy 326.90421 -385.420027) (xy 326.896454 -385.366079)
			(xy 326.895968 -385.338828) (xy 297.790858 -385.338828) (xy 297.788355 -385.347354) (xy 297.765713 -385.396931)
			(xy 297.736247 -385.442781) (xy 297.700556 -385.483972) (xy 297.659365 -385.519663) (xy 297.613515 -385.549129)
			(xy 297.563938 -385.571771) (xy 297.511643 -385.587126) (xy 297.457695 -385.594882) (xy 297.403193 -385.594882)
			(xy 297.349245 -385.587126) (xy 297.29695 -385.571771) (xy 297.247373 -385.549129) (xy 297.201523 -385.519663)
			(xy 297.160332 -385.483972) (xy 297.124641 -385.442781) (xy 297.095175 -385.396931) (xy 297.072533 -385.347354)
			(xy 297.057178 -385.295059) (xy 297.049422 -385.241111) (xy 297.048936 -385.21386) (xy 295.055495 -385.21386)
			(xy 295.046477 -385.314778) (xy 295.022713 -385.491474) (xy 294.991102 -385.666937) (xy 294.951706 -385.840817)
			(xy 294.904604 -386.01277) (xy 294.849888 -386.182454) (xy 294.787667 -386.349531) (xy 294.718066 -386.513672)
			(xy 294.641221 -386.674548) (xy 294.557287 -386.831842) (xy 294.466429 -386.985241) (xy 294.368827 -387.13444)
			(xy 294.264676 -387.279143) (xy 294.154183 -387.419063) (xy 294.037566 -387.553922) (xy 293.915057 -387.683452)
			(xy 293.7869 -387.807396) (xy 293.653349 -387.925508) (xy 293.514669 -388.037553) (xy 293.371135 -388.14331)
			(xy 293.223032 -388.242567) (xy 293.070655 -388.335129) (xy 292.914306 -388.42081) (xy 292.754295 -388.499442)
			(xy 292.590941 -388.570868) (xy 292.424566 -388.634946) (xy 292.255503 -388.691548) (xy 292.084086 -388.740564)
			(xy 292.076264 -388.742428) (xy 326.895968 -388.742428) (xy 326.895968 -387.878828) (xy 326.896454 -387.851577)
			(xy 326.90421 -387.797629) (xy 326.919565 -387.745334) (xy 326.942207 -387.695757) (xy 326.971673 -387.649907)
			(xy 327.007364 -387.608716) (xy 327.048555 -387.573025) (xy 327.094405 -387.543559) (xy 327.143982 -387.520917)
			(xy 327.196277 -387.505562) (xy 327.250225 -387.497806) (xy 327.304727 -387.497806) (xy 327.358675 -387.505562)
			(xy 327.41097 -387.520917) (xy 327.460547 -387.543559) (xy 327.506397 -387.573025) (xy 327.547588 -387.608716)
			(xy 327.583279 -387.649907) (xy 327.612745 -387.695757) (xy 327.635387 -387.745334) (xy 327.650742 -387.797629)
			(xy 327.658498 -387.851577) (xy 327.658984 -387.878828) (xy 327.658984 -388.742428) (xy 359.423716 -388.742428)
			(xy 359.423716 -387.878828) (xy 359.424202 -387.851577) (xy 359.431958 -387.797629) (xy 359.447313 -387.745334)
			(xy 359.469955 -387.695757) (xy 359.499421 -387.649907) (xy 359.535112 -387.608716) (xy 359.576303 -387.573025)
			(xy 359.622153 -387.543559) (xy 359.67173 -387.520917) (xy 359.724025 -387.505562) (xy 359.777973 -387.497806)
			(xy 359.832475 -387.497806) (xy 359.886423 -387.505562) (xy 359.938718 -387.520917) (xy 359.988295 -387.543559)
			(xy 360.034145 -387.573025) (xy 360.075336 -387.608716) (xy 360.111027 -387.649907) (xy 360.140493 -387.695757)
			(xy 360.163135 -387.745334) (xy 360.17849 -387.797629) (xy 360.186246 -387.851577) (xy 360.186732 -387.878828)
			(xy 360.186732 -388.742428) (xy 393.996164 -388.742428) (xy 393.996164 -387.878828) (xy 393.99665 -387.851577)
			(xy 394.004406 -387.797629) (xy 394.019761 -387.745334) (xy 394.042403 -387.695757) (xy 394.071869 -387.649907)
			(xy 394.10756 -387.608716) (xy 394.148751 -387.573025) (xy 394.194601 -387.543559) (xy 394.244178 -387.520917)
			(xy 394.296473 -387.505562) (xy 394.350421 -387.497806) (xy 394.404923 -387.497806) (xy 394.458871 -387.505562)
			(xy 394.511166 -387.520917) (xy 394.560743 -387.543559) (xy 394.606593 -387.573025) (xy 394.647784 -387.608716)
			(xy 394.683475 -387.649907) (xy 394.712941 -387.695757) (xy 394.735583 -387.745334) (xy 394.750938 -387.797629)
			(xy 394.758694 -387.851577) (xy 394.75918 -387.878828) (xy 394.75918 -388.742428) (xy 426.523912 -388.742428)
			(xy 426.523912 -387.878828) (xy 426.524398 -387.851577) (xy 426.532154 -387.797629) (xy 426.547509 -387.745334)
			(xy 426.570151 -387.695757) (xy 426.599617 -387.649907) (xy 426.635308 -387.608716) (xy 426.676499 -387.573025)
			(xy 426.722349 -387.543559) (xy 426.771926 -387.520917) (xy 426.824221 -387.505562) (xy 426.878169 -387.497806)
			(xy 426.932671 -387.497806) (xy 426.986619 -387.505562) (xy 427.038914 -387.520917) (xy 427.088491 -387.543559)
			(xy 427.134341 -387.573025) (xy 427.175532 -387.608716) (xy 427.211223 -387.649907) (xy 427.240689 -387.695757)
			(xy 427.263331 -387.745334) (xy 427.278686 -387.797629) (xy 427.286442 -387.851577) (xy 427.286928 -387.878828)
			(xy 427.286928 -388.742428) (xy 427.286442 -388.769679) (xy 427.278686 -388.823627) (xy 427.263331 -388.875922)
			(xy 427.240689 -388.925499) (xy 427.211223 -388.971349) (xy 427.175532 -389.01254) (xy 427.134341 -389.048231)
			(xy 427.088491 -389.077697) (xy 427.038914 -389.100339) (xy 426.986619 -389.115694) (xy 426.932671 -389.12345)
			(xy 426.878169 -389.12345) (xy 426.824221 -389.115694) (xy 426.771926 -389.100339) (xy 426.722349 -389.077697)
			(xy 426.676499 -389.048231) (xy 426.635308 -389.01254) (xy 426.599617 -388.971349) (xy 426.570151 -388.925499)
			(xy 426.547509 -388.875922) (xy 426.532154 -388.823627) (xy 426.524398 -388.769679) (xy 426.523912 -388.742428)
			(xy 394.75918 -388.742428) (xy 394.758694 -388.769679) (xy 394.750938 -388.823627) (xy 394.735583 -388.875922)
			(xy 394.712941 -388.925499) (xy 394.683475 -388.971349) (xy 394.647784 -389.01254) (xy 394.606593 -389.048231)
			(xy 394.560743 -389.077697) (xy 394.511166 -389.100339) (xy 394.458871 -389.115694) (xy 394.404923 -389.12345)
			(xy 394.350421 -389.12345) (xy 394.296473 -389.115694) (xy 394.244178 -389.100339) (xy 394.194601 -389.077697)
			(xy 394.148751 -389.048231) (xy 394.10756 -389.01254) (xy 394.071869 -388.971349) (xy 394.042403 -388.925499)
			(xy 394.019761 -388.875922) (xy 394.004406 -388.823627) (xy 393.99665 -388.769679) (xy 393.996164 -388.742428)
			(xy 360.186732 -388.742428) (xy 360.186246 -388.769679) (xy 360.17849 -388.823627) (xy 360.163135 -388.875922)
			(xy 360.140493 -388.925499) (xy 360.111027 -388.971349) (xy 360.075336 -389.01254) (xy 360.034145 -389.048231)
			(xy 359.988295 -389.077697) (xy 359.938718 -389.100339) (xy 359.886423 -389.115694) (xy 359.832475 -389.12345)
			(xy 359.777973 -389.12345) (xy 359.724025 -389.115694) (xy 359.67173 -389.100339) (xy 359.622153 -389.077697)
			(xy 359.576303 -389.048231) (xy 359.535112 -389.01254) (xy 359.499421 -388.971349) (xy 359.469955 -388.925499)
			(xy 359.447313 -388.875922) (xy 359.431958 -388.823627) (xy 359.424202 -388.769679) (xy 359.423716 -388.742428)
			(xy 327.658984 -388.742428) (xy 327.658498 -388.769679) (xy 327.650742 -388.823627) (xy 327.635387 -388.875922)
			(xy 327.612745 -388.925499) (xy 327.583279 -388.971349) (xy 327.547588 -389.01254) (xy 327.506397 -389.048231)
			(xy 327.460547 -389.077697) (xy 327.41097 -389.100339) (xy 327.358675 -389.115694) (xy 327.304727 -389.12345)
			(xy 327.250225 -389.12345) (xy 327.196277 -389.115694) (xy 327.143982 -389.100339) (xy 327.094405 -389.077697)
			(xy 327.048555 -389.048231) (xy 327.007364 -389.01254) (xy 326.971673 -388.971349) (xy 326.942207 -388.925499)
			(xy 326.919565 -388.875922) (xy 326.90421 -388.823627) (xy 326.896454 -388.769679) (xy 326.895968 -388.742428)
			(xy 292.076264 -388.742428) (xy 291.910655 -388.781894) (xy 291.735555 -388.815458) (xy 291.559135 -388.841188)
			(xy 291.381743 -388.859034) (xy 291.203732 -388.86896) (xy 291.025455 -388.870946) (xy 290.847268 -388.864989)
			(xy 290.669522 -388.851099) (xy 290.492572 -388.829306) (xy 290.316768 -388.799652) (xy 290.14246 -388.762195)
			(xy 289.969993 -388.717011) (xy 289.79971 -388.664189) (xy 289.631949 -388.603833) (xy 289.467044 -388.536065)
			(xy 289.305321 -388.461017) (xy 289.147102 -388.37884) (xy 288.992701 -388.289697) (xy 288.842424 -388.193763)
			(xy 288.696569 -388.091231) (xy 288.555427 -387.982303) (xy 288.419278 -387.867196) (xy 288.288391 -387.746138)
			(xy 288.163027 -387.619369) (xy 288.043434 -387.487142) (xy 287.929851 -387.349719) (xy 287.822502 -387.207372)
			(xy 287.721601 -387.060384) (xy 287.627348 -386.909048) (xy 287.53993 -386.753663) (xy 287.45952 -386.594538)
			(xy 287.386279 -386.431989) (xy 287.320352 -386.266339) (xy 287.261869 -386.097917) (xy 287.210947 -385.927056)
			(xy 287.167687 -385.754097) (xy 287.132175 -385.579382) (xy 287.104481 -385.403258) (xy 287.08466 -385.226076)
			(xy 287.072752 -385.048187) (xy 287.06878 -384.869944) (xy 281.2288 -384.869944) (xy 281.2288 -387.375146)
			(xy 281.245056 -387.400292) (xy 281.258772 -387.406388) (xy 281.283524 -387.41805) (xy 281.329666 -387.447457)
			(xy 281.371135 -387.483154) (xy 281.407078 -387.524408) (xy 281.43676 -387.570374) (xy 281.45957 -387.620109)
			(xy 281.475042 -387.672592) (xy 281.482858 -387.726748) (xy 281.482857 -387.781464) (xy 281.47504 -387.835619)
			(xy 281.459566 -387.888102) (xy 281.436754 -387.937836) (xy 281.407071 -387.983801) (xy 281.371126 -388.025055)
			(xy 281.329657 -388.06075) (xy 281.283514 -388.090155) (xy 281.258772 -388.10184) (xy 281.245056 -388.107936)
			(xy 281.2288 -388.133082) (xy 281.2288 -390.75106) (xy 297.048936 -390.75106) (xy 297.048936 -389.88746)
			(xy 297.049422 -389.860209) (xy 297.057178 -389.806261) (xy 297.072533 -389.753966) (xy 297.095175 -389.704389)
			(xy 297.124641 -389.658539) (xy 297.160332 -389.617348) (xy 297.201523 -389.581657) (xy 297.247373 -389.552191)
			(xy 297.29695 -389.529549) (xy 297.349245 -389.514194) (xy 297.403193 -389.506438) (xy 297.457695 -389.506438)
			(xy 297.511643 -389.514194) (xy 297.563938 -389.529549) (xy 297.613515 -389.552191) (xy 297.659365 -389.581657)
			(xy 297.700556 -389.617348) (xy 297.736247 -389.658539) (xy 297.765713 -389.704389) (xy 297.788355 -389.753966)
			(xy 297.80371 -389.806261) (xy 297.811466 -389.860209) (xy 297.811952 -389.88746) (xy 297.811952 -390.75106)
			(xy 329.576684 -390.75106) (xy 329.576684 -389.88746) (xy 329.57717 -389.860209) (xy 329.584926 -389.806261)
			(xy 329.600281 -389.753966) (xy 329.622923 -389.704389) (xy 329.652389 -389.658539) (xy 329.68808 -389.617348)
			(xy 329.729271 -389.581657) (xy 329.775121 -389.552191) (xy 329.824698 -389.529549) (xy 329.876993 -389.514194)
			(xy 329.930941 -389.506438) (xy 329.985443 -389.506438) (xy 330.039391 -389.514194) (xy 330.091686 -389.529549)
			(xy 330.141263 -389.552191) (xy 330.187113 -389.581657) (xy 330.228304 -389.617348) (xy 330.263995 -389.658539)
			(xy 330.293461 -389.704389) (xy 330.316103 -389.753966) (xy 330.331458 -389.806261) (xy 330.339214 -389.860209)
			(xy 330.3397 -389.88746) (xy 330.3397 -390.75106) (xy 364.149132 -390.75106) (xy 364.149132 -389.88746)
			(xy 364.149618 -389.860209) (xy 364.157374 -389.806261) (xy 364.172729 -389.753966) (xy 364.195371 -389.704389)
			(xy 364.224837 -389.658539) (xy 364.260528 -389.617348) (xy 364.301719 -389.581657) (xy 364.347569 -389.552191)
			(xy 364.397146 -389.529549) (xy 364.449441 -389.514194) (xy 364.503389 -389.506438) (xy 364.557891 -389.506438)
			(xy 364.611839 -389.514194) (xy 364.664134 -389.529549) (xy 364.713711 -389.552191) (xy 364.759561 -389.581657)
			(xy 364.800752 -389.617348) (xy 364.836443 -389.658539) (xy 364.865909 -389.704389) (xy 364.888551 -389.753966)
			(xy 364.903906 -389.806261) (xy 364.911662 -389.860209) (xy 364.912148 -389.88746) (xy 364.912148 -390.75106)
			(xy 396.67688 -390.75106) (xy 396.67688 -389.88746) (xy 396.677366 -389.860209) (xy 396.685122 -389.806261)
			(xy 396.700477 -389.753966) (xy 396.723119 -389.704389) (xy 396.752585 -389.658539) (xy 396.788276 -389.617348)
			(xy 396.829467 -389.581657) (xy 396.875317 -389.552191) (xy 396.924894 -389.529549) (xy 396.977189 -389.514194)
			(xy 397.031137 -389.506438) (xy 397.085639 -389.506438) (xy 397.139587 -389.514194) (xy 397.191882 -389.529549)
			(xy 397.241459 -389.552191) (xy 397.287309 -389.581657) (xy 397.3285 -389.617348) (xy 397.364191 -389.658539)
			(xy 397.393657 -389.704389) (xy 397.416299 -389.753966) (xy 397.431654 -389.806261) (xy 397.43941 -389.860209)
			(xy 397.439896 -389.88746) (xy 397.439896 -390.75106) (xy 397.43941 -390.778311) (xy 397.431654 -390.832259)
			(xy 397.416299 -390.884554) (xy 397.393657 -390.934131) (xy 397.364191 -390.979981) (xy 397.3285 -391.021172)
			(xy 397.287309 -391.056863) (xy 397.241459 -391.086329) (xy 397.191882 -391.108971) (xy 397.139587 -391.124326)
			(xy 397.085639 -391.132082) (xy 397.031137 -391.132082) (xy 396.977189 -391.124326) (xy 396.924894 -391.108971)
			(xy 396.875317 -391.086329) (xy 396.829467 -391.056863) (xy 396.788276 -391.021172) (xy 396.752585 -390.979981)
			(xy 396.723119 -390.934131) (xy 396.700477 -390.884554) (xy 396.685122 -390.832259) (xy 396.677366 -390.778311)
			(xy 396.67688 -390.75106) (xy 364.912148 -390.75106) (xy 364.911662 -390.778311) (xy 364.903906 -390.832259)
			(xy 364.888551 -390.884554) (xy 364.865909 -390.934131) (xy 364.836443 -390.979981) (xy 364.800752 -391.021172)
			(xy 364.759561 -391.056863) (xy 364.713711 -391.086329) (xy 364.664134 -391.108971) (xy 364.611839 -391.124326)
			(xy 364.557891 -391.132082) (xy 364.503389 -391.132082) (xy 364.449441 -391.124326) (xy 364.397146 -391.108971)
			(xy 364.347569 -391.086329) (xy 364.301719 -391.056863) (xy 364.260528 -391.021172) (xy 364.224837 -390.979981)
			(xy 364.195371 -390.934131) (xy 364.172729 -390.884554) (xy 364.157374 -390.832259) (xy 364.149618 -390.778311)
			(xy 364.149132 -390.75106) (xy 330.3397 -390.75106) (xy 330.339214 -390.778311) (xy 330.331458 -390.832259)
			(xy 330.316103 -390.884554) (xy 330.293461 -390.934131) (xy 330.263995 -390.979981) (xy 330.228304 -391.021172)
			(xy 330.187113 -391.056863) (xy 330.141263 -391.086329) (xy 330.091686 -391.108971) (xy 330.039391 -391.124326)
			(xy 329.985443 -391.132082) (xy 329.930941 -391.132082) (xy 329.876993 -391.124326) (xy 329.824698 -391.108971)
			(xy 329.775121 -391.086329) (xy 329.729271 -391.056863) (xy 329.68808 -391.021172) (xy 329.652389 -390.979981)
			(xy 329.622923 -390.934131) (xy 329.600281 -390.884554) (xy 329.584926 -390.832259) (xy 329.57717 -390.778311)
			(xy 329.576684 -390.75106) (xy 297.811952 -390.75106) (xy 297.811466 -390.778311) (xy 297.80371 -390.832259)
			(xy 297.788355 -390.884554) (xy 297.765713 -390.934131) (xy 297.736247 -390.979981) (xy 297.700556 -391.021172)
			(xy 297.659365 -391.056863) (xy 297.613515 -391.086329) (xy 297.563938 -391.108971) (xy 297.511643 -391.124326)
			(xy 297.457695 -391.132082) (xy 297.403193 -391.132082) (xy 297.349245 -391.124326) (xy 297.29695 -391.108971)
			(xy 297.247373 -391.086329) (xy 297.201523 -391.056863) (xy 297.160332 -391.021172) (xy 297.124641 -390.979981)
			(xy 297.095175 -390.934131) (xy 297.072533 -390.884554) (xy 297.057178 -390.832259) (xy 297.049422 -390.778311)
			(xy 297.048936 -390.75106) (xy 281.2288 -390.75106) (xy 281.2288 -392.180572) (xy 281.228283 -392.20552)
			(xy 281.220475 -392.254803) (xy 281.205064 -392.30226) (xy 281.182426 -392.346726) (xy 281.153119 -392.387109)
			(xy 281.135836 -392.405108) (xy 280.810462 -392.730482) (xy 280.803632 -392.73789) (xy 280.795908 -392.756483)
			(xy 280.795476 -392.76655) (xy 280.795476 -393.110974) (xy 280.794938 -393.135921) (xy 280.787132 -393.185202)
			(xy 280.771724 -393.232658) (xy 280.749092 -393.277124) (xy 280.719792 -393.31751) (xy 280.702512 -393.33551)
			(xy 280.345134 -393.692888) (xy 303.485804 -393.692888) (xy 303.485804 -393.69238) (xy 303.486244 -393.668388)
			(xy 303.493754 -393.620994) (xy 303.508585 -393.575359) (xy 303.530372 -393.532605) (xy 303.558579 -393.493786)
			(xy 303.592511 -393.459858) (xy 303.631333 -393.431655) (xy 303.674088 -393.409872) (xy 303.719725 -393.395046)
			(xy 303.76712 -393.387542) (xy 303.791112 -393.387072) (xy 303.815046 -393.38757) (xy 303.862329 -393.395022)
			(xy 303.907871 -393.409757) (xy 303.950558 -393.431416) (xy 303.989344 -393.459467) (xy 304.02328 -393.493224)
			(xy 304.051536 -393.531861) (xy 304.062892 -393.552934) (xy 304.0634 -393.55395) (xy 304.143706 -393.692888)
			(xy 304.6857 -393.692888) (xy 304.6857 -393.69238) (xy 304.686144 -393.668388) (xy 304.693654 -393.620995)
			(xy 304.708484 -393.57536) (xy 304.730271 -393.532606) (xy 304.758477 -393.493788) (xy 304.792409 -393.459859)
			(xy 304.83123 -393.431656) (xy 304.873986 -393.409873) (xy 304.919622 -393.395047) (xy 304.967016 -393.387542)
			(xy 304.991008 -393.387072) (xy 305.014941 -393.387573) (xy 305.062224 -393.395024) (xy 305.107767 -393.409759)
			(xy 305.150453 -393.431417) (xy 305.189239 -393.459468) (xy 305.223176 -393.493224) (xy 305.251432 -393.531861)
			(xy 305.262788 -393.552934) (xy 305.263296 -393.55395) (xy 305.343602 -393.692888) (xy 305.885596 -393.692888)
			(xy 305.885596 -393.69238) (xy 305.886044 -393.668388) (xy 305.893553 -393.620995) (xy 305.908384 -393.575361)
			(xy 305.93017 -393.532608) (xy 305.958376 -393.493789) (xy 305.992307 -393.459861) (xy 306.031128 -393.431658)
			(xy 306.073883 -393.409875) (xy 306.119519 -393.395048) (xy 306.166912 -393.387542) (xy 306.190904 -393.387072)
			(xy 306.191158 -393.387072) (xy 306.215093 -393.387532) (xy 306.262378 -393.394992) (xy 306.307921 -393.409734)
			(xy 306.350607 -393.431398) (xy 306.389393 -393.459455) (xy 306.423328 -393.493217) (xy 306.451583 -393.531859)
			(xy 306.462938 -393.552934) (xy 306.463446 -393.55395) (xy 306.543752 -393.692888) (xy 307.085492 -393.692888)
			(xy 307.085492 -393.69238) (xy 307.085943 -393.668401) (xy 307.093444 -393.621033) (xy 307.108259 -393.57542)
			(xy 307.130023 -393.532685) (xy 307.158201 -393.493877) (xy 307.192099 -393.459953) (xy 307.230885 -393.431745)
			(xy 307.273604 -393.409949) (xy 307.319205 -393.395099) (xy 307.366567 -393.387562) (xy 307.390546 -393.387072)
			(xy 307.391054 -393.387072) (xy 307.414989 -393.387536) (xy 307.462274 -393.394994) (xy 307.507817 -393.409736)
			(xy 307.550503 -393.4314) (xy 307.589289 -393.459456) (xy 307.623224 -393.493218) (xy 307.651479 -393.531859)
			(xy 307.662834 -393.552934) (xy 307.663342 -393.55395) (xy 307.743648 -393.692888) (xy 308.285388 -393.692888)
			(xy 308.285388 -393.69238) (xy 308.285843 -393.668401) (xy 308.293344 -393.621034) (xy 308.308159 -393.575421)
			(xy 308.329922 -393.532686) (xy 308.358099 -393.493879) (xy 308.391998 -393.459954) (xy 308.430783 -393.431747)
			(xy 308.473501 -393.40995) (xy 308.519102 -393.3951) (xy 308.566463 -393.387562) (xy 308.590442 -393.387072)
			(xy 308.59095 -393.387072) (xy 308.614885 -393.387539) (xy 308.662169 -393.394997) (xy 308.707712 -393.409738)
			(xy 308.750399 -393.431401) (xy 308.789184 -393.459457) (xy 308.82312 -393.493218) (xy 308.851375 -393.531859)
			(xy 308.86273 -393.552934) (xy 308.863238 -393.55395) (xy 308.943544 -393.692888) (xy 309.485792 -393.692888)
			(xy 309.485792 -393.69238) (xy 309.486244 -393.668388) (xy 309.493753 -393.620996) (xy 309.508583 -393.575362)
			(xy 309.530369 -393.532609) (xy 309.558575 -393.49379) (xy 309.592506 -393.459862) (xy 309.631326 -393.431659)
			(xy 309.67408 -393.409876) (xy 309.719715 -393.395049) (xy 309.767108 -393.387543) (xy 309.7911 -393.387072)
			(xy 309.815033 -393.38758) (xy 309.862316 -393.39503) (xy 309.907858 -393.409764) (xy 309.950544 -393.43142)
			(xy 309.989331 -393.45947) (xy 310.023268 -393.493226) (xy 310.051524 -393.531862) (xy 310.06288 -393.552934)
			(xy 310.063388 -393.55395) (xy 310.143694 -393.692888) (xy 310.685688 -393.692888) (xy 310.685688 -393.69238)
			(xy 310.686144 -393.668388) (xy 310.693653 -393.620996) (xy 310.708483 -393.575362) (xy 310.730269 -393.53261)
			(xy 310.758474 -393.493792) (xy 310.792404 -393.459863) (xy 310.831224 -393.43166) (xy 310.873977 -393.409877)
			(xy 310.919612 -393.395049) (xy 310.967004 -393.387543) (xy 310.990996 -393.387072) (xy 311.014932 -393.387502)
			(xy 311.062218 -393.394966) (xy 311.107762 -393.409714) (xy 311.150449 -393.431384) (xy 311.189234 -393.459445)
			(xy 311.223168 -393.493212) (xy 311.251422 -393.531857) (xy 311.262776 -393.552934) (xy 311.263284 -393.55395)
			(xy 311.34359 -393.692888) (xy 311.885584 -393.692888) (xy 311.885584 -393.69238) (xy 311.886044 -393.668389)
			(xy 311.893553 -393.620997) (xy 311.908383 -393.575363) (xy 311.930168 -393.532611) (xy 311.958373 -393.493793)
			(xy 311.992302 -393.459865) (xy 312.031121 -393.431662) (xy 312.073874 -393.409878) (xy 312.119509 -393.39505)
			(xy 312.166901 -393.387543) (xy 312.190892 -393.387072) (xy 312.191146 -393.387072) (xy 312.215081 -393.387542)
			(xy 312.262365 -393.394999) (xy 312.307908 -393.40974) (xy 312.350594 -393.431403) (xy 312.38938 -393.459458)
			(xy 312.423316 -393.493219) (xy 312.451571 -393.531859) (xy 312.462926 -393.552934) (xy 312.463434 -393.55395)
			(xy 312.54374 -393.692888) (xy 313.08548 -393.692888) (xy 313.08548 -393.69238) (xy 313.085921 -393.668374)
			(xy 313.093438 -393.620955) (xy 313.108284 -393.575296) (xy 313.130093 -393.532524) (xy 313.158327 -393.493692)
			(xy 313.192291 -393.459757) (xy 313.231147 -393.431556) (xy 313.273939 -393.409783) (xy 313.31961 -393.394977)
			(xy 313.367036 -393.3875) (xy 313.391042 -393.387072) (xy 313.391296 -393.387072) (xy 313.415232 -393.387502)
			(xy 313.462518 -393.394966) (xy 313.508062 -393.409714) (xy 313.550749 -393.431384) (xy 313.589534 -393.459445)
			(xy 313.623468 -393.493212) (xy 313.651722 -393.531857) (xy 313.663076 -393.552934) (xy 313.663584 -393.55395)
			(xy 313.743156 -393.691618) (xy 314.284868 -393.691618) (xy 314.284868 -393.69111) (xy 314.285294 -393.667096)
			(xy 314.292806 -393.619658) (xy 314.307648 -393.57398) (xy 314.329452 -393.531186) (xy 314.357684 -393.492331)
			(xy 314.391646 -393.458371) (xy 314.430504 -393.430142) (xy 314.473299 -393.40834) (xy 314.518978 -393.393502)
			(xy 314.566416 -393.385992) (xy 314.59043 -393.385548) (xy 314.614379 -393.385999) (xy 314.66169 -393.393469)
			(xy 314.707254 -393.408237) (xy 314.749952 -393.429939) (xy 314.788737 -393.458044) (xy 314.822657 -393.491861)
			(xy 314.850878 -393.530561) (xy 314.86221 -393.551664) (xy 314.862718 -393.55268) (xy 314.943024 -393.691618)
			(xy 315.484764 -393.691618) (xy 315.484764 -393.69111) (xy 315.485194 -393.667096) (xy 315.492706 -393.619659)
			(xy 315.507547 -393.573981) (xy 315.529352 -393.531188) (xy 315.557583 -393.492332) (xy 315.591545 -393.458372)
			(xy 315.630401 -393.430143) (xy 315.673196 -393.408341) (xy 315.718874 -393.393502) (xy 315.766312 -393.385993)
			(xy 315.790326 -393.385548) (xy 315.816649 -393.386105) (xy 315.86852 -393.395108) (xy 315.918077 -393.412876)
			(xy 315.963851 -393.438883) (xy 316.004484 -393.472359) (xy 316.038771 -393.512308) (xy 316.052708 -393.534646)
			(xy 316.062868 -393.552934) (xy 316.063376 -393.55395) (xy 316.142948 -393.691618) (xy 316.685168 -393.691618)
			(xy 316.685168 -393.69111) (xy 316.685617 -393.66711) (xy 316.693121 -393.619701) (xy 316.707946 -393.574048)
			(xy 316.729727 -393.531275) (xy 316.757928 -393.492434) (xy 316.791856 -393.45848) (xy 316.830675 -393.430249)
			(xy 316.873432 -393.408436) (xy 316.919073 -393.393576) (xy 316.966477 -393.386036) (xy 316.990476 -393.385548)
			(xy 317.014423 -393.386043) (xy 317.061732 -393.393505) (xy 317.107295 -393.408264) (xy 317.149994 -393.429959)
			(xy 317.188779 -393.458057) (xy 317.2227 -393.491869) (xy 317.250923 -393.530563) (xy 317.262256 -393.551664)
			(xy 317.262764 -393.55268) (xy 317.34307 -393.691618) (xy 317.885064 -393.691618) (xy 317.885064 -393.69111)
			(xy 317.885517 -393.66711) (xy 317.893021 -393.619702) (xy 317.907845 -393.574049) (xy 317.929626 -393.531276)
			(xy 317.957827 -393.492435) (xy 317.991754 -393.458482) (xy 318.030573 -393.430251) (xy 318.073329 -393.408437)
			(xy 318.11897 -393.393577) (xy 318.166373 -393.386036) (xy 318.190372 -393.385548) (xy 318.216697 -393.386069)
			(xy 318.268569 -393.39508) (xy 318.318127 -393.412856) (xy 318.3639 -393.43887) (xy 318.404532 -393.472351)
			(xy 318.438818 -393.512306) (xy 318.452754 -393.534646) (xy 318.462914 -393.552934) (xy 318.463422 -393.55395)
			(xy 318.542994 -393.691618) (xy 319.08496 -393.691618) (xy 319.08496 -393.69111) (xy 319.085394 -393.667096)
			(xy 319.092906 -393.619659) (xy 319.107747 -393.573982) (xy 319.129551 -393.531189) (xy 319.157781 -393.492334)
			(xy 319.191743 -393.458374) (xy 319.230599 -393.430145) (xy 319.273393 -393.408342) (xy 319.319071 -393.393503)
			(xy 319.366508 -393.385993) (xy 319.390522 -393.385548) (xy 319.41447 -393.386006) (xy 319.461781 -393.393475)
			(xy 319.507345 -393.408241) (xy 319.550044 -393.429942) (xy 319.588829 -393.458046) (xy 319.622748 -393.491862)
			(xy 319.65097 -393.530561) (xy 319.662302 -393.551664) (xy 319.66281 -393.55268) (xy 319.743116 -393.691618)
			(xy 320.284856 -393.691618) (xy 320.284856 -393.69111) (xy 320.285294 -393.667096) (xy 320.292806 -393.61966)
			(xy 320.307646 -393.573983) (xy 320.32945 -393.53119) (xy 320.35768 -393.492335) (xy 320.391641 -393.458375)
			(xy 320.430497 -393.430146) (xy 320.47329 -393.408343) (xy 320.518968 -393.393504) (xy 320.566404 -393.385993)
			(xy 320.590418 -393.385548) (xy 320.616741 -393.386111) (xy 320.668611 -393.395112) (xy 320.718168 -393.41288)
			(xy 320.763942 -393.438886) (xy 320.804575 -393.47236) (xy 320.838863 -393.512309) (xy 320.8528 -393.534646)
			(xy 320.86296 -393.552934) (xy 320.863468 -393.55395) (xy 320.94304 -393.691618) (xy 321.484752 -393.691618)
			(xy 321.484752 -393.69111) (xy 321.485194 -393.667096) (xy 321.492706 -393.619661) (xy 321.507546 -393.573984)
			(xy 321.529349 -393.531191) (xy 321.557579 -393.492336) (xy 321.59154 -393.458376) (xy 321.630395 -393.430147)
			(xy 321.673188 -393.408345) (xy 321.718864 -393.393505) (xy 321.7663 -393.385993) (xy 321.790314 -393.385548)
			(xy 321.816637 -393.386114) (xy 321.868507 -393.395115) (xy 321.918064 -393.412881) (xy 321.963838 -393.438887)
			(xy 322.004471 -393.472361) (xy 322.038759 -393.512309) (xy 322.052696 -393.534646) (xy 322.062856 -393.552934)
			(xy 322.063364 -393.55395) (xy 322.14367 -393.692888) (xy 336.013552 -393.692888) (xy 336.013552 -393.69238)
			(xy 336.014044 -393.66839) (xy 336.021552 -393.621002) (xy 336.03638 -393.575371) (xy 336.058162 -393.532621)
			(xy 336.086363 -393.493804) (xy 336.120289 -393.459876) (xy 336.159104 -393.431673) (xy 336.201852 -393.409887)
			(xy 336.247482 -393.395057) (xy 336.29487 -393.387546) (xy 336.31886 -393.387072) (xy 336.342795 -393.387531)
			(xy 336.39008 -393.39499) (xy 336.435623 -393.409733) (xy 336.47831 -393.431398) (xy 336.517095 -393.459455)
			(xy 336.551031 -393.493217) (xy 336.579285 -393.531859) (xy 336.59064 -393.552934) (xy 336.591148 -393.55395)
			(xy 336.671454 -393.692888) (xy 337.213448 -393.692888) (xy 337.213448 -393.69238) (xy 337.213944 -393.66839)
			(xy 337.221452 -393.621002) (xy 337.236279 -393.575372) (xy 337.258061 -393.532622) (xy 337.286262 -393.493805)
			(xy 337.320187 -393.459878) (xy 337.359001 -393.431674) (xy 337.401749 -393.409888) (xy 337.447379 -393.395057)
			(xy 337.494766 -393.387546) (xy 337.518756 -393.387072) (xy 337.542691 -393.387534) (xy 337.589976 -393.394993)
			(xy 337.635519 -393.409735) (xy 337.678205 -393.431399) (xy 337.716991 -393.459456) (xy 337.750926 -393.493218)
			(xy 337.779181 -393.531859) (xy 337.790536 -393.552934) (xy 337.791044 -393.55395) (xy 337.87135 -393.692888)
			(xy 338.413344 -393.692888) (xy 338.413344 -393.69238) (xy 338.413844 -393.668391) (xy 338.421352 -393.621003)
			(xy 338.436179 -393.575373) (xy 338.457961 -393.532623) (xy 338.486161 -393.493807) (xy 338.520086 -393.459879)
			(xy 338.558899 -393.431675) (xy 338.601647 -393.40989) (xy 338.647276 -393.395058) (xy 338.694663 -393.387546)
			(xy 338.718652 -393.387072) (xy 338.718906 -393.387072) (xy 338.742839 -393.387575) (xy 338.790122 -393.395026)
			(xy 338.835664 -393.40976) (xy 338.878351 -393.431418) (xy 338.917137 -393.459468) (xy 338.951074 -393.493225)
			(xy 338.97933 -393.531861) (xy 338.990686 -393.552934) (xy 338.991194 -393.55395) (xy 339.0715 -393.692888)
			(xy 339.61324 -393.692888) (xy 339.61324 -393.69238) (xy 339.613643 -393.668399) (xy 339.621146 -393.621026)
			(xy 339.635964 -393.575409) (xy 339.657732 -393.53267) (xy 339.685915 -393.493861) (xy 339.719819 -393.459936)
			(xy 339.758612 -393.431729) (xy 339.801337 -393.409935) (xy 339.846945 -393.395089) (xy 339.894313 -393.387558)
			(xy 339.918294 -393.387072) (xy 339.918802 -393.387072) (xy 339.942735 -393.387578) (xy 339.990018 -393.395028)
			(xy 340.03556 -393.409763) (xy 340.078247 -393.43142) (xy 340.117033 -393.459469) (xy 340.15097 -393.493225)
			(xy 340.179226 -393.531861) (xy 340.190582 -393.552934) (xy 340.19109 -393.55395) (xy 340.271396 -393.692888)
			(xy 340.813136 -393.692888) (xy 340.813136 -393.69238) (xy 340.813543 -393.668399) (xy 340.821046 -393.621027)
			(xy 340.835863 -393.57541) (xy 340.857631 -393.532672) (xy 340.885813 -393.493862) (xy 340.919718 -393.459937)
			(xy 340.958509 -393.43173) (xy 341.001234 -393.409936) (xy 341.046841 -393.39509) (xy 341.094209 -393.387558)
			(xy 341.11819 -393.387072) (xy 341.118698 -393.387072) (xy 341.142634 -393.3875) (xy 341.189921 -393.394965)
			(xy 341.235464 -393.409713) (xy 341.278151 -393.431383) (xy 341.316936 -393.459445) (xy 341.35087 -393.493212)
			(xy 341.379124 -393.531857) (xy 341.390478 -393.552934) (xy 341.390986 -393.55395) (xy 341.471292 -393.692888)
			(xy 342.01354 -393.692888) (xy 342.01354 -393.69238) (xy 342.01392 -393.668384) (xy 342.021431 -393.620983)
			(xy 342.036265 -393.575341) (xy 342.058057 -393.532582) (xy 342.08627 -393.493758) (xy 342.12021 -393.459826)
			(xy 342.15904 -393.431622) (xy 342.201804 -393.409839) (xy 342.247449 -393.395015) (xy 342.294852 -393.387515)
			(xy 342.318848 -393.387072) (xy 342.342783 -393.387541) (xy 342.390067 -393.394998) (xy 342.43561 -393.409739)
			(xy 342.478297 -393.431402) (xy 342.517082 -393.459458) (xy 342.551018 -393.493219) (xy 342.579273 -393.531859)
			(xy 342.590628 -393.552934) (xy 342.591136 -393.55395) (xy 342.671442 -393.692888) (xy 343.213436 -393.692888)
			(xy 343.213436 -393.69238) (xy 343.21382 -393.668384) (xy 343.221331 -393.620984) (xy 343.236165 -393.575342)
			(xy 343.257957 -393.532583) (xy 343.286169 -393.493759) (xy 343.320108 -393.459828) (xy 343.358938 -393.431623)
			(xy 343.401701 -393.40984) (xy 343.447346 -393.395016) (xy 343.494748 -393.387515) (xy 343.518744 -393.387072)
			(xy 343.542678 -393.387544) (xy 343.589963 -393.395001) (xy 343.635506 -393.409741) (xy 343.678192 -393.431404)
			(xy 343.716978 -393.459459) (xy 343.750914 -393.493219) (xy 343.779169 -393.53186) (xy 343.790524 -393.552934)
			(xy 343.791032 -393.55395) (xy 343.871338 -393.692888) (xy 344.413332 -393.692888) (xy 344.413332 -393.69238)
			(xy 344.41372 -393.668384) (xy 344.421231 -393.620984) (xy 344.436065 -393.575343) (xy 344.457856 -393.532584)
			(xy 344.486068 -393.493761) (xy 344.520006 -393.459829) (xy 344.558835 -393.431624) (xy 344.601598 -393.409842)
			(xy 344.647243 -393.395017) (xy 344.694644 -393.387515) (xy 344.71864 -393.387072) (xy 344.718894 -393.387072)
			(xy 344.74283 -393.387503) (xy 344.790116 -393.394968) (xy 344.83566 -393.409715) (xy 344.878347 -393.431385)
			(xy 344.917132 -393.459446) (xy 344.951066 -393.493212) (xy 344.97932 -393.531857) (xy 344.990674 -393.552934)
			(xy 344.991182 -393.55395) (xy 345.071488 -393.692888) (xy 345.613228 -393.692888) (xy 345.613228 -393.69238)
			(xy 345.613643 -393.668399) (xy 345.621146 -393.621028) (xy 345.635962 -393.575412) (xy 345.657729 -393.532674)
			(xy 345.685911 -393.493865) (xy 345.719814 -393.45994) (xy 345.758605 -393.431733) (xy 345.801329 -393.409938)
			(xy 345.846935 -393.395092) (xy 345.894301 -393.387559) (xy 345.918282 -393.387072) (xy 345.91879 -393.387072)
			(xy 345.942726 -393.387506) (xy 345.990012 -393.39497) (xy 346.035556 -393.409717) (xy 346.078242 -393.431386)
			(xy 346.117027 -393.459447) (xy 346.150962 -393.493213) (xy 346.179216 -393.531857) (xy 346.19057 -393.552934)
			(xy 346.191078 -393.55395) (xy 346.271384 -393.692888) (xy 346.813124 -393.692888) (xy 346.813124 -393.69238)
			(xy 346.813543 -393.668399) (xy 346.821045 -393.621028) (xy 346.835862 -393.575413) (xy 346.857629 -393.532675)
			(xy 346.88581 -393.493866) (xy 346.919713 -393.459941) (xy 346.958503 -393.431734) (xy 347.001226 -393.40994)
			(xy 347.046832 -393.395093) (xy 347.094198 -393.387559) (xy 347.118178 -393.387072) (xy 347.118686 -393.387072)
			(xy 347.142622 -393.38751) (xy 347.189908 -393.394973) (xy 347.235451 -393.409719) (xy 347.278138 -393.431388)
			(xy 347.316923 -393.459448) (xy 347.350858 -393.493213) (xy 347.379112 -393.531858) (xy 347.390466 -393.552934)
			(xy 347.390974 -393.55395) (xy 347.47128 -393.692888) (xy 348.013528 -393.692888) (xy 348.013528 -393.69238)
			(xy 348.01392 -393.668385) (xy 348.021431 -393.620985) (xy 348.036264 -393.575344) (xy 348.058055 -393.532585)
			(xy 348.086267 -393.493762) (xy 348.120205 -393.45983) (xy 348.159033 -393.431626) (xy 348.201796 -393.409843)
			(xy 348.247439 -393.395018) (xy 348.29484 -393.387515) (xy 348.318836 -393.387072) (xy 348.34277 -393.38755)
			(xy 348.390054 -393.395006) (xy 348.435597 -393.409745) (xy 348.478284 -393.431407) (xy 348.517069 -393.459461)
			(xy 348.551005 -393.49322) (xy 348.579261 -393.53186) (xy 348.590616 -393.552934) (xy 348.591124 -393.55395)
			(xy 348.67143 -393.692888) (xy 349.213424 -393.692888) (xy 349.213424 -393.69238) (xy 349.21382 -393.668385)
			(xy 349.221331 -393.620985) (xy 349.236164 -393.575345) (xy 349.257954 -393.532586) (xy 349.286166 -393.493764)
			(xy 349.320103 -393.459832) (xy 349.358931 -393.431627) (xy 349.401693 -393.409844) (xy 349.447336 -393.395018)
			(xy 349.494737 -393.387516) (xy 349.518732 -393.387072) (xy 349.542666 -393.387554) (xy 349.58995 -393.395009)
			(xy 349.635493 -393.409747) (xy 349.678179 -393.431408) (xy 349.716965 -393.459462) (xy 349.750901 -393.493221)
			(xy 349.779157 -393.53186) (xy 349.790512 -393.552934) (xy 349.79102 -393.55395) (xy 349.871326 -393.692888)
			(xy 350.41332 -393.692888) (xy 350.41332 -393.69238) (xy 350.41372 -393.668385) (xy 350.42123 -393.620986)
			(xy 350.436063 -393.575346) (xy 350.457854 -393.532588) (xy 350.486065 -393.493765) (xy 350.520001 -393.459833)
			(xy 350.558829 -393.431629) (xy 350.60159 -393.409845) (xy 350.647233 -393.395019) (xy 350.694633 -393.387516)
			(xy 350.718628 -393.387072) (xy 350.718882 -393.387072) (xy 350.742818 -393.387513) (xy 350.790103 -393.394976)
			(xy 350.835647 -393.409721) (xy 350.878334 -393.431389) (xy 350.917119 -393.459449) (xy 350.951054 -393.493214)
			(xy 350.979308 -393.531858) (xy 350.990662 -393.552934) (xy 350.99117 -393.55395) (xy 351.071476 -393.692888)
			(xy 351.613216 -393.692888) (xy 351.613216 -393.69238) (xy 351.613643 -393.6684) (xy 351.621145 -393.621029)
			(xy 351.635961 -393.575415) (xy 351.657727 -393.532678) (xy 351.685908 -393.493869) (xy 351.719809 -393.459944)
			(xy 351.758598 -393.431737) (xy 351.80132 -393.409942) (xy 351.846925 -393.395094) (xy 351.89429 -393.38756)
			(xy 351.91827 -393.387072) (xy 351.918778 -393.387072) (xy 351.942713 -393.387516) (xy 351.989999 -393.394978)
			(xy 352.035543 -393.409723) (xy 352.078229 -393.431391) (xy 352.117015 -393.45945) (xy 352.150949 -393.493214)
			(xy 352.179204 -393.531858) (xy 352.190558 -393.552934) (xy 352.191066 -393.55395) (xy 352.271372 -393.692888)
			(xy 352.813112 -393.692888) (xy 352.813112 -393.69238) (xy 352.813521 -393.668373) (xy 352.821039 -393.62095)
			(xy 352.835887 -393.575289) (xy 352.857699 -393.532514) (xy 352.885937 -393.493681) (xy 352.919904 -393.459745)
			(xy 352.958765 -393.431545) (xy 353.001561 -393.409774) (xy 353.047236 -393.39497) (xy 353.094666 -393.387498)
			(xy 353.118674 -393.387072) (xy 353.118928 -393.387072) (xy 353.142862 -393.387557) (xy 353.190146 -393.395011)
			(xy 353.235688 -393.409749) (xy 353.278375 -393.43141) (xy 353.317161 -393.459463) (xy 353.351097 -393.493222)
			(xy 353.379353 -393.53186) (xy 353.390708 -393.552934) (xy 353.391216 -393.55395) (xy 353.471522 -393.692888)
			(xy 354.013516 -393.692888) (xy 354.013516 -393.69238) (xy 354.01392 -393.668385) (xy 354.02143 -393.620987)
			(xy 354.036263 -393.575347) (xy 354.058053 -393.532589) (xy 354.086263 -393.493766) (xy 354.1202 -393.459835)
			(xy 354.159026 -393.43163) (xy 354.201787 -393.409846) (xy 354.247429 -393.39502) (xy 354.294829 -393.387516)
			(xy 354.318824 -393.387072) (xy 354.342758 -393.38756) (xy 354.390042 -393.395014) (xy 354.435584 -393.409751)
			(xy 354.478271 -393.431411) (xy 354.517057 -393.459464) (xy 354.550993 -393.493222) (xy 354.579249 -393.53186)
			(xy 354.590604 -393.552934) (xy 354.591112 -393.55395) (xy 354.671418 -393.692888) (xy 370.586 -393.692888)
			(xy 370.586 -393.69238) (xy 370.586444 -393.668388) (xy 370.593954 -393.620995) (xy 370.608784 -393.57536)
			(xy 370.630571 -393.532606) (xy 370.658777 -393.493788) (xy 370.692709 -393.459859) (xy 370.73153 -393.431656)
			(xy 370.774286 -393.409873) (xy 370.819922 -393.395047) (xy 370.867316 -393.387542) (xy 370.891308 -393.387072)
			(xy 370.915241 -393.387573) (xy 370.962524 -393.395024) (xy 371.008067 -393.409759) (xy 371.050753 -393.431417)
			(xy 371.089539 -393.459468) (xy 371.123476 -393.493224) (xy 371.151732 -393.531861) (xy 371.163088 -393.552934)
			(xy 371.163596 -393.55395) (xy 371.243902 -393.692888) (xy 371.785896 -393.692888) (xy 371.785896 -393.69238)
			(xy 371.786344 -393.668388) (xy 371.793853 -393.620995) (xy 371.808684 -393.575361) (xy 371.83047 -393.532608)
			(xy 371.858676 -393.493789) (xy 371.892607 -393.459861) (xy 371.931428 -393.431658) (xy 371.974183 -393.409875)
			(xy 372.019819 -393.395048) (xy 372.067212 -393.387542) (xy 372.091204 -393.387072) (xy 372.115137 -393.387576)
			(xy 372.16242 -393.395027) (xy 372.207962 -393.409762) (xy 372.250649 -393.431419) (xy 372.289435 -393.459469)
			(xy 372.323372 -393.493225) (xy 372.351628 -393.531861) (xy 372.362984 -393.552934) (xy 372.363492 -393.55395)
			(xy 372.443798 -393.692888) (xy 372.985792 -393.692888) (xy 372.985792 -393.69238) (xy 372.986244 -393.668388)
			(xy 372.993753 -393.620996) (xy 373.008583 -393.575362) (xy 373.030369 -393.532609) (xy 373.058575 -393.49379)
			(xy 373.092506 -393.459862) (xy 373.131326 -393.431659) (xy 373.17408 -393.409876) (xy 373.219715 -393.395049)
			(xy 373.267108 -393.387543) (xy 373.2911 -393.387072) (xy 373.315033 -393.38758) (xy 373.362316 -393.39503)
			(xy 373.407858 -393.409764) (xy 373.450544 -393.43142) (xy 373.489331 -393.45947) (xy 373.523268 -393.493226)
			(xy 373.551524 -393.531862) (xy 373.56288 -393.552934) (xy 373.563388 -393.55395) (xy 373.643694 -393.692888)
			(xy 374.185688 -393.692888) (xy 374.185688 -393.69238) (xy 374.186143 -393.668401) (xy 374.193644 -393.621034)
			(xy 374.208459 -393.575421) (xy 374.230222 -393.532686) (xy 374.258399 -393.493879) (xy 374.292298 -393.459954)
			(xy 374.331083 -393.431747) (xy 374.373801 -393.40995) (xy 374.419402 -393.3951) (xy 374.466763 -393.387562)
			(xy 374.490742 -393.387072) (xy 374.49125 -393.387072) (xy 374.515185 -393.387539) (xy 374.562469 -393.394997)
			(xy 374.608012 -393.409738) (xy 374.650699 -393.431401) (xy 374.689484 -393.459457) (xy 374.72342 -393.493218)
			(xy 374.751675 -393.531859) (xy 374.76303 -393.552934) (xy 374.763538 -393.55395) (xy 374.843844 -393.692888)
			(xy 375.385584 -393.692888) (xy 375.385584 -393.69238) (xy 375.386043 -393.668401) (xy 375.393544 -393.621034)
			(xy 375.408358 -393.575422) (xy 375.430121 -393.532687) (xy 375.458298 -393.49388) (xy 375.492196 -393.459956)
			(xy 375.53098 -393.431748) (xy 375.573698 -393.409951) (xy 375.619298 -393.395101) (xy 375.66666 -393.387562)
			(xy 375.690638 -393.387072) (xy 375.691146 -393.387072) (xy 375.715081 -393.387542) (xy 375.762365 -393.394999)
			(xy 375.807908 -393.40974) (xy 375.850594 -393.431403) (xy 375.88938 -393.459458) (xy 375.923316 -393.493219)
			(xy 375.951571 -393.531859) (xy 375.962926 -393.552934) (xy 375.963434 -393.55395) (xy 376.04374 -393.692888)
			(xy 376.585988 -393.692888) (xy 376.585988 -393.69238) (xy 376.586444 -393.668388) (xy 376.593953 -393.620996)
			(xy 376.608783 -393.575362) (xy 376.630569 -393.53261) (xy 376.658774 -393.493792) (xy 376.692704 -393.459863)
			(xy 376.731524 -393.43166) (xy 376.774277 -393.409877) (xy 376.819912 -393.395049) (xy 376.867304 -393.387543)
			(xy 376.891296 -393.387072) (xy 376.915232 -393.387502) (xy 376.962518 -393.394966) (xy 377.008062 -393.409714)
			(xy 377.050749 -393.431384) (xy 377.089534 -393.459445) (xy 377.123468 -393.493212) (xy 377.151722 -393.531857)
			(xy 377.163076 -393.552934) (xy 377.163584 -393.55395) (xy 377.24389 -393.692888) (xy 377.785884 -393.692888)
			(xy 377.785884 -393.69238) (xy 377.786344 -393.668389) (xy 377.793853 -393.620997) (xy 377.808683 -393.575363)
			(xy 377.830468 -393.532611) (xy 377.858673 -393.493793) (xy 377.892602 -393.459865) (xy 377.931421 -393.431662)
			(xy 377.974174 -393.409878) (xy 378.019809 -393.39505) (xy 378.067201 -393.387543) (xy 378.091192 -393.387072)
			(xy 378.115128 -393.387505) (xy 378.162414 -393.394969) (xy 378.207958 -393.409716) (xy 378.250644 -393.431385)
			(xy 378.28943 -393.459446) (xy 378.323364 -393.493212) (xy 378.351618 -393.531857) (xy 378.362972 -393.552934)
			(xy 378.36348 -393.55395) (xy 378.443786 -393.692888) (xy 378.98578 -393.692888) (xy 378.98578 -393.69238)
			(xy 378.986244 -393.668389) (xy 378.993753 -393.620998) (xy 379.008582 -393.575364) (xy 379.030367 -393.532612)
			(xy 379.058571 -393.493795) (xy 379.092501 -393.459866) (xy 379.131319 -393.431663) (xy 379.174072 -393.409879)
			(xy 379.219705 -393.395051) (xy 379.267097 -393.387543) (xy 379.291088 -393.387072) (xy 379.315024 -393.387508)
			(xy 379.36231 -393.394972) (xy 379.407853 -393.409718) (xy 379.45054 -393.431387) (xy 379.489325 -393.459447)
			(xy 379.52326 -393.493213) (xy 379.551514 -393.531858) (xy 379.562868 -393.552934) (xy 379.563376 -393.55395)
			(xy 379.643682 -393.692888) (xy 380.185676 -393.692888) (xy 380.185676 -393.69238) (xy 380.186143 -393.668402)
			(xy 380.193644 -393.621035) (xy 380.208457 -393.575424) (xy 380.23022 -393.532689) (xy 380.258396 -393.493883)
			(xy 380.292292 -393.459959) (xy 380.331076 -393.431751) (xy 380.373793 -393.409953) (xy 380.419392 -393.395102)
			(xy 380.466752 -393.387563) (xy 380.49073 -393.387072) (xy 380.491238 -393.387072) (xy 380.515172 -393.387549)
			(xy 380.562456 -393.395005) (xy 380.607999 -393.409744) (xy 380.650686 -393.431406) (xy 380.689472 -393.45946)
			(xy 380.723407 -393.49322) (xy 380.751663 -393.53186) (xy 380.763018 -393.552934) (xy 380.763526 -393.55395)
			(xy 380.843832 -393.692888) (xy 381.385572 -393.692888) (xy 381.385572 -393.69238) (xy 381.386043 -393.668402)
			(xy 381.393544 -393.621036) (xy 381.408357 -393.575425) (xy 381.430119 -393.532691) (xy 381.458295 -393.493884)
			(xy 381.492191 -393.45996) (xy 381.530974 -393.431752) (xy 381.57369 -393.409954) (xy 381.619289 -393.395103)
			(xy 381.666648 -393.387563) (xy 381.690626 -393.387072) (xy 381.691134 -393.387072) (xy 381.715068 -393.387552)
			(xy 381.762352 -393.395007) (xy 381.807895 -393.409746) (xy 381.850581 -393.431407) (xy 381.889367 -393.459461)
			(xy 381.923303 -393.493221) (xy 381.951559 -393.53186) (xy 381.962914 -393.552934) (xy 381.963422 -393.55395)
			(xy 382.043728 -393.692888) (xy 382.585976 -393.692888) (xy 382.585976 -393.69238) (xy 382.586444 -393.668389)
			(xy 382.593953 -393.620998) (xy 382.608782 -393.575365) (xy 382.630567 -393.532614) (xy 382.65877 -393.493796)
			(xy 382.692699 -393.459868) (xy 382.731517 -393.431664) (xy 382.774269 -393.40988) (xy 382.819902 -393.395052)
			(xy 382.867293 -393.387544) (xy 382.891284 -393.387072) (xy 382.91522 -393.387511) (xy 382.962506 -393.394974)
			(xy 383.008049 -393.40972) (xy 383.050736 -393.431388) (xy 383.089521 -393.459448) (xy 383.123456 -393.493214)
			(xy 383.15171 -393.531858) (xy 383.163064 -393.552934) (xy 383.163572 -393.55395) (xy 383.243878 -393.692888)
			(xy 383.785872 -393.692888) (xy 383.785872 -393.69238) (xy 383.786344 -393.668389) (xy 383.793853 -393.620999)
			(xy 383.808681 -393.575366) (xy 383.830466 -393.532615) (xy 383.858669 -393.493797) (xy 383.892597 -393.459869)
			(xy 383.931415 -393.431666) (xy 383.974166 -393.409881) (xy 384.019799 -393.395053) (xy 384.067189 -393.387544)
			(xy 384.09118 -393.387072) (xy 384.115116 -393.387515) (xy 384.162401 -393.394977) (xy 384.207945 -393.409722)
			(xy 384.250631 -393.43139) (xy 384.289417 -393.459449) (xy 384.323352 -393.493214) (xy 384.351606 -393.531858)
			(xy 384.36296 -393.552934) (xy 384.363468 -393.55395) (xy 384.443774 -393.692888) (xy 384.985768 -393.692888)
			(xy 384.985768 -393.69238) (xy 384.986244 -393.668389) (xy 384.993752 -393.620999) (xy 385.008581 -393.575367)
			(xy 385.030365 -393.532616) (xy 385.058568 -393.493799) (xy 385.092496 -393.459871) (xy 385.131313 -393.431667)
			(xy 385.174063 -393.409883) (xy 385.219695 -393.395053) (xy 385.267085 -393.387544) (xy 385.291076 -393.387072)
			(xy 385.315011 -393.387518) (xy 385.362297 -393.39498) (xy 385.40784 -393.409724) (xy 385.450527 -393.431391)
			(xy 385.489312 -393.45945) (xy 385.523247 -393.493215) (xy 385.551501 -393.531858) (xy 385.562856 -393.552934)
			(xy 385.563364 -393.55395) (xy 385.64367 -393.692888) (xy 386.185664 -393.692888) (xy 386.185664 -393.69238)
			(xy 386.186143 -393.668402) (xy 386.193643 -393.621037) (xy 386.208456 -393.575427) (xy 386.230218 -393.532693)
			(xy 386.258392 -393.493887) (xy 386.292287 -393.459963) (xy 386.331069 -393.431755) (xy 386.373784 -393.409957)
			(xy 386.419382 -393.395105) (xy 386.466741 -393.387564) (xy 386.490718 -393.387072) (xy 386.491226 -393.387072)
			(xy 386.51516 -393.387558) (xy 386.562444 -393.395013) (xy 386.607986 -393.40975) (xy 386.650673 -393.43141)
			(xy 386.689459 -393.459463) (xy 386.723395 -393.493222) (xy 386.751651 -393.53186) (xy 386.763006 -393.552934)
			(xy 386.763514 -393.55395) (xy 386.84382 -393.692888) (xy 387.38556 -393.692888) (xy 387.38556 -393.69238)
			(xy 387.386043 -393.668403) (xy 387.393543 -393.621038) (xy 387.408356 -393.575428) (xy 387.430117 -393.532694)
			(xy 387.458291 -393.493888) (xy 387.492186 -393.459964) (xy 387.530967 -393.431756) (xy 387.573682 -393.409958)
			(xy 387.619279 -393.395105) (xy 387.666637 -393.387564) (xy 387.690614 -393.387072) (xy 387.691122 -393.387072)
			(xy 387.715056 -393.387562) (xy 387.762339 -393.395015) (xy 387.807882 -393.409752) (xy 387.850568 -393.431412)
			(xy 387.889354 -393.459464) (xy 387.923291 -393.493222) (xy 387.951547 -393.531861) (xy 387.962902 -393.552934)
			(xy 387.96341 -393.55395) (xy 388.043716 -393.692888) (xy 388.585964 -393.692888) (xy 388.585964 -393.69238)
			(xy 388.586444 -393.66839) (xy 388.593952 -393.621) (xy 388.608781 -393.575368) (xy 388.630564 -393.532617)
			(xy 388.658767 -393.4938) (xy 388.692694 -393.459872) (xy 388.73151 -393.431668) (xy 388.774261 -393.409884)
			(xy 388.819892 -393.395054) (xy 388.867282 -393.387545) (xy 388.891272 -393.387072) (xy 388.915207 -393.387521)
			(xy 388.962493 -393.394982) (xy 389.008036 -393.409727) (xy 389.050723 -393.431393) (xy 389.089508 -393.459451)
			(xy 389.123443 -393.493215) (xy 389.151697 -393.531858) (xy 389.163052 -393.552934) (xy 389.16356 -393.55395)
			(xy 389.243866 -393.692888) (xy 403.113748 -393.692888) (xy 403.113748 -393.69238) (xy 403.114244 -393.66839)
			(xy 403.121752 -393.621002) (xy 403.136579 -393.575372) (xy 403.158361 -393.532622) (xy 403.186562 -393.493805)
			(xy 403.220487 -393.459878) (xy 403.259301 -393.431674) (xy 403.302049 -393.409888) (xy 403.347679 -393.395057)
			(xy 403.395066 -393.387546) (xy 403.419056 -393.387072) (xy 403.442991 -393.387534) (xy 403.490276 -393.394993)
			(xy 403.535819 -393.409735) (xy 403.578505 -393.431399) (xy 403.617291 -393.459456) (xy 403.651226 -393.493218)
			(xy 403.679481 -393.531859) (xy 403.690836 -393.552934) (xy 403.691344 -393.55395) (xy 403.77165 -393.692888)
			(xy 404.313644 -393.692888) (xy 404.313644 -393.69238) (xy 404.314144 -393.668391) (xy 404.321652 -393.621003)
			(xy 404.336479 -393.575373) (xy 404.358261 -393.532623) (xy 404.386461 -393.493807) (xy 404.420386 -393.459879)
			(xy 404.459199 -393.431675) (xy 404.501947 -393.40989) (xy 404.547576 -393.395058) (xy 404.594963 -393.387546)
			(xy 404.618952 -393.387072) (xy 404.642887 -393.387537) (xy 404.690171 -393.394995) (xy 404.735714 -393.409737)
			(xy 404.778401 -393.431401) (xy 404.817187 -393.459457) (xy 404.851122 -393.493218) (xy 404.879377 -393.531859)
			(xy 404.890732 -393.552934) (xy 404.89124 -393.55395) (xy 404.971546 -393.692888) (xy 405.51354 -393.692888)
			(xy 405.51354 -393.69238) (xy 405.51392 -393.668384) (xy 405.521431 -393.620983) (xy 405.536265 -393.575341)
			(xy 405.558057 -393.532582) (xy 405.58627 -393.493758) (xy 405.62021 -393.459826) (xy 405.65904 -393.431622)
			(xy 405.701804 -393.409839) (xy 405.747449 -393.395015) (xy 405.794852 -393.387515) (xy 405.818848 -393.387072)
			(xy 405.842783 -393.387541) (xy 405.890067 -393.394998) (xy 405.93561 -393.409739) (xy 405.978297 -393.431402)
			(xy 406.017082 -393.459458) (xy 406.051018 -393.493219) (xy 406.079273 -393.531859) (xy 406.090628 -393.552934)
			(xy 406.091136 -393.55395) (xy 406.171442 -393.692888) (xy 406.713436 -393.692888) (xy 406.713436 -393.69238)
			(xy 406.713843 -393.668399) (xy 406.721346 -393.621027) (xy 406.736163 -393.57541) (xy 406.757931 -393.532672)
			(xy 406.786113 -393.493862) (xy 406.820018 -393.459937) (xy 406.858809 -393.43173) (xy 406.901534 -393.409936)
			(xy 406.947141 -393.39509) (xy 406.994509 -393.387558) (xy 407.01849 -393.387072) (xy 407.018998 -393.387072)
			(xy 407.042934 -393.3875) (xy 407.090221 -393.394965) (xy 407.135764 -393.409713) (xy 407.178451 -393.431383)
			(xy 407.217236 -393.459445) (xy 407.25117 -393.493212) (xy 407.279424 -393.531857) (xy 407.290778 -393.552934)
			(xy 407.291286 -393.55395) (xy 407.371592 -393.692888) (xy 407.913332 -393.692888) (xy 407.913332 -393.69238)
			(xy 407.913743 -393.668399) (xy 407.921246 -393.621027) (xy 407.936063 -393.575411) (xy 407.95783 -393.532673)
			(xy 407.986012 -393.493864) (xy 408.019916 -393.459939) (xy 408.058707 -393.431732) (xy 408.101432 -393.409937)
			(xy 408.147038 -393.395091) (xy 408.194405 -393.387559) (xy 408.218386 -393.387072) (xy 408.218894 -393.387072)
			(xy 408.24283 -393.387503) (xy 408.290116 -393.394968) (xy 408.33566 -393.409715) (xy 408.378347 -393.431385)
			(xy 408.417132 -393.459446) (xy 408.451066 -393.493212) (xy 408.47932 -393.531857) (xy 408.490674 -393.552934)
			(xy 408.491182 -393.55395) (xy 408.571488 -393.692888) (xy 409.113736 -393.692888) (xy 409.113736 -393.69238)
			(xy 409.11412 -393.668384) (xy 409.121631 -393.620984) (xy 409.136465 -393.575342) (xy 409.158257 -393.532583)
			(xy 409.186469 -393.493759) (xy 409.220408 -393.459828) (xy 409.259238 -393.431623) (xy 409.302001 -393.40984)
			(xy 409.347646 -393.395016) (xy 409.395048 -393.387515) (xy 409.419044 -393.387072) (xy 409.442978 -393.387544)
			(xy 409.490263 -393.395001) (xy 409.535806 -393.409741) (xy 409.578492 -393.431404) (xy 409.617278 -393.459459)
			(xy 409.651214 -393.493219) (xy 409.679469 -393.53186) (xy 409.690824 -393.552934) (xy 409.691332 -393.55395)
			(xy 409.771638 -393.692888) (xy 410.313632 -393.692888) (xy 410.313632 -393.69238) (xy 410.31402 -393.668384)
			(xy 410.321531 -393.620984) (xy 410.336365 -393.575343) (xy 410.358156 -393.532584) (xy 410.386368 -393.493761)
			(xy 410.420306 -393.459829) (xy 410.459135 -393.431624) (xy 410.501898 -393.409842) (xy 410.547543 -393.395017)
			(xy 410.594944 -393.387515) (xy 410.61894 -393.387072) (xy 410.642874 -393.387547) (xy 410.690159 -393.395003)
			(xy 410.735701 -393.409743) (xy 410.778388 -393.431405) (xy 410.817174 -393.45946) (xy 410.85111 -393.49322)
			(xy 410.879365 -393.53186) (xy 410.89072 -393.552934) (xy 410.891228 -393.55395) (xy 410.971534 -393.692888)
			(xy 411.513528 -393.692888) (xy 411.513528 -393.69238) (xy 411.51392 -393.668385) (xy 411.521431 -393.620985)
			(xy 411.536264 -393.575344) (xy 411.558055 -393.532585) (xy 411.586267 -393.493762) (xy 411.620205 -393.45983)
			(xy 411.659033 -393.431626) (xy 411.701796 -393.409843) (xy 411.747439 -393.395018) (xy 411.79484 -393.387515)
			(xy 411.818836 -393.387072) (xy 411.84277 -393.38755) (xy 411.890054 -393.395006) (xy 411.935597 -393.409745)
			(xy 411.978284 -393.431407) (xy 412.017069 -393.459461) (xy 412.051005 -393.49322) (xy 412.079261 -393.53186)
			(xy 412.090616 -393.552934) (xy 412.091124 -393.55395) (xy 412.17143 -393.692888) (xy 412.713424 -393.692888)
			(xy 412.713424 -393.69238) (xy 412.713843 -393.668399) (xy 412.721345 -393.621028) (xy 412.736162 -393.575413)
			(xy 412.757929 -393.532675) (xy 412.78611 -393.493866) (xy 412.820013 -393.459941) (xy 412.858803 -393.431734)
			(xy 412.901526 -393.40994) (xy 412.947132 -393.395093) (xy 412.994498 -393.387559) (xy 413.018478 -393.387072)
			(xy 413.018986 -393.387072) (xy 413.042922 -393.38751) (xy 413.090208 -393.394973) (xy 413.135751 -393.409719)
			(xy 413.178438 -393.431388) (xy 413.217223 -393.459448) (xy 413.251158 -393.493213) (xy 413.279412 -393.531858)
			(xy 413.290766 -393.552934) (xy 413.291274 -393.55395) (xy 413.37158 -393.692888) (xy 413.91332 -393.692888)
			(xy 413.91332 -393.69238) (xy 413.913743 -393.6684) (xy 413.921245 -393.621029) (xy 413.936062 -393.575414)
			(xy 413.957828 -393.532676) (xy 413.986009 -393.493868) (xy 414.019911 -393.459943) (xy 414.0587 -393.431736)
			(xy 414.101423 -393.409941) (xy 414.147028 -393.395093) (xy 414.194394 -393.387559) (xy 414.218374 -393.387072)
			(xy 414.218882 -393.387072) (xy 414.242818 -393.387513) (xy 414.290103 -393.394976) (xy 414.335647 -393.409721)
			(xy 414.378334 -393.431389) (xy 414.417119 -393.459449) (xy 414.451054 -393.493214) (xy 414.479308 -393.531858)
			(xy 414.490662 -393.552934) (xy 414.49117 -393.55395) (xy 414.571476 -393.692888) (xy 415.113724 -393.692888)
			(xy 415.113724 -393.69238) (xy 415.11412 -393.668385) (xy 415.121631 -393.620985) (xy 415.136464 -393.575345)
			(xy 415.158254 -393.532586) (xy 415.186466 -393.493764) (xy 415.220403 -393.459832) (xy 415.259231 -393.431627)
			(xy 415.301993 -393.409844) (xy 415.347636 -393.395018) (xy 415.395037 -393.387516) (xy 415.419032 -393.387072)
			(xy 415.442966 -393.387554) (xy 415.49025 -393.395009) (xy 415.535793 -393.409747) (xy 415.578479 -393.431408)
			(xy 415.617265 -393.459462) (xy 415.651201 -393.493221) (xy 415.679457 -393.53186) (xy 415.690812 -393.552934)
			(xy 415.69132 -393.55395) (xy 415.771626 -393.692888) (xy 416.31362 -393.692888) (xy 416.31362 -393.69238)
			(xy 416.31402 -393.668385) (xy 416.32153 -393.620986) (xy 416.336363 -393.575346) (xy 416.358154 -393.532588)
			(xy 416.386365 -393.493765) (xy 416.420301 -393.459833) (xy 416.459129 -393.431629) (xy 416.50189 -393.409845)
			(xy 416.547533 -393.395019) (xy 416.594933 -393.387516) (xy 416.618928 -393.387072) (xy 416.642862 -393.387557)
			(xy 416.690146 -393.395011) (xy 416.735688 -393.409749) (xy 416.778375 -393.43141) (xy 416.817161 -393.459463)
			(xy 416.851097 -393.493222) (xy 416.879353 -393.53186) (xy 416.890708 -393.552934) (xy 416.891216 -393.55395)
			(xy 416.971522 -393.692888) (xy 417.513516 -393.692888) (xy 417.513516 -393.69238) (xy 417.51392 -393.668385)
			(xy 417.52143 -393.620987) (xy 417.536263 -393.575347) (xy 417.558053 -393.532589) (xy 417.586263 -393.493766)
			(xy 417.6202 -393.459835) (xy 417.659026 -393.43163) (xy 417.701787 -393.409846) (xy 417.747429 -393.39502)
			(xy 417.794829 -393.387516) (xy 417.818824 -393.387072) (xy 417.842758 -393.38756) (xy 417.890042 -393.395014)
			(xy 417.935584 -393.409751) (xy 417.978271 -393.431411) (xy 418.017057 -393.459464) (xy 418.050993 -393.493222)
			(xy 418.079249 -393.53186) (xy 418.090604 -393.552934) (xy 418.091112 -393.55395) (xy 418.171418 -393.692888)
			(xy 418.713412 -393.692888) (xy 418.713412 -393.69238) (xy 418.713843 -393.6684) (xy 418.721345 -393.62103)
			(xy 418.736161 -393.575416) (xy 418.757927 -393.532679) (xy 418.786106 -393.493871) (xy 418.820008 -393.459946)
			(xy 418.858796 -393.431739) (xy 418.901518 -393.409943) (xy 418.947122 -393.395095) (xy 418.994486 -393.38756)
			(xy 419.018466 -393.387072) (xy 419.018974 -393.387072) (xy 419.042909 -393.387519) (xy 419.090195 -393.394981)
			(xy 419.135738 -393.409726) (xy 419.178425 -393.431392) (xy 419.21721 -393.459451) (xy 419.251145 -393.493215)
			(xy 419.279399 -393.531858) (xy 419.290754 -393.552934) (xy 419.291262 -393.55395) (xy 419.371568 -393.692888)
			(xy 419.913308 -393.692888) (xy 419.913308 -393.69238) (xy 419.913743 -393.6684) (xy 419.921245 -393.621031)
			(xy 419.936061 -393.575417) (xy 419.957826 -393.53268) (xy 419.986005 -393.493872) (xy 420.019906 -393.459947)
			(xy 420.058694 -393.43174) (xy 420.101415 -393.409944) (xy 420.147018 -393.395096) (xy 420.194382 -393.38756)
			(xy 420.218362 -393.387072) (xy 420.21887 -393.387072) (xy 420.242805 -393.387523) (xy 420.290091 -393.394984)
			(xy 420.335634 -393.409728) (xy 420.378321 -393.431394) (xy 420.417106 -393.459452) (xy 420.451041 -393.493216)
			(xy 420.479295 -393.531858) (xy 420.49065 -393.552934) (xy 420.491158 -393.55395) (xy 420.571464 -393.692888)
			(xy 421.113712 -393.692888) (xy 421.113712 -393.69238) (xy 421.114144 -393.668387) (xy 421.121654 -393.620993)
			(xy 421.136485 -393.575357) (xy 421.158273 -393.532603) (xy 421.186481 -393.493784) (xy 421.220414 -393.459855)
			(xy 421.259237 -393.431652) (xy 421.301994 -393.40987) (xy 421.347632 -393.395045) (xy 421.395027 -393.387541)
			(xy 421.41902 -393.387072) (xy 421.442954 -393.387563) (xy 421.490237 -393.395017) (xy 421.53578 -393.409753)
			(xy 421.578466 -393.431413) (xy 421.617252 -393.459465) (xy 421.651189 -393.493223) (xy 421.679444 -393.531861)
			(xy 421.6908 -393.552934) (xy 421.691308 -393.55395) (xy 422.083738 -394.232892) (xy 422.096563 -394.256225)
			(xy 422.114783 -394.306247) (xy 422.124043 -394.358673) (xy 422.124632 -394.385292) (xy 422.124131 -394.409269)
			(xy 422.116635 -394.456634) (xy 422.101826 -394.502244) (xy 422.080067 -394.544978) (xy 422.051895 -394.583784)
			(xy 422.018002 -394.617709) (xy 421.979222 -394.645918) (xy 421.936509 -394.667716) (xy 421.890912 -394.682568)
			(xy 421.843555 -394.690109) (xy 421.819578 -394.6906) (xy 421.81907 -394.6906) (xy 421.795495 -394.69023)
			(xy 421.748906 -394.682984) (xy 421.703987 -394.668654) (xy 421.661808 -394.647582) (xy 421.623376 -394.620268)
			(xy 421.589605 -394.587365) (xy 421.5613 -394.549657) (xy 421.54983 -394.529056) (xy 421.549322 -394.528294)
			(xy 421.151558 -393.839954) (xy 421.139699 -393.817269) (xy 421.122842 -393.76894) (xy 421.114262 -393.71848)
			(xy 421.113712 -393.692888) (xy 420.571464 -393.692888) (xy 420.883588 -394.232892) (xy 420.89632 -394.256211)
			(xy 420.914415 -394.306158) (xy 420.923631 -394.358477) (xy 420.924228 -394.385038) (xy 420.924228 -394.385292)
			(xy 420.92373 -394.409282) (xy 420.916226 -394.456672) (xy 420.901401 -394.502304) (xy 420.87962 -394.545055)
			(xy 420.85142 -394.583873) (xy 420.817494 -394.617801) (xy 420.778679 -394.646005) (xy 420.73593 -394.66779)
			(xy 420.690299 -394.682619) (xy 420.64291 -394.690128) (xy 420.61892 -394.6906) (xy 420.595347 -394.69019)
			(xy 420.548759 -394.682952) (xy 420.503841 -394.668629) (xy 420.461662 -394.647563) (xy 420.423229 -394.620256)
			(xy 420.389457 -394.587358) (xy 420.361151 -394.549655) (xy 420.34968 -394.529056) (xy 420.349172 -394.528294)
			(xy 419.951408 -393.839954) (xy 419.939474 -393.817295) (xy 419.922543 -393.768965) (xy 419.913891 -393.718491)
			(xy 419.913308 -393.692888) (xy 419.371568 -393.692888) (xy 419.683692 -394.232892) (xy 419.696424 -394.25621)
			(xy 419.714519 -394.306158) (xy 419.723735 -394.358477) (xy 419.724332 -394.385038) (xy 419.724332 -394.385292)
			(xy 419.72383 -394.409282) (xy 419.716326 -394.456671) (xy 419.701501 -394.502303) (xy 419.679721 -394.545054)
			(xy 419.651521 -394.583871) (xy 419.617596 -394.6178) (xy 419.578781 -394.646004) (xy 419.536032 -394.667789)
			(xy 419.490402 -394.682618) (xy 419.443014 -394.690128) (xy 419.419024 -394.6906) (xy 419.395451 -394.690187)
			(xy 419.348863 -394.682949) (xy 419.303945 -394.668627) (xy 419.261767 -394.647561) (xy 419.223333 -394.620255)
			(xy 419.189561 -394.587358) (xy 419.161255 -394.549655) (xy 419.149784 -394.529056) (xy 419.149276 -394.528294)
			(xy 418.751512 -393.839954) (xy 418.739579 -393.817295) (xy 418.722647 -393.768965) (xy 418.713995 -393.718491)
			(xy 418.713412 -393.692888) (xy 418.171418 -393.692888) (xy 418.483542 -394.232892) (xy 418.496367 -394.256224)
			(xy 418.514587 -394.306247) (xy 418.523847 -394.358673) (xy 418.524436 -394.385292) (xy 418.523931 -394.409269)
			(xy 418.516435 -394.456633) (xy 418.501626 -394.502243) (xy 418.479868 -394.544977) (xy 418.451696 -394.583783)
			(xy 418.417804 -394.617708) (xy 418.379024 -394.645916) (xy 418.336311 -394.667715) (xy 418.290716 -394.682567)
			(xy 418.243358 -394.690108) (xy 418.219382 -394.6906) (xy 418.218874 -394.6906) (xy 418.195299 -394.690227)
			(xy 418.14871 -394.682982) (xy 418.103791 -394.668652) (xy 418.061613 -394.64758) (xy 418.02318 -394.620267)
			(xy 417.989409 -394.587365) (xy 417.961104 -394.549657) (xy 417.949634 -394.529056) (xy 417.949126 -394.528294)
			(xy 417.551362 -393.839954) (xy 417.539504 -393.817268) (xy 417.522646 -393.76894) (xy 417.514066 -393.71848)
			(xy 417.513516 -393.692888) (xy 416.971522 -393.692888) (xy 417.283646 -394.232892) (xy 417.296471 -394.256224)
			(xy 417.314691 -394.306247) (xy 417.323951 -394.358673) (xy 417.32454 -394.385292) (xy 417.324031 -394.409269)
			(xy 417.316535 -394.456633) (xy 417.301726 -394.502242) (xy 417.279969 -394.544976) (xy 417.251798 -394.583782)
			(xy 417.217906 -394.617706) (xy 417.179127 -394.645915) (xy 417.136414 -394.667714) (xy 417.090819 -394.682566)
			(xy 417.043462 -394.690108) (xy 417.019486 -394.6906) (xy 417.018978 -394.6906) (xy 416.995403 -394.690224)
			(xy 416.948814 -394.682979) (xy 416.903895 -394.66865) (xy 416.861717 -394.647579) (xy 416.823284 -394.620266)
			(xy 416.789513 -394.587364) (xy 416.761208 -394.549657) (xy 416.749738 -394.529056) (xy 416.74923 -394.528294)
			(xy 416.351466 -393.839954) (xy 416.339608 -393.817268) (xy 416.32275 -393.76894) (xy 416.31417 -393.71848)
			(xy 416.31362 -393.692888) (xy 415.771626 -393.692888) (xy 416.08375 -394.232892) (xy 416.096576 -394.256224)
			(xy 416.114795 -394.306247) (xy 416.124055 -394.358673) (xy 416.124644 -394.385292) (xy 416.124131 -394.409269)
			(xy 416.116635 -394.456632) (xy 416.101827 -394.502241) (xy 416.080069 -394.544974) (xy 416.051899 -394.58378)
			(xy 416.018007 -394.617705) (xy 415.979229 -394.645913) (xy 415.936517 -394.667712) (xy 415.890922 -394.682566)
			(xy 415.843566 -394.690108) (xy 415.81959 -394.6906) (xy 415.819082 -394.6906) (xy 415.795507 -394.690221)
			(xy 415.748919 -394.682977) (xy 415.704 -394.668648) (xy 415.661821 -394.647577) (xy 415.623388 -394.620265)
			(xy 415.589617 -394.587364) (xy 415.561312 -394.549657) (xy 415.549842 -394.529056) (xy 415.549334 -394.528294)
			(xy 415.15157 -393.839954) (xy 415.139712 -393.817268) (xy 415.122855 -393.768939) (xy 415.114274 -393.71848)
			(xy 415.113724 -393.692888) (xy 414.571476 -393.692888) (xy 414.8836 -394.232892) (xy 414.896333 -394.25621)
			(xy 414.914427 -394.306158) (xy 414.923643 -394.358477) (xy 414.92424 -394.385038) (xy 414.92424 -394.385292)
			(xy 414.92373 -394.409281) (xy 414.916226 -394.45667) (xy 414.901402 -394.502301) (xy 414.879622 -394.545051)
			(xy 414.851423 -394.583869) (xy 414.817499 -394.617797) (xy 414.778686 -394.646001) (xy 414.735938 -394.667787)
			(xy 414.690309 -394.682617) (xy 414.642921 -394.690127) (xy 414.618932 -394.6906) (xy 414.595359 -394.69018)
			(xy 414.548772 -394.682944) (xy 414.503854 -394.668623) (xy 414.461675 -394.647558) (xy 414.423242 -394.620253)
			(xy 414.38947 -394.587357) (xy 414.361163 -394.549654) (xy 414.349692 -394.529056) (xy 414.349184 -394.528294)
			(xy 413.95142 -393.839954) (xy 413.939487 -393.817294) (xy 413.922556 -393.768965) (xy 413.913903 -393.718491)
			(xy 413.91332 -393.692888) (xy 413.37158 -393.692888) (xy 413.683704 -394.232892) (xy 413.696437 -394.25621)
			(xy 413.714531 -394.306158) (xy 413.723747 -394.358477) (xy 413.724344 -394.385038) (xy 413.724344 -394.385292)
			(xy 413.72383 -394.409281) (xy 413.716326 -394.456669) (xy 413.701502 -394.5023) (xy 413.679723 -394.54505)
			(xy 413.651524 -394.583867) (xy 413.617601 -394.617796) (xy 413.578788 -394.646) (xy 413.536041 -394.667785)
			(xy 413.490412 -394.682616) (xy 413.443025 -394.690127) (xy 413.419036 -394.6906) (xy 413.395463 -394.690177)
			(xy 413.348876 -394.682941) (xy 413.303958 -394.668621) (xy 413.26178 -394.647557) (xy 413.223346 -394.620252)
			(xy 413.189574 -394.587356) (xy 413.161267 -394.549654) (xy 413.149796 -394.529056) (xy 413.149288 -394.528294)
			(xy 412.751524 -393.839954) (xy 412.739592 -393.817294) (xy 412.72266 -393.768965) (xy 412.714007 -393.718491)
			(xy 412.713424 -393.692888) (xy 412.17143 -393.692888) (xy 412.483554 -394.232892) (xy 412.49638 -394.256224)
			(xy 412.514599 -394.306247) (xy 412.523859 -394.358673) (xy 412.524448 -394.385292) (xy 412.523931 -394.409268)
			(xy 412.516436 -394.456632) (xy 412.501627 -394.50224) (xy 412.47987 -394.544973) (xy 412.4517 -394.583779)
			(xy 412.417809 -394.617703) (xy 412.379031 -394.645912) (xy 412.33632 -394.667711) (xy 412.290726 -394.682565)
			(xy 412.24337 -394.690107) (xy 412.219394 -394.6906) (xy 412.218886 -394.6906) (xy 412.195312 -394.690217)
			(xy 412.148723 -394.682974) (xy 412.103804 -394.668646) (xy 412.061626 -394.647576) (xy 412.023193 -394.620264)
			(xy 411.989421 -394.587363) (xy 411.961116 -394.549656) (xy 411.949646 -394.529056) (xy 411.949138 -394.528294)
			(xy 411.551374 -393.839954) (xy 411.539517 -393.817268) (xy 411.522659 -393.768939) (xy 411.514078 -393.718479)
			(xy 411.513528 -393.692888) (xy 410.971534 -393.692888) (xy 411.283658 -394.232892) (xy 411.296484 -394.256224)
			(xy 411.314704 -394.306247) (xy 411.323963 -394.358673) (xy 411.324552 -394.385292) (xy 411.324031 -394.409268)
			(xy 411.316536 -394.456631) (xy 411.301727 -394.502239) (xy 411.279971 -394.544972) (xy 411.251801 -394.583778)
			(xy 411.217911 -394.617702) (xy 411.179133 -394.645911) (xy 411.136423 -394.66771) (xy 411.090829 -394.682564)
			(xy 411.043474 -394.690107) (xy 411.019498 -394.6906) (xy 411.01899 -394.6906) (xy 410.995416 -394.690214)
			(xy 410.948827 -394.682971) (xy 410.903908 -394.668644) (xy 410.86173 -394.647574) (xy 410.823297 -394.620263)
			(xy 410.789526 -394.587363) (xy 410.76122 -394.549656) (xy 410.74975 -394.529056) (xy 410.749242 -394.528294)
			(xy 410.351478 -393.839954) (xy 410.339621 -393.817268) (xy 410.322763 -393.768939) (xy 410.314182 -393.718479)
			(xy 410.313632 -393.692888) (xy 409.771638 -393.692888) (xy 410.083762 -394.232892) (xy 410.096589 -394.256224)
			(xy 410.114808 -394.306247) (xy 410.124067 -394.358673) (xy 410.124656 -394.385292) (xy 410.124131 -394.409268)
			(xy 410.116636 -394.45663) (xy 410.101828 -394.502239) (xy 410.080072 -394.544971) (xy 410.051902 -394.583776)
			(xy 410.018012 -394.617701) (xy 409.979235 -394.645909) (xy 409.936525 -394.667709) (xy 409.890932 -394.682563)
			(xy 409.843577 -394.690107) (xy 409.819602 -394.6906) (xy 409.819094 -394.6906) (xy 409.79552 -394.690211)
			(xy 409.748931 -394.682969) (xy 409.704013 -394.668642) (xy 409.661834 -394.647573) (xy 409.623401 -394.620262)
			(xy 409.58963 -394.587362) (xy 409.561324 -394.549656) (xy 409.549854 -394.529056) (xy 409.549346 -394.528294)
			(xy 409.151582 -393.839954) (xy 409.139725 -393.817268) (xy 409.122867 -393.768939) (xy 409.114286 -393.718479)
			(xy 409.113736 -393.692888) (xy 408.571488 -393.692888) (xy 408.883612 -394.232892) (xy 408.896346 -394.25621)
			(xy 408.914439 -394.306158) (xy 408.923655 -394.358477) (xy 408.924252 -394.385038) (xy 408.924252 -394.385292)
			(xy 408.92373 -394.409281) (xy 408.916227 -394.456668) (xy 408.901403 -394.502298) (xy 408.879624 -394.545048)
			(xy 408.851427 -394.583865) (xy 408.817504 -394.617793) (xy 408.778692 -394.645997) (xy 408.735946 -394.667783)
			(xy 408.690319 -394.682614) (xy 408.642933 -394.690126) (xy 408.618944 -394.6906) (xy 408.595371 -394.690171)
			(xy 408.548785 -394.682936) (xy 408.503867 -394.668616) (xy 408.461689 -394.647554) (xy 408.423255 -394.620249)
			(xy 408.389482 -394.587355) (xy 408.361175 -394.549654) (xy 408.349704 -394.529056) (xy 408.349196 -394.528294)
			(xy 407.951432 -393.839954) (xy 407.9395 -393.817294) (xy 407.922568 -393.768965) (xy 407.913915 -393.718491)
			(xy 407.913332 -393.692888) (xy 407.371592 -393.692888) (xy 407.683716 -394.232892) (xy 407.69645 -394.256209)
			(xy 407.714543 -394.306158) (xy 407.723759 -394.358477) (xy 407.724356 -394.385038) (xy 407.724356 -394.385292)
			(xy 407.72383 -394.409281) (xy 407.716327 -394.456667) (xy 407.701503 -394.502297) (xy 407.679725 -394.545047)
			(xy 407.651528 -394.583863) (xy 407.617606 -394.617791) (xy 407.578794 -394.645996) (xy 407.536049 -394.667782)
			(xy 407.490422 -394.682614) (xy 407.443037 -394.690126) (xy 407.419048 -394.6906) (xy 407.395475 -394.690168)
			(xy 407.348889 -394.682933) (xy 407.303971 -394.668614) (xy 407.261793 -394.647552) (xy 407.223359 -394.620248)
			(xy 407.189586 -394.587354) (xy 407.161279 -394.549654) (xy 407.149808 -394.529056) (xy 407.1493 -394.528294)
			(xy 406.751536 -393.839954) (xy 406.739605 -393.817294) (xy 406.722672 -393.768964) (xy 406.714019 -393.718491)
			(xy 406.713436 -393.692888) (xy 406.171442 -393.692888) (xy 406.483566 -394.232892) (xy 406.496393 -394.256223)
			(xy 406.514612 -394.306247) (xy 406.523871 -394.358673) (xy 406.52446 -394.385292) (xy 406.524031 -394.409273)
			(xy 406.516532 -394.456644) (xy 406.501719 -394.502261) (xy 406.479954 -394.544999) (xy 406.451774 -394.583809)
			(xy 406.417872 -394.617735) (xy 406.379082 -394.645942) (xy 406.336359 -394.667737) (xy 406.290753 -394.682582)
			(xy 406.243386 -394.690114) (xy 406.219406 -394.6906) (xy 406.218898 -394.6906) (xy 406.195324 -394.690208)
			(xy 406.148736 -394.682966) (xy 406.103817 -394.66864) (xy 406.061639 -394.647571) (xy 406.023206 -394.620261)
			(xy 405.989434 -394.587361) (xy 405.961128 -394.549656) (xy 405.949658 -394.529056) (xy 405.94915 -394.528294)
			(xy 405.551386 -393.839954) (xy 405.53953 -393.817267) (xy 405.522671 -393.768939) (xy 405.51409 -393.718479)
			(xy 405.51354 -393.692888) (xy 404.971546 -393.692888) (xy 405.28367 -394.232892) (xy 405.296497 -394.256223)
			(xy 405.314716 -394.306247) (xy 405.323975 -394.358673) (xy 405.324564 -394.385292) (xy 405.324131 -394.409273)
			(xy 405.316633 -394.456644) (xy 405.301819 -394.50226) (xy 405.280055 -394.544998) (xy 405.251875 -394.583808)
			(xy 405.217974 -394.617733) (xy 405.179184 -394.645941) (xy 405.136461 -394.667735) (xy 405.090856 -394.682581)
			(xy 405.04349 -394.690114) (xy 405.01951 -394.6906) (xy 405.019002 -394.6906) (xy 404.995428 -394.690205)
			(xy 404.94884 -394.682963) (xy 404.903921 -394.668638) (xy 404.861743 -394.64757) (xy 404.82331 -394.62026)
			(xy 404.789538 -394.587361) (xy 404.761233 -394.549656) (xy 404.749762 -394.529056) (xy 404.749254 -394.528294)
			(xy 404.35149 -393.839954) (xy 404.339634 -393.817267) (xy 404.322775 -393.768939) (xy 404.314194 -393.718479)
			(xy 404.313644 -393.692888) (xy 403.77165 -393.692888) (xy 404.083774 -394.232892) (xy 404.096601 -394.256223)
			(xy 404.11482 -394.306247) (xy 404.124079 -394.358673) (xy 404.124668 -394.385292) (xy 404.124231 -394.409272)
			(xy 404.116733 -394.456643) (xy 404.101919 -394.502259) (xy 404.080155 -394.544997) (xy 404.051976 -394.583806)
			(xy 404.018075 -394.617732) (xy 403.979287 -394.645939) (xy 403.936564 -394.667734) (xy 403.890959 -394.682581)
			(xy 403.843594 -394.690113) (xy 403.819614 -394.6906) (xy 403.819106 -394.6906) (xy 403.795532 -394.690201)
			(xy 403.748944 -394.682961) (xy 403.704026 -394.668636) (xy 403.661847 -394.647568) (xy 403.623414 -394.620259)
			(xy 403.589642 -394.58736) (xy 403.561337 -394.549655) (xy 403.549866 -394.529056) (xy 403.549358 -394.528294)
			(xy 403.151594 -393.839954) (xy 403.139738 -393.817267) (xy 403.122879 -393.768939) (xy 403.114298 -393.718479)
			(xy 403.113748 -393.692888) (xy 389.243866 -393.692888) (xy 389.55599 -394.232892) (xy 389.568819 -394.256222)
			(xy 389.587037 -394.306246) (xy 389.596295 -394.358673) (xy 389.596884 -394.385292) (xy 389.596431 -394.409272)
			(xy 389.588933 -394.456641) (xy 389.574121 -394.502255) (xy 389.552358 -394.544992) (xy 389.524181 -394.583801)
			(xy 389.490282 -394.617726) (xy 389.451496 -394.645934) (xy 389.408775 -394.66773) (xy 389.363173 -394.682578)
			(xy 389.315809 -394.690112) (xy 389.29183 -394.6906) (xy 389.291322 -394.6906) (xy 389.267749 -394.690188)
			(xy 389.221161 -394.68295) (xy 389.176243 -394.668628) (xy 389.134065 -394.647562) (xy 389.095631 -394.620255)
			(xy 389.061859 -394.587358) (xy 389.033553 -394.549655) (xy 389.022082 -394.529056) (xy 389.021574 -394.528294)
			(xy 388.62381 -393.839954) (xy 388.611948 -393.81727) (xy 388.595093 -393.76894) (xy 388.586513 -393.71848)
			(xy 388.585964 -393.692888) (xy 388.043716 -393.692888) (xy 388.35584 -394.232892) (xy 388.368576 -394.256208)
			(xy 388.386668 -394.306157) (xy 388.395883 -394.358476) (xy 388.39648 -394.385038) (xy 388.39648 -394.385292)
			(xy 388.396054 -394.409286) (xy 388.388548 -394.456684) (xy 388.373719 -394.502324) (xy 388.351932 -394.545082)
			(xy 388.323724 -394.583905) (xy 388.28979 -394.617837) (xy 388.250965 -394.646042) (xy 388.208206 -394.667826)
			(xy 388.162565 -394.682653) (xy 388.115166 -394.690156) (xy 388.091172 -394.6906) (xy 388.067597 -394.690229)
			(xy 388.021008 -394.682983) (xy 387.976089 -394.668653) (xy 387.93391 -394.647581) (xy 387.895478 -394.620268)
			(xy 387.861707 -394.587365) (xy 387.833402 -394.549657) (xy 387.821932 -394.529056) (xy 387.821424 -394.528294)
			(xy 387.42366 -393.839954) (xy 387.41173 -393.817293) (xy 387.394797 -393.768964) (xy 387.386143 -393.718491)
			(xy 387.38556 -393.692888) (xy 386.84382 -393.692888) (xy 387.155944 -394.232892) (xy 387.16868 -394.256208)
			(xy 387.186772 -394.306157) (xy 387.195988 -394.358476) (xy 387.196584 -394.385038) (xy 387.196584 -394.385292)
			(xy 387.196154 -394.409286) (xy 387.188648 -394.456684) (xy 387.173819 -394.502323) (xy 387.152033 -394.545081)
			(xy 387.123825 -394.583904) (xy 387.089892 -394.617836) (xy 387.051067 -394.646041) (xy 387.008308 -394.667825)
			(xy 386.962668 -394.682652) (xy 386.91527 -394.690156) (xy 386.891276 -394.6906) (xy 386.867701 -394.690226)
			(xy 386.821112 -394.68298) (xy 386.776193 -394.668651) (xy 386.734015 -394.647579) (xy 386.695582 -394.620267)
			(xy 386.661811 -394.587365) (xy 386.633506 -394.549657) (xy 386.622036 -394.529056) (xy 386.621528 -394.528294)
			(xy 386.223764 -393.839954) (xy 386.211835 -393.817292) (xy 386.194901 -393.768964) (xy 386.186248 -393.718491)
			(xy 386.185664 -393.692888) (xy 385.64367 -393.692888) (xy 385.955794 -394.232892) (xy 385.968623 -394.256222)
			(xy 385.986841 -394.306246) (xy 385.996099 -394.358673) (xy 385.996688 -394.385292) (xy 385.996231 -394.409271)
			(xy 385.988733 -394.45664) (xy 385.973921 -394.502254) (xy 385.952159 -394.544991) (xy 385.923982 -394.5838)
			(xy 385.890084 -394.617725) (xy 385.851298 -394.645932) (xy 385.808578 -394.667728) (xy 385.762976 -394.682577)
			(xy 385.715613 -394.690112) (xy 385.691634 -394.6906) (xy 385.691126 -394.6906) (xy 385.667553 -394.690185)
			(xy 385.620965 -394.682948) (xy 385.576047 -394.668626) (xy 385.533869 -394.64756) (xy 385.495436 -394.620254)
			(xy 385.461663 -394.587357) (xy 385.433357 -394.549655) (xy 385.421886 -394.529056) (xy 385.421378 -394.528294)
			(xy 385.023614 -393.839954) (xy 385.011752 -393.81727) (xy 384.994897 -393.76894) (xy 384.986317 -393.71848)
			(xy 384.985768 -393.692888) (xy 384.443774 -393.692888) (xy 384.755898 -394.232892) (xy 384.768719 -394.256226)
			(xy 384.786942 -394.306248) (xy 384.796203 -394.358674) (xy 384.796792 -394.385292) (xy 384.796331 -394.409271)
			(xy 384.788834 -394.45664) (xy 384.774022 -394.502253) (xy 384.75226 -394.54499) (xy 384.724083 -394.583798)
			(xy 384.690186 -394.617723) (xy 384.6514 -394.645931) (xy 384.608681 -394.667727) (xy 384.563079 -394.682576)
			(xy 384.515717 -394.690112) (xy 384.491738 -394.6906) (xy 384.49123 -394.6906) (xy 384.467657 -394.690182)
			(xy 384.42107 -394.682945) (xy 384.376152 -394.668624) (xy 384.333973 -394.647559) (xy 384.29554 -394.620253)
			(xy 384.261768 -394.587357) (xy 384.233461 -394.549654) (xy 384.22199 -394.529056) (xy 384.221482 -394.528294)
			(xy 383.823718 -393.839954) (xy 383.811856 -393.81727) (xy 383.795001 -393.76894) (xy 383.786421 -393.71848)
			(xy 383.785872 -393.692888) (xy 383.243878 -393.692888) (xy 383.556002 -394.232892) (xy 383.568824 -394.256226)
			(xy 383.587046 -394.306248) (xy 383.596307 -394.358674) (xy 383.596896 -394.385292) (xy 383.596431 -394.409271)
			(xy 383.588934 -394.456639) (xy 383.574122 -394.502252) (xy 383.552361 -394.544989) (xy 383.524185 -394.583797)
			(xy 383.490287 -394.617722) (xy 383.451502 -394.64593) (xy 383.408784 -394.667726) (xy 383.363183 -394.682575)
			(xy 383.315821 -394.690111) (xy 383.291842 -394.6906) (xy 383.291334 -394.6906) (xy 383.267761 -394.690179)
			(xy 383.221174 -394.682942) (xy 383.176256 -394.668622) (xy 383.134078 -394.647557) (xy 383.095644 -394.620252)
			(xy 383.061872 -394.587356) (xy 383.033565 -394.549654) (xy 383.022094 -394.529056) (xy 383.021586 -394.528294)
			(xy 382.623822 -393.839954) (xy 382.611961 -393.81727) (xy 382.595105 -393.76894) (xy 382.586526 -393.71848)
			(xy 382.585976 -393.692888) (xy 382.043728 -393.692888) (xy 382.355852 -394.232892) (xy 382.368589 -394.256208)
			(xy 382.386681 -394.306157) (xy 382.395896 -394.358476) (xy 382.396492 -394.385038) (xy 382.396492 -394.385292)
			(xy 382.396054 -394.409286) (xy 382.388548 -394.456682) (xy 382.37372 -394.502321) (xy 382.351934 -394.545079)
			(xy 382.323728 -394.583901) (xy 382.289795 -394.617833) (xy 382.250972 -394.646038) (xy 382.208214 -394.667823)
			(xy 382.162575 -394.68265) (xy 382.115178 -394.690155) (xy 382.091184 -394.6906) (xy 382.06761 -394.690219)
			(xy 382.021021 -394.682975) (xy 381.976102 -394.668647) (xy 381.933923 -394.647576) (xy 381.895491 -394.620265)
			(xy 381.861719 -394.587363) (xy 381.833414 -394.549656) (xy 381.821944 -394.529056) (xy 381.821436 -394.528294)
			(xy 381.423672 -393.839954) (xy 381.411736 -393.817296) (xy 381.394806 -393.768965) (xy 381.386155 -393.718492)
			(xy 381.385572 -393.692888) (xy 380.843832 -393.692888) (xy 381.155956 -394.232892) (xy 381.168693 -394.256208)
			(xy 381.186785 -394.306157) (xy 381.196 -394.358476) (xy 381.196596 -394.385038) (xy 381.196596 -394.385292)
			(xy 381.196154 -394.409286) (xy 381.188648 -394.456682) (xy 381.17382 -394.50232) (xy 381.152035 -394.545077)
			(xy 381.123829 -394.5839) (xy 381.089897 -394.617831) (xy 381.051074 -394.646037) (xy 381.008317 -394.667822)
			(xy 380.962678 -394.682649) (xy 380.915282 -394.690155) (xy 380.891288 -394.6906) (xy 380.867714 -394.690216)
			(xy 380.821125 -394.682973) (xy 380.776206 -394.668645) (xy 380.734028 -394.647575) (xy 380.695595 -394.620264)
			(xy 380.661823 -394.587363) (xy 380.633518 -394.549656) (xy 380.622048 -394.529056) (xy 380.62154 -394.528294)
			(xy 380.223776 -393.839954) (xy 380.21184 -393.817296) (xy 380.19491 -393.768965) (xy 380.186259 -393.718492)
			(xy 380.185676 -393.692888) (xy 379.643682 -393.692888) (xy 379.955806 -394.232892) (xy 379.968628 -394.256226)
			(xy 379.98685 -394.306248) (xy 379.996111 -394.358674) (xy 379.9967 -394.385292) (xy 379.996231 -394.409271)
			(xy 379.988734 -394.456639) (xy 379.973922 -394.502251) (xy 379.952161 -394.544988) (xy 379.923986 -394.583795)
			(xy 379.890089 -394.617721) (xy 379.851304 -394.645928) (xy 379.808586 -394.667725) (xy 379.762986 -394.682574)
			(xy 379.715624 -394.690111) (xy 379.691646 -394.6906) (xy 379.691138 -394.6906) (xy 379.667565 -394.690176)
			(xy 379.620978 -394.68294) (xy 379.57606 -394.66862) (xy 379.533882 -394.647556) (xy 379.495448 -394.620251)
			(xy 379.461676 -394.587356) (xy 379.433369 -394.549654) (xy 379.421898 -394.529056) (xy 379.42139 -394.528294)
			(xy 379.023626 -393.839954) (xy 379.011765 -393.81727) (xy 378.994909 -393.76894) (xy 378.98633 -393.71848)
			(xy 378.98578 -393.692888) (xy 378.443786 -393.692888) (xy 378.75591 -394.232892) (xy 378.768732 -394.256226)
			(xy 378.786954 -394.306248) (xy 378.796215 -394.358673) (xy 378.796804 -394.385292) (xy 378.796331 -394.409271)
			(xy 378.788834 -394.456638) (xy 378.774023 -394.502251) (xy 378.752262 -394.544986) (xy 378.724087 -394.583794)
			(xy 378.690191 -394.617719) (xy 378.651407 -394.645927) (xy 378.608689 -394.667724) (xy 378.563089 -394.682574)
			(xy 378.515728 -394.690111) (xy 378.49175 -394.6906) (xy 378.491242 -394.6906) (xy 378.467669 -394.690172)
			(xy 378.421083 -394.682937) (xy 378.376165 -394.668617) (xy 378.333986 -394.647554) (xy 378.295553 -394.62025)
			(xy 378.26178 -394.587355) (xy 378.233473 -394.549654) (xy 378.222002 -394.529056) (xy 378.221494 -394.528294)
			(xy 377.82373 -393.839954) (xy 377.811869 -393.81727) (xy 377.795013 -393.76894) (xy 377.786434 -393.71848)
			(xy 377.785884 -393.692888) (xy 377.24389 -393.692888) (xy 377.556014 -394.232892) (xy 377.568837 -394.256226)
			(xy 377.587058 -394.306248) (xy 377.596319 -394.358673) (xy 377.596908 -394.385292) (xy 377.596431 -394.40927)
			(xy 377.588934 -394.456637) (xy 377.574123 -394.50225) (xy 377.552363 -394.544985) (xy 377.524188 -394.583793)
			(xy 377.490292 -394.617718) (xy 377.451509 -394.645926) (xy 377.408792 -394.667723) (xy 377.363192 -394.682573)
			(xy 377.315832 -394.69011) (xy 377.291854 -394.6906) (xy 377.291346 -394.6906) (xy 377.267773 -394.690169)
			(xy 377.221187 -394.682935) (xy 377.176269 -394.668615) (xy 377.134091 -394.647553) (xy 377.095657 -394.620249)
			(xy 377.061884 -394.587355) (xy 377.033577 -394.549654) (xy 377.022106 -394.529056) (xy 377.021598 -394.528294)
			(xy 376.623834 -393.839954) (xy 376.611974 -393.81727) (xy 376.595118 -393.76894) (xy 376.586538 -393.71848)
			(xy 376.585988 -393.692888) (xy 376.04374 -393.692888) (xy 376.355864 -394.232892) (xy 376.368602 -394.256207)
			(xy 376.386693 -394.306157) (xy 376.395908 -394.358476) (xy 376.396504 -394.385038) (xy 376.396504 -394.385292)
			(xy 376.396054 -394.409285) (xy 376.388549 -394.456681) (xy 376.373721 -394.502319) (xy 376.351936 -394.545075)
			(xy 376.323731 -394.583897) (xy 376.2898 -394.617829) (xy 376.250978 -394.646034) (xy 376.208222 -394.66782)
			(xy 376.162585 -394.682648) (xy 376.115189 -394.690154) (xy 376.091196 -394.6906) (xy 376.067622 -394.690209)
			(xy 376.021033 -394.682967) (xy 375.976115 -394.668641) (xy 375.933936 -394.647572) (xy 375.895503 -394.620262)
			(xy 375.861732 -394.587362) (xy 375.833426 -394.549656) (xy 375.821956 -394.529056) (xy 375.821448 -394.528294)
			(xy 375.423684 -393.839954) (xy 375.411748 -393.817296) (xy 375.394819 -393.768965) (xy 375.386167 -393.718492)
			(xy 375.385584 -393.692888) (xy 374.843844 -393.692888) (xy 375.155968 -394.232892) (xy 375.168706 -394.256207)
			(xy 375.186797 -394.306157) (xy 375.196012 -394.358476) (xy 375.196608 -394.385038) (xy 375.196608 -394.385292)
			(xy 375.196154 -394.409285) (xy 375.188649 -394.45668) (xy 375.173821 -394.502318) (xy 375.152037 -394.545074)
			(xy 375.123832 -394.583896) (xy 375.089902 -394.617827) (xy 375.051081 -394.646033) (xy 375.008325 -394.667818)
			(xy 374.962688 -394.682647) (xy 374.915293 -394.690154) (xy 374.8913 -394.6906) (xy 374.867726 -394.690206)
			(xy 374.821138 -394.682965) (xy 374.776219 -394.668639) (xy 374.734041 -394.64757) (xy 374.695608 -394.620261)
			(xy 374.661836 -394.587361) (xy 374.63353 -394.549656) (xy 374.62206 -394.529056) (xy 374.621552 -394.528294)
			(xy 374.223788 -393.839954) (xy 374.211853 -393.817296) (xy 374.194923 -393.768965) (xy 374.186271 -393.718491)
			(xy 374.185688 -393.692888) (xy 373.643694 -393.692888) (xy 373.955818 -394.232892) (xy 373.968641 -394.256226)
			(xy 373.986862 -394.306248) (xy 373.996123 -394.358673) (xy 373.996712 -394.385292) (xy 373.996231 -394.40927)
			(xy 373.988734 -394.456637) (xy 373.973924 -394.502249) (xy 373.952164 -394.544984) (xy 373.923989 -394.583791)
			(xy 373.890094 -394.617716) (xy 373.851311 -394.645924) (xy 373.808595 -394.667722) (xy 373.762996 -394.682572)
			(xy 373.715636 -394.69011) (xy 373.691658 -394.6906) (xy 373.69115 -394.6906) (xy 373.667577 -394.690166)
			(xy 373.620991 -394.682932) (xy 373.576073 -394.668613) (xy 373.533895 -394.647551) (xy 373.495461 -394.620248)
			(xy 373.461688 -394.587354) (xy 373.433381 -394.549653) (xy 373.42191 -394.529056) (xy 373.421402 -394.528294)
			(xy 373.023638 -393.839954) (xy 373.011778 -393.817269) (xy 372.994922 -393.76894) (xy 372.986342 -393.71848)
			(xy 372.985792 -393.692888) (xy 372.443798 -393.692888) (xy 372.755922 -394.232892) (xy 372.768745 -394.256225)
			(xy 372.786966 -394.306248) (xy 372.796227 -394.358673) (xy 372.796816 -394.385292) (xy 372.796331 -394.40927)
			(xy 372.788834 -394.456636) (xy 372.774024 -394.502248) (xy 372.752264 -394.544983) (xy 372.72409 -394.58379)
			(xy 372.690196 -394.617715) (xy 372.651413 -394.645923) (xy 372.608698 -394.66772) (xy 372.563099 -394.682571)
			(xy 372.51574 -394.69011) (xy 372.491762 -394.6906) (xy 372.491254 -394.6906) (xy 372.467682 -394.690163)
			(xy 372.421095 -394.682929) (xy 372.376178 -394.668611) (xy 372.333999 -394.64755) (xy 372.295566 -394.620247)
			(xy 372.261793 -394.587353) (xy 372.233485 -394.549653) (xy 372.222014 -394.529056) (xy 372.221506 -394.528294)
			(xy 371.823742 -393.839954) (xy 371.811882 -393.817269) (xy 371.795026 -393.76894) (xy 371.786446 -393.71848)
			(xy 371.785896 -393.692888) (xy 371.243902 -393.692888) (xy 371.556026 -394.232892) (xy 371.56885 -394.256225)
			(xy 371.587071 -394.306247) (xy 371.596331 -394.358673) (xy 371.59692 -394.385292) (xy 371.596431 -394.40927)
			(xy 371.588935 -394.456636) (xy 371.574124 -394.502247) (xy 371.552365 -394.544982) (xy 371.524192 -394.583789)
			(xy 371.490297 -394.617713) (xy 371.451516 -394.645922) (xy 371.4088 -394.667719) (xy 371.363202 -394.68257)
			(xy 371.315843 -394.69011) (xy 371.291866 -394.6906) (xy 371.291358 -394.6906) (xy 371.267786 -394.690159)
			(xy 371.2212 -394.682927) (xy 371.176282 -394.668609) (xy 371.134104 -394.647548) (xy 371.09567 -394.620246)
			(xy 371.061897 -394.587353) (xy 371.03359 -394.549653) (xy 371.022118 -394.529056) (xy 371.02161 -394.528294)
			(xy 370.623846 -393.839954) (xy 370.611986 -393.817269) (xy 370.59513 -393.76894) (xy 370.58655 -393.71848)
			(xy 370.586 -393.692888) (xy 354.671418 -393.692888) (xy 354.983542 -394.232892) (xy 354.996367 -394.256224)
			(xy 355.014587 -394.306247) (xy 355.023847 -394.358673) (xy 355.024436 -394.385292) (xy 355.023931 -394.409269)
			(xy 355.016435 -394.456633) (xy 355.001626 -394.502243) (xy 354.979868 -394.544977) (xy 354.951696 -394.583783)
			(xy 354.917804 -394.617708) (xy 354.879024 -394.645916) (xy 354.836311 -394.667715) (xy 354.790716 -394.682567)
			(xy 354.743358 -394.690108) (xy 354.719382 -394.6906) (xy 354.718874 -394.6906) (xy 354.695299 -394.690227)
			(xy 354.64871 -394.682982) (xy 354.603791 -394.668652) (xy 354.561613 -394.64758) (xy 354.52318 -394.620267)
			(xy 354.489409 -394.587365) (xy 354.461104 -394.549657) (xy 354.449634 -394.529056) (xy 354.449126 -394.528294)
			(xy 354.051362 -393.839954) (xy 354.039504 -393.817268) (xy 354.022646 -393.76894) (xy 354.014066 -393.71848)
			(xy 354.013516 -393.692888) (xy 353.471522 -393.692888) (xy 353.783646 -394.232892) (xy 353.796471 -394.256224)
			(xy 353.814691 -394.306247) (xy 353.823951 -394.358673) (xy 353.82454 -394.385292) (xy 353.824054 -394.409296)
			(xy 353.816541 -394.456713) (xy 353.8017 -394.502369) (xy 353.779896 -394.54514) (xy 353.751667 -394.583972)
			(xy 353.717709 -394.617907) (xy 353.678857 -394.646108) (xy 353.636071 -394.667882) (xy 353.590404 -394.682691)
			(xy 353.542982 -394.69017) (xy 353.518978 -394.6906) (xy 353.518724 -394.6906) (xy 353.495151 -394.690187)
			(xy 353.448563 -394.682949) (xy 353.403645 -394.668627) (xy 353.361467 -394.647561) (xy 353.323033 -394.620255)
			(xy 353.289261 -394.587358) (xy 353.260955 -394.549655) (xy 353.249484 -394.529056) (xy 353.248976 -394.528294)
			(xy 352.851212 -393.839954) (xy 352.839279 -393.817295) (xy 352.822347 -393.768965) (xy 352.813695 -393.718491)
			(xy 352.813112 -393.692888) (xy 352.271372 -393.692888) (xy 352.583496 -394.232892) (xy 352.596228 -394.25621)
			(xy 352.614323 -394.306158) (xy 352.623539 -394.358477) (xy 352.624136 -394.385038) (xy 352.624136 -394.385292)
			(xy 352.62363 -394.409282) (xy 352.616126 -394.45667) (xy 352.601301 -394.502302) (xy 352.579521 -394.545053)
			(xy 352.551322 -394.58387) (xy 352.517397 -394.617798) (xy 352.478583 -394.646002) (xy 352.435835 -394.667788)
			(xy 352.390205 -394.682618) (xy 352.342818 -394.690127) (xy 352.318828 -394.6906) (xy 352.295255 -394.690184)
			(xy 352.248668 -394.682946) (xy 352.20375 -394.668625) (xy 352.161571 -394.64756) (xy 352.123138 -394.620254)
			(xy 352.089365 -394.587357) (xy 352.061059 -394.549654) (xy 352.049588 -394.529056) (xy 352.04908 -394.528294)
			(xy 351.651316 -393.839954) (xy 351.639383 -393.817294) (xy 351.622452 -393.768965) (xy 351.613799 -393.718491)
			(xy 351.613216 -393.692888) (xy 351.071476 -393.692888) (xy 351.3836 -394.232892) (xy 351.396333 -394.25621)
			(xy 351.414427 -394.306158) (xy 351.423643 -394.358477) (xy 351.42424 -394.385038) (xy 351.42424 -394.385292)
			(xy 351.42373 -394.409281) (xy 351.416226 -394.45667) (xy 351.401402 -394.502301) (xy 351.379622 -394.545051)
			(xy 351.351423 -394.583869) (xy 351.317499 -394.617797) (xy 351.278686 -394.646001) (xy 351.235938 -394.667787)
			(xy 351.190309 -394.682617) (xy 351.142921 -394.690127) (xy 351.118932 -394.6906) (xy 351.118678 -394.6906)
			(xy 351.095103 -394.690224) (xy 351.048514 -394.682979) (xy 351.003595 -394.66865) (xy 350.961417 -394.647579)
			(xy 350.922984 -394.620266) (xy 350.889213 -394.587364) (xy 350.860908 -394.549657) (xy 350.849438 -394.529056)
			(xy 350.84893 -394.528294) (xy 350.451166 -393.839954) (xy 350.439308 -393.817268) (xy 350.42245 -393.76894)
			(xy 350.41387 -393.71848) (xy 350.41332 -393.692888) (xy 349.871326 -393.692888) (xy 350.18345 -394.232892)
			(xy 350.196276 -394.256224) (xy 350.214495 -394.306247) (xy 350.223755 -394.358673) (xy 350.224344 -394.385292)
			(xy 350.223831 -394.409269) (xy 350.216335 -394.456632) (xy 350.201527 -394.502241) (xy 350.179769 -394.544974)
			(xy 350.151599 -394.58378) (xy 350.117707 -394.617705) (xy 350.078929 -394.645913) (xy 350.036217 -394.667712)
			(xy 349.990622 -394.682566) (xy 349.943266 -394.690108) (xy 349.91929 -394.6906) (xy 349.918782 -394.6906)
			(xy 349.895207 -394.690221) (xy 349.848619 -394.682977) (xy 349.8037 -394.668648) (xy 349.761521 -394.647577)
			(xy 349.723088 -394.620265) (xy 349.689317 -394.587364) (xy 349.661012 -394.549657) (xy 349.649542 -394.529056)
			(xy 349.649034 -394.528294) (xy 349.25127 -393.839954) (xy 349.239412 -393.817268) (xy 349.222555 -393.768939)
			(xy 349.213974 -393.71848) (xy 349.213424 -393.692888) (xy 348.67143 -393.692888) (xy 348.983554 -394.232892)
			(xy 348.99638 -394.256224) (xy 349.014599 -394.306247) (xy 349.023859 -394.358673) (xy 349.024448 -394.385292)
			(xy 349.023931 -394.409268) (xy 349.016436 -394.456632) (xy 349.001627 -394.50224) (xy 348.97987 -394.544973)
			(xy 348.9517 -394.583779) (xy 348.917809 -394.617703) (xy 348.879031 -394.645912) (xy 348.83632 -394.667711)
			(xy 348.790726 -394.682565) (xy 348.74337 -394.690107) (xy 348.719394 -394.6906) (xy 348.718886 -394.6906)
			(xy 348.695312 -394.690217) (xy 348.648723 -394.682974) (xy 348.603804 -394.668646) (xy 348.561626 -394.647576)
			(xy 348.523193 -394.620264) (xy 348.489421 -394.587363) (xy 348.461116 -394.549656) (xy 348.449646 -394.529056)
			(xy 348.449138 -394.528294) (xy 348.051374 -393.839954) (xy 348.039517 -393.817268) (xy 348.022659 -393.768939)
			(xy 348.014078 -393.718479) (xy 348.013528 -393.692888) (xy 347.47128 -393.692888) (xy 347.783404 -394.232892)
			(xy 347.796137 -394.25621) (xy 347.814231 -394.306158) (xy 347.823447 -394.358477) (xy 347.824044 -394.385038)
			(xy 347.824044 -394.385292) (xy 347.82353 -394.409281) (xy 347.816026 -394.456669) (xy 347.801202 -394.5023)
			(xy 347.779423 -394.54505) (xy 347.751224 -394.583867) (xy 347.717301 -394.617796) (xy 347.678488 -394.646)
			(xy 347.635741 -394.667785) (xy 347.590112 -394.682616) (xy 347.542725 -394.690127) (xy 347.518736 -394.6906)
			(xy 347.495163 -394.690177) (xy 347.448576 -394.682941) (xy 347.403658 -394.668621) (xy 347.36148 -394.647557)
			(xy 347.323046 -394.620252) (xy 347.289274 -394.587356) (xy 347.260967 -394.549654) (xy 347.249496 -394.529056)
			(xy 347.248988 -394.528294) (xy 346.851224 -393.839954) (xy 346.839292 -393.817294) (xy 346.82236 -393.768965)
			(xy 346.813707 -393.718491) (xy 346.813124 -393.692888) (xy 346.271384 -393.692888) (xy 346.583508 -394.232892)
			(xy 346.596241 -394.25621) (xy 346.614335 -394.306158) (xy 346.623551 -394.358477) (xy 346.624148 -394.385038)
			(xy 346.624148 -394.385292) (xy 346.62363 -394.409281) (xy 346.616126 -394.456669) (xy 346.601303 -394.502299)
			(xy 346.579524 -394.545049) (xy 346.551325 -394.583866) (xy 346.517403 -394.617794) (xy 346.47859 -394.645998)
			(xy 346.435843 -394.667784) (xy 346.390215 -394.682615) (xy 346.342829 -394.690126) (xy 346.31884 -394.6906)
			(xy 346.295267 -394.690174) (xy 346.24868 -394.682939) (xy 346.203763 -394.668618) (xy 346.161584 -394.647555)
			(xy 346.123151 -394.620251) (xy 346.089378 -394.587355) (xy 346.061071 -394.549654) (xy 346.0496 -394.529056)
			(xy 346.049092 -394.528294) (xy 345.651328 -393.839954) (xy 345.639396 -393.817294) (xy 345.622464 -393.768965)
			(xy 345.613811 -393.718491) (xy 345.613228 -393.692888) (xy 345.071488 -393.692888) (xy 345.383612 -394.232892)
			(xy 345.396346 -394.25621) (xy 345.414439 -394.306158) (xy 345.423655 -394.358477) (xy 345.424252 -394.385038)
			(xy 345.424252 -394.385292) (xy 345.42373 -394.409281) (xy 345.416227 -394.456668) (xy 345.401403 -394.502298)
			(xy 345.379624 -394.545048) (xy 345.351427 -394.583865) (xy 345.317504 -394.617793) (xy 345.278692 -394.645997)
			(xy 345.235946 -394.667783) (xy 345.190319 -394.682614) (xy 345.142933 -394.690126) (xy 345.118944 -394.6906)
			(xy 345.11869 -394.6906) (xy 345.095116 -394.690214) (xy 345.048527 -394.682971) (xy 345.003608 -394.668644)
			(xy 344.96143 -394.647574) (xy 344.922997 -394.620263) (xy 344.889226 -394.587363) (xy 344.86092 -394.549656)
			(xy 344.84945 -394.529056) (xy 344.848942 -394.528294) (xy 344.451178 -393.839954) (xy 344.439321 -393.817268)
			(xy 344.422463 -393.768939) (xy 344.413882 -393.718479) (xy 344.413332 -393.692888) (xy 343.871338 -393.692888)
			(xy 344.183462 -394.232892) (xy 344.196289 -394.256224) (xy 344.214508 -394.306247) (xy 344.223767 -394.358673)
			(xy 344.224356 -394.385292) (xy 344.223831 -394.409268) (xy 344.216336 -394.45663) (xy 344.201528 -394.502239)
			(xy 344.179772 -394.544971) (xy 344.151602 -394.583776) (xy 344.117712 -394.617701) (xy 344.078935 -394.645909)
			(xy 344.036225 -394.667709) (xy 343.990632 -394.682563) (xy 343.943277 -394.690107) (xy 343.919302 -394.6906)
			(xy 343.918794 -394.6906) (xy 343.89522 -394.690211) (xy 343.848631 -394.682969) (xy 343.803713 -394.668642)
			(xy 343.761534 -394.647573) (xy 343.723101 -394.620262) (xy 343.68933 -394.587362) (xy 343.661024 -394.549656)
			(xy 343.649554 -394.529056) (xy 343.649046 -394.528294) (xy 343.251282 -393.839954) (xy 343.239425 -393.817268)
			(xy 343.222567 -393.768939) (xy 343.213986 -393.718479) (xy 343.213436 -393.692888) (xy 342.671442 -393.692888)
			(xy 342.983566 -394.232892) (xy 342.996393 -394.256223) (xy 343.014612 -394.306247) (xy 343.023871 -394.358673)
			(xy 343.02446 -394.385292) (xy 343.024031 -394.409273) (xy 343.016532 -394.456644) (xy 343.001719 -394.502261)
			(xy 342.979954 -394.544999) (xy 342.951774 -394.583809) (xy 342.917872 -394.617735) (xy 342.879082 -394.645942)
			(xy 342.836359 -394.667737) (xy 342.790753 -394.682582) (xy 342.743386 -394.690114) (xy 342.719406 -394.6906)
			(xy 342.718898 -394.6906) (xy 342.695324 -394.690208) (xy 342.648736 -394.682966) (xy 342.603817 -394.66864)
			(xy 342.561639 -394.647571) (xy 342.523206 -394.620261) (xy 342.489434 -394.587361) (xy 342.461128 -394.549656)
			(xy 342.449658 -394.529056) (xy 342.44915 -394.528294) (xy 342.051386 -393.839954) (xy 342.03953 -393.817267)
			(xy 342.022671 -393.768939) (xy 342.01409 -393.718479) (xy 342.01354 -393.692888) (xy 341.471292 -393.692888)
			(xy 341.783416 -394.232892) (xy 341.79615 -394.256209) (xy 341.814243 -394.306158) (xy 341.823459 -394.358477)
			(xy 341.824056 -394.385038) (xy 341.824056 -394.385292) (xy 341.82353 -394.409281) (xy 341.816027 -394.456667)
			(xy 341.801203 -394.502297) (xy 341.779425 -394.545047) (xy 341.751228 -394.583863) (xy 341.717306 -394.617791)
			(xy 341.678494 -394.645996) (xy 341.635749 -394.667782) (xy 341.590122 -394.682614) (xy 341.542737 -394.690126)
			(xy 341.518748 -394.6906) (xy 341.495175 -394.690168) (xy 341.448589 -394.682933) (xy 341.403671 -394.668614)
			(xy 341.361493 -394.647552) (xy 341.323059 -394.620248) (xy 341.289286 -394.587354) (xy 341.260979 -394.549654)
			(xy 341.249508 -394.529056) (xy 341.249 -394.528294) (xy 340.851236 -393.839954) (xy 340.839305 -393.817294)
			(xy 340.822372 -393.768964) (xy 340.813719 -393.718491) (xy 340.813136 -393.692888) (xy 340.271396 -393.692888)
			(xy 340.58352 -394.232892) (xy 340.596254 -394.256209) (xy 340.614348 -394.306158) (xy 340.623563 -394.358476)
			(xy 340.62416 -394.385038) (xy 340.62416 -394.385292) (xy 340.623754 -394.409287) (xy 340.616247 -394.456687)
			(xy 340.601417 -394.502329) (xy 340.579628 -394.545088) (xy 340.551418 -394.583912) (xy 340.517482 -394.617844)
			(xy 340.478654 -394.646049) (xy 340.435892 -394.667832) (xy 340.390248 -394.682657) (xy 340.342847 -394.690157)
			(xy 340.318852 -394.6906) (xy 340.295279 -394.690164) (xy 340.248693 -394.682931) (xy 340.203776 -394.668612)
			(xy 340.161597 -394.647551) (xy 340.123164 -394.620247) (xy 340.089391 -394.587354) (xy 340.061083 -394.549653)
			(xy 340.049612 -394.529056) (xy 340.049104 -394.528294) (xy 339.65134 -393.839954) (xy 339.639409 -393.817293)
			(xy 339.622476 -393.768964) (xy 339.613823 -393.718491) (xy 339.61324 -393.692888) (xy 339.0715 -393.692888)
			(xy 339.383624 -394.232892) (xy 339.396359 -394.256209) (xy 339.414452 -394.306158) (xy 339.423667 -394.358476)
			(xy 339.424264 -394.385038) (xy 339.424264 -394.385292) (xy 339.423854 -394.409287) (xy 339.416347 -394.456687)
			(xy 339.401517 -394.502328) (xy 339.379729 -394.545087) (xy 339.351519 -394.583911) (xy 339.317583 -394.617843)
			(xy 339.278756 -394.646048) (xy 339.235995 -394.667831) (xy 339.190352 -394.682656) (xy 339.142951 -394.690157)
			(xy 339.118956 -394.6906) (xy 339.118702 -394.6906) (xy 339.095128 -394.690205) (xy 339.04854 -394.682963)
			(xy 339.003621 -394.668638) (xy 338.961443 -394.64757) (xy 338.92301 -394.62026) (xy 338.889238 -394.587361)
			(xy 338.860933 -394.549656) (xy 338.849462 -394.529056) (xy 338.848954 -394.528294) (xy 338.45119 -393.839954)
			(xy 338.439334 -393.817267) (xy 338.422475 -393.768939) (xy 338.413894 -393.718479) (xy 338.413344 -393.692888)
			(xy 337.87135 -393.692888) (xy 338.183474 -394.232892) (xy 338.196301 -394.256223) (xy 338.21452 -394.306247)
			(xy 338.223779 -394.358673) (xy 338.224368 -394.385292) (xy 338.223931 -394.409272) (xy 338.216433 -394.456643)
			(xy 338.201619 -394.502259) (xy 338.179855 -394.544997) (xy 338.151676 -394.583806) (xy 338.117775 -394.617732)
			(xy 338.078987 -394.645939) (xy 338.036264 -394.667734) (xy 337.990659 -394.682581) (xy 337.943294 -394.690113)
			(xy 337.919314 -394.6906) (xy 337.918806 -394.6906) (xy 337.895232 -394.690201) (xy 337.848644 -394.682961)
			(xy 337.803726 -394.668636) (xy 337.761547 -394.647568) (xy 337.723114 -394.620259) (xy 337.689342 -394.58736)
			(xy 337.661037 -394.549655) (xy 337.649566 -394.529056) (xy 337.649058 -394.528294) (xy 337.251294 -393.839954)
			(xy 337.239438 -393.817267) (xy 337.222579 -393.768939) (xy 337.213998 -393.718479) (xy 337.213448 -393.692888)
			(xy 336.671454 -393.692888) (xy 336.983578 -394.232892) (xy 336.996406 -394.256223) (xy 337.014624 -394.306247)
			(xy 337.023883 -394.358673) (xy 337.024472 -394.385292) (xy 337.024031 -394.409272) (xy 337.016533 -394.456643)
			(xy 337.00172 -394.502258) (xy 336.979956 -394.544996) (xy 336.951778 -394.583805) (xy 336.917877 -394.617731)
			(xy 336.879089 -394.645938) (xy 336.836367 -394.667733) (xy 336.790763 -394.68258) (xy 336.743398 -394.690113)
			(xy 336.719418 -394.6906) (xy 336.71891 -394.6906) (xy 336.695336 -394.690198) (xy 336.648748 -394.682958)
			(xy 336.60383 -394.668634) (xy 336.561652 -394.647566) (xy 336.523218 -394.620258) (xy 336.489447 -394.58736)
			(xy 336.461141 -394.549655) (xy 336.44967 -394.529056) (xy 336.449162 -394.528294) (xy 336.051398 -393.839954)
			(xy 336.039542 -393.817267) (xy 336.022683 -393.768939) (xy 336.014102 -393.718479) (xy 336.013552 -393.692888)
			(xy 322.14367 -393.692888) (xy 322.455794 -394.232892) (xy 322.468623 -394.256222) (xy 322.486841 -394.306246)
			(xy 322.496099 -394.358673) (xy 322.496688 -394.385292) (xy 322.496253 -394.409299) (xy 322.488739 -394.45672)
			(xy 322.473895 -394.502381) (xy 322.452087 -394.545156) (xy 322.423852 -394.58399) (xy 322.389887 -394.617925)
			(xy 322.351029 -394.646126) (xy 322.308235 -394.667897) (xy 322.262561 -394.682702) (xy 322.215133 -394.690174)
			(xy 322.191126 -394.6906) (xy 322.164862 -394.690032) (xy 322.1131 -394.681099) (xy 322.06363 -394.66344)
			(xy 322.017911 -394.637577) (xy 321.977293 -394.604272) (xy 321.942972 -394.564508) (xy 321.928998 -394.542264)
			(xy 321.928998 -394.541756) (xy 321.921124 -394.527786) (xy 321.920616 -394.527024) (xy 321.522852 -393.838684)
			(xy 321.510933 -393.816018) (xy 321.493996 -393.767692) (xy 321.485338 -393.717221) (xy 321.484752 -393.691618)
			(xy 320.94304 -393.691618) (xy 321.255898 -394.232892) (xy 321.268719 -394.256226) (xy 321.286942 -394.306248)
			(xy 321.296203 -394.358674) (xy 321.296792 -394.385292) (xy 321.296353 -394.409298) (xy 321.28884 -394.45672)
			(xy 321.273996 -394.50238) (xy 321.252188 -394.545155) (xy 321.223953 -394.583988) (xy 321.189989 -394.617924)
			(xy 321.151131 -394.646125) (xy 321.108338 -394.667896) (xy 321.062664 -394.682701) (xy 321.015237 -394.690174)
			(xy 320.99123 -394.6906) (xy 320.964963 -394.690106) (xy 320.913197 -394.681157) (xy 320.863726 -394.663483)
			(xy 320.818008 -394.637606) (xy 320.777391 -394.604289) (xy 320.743074 -394.564513) (xy 320.729102 -394.542264)
			(xy 320.729102 -394.541756) (xy 320.721228 -394.527786) (xy 320.72072 -394.527024) (xy 320.322956 -393.838684)
			(xy 320.311037 -393.816017) (xy 320.2941 -393.767691) (xy 320.285442 -393.717221) (xy 320.284856 -393.691618)
			(xy 319.743116 -393.691618) (xy 320.05524 -394.231622) (xy 320.060623 -394.241152) (xy 320.070155 -394.260858)
			(xy 320.07429 -394.270992) (xy 320.084581 -394.298308) (xy 320.09571 -394.355602) (xy 320.096388 -394.384784)
			(xy 320.096388 -394.385292) (xy 320.095954 -394.409286) (xy 320.088448 -394.456683) (xy 320.07362 -394.502322)
			(xy 320.051833 -394.54508) (xy 320.023626 -394.583902) (xy 319.989693 -394.617834) (xy 319.95087 -394.64604)
			(xy 319.908111 -394.667824) (xy 319.862471 -394.682651) (xy 319.815074 -394.690155) (xy 319.79108 -394.6906)
			(xy 319.767505 -394.690222) (xy 319.720916 -394.682978) (xy 319.675997 -394.668649) (xy 319.633819 -394.647578)
			(xy 319.595386 -394.620266) (xy 319.561615 -394.587364) (xy 319.53331 -394.549657) (xy 319.52184 -394.529056)
			(xy 319.521332 -394.528294) (xy 319.123568 -393.839954) (xy 319.119045 -393.831606) (xy 319.110909 -393.81445)
			(xy 319.107312 -393.805664) (xy 319.107312 -393.805156) (xy 319.097018 -393.7779) (xy 319.085772 -393.720742)
			(xy 319.08496 -393.691618) (xy 318.542994 -393.691618) (xy 318.855852 -394.232892) (xy 318.868589 -394.256208)
			(xy 318.886681 -394.306157) (xy 318.895896 -394.358476) (xy 318.896492 -394.385038) (xy 318.896492 -394.385292)
			(xy 318.896054 -394.409286) (xy 318.888548 -394.456682) (xy 318.87372 -394.502321) (xy 318.851934 -394.545079)
			(xy 318.823728 -394.583901) (xy 318.789795 -394.617833) (xy 318.750972 -394.646038) (xy 318.708214 -394.667823)
			(xy 318.662575 -394.68265) (xy 318.615178 -394.690155) (xy 318.591184 -394.6906) (xy 318.59093 -394.6906)
			(xy 318.564686 -394.690044) (xy 318.51297 -394.681076) (xy 318.46355 -394.663397) (xy 318.417879 -394.63753)
			(xy 318.377303 -394.604235) (xy 318.343017 -394.564493) (xy 318.329056 -394.542264) (xy 318.329056 -394.541756)
			(xy 318.321182 -394.527786) (xy 318.320674 -394.527024) (xy 317.92291 -393.838684) (xy 317.911022 -393.816013)
			(xy 317.894177 -393.767677) (xy 317.885608 -393.717211) (xy 317.885064 -393.691618) (xy 317.34307 -393.691618)
			(xy 317.655194 -394.231622) (xy 317.660576 -394.241153) (xy 317.670109 -394.260858) (xy 317.674244 -394.270992)
			(xy 317.684636 -394.298418) (xy 317.695885 -394.355972) (xy 317.696596 -394.385292) (xy 317.696131 -394.409271)
			(xy 317.688634 -394.456639) (xy 317.673822 -394.502252) (xy 317.652061 -394.544989) (xy 317.623885 -394.583797)
			(xy 317.589987 -394.617722) (xy 317.551202 -394.64593) (xy 317.508484 -394.667726) (xy 317.462883 -394.682575)
			(xy 317.415521 -394.690111) (xy 317.391542 -394.6906) (xy 317.391034 -394.6906) (xy 317.367461 -394.690179)
			(xy 317.320874 -394.682942) (xy 317.275956 -394.668622) (xy 317.233778 -394.647557) (xy 317.195344 -394.620252)
			(xy 317.161572 -394.587356) (xy 317.133265 -394.549654) (xy 317.121794 -394.529056) (xy 317.121286 -394.528294)
			(xy 316.723522 -393.839954) (xy 316.718985 -393.831548) (xy 316.710852 -393.814263) (xy 316.707266 -393.80541)
			(xy 316.696965 -393.778098) (xy 316.685845 -393.720801) (xy 316.685168 -393.691618) (xy 316.142948 -393.691618)
			(xy 316.455806 -394.232892) (xy 316.468628 -394.256226) (xy 316.48685 -394.306248) (xy 316.496111 -394.358674)
			(xy 316.4967 -394.385292) (xy 316.496254 -394.409298) (xy 316.48874 -394.456718) (xy 316.473896 -394.502378)
			(xy 316.452089 -394.545152) (xy 316.423856 -394.583985) (xy 316.389892 -394.617921) (xy 316.351035 -394.646122)
			(xy 316.308243 -394.667894) (xy 316.262571 -394.682699) (xy 316.215144 -394.690173) (xy 316.191138 -394.6906)
			(xy 316.164871 -394.6901) (xy 316.113106 -394.681152) (xy 316.063635 -394.66348) (xy 316.017917 -394.637604)
			(xy 315.9773 -394.604287) (xy 315.942982 -394.564513) (xy 315.92901 -394.542264) (xy 315.92901 -394.541756)
			(xy 315.921136 -394.527786) (xy 315.920628 -394.527024) (xy 315.522864 -393.838684) (xy 315.510946 -393.816017)
			(xy 315.494008 -393.767691) (xy 315.48535 -393.717221) (xy 315.484764 -393.691618) (xy 314.943024 -393.691618)
			(xy 315.255148 -394.231622) (xy 315.260532 -394.241152) (xy 315.270063 -394.260858) (xy 315.274198 -394.270992)
			(xy 315.28449 -394.298308) (xy 315.295618 -394.355602) (xy 315.296296 -394.384784) (xy 315.296296 -394.385292)
			(xy 315.295854 -394.409286) (xy 315.288348 -394.456682) (xy 315.27352 -394.50232) (xy 315.251735 -394.545077)
			(xy 315.223529 -394.5839) (xy 315.189597 -394.617831) (xy 315.150774 -394.646037) (xy 315.108017 -394.667822)
			(xy 315.062378 -394.682649) (xy 315.014982 -394.690155) (xy 314.990988 -394.6906) (xy 314.967414 -394.690216)
			(xy 314.920825 -394.682973) (xy 314.875906 -394.668645) (xy 314.833728 -394.647575) (xy 314.795295 -394.620264)
			(xy 314.761523 -394.587363) (xy 314.733218 -394.549656) (xy 314.721748 -394.529056) (xy 314.72124 -394.528294)
			(xy 314.323476 -393.839954) (xy 314.318954 -393.831606) (xy 314.310817 -393.81445) (xy 314.30722 -393.805664)
			(xy 314.30722 -393.805156) (xy 314.296926 -393.7779) (xy 314.285681 -393.720742) (xy 314.284868 -393.691618)
			(xy 313.743156 -393.691618) (xy 314.056014 -394.232892) (xy 314.068837 -394.256226) (xy 314.087058 -394.306248)
			(xy 314.096319 -394.358673) (xy 314.096908 -394.385292) (xy 314.096454 -394.409298) (xy 314.08894 -394.456717)
			(xy 314.074097 -394.502377) (xy 314.052291 -394.54515) (xy 314.024058 -394.583983) (xy 313.990095 -394.617918)
			(xy 313.95124 -394.646119) (xy 313.908449 -394.667891) (xy 313.862778 -394.682698) (xy 313.815352 -394.690173)
			(xy 313.791346 -394.6906) (xy 313.791092 -394.6906) (xy 313.767518 -394.690213) (xy 313.720929 -394.68297)
			(xy 313.67601 -394.668643) (xy 313.633832 -394.647573) (xy 313.595399 -394.620263) (xy 313.561628 -394.587362)
			(xy 313.533322 -394.549656) (xy 313.521852 -394.529056) (xy 313.521344 -394.528294) (xy 313.12358 -393.839954)
			(xy 313.111644 -393.817296) (xy 313.094715 -393.768965) (xy 313.086063 -393.718492) (xy 313.08548 -393.692888)
			(xy 312.54374 -393.692888) (xy 312.855864 -394.232892) (xy 312.868602 -394.256207) (xy 312.886693 -394.306157)
			(xy 312.895908 -394.358476) (xy 312.896504 -394.385038) (xy 312.896504 -394.385292) (xy 312.896054 -394.409285)
			(xy 312.888549 -394.456681) (xy 312.873721 -394.502319) (xy 312.851936 -394.545075) (xy 312.823731 -394.583897)
			(xy 312.7898 -394.617829) (xy 312.750978 -394.646034) (xy 312.708222 -394.66782) (xy 312.662585 -394.682648)
			(xy 312.615189 -394.690154) (xy 312.591196 -394.6906) (xy 312.590942 -394.6906) (xy 312.567369 -394.690172)
			(xy 312.520783 -394.682937) (xy 312.475865 -394.668617) (xy 312.433686 -394.647554) (xy 312.395253 -394.62025)
			(xy 312.36148 -394.587355) (xy 312.333173 -394.549654) (xy 312.321702 -394.529056) (xy 312.321194 -394.528294)
			(xy 311.92343 -393.839954) (xy 311.911569 -393.81727) (xy 311.894713 -393.76894) (xy 311.886134 -393.71848)
			(xy 311.885584 -393.692888) (xy 311.34359 -393.692888) (xy 311.655714 -394.232892) (xy 311.668537 -394.256226)
			(xy 311.686758 -394.306248) (xy 311.696019 -394.358673) (xy 311.696608 -394.385292) (xy 311.696131 -394.40927)
			(xy 311.688634 -394.456637) (xy 311.673823 -394.50225) (xy 311.652063 -394.544985) (xy 311.623888 -394.583793)
			(xy 311.589992 -394.617718) (xy 311.551209 -394.645926) (xy 311.508492 -394.667723) (xy 311.462892 -394.682573)
			(xy 311.415532 -394.69011) (xy 311.391554 -394.6906) (xy 311.391046 -394.6906) (xy 311.367473 -394.690169)
			(xy 311.320887 -394.682935) (xy 311.275969 -394.668615) (xy 311.233791 -394.647553) (xy 311.195357 -394.620249)
			(xy 311.161584 -394.587355) (xy 311.133277 -394.549654) (xy 311.121806 -394.529056) (xy 311.121298 -394.528294)
			(xy 310.723534 -393.839954) (xy 310.711674 -393.81727) (xy 310.694818 -393.76894) (xy 310.686238 -393.71848)
			(xy 310.685688 -393.692888) (xy 310.143694 -393.692888) (xy 310.455818 -394.232892) (xy 310.468641 -394.256226)
			(xy 310.486862 -394.306248) (xy 310.496123 -394.358673) (xy 310.496712 -394.385292) (xy 310.496231 -394.40927)
			(xy 310.488734 -394.456637) (xy 310.473924 -394.502249) (xy 310.452164 -394.544984) (xy 310.423989 -394.583791)
			(xy 310.390094 -394.617716) (xy 310.351311 -394.645924) (xy 310.308595 -394.667722) (xy 310.262996 -394.682572)
			(xy 310.215636 -394.69011) (xy 310.191658 -394.6906) (xy 310.19115 -394.6906) (xy 310.167577 -394.690166)
			(xy 310.120991 -394.682932) (xy 310.076073 -394.668613) (xy 310.033895 -394.647551) (xy 309.995461 -394.620248)
			(xy 309.961688 -394.587354) (xy 309.933381 -394.549653) (xy 309.92191 -394.529056) (xy 309.921402 -394.528294)
			(xy 309.523638 -393.839954) (xy 309.511778 -393.817269) (xy 309.494922 -393.76894) (xy 309.486342 -393.71848)
			(xy 309.485792 -393.692888) (xy 308.943544 -393.692888) (xy 309.255668 -394.232892) (xy 309.268406 -394.256207)
			(xy 309.286497 -394.306157) (xy 309.295712 -394.358476) (xy 309.296308 -394.385038) (xy 309.296308 -394.385292)
			(xy 309.295854 -394.409285) (xy 309.288349 -394.45668) (xy 309.273521 -394.502318) (xy 309.251737 -394.545074)
			(xy 309.223532 -394.583896) (xy 309.189602 -394.617827) (xy 309.150781 -394.646033) (xy 309.108025 -394.667818)
			(xy 309.062388 -394.682647) (xy 309.014993 -394.690154) (xy 308.991 -394.6906) (xy 308.967426 -394.690206)
			(xy 308.920838 -394.682965) (xy 308.875919 -394.668639) (xy 308.833741 -394.64757) (xy 308.795308 -394.620261)
			(xy 308.761536 -394.587361) (xy 308.73323 -394.549656) (xy 308.72176 -394.529056) (xy 308.721252 -394.528294)
			(xy 308.323488 -393.839954) (xy 308.311553 -393.817296) (xy 308.294623 -393.768965) (xy 308.285971 -393.718491)
			(xy 308.285388 -393.692888) (xy 307.743648 -393.692888) (xy 308.055772 -394.232892) (xy 308.068511 -394.256207)
			(xy 308.086601 -394.306157) (xy 308.095816 -394.358476) (xy 308.096412 -394.385038) (xy 308.096412 -394.385292)
			(xy 308.095954 -394.409285) (xy 308.088449 -394.45668) (xy 308.073622 -394.502317) (xy 308.051838 -394.545073)
			(xy 308.023634 -394.583894) (xy 307.989703 -394.617826) (xy 307.950883 -394.646032) (xy 307.908128 -394.667817)
			(xy 307.862491 -394.682646) (xy 307.815097 -394.690154) (xy 307.791104 -394.6906) (xy 307.76753 -394.690203)
			(xy 307.720942 -394.682962) (xy 307.676023 -394.668637) (xy 307.633845 -394.647569) (xy 307.595412 -394.62026)
			(xy 307.56164 -394.587361) (xy 307.533335 -394.549656) (xy 307.521864 -394.529056) (xy 307.521356 -394.528294)
			(xy 307.123592 -393.839954) (xy 307.111657 -393.817295) (xy 307.094727 -393.768965) (xy 307.086075 -393.718491)
			(xy 307.085492 -393.692888) (xy 306.543752 -393.692888) (xy 306.855876 -394.232892) (xy 306.868615 -394.256207)
			(xy 306.886705 -394.306157) (xy 306.89592 -394.358476) (xy 306.896516 -394.385038) (xy 306.896516 -394.385292)
			(xy 306.89603 -394.409283) (xy 306.888525 -394.456673) (xy 306.8737 -394.502306) (xy 306.851918 -394.545059)
			(xy 306.823716 -394.583877) (xy 306.789789 -394.617806) (xy 306.750972 -394.646009) (xy 306.708221 -394.667793)
			(xy 306.662589 -394.682622) (xy 306.615199 -394.690129) (xy 306.591208 -394.6906) (xy 306.590954 -394.6906)
			(xy 306.567382 -394.690163) (xy 306.520795 -394.682929) (xy 306.475878 -394.668611) (xy 306.433699 -394.64755)
			(xy 306.395266 -394.620247) (xy 306.361493 -394.587353) (xy 306.333185 -394.549653) (xy 306.321714 -394.529056)
			(xy 306.321206 -394.528294) (xy 305.923442 -393.839954) (xy 305.911582 -393.817269) (xy 305.894726 -393.76894)
			(xy 305.886146 -393.71848) (xy 305.885596 -393.692888) (xy 305.343602 -393.692888) (xy 305.655726 -394.232892)
			(xy 305.66855 -394.256225) (xy 305.686771 -394.306247) (xy 305.696031 -394.358673) (xy 305.69662 -394.385292)
			(xy 305.696131 -394.40927) (xy 305.688635 -394.456636) (xy 305.673824 -394.502247) (xy 305.652065 -394.544982)
			(xy 305.623892 -394.583789) (xy 305.589997 -394.617713) (xy 305.551216 -394.645922) (xy 305.5085 -394.667719)
			(xy 305.462902 -394.68257) (xy 305.415543 -394.69011) (xy 305.391566 -394.6906) (xy 305.391058 -394.6906)
			(xy 305.367486 -394.690159) (xy 305.3209 -394.682927) (xy 305.275982 -394.668609) (xy 305.233804 -394.647548)
			(xy 305.19537 -394.620246) (xy 305.161597 -394.587353) (xy 305.13329 -394.549653) (xy 305.121818 -394.529056)
			(xy 305.12131 -394.528294) (xy 304.723546 -393.839954) (xy 304.711686 -393.817269) (xy 304.69483 -393.76894)
			(xy 304.68625 -393.71848) (xy 304.6857 -393.692888) (xy 304.143706 -393.692888) (xy 304.45583 -394.232892)
			(xy 304.468654 -394.256225) (xy 304.486875 -394.306247) (xy 304.496135 -394.358673) (xy 304.496724 -394.385292)
			(xy 304.496231 -394.40927) (xy 304.488735 -394.456635) (xy 304.473925 -394.502246) (xy 304.452166 -394.54498)
			(xy 304.423993 -394.583787) (xy 304.390099 -394.617712) (xy 304.351318 -394.64592) (xy 304.308603 -394.667718)
			(xy 304.263006 -394.68257) (xy 304.215647 -394.690109) (xy 304.19167 -394.6906) (xy 304.191162 -394.6906)
			(xy 304.16759 -394.690156) (xy 304.121004 -394.682924) (xy 304.076086 -394.668607) (xy 304.033908 -394.647547)
			(xy 303.995474 -394.620245) (xy 303.961701 -394.587352) (xy 303.933394 -394.549653) (xy 303.921922 -394.529056)
			(xy 303.921414 -394.528294) (xy 303.52365 -393.839954) (xy 303.511791 -393.817269) (xy 303.494934 -393.76894)
			(xy 303.486354 -393.71848) (xy 303.485804 -393.692888) (xy 280.345134 -393.692888) (xy 280.093674 -393.944348)
			(xy 280.08686 -393.951769) (xy 280.079126 -393.970352) (xy 280.078688 -393.980416) (xy 280.079196 -394.062966)
			(xy 280.08707 -394.081508) (xy 280.094436 -394.08862) (xy 280.100532 -394.094716) (xy 280.483818 -394.478002)
			(xy 280.510712 -394.505555) (xy 280.558798 -394.565692) (xy 280.599841 -394.630839) (xy 280.633323 -394.700176)
			(xy 280.658823 -394.772829) (xy 280.67602 -394.847882) (xy 280.684696 -394.924389) (xy 280.68524 -394.962888)
			(xy 280.68524 -396.171674) (xy 296.901108 -396.171674) (xy 296.901108 -395.308074) (xy 296.901594 -395.280823)
			(xy 296.90935 -395.226875) (xy 296.924705 -395.17458) (xy 296.947347 -395.125003) (xy 296.976813 -395.079153)
			(xy 297.012504 -395.037962) (xy 297.053695 -395.002271) (xy 297.099545 -394.972805) (xy 297.149122 -394.950163)
			(xy 297.201417 -394.934808) (xy 297.255365 -394.927052) (xy 297.309867 -394.927052) (xy 297.363815 -394.934808)
			(xy 297.41611 -394.950163) (xy 297.465687 -394.972805) (xy 297.511537 -395.002271) (xy 297.552728 -395.037962)
			(xy 297.588419 -395.079153) (xy 297.617885 -395.125003) (xy 297.640527 -395.17458) (xy 297.655882 -395.226875)
			(xy 297.663638 -395.280823) (xy 297.664124 -395.308074) (xy 297.664124 -396.171674) (xy 329.428856 -396.171674)
			(xy 329.428856 -395.308074) (xy 329.429342 -395.280823) (xy 329.437098 -395.226875) (xy 329.452453 -395.17458)
			(xy 329.475095 -395.125003) (xy 329.504561 -395.079153) (xy 329.540252 -395.037962) (xy 329.581443 -395.002271)
			(xy 329.627293 -394.972805) (xy 329.67687 -394.950163) (xy 329.729165 -394.934808) (xy 329.783113 -394.927052)
			(xy 329.837615 -394.927052) (xy 329.891563 -394.934808) (xy 329.943858 -394.950163) (xy 329.993435 -394.972805)
			(xy 330.039285 -395.002271) (xy 330.080476 -395.037962) (xy 330.116167 -395.079153) (xy 330.145633 -395.125003)
			(xy 330.168275 -395.17458) (xy 330.18363 -395.226875) (xy 330.191386 -395.280823) (xy 330.191872 -395.308074)
			(xy 330.191872 -396.171674) (xy 364.001304 -396.171674) (xy 364.001304 -395.308074) (xy 364.00179 -395.280823)
			(xy 364.009546 -395.226875) (xy 364.024901 -395.17458) (xy 364.047543 -395.125003) (xy 364.077009 -395.079153)
			(xy 364.1127 -395.037962) (xy 364.153891 -395.002271) (xy 364.199741 -394.972805) (xy 364.249318 -394.950163)
			(xy 364.301613 -394.934808) (xy 364.355561 -394.927052) (xy 364.410063 -394.927052) (xy 364.464011 -394.934808)
			(xy 364.516306 -394.950163) (xy 364.565883 -394.972805) (xy 364.611733 -395.002271) (xy 364.652924 -395.037962)
			(xy 364.688615 -395.079153) (xy 364.718081 -395.125003) (xy 364.740723 -395.17458) (xy 364.756078 -395.226875)
			(xy 364.763834 -395.280823) (xy 364.76432 -395.308074) (xy 364.76432 -396.171674) (xy 396.529052 -396.171674)
			(xy 396.529052 -395.308074) (xy 396.529538 -395.280823) (xy 396.537294 -395.226875) (xy 396.552649 -395.17458)
			(xy 396.575291 -395.125003) (xy 396.604757 -395.079153) (xy 396.640448 -395.037962) (xy 396.681639 -395.002271)
			(xy 396.727489 -394.972805) (xy 396.777066 -394.950163) (xy 396.829361 -394.934808) (xy 396.883309 -394.927052)
			(xy 396.937811 -394.927052) (xy 396.991759 -394.934808) (xy 397.044054 -394.950163) (xy 397.093631 -394.972805)
			(xy 397.139481 -395.002271) (xy 397.180672 -395.037962) (xy 397.216363 -395.079153) (xy 397.245829 -395.125003)
			(xy 397.268471 -395.17458) (xy 397.283826 -395.226875) (xy 397.291582 -395.280823) (xy 397.292068 -395.308074)
			(xy 397.292068 -396.171674) (xy 397.291582 -396.198925) (xy 397.283826 -396.252873) (xy 397.268471 -396.305168)
			(xy 397.245829 -396.354745) (xy 397.216363 -396.400595) (xy 397.180672 -396.441786) (xy 397.139481 -396.477477)
			(xy 397.093631 -396.506943) (xy 397.044054 -396.529585) (xy 396.991759 -396.54494) (xy 396.937811 -396.552696)
			(xy 396.883309 -396.552696) (xy 396.829361 -396.54494) (xy 396.777066 -396.529585) (xy 396.727489 -396.506943)
			(xy 396.681639 -396.477477) (xy 396.640448 -396.441786) (xy 396.604757 -396.400595) (xy 396.575291 -396.354745)
			(xy 396.552649 -396.305168) (xy 396.537294 -396.252873) (xy 396.529538 -396.198925) (xy 396.529052 -396.171674)
			(xy 364.76432 -396.171674) (xy 364.763834 -396.198925) (xy 364.756078 -396.252873) (xy 364.740723 -396.305168)
			(xy 364.718081 -396.354745) (xy 364.688615 -396.400595) (xy 364.652924 -396.441786) (xy 364.611733 -396.477477)
			(xy 364.565883 -396.506943) (xy 364.516306 -396.529585) (xy 364.464011 -396.54494) (xy 364.410063 -396.552696)
			(xy 364.355561 -396.552696) (xy 364.301613 -396.54494) (xy 364.249318 -396.529585) (xy 364.199741 -396.506943)
			(xy 364.153891 -396.477477) (xy 364.1127 -396.441786) (xy 364.077009 -396.400595) (xy 364.047543 -396.354745)
			(xy 364.024901 -396.305168) (xy 364.009546 -396.252873) (xy 364.00179 -396.198925) (xy 364.001304 -396.171674)
			(xy 330.191872 -396.171674) (xy 330.191386 -396.198925) (xy 330.18363 -396.252873) (xy 330.168275 -396.305168)
			(xy 330.145633 -396.354745) (xy 330.116167 -396.400595) (xy 330.080476 -396.441786) (xy 330.039285 -396.477477)
			(xy 329.993435 -396.506943) (xy 329.943858 -396.529585) (xy 329.891563 -396.54494) (xy 329.837615 -396.552696)
			(xy 329.783113 -396.552696) (xy 329.729165 -396.54494) (xy 329.67687 -396.529585) (xy 329.627293 -396.506943)
			(xy 329.581443 -396.477477) (xy 329.540252 -396.441786) (xy 329.504561 -396.400595) (xy 329.475095 -396.354745)
			(xy 329.452453 -396.305168) (xy 329.437098 -396.252873) (xy 329.429342 -396.198925) (xy 329.428856 -396.171674)
			(xy 297.664124 -396.171674) (xy 297.663638 -396.198925) (xy 297.655882 -396.252873) (xy 297.640527 -396.305168)
			(xy 297.617885 -396.354745) (xy 297.588419 -396.400595) (xy 297.552728 -396.441786) (xy 297.511537 -396.477477)
			(xy 297.465687 -396.506943) (xy 297.41611 -396.529585) (xy 297.363815 -396.54494) (xy 297.309867 -396.552696)
			(xy 297.255365 -396.552696) (xy 297.201417 -396.54494) (xy 297.149122 -396.529585) (xy 297.099545 -396.506943)
			(xy 297.053695 -396.477477) (xy 297.012504 -396.441786) (xy 296.976813 -396.400595) (xy 296.947347 -396.354745)
			(xy 296.924705 -396.305168) (xy 296.90935 -396.252873) (xy 296.901594 -396.198925) (xy 296.901108 -396.171674)
			(xy 280.68524 -396.171674) (xy 280.68524 -397.15694) (xy 303.485804 -397.15694) (xy 303.485804 -397.156432)
			(xy 303.486268 -397.132439) (xy 303.49377 -397.085044) (xy 303.508595 -397.039405) (xy 303.530377 -396.996648)
			(xy 303.558581 -396.957826) (xy 303.592511 -396.923894) (xy 303.631331 -396.895688) (xy 303.674087 -396.873903)
			(xy 303.719724 -396.859075) (xy 303.767119 -396.851569) (xy 303.791112 -396.851124) (xy 303.815047 -396.851594)
			(xy 303.862333 -396.859047) (xy 303.907877 -396.873786) (xy 303.950565 -396.895448) (xy 303.989351 -396.923504)
			(xy 304.023286 -396.957267) (xy 304.051539 -396.99591) (xy 304.062892 -397.016986) (xy 304.0634 -397.018002)
			(xy 304.143706 -397.15694) (xy 304.6857 -397.15694) (xy 304.6857 -397.156432) (xy 304.686168 -397.132439)
			(xy 304.69367 -397.085044) (xy 304.708495 -397.039406) (xy 304.730277 -396.99665) (xy 304.75848 -396.957827)
			(xy 304.792409 -396.923895) (xy 304.831229 -396.895689) (xy 304.873984 -396.873904) (xy 304.919621 -396.859076)
			(xy 304.967015 -396.85157) (xy 304.991008 -396.851124) (xy 305.014943 -396.851597) (xy 305.062229 -396.85905)
			(xy 305.107773 -396.873788) (xy 305.150461 -396.89545) (xy 305.189247 -396.923505) (xy 305.223182 -396.957268)
			(xy 305.251435 -396.99591) (xy 305.262788 -397.016986) (xy 305.263296 -397.018002) (xy 305.343602 -397.15694)
			(xy 305.885596 -397.15694) (xy 305.885596 -397.156432) (xy 305.886068 -397.13244) (xy 305.89357 -397.085045)
			(xy 305.908394 -397.039407) (xy 305.930176 -396.996651) (xy 305.958378 -396.957829) (xy 305.992307 -396.923897)
			(xy 306.031127 -396.895691) (xy 306.073881 -396.873905) (xy 306.119517 -396.859076) (xy 306.166912 -396.85157)
			(xy 306.190904 -396.851124) (xy 306.214839 -396.8516) (xy 306.262124 -396.859053) (xy 306.307668 -396.87379)
			(xy 306.350356 -396.895451) (xy 306.389142 -396.923506) (xy 306.423077 -396.957268) (xy 306.451331 -396.99591)
			(xy 306.462684 -397.016986) (xy 306.463192 -397.018002) (xy 306.543498 -397.15694) (xy 307.085492 -397.15694)
			(xy 307.085492 -397.156432) (xy 307.085991 -397.132454) (xy 307.093484 -397.085088) (xy 307.108292 -397.039476)
			(xy 307.130049 -396.996741) (xy 307.158222 -396.957933) (xy 307.192115 -396.924008) (xy 307.230897 -396.895799)
			(xy 307.273612 -396.874002) (xy 307.31921 -396.859151) (xy 307.366569 -396.851614) (xy 307.390546 -396.851124)
			(xy 307.391054 -396.851124) (xy 307.41499 -396.85156) (xy 307.462278 -396.85902) (xy 307.507823 -396.873764)
			(xy 307.550511 -396.895432) (xy 307.589296 -396.923493) (xy 307.62323 -396.957261) (xy 307.651481 -396.995908)
			(xy 307.662834 -397.016986) (xy 307.663342 -397.018002) (xy 307.743648 -397.15694) (xy 308.285388 -397.15694)
			(xy 308.285388 -397.156432) (xy 308.285891 -397.132455) (xy 308.293384 -397.085089) (xy 308.308192 -397.039477)
			(xy 308.329949 -396.996742) (xy 308.35812 -396.957934) (xy 308.392013 -396.924009) (xy 308.430794 -396.895801)
			(xy 308.473509 -396.874003) (xy 308.519106 -396.859152) (xy 308.566465 -396.851614) (xy 308.590442 -396.851124)
			(xy 308.59095 -396.851124) (xy 308.614886 -396.851563) (xy 308.662173 -396.859022) (xy 308.707718 -396.873766)
			(xy 308.750406 -396.895434) (xy 308.789192 -396.923494) (xy 308.823126 -396.957262) (xy 308.851377 -396.995908)
			(xy 308.86273 -397.016986) (xy 308.863238 -397.018002) (xy 308.943544 -397.15694) (xy 309.485792 -397.15694)
			(xy 309.485792 -397.156432) (xy 309.486268 -397.13244) (xy 309.49377 -397.085045) (xy 309.508594 -397.039408)
			(xy 309.530375 -396.996652) (xy 309.558577 -396.95783) (xy 309.592506 -396.923898) (xy 309.631325 -396.895692)
			(xy 309.674079 -396.873906) (xy 309.719714 -396.859077) (xy 309.767108 -396.85157) (xy 309.7911 -396.851124)
			(xy 309.815035 -396.851603) (xy 309.86232 -396.859055) (xy 309.907864 -396.873792) (xy 309.950552 -396.895453)
			(xy 309.989338 -396.923507) (xy 310.023273 -396.957269) (xy 310.051526 -396.995911) (xy 310.06288 -397.016986)
			(xy 310.063388 -397.018002) (xy 310.143694 -397.15694) (xy 310.685688 -397.15694) (xy 310.685688 -397.156432)
			(xy 310.686168 -397.13244) (xy 310.69367 -397.085046) (xy 310.708493 -397.039409) (xy 310.730274 -396.996653)
			(xy 310.758476 -396.957831) (xy 310.792404 -396.9239) (xy 310.831223 -396.895693) (xy 310.873976 -396.873907)
			(xy 310.919611 -396.859078) (xy 310.967004 -396.851571) (xy 310.990996 -396.851124) (xy 311.014933 -396.851526)
			(xy 311.062223 -396.858992) (xy 311.107768 -396.873742) (xy 311.150456 -396.895416) (xy 311.189241 -396.923483)
			(xy 311.223174 -396.957255) (xy 311.251424 -396.995906) (xy 311.262776 -397.016986) (xy 311.263284 -397.018002)
			(xy 311.34359 -397.15694) (xy 311.885584 -397.15694) (xy 311.885584 -397.156432) (xy 311.886068 -397.13244)
			(xy 311.893569 -397.085046) (xy 311.908393 -397.03941) (xy 311.930174 -396.996654) (xy 311.958375 -396.957833)
			(xy 311.992302 -396.923901) (xy 312.03112 -396.895695) (xy 312.073873 -396.873908) (xy 312.119508 -396.859079)
			(xy 312.1669 -396.851571) (xy 312.190892 -396.851124) (xy 312.214829 -396.851529) (xy 312.262118 -396.858995)
			(xy 312.307664 -396.873745) (xy 312.350352 -396.895418) (xy 312.389137 -396.923484) (xy 312.42307 -396.957256)
			(xy 312.45132 -396.995906) (xy 312.462672 -397.016986) (xy 312.46318 -397.018002) (xy 312.543486 -397.15694)
			(xy 313.08548 -397.15694) (xy 313.08548 -397.156432) (xy 313.085991 -397.132455) (xy 313.093484 -397.08509)
			(xy 313.108291 -397.039479) (xy 313.130047 -396.996744) (xy 313.158218 -396.957937) (xy 313.19211 -396.924012)
			(xy 313.23089 -396.895803) (xy 313.273603 -396.874005) (xy 313.3192 -396.859154) (xy 313.366557 -396.851614)
			(xy 313.390534 -396.851124) (xy 313.391042 -396.851124) (xy 313.414978 -396.851569) (xy 313.462265 -396.859028)
			(xy 313.50781 -396.87377) (xy 313.550497 -396.895437) (xy 313.589283 -396.923496) (xy 313.623217 -396.957263)
			(xy 313.651469 -396.995909) (xy 313.662822 -397.016986) (xy 313.66333 -397.018002) (xy 313.743636 -397.15694)
			(xy 314.285376 -397.15694) (xy 314.285376 -397.156432) (xy 314.285891 -397.132455) (xy 314.293384 -397.08509)
			(xy 314.308191 -397.03948) (xy 314.329947 -396.996746) (xy 314.358117 -396.957938) (xy 314.392008 -396.924013)
			(xy 314.430788 -396.895805) (xy 314.473501 -396.874006) (xy 314.519096 -396.859155) (xy 314.566454 -396.851615)
			(xy 314.59043 -396.851124) (xy 314.590938 -396.851124) (xy 314.614874 -396.851573) (xy 314.662161 -396.85903)
			(xy 314.707705 -396.873772) (xy 314.750393 -396.895438) (xy 314.789179 -396.923498) (xy 314.823113 -396.957263)
			(xy 314.851365 -396.995909) (xy 314.862718 -397.016986) (xy 314.863226 -397.018002) (xy 314.943532 -397.15694)
			(xy 315.48578 -397.15694) (xy 315.48578 -397.156432) (xy 315.486268 -397.13244) (xy 315.493769 -397.085047)
			(xy 315.508593 -397.039411) (xy 315.530373 -396.996656) (xy 315.558574 -396.957834) (xy 315.592501 -396.923902)
			(xy 315.631318 -396.895696) (xy 315.67407 -396.87391) (xy 315.719704 -396.85908) (xy 315.767096 -396.851571)
			(xy 315.791088 -396.851124) (xy 315.815025 -396.851532) (xy 315.862314 -396.858997) (xy 315.90786 -396.873747)
			(xy 315.950547 -396.895419) (xy 315.989333 -396.923485) (xy 316.023266 -396.957256) (xy 316.051516 -396.995907)
			(xy 316.062868 -397.016986) (xy 316.063376 -397.018002) (xy 316.143682 -397.15694) (xy 316.685676 -397.15694)
			(xy 316.685676 -397.156432) (xy 316.686168 -397.132441) (xy 316.693669 -397.085048) (xy 316.708492 -397.039412)
			(xy 316.730272 -396.996657) (xy 316.758473 -396.957836) (xy 316.792399 -396.923904) (xy 316.831216 -396.895697)
			(xy 316.873967 -396.873911) (xy 316.919601 -396.85908) (xy 316.966993 -396.851571) (xy 316.990984 -396.851124)
			(xy 317.014921 -396.851535) (xy 317.06221 -396.859) (xy 317.107755 -396.873749) (xy 317.150443 -396.895421)
			(xy 317.189228 -396.923486) (xy 317.223161 -396.957257) (xy 317.251412 -396.995907) (xy 317.262764 -397.016986)
			(xy 317.263272 -397.018002) (xy 317.343578 -397.15694) (xy 317.885572 -397.15694) (xy 317.885572 -397.156432)
			(xy 317.886068 -397.132441) (xy 317.893569 -397.085048) (xy 317.908392 -397.039413) (xy 317.930172 -396.996658)
			(xy 317.958371 -396.957837) (xy 317.992297 -396.923905) (xy 318.031114 -396.895699) (xy 318.073865 -396.873912)
			(xy 318.119498 -396.859081) (xy 318.166889 -396.851572) (xy 318.19088 -396.851124) (xy 318.214817 -396.851539)
			(xy 318.262105 -396.859002) (xy 318.307651 -396.873751) (xy 318.350339 -396.895422) (xy 318.389124 -396.923487)
			(xy 318.423057 -396.957257) (xy 318.451308 -396.995907) (xy 318.46266 -397.016986) (xy 318.463168 -397.018002)
			(xy 318.543474 -397.15694) (xy 319.085468 -397.15694) (xy 319.085468 -397.156432) (xy 319.085991 -397.132456)
			(xy 319.093484 -397.085092) (xy 319.10829 -397.039482) (xy 319.130045 -396.996748) (xy 319.158215 -396.957941)
			(xy 319.192105 -396.924016) (xy 319.230883 -396.895807) (xy 319.273595 -396.874009) (xy 319.31919 -396.859156)
			(xy 319.366546 -396.851615) (xy 319.390522 -396.851124) (xy 319.39103 -396.851124) (xy 319.414965 -396.851579)
			(xy 319.462252 -396.859035) (xy 319.507797 -396.873776) (xy 319.550484 -396.895441) (xy 319.58927 -396.9235)
			(xy 319.623205 -396.957264) (xy 319.651457 -396.995909) (xy 319.66281 -397.016986) (xy 319.663318 -397.018002)
			(xy 319.743624 -397.15694) (xy 320.285364 -397.15694) (xy 320.285364 -397.156432) (xy 320.285891 -397.132456)
			(xy 320.293383 -397.085092) (xy 320.308189 -397.039483) (xy 320.329944 -396.996749) (xy 320.358113 -396.957943)
			(xy 320.392003 -396.924018) (xy 320.430781 -396.895809) (xy 320.473492 -396.87401) (xy 320.519086 -396.859157)
			(xy 320.566442 -396.851616) (xy 320.590418 -396.851124) (xy 320.590926 -396.851124) (xy 320.614861 -396.851582)
			(xy 320.662148 -396.859038) (xy 320.707692 -396.873778) (xy 320.75038 -396.895443) (xy 320.789166 -396.923501)
			(xy 320.823101 -396.957265) (xy 320.851353 -396.995909) (xy 320.862706 -397.016986) (xy 320.863214 -397.018002)
			(xy 320.94352 -397.15694) (xy 321.485768 -397.15694) (xy 321.485768 -397.156432) (xy 321.486268 -397.132441)
			(xy 321.493769 -397.085049) (xy 321.508592 -397.039414) (xy 321.530371 -396.996659) (xy 321.55857 -396.957838)
			(xy 321.592496 -396.923907) (xy 321.631311 -396.8957) (xy 321.674062 -396.873913) (xy 321.719694 -396.859082)
			(xy 321.767085 -396.851572) (xy 321.791076 -396.851124) (xy 321.815013 -396.851542) (xy 321.862301 -396.859005)
			(xy 321.907847 -396.873753) (xy 321.950534 -396.895424) (xy 321.98932 -396.923488) (xy 322.023253 -396.957258)
			(xy 322.051504 -396.995907) (xy 322.062856 -397.016986) (xy 322.063364 -397.018002) (xy 322.14367 -397.15694)
			(xy 336.013552 -397.15694) (xy 336.013552 -397.156432) (xy 336.014092 -397.132444) (xy 336.021592 -397.085057)
			(xy 336.036413 -397.039427) (xy 336.058189 -396.996677) (xy 336.086384 -396.95786) (xy 336.120305 -396.923931)
			(xy 336.159115 -396.895726) (xy 336.20186 -396.87394) (xy 336.247487 -396.859109) (xy 336.294872 -396.851598)
			(xy 336.31886 -396.851124) (xy 336.342796 -396.851555) (xy 336.390084 -396.859016) (xy 336.435629 -396.873761)
			(xy 336.478317 -396.89543) (xy 336.517103 -396.923492) (xy 336.551036 -396.95726) (xy 336.579288 -396.995908)
			(xy 336.59064 -397.016986) (xy 336.591148 -397.018002) (xy 336.671454 -397.15694) (xy 337.213448 -397.15694)
			(xy 337.213448 -397.156432) (xy 337.213992 -397.132444) (xy 337.221492 -397.085057) (xy 337.236312 -397.039428)
			(xy 337.258088 -396.996678) (xy 337.286283 -396.957861) (xy 337.320203 -396.923933) (xy 337.359013 -396.895728)
			(xy 337.401757 -396.873941) (xy 337.447383 -396.85911) (xy 337.494768 -396.851598) (xy 337.518756 -396.851124)
			(xy 337.542692 -396.851558) (xy 337.58998 -396.859018) (xy 337.635525 -396.873763) (xy 337.678213 -396.895431)
			(xy 337.716998 -396.923493) (xy 337.750932 -396.957261) (xy 337.779183 -396.995908) (xy 337.790536 -397.016986)
			(xy 337.791044 -397.018002) (xy 337.87135 -397.15694) (xy 338.413344 -397.15694) (xy 338.413344 -397.156432)
			(xy 338.413892 -397.132444) (xy 338.421392 -397.085058) (xy 338.436212 -397.039429) (xy 338.457987 -396.996679)
			(xy 338.486182 -396.957862) (xy 338.520101 -396.923934) (xy 338.558911 -396.895729) (xy 338.601655 -396.873943)
			(xy 338.64728 -396.859111) (xy 338.694664 -396.851598) (xy 338.718652 -396.851124) (xy 338.742588 -396.851561)
			(xy 338.789876 -396.859021) (xy 338.835421 -396.873765) (xy 338.878108 -396.895433) (xy 338.916894 -396.923494)
			(xy 338.950828 -396.957261) (xy 338.979079 -396.995908) (xy 338.990432 -397.016986) (xy 338.99094 -397.018002)
			(xy 339.071246 -397.15694) (xy 339.61324 -397.15694) (xy 339.61324 -397.156432) (xy 339.613691 -397.132452)
			(xy 339.621186 -397.085081) (xy 339.635997 -397.039465) (xy 339.657758 -396.996726) (xy 339.685936 -396.957917)
			(xy 339.719835 -396.92399) (xy 339.758623 -396.895783) (xy 339.801345 -396.873988) (xy 339.846949 -396.859142)
			(xy 339.894314 -396.85161) (xy 339.918294 -396.851124) (xy 339.918802 -396.851124) (xy 339.942737 -396.851602)
			(xy 339.990022 -396.859054) (xy 340.035566 -396.873791) (xy 340.078254 -396.895452) (xy 340.11704 -396.923507)
			(xy 340.150975 -396.957268) (xy 340.179229 -396.99591) (xy 340.190582 -397.016986) (xy 340.19109 -397.018002)
			(xy 340.271396 -397.15694) (xy 340.813136 -397.15694) (xy 340.813136 -397.156432) (xy 340.813591 -397.132452)
			(xy 340.821086 -397.085082) (xy 340.835896 -397.039466) (xy 340.857658 -396.996728) (xy 340.885834 -396.957918)
			(xy 340.919734 -396.923992) (xy 340.958521 -396.895784) (xy 341.001242 -396.873989) (xy 341.046846 -396.859143)
			(xy 341.09421 -396.85161) (xy 341.11819 -396.851124) (xy 341.118698 -396.851124) (xy 341.142635 -396.851524)
			(xy 341.189925 -396.858991) (xy 341.235471 -396.873741) (xy 341.278158 -396.895415) (xy 341.316943 -396.923482)
			(xy 341.350876 -396.957255) (xy 341.379126 -396.995906) (xy 341.390478 -397.016986) (xy 341.390986 -397.018002)
			(xy 341.471292 -397.15694) (xy 342.01354 -397.15694) (xy 342.01354 -397.156432) (xy 342.013968 -397.132437)
			(xy 342.021471 -397.085038) (xy 342.036298 -397.039397) (xy 342.058084 -396.996638) (xy 342.086291 -396.957814)
			(xy 342.120226 -396.923881) (xy 342.159051 -396.895676) (xy 342.201812 -396.873892) (xy 342.247454 -396.859068)
			(xy 342.294853 -396.851567) (xy 342.318848 -396.851124) (xy 342.342784 -396.851565) (xy 342.390071 -396.859024)
			(xy 342.435616 -396.873767) (xy 342.478304 -396.895434) (xy 342.51709 -396.923495) (xy 342.551024 -396.957262)
			(xy 342.579275 -396.995908) (xy 342.590628 -397.016986) (xy 342.591136 -397.018002) (xy 342.671442 -397.15694)
			(xy 343.213436 -397.15694) (xy 343.213436 -397.156432) (xy 343.213868 -397.132438) (xy 343.221371 -397.085039)
			(xy 343.236198 -397.039398) (xy 343.257983 -396.996639) (xy 343.28619 -396.957815) (xy 343.320124 -396.923882)
			(xy 343.358949 -396.895677) (xy 343.401709 -396.873893) (xy 343.447351 -396.859068) (xy 343.49475 -396.851567)
			(xy 343.518744 -396.851124) (xy 343.54268 -396.851568) (xy 343.589967 -396.859026) (xy 343.635512 -396.873769)
			(xy 343.6782 -396.895436) (xy 343.716985 -396.923496) (xy 343.750919 -396.957262) (xy 343.779171 -396.995909)
			(xy 343.790524 -397.016986) (xy 343.791032 -397.018002) (xy 343.871338 -397.15694) (xy 344.413332 -397.15694)
			(xy 344.413332 -397.156432) (xy 344.413768 -397.132438) (xy 344.421271 -397.085039) (xy 344.436098 -397.039399)
			(xy 344.457883 -396.99664) (xy 344.486089 -396.957816) (xy 344.520022 -396.923884) (xy 344.558847 -396.895678)
			(xy 344.601606 -396.873895) (xy 344.647247 -396.859069) (xy 344.694646 -396.851567) (xy 344.71864 -396.851124)
			(xy 344.742576 -396.851571) (xy 344.789863 -396.859029) (xy 344.835408 -396.873771) (xy 344.878095 -396.895437)
			(xy 344.916881 -396.923497) (xy 344.950815 -396.957263) (xy 344.979067 -396.995909) (xy 344.99042 -397.016986)
			(xy 344.990928 -397.018002) (xy 345.071234 -397.15694) (xy 345.613228 -397.15694) (xy 345.613228 -397.156432)
			(xy 345.613691 -397.132453) (xy 345.621186 -397.085083) (xy 345.635996 -397.039468) (xy 345.657756 -396.99673)
			(xy 345.685932 -396.957921) (xy 345.71983 -396.923995) (xy 345.758617 -396.895787) (xy 345.801337 -396.873991)
			(xy 345.846939 -396.859144) (xy 345.894303 -396.851611) (xy 345.918282 -396.851124) (xy 345.91879 -396.851124)
			(xy 345.942727 -396.85153) (xy 345.990016 -396.858996) (xy 346.035562 -396.873746) (xy 346.07825 -396.895419)
			(xy 346.117035 -396.923484) (xy 346.150968 -396.957256) (xy 346.179218 -396.995907) (xy 346.19057 -397.016986)
			(xy 346.191078 -397.018002) (xy 346.271384 -397.15694) (xy 346.813124 -397.15694) (xy 346.813124 -397.156432)
			(xy 346.813591 -397.132453) (xy 346.821086 -397.085083) (xy 346.835895 -397.039469) (xy 346.857655 -396.996731)
			(xy 346.885831 -396.957922) (xy 346.919729 -396.923996) (xy 346.958514 -396.895788) (xy 347.001234 -396.873993)
			(xy 347.046836 -396.859145) (xy 347.094199 -396.851611) (xy 347.118178 -396.851124) (xy 347.118686 -396.851124)
			(xy 347.142623 -396.851534) (xy 347.189912 -396.858998) (xy 347.235457 -396.873748) (xy 347.278145 -396.89542)
			(xy 347.31693 -396.923485) (xy 347.350864 -396.957256) (xy 347.379114 -396.995907) (xy 347.390466 -397.016986)
			(xy 347.390974 -397.018002) (xy 347.47128 -397.15694) (xy 348.013528 -397.15694) (xy 348.013528 -397.156432)
			(xy 348.013968 -397.132438) (xy 348.021471 -397.08504) (xy 348.036297 -397.0394) (xy 348.058082 -396.996641)
			(xy 348.086288 -396.957818) (xy 348.120221 -396.923885) (xy 348.159045 -396.89568) (xy 348.201804 -396.873896)
			(xy 348.247444 -396.85907) (xy 348.294842 -396.851568) (xy 348.318836 -396.851124) (xy 348.342772 -396.851574)
			(xy 348.390058 -396.859031) (xy 348.435603 -396.873773) (xy 348.478291 -396.895439) (xy 348.517077 -396.923498)
			(xy 348.551011 -396.957264) (xy 348.579263 -396.995909) (xy 348.590616 -397.016986) (xy 348.591124 -397.018002)
			(xy 348.67143 -397.15694) (xy 349.213424 -397.15694) (xy 349.213424 -397.156432) (xy 349.213868 -397.132438)
			(xy 349.221371 -397.085041) (xy 349.236197 -397.039401) (xy 349.257981 -396.996643) (xy 349.286187 -396.957819)
			(xy 349.320119 -396.923887) (xy 349.358943 -396.895681) (xy 349.401701 -396.873897) (xy 349.447341 -396.859071)
			(xy 349.494738 -396.851568) (xy 349.518732 -396.851124) (xy 349.542668 -396.851578) (xy 349.589954 -396.859034)
			(xy 349.635499 -396.873775) (xy 349.678187 -396.89544) (xy 349.716972 -396.923499) (xy 349.750907 -396.957264)
			(xy 349.779159 -396.995909) (xy 349.790512 -397.016986) (xy 349.79102 -397.018002) (xy 349.871326 -397.15694)
			(xy 350.41332 -397.15694) (xy 350.41332 -397.156432) (xy 350.413768 -397.132438) (xy 350.421271 -397.085041)
			(xy 350.436097 -397.039402) (xy 350.45788 -396.996644) (xy 350.486086 -396.95782) (xy 350.520017 -396.923888)
			(xy 350.55884 -396.895682) (xy 350.601598 -396.873898) (xy 350.647237 -396.859072) (xy 350.694634 -396.851568)
			(xy 350.718628 -396.851124) (xy 350.742563 -396.851581) (xy 350.78985 -396.859037) (xy 350.835395 -396.873777)
			(xy 350.878082 -396.895442) (xy 350.916868 -396.9235) (xy 350.950803 -396.957265) (xy 350.979055 -396.995909)
			(xy 350.990408 -397.016986) (xy 350.990916 -397.018002) (xy 351.071222 -397.15694) (xy 351.613216 -397.15694)
			(xy 351.613216 -397.156432) (xy 351.613691 -397.132453) (xy 351.621185 -397.085085) (xy 351.635994 -397.039471)
			(xy 351.657754 -396.996734) (xy 351.685929 -396.957925) (xy 351.719825 -396.923999) (xy 351.75861 -396.895791)
			(xy 351.801328 -396.873995) (xy 351.846929 -396.859147) (xy 351.894292 -396.851612) (xy 351.91827 -396.851124)
			(xy 351.918778 -396.851124) (xy 351.942715 -396.85154) (xy 351.990003 -396.859004) (xy 352.035549 -396.873752)
			(xy 352.078237 -396.895423) (xy 352.117022 -396.923487) (xy 352.150955 -396.957258) (xy 352.179206 -396.995907)
			(xy 352.190558 -397.016986) (xy 352.191066 -397.018002) (xy 352.271372 -397.15694) (xy 352.813112 -397.15694)
			(xy 352.813112 -397.156432) (xy 352.813591 -397.132453) (xy 352.821085 -397.085085) (xy 352.835894 -397.039472)
			(xy 352.857653 -396.996735) (xy 352.885827 -396.957926) (xy 352.919724 -396.924) (xy 352.958508 -396.895792)
			(xy 353.001225 -396.873996) (xy 353.046826 -396.859147) (xy 353.094188 -396.851612) (xy 353.118166 -396.851124)
			(xy 353.118674 -396.851124) (xy 353.142611 -396.851543) (xy 353.189899 -396.859006) (xy 353.235444 -396.873754)
			(xy 353.278132 -396.895425) (xy 353.316918 -396.923488) (xy 353.350851 -396.957258) (xy 353.379102 -396.995907)
			(xy 353.390454 -397.016986) (xy 353.390962 -397.018002) (xy 353.471268 -397.15694) (xy 354.013516 -397.15694)
			(xy 354.013516 -397.156432) (xy 354.013968 -397.132439) (xy 354.021471 -397.085042) (xy 354.036296 -397.039403)
			(xy 354.05808 -396.996645) (xy 354.086284 -396.957822) (xy 354.120216 -396.92389) (xy 354.159038 -396.895684)
			(xy 354.201795 -396.873899) (xy 354.247434 -396.859072) (xy 354.294831 -396.851568) (xy 354.318824 -396.851124)
			(xy 354.342759 -396.851584) (xy 354.390046 -396.859039) (xy 354.43559 -396.873779) (xy 354.478278 -396.895444)
			(xy 354.517064 -396.923501) (xy 354.550998 -396.957265) (xy 354.579251 -396.99591) (xy 354.590604 -397.016986)
			(xy 354.591112 -397.018002) (xy 354.671418 -397.15694) (xy 370.586 -397.15694) (xy 370.586 -397.156432)
			(xy 370.586468 -397.132439) (xy 370.59397 -397.085044) (xy 370.608795 -397.039406) (xy 370.630577 -396.99665)
			(xy 370.65878 -396.957827) (xy 370.692709 -396.923895) (xy 370.731529 -396.895689) (xy 370.774284 -396.873904)
			(xy 370.819921 -396.859076) (xy 370.867315 -396.85157) (xy 370.891308 -396.851124) (xy 370.915243 -396.851597)
			(xy 370.962529 -396.85905) (xy 371.008073 -396.873788) (xy 371.050761 -396.89545) (xy 371.089547 -396.923505)
			(xy 371.123482 -396.957268) (xy 371.151735 -396.99591) (xy 371.163088 -397.016986) (xy 371.163596 -397.018002)
			(xy 371.243902 -397.15694) (xy 371.785896 -397.15694) (xy 371.785896 -397.156432) (xy 371.786368 -397.13244)
			(xy 371.79387 -397.085045) (xy 371.808694 -397.039407) (xy 371.830476 -396.996651) (xy 371.858678 -396.957829)
			(xy 371.892607 -396.923897) (xy 371.931427 -396.895691) (xy 371.974181 -396.873905) (xy 372.019817 -396.859076)
			(xy 372.067212 -396.85157) (xy 372.091204 -396.851124) (xy 372.115139 -396.8516) (xy 372.162424 -396.859053)
			(xy 372.207968 -396.87379) (xy 372.250656 -396.895451) (xy 372.289442 -396.923506) (xy 372.323377 -396.957268)
			(xy 372.351631 -396.99591) (xy 372.362984 -397.016986) (xy 372.363492 -397.018002) (xy 372.443798 -397.15694)
			(xy 372.985792 -397.15694) (xy 372.985792 -397.156432) (xy 372.986268 -397.13244) (xy 372.99377 -397.085045)
			(xy 373.008594 -397.039408) (xy 373.030375 -396.996652) (xy 373.058577 -396.95783) (xy 373.092506 -396.923898)
			(xy 373.131325 -396.895692) (xy 373.174079 -396.873906) (xy 373.219714 -396.859077) (xy 373.267108 -396.85157)
			(xy 373.2911 -396.851124) (xy 373.315035 -396.851603) (xy 373.36232 -396.859055) (xy 373.407864 -396.873792)
			(xy 373.450552 -396.895453) (xy 373.489338 -396.923507) (xy 373.523273 -396.957269) (xy 373.551526 -396.995911)
			(xy 373.56288 -397.016986) (xy 373.563388 -397.018002) (xy 373.643694 -397.15694) (xy 374.185688 -397.15694)
			(xy 374.185688 -397.156432) (xy 374.186191 -397.132455) (xy 374.193684 -397.085089) (xy 374.208492 -397.039477)
			(xy 374.230249 -396.996742) (xy 374.25842 -396.957934) (xy 374.292313 -396.924009) (xy 374.331094 -396.895801)
			(xy 374.373809 -396.874003) (xy 374.419406 -396.859152) (xy 374.466765 -396.851614) (xy 374.490742 -396.851124)
			(xy 374.49125 -396.851124) (xy 374.515186 -396.851563) (xy 374.562473 -396.859022) (xy 374.608018 -396.873766)
			(xy 374.650706 -396.895434) (xy 374.689492 -396.923494) (xy 374.723426 -396.957262) (xy 374.751677 -396.995908)
			(xy 374.76303 -397.016986) (xy 374.763538 -397.018002) (xy 374.843844 -397.15694) (xy 375.385584 -397.15694)
			(xy 375.385584 -397.156432) (xy 375.386091 -397.132455) (xy 375.393584 -397.085089) (xy 375.408391 -397.039478)
			(xy 375.430148 -396.996743) (xy 375.458319 -396.957936) (xy 375.492212 -396.92401) (xy 375.530992 -396.895802)
			(xy 375.573706 -396.874004) (xy 375.619303 -396.859153) (xy 375.666661 -396.851614) (xy 375.690638 -396.851124)
			(xy 375.691146 -396.851124) (xy 375.715082 -396.851566) (xy 375.762369 -396.859025) (xy 375.807914 -396.873768)
			(xy 375.850602 -396.895435) (xy 375.889387 -396.923495) (xy 375.923322 -396.957262) (xy 375.951573 -396.995909)
			(xy 375.962926 -397.016986) (xy 375.963434 -397.018002) (xy 376.04374 -397.15694) (xy 376.585988 -397.15694)
			(xy 376.585988 -397.156432) (xy 376.586468 -397.13244) (xy 376.59397 -397.085046) (xy 376.608793 -397.039409)
			(xy 376.630574 -396.996653) (xy 376.658776 -396.957831) (xy 376.692704 -396.9239) (xy 376.731523 -396.895693)
			(xy 376.774276 -396.873907) (xy 376.819911 -396.859078) (xy 376.867304 -396.851571) (xy 376.891296 -396.851124)
			(xy 376.915233 -396.851526) (xy 376.962523 -396.858992) (xy 377.008068 -396.873742) (xy 377.050756 -396.895416)
			(xy 377.089541 -396.923483) (xy 377.123474 -396.957255) (xy 377.151724 -396.995906) (xy 377.163076 -397.016986)
			(xy 377.163584 -397.018002) (xy 377.24389 -397.15694) (xy 377.785884 -397.15694) (xy 377.785884 -397.156432)
			(xy 377.786368 -397.13244) (xy 377.793869 -397.085046) (xy 377.808693 -397.03941) (xy 377.830474 -396.996654)
			(xy 377.858675 -396.957833) (xy 377.892602 -396.923901) (xy 377.93142 -396.895695) (xy 377.974173 -396.873908)
			(xy 378.019808 -396.859079) (xy 378.0672 -396.851571) (xy 378.091192 -396.851124) (xy 378.115129 -396.851529)
			(xy 378.162418 -396.858995) (xy 378.207964 -396.873745) (xy 378.250652 -396.895418) (xy 378.289437 -396.923484)
			(xy 378.32337 -396.957256) (xy 378.35162 -396.995906) (xy 378.362972 -397.016986) (xy 378.36348 -397.018002)
			(xy 378.443786 -397.15694) (xy 378.98578 -397.15694) (xy 378.98578 -397.156432) (xy 378.986268 -397.13244)
			(xy 378.993769 -397.085047) (xy 379.008593 -397.039411) (xy 379.030373 -396.996656) (xy 379.058574 -396.957834)
			(xy 379.092501 -396.923902) (xy 379.131318 -396.895696) (xy 379.17407 -396.87391) (xy 379.219704 -396.85908)
			(xy 379.267096 -396.851571) (xy 379.291088 -396.851124) (xy 379.315025 -396.851532) (xy 379.362314 -396.858997)
			(xy 379.40786 -396.873747) (xy 379.450547 -396.895419) (xy 379.489333 -396.923485) (xy 379.523266 -396.957256)
			(xy 379.551516 -396.995907) (xy 379.562868 -397.016986) (xy 379.563376 -397.018002) (xy 379.643682 -397.15694)
			(xy 380.185676 -397.15694) (xy 380.185676 -397.156432) (xy 380.186191 -397.132455) (xy 380.193684 -397.08509)
			(xy 380.208491 -397.03948) (xy 380.230247 -396.996746) (xy 380.258417 -396.957938) (xy 380.292308 -396.924013)
			(xy 380.331088 -396.895805) (xy 380.373801 -396.874006) (xy 380.419396 -396.859155) (xy 380.466754 -396.851615)
			(xy 380.49073 -396.851124) (xy 380.491238 -396.851124) (xy 380.515174 -396.851573) (xy 380.562461 -396.85903)
			(xy 380.608005 -396.873772) (xy 380.650693 -396.895438) (xy 380.689479 -396.923498) (xy 380.723413 -396.957263)
			(xy 380.751665 -396.995909) (xy 380.763018 -397.016986) (xy 380.763526 -397.018002) (xy 380.843832 -397.15694)
			(xy 381.385572 -397.15694) (xy 381.385572 -397.156432) (xy 381.386091 -397.132455) (xy 381.393584 -397.085091)
			(xy 381.40839 -397.039481) (xy 381.430146 -396.996747) (xy 381.458316 -396.95794) (xy 381.492207 -396.924015)
			(xy 381.530985 -396.895806) (xy 381.573698 -396.874007) (xy 381.619293 -396.859155) (xy 381.66665 -396.851615)
			(xy 381.690626 -396.851124) (xy 381.691134 -396.851124) (xy 381.71507 -396.851576) (xy 381.762356 -396.859033)
			(xy 381.807901 -396.873774) (xy 381.850589 -396.89544) (xy 381.889375 -396.923499) (xy 381.923309 -396.957264)
			(xy 381.951561 -396.995909) (xy 381.962914 -397.016986) (xy 381.963422 -397.018002) (xy 382.043728 -397.15694)
			(xy 382.585976 -397.15694) (xy 382.585976 -397.156432) (xy 382.586468 -397.132441) (xy 382.593969 -397.085048)
			(xy 382.608792 -397.039412) (xy 382.630572 -396.996657) (xy 382.658773 -396.957836) (xy 382.692699 -396.923904)
			(xy 382.731516 -396.895697) (xy 382.774267 -396.873911) (xy 382.819901 -396.85908) (xy 382.867293 -396.851571)
			(xy 382.891284 -396.851124) (xy 382.915221 -396.851535) (xy 382.96251 -396.859) (xy 383.008055 -396.873749)
			(xy 383.050743 -396.895421) (xy 383.089528 -396.923486) (xy 383.123461 -396.957257) (xy 383.151712 -396.995907)
			(xy 383.163064 -397.016986) (xy 383.163572 -397.018002) (xy 383.243878 -397.15694) (xy 383.785872 -397.15694)
			(xy 383.785872 -397.156432) (xy 383.786368 -397.132441) (xy 383.793869 -397.085048) (xy 383.808692 -397.039413)
			(xy 383.830472 -396.996658) (xy 383.858671 -396.957837) (xy 383.892597 -396.923905) (xy 383.931414 -396.895699)
			(xy 383.974165 -396.873912) (xy 384.019798 -396.859081) (xy 384.067189 -396.851572) (xy 384.09118 -396.851124)
			(xy 384.115117 -396.851539) (xy 384.162405 -396.859002) (xy 384.207951 -396.873751) (xy 384.250639 -396.895422)
			(xy 384.289424 -396.923487) (xy 384.323357 -396.957257) (xy 384.351608 -396.995907) (xy 384.36296 -397.016986)
			(xy 384.363468 -397.018002) (xy 384.443774 -397.15694) (xy 384.985768 -397.15694) (xy 384.985768 -397.156432)
			(xy 384.986268 -397.132441) (xy 384.993769 -397.085049) (xy 385.008592 -397.039414) (xy 385.030371 -396.996659)
			(xy 385.05857 -396.957838) (xy 385.092496 -396.923907) (xy 385.131311 -396.8957) (xy 385.174062 -396.873913)
			(xy 385.219694 -396.859082) (xy 385.267085 -396.851572) (xy 385.291076 -396.851124) (xy 385.315013 -396.851542)
			(xy 385.362301 -396.859005) (xy 385.407847 -396.873753) (xy 385.450534 -396.895424) (xy 385.48932 -396.923488)
			(xy 385.523253 -396.957258) (xy 385.551504 -396.995907) (xy 385.562856 -397.016986) (xy 385.563364 -397.018002)
			(xy 385.64367 -397.15694) (xy 386.185664 -397.15694) (xy 386.185664 -397.156432) (xy 386.186191 -397.132456)
			(xy 386.193683 -397.085092) (xy 386.208489 -397.039483) (xy 386.230244 -396.996749) (xy 386.258413 -396.957943)
			(xy 386.292303 -396.924018) (xy 386.331081 -396.895809) (xy 386.373792 -396.87401) (xy 386.419386 -396.859157)
			(xy 386.466742 -396.851616) (xy 386.490718 -396.851124) (xy 386.491226 -396.851124) (xy 386.515161 -396.851582)
			(xy 386.562448 -396.859038) (xy 386.607992 -396.873778) (xy 386.65068 -396.895443) (xy 386.689466 -396.923501)
			(xy 386.723401 -396.957265) (xy 386.751653 -396.995909) (xy 386.763006 -397.016986) (xy 386.763514 -397.018002)
			(xy 386.84382 -397.15694) (xy 387.38556 -397.15694) (xy 387.38556 -397.156432) (xy 387.386091 -397.132456)
			(xy 387.393583 -397.085093) (xy 387.408389 -397.039484) (xy 387.430144 -396.99675) (xy 387.458312 -396.957944)
			(xy 387.492202 -396.924019) (xy 387.530979 -396.89581) (xy 387.573689 -396.874011) (xy 387.619283 -396.859158)
			(xy 387.666638 -396.851616) (xy 387.690614 -396.851124) (xy 387.691122 -396.851124) (xy 387.715057 -396.851586)
			(xy 387.762343 -396.859041) (xy 387.807888 -396.873781) (xy 387.850576 -396.895444) (xy 387.889362 -396.923502)
			(xy 387.923296 -396.957266) (xy 387.951549 -396.99591) (xy 387.962902 -397.016986) (xy 387.96341 -397.018002)
			(xy 388.043716 -397.15694) (xy 388.585964 -397.15694) (xy 388.585964 -397.156432) (xy 388.586468 -397.132441)
			(xy 388.593969 -397.085049) (xy 388.608791 -397.039415) (xy 388.63057 -396.99666) (xy 388.658769 -396.95784)
			(xy 388.692694 -396.923908) (xy 388.731509 -396.895701) (xy 388.774259 -396.873914) (xy 388.819891 -396.859083)
			(xy 388.867281 -396.851572) (xy 388.891272 -396.851124) (xy 388.915209 -396.851545) (xy 388.962497 -396.859008)
			(xy 389.008042 -396.873755) (xy 389.05073 -396.895425) (xy 389.089515 -396.923489) (xy 389.123449 -396.957258)
			(xy 389.1517 -396.995907) (xy 389.163052 -397.016986) (xy 389.16356 -397.018002) (xy 389.243866 -397.15694)
			(xy 403.113748 -397.15694) (xy 403.113748 -397.156432) (xy 403.114292 -397.132444) (xy 403.121792 -397.085057)
			(xy 403.136612 -397.039428) (xy 403.158388 -396.996678) (xy 403.186583 -396.957861) (xy 403.220503 -396.923933)
			(xy 403.259313 -396.895728) (xy 403.302057 -396.873941) (xy 403.347683 -396.85911) (xy 403.395068 -396.851598)
			(xy 403.419056 -396.851124) (xy 403.442992 -396.851558) (xy 403.49028 -396.859018) (xy 403.535825 -396.873763)
			(xy 403.578513 -396.895431) (xy 403.617298 -396.923493) (xy 403.651232 -396.957261) (xy 403.679483 -396.995908)
			(xy 403.690836 -397.016986) (xy 403.691344 -397.018002) (xy 403.77165 -397.15694) (xy 404.313644 -397.15694)
			(xy 404.313644 -397.156432) (xy 404.314192 -397.132444) (xy 404.321692 -397.085058) (xy 404.336512 -397.039429)
			(xy 404.358287 -396.996679) (xy 404.386482 -396.957862) (xy 404.420401 -396.923934) (xy 404.459211 -396.895729)
			(xy 404.501955 -396.873943) (xy 404.54758 -396.859111) (xy 404.594964 -396.851598) (xy 404.618952 -396.851124)
			(xy 404.642888 -396.851561) (xy 404.690176 -396.859021) (xy 404.735721 -396.873765) (xy 404.778408 -396.895433)
			(xy 404.817194 -396.923494) (xy 404.851128 -396.957261) (xy 404.879379 -396.995908) (xy 404.890732 -397.016986)
			(xy 404.89124 -397.018002) (xy 404.971546 -397.15694) (xy 405.51354 -397.15694) (xy 405.51354 -397.156432)
			(xy 405.513968 -397.132437) (xy 405.521471 -397.085038) (xy 405.536298 -397.039397) (xy 405.558084 -396.996638)
			(xy 405.586291 -396.957814) (xy 405.620226 -396.923881) (xy 405.659051 -396.895676) (xy 405.701812 -396.873892)
			(xy 405.747454 -396.859068) (xy 405.794853 -396.851567) (xy 405.818848 -396.851124) (xy 405.842784 -396.851565)
			(xy 405.890071 -396.859024) (xy 405.935616 -396.873767) (xy 405.978304 -396.895434) (xy 406.01709 -396.923495)
			(xy 406.051024 -396.957262) (xy 406.079275 -396.995908) (xy 406.090628 -397.016986) (xy 406.091136 -397.018002)
			(xy 406.171442 -397.15694) (xy 406.713436 -397.15694) (xy 406.713436 -397.156432) (xy 406.713891 -397.132452)
			(xy 406.721386 -397.085082) (xy 406.736196 -397.039466) (xy 406.757958 -396.996728) (xy 406.786134 -396.957918)
			(xy 406.820034 -396.923992) (xy 406.858821 -396.895784) (xy 406.901542 -396.873989) (xy 406.947146 -396.859143)
			(xy 406.99451 -396.85161) (xy 407.01849 -396.851124) (xy 407.018998 -396.851124) (xy 407.042935 -396.851524)
			(xy 407.090225 -396.858991) (xy 407.135771 -396.873741) (xy 407.178458 -396.895415) (xy 407.217243 -396.923482)
			(xy 407.251176 -396.957255) (xy 407.279426 -396.995906) (xy 407.290778 -397.016986) (xy 407.291286 -397.018002)
			(xy 407.371592 -397.15694) (xy 407.913332 -397.15694) (xy 407.913332 -397.156432) (xy 407.913791 -397.132452)
			(xy 407.921286 -397.085082) (xy 407.936096 -397.039467) (xy 407.957857 -396.996729) (xy 407.986033 -396.957919)
			(xy 408.019932 -396.923993) (xy 408.058719 -396.895786) (xy 408.101439 -396.87399) (xy 408.147043 -396.859143)
			(xy 408.194407 -396.851611) (xy 408.218386 -396.851124) (xy 408.218894 -396.851124) (xy 408.242831 -396.851527)
			(xy 408.29012 -396.858993) (xy 408.335666 -396.873744) (xy 408.378354 -396.895417) (xy 408.417139 -396.923483)
			(xy 408.451072 -396.957255) (xy 408.479322 -396.995906) (xy 408.490674 -397.016986) (xy 408.491182 -397.018002)
			(xy 408.571488 -397.15694) (xy 409.113736 -397.15694) (xy 409.113736 -397.156432) (xy 409.114168 -397.132438)
			(xy 409.121671 -397.085039) (xy 409.136498 -397.039398) (xy 409.158283 -396.996639) (xy 409.18649 -396.957815)
			(xy 409.220424 -396.923882) (xy 409.259249 -396.895677) (xy 409.302009 -396.873893) (xy 409.347651 -396.859068)
			(xy 409.39505 -396.851567) (xy 409.419044 -396.851124) (xy 409.44298 -396.851568) (xy 409.490267 -396.859026)
			(xy 409.535812 -396.873769) (xy 409.5785 -396.895436) (xy 409.617285 -396.923496) (xy 409.651219 -396.957262)
			(xy 409.679471 -396.995909) (xy 409.690824 -397.016986) (xy 409.691332 -397.018002) (xy 409.771638 -397.15694)
			(xy 410.313632 -397.15694) (xy 410.313632 -397.156432) (xy 410.314068 -397.132438) (xy 410.321571 -397.085039)
			(xy 410.336398 -397.039399) (xy 410.358183 -396.99664) (xy 410.386389 -396.957816) (xy 410.420322 -396.923884)
			(xy 410.459147 -396.895678) (xy 410.501906 -396.873895) (xy 410.547547 -396.859069) (xy 410.594946 -396.851567)
			(xy 410.61894 -396.851124) (xy 410.642876 -396.851571) (xy 410.690163 -396.859029) (xy 410.735708 -396.873771)
			(xy 410.778395 -396.895437) (xy 410.817181 -396.923497) (xy 410.851115 -396.957263) (xy 410.879367 -396.995909)
			(xy 410.89072 -397.016986) (xy 410.891228 -397.018002) (xy 410.971534 -397.15694) (xy 411.513528 -397.15694)
			(xy 411.513528 -397.156432) (xy 411.513968 -397.132438) (xy 411.521471 -397.08504) (xy 411.536297 -397.0394)
			(xy 411.558082 -396.996641) (xy 411.586288 -396.957818) (xy 411.620221 -396.923885) (xy 411.659045 -396.89568)
			(xy 411.701804 -396.873896) (xy 411.747444 -396.85907) (xy 411.794842 -396.851568) (xy 411.818836 -396.851124)
			(xy 411.842772 -396.851574) (xy 411.890058 -396.859031) (xy 411.935603 -396.873773) (xy 411.978291 -396.895439)
			(xy 412.017077 -396.923498) (xy 412.051011 -396.957264) (xy 412.079263 -396.995909) (xy 412.090616 -397.016986)
			(xy 412.091124 -397.018002) (xy 412.17143 -397.15694) (xy 412.713424 -397.15694) (xy 412.713424 -397.156432)
			(xy 412.713891 -397.132453) (xy 412.721386 -397.085083) (xy 412.736195 -397.039469) (xy 412.757955 -396.996731)
			(xy 412.786131 -396.957922) (xy 412.820029 -396.923996) (xy 412.858814 -396.895788) (xy 412.901534 -396.873993)
			(xy 412.947136 -396.859145) (xy 412.994499 -396.851611) (xy 413.018478 -396.851124) (xy 413.018986 -396.851124)
			(xy 413.042923 -396.851534) (xy 413.090212 -396.858998) (xy 413.135757 -396.873748) (xy 413.178445 -396.89542)
			(xy 413.21723 -396.923485) (xy 413.251164 -396.957256) (xy 413.279414 -396.995907) (xy 413.290766 -397.016986)
			(xy 413.291274 -397.018002) (xy 413.37158 -397.15694) (xy 413.91332 -397.15694) (xy 413.91332 -397.156432)
			(xy 413.913791 -397.132453) (xy 413.921285 -397.085084) (xy 413.936095 -397.03947) (xy 413.957855 -396.996732)
			(xy 413.98603 -396.957923) (xy 414.019927 -396.923998) (xy 414.058712 -396.89579) (xy 414.101431 -396.873994)
			(xy 414.147033 -396.859146) (xy 414.194395 -396.851612) (xy 414.218374 -396.851124) (xy 414.218882 -396.851124)
			(xy 414.242819 -396.851537) (xy 414.290108 -396.859001) (xy 414.335653 -396.87375) (xy 414.378341 -396.895422)
			(xy 414.417126 -396.923486) (xy 414.451059 -396.957257) (xy 414.47931 -396.995907) (xy 414.490662 -397.016986)
			(xy 414.49117 -397.018002) (xy 414.571476 -397.15694) (xy 415.113724 -397.15694) (xy 415.113724 -397.156432)
			(xy 415.114168 -397.132438) (xy 415.121671 -397.085041) (xy 415.136497 -397.039401) (xy 415.158281 -396.996643)
			(xy 415.186487 -396.957819) (xy 415.220419 -396.923887) (xy 415.259243 -396.895681) (xy 415.302001 -396.873897)
			(xy 415.347641 -396.859071) (xy 415.395038 -396.851568) (xy 415.419032 -396.851124) (xy 415.442968 -396.851578)
			(xy 415.490254 -396.859034) (xy 415.535799 -396.873775) (xy 415.578487 -396.89544) (xy 415.617272 -396.923499)
			(xy 415.651207 -396.957264) (xy 415.679459 -396.995909) (xy 415.690812 -397.016986) (xy 415.69132 -397.018002)
			(xy 415.771626 -397.15694) (xy 416.31362 -397.15694) (xy 416.31362 -397.156432) (xy 416.314068 -397.132438)
			(xy 416.321571 -397.085041) (xy 416.336397 -397.039402) (xy 416.35818 -396.996644) (xy 416.386386 -396.95782)
			(xy 416.420317 -396.923888) (xy 416.45914 -396.895682) (xy 416.501898 -396.873898) (xy 416.547537 -396.859072)
			(xy 416.594934 -396.851568) (xy 416.618928 -396.851124) (xy 416.642863 -396.851581) (xy 416.69015 -396.859037)
			(xy 416.735695 -396.873777) (xy 416.778382 -396.895442) (xy 416.817168 -396.9235) (xy 416.851103 -396.957265)
			(xy 416.879355 -396.995909) (xy 416.890708 -397.016986) (xy 416.891216 -397.018002) (xy 416.971522 -397.15694)
			(xy 417.513516 -397.15694) (xy 417.513516 -397.156432) (xy 417.513968 -397.132439) (xy 417.521471 -397.085042)
			(xy 417.536296 -397.039403) (xy 417.55808 -396.996645) (xy 417.586284 -396.957822) (xy 417.620216 -396.92389)
			(xy 417.659038 -396.895684) (xy 417.701795 -396.873899) (xy 417.747434 -396.859072) (xy 417.794831 -396.851568)
			(xy 417.818824 -396.851124) (xy 417.842759 -396.851584) (xy 417.890046 -396.859039) (xy 417.93559 -396.873779)
			(xy 417.978278 -396.895444) (xy 418.017064 -396.923501) (xy 418.050998 -396.957265) (xy 418.079251 -396.99591)
			(xy 418.090604 -397.016986) (xy 418.091112 -397.018002) (xy 418.171418 -397.15694) (xy 418.713412 -397.15694)
			(xy 418.713412 -397.156432) (xy 418.713891 -397.132453) (xy 418.721385 -397.085085) (xy 418.736194 -397.039472)
			(xy 418.757953 -396.996735) (xy 418.786127 -396.957926) (xy 418.820024 -396.924) (xy 418.858808 -396.895792)
			(xy 418.901525 -396.873996) (xy 418.947126 -396.859147) (xy 418.994488 -396.851612) (xy 419.018466 -396.851124)
			(xy 419.018974 -396.851124) (xy 419.042911 -396.851543) (xy 419.090199 -396.859006) (xy 419.135744 -396.873754)
			(xy 419.178432 -396.895425) (xy 419.217218 -396.923488) (xy 419.251151 -396.957258) (xy 419.279402 -396.995907)
			(xy 419.290754 -397.016986) (xy 419.291262 -397.018002) (xy 419.371568 -397.15694) (xy 419.913308 -397.15694)
			(xy 419.913308 -397.156432) (xy 419.913791 -397.132454) (xy 419.921285 -397.085086) (xy 419.936094 -397.039473)
			(xy 419.957852 -396.996736) (xy 419.986026 -396.957927) (xy 420.019922 -396.924002) (xy 420.058705 -396.895794)
			(xy 420.101423 -396.873997) (xy 420.147023 -396.859148) (xy 420.194384 -396.851612) (xy 420.218362 -396.851124)
			(xy 420.21887 -396.851124) (xy 420.242807 -396.851547) (xy 420.290095 -396.859009) (xy 420.33564 -396.873756)
			(xy 420.378328 -396.895426) (xy 420.417113 -396.923489) (xy 420.451047 -396.957259) (xy 420.479298 -396.995907)
			(xy 420.49065 -397.016986) (xy 420.491158 -397.018002) (xy 420.571464 -397.15694) (xy 421.113712 -397.15694)
			(xy 421.113712 -397.156432) (xy 421.114168 -397.132439) (xy 421.12167 -397.085042) (xy 421.136496 -397.039404)
			(xy 421.158279 -396.996646) (xy 421.186483 -396.957823) (xy 421.220414 -396.923891) (xy 421.259236 -396.895685)
			(xy 421.301992 -396.8739) (xy 421.347631 -396.859073) (xy 421.395027 -396.851569) (xy 421.41902 -396.851124)
			(xy 421.442955 -396.851587) (xy 421.490241 -396.859042) (xy 421.535786 -396.873782) (xy 421.578474 -396.895445)
			(xy 421.61726 -396.923502) (xy 421.651194 -396.957266) (xy 421.679447 -396.99591) (xy 421.6908 -397.016986)
			(xy 421.691308 -397.018002) (xy 422.083738 -397.696944) (xy 422.096544 -397.720286) (xy 422.114771 -397.770304)
			(xy 422.124039 -397.822727) (xy 422.124632 -397.849344) (xy 422.124179 -397.873323) (xy 422.116675 -397.920689)
			(xy 422.101859 -397.9663) (xy 422.080094 -398.009034) (xy 422.051916 -398.04784) (xy 422.018018 -398.081764)
			(xy 421.979234 -398.109971) (xy 421.936517 -398.131769) (xy 421.890917 -398.14662) (xy 421.843556 -398.154161)
			(xy 421.819578 -398.154652) (xy 421.81907 -398.154652) (xy 421.795497 -398.154255) (xy 421.74891 -398.14701)
			(xy 421.703993 -398.132683) (xy 421.661815 -398.111614) (xy 421.623383 -398.084306) (xy 421.58961 -398.051409)
			(xy 421.561302 -398.013706) (xy 421.54983 -397.993108) (xy 421.549322 -397.992346) (xy 421.151558 -397.304006)
			(xy 421.139682 -397.281329) (xy 421.122831 -397.232996) (xy 421.114258 -397.182533) (xy 421.113712 -397.15694)
			(xy 420.571464 -397.15694) (xy 420.883588 -397.696944) (xy 420.896302 -397.720272) (xy 420.914403 -397.770215)
			(xy 420.923627 -397.82253) (xy 420.924228 -397.84909) (xy 420.924228 -397.849344) (xy 420.923778 -397.873335)
			(xy 420.916266 -397.920727) (xy 420.901434 -397.96636) (xy 420.879647 -398.009111) (xy 420.851441 -398.047928)
			(xy 420.81751 -398.081856) (xy 420.778691 -398.110059) (xy 420.735937 -398.131843) (xy 420.690303 -398.146672)
			(xy 420.642911 -398.15418) (xy 420.61892 -398.154652) (xy 420.595348 -398.154215) (xy 420.548763 -398.146978)
			(xy 420.503847 -398.132658) (xy 420.46167 -398.111595) (xy 420.423236 -398.084293) (xy 420.389462 -398.051402)
			(xy 420.361153 -398.013704) (xy 420.34968 -397.993108) (xy 420.349172 -397.992346) (xy 419.951408 -397.304006)
			(xy 419.939493 -397.281337) (xy 419.922555 -397.233012) (xy 419.913896 -397.182542) (xy 419.913308 -397.15694)
			(xy 419.371568 -397.15694) (xy 419.683692 -397.696944) (xy 419.696406 -397.720272) (xy 419.714507 -397.770215)
			(xy 419.723731 -397.82253) (xy 419.724332 -397.84909) (xy 419.724332 -397.849344) (xy 419.723878 -397.873335)
			(xy 419.716366 -397.920726) (xy 419.701534 -397.966359) (xy 419.679747 -398.00911) (xy 419.651542 -398.047927)
			(xy 419.617612 -398.081855) (xy 419.578793 -398.110058) (xy 419.53604 -398.131842) (xy 419.490407 -398.146671)
			(xy 419.443015 -398.15418) (xy 419.419024 -398.154652) (xy 419.395452 -398.154211) (xy 419.348867 -398.146975)
			(xy 419.303951 -398.132656) (xy 419.261774 -398.111594) (xy 419.223341 -398.084292) (xy 419.189567 -398.051401)
			(xy 419.161257 -398.013704) (xy 419.149784 -397.993108) (xy 419.149276 -397.992346) (xy 418.751512 -397.304006)
			(xy 418.739598 -397.281337) (xy 418.72266 -397.233012) (xy 418.714 -397.182542) (xy 418.713412 -397.15694)
			(xy 418.171418 -397.15694) (xy 418.483542 -397.696944) (xy 418.496349 -397.720286) (xy 418.514576 -397.770304)
			(xy 418.523843 -397.822727) (xy 418.524436 -397.849344) (xy 418.523979 -397.873322) (xy 418.516475 -397.920688)
			(xy 418.501659 -397.966299) (xy 418.479895 -398.009033) (xy 418.451717 -398.047839) (xy 418.41782 -398.081762)
			(xy 418.379036 -398.10997) (xy 418.336319 -398.131768) (xy 418.29072 -398.14662) (xy 418.24336 -398.15416)
			(xy 418.219382 -398.154652) (xy 418.218874 -398.154652) (xy 418.195301 -398.154252) (xy 418.148714 -398.147008)
			(xy 418.103797 -398.132681) (xy 418.06162 -398.111613) (xy 418.023187 -398.084305) (xy 417.989414 -398.051408)
			(xy 417.961106 -398.013706) (xy 417.949634 -397.993108) (xy 417.949126 -397.992346) (xy 417.551362 -397.304006)
			(xy 417.539486 -397.281329) (xy 417.522635 -397.232996) (xy 417.514062 -397.182533) (xy 417.513516 -397.15694)
			(xy 416.971522 -397.15694) (xy 417.283646 -397.696944) (xy 417.296453 -397.720286) (xy 417.31468 -397.770304)
			(xy 417.323947 -397.822727) (xy 417.32454 -397.849344) (xy 417.324079 -397.873322) (xy 417.316575 -397.920688)
			(xy 417.301759 -397.966298) (xy 417.279995 -398.009032) (xy 417.251818 -398.047837) (xy 417.217922 -398.081761)
			(xy 417.179138 -398.109969) (xy 417.136422 -398.131767) (xy 417.090824 -398.146619) (xy 417.043464 -398.15416)
			(xy 417.019486 -398.154652) (xy 417.018978 -398.154652) (xy 416.995405 -398.154249) (xy 416.948818 -398.147005)
			(xy 416.903901 -398.132679) (xy 416.861724 -398.111611) (xy 416.823291 -398.084304) (xy 416.789518 -398.051408)
			(xy 416.76121 -398.013706) (xy 416.749738 -397.993108) (xy 416.74923 -397.992346) (xy 416.351466 -397.304006)
			(xy 416.339591 -397.281329) (xy 416.322739 -397.232996) (xy 416.314166 -397.182533) (xy 416.31362 -397.15694)
			(xy 415.771626 -397.15694) (xy 416.08375 -397.696944) (xy 416.096557 -397.720285) (xy 416.114784 -397.770304)
			(xy 416.124051 -397.822726) (xy 416.124644 -397.849344) (xy 416.124179 -397.873322) (xy 416.116676 -397.920687)
			(xy 416.10186 -397.966297) (xy 416.080096 -398.00903) (xy 416.05192 -398.047836) (xy 416.018023 -398.08176)
			(xy 415.97924 -398.109967) (xy 415.936525 -398.131765) (xy 415.890927 -398.146618) (xy 415.843568 -398.15416)
			(xy 415.81959 -398.154652) (xy 415.819082 -398.154652) (xy 415.795509 -398.154245) (xy 415.748922 -398.147003)
			(xy 415.704006 -398.132677) (xy 415.661828 -398.11161) (xy 415.623395 -398.084303) (xy 415.589623 -398.051407)
			(xy 415.561314 -398.013706) (xy 415.549842 -397.993108) (xy 415.549334 -397.992346) (xy 415.15157 -397.304006)
			(xy 415.139695 -397.281329) (xy 415.122843 -397.232996) (xy 415.11427 -397.182533) (xy 415.113724 -397.15694)
			(xy 414.571476 -397.15694) (xy 414.8836 -397.696944) (xy 414.896315 -397.720271) (xy 414.914415 -397.770215)
			(xy 414.923639 -397.82253) (xy 414.92424 -397.84909) (xy 414.92424 -397.849344) (xy 414.923778 -397.873335)
			(xy 414.916266 -397.920725) (xy 414.901435 -397.966357) (xy 414.879649 -398.009107) (xy 414.851444 -398.047924)
			(xy 414.817515 -398.081852) (xy 414.778697 -398.110055) (xy 414.735946 -398.13184) (xy 414.690313 -398.146669)
			(xy 414.642923 -398.154179) (xy 414.618932 -398.154652) (xy 414.59536 -398.154205) (xy 414.548776 -398.14697)
			(xy 414.50386 -398.132651) (xy 414.461683 -398.111591) (xy 414.423249 -398.08429) (xy 414.389475 -398.0514)
			(xy 414.361165 -398.013703) (xy 414.349692 -397.993108) (xy 414.349184 -397.992346) (xy 413.95142 -397.304006)
			(xy 413.939506 -397.281337) (xy 413.922568 -397.233012) (xy 413.913908 -397.182542) (xy 413.91332 -397.15694)
			(xy 413.37158 -397.15694) (xy 413.683704 -397.696944) (xy 413.696419 -397.720271) (xy 413.71452 -397.770214)
			(xy 413.723743 -397.82253) (xy 413.724344 -397.84909) (xy 413.724344 -397.849344) (xy 413.723878 -397.873335)
			(xy 413.716367 -397.920724) (xy 413.701535 -397.966356) (xy 413.679749 -398.009106) (xy 413.651545 -398.047923)
			(xy 413.617617 -398.08185) (xy 413.578799 -398.110054) (xy 413.536049 -398.131838) (xy 413.490417 -398.146668)
			(xy 413.443027 -398.154179) (xy 413.419036 -398.154652) (xy 413.395464 -398.154202) (xy 413.34888 -398.146967)
			(xy 413.303964 -398.132649) (xy 413.261787 -398.111589) (xy 413.223353 -398.084289) (xy 413.189579 -398.051399)
			(xy 413.161269 -398.013703) (xy 413.149796 -397.993108) (xy 413.149288 -397.992346) (xy 412.751524 -397.304006)
			(xy 412.739611 -397.281337) (xy 412.722672 -397.233012) (xy 412.714012 -397.182542) (xy 412.713424 -397.15694)
			(xy 412.17143 -397.15694) (xy 412.483554 -397.696944) (xy 412.496362 -397.720285) (xy 412.514588 -397.770304)
			(xy 412.523855 -397.822726) (xy 412.524448 -397.849344) (xy 412.523979 -397.873322) (xy 412.516476 -397.920687)
			(xy 412.50166 -397.966296) (xy 412.479897 -398.009029) (xy 412.451721 -398.047835) (xy 412.417825 -398.081758)
			(xy 412.379043 -398.109966) (xy 412.336328 -398.131764) (xy 412.29073 -398.146617) (xy 412.243371 -398.154159)
			(xy 412.219394 -398.154652) (xy 412.218886 -398.154652) (xy 412.195313 -398.154242) (xy 412.148727 -398.147)
			(xy 412.10381 -398.132675) (xy 412.061633 -398.111608) (xy 412.0232 -398.084302) (xy 411.989427 -398.051406)
			(xy 411.961119 -398.013705) (xy 411.949646 -397.993108) (xy 411.949138 -397.992346) (xy 411.551374 -397.304006)
			(xy 411.539499 -397.281329) (xy 411.522648 -397.232996) (xy 411.514074 -397.182533) (xy 411.513528 -397.15694)
			(xy 410.971534 -397.15694) (xy 411.283658 -397.696944) (xy 411.296466 -397.720285) (xy 411.314692 -397.770304)
			(xy 411.323959 -397.822726) (xy 411.324552 -397.849344) (xy 411.324079 -397.873322) (xy 411.316576 -397.920686)
			(xy 411.301761 -397.966295) (xy 411.279998 -398.009028) (xy 411.251822 -398.047833) (xy 411.217927 -398.081757)
			(xy 411.179145 -398.109965) (xy 411.13643 -398.131763) (xy 411.090833 -398.146616) (xy 411.043475 -398.154159)
			(xy 411.019498 -398.154652) (xy 411.01899 -398.154652) (xy 410.995417 -398.154239) (xy 410.948831 -398.146997)
			(xy 410.903914 -398.132673) (xy 410.861737 -398.111607) (xy 410.823304 -398.084301) (xy 410.789531 -398.051406)
			(xy 410.761223 -398.013705) (xy 410.74975 -397.993108) (xy 410.749242 -397.992346) (xy 410.351478 -397.304006)
			(xy 410.339603 -397.281328) (xy 410.322752 -397.232996) (xy 410.314178 -397.182533) (xy 410.313632 -397.15694)
			(xy 409.771638 -397.15694) (xy 410.083762 -397.696944) (xy 410.09657 -397.720285) (xy 410.114796 -397.770304)
			(xy 410.124063 -397.822726) (xy 410.124656 -397.849344) (xy 410.124179 -397.873321) (xy 410.116676 -397.920686)
			(xy 410.101861 -397.966295) (xy 410.080098 -398.009027) (xy 410.051923 -398.047832) (xy 410.018028 -398.081755)
			(xy 409.979247 -398.109963) (xy 409.936533 -398.131762) (xy 409.890937 -398.146616) (xy 409.843579 -398.154159)
			(xy 409.819602 -398.154652) (xy 409.819094 -398.154652) (xy 409.795521 -398.154236) (xy 409.748935 -398.146995)
			(xy 409.704019 -398.132671) (xy 409.661841 -398.111605) (xy 409.623408 -398.0843) (xy 409.589635 -398.051405)
			(xy 409.561327 -398.013705) (xy 409.549854 -397.993108) (xy 409.549346 -397.992346) (xy 409.151582 -397.304006)
			(xy 409.139708 -397.281328) (xy 409.122856 -397.232996) (xy 409.114282 -397.182533) (xy 409.113736 -397.15694)
			(xy 408.571488 -397.15694) (xy 408.883612 -397.696944) (xy 408.896328 -397.720271) (xy 408.914428 -397.770214)
			(xy 408.923651 -397.82253) (xy 408.924252 -397.84909) (xy 408.924252 -397.849344) (xy 408.923778 -397.873334)
			(xy 408.916267 -397.920723) (xy 408.901436 -397.966354) (xy 408.879651 -398.009104) (xy 408.851448 -398.04792)
			(xy 408.81752 -398.081848) (xy 408.778704 -398.110051) (xy 408.735954 -398.131836) (xy 408.690323 -398.146667)
			(xy 408.642934 -398.154178) (xy 408.618944 -398.154652) (xy 408.595373 -398.154195) (xy 408.548789 -398.146962)
			(xy 408.503873 -398.132645) (xy 408.461696 -398.111586) (xy 408.423262 -398.084287) (xy 408.389488 -398.051398)
			(xy 408.361178 -398.013703) (xy 408.349704 -397.993108) (xy 408.349196 -397.992346) (xy 407.951432 -397.304006)
			(xy 407.939519 -397.281336) (xy 407.92258 -397.233012) (xy 407.91392 -397.182542) (xy 407.913332 -397.15694)
			(xy 407.371592 -397.15694) (xy 407.683716 -397.696944) (xy 407.696432 -397.720271) (xy 407.714532 -397.770214)
			(xy 407.723755 -397.82253) (xy 407.724356 -397.84909) (xy 407.724356 -397.849344) (xy 407.723878 -397.873334)
			(xy 407.716367 -397.920723) (xy 407.701536 -397.966353) (xy 407.679752 -398.009103) (xy 407.651549 -398.047919)
			(xy 407.617622 -398.081846) (xy 407.578806 -398.11005) (xy 407.536057 -398.131835) (xy 407.490427 -398.146666)
			(xy 407.443038 -398.154178) (xy 407.419048 -398.154652) (xy 407.395477 -398.154192) (xy 407.348893 -398.146959)
			(xy 407.303977 -398.132643) (xy 407.2618 -398.111585) (xy 407.223366 -398.084286) (xy 407.189592 -398.051398)
			(xy 407.161282 -398.013703) (xy 407.149808 -397.993108) (xy 407.1493 -397.992346) (xy 406.751536 -397.304006)
			(xy 406.739623 -397.281336) (xy 406.722684 -397.233012) (xy 406.714024 -397.182542) (xy 406.713436 -397.15694)
			(xy 406.171442 -397.15694) (xy 406.483566 -397.696944) (xy 406.496375 -397.720285) (xy 406.5146 -397.770303)
			(xy 406.523867 -397.822726) (xy 406.52446 -397.849344) (xy 406.524079 -397.873326) (xy 406.516573 -397.9207)
			(xy 406.501752 -397.966317) (xy 406.479981 -398.009055) (xy 406.451795 -398.047865) (xy 406.417888 -398.08179)
			(xy 406.379094 -398.109996) (xy 406.336367 -398.13179) (xy 406.290757 -398.146635) (xy 406.243388 -398.154166)
			(xy 406.219406 -398.154652) (xy 406.218898 -398.154652) (xy 406.195325 -398.154232) (xy 406.14874 -398.146992)
			(xy 406.103823 -398.132669) (xy 406.061646 -398.111604) (xy 406.023213 -398.084299) (xy 405.989439 -398.051405)
			(xy 405.961131 -398.013705) (xy 405.949658 -397.993108) (xy 405.94915 -397.992346) (xy 405.551386 -397.304006)
			(xy 405.539512 -397.281328) (xy 405.52266 -397.232996) (xy 405.514086 -397.182533) (xy 405.51354 -397.15694)
			(xy 404.971546 -397.15694) (xy 405.28367 -397.696944) (xy 405.296479 -397.720285) (xy 405.314704 -397.770303)
			(xy 405.323971 -397.822726) (xy 405.324564 -397.849344) (xy 405.324179 -397.873326) (xy 405.316673 -397.920699)
			(xy 405.301852 -397.966316) (xy 405.280081 -398.009054) (xy 405.251896 -398.047863) (xy 405.21799 -398.081788)
			(xy 405.179196 -398.109994) (xy 405.136469 -398.131788) (xy 405.090861 -398.146634) (xy 405.043492 -398.154166)
			(xy 405.01951 -398.154652) (xy 405.019002 -398.154652) (xy 404.995429 -398.154229) (xy 404.948844 -398.14699)
			(xy 404.903927 -398.132667) (xy 404.86175 -398.111602) (xy 404.823317 -398.084298) (xy 404.789544 -398.051404)
			(xy 404.761235 -398.013705) (xy 404.749762 -397.993108) (xy 404.749254 -397.992346) (xy 404.35149 -397.304006)
			(xy 404.339616 -397.281328) (xy 404.322764 -397.232995) (xy 404.31419 -397.182533) (xy 404.313644 -397.15694)
			(xy 403.77165 -397.15694) (xy 404.083774 -397.696944) (xy 404.096583 -397.720284) (xy 404.114808 -397.770303)
			(xy 404.124075 -397.822726) (xy 404.124668 -397.849344) (xy 404.124279 -397.873326) (xy 404.116773 -397.920698)
			(xy 404.101952 -397.966315) (xy 404.080182 -398.009053) (xy 404.051997 -398.047862) (xy 404.018091 -398.081787)
			(xy 403.979298 -398.109993) (xy 403.936572 -398.131787) (xy 403.890964 -398.146633) (xy 403.843595 -398.154165)
			(xy 403.819614 -398.154652) (xy 403.819106 -398.154652) (xy 403.795534 -398.154226) (xy 403.748948 -398.146987)
			(xy 403.704032 -398.132665) (xy 403.661854 -398.111601) (xy 403.623421 -398.084297) (xy 403.589648 -398.051404)
			(xy 403.561339 -398.013705) (xy 403.549866 -397.993108) (xy 403.549358 -397.992346) (xy 403.151594 -397.304006)
			(xy 403.139721 -397.281328) (xy 403.122868 -397.232995) (xy 403.114294 -397.182532) (xy 403.113748 -397.15694)
			(xy 389.243866 -397.15694) (xy 389.55599 -397.696944) (xy 389.568801 -397.720284) (xy 389.587025 -397.770303)
			(xy 389.596291 -397.822726) (xy 389.596884 -397.849344) (xy 389.596479 -397.873325) (xy 389.588973 -397.920696)
			(xy 389.574154 -397.966311) (xy 389.552385 -398.009048) (xy 389.524202 -398.047856) (xy 389.490298 -398.081781)
			(xy 389.451507 -398.109988) (xy 389.408783 -398.131783) (xy 389.363177 -398.14663) (xy 389.315811 -398.154164)
			(xy 389.29183 -398.154652) (xy 389.291322 -398.154652) (xy 389.26775 -398.154213) (xy 389.221165 -398.146976)
			(xy 389.176249 -398.132657) (xy 389.134072 -398.111595) (xy 389.095638 -398.084293) (xy 389.061865 -398.051401)
			(xy 389.033555 -398.013704) (xy 389.022082 -397.993108) (xy 389.021574 -397.992346) (xy 388.62381 -397.304006)
			(xy 388.61193 -397.281331) (xy 388.595082 -397.232997) (xy 388.58651 -397.182533) (xy 388.585964 -397.15694)
			(xy 388.043716 -397.15694) (xy 388.35584 -397.696944) (xy 388.368558 -397.72027) (xy 388.386657 -397.770214)
			(xy 388.395879 -397.82253) (xy 388.39648 -397.84909) (xy 388.39648 -397.849344) (xy 388.396078 -397.873338)
			(xy 388.388564 -397.920734) (xy 388.373729 -397.966371) (xy 388.351938 -398.009125) (xy 388.323726 -398.047945)
			(xy 388.28979 -398.081873) (xy 388.250964 -398.110075) (xy 388.208204 -398.131857) (xy 388.162564 -398.146681)
			(xy 388.115166 -398.154184) (xy 388.091172 -398.154652) (xy 388.067599 -398.154253) (xy 388.021012 -398.147009)
			(xy 387.976095 -398.132682) (xy 387.933917 -398.111614) (xy 387.895485 -398.084306) (xy 387.861712 -398.051408)
			(xy 387.833404 -398.013706) (xy 387.821932 -397.993108) (xy 387.821424 -397.992346) (xy 387.42366 -397.304006)
			(xy 387.411749 -397.281335) (xy 387.394809 -397.233011) (xy 387.386148 -397.182542) (xy 387.38556 -397.15694)
			(xy 386.84382 -397.15694) (xy 387.155944 -397.696944) (xy 387.168662 -397.720269) (xy 387.186761 -397.770214)
			(xy 387.195983 -397.82253) (xy 387.196584 -397.84909) (xy 387.196584 -397.849344) (xy 387.196178 -397.873338)
			(xy 387.188664 -397.920733) (xy 387.17383 -397.96637) (xy 387.152038 -398.009124) (xy 387.123828 -398.047943)
			(xy 387.089892 -398.081872) (xy 387.051066 -398.110074) (xy 387.008307 -398.131856) (xy 386.962667 -398.14668)
			(xy 386.91527 -398.154183) (xy 386.891276 -398.154652) (xy 386.867703 -398.15425) (xy 386.821116 -398.147007)
			(xy 386.776199 -398.13268) (xy 386.734022 -398.111612) (xy 386.695589 -398.084305) (xy 386.661816 -398.051408)
			(xy 386.633508 -398.013706) (xy 386.622036 -397.993108) (xy 386.621528 -397.992346) (xy 386.223764 -397.304006)
			(xy 386.211854 -397.281335) (xy 386.194914 -397.233011) (xy 386.186252 -397.182542) (xy 386.185664 -397.15694)
			(xy 385.64367 -397.15694) (xy 385.955794 -397.696944) (xy 385.968605 -397.720283) (xy 385.986829 -397.770303)
			(xy 385.996095 -397.822726) (xy 385.996688 -397.849344) (xy 385.996279 -397.873325) (xy 385.988774 -397.920695)
			(xy 385.973954 -397.96631) (xy 385.952186 -398.009047) (xy 385.924003 -398.047855) (xy 385.8901 -398.08178)
			(xy 385.851309 -398.109986) (xy 385.808586 -398.131782) (xy 385.76298 -398.146629) (xy 385.715614 -398.154164)
			(xy 385.691634 -398.154652) (xy 385.691126 -398.154652) (xy 385.667554 -398.15421) (xy 385.620969 -398.146974)
			(xy 385.576053 -398.132654) (xy 385.533876 -398.111593) (xy 385.495443 -398.084292) (xy 385.461669 -398.051401)
			(xy 385.433359 -398.013704) (xy 385.421886 -397.993108) (xy 385.421378 -397.992346) (xy 385.023614 -397.304006)
			(xy 385.011735 -397.281331) (xy 384.994886 -397.232997) (xy 384.986314 -397.182533) (xy 384.985768 -397.15694)
			(xy 384.443774 -397.15694) (xy 384.755898 -397.696944) (xy 384.768701 -397.720288) (xy 384.78693 -397.770305)
			(xy 384.796199 -397.822727) (xy 384.796792 -397.849344) (xy 384.796379 -397.873325) (xy 384.788874 -397.920695)
			(xy 384.774055 -397.966309) (xy 384.752287 -398.009046) (xy 384.724104 -398.047854) (xy 384.690201 -398.081778)
			(xy 384.651412 -398.109985) (xy 384.608689 -398.13178) (xy 384.563084 -398.146628) (xy 384.515718 -398.154164)
			(xy 384.491738 -398.154652) (xy 384.49123 -398.154652) (xy 384.467658 -398.154207) (xy 384.421074 -398.146971)
			(xy 384.376158 -398.132652) (xy 384.33398 -398.111592) (xy 384.295547 -398.084291) (xy 384.261773 -398.0514)
			(xy 384.233463 -398.013704) (xy 384.22199 -397.993108) (xy 384.221482 -397.992346) (xy 383.823718 -397.304006)
			(xy 383.811839 -397.281331) (xy 383.79499 -397.232997) (xy 383.786418 -397.182533) (xy 383.785872 -397.15694)
			(xy 383.243878 -397.15694) (xy 383.556002 -397.696944) (xy 383.568805 -397.720288) (xy 383.587034 -397.770305)
			(xy 383.596303 -397.822727) (xy 383.596896 -397.849344) (xy 383.596479 -397.873324) (xy 383.588974 -397.920694)
			(xy 383.574155 -397.966308) (xy 383.552387 -398.009045) (xy 383.524206 -398.047852) (xy 383.490303 -398.081777)
			(xy 383.451514 -398.109984) (xy 383.408792 -398.131779) (xy 383.363187 -398.146628) (xy 383.315822 -398.154163)
			(xy 383.291842 -398.154652) (xy 383.291334 -398.154652) (xy 383.267762 -398.154203) (xy 383.221178 -398.146969)
			(xy 383.176262 -398.13265) (xy 383.134085 -398.11159) (xy 383.095651 -398.08429) (xy 383.061877 -398.0514)
			(xy 383.033567 -398.013703) (xy 383.022094 -397.993108) (xy 383.021586 -397.992346) (xy 382.623822 -397.304006)
			(xy 382.611943 -397.281331) (xy 382.595094 -397.232996) (xy 382.586522 -397.182533) (xy 382.585976 -397.15694)
			(xy 382.043728 -397.15694) (xy 382.355852 -397.696944) (xy 382.368571 -397.720269) (xy 382.386669 -397.770214)
			(xy 382.395891 -397.82253) (xy 382.396492 -397.84909) (xy 382.396492 -397.849344) (xy 382.396078 -397.873337)
			(xy 382.388565 -397.920732) (xy 382.37373 -397.966368) (xy 382.35194 -398.009122) (xy 382.32373 -398.047941)
			(xy 382.289795 -398.081869) (xy 382.250971 -398.110071) (xy 382.208212 -398.131853) (xy 382.162574 -398.146679)
			(xy 382.115177 -398.154183) (xy 382.091184 -398.154652) (xy 382.067611 -398.154244) (xy 382.021025 -398.147001)
			(xy 381.976108 -398.132676) (xy 381.933931 -398.111609) (xy 381.895498 -398.084302) (xy 381.861725 -398.051407)
			(xy 381.833416 -398.013706) (xy 381.821944 -397.993108) (xy 381.821436 -397.992346) (xy 381.423672 -397.304006)
			(xy 381.411754 -397.281339) (xy 381.394818 -397.233013) (xy 381.386159 -397.182542) (xy 381.385572 -397.15694)
			(xy 380.843832 -397.15694) (xy 381.155956 -397.696944) (xy 381.168675 -397.720269) (xy 381.186773 -397.770214)
			(xy 381.195995 -397.822529) (xy 381.196596 -397.84909) (xy 381.196596 -397.849344) (xy 381.196178 -397.873337)
			(xy 381.188665 -397.920731) (xy 381.173831 -397.966367) (xy 381.152041 -398.009121) (xy 381.123831 -398.047939)
			(xy 381.089897 -398.081868) (xy 381.051073 -398.11007) (xy 381.008315 -398.131852) (xy 380.962677 -398.146678)
			(xy 380.915281 -398.154182) (xy 380.891288 -398.154652) (xy 380.867715 -398.154241) (xy 380.821129 -398.146999)
			(xy 380.776212 -398.132674) (xy 380.734035 -398.111608) (xy 380.695602 -398.084301) (xy 380.661829 -398.051406)
			(xy 380.633521 -398.013705) (xy 380.622048 -397.993108) (xy 380.62154 -397.992346) (xy 380.223776 -397.304006)
			(xy 380.211859 -397.281339) (xy 380.194923 -397.233013) (xy 380.186263 -397.182542) (xy 380.185676 -397.15694)
			(xy 379.643682 -397.15694) (xy 379.955806 -397.696944) (xy 379.96861 -397.720287) (xy 379.986838 -397.770304)
			(xy 379.996107 -397.822727) (xy 379.9967 -397.849344) (xy 379.996279 -397.873324) (xy 379.988774 -397.920694)
			(xy 379.973956 -397.966307) (xy 379.952188 -398.009044) (xy 379.924007 -398.047851) (xy 379.890105 -398.081775)
			(xy 379.851316 -398.109982) (xy 379.808594 -398.131778) (xy 379.76299 -398.146627) (xy 379.715626 -398.154163)
			(xy 379.691646 -398.154652) (xy 379.691138 -398.154652) (xy 379.667566 -398.1542) (xy 379.620982 -398.146966)
			(xy 379.576066 -398.132648) (xy 379.533889 -398.111589) (xy 379.495456 -398.084289) (xy 379.461681 -398.051399)
			(xy 379.433371 -398.013703) (xy 379.421898 -397.993108) (xy 379.42139 -397.992346) (xy 379.023626 -397.304006)
			(xy 379.011747 -397.28133) (xy 378.994898 -397.232996) (xy 378.986326 -397.182533) (xy 378.98578 -397.15694)
			(xy 378.443786 -397.15694) (xy 378.75591 -397.696944) (xy 378.768714 -397.720287) (xy 378.786943 -397.770304)
			(xy 378.796211 -397.822727) (xy 378.796804 -397.849344) (xy 378.796379 -397.873324) (xy 378.788874 -397.920693)
			(xy 378.774056 -397.966307) (xy 378.752289 -398.009042) (xy 378.724108 -398.04785) (xy 378.690206 -398.081774)
			(xy 378.651418 -398.109981) (xy 378.608697 -398.131777) (xy 378.563094 -398.146626) (xy 378.51573 -398.154163)
			(xy 378.49175 -398.154652) (xy 378.491242 -398.154652) (xy 378.467671 -398.154197) (xy 378.421086 -398.146963)
			(xy 378.376171 -398.132646) (xy 378.333993 -398.111587) (xy 378.29556 -398.084288) (xy 378.261786 -398.051398)
			(xy 378.233476 -398.013703) (xy 378.222002 -397.993108) (xy 378.221494 -397.992346) (xy 377.82373 -397.304006)
			(xy 377.811852 -397.28133) (xy 377.795002 -397.232996) (xy 377.78643 -397.182533) (xy 377.785884 -397.15694)
			(xy 377.24389 -397.15694) (xy 377.556014 -397.696944) (xy 377.568818 -397.720287) (xy 377.587047 -397.770304)
			(xy 377.596315 -397.822727) (xy 377.596908 -397.849344) (xy 377.596479 -397.873324) (xy 377.588974 -397.920693)
			(xy 377.574156 -397.966306) (xy 377.552389 -398.009041) (xy 377.524209 -398.047848) (xy 377.490308 -398.081772)
			(xy 377.45152 -398.10998) (xy 377.4088 -398.131776) (xy 377.363197 -398.146625) (xy 377.315833 -398.154162)
			(xy 377.291854 -398.154652) (xy 377.291346 -398.154652) (xy 377.267775 -398.154194) (xy 377.221191 -398.146961)
			(xy 377.176275 -398.132644) (xy 377.134098 -398.111586) (xy 377.095664 -398.084287) (xy 377.06189 -398.051398)
			(xy 377.03358 -398.013703) (xy 377.022106 -397.993108) (xy 377.021598 -397.992346) (xy 376.623834 -397.304006)
			(xy 376.611956 -397.28133) (xy 376.595106 -397.232996) (xy 376.586534 -397.182533) (xy 376.585988 -397.15694)
			(xy 376.04374 -397.15694) (xy 376.355864 -397.696944) (xy 376.368584 -397.720268) (xy 376.386681 -397.770213)
			(xy 376.395904 -397.822529) (xy 376.396504 -397.84909) (xy 376.396504 -397.849344) (xy 376.396078 -397.873337)
			(xy 376.388565 -397.92073) (xy 376.373731 -397.966365) (xy 376.351942 -398.009118) (xy 376.323733 -398.047937)
			(xy 376.2898 -398.081865) (xy 376.250977 -398.110067) (xy 376.208221 -398.13185) (xy 376.162583 -398.146676)
			(xy 376.115189 -398.154182) (xy 376.091196 -398.154652) (xy 376.067623 -398.154234) (xy 376.021037 -398.146993)
			(xy 375.976121 -398.13267) (xy 375.933944 -398.111605) (xy 375.89551 -398.084299) (xy 375.861737 -398.051405)
			(xy 375.833429 -398.013705) (xy 375.821956 -397.993108) (xy 375.821448 -397.992346) (xy 375.423684 -397.304006)
			(xy 375.411767 -397.281338) (xy 375.394831 -397.233013) (xy 375.386171 -397.182542) (xy 375.385584 -397.15694)
			(xy 374.843844 -397.15694) (xy 375.155968 -397.696944) (xy 375.168688 -397.720268) (xy 375.186786 -397.770213)
			(xy 375.196008 -397.822529) (xy 375.196608 -397.84909) (xy 375.196608 -397.849344) (xy 375.196178 -397.873336)
			(xy 375.188665 -397.92073) (xy 375.173832 -397.966364) (xy 375.152043 -398.009117) (xy 375.123835 -398.047935)
			(xy 375.089902 -398.081863) (xy 375.051079 -398.110066) (xy 375.008324 -398.131849) (xy 374.962687 -398.146676)
			(xy 374.915292 -398.154181) (xy 374.8913 -398.154652) (xy 374.867727 -398.154231) (xy 374.821142 -398.146991)
			(xy 374.776225 -398.132668) (xy 374.734048 -398.111603) (xy 374.695615 -398.084298) (xy 374.661842 -398.051404)
			(xy 374.633533 -398.013705) (xy 374.62206 -397.993108) (xy 374.621552 -397.992346) (xy 374.223788 -397.304006)
			(xy 374.211872 -397.281338) (xy 374.194935 -397.233013) (xy 374.186275 -397.182542) (xy 374.185688 -397.15694)
			(xy 373.643694 -397.15694) (xy 373.955818 -397.696944) (xy 373.968623 -397.720287) (xy 373.986851 -397.770304)
			(xy 373.996119 -397.822727) (xy 373.996712 -397.849344) (xy 373.996279 -397.873324) (xy 373.988774 -397.920692)
			(xy 373.973957 -397.966305) (xy 373.95219 -398.00904) (xy 373.92401 -398.047847) (xy 373.89011 -398.081771)
			(xy 373.851323 -398.109978) (xy 373.808603 -398.131775) (xy 373.763 -398.146624) (xy 373.715637 -398.154162)
			(xy 373.691658 -398.154652) (xy 373.69115 -398.154652) (xy 373.667579 -398.154191) (xy 373.620995 -398.146958)
			(xy 373.576079 -398.132642) (xy 373.533902 -398.111584) (xy 373.495468 -398.084286) (xy 373.461694 -398.051397)
			(xy 373.433384 -398.013703) (xy 373.42191 -397.993108) (xy 373.421402 -397.992346) (xy 373.023638 -397.304006)
			(xy 373.01176 -397.28133) (xy 372.994911 -397.232996) (xy 372.986338 -397.182533) (xy 372.985792 -397.15694)
			(xy 372.443798 -397.15694) (xy 372.755922 -397.696944) (xy 372.768727 -397.720287) (xy 372.786955 -397.770304)
			(xy 372.796223 -397.822727) (xy 372.796816 -397.849344) (xy 372.796379 -397.873323) (xy 372.788875 -397.920691)
			(xy 372.774057 -397.966304) (xy 372.752291 -398.009039) (xy 372.724111 -398.047846) (xy 372.690212 -398.08177)
			(xy 372.651425 -398.109977) (xy 372.608705 -398.131773) (xy 372.563104 -398.146624) (xy 372.515741 -398.154162)
			(xy 372.491762 -398.154652) (xy 372.491254 -398.154652) (xy 372.467683 -398.154187) (xy 372.421099 -398.146955)
			(xy 372.376184 -398.13264) (xy 372.334006 -398.111583) (xy 372.295573 -398.084285) (xy 372.261798 -398.051397)
			(xy 372.233488 -398.013702) (xy 372.222014 -397.993108) (xy 372.221506 -397.992346) (xy 371.823742 -397.304006)
			(xy 371.811865 -397.28133) (xy 371.795015 -397.232996) (xy 371.786442 -397.182533) (xy 371.785896 -397.15694)
			(xy 371.243902 -397.15694) (xy 371.556026 -397.696944) (xy 371.568831 -397.720286) (xy 371.587059 -397.770304)
			(xy 371.596327 -397.822727) (xy 371.59692 -397.849344) (xy 371.596479 -397.873323) (xy 371.588975 -397.920691)
			(xy 371.574157 -397.966303) (xy 371.552392 -398.009038) (xy 371.524213 -398.047844) (xy 371.490313 -398.081768)
			(xy 371.451527 -398.109975) (xy 371.408808 -398.131772) (xy 371.363207 -398.146623) (xy 371.315845 -398.154162)
			(xy 371.291866 -398.154652) (xy 371.291358 -398.154652) (xy 371.267787 -398.154184) (xy 371.221204 -398.146953)
			(xy 371.176288 -398.132638) (xy 371.134111 -398.111581) (xy 371.095677 -398.084284) (xy 371.061902 -398.051396)
			(xy 371.033592 -398.013702) (xy 371.022118 -397.993108) (xy 371.02161 -397.992346) (xy 370.623846 -397.304006)
			(xy 370.611969 -397.28133) (xy 370.595119 -397.232996) (xy 370.586546 -397.182533) (xy 370.586 -397.15694)
			(xy 354.671418 -397.15694) (xy 354.983542 -397.696944) (xy 354.996349 -397.720286) (xy 355.014576 -397.770304)
			(xy 355.023843 -397.822727) (xy 355.024436 -397.849344) (xy 355.023979 -397.873322) (xy 355.016475 -397.920688)
			(xy 355.001659 -397.966299) (xy 354.979895 -398.009033) (xy 354.951717 -398.047839) (xy 354.91782 -398.081762)
			(xy 354.879036 -398.10997) (xy 354.836319 -398.131768) (xy 354.79072 -398.14662) (xy 354.74336 -398.15416)
			(xy 354.719382 -398.154652) (xy 354.718874 -398.154652) (xy 354.695301 -398.154252) (xy 354.648714 -398.147008)
			(xy 354.603797 -398.132681) (xy 354.56162 -398.111613) (xy 354.523187 -398.084305) (xy 354.489414 -398.051408)
			(xy 354.461106 -398.013706) (xy 354.449634 -397.993108) (xy 354.449126 -397.992346) (xy 354.051362 -397.304006)
			(xy 354.039486 -397.281329) (xy 354.022635 -397.232996) (xy 354.014062 -397.182533) (xy 354.013516 -397.15694)
			(xy 353.471268 -397.15694) (xy 353.783392 -397.696944) (xy 353.796106 -397.720272) (xy 353.814207 -397.770215)
			(xy 353.823431 -397.82253) (xy 353.824032 -397.84909) (xy 353.824032 -397.849344) (xy 353.823578 -397.873335)
			(xy 353.816066 -397.920726) (xy 353.801234 -397.966359) (xy 353.779447 -398.00911) (xy 353.751242 -398.047927)
			(xy 353.717312 -398.081855) (xy 353.678493 -398.110058) (xy 353.63574 -398.131842) (xy 353.590107 -398.146671)
			(xy 353.542715 -398.15418) (xy 353.518724 -398.154652) (xy 353.495152 -398.154211) (xy 353.448567 -398.146975)
			(xy 353.403651 -398.132656) (xy 353.361474 -398.111594) (xy 353.323041 -398.084292) (xy 353.289267 -398.051401)
			(xy 353.260957 -398.013704) (xy 353.249484 -397.993108) (xy 353.248976 -397.992346) (xy 352.851212 -397.304006)
			(xy 352.839298 -397.281337) (xy 352.82236 -397.233012) (xy 352.8137 -397.182542) (xy 352.813112 -397.15694)
			(xy 352.271372 -397.15694) (xy 352.583496 -397.696944) (xy 352.59621 -397.720271) (xy 352.614311 -397.770215)
			(xy 352.623535 -397.82253) (xy 352.624136 -397.84909) (xy 352.624136 -397.849344) (xy 352.623678 -397.873335)
			(xy 352.616166 -397.920726) (xy 352.601335 -397.966358) (xy 352.579548 -398.009109) (xy 352.551343 -398.047926)
			(xy 352.517413 -398.081853) (xy 352.478595 -398.110056) (xy 352.435843 -398.131841) (xy 352.39021 -398.14667)
			(xy 352.342819 -398.154179) (xy 352.318828 -398.154652) (xy 352.295256 -398.154208) (xy 352.248672 -398.146972)
			(xy 352.203756 -398.132653) (xy 352.161578 -398.111592) (xy 352.123145 -398.084291) (xy 352.089371 -398.0514)
			(xy 352.061061 -398.013704) (xy 352.049588 -397.993108) (xy 352.04908 -397.992346) (xy 351.651316 -397.304006)
			(xy 351.639402 -397.281337) (xy 351.622464 -397.233012) (xy 351.613804 -397.182542) (xy 351.613216 -397.15694)
			(xy 351.071222 -397.15694) (xy 351.383346 -397.696944) (xy 351.396153 -397.720286) (xy 351.41438 -397.770304)
			(xy 351.423647 -397.822727) (xy 351.42424 -397.849344) (xy 351.423779 -397.873322) (xy 351.416275 -397.920688)
			(xy 351.401459 -397.966298) (xy 351.379695 -398.009032) (xy 351.351518 -398.047837) (xy 351.317622 -398.081761)
			(xy 351.278838 -398.109969) (xy 351.236122 -398.131767) (xy 351.190524 -398.146619) (xy 351.143164 -398.15416)
			(xy 351.119186 -398.154652) (xy 351.118678 -398.154652) (xy 351.095105 -398.154249) (xy 351.048518 -398.147005)
			(xy 351.003601 -398.132679) (xy 350.961424 -398.111611) (xy 350.922991 -398.084304) (xy 350.889218 -398.051408)
			(xy 350.86091 -398.013706) (xy 350.849438 -397.993108) (xy 350.84893 -397.992346) (xy 350.451166 -397.304006)
			(xy 350.439291 -397.281329) (xy 350.422439 -397.232996) (xy 350.413866 -397.182533) (xy 350.41332 -397.15694)
			(xy 349.871326 -397.15694) (xy 350.18345 -397.696944) (xy 350.196257 -397.720285) (xy 350.214484 -397.770304)
			(xy 350.223751 -397.822726) (xy 350.224344 -397.849344) (xy 350.223879 -397.873322) (xy 350.216376 -397.920687)
			(xy 350.20156 -397.966297) (xy 350.179796 -398.00903) (xy 350.15162 -398.047836) (xy 350.117723 -398.08176)
			(xy 350.07894 -398.109967) (xy 350.036225 -398.131765) (xy 349.990627 -398.146618) (xy 349.943268 -398.15416)
			(xy 349.91929 -398.154652) (xy 349.918782 -398.154652) (xy 349.895209 -398.154245) (xy 349.848622 -398.147003)
			(xy 349.803706 -398.132677) (xy 349.761528 -398.11161) (xy 349.723095 -398.084303) (xy 349.689323 -398.051407)
			(xy 349.661014 -398.013706) (xy 349.649542 -397.993108) (xy 349.649034 -397.992346) (xy 349.25127 -397.304006)
			(xy 349.239395 -397.281329) (xy 349.222543 -397.232996) (xy 349.21397 -397.182533) (xy 349.213424 -397.15694)
			(xy 348.67143 -397.15694) (xy 348.983554 -397.696944) (xy 348.996362 -397.720285) (xy 349.014588 -397.770304)
			(xy 349.023855 -397.822726) (xy 349.024448 -397.849344) (xy 349.023979 -397.873322) (xy 349.016476 -397.920687)
			(xy 349.00166 -397.966296) (xy 348.979897 -398.009029) (xy 348.951721 -398.047835) (xy 348.917825 -398.081758)
			(xy 348.879043 -398.109966) (xy 348.836328 -398.131764) (xy 348.79073 -398.146617) (xy 348.743371 -398.154159)
			(xy 348.719394 -398.154652) (xy 348.718886 -398.154652) (xy 348.695313 -398.154242) (xy 348.648727 -398.147)
			(xy 348.60381 -398.132675) (xy 348.561633 -398.111608) (xy 348.5232 -398.084302) (xy 348.489427 -398.051406)
			(xy 348.461119 -398.013705) (xy 348.449646 -397.993108) (xy 348.449138 -397.992346) (xy 348.051374 -397.304006)
			(xy 348.039499 -397.281329) (xy 348.022648 -397.232996) (xy 348.014074 -397.182533) (xy 348.013528 -397.15694)
			(xy 347.47128 -397.15694) (xy 347.783404 -397.696944) (xy 347.796119 -397.720271) (xy 347.81422 -397.770214)
			(xy 347.823443 -397.82253) (xy 347.824044 -397.84909) (xy 347.824044 -397.849344) (xy 347.823578 -397.873335)
			(xy 347.816067 -397.920724) (xy 347.801235 -397.966356) (xy 347.779449 -398.009106) (xy 347.751245 -398.047923)
			(xy 347.717317 -398.08185) (xy 347.678499 -398.110054) (xy 347.635749 -398.131838) (xy 347.590117 -398.146668)
			(xy 347.542727 -398.154179) (xy 347.518736 -398.154652) (xy 347.495164 -398.154202) (xy 347.44858 -398.146967)
			(xy 347.403664 -398.132649) (xy 347.361487 -398.111589) (xy 347.323053 -398.084289) (xy 347.289279 -398.051399)
			(xy 347.260969 -398.013703) (xy 347.249496 -397.993108) (xy 347.248988 -397.992346) (xy 346.851224 -397.304006)
			(xy 346.839311 -397.281337) (xy 346.822372 -397.233012) (xy 346.813712 -397.182542) (xy 346.813124 -397.15694)
			(xy 346.271384 -397.15694) (xy 346.583508 -397.696944) (xy 346.596223 -397.720271) (xy 346.614324 -397.770214)
			(xy 346.623547 -397.82253) (xy 346.624148 -397.84909) (xy 346.624148 -397.849344) (xy 346.623678 -397.873334)
			(xy 346.616167 -397.920724) (xy 346.601336 -397.966355) (xy 346.57955 -398.009105) (xy 346.551346 -398.047922)
			(xy 346.517418 -398.081849) (xy 346.478602 -398.110052) (xy 346.435851 -398.131837) (xy 346.39022 -398.146668)
			(xy 346.34283 -398.154178) (xy 346.31884 -398.154652) (xy 346.295269 -398.154199) (xy 346.248684 -398.146965)
			(xy 346.203769 -398.132647) (xy 346.161591 -398.111588) (xy 346.123158 -398.084288) (xy 346.089383 -398.051399)
			(xy 346.061073 -398.013703) (xy 346.0496 -397.993108) (xy 346.049092 -397.992346) (xy 345.651328 -397.304006)
			(xy 345.639415 -397.281337) (xy 345.622476 -397.233012) (xy 345.613816 -397.182542) (xy 345.613228 -397.15694)
			(xy 345.071234 -397.15694) (xy 345.383358 -397.696944) (xy 345.396166 -397.720285) (xy 345.414392 -397.770304)
			(xy 345.423659 -397.822726) (xy 345.424252 -397.849344) (xy 345.423779 -397.873322) (xy 345.416276 -397.920686)
			(xy 345.401461 -397.966295) (xy 345.379698 -398.009028) (xy 345.351522 -398.047833) (xy 345.317627 -398.081757)
			(xy 345.278845 -398.109965) (xy 345.23613 -398.131763) (xy 345.190533 -398.146616) (xy 345.143175 -398.154159)
			(xy 345.119198 -398.154652) (xy 345.11869 -398.154652) (xy 345.095117 -398.154239) (xy 345.048531 -398.146997)
			(xy 345.003614 -398.132673) (xy 344.961437 -398.111607) (xy 344.923004 -398.084301) (xy 344.889231 -398.051406)
			(xy 344.860923 -398.013705) (xy 344.84945 -397.993108) (xy 344.848942 -397.992346) (xy 344.451178 -397.304006)
			(xy 344.439303 -397.281328) (xy 344.422452 -397.232996) (xy 344.413878 -397.182533) (xy 344.413332 -397.15694)
			(xy 343.871338 -397.15694) (xy 344.183462 -397.696944) (xy 344.19627 -397.720285) (xy 344.214496 -397.770304)
			(xy 344.223763 -397.822726) (xy 344.224356 -397.849344) (xy 344.223879 -397.873321) (xy 344.216376 -397.920686)
			(xy 344.201561 -397.966295) (xy 344.179798 -398.009027) (xy 344.151623 -398.047832) (xy 344.117728 -398.081755)
			(xy 344.078947 -398.109963) (xy 344.036233 -398.131762) (xy 343.990637 -398.146616) (xy 343.943279 -398.154159)
			(xy 343.919302 -398.154652) (xy 343.918794 -398.154652) (xy 343.895221 -398.154236) (xy 343.848635 -398.146995)
			(xy 343.803719 -398.132671) (xy 343.761541 -398.111605) (xy 343.723108 -398.0843) (xy 343.689335 -398.051405)
			(xy 343.661027 -398.013705) (xy 343.649554 -397.993108) (xy 343.649046 -397.992346) (xy 343.251282 -397.304006)
			(xy 343.239408 -397.281328) (xy 343.222556 -397.232996) (xy 343.213982 -397.182533) (xy 343.213436 -397.15694)
			(xy 342.671442 -397.15694) (xy 342.983566 -397.696944) (xy 342.996375 -397.720285) (xy 343.0146 -397.770303)
			(xy 343.023867 -397.822726) (xy 343.02446 -397.849344) (xy 343.024079 -397.873326) (xy 343.016573 -397.9207)
			(xy 343.001752 -397.966317) (xy 342.979981 -398.009055) (xy 342.951795 -398.047865) (xy 342.917888 -398.08179)
			(xy 342.879094 -398.109996) (xy 342.836367 -398.13179) (xy 342.790757 -398.146635) (xy 342.743388 -398.154166)
			(xy 342.719406 -398.154652) (xy 342.718898 -398.154652) (xy 342.695325 -398.154232) (xy 342.64874 -398.146992)
			(xy 342.603823 -398.132669) (xy 342.561646 -398.111604) (xy 342.523213 -398.084299) (xy 342.489439 -398.051405)
			(xy 342.461131 -398.013705) (xy 342.449658 -397.993108) (xy 342.44915 -397.992346) (xy 342.051386 -397.304006)
			(xy 342.039512 -397.281328) (xy 342.02266 -397.232996) (xy 342.014086 -397.182533) (xy 342.01354 -397.15694)
			(xy 341.471292 -397.15694) (xy 341.783416 -397.696944) (xy 341.796132 -397.720271) (xy 341.814232 -397.770214)
			(xy 341.823455 -397.82253) (xy 341.824056 -397.84909) (xy 341.824056 -397.849344) (xy 341.823578 -397.873334)
			(xy 341.816067 -397.920723) (xy 341.801236 -397.966353) (xy 341.779452 -398.009103) (xy 341.751249 -398.047919)
			(xy 341.717322 -398.081846) (xy 341.678506 -398.11005) (xy 341.635757 -398.131835) (xy 341.590127 -398.146666)
			(xy 341.542738 -398.154178) (xy 341.518748 -398.154652) (xy 341.495177 -398.154192) (xy 341.448593 -398.146959)
			(xy 341.403677 -398.132643) (xy 341.3615 -398.111585) (xy 341.323066 -398.084286) (xy 341.289292 -398.051398)
			(xy 341.260982 -398.013703) (xy 341.249508 -397.993108) (xy 341.249 -397.992346) (xy 340.851236 -397.304006)
			(xy 340.839323 -397.281336) (xy 340.822384 -397.233012) (xy 340.813724 -397.182542) (xy 340.813136 -397.15694)
			(xy 340.271396 -397.15694) (xy 340.58352 -397.696944) (xy 340.596236 -397.72027) (xy 340.614336 -397.770214)
			(xy 340.623559 -397.82253) (xy 340.62416 -397.84909) (xy 340.62416 -397.849344) (xy 340.623802 -397.873341)
			(xy 340.616287 -397.920742) (xy 340.60145 -397.966385) (xy 340.579655 -398.009144) (xy 340.551439 -398.047968)
			(xy 340.517498 -398.081899) (xy 340.478666 -398.110103) (xy 340.4359 -398.131885) (xy 340.390253 -398.146709)
			(xy 340.342849 -398.154209) (xy 340.318852 -398.154652) (xy 340.295281 -398.154189) (xy 340.248697 -398.146957)
			(xy 340.203782 -398.132641) (xy 340.161604 -398.111583) (xy 340.123171 -398.084285) (xy 340.089396 -398.051397)
			(xy 340.061086 -398.013703) (xy 340.049612 -397.993108) (xy 340.049104 -397.992346) (xy 339.65134 -397.304006)
			(xy 339.639428 -397.281336) (xy 339.622488 -397.233012) (xy 339.613828 -397.182542) (xy 339.61324 -397.15694)
			(xy 339.071246 -397.15694) (xy 339.38337 -397.696944) (xy 339.396179 -397.720285) (xy 339.414404 -397.770303)
			(xy 339.423671 -397.822726) (xy 339.424264 -397.849344) (xy 339.423879 -397.873326) (xy 339.416373 -397.920699)
			(xy 339.401552 -397.966316) (xy 339.379781 -398.009054) (xy 339.351596 -398.047863) (xy 339.31769 -398.081788)
			(xy 339.278896 -398.109994) (xy 339.236169 -398.131788) (xy 339.190561 -398.146634) (xy 339.143192 -398.154166)
			(xy 339.11921 -398.154652) (xy 339.118702 -398.154652) (xy 339.095129 -398.154229) (xy 339.048544 -398.14699)
			(xy 339.003627 -398.132667) (xy 338.96145 -398.111602) (xy 338.923017 -398.084298) (xy 338.889244 -398.051404)
			(xy 338.860935 -398.013705) (xy 338.849462 -397.993108) (xy 338.848954 -397.992346) (xy 338.45119 -397.304006)
			(xy 338.439316 -397.281328) (xy 338.422464 -397.232995) (xy 338.41389 -397.182533) (xy 338.413344 -397.15694)
			(xy 337.87135 -397.15694) (xy 338.183474 -397.696944) (xy 338.196283 -397.720284) (xy 338.214508 -397.770303)
			(xy 338.223775 -397.822726) (xy 338.224368 -397.849344) (xy 338.223979 -397.873326) (xy 338.216473 -397.920698)
			(xy 338.201652 -397.966315) (xy 338.179882 -398.009053) (xy 338.151697 -398.047862) (xy 338.117791 -398.081787)
			(xy 338.078998 -398.109993) (xy 338.036272 -398.131787) (xy 337.990664 -398.146633) (xy 337.943295 -398.154165)
			(xy 337.919314 -398.154652) (xy 337.918806 -398.154652) (xy 337.895234 -398.154226) (xy 337.848648 -398.146987)
			(xy 337.803732 -398.132665) (xy 337.761554 -398.111601) (xy 337.723121 -398.084297) (xy 337.689348 -398.051404)
			(xy 337.661039 -398.013705) (xy 337.649566 -397.993108) (xy 337.649058 -397.992346) (xy 337.251294 -397.304006)
			(xy 337.239421 -397.281328) (xy 337.222568 -397.232995) (xy 337.213994 -397.182532) (xy 337.213448 -397.15694)
			(xy 336.671454 -397.15694) (xy 336.983578 -397.696944) (xy 336.996388 -397.720284) (xy 337.014613 -397.770303)
			(xy 337.023879 -397.822726) (xy 337.024472 -397.849344) (xy 337.024079 -397.873326) (xy 337.016573 -397.920698)
			(xy 337.001753 -397.966314) (xy 336.979983 -398.009052) (xy 336.951799 -398.047861) (xy 336.917893 -398.081785)
			(xy 336.8791 -398.109992) (xy 336.836375 -398.131786) (xy 336.790767 -398.146632) (xy 336.743399 -398.154165)
			(xy 336.719418 -398.154652) (xy 336.71891 -398.154652) (xy 336.695338 -398.154223) (xy 336.648752 -398.146984)
			(xy 336.603836 -398.132663) (xy 336.561659 -398.111599) (xy 336.523225 -398.084296) (xy 336.489452 -398.051403)
			(xy 336.461143 -398.013704) (xy 336.44967 -397.993108) (xy 336.449162 -397.992346) (xy 336.051398 -397.304006)
			(xy 336.039525 -397.281328) (xy 336.022672 -397.232995) (xy 336.014098 -397.182532) (xy 336.013552 -397.15694)
			(xy 322.14367 -397.15694) (xy 322.455794 -397.696944) (xy 322.468605 -397.720283) (xy 322.486829 -397.770303)
			(xy 322.496095 -397.822726) (xy 322.496688 -397.849344) (xy 322.496279 -397.873325) (xy 322.488774 -397.920695)
			(xy 322.473954 -397.96631) (xy 322.452186 -398.009047) (xy 322.424003 -398.047855) (xy 322.3901 -398.08178)
			(xy 322.351309 -398.109986) (xy 322.308586 -398.131782) (xy 322.26298 -398.146629) (xy 322.215614 -398.154164)
			(xy 322.191634 -398.154652) (xy 322.191126 -398.154652) (xy 322.167554 -398.15421) (xy 322.120969 -398.146974)
			(xy 322.076053 -398.132654) (xy 322.033876 -398.111593) (xy 321.995443 -398.084292) (xy 321.961669 -398.051401)
			(xy 321.933359 -398.013704) (xy 321.921886 -397.993108) (xy 321.921378 -397.992346) (xy 321.523614 -397.304006)
			(xy 321.511735 -397.281331) (xy 321.494886 -397.232997) (xy 321.486314 -397.182533) (xy 321.485768 -397.15694)
			(xy 320.94352 -397.15694) (xy 321.255644 -397.696944) (xy 321.268362 -397.720269) (xy 321.286461 -397.770214)
			(xy 321.295683 -397.82253) (xy 321.296284 -397.84909) (xy 321.296284 -397.849344) (xy 321.295878 -397.873338)
			(xy 321.288364 -397.920733) (xy 321.27353 -397.96637) (xy 321.251738 -398.009124) (xy 321.223528 -398.047943)
			(xy 321.189592 -398.081872) (xy 321.150766 -398.110074) (xy 321.108007 -398.131856) (xy 321.062367 -398.14668)
			(xy 321.01497 -398.154183) (xy 320.990976 -398.154652) (xy 320.967403 -398.15425) (xy 320.920816 -398.147007)
			(xy 320.875899 -398.13268) (xy 320.833722 -398.111612) (xy 320.795289 -398.084305) (xy 320.761516 -398.051408)
			(xy 320.733208 -398.013706) (xy 320.721736 -397.993108) (xy 320.721228 -397.992346) (xy 320.323464 -397.304006)
			(xy 320.311554 -397.281335) (xy 320.294614 -397.233011) (xy 320.285952 -397.182542) (xy 320.285364 -397.15694)
			(xy 319.743624 -397.15694) (xy 320.055748 -397.696944) (xy 320.068467 -397.720269) (xy 320.086565 -397.770214)
			(xy 320.095787 -397.82253) (xy 320.096388 -397.84909) (xy 320.096388 -397.849344) (xy 320.095978 -397.873337)
			(xy 320.088465 -397.920733) (xy 320.07363 -397.966369) (xy 320.051839 -398.009123) (xy 320.023629 -398.047942)
			(xy 319.989693 -398.08187) (xy 319.950868 -398.110073) (xy 319.90811 -398.131854) (xy 319.86247 -398.14668)
			(xy 319.815074 -398.154183) (xy 319.79108 -398.154652) (xy 319.767507 -398.154247) (xy 319.72092 -398.147004)
			(xy 319.676003 -398.132678) (xy 319.633826 -398.111611) (xy 319.595393 -398.084304) (xy 319.561621 -398.051407)
			(xy 319.533312 -398.013706) (xy 319.52184 -397.993108) (xy 319.521332 -397.992346) (xy 319.123568 -397.304006)
			(xy 319.111658 -397.281335) (xy 319.094718 -397.233011) (xy 319.086056 -397.182542) (xy 319.085468 -397.15694)
			(xy 318.543474 -397.15694) (xy 318.855598 -397.696944) (xy 318.868401 -397.720288) (xy 318.88663 -397.770305)
			(xy 318.895899 -397.822727) (xy 318.896492 -397.849344) (xy 318.896079 -397.873325) (xy 318.888574 -397.920695)
			(xy 318.873755 -397.966309) (xy 318.851987 -398.009046) (xy 318.823804 -398.047854) (xy 318.789901 -398.081778)
			(xy 318.751112 -398.109985) (xy 318.708389 -398.13178) (xy 318.662784 -398.146628) (xy 318.615418 -398.154164)
			(xy 318.591438 -398.154652) (xy 318.59093 -398.154652) (xy 318.567358 -398.154207) (xy 318.520774 -398.146971)
			(xy 318.475858 -398.132652) (xy 318.43368 -398.111592) (xy 318.395247 -398.084291) (xy 318.361473 -398.0514)
			(xy 318.333163 -398.013704) (xy 318.32169 -397.993108) (xy 318.321182 -397.992346) (xy 317.923418 -397.304006)
			(xy 317.911539 -397.281331) (xy 317.89469 -397.232997) (xy 317.886118 -397.182533) (xy 317.885572 -397.15694)
			(xy 317.343578 -397.15694) (xy 317.655702 -397.696944) (xy 317.668505 -397.720288) (xy 317.686734 -397.770305)
			(xy 317.696003 -397.822727) (xy 317.696596 -397.849344) (xy 317.696179 -397.873324) (xy 317.688674 -397.920694)
			(xy 317.673855 -397.966308) (xy 317.652087 -398.009045) (xy 317.623906 -398.047852) (xy 317.590003 -398.081777)
			(xy 317.551214 -398.109984) (xy 317.508492 -398.131779) (xy 317.462887 -398.146628) (xy 317.415522 -398.154163)
			(xy 317.391542 -398.154652) (xy 317.391034 -398.154652) (xy 317.367462 -398.154203) (xy 317.320878 -398.146969)
			(xy 317.275962 -398.13265) (xy 317.233785 -398.11159) (xy 317.195351 -398.08429) (xy 317.161577 -398.0514)
			(xy 317.133267 -398.013703) (xy 317.121794 -397.993108) (xy 317.121286 -397.992346) (xy 316.723522 -397.304006)
			(xy 316.711643 -397.281331) (xy 316.694794 -397.232996) (xy 316.686222 -397.182533) (xy 316.685676 -397.15694)
			(xy 316.143682 -397.15694) (xy 316.455806 -397.696944) (xy 316.46861 -397.720287) (xy 316.486838 -397.770304)
			(xy 316.496107 -397.822727) (xy 316.4967 -397.849344) (xy 316.496279 -397.873324) (xy 316.488774 -397.920694)
			(xy 316.473956 -397.966307) (xy 316.452188 -398.009044) (xy 316.424007 -398.047851) (xy 316.390105 -398.081775)
			(xy 316.351316 -398.109982) (xy 316.308594 -398.131778) (xy 316.26299 -398.146627) (xy 316.215626 -398.154163)
			(xy 316.191646 -398.154652) (xy 316.191138 -398.154652) (xy 316.167566 -398.1542) (xy 316.120982 -398.146966)
			(xy 316.076066 -398.132648) (xy 316.033889 -398.111589) (xy 315.995456 -398.084289) (xy 315.961681 -398.051399)
			(xy 315.933371 -398.013703) (xy 315.921898 -397.993108) (xy 315.92139 -397.992346) (xy 315.523626 -397.304006)
			(xy 315.511747 -397.28133) (xy 315.494898 -397.232996) (xy 315.486326 -397.182533) (xy 315.48578 -397.15694)
			(xy 314.943532 -397.15694) (xy 315.255656 -397.696944) (xy 315.268375 -397.720269) (xy 315.286473 -397.770214)
			(xy 315.295695 -397.822529) (xy 315.296296 -397.84909) (xy 315.296296 -397.849344) (xy 315.295878 -397.873337)
			(xy 315.288365 -397.920731) (xy 315.273531 -397.966367) (xy 315.251741 -398.009121) (xy 315.223531 -398.047939)
			(xy 315.189597 -398.081868) (xy 315.150773 -398.11007) (xy 315.108015 -398.131852) (xy 315.062377 -398.146678)
			(xy 315.014981 -398.154182) (xy 314.990988 -398.154652) (xy 314.967415 -398.154241) (xy 314.920829 -398.146999)
			(xy 314.875912 -398.132674) (xy 314.833735 -398.111608) (xy 314.795302 -398.084301) (xy 314.761529 -398.051406)
			(xy 314.733221 -398.013705) (xy 314.721748 -397.993108) (xy 314.72124 -397.992346) (xy 314.323476 -397.304006)
			(xy 314.311559 -397.281339) (xy 314.294623 -397.233013) (xy 314.285963 -397.182542) (xy 314.285376 -397.15694)
			(xy 313.743636 -397.15694) (xy 314.05576 -397.696944) (xy 314.06848 -397.720269) (xy 314.086577 -397.770214)
			(xy 314.095799 -397.822529) (xy 314.0964 -397.84909) (xy 314.0964 -397.849344) (xy 314.095978 -397.873337)
			(xy 314.088465 -397.920731) (xy 314.073631 -397.966366) (xy 314.051841 -398.009119) (xy 314.023632 -398.047938)
			(xy 313.989698 -398.081866) (xy 313.950875 -398.110069) (xy 313.908118 -398.131851) (xy 313.86248 -398.146677)
			(xy 313.815085 -398.154182) (xy 313.791092 -398.154652) (xy 313.767519 -398.154237) (xy 313.720933 -398.146996)
			(xy 313.676016 -398.132672) (xy 313.633839 -398.111606) (xy 313.595406 -398.0843) (xy 313.561633 -398.051406)
			(xy 313.533325 -398.013705) (xy 313.521852 -397.993108) (xy 313.521344 -397.992346) (xy 313.12358 -397.304006)
			(xy 313.111663 -397.281339) (xy 313.094727 -397.233013) (xy 313.086067 -397.182542) (xy 313.08548 -397.15694)
			(xy 312.543486 -397.15694) (xy 312.85561 -397.696944) (xy 312.868414 -397.720287) (xy 312.886643 -397.770304)
			(xy 312.895911 -397.822727) (xy 312.896504 -397.849344) (xy 312.896079 -397.873324) (xy 312.888574 -397.920693)
			(xy 312.873756 -397.966307) (xy 312.851989 -398.009042) (xy 312.823808 -398.04785) (xy 312.789906 -398.081774)
			(xy 312.751118 -398.109981) (xy 312.708397 -398.131777) (xy 312.662794 -398.146626) (xy 312.61543 -398.154163)
			(xy 312.59145 -398.154652) (xy 312.590942 -398.154652) (xy 312.567371 -398.154197) (xy 312.520786 -398.146963)
			(xy 312.475871 -398.132646) (xy 312.433693 -398.111587) (xy 312.39526 -398.084288) (xy 312.361486 -398.051398)
			(xy 312.333176 -398.013703) (xy 312.321702 -397.993108) (xy 312.321194 -397.992346) (xy 311.92343 -397.304006)
			(xy 311.911552 -397.28133) (xy 311.894702 -397.232996) (xy 311.88613 -397.182533) (xy 311.885584 -397.15694)
			(xy 311.34359 -397.15694) (xy 311.655714 -397.696944) (xy 311.668518 -397.720287) (xy 311.686747 -397.770304)
			(xy 311.696015 -397.822727) (xy 311.696608 -397.849344) (xy 311.696179 -397.873324) (xy 311.688674 -397.920693)
			(xy 311.673856 -397.966306) (xy 311.652089 -398.009041) (xy 311.623909 -398.047848) (xy 311.590008 -398.081772)
			(xy 311.55122 -398.10998) (xy 311.5085 -398.131776) (xy 311.462897 -398.146625) (xy 311.415533 -398.154162)
			(xy 311.391554 -398.154652) (xy 311.391046 -398.154652) (xy 311.367475 -398.154194) (xy 311.320891 -398.146961)
			(xy 311.275975 -398.132644) (xy 311.233798 -398.111586) (xy 311.195364 -398.084287) (xy 311.16159 -398.051398)
			(xy 311.13328 -398.013703) (xy 311.121806 -397.993108) (xy 311.121298 -397.992346) (xy 310.723534 -397.304006)
			(xy 310.711656 -397.28133) (xy 310.694806 -397.232996) (xy 310.686234 -397.182533) (xy 310.685688 -397.15694)
			(xy 310.143694 -397.15694) (xy 310.455818 -397.696944) (xy 310.468623 -397.720287) (xy 310.486851 -397.770304)
			(xy 310.496119 -397.822727) (xy 310.496712 -397.849344) (xy 310.496279 -397.873324) (xy 310.488774 -397.920692)
			(xy 310.473957 -397.966305) (xy 310.45219 -398.00904) (xy 310.42401 -398.047847) (xy 310.39011 -398.081771)
			(xy 310.351323 -398.109978) (xy 310.308603 -398.131775) (xy 310.263 -398.146624) (xy 310.215637 -398.154162)
			(xy 310.191658 -398.154652) (xy 310.19115 -398.154652) (xy 310.167579 -398.154191) (xy 310.120995 -398.146958)
			(xy 310.076079 -398.132642) (xy 310.033902 -398.111584) (xy 309.995468 -398.084286) (xy 309.961694 -398.051397)
			(xy 309.933384 -398.013703) (xy 309.92191 -397.993108) (xy 309.921402 -397.992346) (xy 309.523638 -397.304006)
			(xy 309.51176 -397.28133) (xy 309.494911 -397.232996) (xy 309.486338 -397.182533) (xy 309.485792 -397.15694)
			(xy 308.943544 -397.15694) (xy 309.255668 -397.696944) (xy 309.268388 -397.720268) (xy 309.286486 -397.770213)
			(xy 309.295708 -397.822529) (xy 309.296308 -397.84909) (xy 309.296308 -397.849344) (xy 309.295878 -397.873336)
			(xy 309.288365 -397.92073) (xy 309.273532 -397.966364) (xy 309.251743 -398.009117) (xy 309.223535 -398.047935)
			(xy 309.189602 -398.081863) (xy 309.150779 -398.110066) (xy 309.108024 -398.131849) (xy 309.062387 -398.146676)
			(xy 309.014992 -398.154181) (xy 308.991 -398.154652) (xy 308.967427 -398.154231) (xy 308.920842 -398.146991)
			(xy 308.875925 -398.132668) (xy 308.833748 -398.111603) (xy 308.795315 -398.084298) (xy 308.761542 -398.051404)
			(xy 308.733233 -398.013705) (xy 308.72176 -397.993108) (xy 308.721252 -397.992346) (xy 308.323488 -397.304006)
			(xy 308.311572 -397.281338) (xy 308.294635 -397.233013) (xy 308.285975 -397.182542) (xy 308.285388 -397.15694)
			(xy 307.743648 -397.15694) (xy 308.055772 -397.696944) (xy 308.068493 -397.720268) (xy 308.08659 -397.770213)
			(xy 308.095812 -397.822529) (xy 308.096412 -397.84909) (xy 308.096412 -397.849344) (xy 308.095978 -397.873336)
			(xy 308.088465 -397.920729) (xy 308.073632 -397.966363) (xy 308.051844 -398.009116) (xy 308.023636 -398.047934)
			(xy 307.989703 -398.081862) (xy 307.950882 -398.110065) (xy 307.908126 -398.131848) (xy 307.86249 -398.146675)
			(xy 307.815096 -398.154181) (xy 307.791104 -398.154652) (xy 307.767532 -398.154228) (xy 307.720946 -398.146988)
			(xy 307.676029 -398.132666) (xy 307.633852 -398.111602) (xy 307.595419 -398.084297) (xy 307.561646 -398.051404)
			(xy 307.533337 -398.013705) (xy 307.521864 -397.993108) (xy 307.521356 -397.992346) (xy 307.123592 -397.304006)
			(xy 307.111676 -397.281338) (xy 307.094739 -397.233012) (xy 307.086079 -397.182542) (xy 307.085492 -397.15694)
			(xy 306.543498 -397.15694) (xy 306.855622 -397.696944) (xy 306.868427 -397.720287) (xy 306.886655 -397.770304)
			(xy 306.895923 -397.822727) (xy 306.896516 -397.849344) (xy 306.896079 -397.873323) (xy 306.888575 -397.920691)
			(xy 306.873757 -397.966304) (xy 306.851991 -398.009039) (xy 306.823811 -398.047846) (xy 306.789912 -398.08177)
			(xy 306.751125 -398.109977) (xy 306.708405 -398.131773) (xy 306.662804 -398.146624) (xy 306.615441 -398.154162)
			(xy 306.591462 -398.154652) (xy 306.590954 -398.154652) (xy 306.567383 -398.154187) (xy 306.520799 -398.146955)
			(xy 306.475884 -398.13264) (xy 306.433706 -398.111583) (xy 306.395273 -398.084285) (xy 306.361498 -398.051397)
			(xy 306.333188 -398.013702) (xy 306.321714 -397.993108) (xy 306.321206 -397.992346) (xy 305.923442 -397.304006)
			(xy 305.911565 -397.28133) (xy 305.894715 -397.232996) (xy 305.886142 -397.182533) (xy 305.885596 -397.15694)
			(xy 305.343602 -397.15694) (xy 305.655726 -397.696944) (xy 305.668531 -397.720286) (xy 305.686759 -397.770304)
			(xy 305.696027 -397.822727) (xy 305.69662 -397.849344) (xy 305.696179 -397.873323) (xy 305.688675 -397.920691)
			(xy 305.673857 -397.966303) (xy 305.652092 -398.009038) (xy 305.623913 -398.047844) (xy 305.590013 -398.081768)
			(xy 305.551227 -398.109975) (xy 305.508508 -398.131772) (xy 305.462907 -398.146623) (xy 305.415545 -398.154162)
			(xy 305.391566 -398.154652) (xy 305.391058 -398.154652) (xy 305.367487 -398.154184) (xy 305.320904 -398.146953)
			(xy 305.275988 -398.132638) (xy 305.233811 -398.111581) (xy 305.195377 -398.084284) (xy 305.161602 -398.051396)
			(xy 305.133292 -398.013702) (xy 305.121818 -397.993108) (xy 305.12131 -397.992346) (xy 304.723546 -397.304006)
			(xy 304.711669 -397.28133) (xy 304.694819 -397.232996) (xy 304.686246 -397.182533) (xy 304.6857 -397.15694)
			(xy 304.143706 -397.15694) (xy 304.45583 -397.696944) (xy 304.468636 -397.720286) (xy 304.486863 -397.770304)
			(xy 304.496131 -397.822727) (xy 304.496724 -397.849344) (xy 304.496279 -397.873323) (xy 304.488775 -397.92069)
			(xy 304.473958 -397.966302) (xy 304.452192 -398.009036) (xy 304.424014 -398.047843) (xy 304.390115 -398.081767)
			(xy 304.351329 -398.109974) (xy 304.308611 -398.131771) (xy 304.26301 -398.146622) (xy 304.215649 -398.154161)
			(xy 304.19167 -398.154652) (xy 304.191162 -398.154652) (xy 304.167591 -398.154181) (xy 304.121008 -398.14695)
			(xy 304.076092 -398.132636) (xy 304.033915 -398.11158) (xy 303.995481 -398.084283) (xy 303.961707 -398.051396)
			(xy 303.933396 -398.013702) (xy 303.921922 -397.993108) (xy 303.921414 -397.992346) (xy 303.52365 -397.304006)
			(xy 303.511773 -397.281329) (xy 303.494923 -397.232996) (xy 303.48635 -397.182533) (xy 303.485804 -397.15694)
			(xy 280.68524 -397.15694) (xy 280.68524 -401.674838) (xy 303.434496 -401.674838) (xy 303.434496 -400.811238)
			(xy 303.434982 -400.783969) (xy 303.442744 -400.729985) (xy 303.458109 -400.677655) (xy 303.480766 -400.628045)
			(xy 303.510252 -400.582164) (xy 303.545967 -400.540947) (xy 303.587184 -400.505232) (xy 303.633065 -400.475746)
			(xy 303.682675 -400.453089) (xy 303.735005 -400.437724) (xy 303.788989 -400.429962) (xy 303.843527 -400.429962)
			(xy 303.897511 -400.437724) (xy 303.949841 -400.453089) (xy 303.999451 -400.475746) (xy 304.045332 -400.505232)
			(xy 304.086549 -400.540947) (xy 304.122264 -400.582164) (xy 304.15175 -400.628045) (xy 304.174407 -400.677655)
			(xy 304.189772 -400.729985) (xy 304.197534 -400.783969) (xy 304.19802 -400.811238) (xy 304.19802 -401.674838)
			(xy 304.634392 -401.674838) (xy 304.634392 -400.811238) (xy 304.634878 -400.783969) (xy 304.64264 -400.729985)
			(xy 304.658005 -400.677655) (xy 304.680662 -400.628045) (xy 304.710148 -400.582164) (xy 304.745863 -400.540947)
			(xy 304.78708 -400.505232) (xy 304.832961 -400.475746) (xy 304.882571 -400.453089) (xy 304.934901 -400.437724)
			(xy 304.988885 -400.429962) (xy 305.043423 -400.429962) (xy 305.097407 -400.437724) (xy 305.149737 -400.453089)
			(xy 305.199347 -400.475746) (xy 305.245228 -400.505232) (xy 305.286445 -400.540947) (xy 305.32216 -400.582164)
			(xy 305.351646 -400.628045) (xy 305.374303 -400.677655) (xy 305.389668 -400.729985) (xy 305.39743 -400.783969)
			(xy 305.397916 -400.811238) (xy 305.397916 -401.674838) (xy 305.834796 -401.674838) (xy 305.834796 -400.811238)
			(xy 305.835282 -400.783987) (xy 305.843038 -400.730039) (xy 305.858393 -400.677744) (xy 305.881035 -400.628167)
			(xy 305.910501 -400.582317) (xy 305.946192 -400.541126) (xy 305.987383 -400.505435) (xy 306.033233 -400.475969)
			(xy 306.08281 -400.453327) (xy 306.135105 -400.437972) (xy 306.189053 -400.430216) (xy 306.243555 -400.430216)
			(xy 306.297503 -400.437972) (xy 306.349798 -400.453327) (xy 306.399375 -400.475969) (xy 306.445225 -400.505435)
			(xy 306.486416 -400.541126) (xy 306.522107 -400.582317) (xy 306.551573 -400.628167) (xy 306.574215 -400.677744)
			(xy 306.58957 -400.730039) (xy 306.597326 -400.783987) (xy 306.597812 -400.811238) (xy 306.597812 -401.674838)
			(xy 307.034692 -401.674838) (xy 307.034692 -400.811238) (xy 307.035178 -400.783987) (xy 307.042934 -400.730039)
			(xy 307.058289 -400.677744) (xy 307.080931 -400.628167) (xy 307.110397 -400.582317) (xy 307.146088 -400.541126)
			(xy 307.187279 -400.505435) (xy 307.233129 -400.475969) (xy 307.282706 -400.453327) (xy 307.335001 -400.437972)
			(xy 307.388949 -400.430216) (xy 307.443451 -400.430216) (xy 307.497399 -400.437972) (xy 307.549694 -400.453327)
			(xy 307.599271 -400.475969) (xy 307.645121 -400.505435) (xy 307.686312 -400.541126) (xy 307.722003 -400.582317)
			(xy 307.751469 -400.628167) (xy 307.774111 -400.677744) (xy 307.789466 -400.730039) (xy 307.797222 -400.783987)
			(xy 307.797708 -400.811238) (xy 307.797708 -401.674838) (xy 308.234588 -401.674838) (xy 308.234588 -400.811238)
			(xy 308.235074 -400.783969) (xy 308.242836 -400.729985) (xy 308.258201 -400.677655) (xy 308.280858 -400.628045)
			(xy 308.310344 -400.582164) (xy 308.346059 -400.540947) (xy 308.387276 -400.505232) (xy 308.433157 -400.475746)
			(xy 308.482767 -400.453089) (xy 308.535097 -400.437724) (xy 308.589081 -400.429962) (xy 308.643619 -400.429962)
			(xy 308.697603 -400.437724) (xy 308.749933 -400.453089) (xy 308.799543 -400.475746) (xy 308.845424 -400.505232)
			(xy 308.886641 -400.540947) (xy 308.922356 -400.582164) (xy 308.951842 -400.628045) (xy 308.974499 -400.677655)
			(xy 308.989864 -400.729985) (xy 308.997626 -400.783969) (xy 308.998112 -400.811238) (xy 308.998112 -401.674838)
			(xy 309.434484 -401.674838) (xy 309.434484 -400.811238) (xy 309.43497 -400.783969) (xy 309.442732 -400.729985)
			(xy 309.458097 -400.677655) (xy 309.480754 -400.628045) (xy 309.51024 -400.582164) (xy 309.545955 -400.540947)
			(xy 309.587172 -400.505232) (xy 309.633053 -400.475746) (xy 309.682663 -400.453089) (xy 309.734993 -400.437724)
			(xy 309.788977 -400.429962) (xy 309.843515 -400.429962) (xy 309.897499 -400.437724) (xy 309.949829 -400.453089)
			(xy 309.999439 -400.475746) (xy 310.04532 -400.505232) (xy 310.086537 -400.540947) (xy 310.122252 -400.582164)
			(xy 310.151738 -400.628045) (xy 310.174395 -400.677655) (xy 310.18976 -400.729985) (xy 310.197522 -400.783969)
			(xy 310.198008 -400.811238) (xy 310.198008 -401.674838) (xy 310.634888 -401.674838) (xy 310.634888 -400.811238)
			(xy 310.635374 -400.783987) (xy 310.64313 -400.730039) (xy 310.658485 -400.677744) (xy 310.681127 -400.628167)
			(xy 310.710593 -400.582317) (xy 310.746284 -400.541126) (xy 310.787475 -400.505435) (xy 310.833325 -400.475969)
			(xy 310.882902 -400.453327) (xy 310.935197 -400.437972) (xy 310.989145 -400.430216) (xy 311.043647 -400.430216)
			(xy 311.097595 -400.437972) (xy 311.14989 -400.453327) (xy 311.199467 -400.475969) (xy 311.245317 -400.505435)
			(xy 311.286508 -400.541126) (xy 311.322199 -400.582317) (xy 311.351665 -400.628167) (xy 311.374307 -400.677744)
			(xy 311.389662 -400.730039) (xy 311.397418 -400.783987) (xy 311.397904 -400.811238) (xy 311.397904 -401.674838)
			(xy 311.834784 -401.674838) (xy 311.834784 -400.811238) (xy 311.83527 -400.783987) (xy 311.843026 -400.730039)
			(xy 311.858381 -400.677744) (xy 311.881023 -400.628167) (xy 311.910489 -400.582317) (xy 311.94618 -400.541126)
			(xy 311.987371 -400.505435) (xy 312.033221 -400.475969) (xy 312.082798 -400.453327) (xy 312.135093 -400.437972)
			(xy 312.189041 -400.430216) (xy 312.243543 -400.430216) (xy 312.297491 -400.437972) (xy 312.349786 -400.453327)
			(xy 312.399363 -400.475969) (xy 312.445213 -400.505435) (xy 312.486404 -400.541126) (xy 312.522095 -400.582317)
			(xy 312.551561 -400.628167) (xy 312.574203 -400.677744) (xy 312.589558 -400.730039) (xy 312.597314 -400.783987)
			(xy 312.5978 -400.811238) (xy 312.5978 -401.674838) (xy 313.03468 -401.674838) (xy 313.03468 -400.811238)
			(xy 313.035166 -400.783969) (xy 313.042928 -400.729985) (xy 313.058293 -400.677655) (xy 313.08095 -400.628045)
			(xy 313.110436 -400.582164) (xy 313.146151 -400.540947) (xy 313.187368 -400.505232) (xy 313.233249 -400.475746)
			(xy 313.282859 -400.453089) (xy 313.335189 -400.437724) (xy 313.389173 -400.429962) (xy 313.443711 -400.429962)
			(xy 313.497695 -400.437724) (xy 313.550025 -400.453089) (xy 313.599635 -400.475746) (xy 313.645516 -400.505232)
			(xy 313.686733 -400.540947) (xy 313.722448 -400.582164) (xy 313.751934 -400.628045) (xy 313.774591 -400.677655)
			(xy 313.789956 -400.729985) (xy 313.797718 -400.783969) (xy 313.798204 -400.811238) (xy 313.798204 -401.674838)
			(xy 314.234576 -401.674838) (xy 314.234576 -400.811238) (xy 314.235062 -400.783969) (xy 314.242824 -400.729985)
			(xy 314.258189 -400.677655) (xy 314.280846 -400.628045) (xy 314.310332 -400.582164) (xy 314.346047 -400.540947)
			(xy 314.387264 -400.505232) (xy 314.433145 -400.475746) (xy 314.482755 -400.453089) (xy 314.535085 -400.437724)
			(xy 314.589069 -400.429962) (xy 314.643607 -400.429962) (xy 314.697591 -400.437724) (xy 314.749921 -400.453089)
			(xy 314.799531 -400.475746) (xy 314.845412 -400.505232) (xy 314.886629 -400.540947) (xy 314.922344 -400.582164)
			(xy 314.95183 -400.628045) (xy 314.974487 -400.677655) (xy 314.989852 -400.729985) (xy 314.997614 -400.783969)
			(xy 314.9981 -400.811238) (xy 314.9981 -401.674838) (xy 315.43498 -401.674838) (xy 315.43498 -400.811238)
			(xy 315.435466 -400.783987) (xy 315.443222 -400.730039) (xy 315.458577 -400.677744) (xy 315.481219 -400.628167)
			(xy 315.510685 -400.582317) (xy 315.546376 -400.541126) (xy 315.587567 -400.505435) (xy 315.633417 -400.475969)
			(xy 315.682994 -400.453327) (xy 315.735289 -400.437972) (xy 315.789237 -400.430216) (xy 315.843739 -400.430216)
			(xy 315.897687 -400.437972) (xy 315.949982 -400.453327) (xy 315.999559 -400.475969) (xy 316.045409 -400.505435)
			(xy 316.0866 -400.541126) (xy 316.122291 -400.582317) (xy 316.151757 -400.628167) (xy 316.174399 -400.677744)
			(xy 316.189754 -400.730039) (xy 316.19751 -400.783987) (xy 316.197996 -400.811238) (xy 316.197996 -401.674838)
			(xy 316.634876 -401.674838) (xy 316.634876 -400.811238) (xy 316.635362 -400.783987) (xy 316.643118 -400.730039)
			(xy 316.658473 -400.677744) (xy 316.681115 -400.628167) (xy 316.710581 -400.582317) (xy 316.746272 -400.541126)
			(xy 316.787463 -400.505435) (xy 316.833313 -400.475969) (xy 316.88289 -400.453327) (xy 316.935185 -400.437972)
			(xy 316.989133 -400.430216) (xy 317.043635 -400.430216) (xy 317.097583 -400.437972) (xy 317.149878 -400.453327)
			(xy 317.199455 -400.475969) (xy 317.245305 -400.505435) (xy 317.286496 -400.541126) (xy 317.322187 -400.582317)
			(xy 317.351653 -400.628167) (xy 317.374295 -400.677744) (xy 317.38965 -400.730039) (xy 317.397406 -400.783987)
			(xy 317.397892 -400.811238) (xy 317.397892 -401.674838) (xy 317.834772 -401.674838) (xy 317.834772 -400.811238)
			(xy 317.835258 -400.783987) (xy 317.843014 -400.730039) (xy 317.858369 -400.677744) (xy 317.881011 -400.628167)
			(xy 317.910477 -400.582317) (xy 317.946168 -400.541126) (xy 317.987359 -400.505435) (xy 318.033209 -400.475969)
			(xy 318.082786 -400.453327) (xy 318.135081 -400.437972) (xy 318.189029 -400.430216) (xy 318.243531 -400.430216)
			(xy 318.297479 -400.437972) (xy 318.349774 -400.453327) (xy 318.399351 -400.475969) (xy 318.445201 -400.505435)
			(xy 318.486392 -400.541126) (xy 318.522083 -400.582317) (xy 318.551549 -400.628167) (xy 318.574191 -400.677744)
			(xy 318.589546 -400.730039) (xy 318.597302 -400.783987) (xy 318.597788 -400.811238) (xy 318.597788 -401.674838)
			(xy 319.034668 -401.674838) (xy 319.034668 -400.811238) (xy 319.035154 -400.783987) (xy 319.04291 -400.730039)
			(xy 319.058265 -400.677744) (xy 319.080907 -400.628167) (xy 319.110373 -400.582317) (xy 319.146064 -400.541126)
			(xy 319.187255 -400.505435) (xy 319.233105 -400.475969) (xy 319.282682 -400.453327) (xy 319.334977 -400.437972)
			(xy 319.388925 -400.430216) (xy 319.443427 -400.430216) (xy 319.497375 -400.437972) (xy 319.54967 -400.453327)
			(xy 319.599247 -400.475969) (xy 319.645097 -400.505435) (xy 319.686288 -400.541126) (xy 319.721979 -400.582317)
			(xy 319.751445 -400.628167) (xy 319.774087 -400.677744) (xy 319.789442 -400.730039) (xy 319.797198 -400.783987)
			(xy 319.797684 -400.811238) (xy 319.797684 -401.674838) (xy 320.234564 -401.674838) (xy 320.234564 -400.811238)
			(xy 320.23505 -400.783969) (xy 320.242812 -400.729985) (xy 320.258177 -400.677655) (xy 320.280834 -400.628045)
			(xy 320.31032 -400.582164) (xy 320.346035 -400.540947) (xy 320.387252 -400.505232) (xy 320.433133 -400.475746)
			(xy 320.482743 -400.453089) (xy 320.535073 -400.437724) (xy 320.589057 -400.429962) (xy 320.643595 -400.429962)
			(xy 320.697579 -400.437724) (xy 320.749909 -400.453089) (xy 320.799519 -400.475746) (xy 320.8454 -400.505232)
			(xy 320.886617 -400.540947) (xy 320.922332 -400.582164) (xy 320.951818 -400.628045) (xy 320.974475 -400.677655)
			(xy 320.98984 -400.729985) (xy 320.997602 -400.783969) (xy 320.998088 -400.811238) (xy 320.998088 -401.674838)
			(xy 321.43446 -401.674838) (xy 321.43446 -400.811238) (xy 321.434946 -400.783969) (xy 321.442708 -400.729985)
			(xy 321.458073 -400.677655) (xy 321.48073 -400.628045) (xy 321.510216 -400.582164) (xy 321.545931 -400.540947)
			(xy 321.587148 -400.505232) (xy 321.633029 -400.475746) (xy 321.682639 -400.453089) (xy 321.734969 -400.437724)
			(xy 321.788953 -400.429962) (xy 321.843491 -400.429962) (xy 321.897475 -400.437724) (xy 321.949805 -400.453089)
			(xy 321.999415 -400.475746) (xy 322.045296 -400.505232) (xy 322.086513 -400.540947) (xy 322.122228 -400.582164)
			(xy 322.151714 -400.628045) (xy 322.174371 -400.677655) (xy 322.189736 -400.729985) (xy 322.197498 -400.783969)
			(xy 322.197984 -400.811238) (xy 322.197984 -401.674838) (xy 335.962244 -401.674838) (xy 335.962244 -400.811238)
			(xy 335.96273 -400.783969) (xy 335.970492 -400.729985) (xy 335.985857 -400.677655) (xy 336.008514 -400.628045)
			(xy 336.038 -400.582164) (xy 336.073715 -400.540947) (xy 336.114932 -400.505232) (xy 336.160813 -400.475746)
			(xy 336.210423 -400.453089) (xy 336.262753 -400.437724) (xy 336.316737 -400.429962) (xy 336.371275 -400.429962)
			(xy 336.425259 -400.437724) (xy 336.477589 -400.453089) (xy 336.527199 -400.475746) (xy 336.57308 -400.505232)
			(xy 336.614297 -400.540947) (xy 336.650012 -400.582164) (xy 336.679498 -400.628045) (xy 336.702155 -400.677655)
			(xy 336.71752 -400.729985) (xy 336.725282 -400.783969) (xy 336.725768 -400.811238) (xy 336.725768 -401.674838)
			(xy 337.16214 -401.674838) (xy 337.16214 -400.811238) (xy 337.162626 -400.783969) (xy 337.170388 -400.729985)
			(xy 337.185753 -400.677655) (xy 337.20841 -400.628045) (xy 337.237896 -400.582164) (xy 337.273611 -400.540947)
			(xy 337.314828 -400.505232) (xy 337.360709 -400.475746) (xy 337.410319 -400.453089) (xy 337.462649 -400.437724)
			(xy 337.516633 -400.429962) (xy 337.571171 -400.429962) (xy 337.625155 -400.437724) (xy 337.677485 -400.453089)
			(xy 337.727095 -400.475746) (xy 337.772976 -400.505232) (xy 337.814193 -400.540947) (xy 337.849908 -400.582164)
			(xy 337.879394 -400.628045) (xy 337.902051 -400.677655) (xy 337.917416 -400.729985) (xy 337.925178 -400.783969)
			(xy 337.925664 -400.811238) (xy 337.925664 -401.674838) (xy 338.362544 -401.674838) (xy 338.362544 -400.811238)
			(xy 338.36303 -400.783987) (xy 338.370786 -400.730039) (xy 338.386141 -400.677744) (xy 338.408783 -400.628167)
			(xy 338.438249 -400.582317) (xy 338.47394 -400.541126) (xy 338.515131 -400.505435) (xy 338.560981 -400.475969)
			(xy 338.610558 -400.453327) (xy 338.662853 -400.437972) (xy 338.716801 -400.430216) (xy 338.771303 -400.430216)
			(xy 338.825251 -400.437972) (xy 338.877546 -400.453327) (xy 338.927123 -400.475969) (xy 338.972973 -400.505435)
			(xy 339.014164 -400.541126) (xy 339.049855 -400.582317) (xy 339.079321 -400.628167) (xy 339.101963 -400.677744)
			(xy 339.117318 -400.730039) (xy 339.125074 -400.783987) (xy 339.12556 -400.811238) (xy 339.12556 -401.674838)
			(xy 339.56244 -401.674838) (xy 339.56244 -400.811238) (xy 339.562926 -400.783987) (xy 339.570682 -400.730039)
			(xy 339.586037 -400.677744) (xy 339.608679 -400.628167) (xy 339.638145 -400.582317) (xy 339.673836 -400.541126)
			(xy 339.715027 -400.505435) (xy 339.760877 -400.475969) (xy 339.810454 -400.453327) (xy 339.862749 -400.437972)
			(xy 339.916697 -400.430216) (xy 339.971199 -400.430216) (xy 340.025147 -400.437972) (xy 340.077442 -400.453327)
			(xy 340.127019 -400.475969) (xy 340.172869 -400.505435) (xy 340.21406 -400.541126) (xy 340.249751 -400.582317)
			(xy 340.279217 -400.628167) (xy 340.301859 -400.677744) (xy 340.317214 -400.730039) (xy 340.32497 -400.783987)
			(xy 340.325456 -400.811238) (xy 340.325456 -401.674838) (xy 340.762336 -401.674838) (xy 340.762336 -400.811238)
			(xy 340.762822 -400.783969) (xy 340.770584 -400.729985) (xy 340.785949 -400.677655) (xy 340.808606 -400.628045)
			(xy 340.838092 -400.582164) (xy 340.873807 -400.540947) (xy 340.915024 -400.505232) (xy 340.960905 -400.475746)
			(xy 341.010515 -400.453089) (xy 341.062845 -400.437724) (xy 341.116829 -400.429962) (xy 341.171367 -400.429962)
			(xy 341.225351 -400.437724) (xy 341.277681 -400.453089) (xy 341.327291 -400.475746) (xy 341.373172 -400.505232)
			(xy 341.414389 -400.540947) (xy 341.450104 -400.582164) (xy 341.47959 -400.628045) (xy 341.502247 -400.677655)
			(xy 341.517612 -400.729985) (xy 341.525374 -400.783969) (xy 341.52586 -400.811238) (xy 341.52586 -401.674838)
			(xy 341.962232 -401.674838) (xy 341.962232 -400.811238) (xy 341.962718 -400.783969) (xy 341.97048 -400.729985)
			(xy 341.985845 -400.677655) (xy 342.008502 -400.628045) (xy 342.037988 -400.582164) (xy 342.073703 -400.540947)
			(xy 342.11492 -400.505232) (xy 342.160801 -400.475746) (xy 342.210411 -400.453089) (xy 342.262741 -400.437724)
			(xy 342.316725 -400.429962) (xy 342.371263 -400.429962) (xy 342.425247 -400.437724) (xy 342.477577 -400.453089)
			(xy 342.527187 -400.475746) (xy 342.573068 -400.505232) (xy 342.614285 -400.540947) (xy 342.65 -400.582164)
			(xy 342.679486 -400.628045) (xy 342.702143 -400.677655) (xy 342.717508 -400.729985) (xy 342.72527 -400.783969)
			(xy 342.725756 -400.811238) (xy 342.725756 -401.674838) (xy 343.162636 -401.674838) (xy 343.162636 -400.811238)
			(xy 343.163122 -400.783987) (xy 343.170878 -400.730039) (xy 343.186233 -400.677744) (xy 343.208875 -400.628167)
			(xy 343.238341 -400.582317) (xy 343.274032 -400.541126) (xy 343.315223 -400.505435) (xy 343.361073 -400.475969)
			(xy 343.41065 -400.453327) (xy 343.462945 -400.437972) (xy 343.516893 -400.430216) (xy 343.571395 -400.430216)
			(xy 343.625343 -400.437972) (xy 343.677638 -400.453327) (xy 343.727215 -400.475969) (xy 343.773065 -400.505435)
			(xy 343.814256 -400.541126) (xy 343.849947 -400.582317) (xy 343.879413 -400.628167) (xy 343.902055 -400.677744)
			(xy 343.91741 -400.730039) (xy 343.925166 -400.783987) (xy 343.925652 -400.811238) (xy 343.925652 -401.674838)
			(xy 344.362532 -401.674838) (xy 344.362532 -400.811238) (xy 344.363018 -400.783987) (xy 344.370774 -400.730039)
			(xy 344.386129 -400.677744) (xy 344.408771 -400.628167) (xy 344.438237 -400.582317) (xy 344.473928 -400.541126)
			(xy 344.515119 -400.505435) (xy 344.560969 -400.475969) (xy 344.610546 -400.453327) (xy 344.662841 -400.437972)
			(xy 344.716789 -400.430216) (xy 344.771291 -400.430216) (xy 344.825239 -400.437972) (xy 344.877534 -400.453327)
			(xy 344.927111 -400.475969) (xy 344.972961 -400.505435) (xy 345.014152 -400.541126) (xy 345.049843 -400.582317)
			(xy 345.079309 -400.628167) (xy 345.101951 -400.677744) (xy 345.117306 -400.730039) (xy 345.125062 -400.783987)
			(xy 345.125548 -400.811238) (xy 345.125548 -401.674838) (xy 345.562428 -401.674838) (xy 345.562428 -400.811238)
			(xy 345.562914 -400.783969) (xy 345.570676 -400.729985) (xy 345.586041 -400.677655) (xy 345.608698 -400.628045)
			(xy 345.638184 -400.582164) (xy 345.673899 -400.540947) (xy 345.715116 -400.505232) (xy 345.760997 -400.475746)
			(xy 345.810607 -400.453089) (xy 345.862937 -400.437724) (xy 345.916921 -400.429962) (xy 345.971459 -400.429962)
			(xy 346.025443 -400.437724) (xy 346.077773 -400.453089) (xy 346.127383 -400.475746) (xy 346.173264 -400.505232)
			(xy 346.214481 -400.540947) (xy 346.250196 -400.582164) (xy 346.279682 -400.628045) (xy 346.302339 -400.677655)
			(xy 346.317704 -400.729985) (xy 346.325466 -400.783969) (xy 346.325952 -400.811238) (xy 346.325952 -401.674838)
			(xy 346.762324 -401.674838) (xy 346.762324 -400.811238) (xy 346.76281 -400.783969) (xy 346.770572 -400.729985)
			(xy 346.785937 -400.677655) (xy 346.808594 -400.628045) (xy 346.83808 -400.582164) (xy 346.873795 -400.540947)
			(xy 346.915012 -400.505232) (xy 346.960893 -400.475746) (xy 347.010503 -400.453089) (xy 347.062833 -400.437724)
			(xy 347.116817 -400.429962) (xy 347.171355 -400.429962) (xy 347.225339 -400.437724) (xy 347.277669 -400.453089)
			(xy 347.327279 -400.475746) (xy 347.37316 -400.505232) (xy 347.414377 -400.540947) (xy 347.450092 -400.582164)
			(xy 347.479578 -400.628045) (xy 347.502235 -400.677655) (xy 347.5176 -400.729985) (xy 347.525362 -400.783969)
			(xy 347.525848 -400.811238) (xy 347.525848 -401.674838) (xy 347.962728 -401.674838) (xy 347.962728 -400.811238)
			(xy 347.963214 -400.783987) (xy 347.97097 -400.730039) (xy 347.986325 -400.677744) (xy 348.008967 -400.628167)
			(xy 348.038433 -400.582317) (xy 348.074124 -400.541126) (xy 348.115315 -400.505435) (xy 348.161165 -400.475969)
			(xy 348.210742 -400.453327) (xy 348.263037 -400.437972) (xy 348.316985 -400.430216) (xy 348.371487 -400.430216)
			(xy 348.425435 -400.437972) (xy 348.47773 -400.453327) (xy 348.527307 -400.475969) (xy 348.573157 -400.505435)
			(xy 348.614348 -400.541126) (xy 348.650039 -400.582317) (xy 348.679505 -400.628167) (xy 348.702147 -400.677744)
			(xy 348.717502 -400.730039) (xy 348.725258 -400.783987) (xy 348.725744 -400.811238) (xy 348.725744 -401.674838)
			(xy 349.162624 -401.674838) (xy 349.162624 -400.811238) (xy 349.16311 -400.783987) (xy 349.170866 -400.730039)
			(xy 349.186221 -400.677744) (xy 349.208863 -400.628167) (xy 349.238329 -400.582317) (xy 349.27402 -400.541126)
			(xy 349.315211 -400.505435) (xy 349.361061 -400.475969) (xy 349.410638 -400.453327) (xy 349.462933 -400.437972)
			(xy 349.516881 -400.430216) (xy 349.571383 -400.430216) (xy 349.625331 -400.437972) (xy 349.677626 -400.453327)
			(xy 349.727203 -400.475969) (xy 349.773053 -400.505435) (xy 349.814244 -400.541126) (xy 349.849935 -400.582317)
			(xy 349.879401 -400.628167) (xy 349.902043 -400.677744) (xy 349.917398 -400.730039) (xy 349.925154 -400.783987)
			(xy 349.92564 -400.811238) (xy 349.92564 -401.674838) (xy 350.36252 -401.674838) (xy 350.36252 -400.811238)
			(xy 350.363006 -400.783987) (xy 350.370762 -400.730039) (xy 350.386117 -400.677744) (xy 350.408759 -400.628167)
			(xy 350.438225 -400.582317) (xy 350.473916 -400.541126) (xy 350.515107 -400.505435) (xy 350.560957 -400.475969)
			(xy 350.610534 -400.453327) (xy 350.662829 -400.437972) (xy 350.716777 -400.430216) (xy 350.771279 -400.430216)
			(xy 350.825227 -400.437972) (xy 350.877522 -400.453327) (xy 350.927099 -400.475969) (xy 350.972949 -400.505435)
			(xy 351.01414 -400.541126) (xy 351.049831 -400.582317) (xy 351.079297 -400.628167) (xy 351.101939 -400.677744)
			(xy 351.117294 -400.730039) (xy 351.12505 -400.783987) (xy 351.125536 -400.811238) (xy 351.125536 -401.674838)
			(xy 351.562416 -401.674838) (xy 351.562416 -400.811238) (xy 351.562902 -400.783987) (xy 351.570658 -400.730039)
			(xy 351.586013 -400.677744) (xy 351.608655 -400.628167) (xy 351.638121 -400.582317) (xy 351.673812 -400.541126)
			(xy 351.715003 -400.505435) (xy 351.760853 -400.475969) (xy 351.81043 -400.453327) (xy 351.862725 -400.437972)
			(xy 351.916673 -400.430216) (xy 351.971175 -400.430216) (xy 352.025123 -400.437972) (xy 352.077418 -400.453327)
			(xy 352.126995 -400.475969) (xy 352.172845 -400.505435) (xy 352.214036 -400.541126) (xy 352.249727 -400.582317)
			(xy 352.279193 -400.628167) (xy 352.301835 -400.677744) (xy 352.31719 -400.730039) (xy 352.324946 -400.783987)
			(xy 352.325432 -400.811238) (xy 352.325432 -401.674838) (xy 352.762312 -401.674838) (xy 352.762312 -400.811238)
			(xy 352.762798 -400.783969) (xy 352.77056 -400.729985) (xy 352.785925 -400.677655) (xy 352.808582 -400.628045)
			(xy 352.838068 -400.582164) (xy 352.873783 -400.540947) (xy 352.915 -400.505232) (xy 352.960881 -400.475746)
			(xy 353.010491 -400.453089) (xy 353.062821 -400.437724) (xy 353.116805 -400.429962) (xy 353.171343 -400.429962)
			(xy 353.225327 -400.437724) (xy 353.277657 -400.453089) (xy 353.327267 -400.475746) (xy 353.373148 -400.505232)
			(xy 353.414365 -400.540947) (xy 353.45008 -400.582164) (xy 353.479566 -400.628045) (xy 353.502223 -400.677655)
			(xy 353.517588 -400.729985) (xy 353.52535 -400.783969) (xy 353.525836 -400.811238) (xy 353.525836 -401.674838)
			(xy 353.962208 -401.674838) (xy 353.962208 -400.811238) (xy 353.962694 -400.783969) (xy 353.970456 -400.729985)
			(xy 353.985821 -400.677655) (xy 354.008478 -400.628045) (xy 354.037964 -400.582164) (xy 354.073679 -400.540947)
			(xy 354.114896 -400.505232) (xy 354.160777 -400.475746) (xy 354.210387 -400.453089) (xy 354.262717 -400.437724)
			(xy 354.316701 -400.429962) (xy 354.371239 -400.429962) (xy 354.425223 -400.437724) (xy 354.477553 -400.453089)
			(xy 354.527163 -400.475746) (xy 354.573044 -400.505232) (xy 354.614261 -400.540947) (xy 354.649976 -400.582164)
			(xy 354.679462 -400.628045) (xy 354.702119 -400.677655) (xy 354.717484 -400.729985) (xy 354.725246 -400.783969)
			(xy 354.725732 -400.811238) (xy 354.725732 -401.674838) (xy 370.534692 -401.674838) (xy 370.534692 -400.811238)
			(xy 370.535178 -400.783969) (xy 370.54294 -400.729985) (xy 370.558305 -400.677655) (xy 370.580962 -400.628045)
			(xy 370.610448 -400.582164) (xy 370.646163 -400.540947) (xy 370.68738 -400.505232) (xy 370.733261 -400.475746)
			(xy 370.782871 -400.453089) (xy 370.835201 -400.437724) (xy 370.889185 -400.429962) (xy 370.943723 -400.429962)
			(xy 370.997707 -400.437724) (xy 371.050037 -400.453089) (xy 371.099647 -400.475746) (xy 371.145528 -400.505232)
			(xy 371.186745 -400.540947) (xy 371.22246 -400.582164) (xy 371.251946 -400.628045) (xy 371.274603 -400.677655)
			(xy 371.289968 -400.729985) (xy 371.29773 -400.783969) (xy 371.298216 -400.811238) (xy 371.298216 -401.674838)
			(xy 371.734588 -401.674838) (xy 371.734588 -400.811238) (xy 371.735074 -400.783969) (xy 371.742836 -400.729985)
			(xy 371.758201 -400.677655) (xy 371.780858 -400.628045) (xy 371.810344 -400.582164) (xy 371.846059 -400.540947)
			(xy 371.887276 -400.505232) (xy 371.933157 -400.475746) (xy 371.982767 -400.453089) (xy 372.035097 -400.437724)
			(xy 372.089081 -400.429962) (xy 372.143619 -400.429962) (xy 372.197603 -400.437724) (xy 372.249933 -400.453089)
			(xy 372.299543 -400.475746) (xy 372.345424 -400.505232) (xy 372.386641 -400.540947) (xy 372.422356 -400.582164)
			(xy 372.451842 -400.628045) (xy 372.474499 -400.677655) (xy 372.489864 -400.729985) (xy 372.497626 -400.783969)
			(xy 372.498112 -400.811238) (xy 372.498112 -401.674838) (xy 372.934992 -401.674838) (xy 372.934992 -400.811238)
			(xy 372.935478 -400.783987) (xy 372.943234 -400.730039) (xy 372.958589 -400.677744) (xy 372.981231 -400.628167)
			(xy 373.010697 -400.582317) (xy 373.046388 -400.541126) (xy 373.087579 -400.505435) (xy 373.133429 -400.475969)
			(xy 373.183006 -400.453327) (xy 373.235301 -400.437972) (xy 373.289249 -400.430216) (xy 373.343751 -400.430216)
			(xy 373.397699 -400.437972) (xy 373.449994 -400.453327) (xy 373.499571 -400.475969) (xy 373.545421 -400.505435)
			(xy 373.586612 -400.541126) (xy 373.622303 -400.582317) (xy 373.651769 -400.628167) (xy 373.674411 -400.677744)
			(xy 373.689766 -400.730039) (xy 373.697522 -400.783987) (xy 373.698008 -400.811238) (xy 373.698008 -401.674838)
			(xy 374.134888 -401.674838) (xy 374.134888 -400.811238) (xy 374.135374 -400.783987) (xy 374.14313 -400.730039)
			(xy 374.158485 -400.677744) (xy 374.181127 -400.628167) (xy 374.210593 -400.582317) (xy 374.246284 -400.541126)
			(xy 374.287475 -400.505435) (xy 374.333325 -400.475969) (xy 374.382902 -400.453327) (xy 374.435197 -400.437972)
			(xy 374.489145 -400.430216) (xy 374.543647 -400.430216) (xy 374.597595 -400.437972) (xy 374.64989 -400.453327)
			(xy 374.699467 -400.475969) (xy 374.745317 -400.505435) (xy 374.786508 -400.541126) (xy 374.822199 -400.582317)
			(xy 374.851665 -400.628167) (xy 374.874307 -400.677744) (xy 374.889662 -400.730039) (xy 374.897418 -400.783987)
			(xy 374.897904 -400.811238) (xy 374.897904 -401.674838) (xy 375.334784 -401.674838) (xy 375.334784 -400.811238)
			(xy 375.33527 -400.783969) (xy 375.343032 -400.729985) (xy 375.358397 -400.677655) (xy 375.381054 -400.628045)
			(xy 375.41054 -400.582164) (xy 375.446255 -400.540947) (xy 375.487472 -400.505232) (xy 375.533353 -400.475746)
			(xy 375.582963 -400.453089) (xy 375.635293 -400.437724) (xy 375.689277 -400.429962) (xy 375.743815 -400.429962)
			(xy 375.797799 -400.437724) (xy 375.850129 -400.453089) (xy 375.899739 -400.475746) (xy 375.94562 -400.505232)
			(xy 375.986837 -400.540947) (xy 376.022552 -400.582164) (xy 376.052038 -400.628045) (xy 376.074695 -400.677655)
			(xy 376.09006 -400.729985) (xy 376.097822 -400.783969) (xy 376.098308 -400.811238) (xy 376.098308 -401.674838)
			(xy 376.53468 -401.674838) (xy 376.53468 -400.811238) (xy 376.535166 -400.783969) (xy 376.542928 -400.729985)
			(xy 376.558293 -400.677655) (xy 376.58095 -400.628045) (xy 376.610436 -400.582164) (xy 376.646151 -400.540947)
			(xy 376.687368 -400.505232) (xy 376.733249 -400.475746) (xy 376.782859 -400.453089) (xy 376.835189 -400.437724)
			(xy 376.889173 -400.429962) (xy 376.943711 -400.429962) (xy 376.997695 -400.437724) (xy 377.050025 -400.453089)
			(xy 377.099635 -400.475746) (xy 377.145516 -400.505232) (xy 377.186733 -400.540947) (xy 377.222448 -400.582164)
			(xy 377.251934 -400.628045) (xy 377.274591 -400.677655) (xy 377.289956 -400.729985) (xy 377.297718 -400.783969)
			(xy 377.298204 -400.811238) (xy 377.298204 -401.674838) (xy 377.735084 -401.674838) (xy 377.735084 -400.811238)
			(xy 377.73557 -400.783987) (xy 377.743326 -400.730039) (xy 377.758681 -400.677744) (xy 377.781323 -400.628167)
			(xy 377.810789 -400.582317) (xy 377.84648 -400.541126) (xy 377.887671 -400.505435) (xy 377.933521 -400.475969)
			(xy 377.983098 -400.453327) (xy 378.035393 -400.437972) (xy 378.089341 -400.430216) (xy 378.143843 -400.430216)
			(xy 378.197791 -400.437972) (xy 378.250086 -400.453327) (xy 378.299663 -400.475969) (xy 378.345513 -400.505435)
			(xy 378.386704 -400.541126) (xy 378.422395 -400.582317) (xy 378.451861 -400.628167) (xy 378.474503 -400.677744)
			(xy 378.489858 -400.730039) (xy 378.497614 -400.783987) (xy 378.4981 -400.811238) (xy 378.4981 -401.674838)
			(xy 378.93498 -401.674838) (xy 378.93498 -400.811238) (xy 378.935466 -400.783987) (xy 378.943222 -400.730039)
			(xy 378.958577 -400.677744) (xy 378.981219 -400.628167) (xy 379.010685 -400.582317) (xy 379.046376 -400.541126)
			(xy 379.087567 -400.505435) (xy 379.133417 -400.475969) (xy 379.182994 -400.453327) (xy 379.235289 -400.437972)
			(xy 379.289237 -400.430216) (xy 379.343739 -400.430216) (xy 379.397687 -400.437972) (xy 379.449982 -400.453327)
			(xy 379.499559 -400.475969) (xy 379.545409 -400.505435) (xy 379.5866 -400.541126) (xy 379.622291 -400.582317)
			(xy 379.651757 -400.628167) (xy 379.674399 -400.677744) (xy 379.689754 -400.730039) (xy 379.69751 -400.783987)
			(xy 379.697996 -400.811238) (xy 379.697996 -401.674838) (xy 380.134876 -401.674838) (xy 380.134876 -400.811238)
			(xy 380.135362 -400.783969) (xy 380.143124 -400.729985) (xy 380.158489 -400.677655) (xy 380.181146 -400.628045)
			(xy 380.210632 -400.582164) (xy 380.246347 -400.540947) (xy 380.287564 -400.505232) (xy 380.333445 -400.475746)
			(xy 380.383055 -400.453089) (xy 380.435385 -400.437724) (xy 380.489369 -400.429962) (xy 380.543907 -400.429962)
			(xy 380.597891 -400.437724) (xy 380.650221 -400.453089) (xy 380.699831 -400.475746) (xy 380.745712 -400.505232)
			(xy 380.786929 -400.540947) (xy 380.822644 -400.582164) (xy 380.85213 -400.628045) (xy 380.874787 -400.677655)
			(xy 380.890152 -400.729985) (xy 380.897914 -400.783969) (xy 380.8984 -400.811238) (xy 380.8984 -401.674838)
			(xy 381.334772 -401.674838) (xy 381.334772 -400.811238) (xy 381.335258 -400.783969) (xy 381.34302 -400.729985)
			(xy 381.358385 -400.677655) (xy 381.381042 -400.628045) (xy 381.410528 -400.582164) (xy 381.446243 -400.540947)
			(xy 381.48746 -400.505232) (xy 381.533341 -400.475746) (xy 381.582951 -400.453089) (xy 381.635281 -400.437724)
			(xy 381.689265 -400.429962) (xy 381.743803 -400.429962) (xy 381.797787 -400.437724) (xy 381.850117 -400.453089)
			(xy 381.899727 -400.475746) (xy 381.945608 -400.505232) (xy 381.986825 -400.540947) (xy 382.02254 -400.582164)
			(xy 382.052026 -400.628045) (xy 382.074683 -400.677655) (xy 382.090048 -400.729985) (xy 382.09781 -400.783969)
			(xy 382.098296 -400.811238) (xy 382.098296 -401.674838) (xy 382.535176 -401.674838) (xy 382.535176 -400.811238)
			(xy 382.535662 -400.783987) (xy 382.543418 -400.730039) (xy 382.558773 -400.677744) (xy 382.581415 -400.628167)
			(xy 382.610881 -400.582317) (xy 382.646572 -400.541126) (xy 382.687763 -400.505435) (xy 382.733613 -400.475969)
			(xy 382.78319 -400.453327) (xy 382.835485 -400.437972) (xy 382.889433 -400.430216) (xy 382.943935 -400.430216)
			(xy 382.997883 -400.437972) (xy 383.050178 -400.453327) (xy 383.099755 -400.475969) (xy 383.145605 -400.505435)
			(xy 383.186796 -400.541126) (xy 383.222487 -400.582317) (xy 383.251953 -400.628167) (xy 383.274595 -400.677744)
			(xy 383.28995 -400.730039) (xy 383.297706 -400.783987) (xy 383.298192 -400.811238) (xy 383.298192 -401.674838)
			(xy 383.735072 -401.674838) (xy 383.735072 -400.811238) (xy 383.735558 -400.783987) (xy 383.743314 -400.730039)
			(xy 383.758669 -400.677744) (xy 383.781311 -400.628167) (xy 383.810777 -400.582317) (xy 383.846468 -400.541126)
			(xy 383.887659 -400.505435) (xy 383.933509 -400.475969) (xy 383.983086 -400.453327) (xy 384.035381 -400.437972)
			(xy 384.089329 -400.430216) (xy 384.143831 -400.430216) (xy 384.197779 -400.437972) (xy 384.250074 -400.453327)
			(xy 384.299651 -400.475969) (xy 384.345501 -400.505435) (xy 384.386692 -400.541126) (xy 384.422383 -400.582317)
			(xy 384.451849 -400.628167) (xy 384.474491 -400.677744) (xy 384.489846 -400.730039) (xy 384.497602 -400.783987)
			(xy 384.498088 -400.811238) (xy 384.498088 -401.674838) (xy 384.934968 -401.674838) (xy 384.934968 -400.811238)
			(xy 384.935454 -400.783987) (xy 384.94321 -400.730039) (xy 384.958565 -400.677744) (xy 384.981207 -400.628167)
			(xy 385.010673 -400.582317) (xy 385.046364 -400.541126) (xy 385.087555 -400.505435) (xy 385.133405 -400.475969)
			(xy 385.182982 -400.453327) (xy 385.235277 -400.437972) (xy 385.289225 -400.430216) (xy 385.343727 -400.430216)
			(xy 385.397675 -400.437972) (xy 385.44997 -400.453327) (xy 385.499547 -400.475969) (xy 385.545397 -400.505435)
			(xy 385.586588 -400.541126) (xy 385.622279 -400.582317) (xy 385.651745 -400.628167) (xy 385.674387 -400.677744)
			(xy 385.689742 -400.730039) (xy 385.697498 -400.783987) (xy 385.697984 -400.811238) (xy 385.697984 -401.674838)
			(xy 386.134864 -401.674838) (xy 386.134864 -400.811238) (xy 386.13535 -400.783987) (xy 386.143106 -400.730039)
			(xy 386.158461 -400.677744) (xy 386.181103 -400.628167) (xy 386.210569 -400.582317) (xy 386.24626 -400.541126)
			(xy 386.287451 -400.505435) (xy 386.333301 -400.475969) (xy 386.382878 -400.453327) (xy 386.435173 -400.437972)
			(xy 386.489121 -400.430216) (xy 386.543623 -400.430216) (xy 386.597571 -400.437972) (xy 386.649866 -400.453327)
			(xy 386.699443 -400.475969) (xy 386.745293 -400.505435) (xy 386.786484 -400.541126) (xy 386.822175 -400.582317)
			(xy 386.851641 -400.628167) (xy 386.874283 -400.677744) (xy 386.889638 -400.730039) (xy 386.897394 -400.783987)
			(xy 386.89788 -400.811238) (xy 386.89788 -401.674838) (xy 387.33476 -401.674838) (xy 387.33476 -400.811238)
			(xy 387.335246 -400.783969) (xy 387.343008 -400.729985) (xy 387.358373 -400.677655) (xy 387.38103 -400.628045)
			(xy 387.410516 -400.582164) (xy 387.446231 -400.540947) (xy 387.487448 -400.505232) (xy 387.533329 -400.475746)
			(xy 387.582939 -400.453089) (xy 387.635269 -400.437724) (xy 387.689253 -400.429962) (xy 387.743791 -400.429962)
			(xy 387.797775 -400.437724) (xy 387.850105 -400.453089) (xy 387.899715 -400.475746) (xy 387.945596 -400.505232)
			(xy 387.986813 -400.540947) (xy 388.022528 -400.582164) (xy 388.052014 -400.628045) (xy 388.074671 -400.677655)
			(xy 388.090036 -400.729985) (xy 388.097798 -400.783969) (xy 388.098284 -400.811238) (xy 388.098284 -401.674838)
			(xy 388.534656 -401.674838) (xy 388.534656 -400.811238) (xy 388.535142 -400.783969) (xy 388.542904 -400.729985)
			(xy 388.558269 -400.677655) (xy 388.580926 -400.628045) (xy 388.610412 -400.582164) (xy 388.646127 -400.540947)
			(xy 388.687344 -400.505232) (xy 388.733225 -400.475746) (xy 388.782835 -400.453089) (xy 388.835165 -400.437724)
			(xy 388.889149 -400.429962) (xy 388.943687 -400.429962) (xy 388.997671 -400.437724) (xy 389.050001 -400.453089)
			(xy 389.099611 -400.475746) (xy 389.145492 -400.505232) (xy 389.186709 -400.540947) (xy 389.222424 -400.582164)
			(xy 389.25191 -400.628045) (xy 389.274567 -400.677655) (xy 389.289932 -400.729985) (xy 389.297694 -400.783969)
			(xy 389.29818 -400.811238) (xy 389.29818 -401.674838) (xy 403.06244 -401.674838) (xy 403.06244 -400.811238)
			(xy 403.062926 -400.783969) (xy 403.070688 -400.729985) (xy 403.086053 -400.677655) (xy 403.10871 -400.628045)
			(xy 403.138196 -400.582164) (xy 403.173911 -400.540947) (xy 403.215128 -400.505232) (xy 403.261009 -400.475746)
			(xy 403.310619 -400.453089) (xy 403.362949 -400.437724) (xy 403.416933 -400.429962) (xy 403.471471 -400.429962)
			(xy 403.525455 -400.437724) (xy 403.577785 -400.453089) (xy 403.627395 -400.475746) (xy 403.673276 -400.505232)
			(xy 403.714493 -400.540947) (xy 403.750208 -400.582164) (xy 403.779694 -400.628045) (xy 403.802351 -400.677655)
			(xy 403.817716 -400.729985) (xy 403.825478 -400.783969) (xy 403.825964 -400.811238) (xy 403.825964 -401.674838)
			(xy 404.262336 -401.674838) (xy 404.262336 -400.811238) (xy 404.262822 -400.783969) (xy 404.270584 -400.729985)
			(xy 404.285949 -400.677655) (xy 404.308606 -400.628045) (xy 404.338092 -400.582164) (xy 404.373807 -400.540947)
			(xy 404.415024 -400.505232) (xy 404.460905 -400.475746) (xy 404.510515 -400.453089) (xy 404.562845 -400.437724)
			(xy 404.616829 -400.429962) (xy 404.671367 -400.429962) (xy 404.725351 -400.437724) (xy 404.777681 -400.453089)
			(xy 404.827291 -400.475746) (xy 404.873172 -400.505232) (xy 404.914389 -400.540947) (xy 404.950104 -400.582164)
			(xy 404.97959 -400.628045) (xy 405.002247 -400.677655) (xy 405.017612 -400.729985) (xy 405.025374 -400.783969)
			(xy 405.02586 -400.811238) (xy 405.02586 -401.674838) (xy 405.46274 -401.674838) (xy 405.46274 -400.811238)
			(xy 405.463226 -400.783987) (xy 405.470982 -400.730039) (xy 405.486337 -400.677744) (xy 405.508979 -400.628167)
			(xy 405.538445 -400.582317) (xy 405.574136 -400.541126) (xy 405.615327 -400.505435) (xy 405.661177 -400.475969)
			(xy 405.710754 -400.453327) (xy 405.763049 -400.437972) (xy 405.816997 -400.430216) (xy 405.871499 -400.430216)
			(xy 405.925447 -400.437972) (xy 405.977742 -400.453327) (xy 406.027319 -400.475969) (xy 406.073169 -400.505435)
			(xy 406.11436 -400.541126) (xy 406.150051 -400.582317) (xy 406.179517 -400.628167) (xy 406.202159 -400.677744)
			(xy 406.217514 -400.730039) (xy 406.22527 -400.783987) (xy 406.225756 -400.811238) (xy 406.225756 -401.674838)
			(xy 406.662636 -401.674838) (xy 406.662636 -400.811238) (xy 406.663122 -400.783987) (xy 406.670878 -400.730039)
			(xy 406.686233 -400.677744) (xy 406.708875 -400.628167) (xy 406.738341 -400.582317) (xy 406.774032 -400.541126)
			(xy 406.815223 -400.505435) (xy 406.861073 -400.475969) (xy 406.91065 -400.453327) (xy 406.962945 -400.437972)
			(xy 407.016893 -400.430216) (xy 407.071395 -400.430216) (xy 407.125343 -400.437972) (xy 407.177638 -400.453327)
			(xy 407.227215 -400.475969) (xy 407.273065 -400.505435) (xy 407.314256 -400.541126) (xy 407.349947 -400.582317)
			(xy 407.379413 -400.628167) (xy 407.402055 -400.677744) (xy 407.41741 -400.730039) (xy 407.425166 -400.783987)
			(xy 407.425652 -400.811238) (xy 407.425652 -401.674838) (xy 407.862532 -401.674838) (xy 407.862532 -400.811238)
			(xy 407.863018 -400.783969) (xy 407.87078 -400.729985) (xy 407.886145 -400.677655) (xy 407.908802 -400.628045)
			(xy 407.938288 -400.582164) (xy 407.974003 -400.540947) (xy 408.01522 -400.505232) (xy 408.061101 -400.475746)
			(xy 408.110711 -400.453089) (xy 408.163041 -400.437724) (xy 408.217025 -400.429962) (xy 408.271563 -400.429962)
			(xy 408.325547 -400.437724) (xy 408.377877 -400.453089) (xy 408.427487 -400.475746) (xy 408.473368 -400.505232)
			(xy 408.514585 -400.540947) (xy 408.5503 -400.582164) (xy 408.579786 -400.628045) (xy 408.602443 -400.677655)
			(xy 408.617808 -400.729985) (xy 408.62557 -400.783969) (xy 408.626056 -400.811238) (xy 408.626056 -401.674838)
			(xy 409.062428 -401.674838) (xy 409.062428 -400.811238) (xy 409.062914 -400.783969) (xy 409.070676 -400.729985)
			(xy 409.086041 -400.677655) (xy 409.108698 -400.628045) (xy 409.138184 -400.582164) (xy 409.173899 -400.540947)
			(xy 409.215116 -400.505232) (xy 409.260997 -400.475746) (xy 409.310607 -400.453089) (xy 409.362937 -400.437724)
			(xy 409.416921 -400.429962) (xy 409.471459 -400.429962) (xy 409.525443 -400.437724) (xy 409.577773 -400.453089)
			(xy 409.627383 -400.475746) (xy 409.673264 -400.505232) (xy 409.714481 -400.540947) (xy 409.750196 -400.582164)
			(xy 409.779682 -400.628045) (xy 409.802339 -400.677655) (xy 409.817704 -400.729985) (xy 409.825466 -400.783969)
			(xy 409.825952 -400.811238) (xy 409.825952 -401.674838) (xy 410.262832 -401.674838) (xy 410.262832 -400.811238)
			(xy 410.263318 -400.783987) (xy 410.271074 -400.730039) (xy 410.286429 -400.677744) (xy 410.309071 -400.628167)
			(xy 410.338537 -400.582317) (xy 410.374228 -400.541126) (xy 410.415419 -400.505435) (xy 410.461269 -400.475969)
			(xy 410.510846 -400.453327) (xy 410.563141 -400.437972) (xy 410.617089 -400.430216) (xy 410.671591 -400.430216)
			(xy 410.725539 -400.437972) (xy 410.777834 -400.453327) (xy 410.827411 -400.475969) (xy 410.873261 -400.505435)
			(xy 410.914452 -400.541126) (xy 410.950143 -400.582317) (xy 410.979609 -400.628167) (xy 411.002251 -400.677744)
			(xy 411.017606 -400.730039) (xy 411.025362 -400.783987) (xy 411.025848 -400.811238) (xy 411.025848 -401.674838)
			(xy 411.462728 -401.674838) (xy 411.462728 -400.811238) (xy 411.463214 -400.783987) (xy 411.47097 -400.730039)
			(xy 411.486325 -400.677744) (xy 411.508967 -400.628167) (xy 411.538433 -400.582317) (xy 411.574124 -400.541126)
			(xy 411.615315 -400.505435) (xy 411.661165 -400.475969) (xy 411.710742 -400.453327) (xy 411.763037 -400.437972)
			(xy 411.816985 -400.430216) (xy 411.871487 -400.430216) (xy 411.925435 -400.437972) (xy 411.97773 -400.453327)
			(xy 412.027307 -400.475969) (xy 412.073157 -400.505435) (xy 412.114348 -400.541126) (xy 412.150039 -400.582317)
			(xy 412.179505 -400.628167) (xy 412.202147 -400.677744) (xy 412.217502 -400.730039) (xy 412.225258 -400.783987)
			(xy 412.225744 -400.811238) (xy 412.225744 -401.674838) (xy 412.662624 -401.674838) (xy 412.662624 -400.811238)
			(xy 412.66311 -400.783969) (xy 412.670872 -400.729985) (xy 412.686237 -400.677655) (xy 412.708894 -400.628045)
			(xy 412.73838 -400.582164) (xy 412.774095 -400.540947) (xy 412.815312 -400.505232) (xy 412.861193 -400.475746)
			(xy 412.910803 -400.453089) (xy 412.963133 -400.437724) (xy 413.017117 -400.429962) (xy 413.071655 -400.429962)
			(xy 413.125639 -400.437724) (xy 413.177969 -400.453089) (xy 413.227579 -400.475746) (xy 413.27346 -400.505232)
			(xy 413.314677 -400.540947) (xy 413.350392 -400.582164) (xy 413.379878 -400.628045) (xy 413.402535 -400.677655)
			(xy 413.4179 -400.729985) (xy 413.425662 -400.783969) (xy 413.426148 -400.811238) (xy 413.426148 -401.674838)
			(xy 413.86252 -401.674838) (xy 413.86252 -400.811238) (xy 413.863006 -400.783969) (xy 413.870768 -400.729985)
			(xy 413.886133 -400.677655) (xy 413.90879 -400.628045) (xy 413.938276 -400.582164) (xy 413.973991 -400.540947)
			(xy 414.015208 -400.505232) (xy 414.061089 -400.475746) (xy 414.110699 -400.453089) (xy 414.163029 -400.437724)
			(xy 414.217013 -400.429962) (xy 414.271551 -400.429962) (xy 414.325535 -400.437724) (xy 414.377865 -400.453089)
			(xy 414.427475 -400.475746) (xy 414.473356 -400.505232) (xy 414.514573 -400.540947) (xy 414.550288 -400.582164)
			(xy 414.579774 -400.628045) (xy 414.602431 -400.677655) (xy 414.617796 -400.729985) (xy 414.625558 -400.783969)
			(xy 414.626044 -400.811238) (xy 414.626044 -401.674838) (xy 415.062924 -401.674838) (xy 415.062924 -400.811238)
			(xy 415.06341 -400.783987) (xy 415.071166 -400.730039) (xy 415.086521 -400.677744) (xy 415.109163 -400.628167)
			(xy 415.138629 -400.582317) (xy 415.17432 -400.541126) (xy 415.215511 -400.505435) (xy 415.261361 -400.475969)
			(xy 415.310938 -400.453327) (xy 415.363233 -400.437972) (xy 415.417181 -400.430216) (xy 415.471683 -400.430216)
			(xy 415.525631 -400.437972) (xy 415.577926 -400.453327) (xy 415.627503 -400.475969) (xy 415.673353 -400.505435)
			(xy 415.714544 -400.541126) (xy 415.750235 -400.582317) (xy 415.779701 -400.628167) (xy 415.802343 -400.677744)
			(xy 415.817698 -400.730039) (xy 415.825454 -400.783987) (xy 415.82594 -400.811238) (xy 415.82594 -401.674838)
			(xy 416.26282 -401.674838) (xy 416.26282 -400.811238) (xy 416.263306 -400.783987) (xy 416.271062 -400.730039)
			(xy 416.286417 -400.677744) (xy 416.309059 -400.628167) (xy 416.338525 -400.582317) (xy 416.374216 -400.541126)
			(xy 416.415407 -400.505435) (xy 416.461257 -400.475969) (xy 416.510834 -400.453327) (xy 416.563129 -400.437972)
			(xy 416.617077 -400.430216) (xy 416.671579 -400.430216) (xy 416.725527 -400.437972) (xy 416.777822 -400.453327)
			(xy 416.827399 -400.475969) (xy 416.873249 -400.505435) (xy 416.91444 -400.541126) (xy 416.950131 -400.582317)
			(xy 416.979597 -400.628167) (xy 417.002239 -400.677744) (xy 417.017594 -400.730039) (xy 417.02535 -400.783987)
			(xy 417.025836 -400.811238) (xy 417.025836 -401.674838) (xy 417.462716 -401.674838) (xy 417.462716 -400.811238)
			(xy 417.463202 -400.783987) (xy 417.470958 -400.730039) (xy 417.486313 -400.677744) (xy 417.508955 -400.628167)
			(xy 417.538421 -400.582317) (xy 417.574112 -400.541126) (xy 417.615303 -400.505435) (xy 417.661153 -400.475969)
			(xy 417.71073 -400.453327) (xy 417.763025 -400.437972) (xy 417.816973 -400.430216) (xy 417.871475 -400.430216)
			(xy 417.925423 -400.437972) (xy 417.977718 -400.453327) (xy 418.027295 -400.475969) (xy 418.073145 -400.505435)
			(xy 418.114336 -400.541126) (xy 418.150027 -400.582317) (xy 418.179493 -400.628167) (xy 418.202135 -400.677744)
			(xy 418.21749 -400.730039) (xy 418.225246 -400.783987) (xy 418.225732 -400.811238) (xy 418.225732 -401.674838)
			(xy 418.662612 -401.674838) (xy 418.662612 -400.811238) (xy 418.663098 -400.783987) (xy 418.670854 -400.730039)
			(xy 418.686209 -400.677744) (xy 418.708851 -400.628167) (xy 418.738317 -400.582317) (xy 418.774008 -400.541126)
			(xy 418.815199 -400.505435) (xy 418.861049 -400.475969) (xy 418.910626 -400.453327) (xy 418.962921 -400.437972)
			(xy 419.016869 -400.430216) (xy 419.071371 -400.430216) (xy 419.125319 -400.437972) (xy 419.177614 -400.453327)
			(xy 419.227191 -400.475969) (xy 419.273041 -400.505435) (xy 419.314232 -400.541126) (xy 419.349923 -400.582317)
			(xy 419.379389 -400.628167) (xy 419.402031 -400.677744) (xy 419.417386 -400.730039) (xy 419.425142 -400.783987)
			(xy 419.425628 -400.811238) (xy 419.425628 -401.674838) (xy 419.862508 -401.674838) (xy 419.862508 -400.811238)
			(xy 419.862994 -400.783969) (xy 419.870756 -400.729985) (xy 419.886121 -400.677655) (xy 419.908778 -400.628045)
			(xy 419.938264 -400.582164) (xy 419.973979 -400.540947) (xy 420.015196 -400.505232) (xy 420.061077 -400.475746)
			(xy 420.110687 -400.453089) (xy 420.163017 -400.437724) (xy 420.217001 -400.429962) (xy 420.271539 -400.429962)
			(xy 420.325523 -400.437724) (xy 420.377853 -400.453089) (xy 420.427463 -400.475746) (xy 420.473344 -400.505232)
			(xy 420.514561 -400.540947) (xy 420.550276 -400.582164) (xy 420.579762 -400.628045) (xy 420.602419 -400.677655)
			(xy 420.617784 -400.729985) (xy 420.625546 -400.783969) (xy 420.626032 -400.811238) (xy 420.626032 -401.674838)
			(xy 421.062404 -401.674838) (xy 421.062404 -400.811238) (xy 421.06289 -400.783969) (xy 421.070652 -400.729985)
			(xy 421.086017 -400.677655) (xy 421.108674 -400.628045) (xy 421.13816 -400.582164) (xy 421.173875 -400.540947)
			(xy 421.215092 -400.505232) (xy 421.260973 -400.475746) (xy 421.310583 -400.453089) (xy 421.362913 -400.437724)
			(xy 421.416897 -400.429962) (xy 421.471435 -400.429962) (xy 421.525419 -400.437724) (xy 421.577749 -400.453089)
			(xy 421.627359 -400.475746) (xy 421.67324 -400.505232) (xy 421.714457 -400.540947) (xy 421.750172 -400.582164)
			(xy 421.779658 -400.628045) (xy 421.802315 -400.677655) (xy 421.81768 -400.729985) (xy 421.825442 -400.783969)
			(xy 421.825928 -400.811238) (xy 421.825928 -401.674838) (xy 421.825442 -401.702107) (xy 421.81768 -401.756091)
			(xy 421.802315 -401.808421) (xy 421.779658 -401.858031) (xy 421.750172 -401.903912) (xy 421.714457 -401.945129)
			(xy 421.67324 -401.980844) (xy 421.627359 -402.01033) (xy 421.577749 -402.032987) (xy 421.525419 -402.048352)
			(xy 421.471435 -402.056114) (xy 421.416897 -402.056114) (xy 421.362913 -402.048352) (xy 421.310583 -402.032987)
			(xy 421.260973 -402.01033) (xy 421.215092 -401.980844) (xy 421.173875 -401.945129) (xy 421.13816 -401.903912)
			(xy 421.108674 -401.858031) (xy 421.086017 -401.808421) (xy 421.070652 -401.756091) (xy 421.06289 -401.702107)
			(xy 421.062404 -401.674838) (xy 420.626032 -401.674838) (xy 420.625546 -401.702107) (xy 420.617784 -401.756091)
			(xy 420.602419 -401.808421) (xy 420.579762 -401.858031) (xy 420.550276 -401.903912) (xy 420.514561 -401.945129)
			(xy 420.473344 -401.980844) (xy 420.427463 -402.01033) (xy 420.377853 -402.032987) (xy 420.325523 -402.048352)
			(xy 420.271539 -402.056114) (xy 420.217001 -402.056114) (xy 420.163017 -402.048352) (xy 420.110687 -402.032987)
			(xy 420.061077 -402.01033) (xy 420.015196 -401.980844) (xy 419.973979 -401.945129) (xy 419.938264 -401.903912)
			(xy 419.908778 -401.858031) (xy 419.886121 -401.808421) (xy 419.870756 -401.756091) (xy 419.862994 -401.702107)
			(xy 419.862508 -401.674838) (xy 419.425628 -401.674838) (xy 419.425142 -401.702089) (xy 419.417386 -401.756037)
			(xy 419.402031 -401.808332) (xy 419.379389 -401.857909) (xy 419.349923 -401.903759) (xy 419.314232 -401.94495)
			(xy 419.273041 -401.980641) (xy 419.227191 -402.010107) (xy 419.177614 -402.032749) (xy 419.125319 -402.048104)
			(xy 419.071371 -402.05586) (xy 419.016869 -402.05586) (xy 418.962921 -402.048104) (xy 418.910626 -402.032749)
			(xy 418.861049 -402.010107) (xy 418.815199 -401.980641) (xy 418.774008 -401.94495) (xy 418.738317 -401.903759)
			(xy 418.708851 -401.857909) (xy 418.686209 -401.808332) (xy 418.670854 -401.756037) (xy 418.663098 -401.702089)
			(xy 418.662612 -401.674838) (xy 418.225732 -401.674838) (xy 418.225246 -401.702089) (xy 418.21749 -401.756037)
			(xy 418.202135 -401.808332) (xy 418.179493 -401.857909) (xy 418.150027 -401.903759) (xy 418.114336 -401.94495)
			(xy 418.073145 -401.980641) (xy 418.027295 -402.010107) (xy 417.977718 -402.032749) (xy 417.925423 -402.048104)
			(xy 417.871475 -402.05586) (xy 417.816973 -402.05586) (xy 417.763025 -402.048104) (xy 417.71073 -402.032749)
			(xy 417.661153 -402.010107) (xy 417.615303 -401.980641) (xy 417.574112 -401.94495) (xy 417.538421 -401.903759)
			(xy 417.508955 -401.857909) (xy 417.486313 -401.808332) (xy 417.470958 -401.756037) (xy 417.463202 -401.702089)
			(xy 417.462716 -401.674838) (xy 417.025836 -401.674838) (xy 417.02535 -401.702089) (xy 417.017594 -401.756037)
			(xy 417.002239 -401.808332) (xy 416.979597 -401.857909) (xy 416.950131 -401.903759) (xy 416.91444 -401.94495)
			(xy 416.873249 -401.980641) (xy 416.827399 -402.010107) (xy 416.777822 -402.032749) (xy 416.725527 -402.048104)
			(xy 416.671579 -402.05586) (xy 416.617077 -402.05586) (xy 416.563129 -402.048104) (xy 416.510834 -402.032749)
			(xy 416.461257 -402.010107) (xy 416.415407 -401.980641) (xy 416.374216 -401.94495) (xy 416.338525 -401.903759)
			(xy 416.309059 -401.857909) (xy 416.286417 -401.808332) (xy 416.271062 -401.756037) (xy 416.263306 -401.702089)
			(xy 416.26282 -401.674838) (xy 415.82594 -401.674838) (xy 415.825454 -401.702089) (xy 415.817698 -401.756037)
			(xy 415.802343 -401.808332) (xy 415.779701 -401.857909) (xy 415.750235 -401.903759) (xy 415.714544 -401.94495)
			(xy 415.673353 -401.980641) (xy 415.627503 -402.010107) (xy 415.577926 -402.032749) (xy 415.525631 -402.048104)
			(xy 415.471683 -402.05586) (xy 415.417181 -402.05586) (xy 415.363233 -402.048104) (xy 415.310938 -402.032749)
			(xy 415.261361 -402.010107) (xy 415.215511 -401.980641) (xy 415.17432 -401.94495) (xy 415.138629 -401.903759)
			(xy 415.109163 -401.857909) (xy 415.086521 -401.808332) (xy 415.071166 -401.756037) (xy 415.06341 -401.702089)
			(xy 415.062924 -401.674838) (xy 414.626044 -401.674838) (xy 414.625558 -401.702107) (xy 414.617796 -401.756091)
			(xy 414.602431 -401.808421) (xy 414.579774 -401.858031) (xy 414.550288 -401.903912) (xy 414.514573 -401.945129)
			(xy 414.473356 -401.980844) (xy 414.427475 -402.01033) (xy 414.377865 -402.032987) (xy 414.325535 -402.048352)
			(xy 414.271551 -402.056114) (xy 414.217013 -402.056114) (xy 414.163029 -402.048352) (xy 414.110699 -402.032987)
			(xy 414.061089 -402.01033) (xy 414.015208 -401.980844) (xy 413.973991 -401.945129) (xy 413.938276 -401.903912)
			(xy 413.90879 -401.858031) (xy 413.886133 -401.808421) (xy 413.870768 -401.756091) (xy 413.863006 -401.702107)
			(xy 413.86252 -401.674838) (xy 413.426148 -401.674838) (xy 413.425662 -401.702107) (xy 413.4179 -401.756091)
			(xy 413.402535 -401.808421) (xy 413.379878 -401.858031) (xy 413.350392 -401.903912) (xy 413.314677 -401.945129)
			(xy 413.27346 -401.980844) (xy 413.227579 -402.01033) (xy 413.177969 -402.032987) (xy 413.125639 -402.048352)
			(xy 413.071655 -402.056114) (xy 413.017117 -402.056114) (xy 412.963133 -402.048352) (xy 412.910803 -402.032987)
			(xy 412.861193 -402.01033) (xy 412.815312 -401.980844) (xy 412.774095 -401.945129) (xy 412.73838 -401.903912)
			(xy 412.708894 -401.858031) (xy 412.686237 -401.808421) (xy 412.670872 -401.756091) (xy 412.66311 -401.702107)
			(xy 412.662624 -401.674838) (xy 412.225744 -401.674838) (xy 412.225258 -401.702089) (xy 412.217502 -401.756037)
			(xy 412.202147 -401.808332) (xy 412.179505 -401.857909) (xy 412.150039 -401.903759) (xy 412.114348 -401.94495)
			(xy 412.073157 -401.980641) (xy 412.027307 -402.010107) (xy 411.97773 -402.032749) (xy 411.925435 -402.048104)
			(xy 411.871487 -402.05586) (xy 411.816985 -402.05586) (xy 411.763037 -402.048104) (xy 411.710742 -402.032749)
			(xy 411.661165 -402.010107) (xy 411.615315 -401.980641) (xy 411.574124 -401.94495) (xy 411.538433 -401.903759)
			(xy 411.508967 -401.857909) (xy 411.486325 -401.808332) (xy 411.47097 -401.756037) (xy 411.463214 -401.702089)
			(xy 411.462728 -401.674838) (xy 411.025848 -401.674838) (xy 411.025362 -401.702089) (xy 411.017606 -401.756037)
			(xy 411.002251 -401.808332) (xy 410.979609 -401.857909) (xy 410.950143 -401.903759) (xy 410.914452 -401.94495)
			(xy 410.873261 -401.980641) (xy 410.827411 -402.010107) (xy 410.777834 -402.032749) (xy 410.725539 -402.048104)
			(xy 410.671591 -402.05586) (xy 410.617089 -402.05586) (xy 410.563141 -402.048104) (xy 410.510846 -402.032749)
			(xy 410.461269 -402.010107) (xy 410.415419 -401.980641) (xy 410.374228 -401.94495) (xy 410.338537 -401.903759)
			(xy 410.309071 -401.857909) (xy 410.286429 -401.808332) (xy 410.271074 -401.756037) (xy 410.263318 -401.702089)
			(xy 410.262832 -401.674838) (xy 409.825952 -401.674838) (xy 409.825466 -401.702107) (xy 409.817704 -401.756091)
			(xy 409.802339 -401.808421) (xy 409.779682 -401.858031) (xy 409.750196 -401.903912) (xy 409.714481 -401.945129)
			(xy 409.673264 -401.980844) (xy 409.627383 -402.01033) (xy 409.577773 -402.032987) (xy 409.525443 -402.048352)
			(xy 409.471459 -402.056114) (xy 409.416921 -402.056114) (xy 409.362937 -402.048352) (xy 409.310607 -402.032987)
			(xy 409.260997 -402.01033) (xy 409.215116 -401.980844) (xy 409.173899 -401.945129) (xy 409.138184 -401.903912)
			(xy 409.108698 -401.858031) (xy 409.086041 -401.808421) (xy 409.070676 -401.756091) (xy 409.062914 -401.702107)
			(xy 409.062428 -401.674838) (xy 408.626056 -401.674838) (xy 408.62557 -401.702107) (xy 408.617808 -401.756091)
			(xy 408.602443 -401.808421) (xy 408.579786 -401.858031) (xy 408.5503 -401.903912) (xy 408.514585 -401.945129)
			(xy 408.473368 -401.980844) (xy 408.427487 -402.01033) (xy 408.377877 -402.032987) (xy 408.325547 -402.048352)
			(xy 408.271563 -402.056114) (xy 408.217025 -402.056114) (xy 408.163041 -402.048352) (xy 408.110711 -402.032987)
			(xy 408.061101 -402.01033) (xy 408.01522 -401.980844) (xy 407.974003 -401.945129) (xy 407.938288 -401.903912)
			(xy 407.908802 -401.858031) (xy 407.886145 -401.808421) (xy 407.87078 -401.756091) (xy 407.863018 -401.702107)
			(xy 407.862532 -401.674838) (xy 407.425652 -401.674838) (xy 407.425166 -401.702089) (xy 407.41741 -401.756037)
			(xy 407.402055 -401.808332) (xy 407.379413 -401.857909) (xy 407.349947 -401.903759) (xy 407.314256 -401.94495)
			(xy 407.273065 -401.980641) (xy 407.227215 -402.010107) (xy 407.177638 -402.032749) (xy 407.125343 -402.048104)
			(xy 407.071395 -402.05586) (xy 407.016893 -402.05586) (xy 406.962945 -402.048104) (xy 406.91065 -402.032749)
			(xy 406.861073 -402.010107) (xy 406.815223 -401.980641) (xy 406.774032 -401.94495) (xy 406.738341 -401.903759)
			(xy 406.708875 -401.857909) (xy 406.686233 -401.808332) (xy 406.670878 -401.756037) (xy 406.663122 -401.702089)
			(xy 406.662636 -401.674838) (xy 406.225756 -401.674838) (xy 406.22527 -401.702089) (xy 406.217514 -401.756037)
			(xy 406.202159 -401.808332) (xy 406.179517 -401.857909) (xy 406.150051 -401.903759) (xy 406.11436 -401.94495)
			(xy 406.073169 -401.980641) (xy 406.027319 -402.010107) (xy 405.977742 -402.032749) (xy 405.925447 -402.048104)
			(xy 405.871499 -402.05586) (xy 405.816997 -402.05586) (xy 405.763049 -402.048104) (xy 405.710754 -402.032749)
			(xy 405.661177 -402.010107) (xy 405.615327 -401.980641) (xy 405.574136 -401.94495) (xy 405.538445 -401.903759)
			(xy 405.508979 -401.857909) (xy 405.486337 -401.808332) (xy 405.470982 -401.756037) (xy 405.463226 -401.702089)
			(xy 405.46274 -401.674838) (xy 405.02586 -401.674838) (xy 405.025374 -401.702107) (xy 405.017612 -401.756091)
			(xy 405.002247 -401.808421) (xy 404.97959 -401.858031) (xy 404.950104 -401.903912) (xy 404.914389 -401.945129)
			(xy 404.873172 -401.980844) (xy 404.827291 -402.01033) (xy 404.777681 -402.032987) (xy 404.725351 -402.048352)
			(xy 404.671367 -402.056114) (xy 404.616829 -402.056114) (xy 404.562845 -402.048352) (xy 404.510515 -402.032987)
			(xy 404.460905 -402.01033) (xy 404.415024 -401.980844) (xy 404.373807 -401.945129) (xy 404.338092 -401.903912)
			(xy 404.308606 -401.858031) (xy 404.285949 -401.808421) (xy 404.270584 -401.756091) (xy 404.262822 -401.702107)
			(xy 404.262336 -401.674838) (xy 403.825964 -401.674838) (xy 403.825478 -401.702107) (xy 403.817716 -401.756091)
			(xy 403.802351 -401.808421) (xy 403.779694 -401.858031) (xy 403.750208 -401.903912) (xy 403.714493 -401.945129)
			(xy 403.673276 -401.980844) (xy 403.627395 -402.01033) (xy 403.577785 -402.032987) (xy 403.525455 -402.048352)
			(xy 403.471471 -402.056114) (xy 403.416933 -402.056114) (xy 403.362949 -402.048352) (xy 403.310619 -402.032987)
			(xy 403.261009 -402.01033) (xy 403.215128 -401.980844) (xy 403.173911 -401.945129) (xy 403.138196 -401.903912)
			(xy 403.10871 -401.858031) (xy 403.086053 -401.808421) (xy 403.070688 -401.756091) (xy 403.062926 -401.702107)
			(xy 403.06244 -401.674838) (xy 389.29818 -401.674838) (xy 389.297694 -401.702107) (xy 389.289932 -401.756091)
			(xy 389.274567 -401.808421) (xy 389.25191 -401.858031) (xy 389.222424 -401.903912) (xy 389.186709 -401.945129)
			(xy 389.145492 -401.980844) (xy 389.099611 -402.01033) (xy 389.050001 -402.032987) (xy 388.997671 -402.048352)
			(xy 388.943687 -402.056114) (xy 388.889149 -402.056114) (xy 388.835165 -402.048352) (xy 388.782835 -402.032987)
			(xy 388.733225 -402.01033) (xy 388.687344 -401.980844) (xy 388.646127 -401.945129) (xy 388.610412 -401.903912)
			(xy 388.580926 -401.858031) (xy 388.558269 -401.808421) (xy 388.542904 -401.756091) (xy 388.535142 -401.702107)
			(xy 388.534656 -401.674838) (xy 388.098284 -401.674838) (xy 388.097798 -401.702107) (xy 388.090036 -401.756091)
			(xy 388.074671 -401.808421) (xy 388.052014 -401.858031) (xy 388.022528 -401.903912) (xy 387.986813 -401.945129)
			(xy 387.945596 -401.980844) (xy 387.899715 -402.01033) (xy 387.850105 -402.032987) (xy 387.797775 -402.048352)
			(xy 387.743791 -402.056114) (xy 387.689253 -402.056114) (xy 387.635269 -402.048352) (xy 387.582939 -402.032987)
			(xy 387.533329 -402.01033) (xy 387.487448 -401.980844) (xy 387.446231 -401.945129) (xy 387.410516 -401.903912)
			(xy 387.38103 -401.858031) (xy 387.358373 -401.808421) (xy 387.343008 -401.756091) (xy 387.335246 -401.702107)
			(xy 387.33476 -401.674838) (xy 386.89788 -401.674838) (xy 386.897394 -401.702089) (xy 386.889638 -401.756037)
			(xy 386.874283 -401.808332) (xy 386.851641 -401.857909) (xy 386.822175 -401.903759) (xy 386.786484 -401.94495)
			(xy 386.745293 -401.980641) (xy 386.699443 -402.010107) (xy 386.649866 -402.032749) (xy 386.597571 -402.048104)
			(xy 386.543623 -402.05586) (xy 386.489121 -402.05586) (xy 386.435173 -402.048104) (xy 386.382878 -402.032749)
			(xy 386.333301 -402.010107) (xy 386.287451 -401.980641) (xy 386.24626 -401.94495) (xy 386.210569 -401.903759)
			(xy 386.181103 -401.857909) (xy 386.158461 -401.808332) (xy 386.143106 -401.756037) (xy 386.13535 -401.702089)
			(xy 386.134864 -401.674838) (xy 385.697984 -401.674838) (xy 385.697498 -401.702089) (xy 385.689742 -401.756037)
			(xy 385.674387 -401.808332) (xy 385.651745 -401.857909) (xy 385.622279 -401.903759) (xy 385.586588 -401.94495)
			(xy 385.545397 -401.980641) (xy 385.499547 -402.010107) (xy 385.44997 -402.032749) (xy 385.397675 -402.048104)
			(xy 385.343727 -402.05586) (xy 385.289225 -402.05586) (xy 385.235277 -402.048104) (xy 385.182982 -402.032749)
			(xy 385.133405 -402.010107) (xy 385.087555 -401.980641) (xy 385.046364 -401.94495) (xy 385.010673 -401.903759)
			(xy 384.981207 -401.857909) (xy 384.958565 -401.808332) (xy 384.94321 -401.756037) (xy 384.935454 -401.702089)
			(xy 384.934968 -401.674838) (xy 384.498088 -401.674838) (xy 384.497602 -401.702089) (xy 384.489846 -401.756037)
			(xy 384.474491 -401.808332) (xy 384.451849 -401.857909) (xy 384.422383 -401.903759) (xy 384.386692 -401.94495)
			(xy 384.345501 -401.980641) (xy 384.299651 -402.010107) (xy 384.250074 -402.032749) (xy 384.197779 -402.048104)
			(xy 384.143831 -402.05586) (xy 384.089329 -402.05586) (xy 384.035381 -402.048104) (xy 383.983086 -402.032749)
			(xy 383.933509 -402.010107) (xy 383.887659 -401.980641) (xy 383.846468 -401.94495) (xy 383.810777 -401.903759)
			(xy 383.781311 -401.857909) (xy 383.758669 -401.808332) (xy 383.743314 -401.756037) (xy 383.735558 -401.702089)
			(xy 383.735072 -401.674838) (xy 383.298192 -401.674838) (xy 383.297706 -401.702089) (xy 383.28995 -401.756037)
			(xy 383.274595 -401.808332) (xy 383.251953 -401.857909) (xy 383.222487 -401.903759) (xy 383.186796 -401.94495)
			(xy 383.145605 -401.980641) (xy 383.099755 -402.010107) (xy 383.050178 -402.032749) (xy 382.997883 -402.048104)
			(xy 382.943935 -402.05586) (xy 382.889433 -402.05586) (xy 382.835485 -402.048104) (xy 382.78319 -402.032749)
			(xy 382.733613 -402.010107) (xy 382.687763 -401.980641) (xy 382.646572 -401.94495) (xy 382.610881 -401.903759)
			(xy 382.581415 -401.857909) (xy 382.558773 -401.808332) (xy 382.543418 -401.756037) (xy 382.535662 -401.702089)
			(xy 382.535176 -401.674838) (xy 382.098296 -401.674838) (xy 382.09781 -401.702107) (xy 382.090048 -401.756091)
			(xy 382.074683 -401.808421) (xy 382.052026 -401.858031) (xy 382.02254 -401.903912) (xy 381.986825 -401.945129)
			(xy 381.945608 -401.980844) (xy 381.899727 -402.01033) (xy 381.850117 -402.032987) (xy 381.797787 -402.048352)
			(xy 381.743803 -402.056114) (xy 381.689265 -402.056114) (xy 381.635281 -402.048352) (xy 381.582951 -402.032987)
			(xy 381.533341 -402.01033) (xy 381.48746 -401.980844) (xy 381.446243 -401.945129) (xy 381.410528 -401.903912)
			(xy 381.381042 -401.858031) (xy 381.358385 -401.808421) (xy 381.34302 -401.756091) (xy 381.335258 -401.702107)
			(xy 381.334772 -401.674838) (xy 380.8984 -401.674838) (xy 380.897914 -401.702107) (xy 380.890152 -401.756091)
			(xy 380.874787 -401.808421) (xy 380.85213 -401.858031) (xy 380.822644 -401.903912) (xy 380.786929 -401.945129)
			(xy 380.745712 -401.980844) (xy 380.699831 -402.01033) (xy 380.650221 -402.032987) (xy 380.597891 -402.048352)
			(xy 380.543907 -402.056114) (xy 380.489369 -402.056114) (xy 380.435385 -402.048352) (xy 380.383055 -402.032987)
			(xy 380.333445 -402.01033) (xy 380.287564 -401.980844) (xy 380.246347 -401.945129) (xy 380.210632 -401.903912)
			(xy 380.181146 -401.858031) (xy 380.158489 -401.808421) (xy 380.143124 -401.756091) (xy 380.135362 -401.702107)
			(xy 380.134876 -401.674838) (xy 379.697996 -401.674838) (xy 379.69751 -401.702089) (xy 379.689754 -401.756037)
			(xy 379.674399 -401.808332) (xy 379.651757 -401.857909) (xy 379.622291 -401.903759) (xy 379.5866 -401.94495)
			(xy 379.545409 -401.980641) (xy 379.499559 -402.010107) (xy 379.449982 -402.032749) (xy 379.397687 -402.048104)
			(xy 379.343739 -402.05586) (xy 379.289237 -402.05586) (xy 379.235289 -402.048104) (xy 379.182994 -402.032749)
			(xy 379.133417 -402.010107) (xy 379.087567 -401.980641) (xy 379.046376 -401.94495) (xy 379.010685 -401.903759)
			(xy 378.981219 -401.857909) (xy 378.958577 -401.808332) (xy 378.943222 -401.756037) (xy 378.935466 -401.702089)
			(xy 378.93498 -401.674838) (xy 378.4981 -401.674838) (xy 378.497614 -401.702089) (xy 378.489858 -401.756037)
			(xy 378.474503 -401.808332) (xy 378.451861 -401.857909) (xy 378.422395 -401.903759) (xy 378.386704 -401.94495)
			(xy 378.345513 -401.980641) (xy 378.299663 -402.010107) (xy 378.250086 -402.032749) (xy 378.197791 -402.048104)
			(xy 378.143843 -402.05586) (xy 378.089341 -402.05586) (xy 378.035393 -402.048104) (xy 377.983098 -402.032749)
			(xy 377.933521 -402.010107) (xy 377.887671 -401.980641) (xy 377.84648 -401.94495) (xy 377.810789 -401.903759)
			(xy 377.781323 -401.857909) (xy 377.758681 -401.808332) (xy 377.743326 -401.756037) (xy 377.73557 -401.702089)
			(xy 377.735084 -401.674838) (xy 377.298204 -401.674838) (xy 377.297718 -401.702107) (xy 377.289956 -401.756091)
			(xy 377.274591 -401.808421) (xy 377.251934 -401.858031) (xy 377.222448 -401.903912) (xy 377.186733 -401.945129)
			(xy 377.145516 -401.980844) (xy 377.099635 -402.01033) (xy 377.050025 -402.032987) (xy 376.997695 -402.048352)
			(xy 376.943711 -402.056114) (xy 376.889173 -402.056114) (xy 376.835189 -402.048352) (xy 376.782859 -402.032987)
			(xy 376.733249 -402.01033) (xy 376.687368 -401.980844) (xy 376.646151 -401.945129) (xy 376.610436 -401.903912)
			(xy 376.58095 -401.858031) (xy 376.558293 -401.808421) (xy 376.542928 -401.756091) (xy 376.535166 -401.702107)
			(xy 376.53468 -401.674838) (xy 376.098308 -401.674838) (xy 376.097822 -401.702107) (xy 376.09006 -401.756091)
			(xy 376.074695 -401.808421) (xy 376.052038 -401.858031) (xy 376.022552 -401.903912) (xy 375.986837 -401.945129)
			(xy 375.94562 -401.980844) (xy 375.899739 -402.01033) (xy 375.850129 -402.032987) (xy 375.797799 -402.048352)
			(xy 375.743815 -402.056114) (xy 375.689277 -402.056114) (xy 375.635293 -402.048352) (xy 375.582963 -402.032987)
			(xy 375.533353 -402.01033) (xy 375.487472 -401.980844) (xy 375.446255 -401.945129) (xy 375.41054 -401.903912)
			(xy 375.381054 -401.858031) (xy 375.358397 -401.808421) (xy 375.343032 -401.756091) (xy 375.33527 -401.702107)
			(xy 375.334784 -401.674838) (xy 374.897904 -401.674838) (xy 374.897418 -401.702089) (xy 374.889662 -401.756037)
			(xy 374.874307 -401.808332) (xy 374.851665 -401.857909) (xy 374.822199 -401.903759) (xy 374.786508 -401.94495)
			(xy 374.745317 -401.980641) (xy 374.699467 -402.010107) (xy 374.64989 -402.032749) (xy 374.597595 -402.048104)
			(xy 374.543647 -402.05586) (xy 374.489145 -402.05586) (xy 374.435197 -402.048104) (xy 374.382902 -402.032749)
			(xy 374.333325 -402.010107) (xy 374.287475 -401.980641) (xy 374.246284 -401.94495) (xy 374.210593 -401.903759)
			(xy 374.181127 -401.857909) (xy 374.158485 -401.808332) (xy 374.14313 -401.756037) (xy 374.135374 -401.702089)
			(xy 374.134888 -401.674838) (xy 373.698008 -401.674838) (xy 373.697522 -401.702089) (xy 373.689766 -401.756037)
			(xy 373.674411 -401.808332) (xy 373.651769 -401.857909) (xy 373.622303 -401.903759) (xy 373.586612 -401.94495)
			(xy 373.545421 -401.980641) (xy 373.499571 -402.010107) (xy 373.449994 -402.032749) (xy 373.397699 -402.048104)
			(xy 373.343751 -402.05586) (xy 373.289249 -402.05586) (xy 373.235301 -402.048104) (xy 373.183006 -402.032749)
			(xy 373.133429 -402.010107) (xy 373.087579 -401.980641) (xy 373.046388 -401.94495) (xy 373.010697 -401.903759)
			(xy 372.981231 -401.857909) (xy 372.958589 -401.808332) (xy 372.943234 -401.756037) (xy 372.935478 -401.702089)
			(xy 372.934992 -401.674838) (xy 372.498112 -401.674838) (xy 372.497626 -401.702107) (xy 372.489864 -401.756091)
			(xy 372.474499 -401.808421) (xy 372.451842 -401.858031) (xy 372.422356 -401.903912) (xy 372.386641 -401.945129)
			(xy 372.345424 -401.980844) (xy 372.299543 -402.01033) (xy 372.249933 -402.032987) (xy 372.197603 -402.048352)
			(xy 372.143619 -402.056114) (xy 372.089081 -402.056114) (xy 372.035097 -402.048352) (xy 371.982767 -402.032987)
			(xy 371.933157 -402.01033) (xy 371.887276 -401.980844) (xy 371.846059 -401.945129) (xy 371.810344 -401.903912)
			(xy 371.780858 -401.858031) (xy 371.758201 -401.808421) (xy 371.742836 -401.756091) (xy 371.735074 -401.702107)
			(xy 371.734588 -401.674838) (xy 371.298216 -401.674838) (xy 371.29773 -401.702107) (xy 371.289968 -401.756091)
			(xy 371.274603 -401.808421) (xy 371.251946 -401.858031) (xy 371.22246 -401.903912) (xy 371.186745 -401.945129)
			(xy 371.145528 -401.980844) (xy 371.099647 -402.01033) (xy 371.050037 -402.032987) (xy 370.997707 -402.048352)
			(xy 370.943723 -402.056114) (xy 370.889185 -402.056114) (xy 370.835201 -402.048352) (xy 370.782871 -402.032987)
			(xy 370.733261 -402.01033) (xy 370.68738 -401.980844) (xy 370.646163 -401.945129) (xy 370.610448 -401.903912)
			(xy 370.580962 -401.858031) (xy 370.558305 -401.808421) (xy 370.54294 -401.756091) (xy 370.535178 -401.702107)
			(xy 370.534692 -401.674838) (xy 354.725732 -401.674838) (xy 354.725246 -401.702107) (xy 354.717484 -401.756091)
			(xy 354.702119 -401.808421) (xy 354.679462 -401.858031) (xy 354.649976 -401.903912) (xy 354.614261 -401.945129)
			(xy 354.573044 -401.980844) (xy 354.527163 -402.01033) (xy 354.477553 -402.032987) (xy 354.425223 -402.048352)
			(xy 354.371239 -402.056114) (xy 354.316701 -402.056114) (xy 354.262717 -402.048352) (xy 354.210387 -402.032987)
			(xy 354.160777 -402.01033) (xy 354.114896 -401.980844) (xy 354.073679 -401.945129) (xy 354.037964 -401.903912)
			(xy 354.008478 -401.858031) (xy 353.985821 -401.808421) (xy 353.970456 -401.756091) (xy 353.962694 -401.702107)
			(xy 353.962208 -401.674838) (xy 353.525836 -401.674838) (xy 353.52535 -401.702107) (xy 353.517588 -401.756091)
			(xy 353.502223 -401.808421) (xy 353.479566 -401.858031) (xy 353.45008 -401.903912) (xy 353.414365 -401.945129)
			(xy 353.373148 -401.980844) (xy 353.327267 -402.01033) (xy 353.277657 -402.032987) (xy 353.225327 -402.048352)
			(xy 353.171343 -402.056114) (xy 353.116805 -402.056114) (xy 353.062821 -402.048352) (xy 353.010491 -402.032987)
			(xy 352.960881 -402.01033) (xy 352.915 -401.980844) (xy 352.873783 -401.945129) (xy 352.838068 -401.903912)
			(xy 352.808582 -401.858031) (xy 352.785925 -401.808421) (xy 352.77056 -401.756091) (xy 352.762798 -401.702107)
			(xy 352.762312 -401.674838) (xy 352.325432 -401.674838) (xy 352.324946 -401.702089) (xy 352.31719 -401.756037)
			(xy 352.301835 -401.808332) (xy 352.279193 -401.857909) (xy 352.249727 -401.903759) (xy 352.214036 -401.94495)
			(xy 352.172845 -401.980641) (xy 352.126995 -402.010107) (xy 352.077418 -402.032749) (xy 352.025123 -402.048104)
			(xy 351.971175 -402.05586) (xy 351.916673 -402.05586) (xy 351.862725 -402.048104) (xy 351.81043 -402.032749)
			(xy 351.760853 -402.010107) (xy 351.715003 -401.980641) (xy 351.673812 -401.94495) (xy 351.638121 -401.903759)
			(xy 351.608655 -401.857909) (xy 351.586013 -401.808332) (xy 351.570658 -401.756037) (xy 351.562902 -401.702089)
			(xy 351.562416 -401.674838) (xy 351.125536 -401.674838) (xy 351.12505 -401.702089) (xy 351.117294 -401.756037)
			(xy 351.101939 -401.808332) (xy 351.079297 -401.857909) (xy 351.049831 -401.903759) (xy 351.01414 -401.94495)
			(xy 350.972949 -401.980641) (xy 350.927099 -402.010107) (xy 350.877522 -402.032749) (xy 350.825227 -402.048104)
			(xy 350.771279 -402.05586) (xy 350.716777 -402.05586) (xy 350.662829 -402.048104) (xy 350.610534 -402.032749)
			(xy 350.560957 -402.010107) (xy 350.515107 -401.980641) (xy 350.473916 -401.94495) (xy 350.438225 -401.903759)
			(xy 350.408759 -401.857909) (xy 350.386117 -401.808332) (xy 350.370762 -401.756037) (xy 350.363006 -401.702089)
			(xy 350.36252 -401.674838) (xy 349.92564 -401.674838) (xy 349.925154 -401.702089) (xy 349.917398 -401.756037)
			(xy 349.902043 -401.808332) (xy 349.879401 -401.857909) (xy 349.849935 -401.903759) (xy 349.814244 -401.94495)
			(xy 349.773053 -401.980641) (xy 349.727203 -402.010107) (xy 349.677626 -402.032749) (xy 349.625331 -402.048104)
			(xy 349.571383 -402.05586) (xy 349.516881 -402.05586) (xy 349.462933 -402.048104) (xy 349.410638 -402.032749)
			(xy 349.361061 -402.010107) (xy 349.315211 -401.980641) (xy 349.27402 -401.94495) (xy 349.238329 -401.903759)
			(xy 349.208863 -401.857909) (xy 349.186221 -401.808332) (xy 349.170866 -401.756037) (xy 349.16311 -401.702089)
			(xy 349.162624 -401.674838) (xy 348.725744 -401.674838) (xy 348.725258 -401.702089) (xy 348.717502 -401.756037)
			(xy 348.702147 -401.808332) (xy 348.679505 -401.857909) (xy 348.650039 -401.903759) (xy 348.614348 -401.94495)
			(xy 348.573157 -401.980641) (xy 348.527307 -402.010107) (xy 348.47773 -402.032749) (xy 348.425435 -402.048104)
			(xy 348.371487 -402.05586) (xy 348.316985 -402.05586) (xy 348.263037 -402.048104) (xy 348.210742 -402.032749)
			(xy 348.161165 -402.010107) (xy 348.115315 -401.980641) (xy 348.074124 -401.94495) (xy 348.038433 -401.903759)
			(xy 348.008967 -401.857909) (xy 347.986325 -401.808332) (xy 347.97097 -401.756037) (xy 347.963214 -401.702089)
			(xy 347.962728 -401.674838) (xy 347.525848 -401.674838) (xy 347.525362 -401.702107) (xy 347.5176 -401.756091)
			(xy 347.502235 -401.808421) (xy 347.479578 -401.858031) (xy 347.450092 -401.903912) (xy 347.414377 -401.945129)
			(xy 347.37316 -401.980844) (xy 347.327279 -402.01033) (xy 347.277669 -402.032987) (xy 347.225339 -402.048352)
			(xy 347.171355 -402.056114) (xy 347.116817 -402.056114) (xy 347.062833 -402.048352) (xy 347.010503 -402.032987)
			(xy 346.960893 -402.01033) (xy 346.915012 -401.980844) (xy 346.873795 -401.945129) (xy 346.83808 -401.903912)
			(xy 346.808594 -401.858031) (xy 346.785937 -401.808421) (xy 346.770572 -401.756091) (xy 346.76281 -401.702107)
			(xy 346.762324 -401.674838) (xy 346.325952 -401.674838) (xy 346.325466 -401.702107) (xy 346.317704 -401.756091)
			(xy 346.302339 -401.808421) (xy 346.279682 -401.858031) (xy 346.250196 -401.903912) (xy 346.214481 -401.945129)
			(xy 346.173264 -401.980844) (xy 346.127383 -402.01033) (xy 346.077773 -402.032987) (xy 346.025443 -402.048352)
			(xy 345.971459 -402.056114) (xy 345.916921 -402.056114) (xy 345.862937 -402.048352) (xy 345.810607 -402.032987)
			(xy 345.760997 -402.01033) (xy 345.715116 -401.980844) (xy 345.673899 -401.945129) (xy 345.638184 -401.903912)
			(xy 345.608698 -401.858031) (xy 345.586041 -401.808421) (xy 345.570676 -401.756091) (xy 345.562914 -401.702107)
			(xy 345.562428 -401.674838) (xy 345.125548 -401.674838) (xy 345.125062 -401.702089) (xy 345.117306 -401.756037)
			(xy 345.101951 -401.808332) (xy 345.079309 -401.857909) (xy 345.049843 -401.903759) (xy 345.014152 -401.94495)
			(xy 344.972961 -401.980641) (xy 344.927111 -402.010107) (xy 344.877534 -402.032749) (xy 344.825239 -402.048104)
			(xy 344.771291 -402.05586) (xy 344.716789 -402.05586) (xy 344.662841 -402.048104) (xy 344.610546 -402.032749)
			(xy 344.560969 -402.010107) (xy 344.515119 -401.980641) (xy 344.473928 -401.94495) (xy 344.438237 -401.903759)
			(xy 344.408771 -401.857909) (xy 344.386129 -401.808332) (xy 344.370774 -401.756037) (xy 344.363018 -401.702089)
			(xy 344.362532 -401.674838) (xy 343.925652 -401.674838) (xy 343.925166 -401.702089) (xy 343.91741 -401.756037)
			(xy 343.902055 -401.808332) (xy 343.879413 -401.857909) (xy 343.849947 -401.903759) (xy 343.814256 -401.94495)
			(xy 343.773065 -401.980641) (xy 343.727215 -402.010107) (xy 343.677638 -402.032749) (xy 343.625343 -402.048104)
			(xy 343.571395 -402.05586) (xy 343.516893 -402.05586) (xy 343.462945 -402.048104) (xy 343.41065 -402.032749)
			(xy 343.361073 -402.010107) (xy 343.315223 -401.980641) (xy 343.274032 -401.94495) (xy 343.238341 -401.903759)
			(xy 343.208875 -401.857909) (xy 343.186233 -401.808332) (xy 343.170878 -401.756037) (xy 343.163122 -401.702089)
			(xy 343.162636 -401.674838) (xy 342.725756 -401.674838) (xy 342.72527 -401.702107) (xy 342.717508 -401.756091)
			(xy 342.702143 -401.808421) (xy 342.679486 -401.858031) (xy 342.65 -401.903912) (xy 342.614285 -401.945129)
			(xy 342.573068 -401.980844) (xy 342.527187 -402.01033) (xy 342.477577 -402.032987) (xy 342.425247 -402.048352)
			(xy 342.371263 -402.056114) (xy 342.316725 -402.056114) (xy 342.262741 -402.048352) (xy 342.210411 -402.032987)
			(xy 342.160801 -402.01033) (xy 342.11492 -401.980844) (xy 342.073703 -401.945129) (xy 342.037988 -401.903912)
			(xy 342.008502 -401.858031) (xy 341.985845 -401.808421) (xy 341.97048 -401.756091) (xy 341.962718 -401.702107)
			(xy 341.962232 -401.674838) (xy 341.52586 -401.674838) (xy 341.525374 -401.702107) (xy 341.517612 -401.756091)
			(xy 341.502247 -401.808421) (xy 341.47959 -401.858031) (xy 341.450104 -401.903912) (xy 341.414389 -401.945129)
			(xy 341.373172 -401.980844) (xy 341.327291 -402.01033) (xy 341.277681 -402.032987) (xy 341.225351 -402.048352)
			(xy 341.171367 -402.056114) (xy 341.116829 -402.056114) (xy 341.062845 -402.048352) (xy 341.010515 -402.032987)
			(xy 340.960905 -402.01033) (xy 340.915024 -401.980844) (xy 340.873807 -401.945129) (xy 340.838092 -401.903912)
			(xy 340.808606 -401.858031) (xy 340.785949 -401.808421) (xy 340.770584 -401.756091) (xy 340.762822 -401.702107)
			(xy 340.762336 -401.674838) (xy 340.325456 -401.674838) (xy 340.32497 -401.702089) (xy 340.317214 -401.756037)
			(xy 340.301859 -401.808332) (xy 340.279217 -401.857909) (xy 340.249751 -401.903759) (xy 340.21406 -401.94495)
			(xy 340.172869 -401.980641) (xy 340.127019 -402.010107) (xy 340.077442 -402.032749) (xy 340.025147 -402.048104)
			(xy 339.971199 -402.05586) (xy 339.916697 -402.05586) (xy 339.862749 -402.048104) (xy 339.810454 -402.032749)
			(xy 339.760877 -402.010107) (xy 339.715027 -401.980641) (xy 339.673836 -401.94495) (xy 339.638145 -401.903759)
			(xy 339.608679 -401.857909) (xy 339.586037 -401.808332) (xy 339.570682 -401.756037) (xy 339.562926 -401.702089)
			(xy 339.56244 -401.674838) (xy 339.12556 -401.674838) (xy 339.125074 -401.702089) (xy 339.117318 -401.756037)
			(xy 339.101963 -401.808332) (xy 339.079321 -401.857909) (xy 339.049855 -401.903759) (xy 339.014164 -401.94495)
			(xy 338.972973 -401.980641) (xy 338.927123 -402.010107) (xy 338.877546 -402.032749) (xy 338.825251 -402.048104)
			(xy 338.771303 -402.05586) (xy 338.716801 -402.05586) (xy 338.662853 -402.048104) (xy 338.610558 -402.032749)
			(xy 338.560981 -402.010107) (xy 338.515131 -401.980641) (xy 338.47394 -401.94495) (xy 338.438249 -401.903759)
			(xy 338.408783 -401.857909) (xy 338.386141 -401.808332) (xy 338.370786 -401.756037) (xy 338.36303 -401.702089)
			(xy 338.362544 -401.674838) (xy 337.925664 -401.674838) (xy 337.925178 -401.702107) (xy 337.917416 -401.756091)
			(xy 337.902051 -401.808421) (xy 337.879394 -401.858031) (xy 337.849908 -401.903912) (xy 337.814193 -401.945129)
			(xy 337.772976 -401.980844) (xy 337.727095 -402.01033) (xy 337.677485 -402.032987) (xy 337.625155 -402.048352)
			(xy 337.571171 -402.056114) (xy 337.516633 -402.056114) (xy 337.462649 -402.048352) (xy 337.410319 -402.032987)
			(xy 337.360709 -402.01033) (xy 337.314828 -401.980844) (xy 337.273611 -401.945129) (xy 337.237896 -401.903912)
			(xy 337.20841 -401.858031) (xy 337.185753 -401.808421) (xy 337.170388 -401.756091) (xy 337.162626 -401.702107)
			(xy 337.16214 -401.674838) (xy 336.725768 -401.674838) (xy 336.725282 -401.702107) (xy 336.71752 -401.756091)
			(xy 336.702155 -401.808421) (xy 336.679498 -401.858031) (xy 336.650012 -401.903912) (xy 336.614297 -401.945129)
			(xy 336.57308 -401.980844) (xy 336.527199 -402.01033) (xy 336.477589 -402.032987) (xy 336.425259 -402.048352)
			(xy 336.371275 -402.056114) (xy 336.316737 -402.056114) (xy 336.262753 -402.048352) (xy 336.210423 -402.032987)
			(xy 336.160813 -402.01033) (xy 336.114932 -401.980844) (xy 336.073715 -401.945129) (xy 336.038 -401.903912)
			(xy 336.008514 -401.858031) (xy 335.985857 -401.808421) (xy 335.970492 -401.756091) (xy 335.96273 -401.702107)
			(xy 335.962244 -401.674838) (xy 322.197984 -401.674838) (xy 322.197498 -401.702107) (xy 322.189736 -401.756091)
			(xy 322.174371 -401.808421) (xy 322.151714 -401.858031) (xy 322.122228 -401.903912) (xy 322.086513 -401.945129)
			(xy 322.045296 -401.980844) (xy 321.999415 -402.01033) (xy 321.949805 -402.032987) (xy 321.897475 -402.048352)
			(xy 321.843491 -402.056114) (xy 321.788953 -402.056114) (xy 321.734969 -402.048352) (xy 321.682639 -402.032987)
			(xy 321.633029 -402.01033) (xy 321.587148 -401.980844) (xy 321.545931 -401.945129) (xy 321.510216 -401.903912)
			(xy 321.48073 -401.858031) (xy 321.458073 -401.808421) (xy 321.442708 -401.756091) (xy 321.434946 -401.702107)
			(xy 321.43446 -401.674838) (xy 320.998088 -401.674838) (xy 320.997602 -401.702107) (xy 320.98984 -401.756091)
			(xy 320.974475 -401.808421) (xy 320.951818 -401.858031) (xy 320.922332 -401.903912) (xy 320.886617 -401.945129)
			(xy 320.8454 -401.980844) (xy 320.799519 -402.01033) (xy 320.749909 -402.032987) (xy 320.697579 -402.048352)
			(xy 320.643595 -402.056114) (xy 320.589057 -402.056114) (xy 320.535073 -402.048352) (xy 320.482743 -402.032987)
			(xy 320.433133 -402.01033) (xy 320.387252 -401.980844) (xy 320.346035 -401.945129) (xy 320.31032 -401.903912)
			(xy 320.280834 -401.858031) (xy 320.258177 -401.808421) (xy 320.242812 -401.756091) (xy 320.23505 -401.702107)
			(xy 320.234564 -401.674838) (xy 319.797684 -401.674838) (xy 319.797198 -401.702089) (xy 319.789442 -401.756037)
			(xy 319.774087 -401.808332) (xy 319.751445 -401.857909) (xy 319.721979 -401.903759) (xy 319.686288 -401.94495)
			(xy 319.645097 -401.980641) (xy 319.599247 -402.010107) (xy 319.54967 -402.032749) (xy 319.497375 -402.048104)
			(xy 319.443427 -402.05586) (xy 319.388925 -402.05586) (xy 319.334977 -402.048104) (xy 319.282682 -402.032749)
			(xy 319.233105 -402.010107) (xy 319.187255 -401.980641) (xy 319.146064 -401.94495) (xy 319.110373 -401.903759)
			(xy 319.080907 -401.857909) (xy 319.058265 -401.808332) (xy 319.04291 -401.756037) (xy 319.035154 -401.702089)
			(xy 319.034668 -401.674838) (xy 318.597788 -401.674838) (xy 318.597302 -401.702089) (xy 318.589546 -401.756037)
			(xy 318.574191 -401.808332) (xy 318.551549 -401.857909) (xy 318.522083 -401.903759) (xy 318.486392 -401.94495)
			(xy 318.445201 -401.980641) (xy 318.399351 -402.010107) (xy 318.349774 -402.032749) (xy 318.297479 -402.048104)
			(xy 318.243531 -402.05586) (xy 318.189029 -402.05586) (xy 318.135081 -402.048104) (xy 318.082786 -402.032749)
			(xy 318.033209 -402.010107) (xy 317.987359 -401.980641) (xy 317.946168 -401.94495) (xy 317.910477 -401.903759)
			(xy 317.881011 -401.857909) (xy 317.858369 -401.808332) (xy 317.843014 -401.756037) (xy 317.835258 -401.702089)
			(xy 317.834772 -401.674838) (xy 317.397892 -401.674838) (xy 317.397406 -401.702089) (xy 317.38965 -401.756037)
			(xy 317.374295 -401.808332) (xy 317.351653 -401.857909) (xy 317.322187 -401.903759) (xy 317.286496 -401.94495)
			(xy 317.245305 -401.980641) (xy 317.199455 -402.010107) (xy 317.149878 -402.032749) (xy 317.097583 -402.048104)
			(xy 317.043635 -402.05586) (xy 316.989133 -402.05586) (xy 316.935185 -402.048104) (xy 316.88289 -402.032749)
			(xy 316.833313 -402.010107) (xy 316.787463 -401.980641) (xy 316.746272 -401.94495) (xy 316.710581 -401.903759)
			(xy 316.681115 -401.857909) (xy 316.658473 -401.808332) (xy 316.643118 -401.756037) (xy 316.635362 -401.702089)
			(xy 316.634876 -401.674838) (xy 316.197996 -401.674838) (xy 316.19751 -401.702089) (xy 316.189754 -401.756037)
			(xy 316.174399 -401.808332) (xy 316.151757 -401.857909) (xy 316.122291 -401.903759) (xy 316.0866 -401.94495)
			(xy 316.045409 -401.980641) (xy 315.999559 -402.010107) (xy 315.949982 -402.032749) (xy 315.897687 -402.048104)
			(xy 315.843739 -402.05586) (xy 315.789237 -402.05586) (xy 315.735289 -402.048104) (xy 315.682994 -402.032749)
			(xy 315.633417 -402.010107) (xy 315.587567 -401.980641) (xy 315.546376 -401.94495) (xy 315.510685 -401.903759)
			(xy 315.481219 -401.857909) (xy 315.458577 -401.808332) (xy 315.443222 -401.756037) (xy 315.435466 -401.702089)
			(xy 315.43498 -401.674838) (xy 314.9981 -401.674838) (xy 314.997614 -401.702107) (xy 314.989852 -401.756091)
			(xy 314.974487 -401.808421) (xy 314.95183 -401.858031) (xy 314.922344 -401.903912) (xy 314.886629 -401.945129)
			(xy 314.845412 -401.980844) (xy 314.799531 -402.01033) (xy 314.749921 -402.032987) (xy 314.697591 -402.048352)
			(xy 314.643607 -402.056114) (xy 314.589069 -402.056114) (xy 314.535085 -402.048352) (xy 314.482755 -402.032987)
			(xy 314.433145 -402.01033) (xy 314.387264 -401.980844) (xy 314.346047 -401.945129) (xy 314.310332 -401.903912)
			(xy 314.280846 -401.858031) (xy 314.258189 -401.808421) (xy 314.242824 -401.756091) (xy 314.235062 -401.702107)
			(xy 314.234576 -401.674838) (xy 313.798204 -401.674838) (xy 313.797718 -401.702107) (xy 313.789956 -401.756091)
			(xy 313.774591 -401.808421) (xy 313.751934 -401.858031) (xy 313.722448 -401.903912) (xy 313.686733 -401.945129)
			(xy 313.645516 -401.980844) (xy 313.599635 -402.01033) (xy 313.550025 -402.032987) (xy 313.497695 -402.048352)
			(xy 313.443711 -402.056114) (xy 313.389173 -402.056114) (xy 313.335189 -402.048352) (xy 313.282859 -402.032987)
			(xy 313.233249 -402.01033) (xy 313.187368 -401.980844) (xy 313.146151 -401.945129) (xy 313.110436 -401.903912)
			(xy 313.08095 -401.858031) (xy 313.058293 -401.808421) (xy 313.042928 -401.756091) (xy 313.035166 -401.702107)
			(xy 313.03468 -401.674838) (xy 312.5978 -401.674838) (xy 312.597314 -401.702089) (xy 312.589558 -401.756037)
			(xy 312.574203 -401.808332) (xy 312.551561 -401.857909) (xy 312.522095 -401.903759) (xy 312.486404 -401.94495)
			(xy 312.445213 -401.980641) (xy 312.399363 -402.010107) (xy 312.349786 -402.032749) (xy 312.297491 -402.048104)
			(xy 312.243543 -402.05586) (xy 312.189041 -402.05586) (xy 312.135093 -402.048104) (xy 312.082798 -402.032749)
			(xy 312.033221 -402.010107) (xy 311.987371 -401.980641) (xy 311.94618 -401.94495) (xy 311.910489 -401.903759)
			(xy 311.881023 -401.857909) (xy 311.858381 -401.808332) (xy 311.843026 -401.756037) (xy 311.83527 -401.702089)
			(xy 311.834784 -401.674838) (xy 311.397904 -401.674838) (xy 311.397418 -401.702089) (xy 311.389662 -401.756037)
			(xy 311.374307 -401.808332) (xy 311.351665 -401.857909) (xy 311.322199 -401.903759) (xy 311.286508 -401.94495)
			(xy 311.245317 -401.980641) (xy 311.199467 -402.010107) (xy 311.14989 -402.032749) (xy 311.097595 -402.048104)
			(xy 311.043647 -402.05586) (xy 310.989145 -402.05586) (xy 310.935197 -402.048104) (xy 310.882902 -402.032749)
			(xy 310.833325 -402.010107) (xy 310.787475 -401.980641) (xy 310.746284 -401.94495) (xy 310.710593 -401.903759)
			(xy 310.681127 -401.857909) (xy 310.658485 -401.808332) (xy 310.64313 -401.756037) (xy 310.635374 -401.702089)
			(xy 310.634888 -401.674838) (xy 310.198008 -401.674838) (xy 310.197522 -401.702107) (xy 310.18976 -401.756091)
			(xy 310.174395 -401.808421) (xy 310.151738 -401.858031) (xy 310.122252 -401.903912) (xy 310.086537 -401.945129)
			(xy 310.04532 -401.980844) (xy 309.999439 -402.01033) (xy 309.949829 -402.032987) (xy 309.897499 -402.048352)
			(xy 309.843515 -402.056114) (xy 309.788977 -402.056114) (xy 309.734993 -402.048352) (xy 309.682663 -402.032987)
			(xy 309.633053 -402.01033) (xy 309.587172 -401.980844) (xy 309.545955 -401.945129) (xy 309.51024 -401.903912)
			(xy 309.480754 -401.858031) (xy 309.458097 -401.808421) (xy 309.442732 -401.756091) (xy 309.43497 -401.702107)
			(xy 309.434484 -401.674838) (xy 308.998112 -401.674838) (xy 308.997626 -401.702107) (xy 308.989864 -401.756091)
			(xy 308.974499 -401.808421) (xy 308.951842 -401.858031) (xy 308.922356 -401.903912) (xy 308.886641 -401.945129)
			(xy 308.845424 -401.980844) (xy 308.799543 -402.01033) (xy 308.749933 -402.032987) (xy 308.697603 -402.048352)
			(xy 308.643619 -402.056114) (xy 308.589081 -402.056114) (xy 308.535097 -402.048352) (xy 308.482767 -402.032987)
			(xy 308.433157 -402.01033) (xy 308.387276 -401.980844) (xy 308.346059 -401.945129) (xy 308.310344 -401.903912)
			(xy 308.280858 -401.858031) (xy 308.258201 -401.808421) (xy 308.242836 -401.756091) (xy 308.235074 -401.702107)
			(xy 308.234588 -401.674838) (xy 307.797708 -401.674838) (xy 307.797222 -401.702089) (xy 307.789466 -401.756037)
			(xy 307.774111 -401.808332) (xy 307.751469 -401.857909) (xy 307.722003 -401.903759) (xy 307.686312 -401.94495)
			(xy 307.645121 -401.980641) (xy 307.599271 -402.010107) (xy 307.549694 -402.032749) (xy 307.497399 -402.048104)
			(xy 307.443451 -402.05586) (xy 307.388949 -402.05586) (xy 307.335001 -402.048104) (xy 307.282706 -402.032749)
			(xy 307.233129 -402.010107) (xy 307.187279 -401.980641) (xy 307.146088 -401.94495) (xy 307.110397 -401.903759)
			(xy 307.080931 -401.857909) (xy 307.058289 -401.808332) (xy 307.042934 -401.756037) (xy 307.035178 -401.702089)
			(xy 307.034692 -401.674838) (xy 306.597812 -401.674838) (xy 306.597326 -401.702089) (xy 306.58957 -401.756037)
			(xy 306.574215 -401.808332) (xy 306.551573 -401.857909) (xy 306.522107 -401.903759) (xy 306.486416 -401.94495)
			(xy 306.445225 -401.980641) (xy 306.399375 -402.010107) (xy 306.349798 -402.032749) (xy 306.297503 -402.048104)
			(xy 306.243555 -402.05586) (xy 306.189053 -402.05586) (xy 306.135105 -402.048104) (xy 306.08281 -402.032749)
			(xy 306.033233 -402.010107) (xy 305.987383 -401.980641) (xy 305.946192 -401.94495) (xy 305.910501 -401.903759)
			(xy 305.881035 -401.857909) (xy 305.858393 -401.808332) (xy 305.843038 -401.756037) (xy 305.835282 -401.702089)
			(xy 305.834796 -401.674838) (xy 305.397916 -401.674838) (xy 305.39743 -401.702107) (xy 305.389668 -401.756091)
			(xy 305.374303 -401.808421) (xy 305.351646 -401.858031) (xy 305.32216 -401.903912) (xy 305.286445 -401.945129)
			(xy 305.245228 -401.980844) (xy 305.199347 -402.01033) (xy 305.149737 -402.032987) (xy 305.097407 -402.048352)
			(xy 305.043423 -402.056114) (xy 304.988885 -402.056114) (xy 304.934901 -402.048352) (xy 304.882571 -402.032987)
			(xy 304.832961 -402.01033) (xy 304.78708 -401.980844) (xy 304.745863 -401.945129) (xy 304.710148 -401.903912)
			(xy 304.680662 -401.858031) (xy 304.658005 -401.808421) (xy 304.64264 -401.756091) (xy 304.634878 -401.702107)
			(xy 304.634392 -401.674838) (xy 304.19802 -401.674838) (xy 304.197534 -401.702107) (xy 304.189772 -401.756091)
			(xy 304.174407 -401.808421) (xy 304.15175 -401.858031) (xy 304.122264 -401.903912) (xy 304.086549 -401.945129)
			(xy 304.045332 -401.980844) (xy 303.999451 -402.01033) (xy 303.949841 -402.032987) (xy 303.897511 -402.048352)
			(xy 303.843527 -402.056114) (xy 303.788989 -402.056114) (xy 303.735005 -402.048352) (xy 303.682675 -402.032987)
			(xy 303.633065 -402.01033) (xy 303.587184 -401.980844) (xy 303.545967 -401.945129) (xy 303.510252 -401.903912)
			(xy 303.480766 -401.858031) (xy 303.458109 -401.808421) (xy 303.442744 -401.756091) (xy 303.434982 -401.702107)
			(xy 303.434496 -401.674838) (xy 280.68524 -401.674838) (xy 280.68524 -404.215092) (xy 283.62402 -404.215092)
			(xy 283.62402 -403.351492) (xy 283.624506 -403.324223) (xy 283.632268 -403.270239) (xy 283.647633 -403.217909)
			(xy 283.67029 -403.168299) (xy 283.699776 -403.122418) (xy 283.735491 -403.081201) (xy 283.776708 -403.045486)
			(xy 283.822589 -403.016) (xy 283.872199 -402.993343) (xy 283.924529 -402.977978) (xy 283.978513 -402.970216)
			(xy 284.033051 -402.970216) (xy 284.087035 -402.977978) (xy 284.139365 -402.993343) (xy 284.188975 -403.016)
			(xy 284.203533 -403.025356) (xy 289.919156 -403.025356) (xy 289.919156 -402.161756) (xy 289.919642 -402.134487)
			(xy 289.927404 -402.080503) (xy 289.942769 -402.028173) (xy 289.965426 -401.978563) (xy 289.994912 -401.932682)
			(xy 290.030627 -401.891465) (xy 290.071844 -401.85575) (xy 290.117725 -401.826264) (xy 290.167335 -401.803607)
			(xy 290.219665 -401.788242) (xy 290.273649 -401.78048) (xy 290.328187 -401.78048) (xy 290.382171 -401.788242)
			(xy 290.434501 -401.803607) (xy 290.484111 -401.826264) (xy 290.529992 -401.85575) (xy 290.571209 -401.891465)
			(xy 290.606924 -401.932682) (xy 290.63641 -401.978563) (xy 290.659067 -402.028173) (xy 290.674432 -402.080503)
			(xy 290.682194 -402.134487) (xy 290.68268 -402.161756) (xy 290.68268 -403.025356) (xy 290.682194 -403.052625)
			(xy 290.674432 -403.106609) (xy 290.659067 -403.158939) (xy 290.63641 -403.208549) (xy 290.606924 -403.25443)
			(xy 290.571209 -403.295647) (xy 290.529992 -403.331362) (xy 290.484111 -403.360848) (xy 290.434501 -403.383505)
			(xy 290.382171 -403.39887) (xy 290.328187 -403.406632) (xy 290.273649 -403.406632) (xy 290.219665 -403.39887)
			(xy 290.167335 -403.383505) (xy 290.117725 -403.360848) (xy 290.071844 -403.331362) (xy 290.030627 -403.295647)
			(xy 289.994912 -403.25443) (xy 289.965426 -403.208549) (xy 289.942769 -403.158939) (xy 289.927404 -403.106609)
			(xy 289.919642 -403.052625) (xy 289.919156 -403.025356) (xy 284.203533 -403.025356) (xy 284.234856 -403.045486)
			(xy 284.276073 -403.081201) (xy 284.311788 -403.122418) (xy 284.341274 -403.168299) (xy 284.363931 -403.217909)
			(xy 284.379296 -403.270239) (xy 284.387058 -403.324223) (xy 284.387544 -403.351492) (xy 284.387544 -404.215092)
			(xy 284.387058 -404.242361) (xy 284.379296 -404.296345) (xy 284.363931 -404.348675) (xy 284.341274 -404.398285)
			(xy 284.311788 -404.444166) (xy 284.276073 -404.485383) (xy 284.234856 -404.521098) (xy 284.188975 -404.550584)
			(xy 284.139365 -404.573241) (xy 284.087035 -404.588606) (xy 284.033051 -404.596368) (xy 283.978513 -404.596368)
			(xy 283.924529 -404.588606) (xy 283.872199 -404.573241) (xy 283.822589 -404.550584) (xy 283.776708 -404.521098)
			(xy 283.735491 -404.485383) (xy 283.699776 -404.444166) (xy 283.67029 -404.398285) (xy 283.647633 -404.348675)
			(xy 283.632268 -404.296345) (xy 283.624506 -404.242361) (xy 283.62402 -404.215092) (xy 280.68524 -404.215092)
			(xy 280.68524 -407.583953) (xy 282.536071 -407.583953) (xy 282.536071 -407.529447) (xy 282.543829 -407.475495)
			(xy 282.559186 -407.423196) (xy 282.581831 -407.373615) (xy 282.611301 -407.327762) (xy 282.646997 -407.28657)
			(xy 282.688193 -407.250878) (xy 282.734049 -407.221412) (xy 282.783632 -407.198773) (xy 282.835932 -407.183421)
			(xy 282.889885 -407.175669) (xy 282.917138 -407.175208) (xy 283.780738 -407.175208) (xy 283.807989 -407.175664)
			(xy 283.861934 -407.183426) (xy 283.914227 -407.198785) (xy 283.963801 -407.221429) (xy 284.009649 -407.250898)
			(xy 284.050836 -407.286591) (xy 284.086525 -407.327782) (xy 284.115989 -407.373632) (xy 284.134525 -407.414222)
			(xy 287.101788 -407.414222) (xy 287.101788 -406.550622) (xy 287.102274 -406.523371) (xy 287.11003 -406.469423)
			(xy 287.125385 -406.417128) (xy 287.148027 -406.367551) (xy 287.177493 -406.321701) (xy 287.213184 -406.28051)
			(xy 287.254375 -406.244819) (xy 287.300225 -406.215353) (xy 287.349802 -406.192711) (xy 287.402097 -406.177356)
			(xy 287.456045 -406.1696) (xy 287.510547 -406.1696) (xy 287.564495 -406.177356) (xy 287.61679 -406.192711)
			(xy 287.666367 -406.215353) (xy 287.712217 -406.244819) (xy 287.753408 -406.28051) (xy 287.789099 -406.321701)
			(xy 287.818565 -406.367551) (xy 287.841207 -406.417128) (xy 287.856562 -406.469423) (xy 287.864318 -406.523371)
			(xy 287.864804 -406.550622) (xy 287.864804 -407.414222) (xy 287.864318 -407.441473) (xy 287.856562 -407.495421)
			(xy 287.841207 -407.547716) (xy 287.818565 -407.597293) (xy 287.789099 -407.643143) (xy 287.753408 -407.684334)
			(xy 287.712217 -407.720025) (xy 287.666367 -407.749491) (xy 287.61679 -407.772133) (xy 287.564495 -407.787488)
			(xy 287.510547 -407.795244) (xy 287.456045 -407.795244) (xy 287.402097 -407.787488) (xy 287.349802 -407.772133)
			(xy 287.300225 -407.749491) (xy 287.254375 -407.720025) (xy 287.213184 -407.684334) (xy 287.177493 -407.643143)
			(xy 287.148027 -407.597293) (xy 287.125385 -407.547716) (xy 287.11003 -407.495421) (xy 287.102274 -407.441473)
			(xy 287.101788 -407.414222) (xy 284.134525 -407.414222) (xy 284.138629 -407.423209) (xy 284.153982 -407.475503)
			(xy 284.161738 -407.529449) (xy 284.161738 -407.583951) (xy 284.153982 -407.637897) (xy 284.138629 -407.690191)
			(xy 284.115989 -407.739768) (xy 284.086525 -407.785619) (xy 284.050836 -407.826809) (xy 284.009649 -407.862502)
			(xy 283.963801 -407.891971) (xy 283.914227 -407.914615) (xy 283.861934 -407.929974) (xy 283.807989 -407.937736)
			(xy 283.780738 -407.938224) (xy 282.917138 -407.938224) (xy 282.889885 -407.937731) (xy 282.835932 -407.929979)
			(xy 282.783632 -407.914627) (xy 282.734049 -407.891988) (xy 282.688193 -407.862522) (xy 282.646997 -407.82683)
			(xy 282.611301 -407.785638) (xy 282.581831 -407.739785) (xy 282.559186 -407.690204) (xy 282.543829 -407.637905)
			(xy 282.536071 -407.583953) (xy 280.68524 -407.583953) (xy 280.68524 -409.10256) (xy 280.684766 -409.12751)
			(xy 280.676946 -409.176794) (xy 280.661524 -409.224251) (xy 280.638877 -409.268716) (xy 280.609563 -409.309098)
			(xy 280.592276 -409.327096) (xy 276.749256 -413.170116) (xy 293.568894 -413.170116) (xy 293.572866 -412.991873)
			(xy 293.584774 -412.813984) (xy 293.604595 -412.636802) (xy 293.632289 -412.460678) (xy 293.667801 -412.285963)
			(xy 293.711061 -412.113004) (xy 293.761983 -411.942143) (xy 293.820466 -411.773721) (xy 293.886393 -411.608071)
			(xy 293.959634 -411.445522) (xy 294.040044 -411.286397) (xy 294.127462 -411.131012) (xy 294.221715 -410.979676)
			(xy 294.322616 -410.832688) (xy 294.429965 -410.690341) (xy 294.543548 -410.552918) (xy 294.663141 -410.420691)
			(xy 294.788505 -410.293922) (xy 294.919392 -410.172864) (xy 295.055541 -410.057757) (xy 295.196683 -409.948829)
			(xy 295.342538 -409.846297) (xy 295.492815 -409.750363) (xy 295.647216 -409.66122) (xy 295.805435 -409.579043)
			(xy 295.967158 -409.503995) (xy 296.132063 -409.436227) (xy 296.299824 -409.375871) (xy 296.470107 -409.323049)
			(xy 296.642574 -409.277865) (xy 296.816882 -409.240408) (xy 296.992686 -409.210754) (xy 297.169636 -409.188961)
			(xy 297.347382 -409.175071) (xy 297.525569 -409.169114) (xy 297.703846 -409.1711) (xy 297.881857 -409.181026)
			(xy 298.059249 -409.198872) (xy 298.235669 -409.224602) (xy 298.410769 -409.258166) (xy 298.5842 -409.299496)
			(xy 298.755617 -409.348512) (xy 298.92468 -409.405114) (xy 299.091055 -409.469192) (xy 299.254409 -409.540618)
			(xy 299.41442 -409.61925) (xy 299.570769 -409.704931) (xy 299.723146 -409.797493) (xy 299.871249 -409.89675)
			(xy 300.014783 -410.002507) (xy 300.153463 -410.114552) (xy 300.287014 -410.232664) (xy 300.415171 -410.356608)
			(xy 300.53768 -410.486138) (xy 300.654297 -410.620997) (xy 300.76479 -410.760917) (xy 300.868941 -410.90562)
			(xy 300.966543 -411.054819) (xy 301.057401 -411.208218) (xy 301.141335 -411.365512) (xy 301.21818 -411.526388)
			(xy 301.287781 -411.690529) (xy 301.350002 -411.857606) (xy 301.404718 -412.02729) (xy 301.45182 -412.199243)
			(xy 301.491216 -412.373123) (xy 301.522827 -412.548586) (xy 301.546591 -412.725282) (xy 301.559858 -412.873752)
			(xy 303.412875 -412.873752) (xy 303.412875 -412.819248) (xy 303.420632 -412.7653) (xy 303.435988 -412.713004)
			(xy 303.458629 -412.663426) (xy 303.488096 -412.617575) (xy 303.523789 -412.576384) (xy 303.56498 -412.540693)
			(xy 303.610831 -412.511226) (xy 303.66041 -412.488585) (xy 303.712706 -412.473231) (xy 303.766654 -412.465475)
			(xy 303.793906 -412.465012) (xy 304.657506 -412.465012) (xy 304.684758 -412.465458) (xy 304.738708 -412.473216)
			(xy 304.791005 -412.488572) (xy 304.840584 -412.511215) (xy 304.886436 -412.540683) (xy 304.927628 -412.576376)
			(xy 304.963321 -412.617569) (xy 304.992788 -412.663421) (xy 305.01543 -412.713001) (xy 305.030785 -412.765298)
			(xy 305.038542 -412.819248) (xy 305.038542 -412.873752) (xy 305.038542 -412.873754) (xy 306.476075 -412.873754)
			(xy 306.476075 -412.819246) (xy 306.483833 -412.765294) (xy 306.499191 -412.712996) (xy 306.521835 -412.663415)
			(xy 306.551306 -412.617562) (xy 306.587003 -412.57637) (xy 306.628199 -412.540679) (xy 306.674055 -412.511213)
			(xy 306.723639 -412.488575) (xy 306.775939 -412.473223) (xy 306.829892 -412.465472) (xy 306.857146 -412.465012)
			(xy 307.720746 -412.465012) (xy 307.747997 -412.465461) (xy 307.801942 -412.473223) (xy 307.854234 -412.488583)
			(xy 307.903808 -412.511228) (xy 307.949655 -412.540697) (xy 307.990842 -412.576391) (xy 308.02653 -412.617582)
			(xy 308.055994 -412.663432) (xy 308.078633 -412.713009) (xy 308.093987 -412.765303) (xy 308.101742 -412.819249)
			(xy 308.101742 -412.873749) (xy 309.539398 -412.873749) (xy 309.539398 -412.819251) (xy 309.547154 -412.765307)
			(xy 309.562508 -412.713016) (xy 309.585146 -412.663443) (xy 309.61461 -412.617596) (xy 309.650298 -412.576408)
			(xy 309.691484 -412.540718) (xy 309.73733 -412.511253) (xy 309.786903 -412.488612) (xy 309.839194 -412.473257)
			(xy 309.893137 -412.465499) (xy 309.920386 -412.465012) (xy 310.783986 -412.465012) (xy 310.811241 -412.465434)
			(xy 310.865196 -412.47319) (xy 310.917499 -412.488545) (xy 310.967083 -412.511188) (xy 311.012941 -412.540657)
			(xy 311.054137 -412.576353) (xy 311.089834 -412.617548) (xy 311.119305 -412.663405) (xy 311.14195 -412.712988)
			(xy 311.157307 -412.76529) (xy 311.165065 -412.819245) (xy 311.165065 -412.873753) (xy 312.602575 -412.873753)
			(xy 312.602575 -412.819247) (xy 312.610333 -412.765297) (xy 312.625689 -412.713) (xy 312.648332 -412.663421)
			(xy 312.677801 -412.617569) (xy 312.713496 -412.576377) (xy 312.754689 -412.540686) (xy 312.800543 -412.51122)
			(xy 312.850124 -412.48858) (xy 312.902422 -412.473227) (xy 312.956373 -412.465474) (xy 312.983626 -412.465012)
			(xy 313.847226 -412.465012) (xy 313.874477 -412.46546) (xy 313.928425 -412.47322) (xy 313.98072 -412.488578)
			(xy 314.030296 -412.511222) (xy 314.076146 -412.54069) (xy 314.117335 -412.576383) (xy 314.153026 -412.617575)
			(xy 314.182491 -412.663427) (xy 314.205131 -412.713005) (xy 314.220486 -412.7653) (xy 314.228242 -412.819249)
			(xy 314.228242 -412.873748) (xy 315.665898 -412.873748) (xy 315.665898 -412.819252) (xy 315.673653 -412.76531)
			(xy 315.689006 -412.713021) (xy 315.711643 -412.663448) (xy 315.741105 -412.617602) (xy 315.776791 -412.576415)
			(xy 315.817975 -412.540725) (xy 315.863818 -412.51126) (xy 315.913389 -412.488618) (xy 315.965677 -412.473261)
			(xy 316.019618 -412.465501) (xy 316.046866 -412.465012) (xy 316.910466 -412.465012) (xy 316.937722 -412.465433)
			(xy 316.991679 -412.473186) (xy 317.043984 -412.48854) (xy 317.093571 -412.511182) (xy 317.139431 -412.54065)
			(xy 317.18063 -412.576346) (xy 317.216329 -412.617542) (xy 317.245802 -412.663399) (xy 317.268448 -412.712984)
			(xy 317.283807 -412.765287) (xy 317.291565 -412.819244) (xy 317.291565 -412.873752) (xy 318.729075 -412.873752)
			(xy 318.729075 -412.819248) (xy 318.736832 -412.7653) (xy 318.752188 -412.713004) (xy 318.774829 -412.663426)
			(xy 318.804296 -412.617575) (xy 318.839989 -412.576384) (xy 318.88118 -412.540693) (xy 318.927031 -412.511226)
			(xy 318.97661 -412.488585) (xy 319.028906 -412.473231) (xy 319.082854 -412.465475) (xy 319.110106 -412.465012)
			(xy 319.973706 -412.465012) (xy 320.000958 -412.465458) (xy 320.054908 -412.473216) (xy 320.107205 -412.488572)
			(xy 320.156784 -412.511215) (xy 320.202636 -412.540683) (xy 320.243828 -412.576376) (xy 320.279521 -412.617569)
			(xy 320.308988 -412.663421) (xy 320.33163 -412.713001) (xy 320.346985 -412.765298) (xy 320.354742 -412.819248)
			(xy 320.354742 -412.873752) (xy 320.354742 -412.873754) (xy 321.792275 -412.873754) (xy 321.792275 -412.819246)
			(xy 321.800033 -412.765294) (xy 321.815391 -412.712996) (xy 321.838035 -412.663415) (xy 321.867506 -412.617562)
			(xy 321.903203 -412.57637) (xy 321.944399 -412.540679) (xy 321.990255 -412.511213) (xy 322.039839 -412.488575)
			(xy 322.092139 -412.473223) (xy 322.146092 -412.465472) (xy 322.173346 -412.465012) (xy 323.036946 -412.465012)
			(xy 323.064197 -412.465461) (xy 323.118142 -412.473223) (xy 323.170434 -412.488583) (xy 323.220008 -412.511228)
			(xy 323.265855 -412.540697) (xy 323.307042 -412.576391) (xy 323.34273 -412.617582) (xy 323.372194 -412.663432)
			(xy 323.394833 -412.713009) (xy 323.410187 -412.765303) (xy 323.417942 -412.819249) (xy 323.417942 -412.873749)
			(xy 324.855598 -412.873749) (xy 324.855598 -412.819251) (xy 324.863354 -412.765307) (xy 324.878708 -412.713016)
			(xy 324.901346 -412.663443) (xy 324.93081 -412.617596) (xy 324.966498 -412.576408) (xy 325.007684 -412.540718)
			(xy 325.05353 -412.511253) (xy 325.103103 -412.488612) (xy 325.155394 -412.473257) (xy 325.209337 -412.465499)
			(xy 325.236586 -412.465012) (xy 326.100186 -412.465012) (xy 326.127441 -412.465434) (xy 326.181396 -412.47319)
			(xy 326.233699 -412.488545) (xy 326.283283 -412.511188) (xy 326.329141 -412.540657) (xy 326.370337 -412.576353)
			(xy 326.406034 -412.617548) (xy 326.435505 -412.663405) (xy 326.45815 -412.712988) (xy 326.473507 -412.76529)
			(xy 326.481265 -412.819245) (xy 326.481265 -412.873753) (xy 327.918775 -412.873753) (xy 327.918775 -412.819247)
			(xy 327.926533 -412.765297) (xy 327.941889 -412.713) (xy 327.964532 -412.663421) (xy 327.994001 -412.617569)
			(xy 328.029696 -412.576377) (xy 328.070889 -412.540686) (xy 328.116743 -412.51122) (xy 328.166324 -412.48858)
			(xy 328.218622 -412.473227) (xy 328.272573 -412.465474) (xy 328.299826 -412.465012) (xy 329.163426 -412.465012)
			(xy 329.190677 -412.46546) (xy 329.244625 -412.47322) (xy 329.29692 -412.488578) (xy 329.346496 -412.511222)
			(xy 329.392346 -412.54069) (xy 329.433535 -412.576383) (xy 329.469226 -412.617575) (xy 329.498691 -412.663427)
			(xy 329.521331 -412.713005) (xy 329.536686 -412.7653) (xy 329.544442 -412.819249) (xy 329.544442 -412.873748)
			(xy 330.982098 -412.873748) (xy 330.982098 -412.819252) (xy 330.989853 -412.76531) (xy 331.005206 -412.713021)
			(xy 331.027843 -412.663448) (xy 331.057305 -412.617602) (xy 331.092991 -412.576415) (xy 331.134175 -412.540725)
			(xy 331.180018 -412.51126) (xy 331.229589 -412.488618) (xy 331.281877 -412.473261) (xy 331.335818 -412.465501)
			(xy 331.363066 -412.465012) (xy 332.226666 -412.465012) (xy 332.253922 -412.465433) (xy 332.307879 -412.473186)
			(xy 332.360184 -412.48854) (xy 332.409771 -412.511182) (xy 332.455631 -412.54065) (xy 332.49683 -412.576346)
			(xy 332.532529 -412.617542) (xy 332.562002 -412.663399) (xy 332.584648 -412.712984) (xy 332.600007 -412.765287)
			(xy 332.607765 -412.819244) (xy 332.607765 -412.873752) (xy 334.045275 -412.873752) (xy 334.045275 -412.819248)
			(xy 334.053032 -412.7653) (xy 334.068388 -412.713004) (xy 334.091029 -412.663426) (xy 334.120496 -412.617575)
			(xy 334.156189 -412.576384) (xy 334.19738 -412.540693) (xy 334.243231 -412.511226) (xy 334.29281 -412.488585)
			(xy 334.345106 -412.473231) (xy 334.399054 -412.465475) (xy 334.426306 -412.465012) (xy 335.289906 -412.465012)
			(xy 335.317158 -412.465458) (xy 335.371108 -412.473216) (xy 335.423405 -412.488572) (xy 335.472984 -412.511215)
			(xy 335.518836 -412.540683) (xy 335.560028 -412.576376) (xy 335.595721 -412.617569) (xy 335.625188 -412.663421)
			(xy 335.64783 -412.713001) (xy 335.663185 -412.765298) (xy 335.670942 -412.819248) (xy 335.670942 -412.873752)
			(xy 335.670942 -412.873754) (xy 337.108475 -412.873754) (xy 337.108475 -412.819246) (xy 337.116233 -412.765294)
			(xy 337.131591 -412.712996) (xy 337.154235 -412.663415) (xy 337.183706 -412.617562) (xy 337.219403 -412.57637)
			(xy 337.260599 -412.540679) (xy 337.306455 -412.511213) (xy 337.356039 -412.488575) (xy 337.408339 -412.473223)
			(xy 337.462292 -412.465472) (xy 337.489546 -412.465012) (xy 338.353146 -412.465012) (xy 338.380397 -412.465461)
			(xy 338.434342 -412.473223) (xy 338.486634 -412.488583) (xy 338.536208 -412.511228) (xy 338.582055 -412.540697)
			(xy 338.623242 -412.576391) (xy 338.65893 -412.617582) (xy 338.688394 -412.663432) (xy 338.711033 -412.713009)
			(xy 338.726387 -412.765303) (xy 338.734142 -412.819249) (xy 338.734142 -412.873749) (xy 340.171798 -412.873749)
			(xy 340.171798 -412.819251) (xy 340.179554 -412.765307) (xy 340.194908 -412.713016) (xy 340.217546 -412.663443)
			(xy 340.24701 -412.617596) (xy 340.282698 -412.576408) (xy 340.323884 -412.540718) (xy 340.36973 -412.511253)
			(xy 340.419303 -412.488612) (xy 340.471594 -412.473257) (xy 340.525537 -412.465499) (xy 340.552786 -412.465012)
			(xy 341.416386 -412.465012) (xy 341.443641 -412.465434) (xy 341.497596 -412.47319) (xy 341.549899 -412.488545)
			(xy 341.599483 -412.511188) (xy 341.645341 -412.540657) (xy 341.686537 -412.576353) (xy 341.722234 -412.617548)
			(xy 341.751705 -412.663405) (xy 341.77435 -412.712988) (xy 341.789707 -412.76529) (xy 341.797465 -412.819245)
			(xy 341.797465 -412.873753) (xy 343.234975 -412.873753) (xy 343.234975 -412.819247) (xy 343.242733 -412.765297)
			(xy 343.258089 -412.713) (xy 343.280732 -412.663421) (xy 343.310201 -412.617569) (xy 343.345896 -412.576377)
			(xy 343.387089 -412.540686) (xy 343.432943 -412.51122) (xy 343.482524 -412.48858) (xy 343.534822 -412.473227)
			(xy 343.588773 -412.465474) (xy 343.616026 -412.465012) (xy 344.479626 -412.465012) (xy 344.506877 -412.46546)
			(xy 344.560825 -412.47322) (xy 344.61312 -412.488578) (xy 344.662696 -412.511222) (xy 344.708546 -412.54069)
			(xy 344.749735 -412.576383) (xy 344.785426 -412.617575) (xy 344.814891 -412.663427) (xy 344.837531 -412.713005)
			(xy 344.852886 -412.7653) (xy 344.860642 -412.819249) (xy 344.860642 -412.873748) (xy 346.298298 -412.873748)
			(xy 346.298298 -412.819252) (xy 346.306053 -412.76531) (xy 346.321406 -412.713021) (xy 346.344043 -412.663448)
			(xy 346.373505 -412.617602) (xy 346.409191 -412.576415) (xy 346.450375 -412.540725) (xy 346.496218 -412.51126)
			(xy 346.545789 -412.488618) (xy 346.598077 -412.473261) (xy 346.652018 -412.465501) (xy 346.679266 -412.465012)
			(xy 347.542866 -412.465012) (xy 347.570122 -412.465433) (xy 347.624079 -412.473186) (xy 347.676384 -412.48854)
			(xy 347.725971 -412.511182) (xy 347.771831 -412.54065) (xy 347.81303 -412.576346) (xy 347.848729 -412.617542)
			(xy 347.878202 -412.663399) (xy 347.900848 -412.712984) (xy 347.916207 -412.765287) (xy 347.923965 -412.819244)
			(xy 347.923965 -412.873752) (xy 349.361475 -412.873752) (xy 349.361475 -412.819248) (xy 349.369232 -412.7653)
			(xy 349.384588 -412.713004) (xy 349.407229 -412.663426) (xy 349.436696 -412.617575) (xy 349.472389 -412.576384)
			(xy 349.51358 -412.540693) (xy 349.559431 -412.511226) (xy 349.60901 -412.488585) (xy 349.661306 -412.473231)
			(xy 349.715254 -412.465475) (xy 349.742506 -412.465012) (xy 350.606106 -412.465012) (xy 350.633358 -412.465458)
			(xy 350.687308 -412.473216) (xy 350.739605 -412.488572) (xy 350.789184 -412.511215) (xy 350.835036 -412.540683)
			(xy 350.876228 -412.576376) (xy 350.911921 -412.617569) (xy 350.941388 -412.663421) (xy 350.96403 -412.713001)
			(xy 350.979385 -412.765298) (xy 350.987142 -412.819248) (xy 350.987142 -412.873752) (xy 370.513075 -412.873752)
			(xy 370.513075 -412.819248) (xy 370.520832 -412.7653) (xy 370.536187 -412.713005) (xy 370.558829 -412.663427)
			(xy 370.588295 -412.617576) (xy 370.623987 -412.576386) (xy 370.665178 -412.540694) (xy 370.711029 -412.511228)
			(xy 370.760607 -412.488587) (xy 370.812902 -412.473231) (xy 370.86685 -412.465475) (xy 370.894102 -412.465012)
			(xy 371.757702 -412.465012) (xy 371.784955 -412.465458) (xy 371.838905 -412.473215) (xy 371.891202 -412.488571)
			(xy 371.940782 -412.511214) (xy 371.986634 -412.540682) (xy 372.027826 -412.576375) (xy 372.06352 -412.617567)
			(xy 372.092987 -412.66342) (xy 372.115629 -412.713) (xy 372.130985 -412.765297) (xy 372.138742 -412.819247)
			(xy 372.138742 -412.873753) (xy 373.576275 -412.873753) (xy 373.576275 -412.819247) (xy 373.584033 -412.765295)
			(xy 373.59939 -412.712996) (xy 373.622035 -412.663416) (xy 373.651505 -412.617563) (xy 373.687201 -412.576372)
			(xy 373.728397 -412.54068) (xy 373.774253 -412.511215) (xy 373.823836 -412.488576) (xy 373.876136 -412.473224)
			(xy 373.930089 -412.465472) (xy 373.957342 -412.465012) (xy 374.820942 -412.465012) (xy 374.848193 -412.465461)
			(xy 374.902139 -412.473222) (xy 374.954431 -412.488582) (xy 375.004006 -412.511227) (xy 375.049853 -412.540696)
			(xy 375.091041 -412.576389) (xy 375.126729 -412.61758) (xy 375.156193 -412.663431) (xy 375.178833 -412.713008)
			(xy 375.194186 -412.765302) (xy 375.201942 -412.819249) (xy 375.201942 -412.873749) (xy 376.639598 -412.873749)
			(xy 376.639598 -412.819251) (xy 376.647354 -412.765308) (xy 376.662707 -412.713017) (xy 376.685346 -412.663444)
			(xy 376.714809 -412.617597) (xy 376.750497 -412.576409) (xy 376.791682 -412.54072) (xy 376.837528 -412.511254)
			(xy 376.8871 -412.488613) (xy 376.93939 -412.473258) (xy 376.993333 -412.465499) (xy 377.020582 -412.465012)
			(xy 377.884182 -412.465012) (xy 377.911437 -412.465434) (xy 377.965393 -412.473189) (xy 378.017696 -412.488544)
			(xy 378.067281 -412.511187) (xy 378.113139 -412.540656) (xy 378.154336 -412.576352) (xy 378.190033 -412.617547)
			(xy 378.219504 -412.663403) (xy 378.242149 -412.712987) (xy 378.257507 -412.765289) (xy 378.265265 -412.819245)
			(xy 378.265265 -412.873752) (xy 379.702775 -412.873752) (xy 379.702775 -412.819248) (xy 379.710532 -412.765298)
			(xy 379.725889 -412.713001) (xy 379.748532 -412.663422) (xy 379.778 -412.61757) (xy 379.813694 -412.576379)
			(xy 379.854888 -412.540687) (xy 379.900741 -412.511221) (xy 379.950321 -412.488581) (xy 380.002619 -412.473228)
			(xy 380.05657 -412.465474) (xy 380.083822 -412.465012) (xy 380.947422 -412.465012) (xy 380.974674 -412.465459)
			(xy 381.028622 -412.473219) (xy 381.080917 -412.488577) (xy 381.130494 -412.51122) (xy 381.176344 -412.540689)
			(xy 381.217534 -412.576382) (xy 381.253225 -412.617574) (xy 381.28269 -412.663426) (xy 381.305331 -412.713004)
			(xy 381.320686 -412.7653) (xy 381.328442 -412.819248) (xy 381.328442 -412.873748) (xy 382.766098 -412.873748)
			(xy 382.766098 -412.819252) (xy 382.773853 -412.76531) (xy 382.789206 -412.713022) (xy 382.811843 -412.663449)
			(xy 382.841304 -412.617603) (xy 382.876989 -412.576416) (xy 382.918173 -412.540727) (xy 382.964016 -412.511261)
			(xy 383.013586 -412.488619) (xy 383.065873 -412.473261) (xy 383.119814 -412.465501) (xy 383.147062 -412.465012)
			(xy 384.010662 -412.465012) (xy 384.037918 -412.465432) (xy 384.091876 -412.473185) (xy 384.144181 -412.488539)
			(xy 384.193769 -412.51118) (xy 384.239629 -412.540649) (xy 384.280829 -412.576345) (xy 384.316528 -412.61754)
			(xy 384.346001 -412.663398) (xy 384.368648 -412.712983) (xy 384.384007 -412.765287) (xy 384.391765 -412.819244)
			(xy 384.391765 -412.873752) (xy 385.829275 -412.873752) (xy 385.829275 -412.819248) (xy 385.837032 -412.7653)
			(xy 385.852387 -412.713005) (xy 385.875029 -412.663427) (xy 385.904495 -412.617576) (xy 385.940187 -412.576386)
			(xy 385.981378 -412.540694) (xy 386.027229 -412.511228) (xy 386.076807 -412.488587) (xy 386.129102 -412.473231)
			(xy 386.18305 -412.465475) (xy 386.210302 -412.465012) (xy 387.073902 -412.465012) (xy 387.101155 -412.465458)
			(xy 387.155105 -412.473215) (xy 387.207402 -412.488571) (xy 387.256982 -412.511214) (xy 387.302834 -412.540682)
			(xy 387.344026 -412.576375) (xy 387.37972 -412.617567) (xy 387.409187 -412.66342) (xy 387.431829 -412.713)
			(xy 387.447185 -412.765297) (xy 387.454942 -412.819247) (xy 387.454942 -412.873753) (xy 388.892475 -412.873753)
			(xy 388.892475 -412.819247) (xy 388.900233 -412.765295) (xy 388.91559 -412.712996) (xy 388.938235 -412.663416)
			(xy 388.967705 -412.617563) (xy 389.003401 -412.576372) (xy 389.044597 -412.54068) (xy 389.090453 -412.511215)
			(xy 389.140036 -412.488576) (xy 389.192336 -412.473224) (xy 389.246289 -412.465472) (xy 389.273542 -412.465012)
			(xy 390.137142 -412.465012) (xy 390.164393 -412.465461) (xy 390.218339 -412.473222) (xy 390.270631 -412.488582)
			(xy 390.320206 -412.511227) (xy 390.366053 -412.540696) (xy 390.407241 -412.576389) (xy 390.442929 -412.61758)
			(xy 390.472393 -412.663431) (xy 390.495033 -412.713008) (xy 390.510386 -412.765302) (xy 390.518142 -412.819249)
			(xy 390.518142 -412.873749) (xy 391.955798 -412.873749) (xy 391.955798 -412.819251) (xy 391.963554 -412.765308)
			(xy 391.978907 -412.713017) (xy 392.001546 -412.663444) (xy 392.031009 -412.617597) (xy 392.066697 -412.576409)
			(xy 392.107882 -412.54072) (xy 392.153728 -412.511254) (xy 392.2033 -412.488613) (xy 392.25559 -412.473258)
			(xy 392.309533 -412.465499) (xy 392.336782 -412.465012) (xy 393.200382 -412.465012) (xy 393.227637 -412.465434)
			(xy 393.281593 -412.473189) (xy 393.333896 -412.488544) (xy 393.383481 -412.511187) (xy 393.429339 -412.540656)
			(xy 393.470536 -412.576352) (xy 393.506233 -412.617547) (xy 393.535704 -412.663403) (xy 393.558349 -412.712987)
			(xy 393.573707 -412.765289) (xy 393.581465 -412.819245) (xy 393.581465 -412.873752) (xy 395.018975 -412.873752)
			(xy 395.018975 -412.819248) (xy 395.026732 -412.765298) (xy 395.042089 -412.713001) (xy 395.064732 -412.663422)
			(xy 395.0942 -412.61757) (xy 395.129894 -412.576379) (xy 395.171088 -412.540687) (xy 395.216941 -412.511221)
			(xy 395.266521 -412.488581) (xy 395.318819 -412.473228) (xy 395.37277 -412.465474) (xy 395.400022 -412.465012)
			(xy 396.263622 -412.465012) (xy 396.290874 -412.465459) (xy 396.344822 -412.473219) (xy 396.397117 -412.488577)
			(xy 396.446694 -412.51122) (xy 396.492544 -412.540689) (xy 396.533734 -412.576382) (xy 396.569425 -412.617574)
			(xy 396.59889 -412.663426) (xy 396.621531 -412.713004) (xy 396.636886 -412.7653) (xy 396.644642 -412.819248)
			(xy 396.644642 -412.873748) (xy 398.082298 -412.873748) (xy 398.082298 -412.819252) (xy 398.090053 -412.76531)
			(xy 398.105406 -412.713022) (xy 398.128043 -412.663449) (xy 398.157504 -412.617603) (xy 398.193189 -412.576416)
			(xy 398.234373 -412.540727) (xy 398.280216 -412.511261) (xy 398.329786 -412.488619) (xy 398.382073 -412.473261)
			(xy 398.436014 -412.465501) (xy 398.463262 -412.465012) (xy 399.326862 -412.465012) (xy 399.354118 -412.465432)
			(xy 399.408076 -412.473185) (xy 399.460381 -412.488539) (xy 399.509969 -412.51118) (xy 399.555829 -412.540649)
			(xy 399.597029 -412.576345) (xy 399.632728 -412.61754) (xy 399.662201 -412.663398) (xy 399.684848 -412.712983)
			(xy 399.700207 -412.765287) (xy 399.707965 -412.819244) (xy 399.707965 -412.873752) (xy 401.145475 -412.873752)
			(xy 401.145475 -412.819248) (xy 401.153232 -412.7653) (xy 401.168587 -412.713005) (xy 401.191229 -412.663427)
			(xy 401.220695 -412.617576) (xy 401.256387 -412.576386) (xy 401.297578 -412.540694) (xy 401.343429 -412.511228)
			(xy 401.393007 -412.488587) (xy 401.445302 -412.473231) (xy 401.49925 -412.465475) (xy 401.526502 -412.465012)
			(xy 402.390102 -412.465012) (xy 402.417355 -412.465458) (xy 402.471305 -412.473215) (xy 402.523602 -412.488571)
			(xy 402.573182 -412.511214) (xy 402.619034 -412.540682) (xy 402.660226 -412.576375) (xy 402.69592 -412.617567)
			(xy 402.725387 -412.66342) (xy 402.748029 -412.713) (xy 402.763385 -412.765297) (xy 402.771142 -412.819247)
			(xy 402.771142 -412.873753) (xy 404.208675 -412.873753) (xy 404.208675 -412.819247) (xy 404.216433 -412.765295)
			(xy 404.23179 -412.712996) (xy 404.254435 -412.663416) (xy 404.283905 -412.617563) (xy 404.319601 -412.576372)
			(xy 404.360797 -412.54068) (xy 404.406653 -412.511215) (xy 404.456236 -412.488576) (xy 404.508536 -412.473224)
			(xy 404.562489 -412.465472) (xy 404.589742 -412.465012) (xy 405.453342 -412.465012) (xy 405.480593 -412.465461)
			(xy 405.534539 -412.473222) (xy 405.586831 -412.488582) (xy 405.636406 -412.511227) (xy 405.682253 -412.540696)
			(xy 405.723441 -412.576389) (xy 405.759129 -412.61758) (xy 405.788593 -412.663431) (xy 405.811233 -412.713008)
			(xy 405.826586 -412.765302) (xy 405.834342 -412.819249) (xy 405.834342 -412.873749) (xy 407.271998 -412.873749)
			(xy 407.271998 -412.819251) (xy 407.279754 -412.765308) (xy 407.295107 -412.713017) (xy 407.317746 -412.663444)
			(xy 407.347209 -412.617597) (xy 407.382897 -412.576409) (xy 407.424082 -412.54072) (xy 407.469928 -412.511254)
			(xy 407.5195 -412.488613) (xy 407.57179 -412.473258) (xy 407.625733 -412.465499) (xy 407.652982 -412.465012)
			(xy 408.516582 -412.465012) (xy 408.543837 -412.465434) (xy 408.597793 -412.473189) (xy 408.650096 -412.488544)
			(xy 408.699681 -412.511187) (xy 408.745539 -412.540656) (xy 408.786736 -412.576352) (xy 408.822433 -412.617547)
			(xy 408.851904 -412.663403) (xy 408.874549 -412.712987) (xy 408.889907 -412.765289) (xy 408.897665 -412.819245)
			(xy 408.897665 -412.873752) (xy 410.335175 -412.873752) (xy 410.335175 -412.819248) (xy 410.342932 -412.765298)
			(xy 410.358289 -412.713001) (xy 410.380932 -412.663422) (xy 410.4104 -412.61757) (xy 410.446094 -412.576379)
			(xy 410.487288 -412.540687) (xy 410.533141 -412.511221) (xy 410.582721 -412.488581) (xy 410.635019 -412.473228)
			(xy 410.68897 -412.465474) (xy 410.716222 -412.465012) (xy 411.579822 -412.465012) (xy 411.607074 -412.465459)
			(xy 411.661022 -412.473219) (xy 411.713317 -412.488577) (xy 411.762894 -412.51122) (xy 411.808744 -412.540689)
			(xy 411.849934 -412.576382) (xy 411.885625 -412.617574) (xy 411.91509 -412.663426) (xy 411.937731 -412.713004)
			(xy 411.953086 -412.7653) (xy 411.960842 -412.819248) (xy 411.960842 -412.873748) (xy 413.398498 -412.873748)
			(xy 413.398498 -412.819252) (xy 413.406253 -412.76531) (xy 413.421606 -412.713022) (xy 413.444243 -412.663449)
			(xy 413.473704 -412.617603) (xy 413.509389 -412.576416) (xy 413.550573 -412.540727) (xy 413.596416 -412.511261)
			(xy 413.645986 -412.488619) (xy 413.698273 -412.473261) (xy 413.752214 -412.465501) (xy 413.779462 -412.465012)
			(xy 414.643062 -412.465012) (xy 414.670318 -412.465432) (xy 414.724276 -412.473185) (xy 414.776581 -412.488539)
			(xy 414.826169 -412.51118) (xy 414.872029 -412.540649) (xy 414.913229 -412.576345) (xy 414.948928 -412.61754)
			(xy 414.978401 -412.663398) (xy 415.001048 -412.712983) (xy 415.016407 -412.765287) (xy 415.024165 -412.819244)
			(xy 415.024165 -412.873752) (xy 416.461675 -412.873752) (xy 416.461675 -412.819248) (xy 416.469432 -412.7653)
			(xy 416.484787 -412.713005) (xy 416.507429 -412.663427) (xy 416.536895 -412.617576) (xy 416.572587 -412.576386)
			(xy 416.613778 -412.540694) (xy 416.659629 -412.511228) (xy 416.709207 -412.488587) (xy 416.761502 -412.473231)
			(xy 416.81545 -412.465475) (xy 416.842702 -412.465012) (xy 417.706302 -412.465012) (xy 417.733555 -412.465458)
			(xy 417.787505 -412.473215) (xy 417.839802 -412.488571) (xy 417.889382 -412.511214) (xy 417.935234 -412.540682)
			(xy 417.976426 -412.576375) (xy 418.01212 -412.617567) (xy 418.041587 -412.66342) (xy 418.064229 -412.713)
			(xy 418.079585 -412.765297) (xy 418.087342 -412.819247) (xy 418.087342 -412.873753) (xy 418.079585 -412.927703)
			(xy 418.064229 -412.98) (xy 418.041587 -413.02958) (xy 418.01212 -413.075433) (xy 417.976426 -413.116625)
			(xy 417.935234 -413.152318) (xy 417.90754 -413.170116) (xy 422.998658 -413.170116) (xy 423.00263 -412.991873)
			(xy 423.014538 -412.813984) (xy 423.034359 -412.636802) (xy 423.062053 -412.460678) (xy 423.097565 -412.285963)
			(xy 423.140825 -412.113004) (xy 423.191747 -411.942143) (xy 423.25023 -411.773721) (xy 423.316157 -411.608071)
			(xy 423.389398 -411.445522) (xy 423.469808 -411.286397) (xy 423.557226 -411.131012) (xy 423.651479 -410.979676)
			(xy 423.75238 -410.832688) (xy 423.859729 -410.690341) (xy 423.973312 -410.552918) (xy 424.092905 -410.420691)
			(xy 424.218269 -410.293922) (xy 424.349156 -410.172864) (xy 424.485305 -410.057757) (xy 424.626447 -409.948829)
			(xy 424.772302 -409.846297) (xy 424.922579 -409.750363) (xy 425.07698 -409.66122) (xy 425.235199 -409.579043)
			(xy 425.396922 -409.503995) (xy 425.561827 -409.436227) (xy 425.729588 -409.375871) (xy 425.899871 -409.323049)
			(xy 426.072338 -409.277865) (xy 426.246646 -409.240408) (xy 426.42245 -409.210754) (xy 426.5994 -409.188961)
			(xy 426.777146 -409.175071) (xy 426.955333 -409.169114) (xy 427.13361 -409.1711) (xy 427.311621 -409.181026)
			(xy 427.489013 -409.198872) (xy 427.665433 -409.224602) (xy 427.840533 -409.258166) (xy 428.013964 -409.299496)
			(xy 428.185381 -409.348512) (xy 428.354444 -409.405114) (xy 428.520819 -409.469192) (xy 428.684173 -409.540618)
			(xy 428.844184 -409.61925) (xy 429.000533 -409.704931) (xy 429.15291 -409.797493) (xy 429.301013 -409.89675)
			(xy 429.444547 -410.002507) (xy 429.583227 -410.114552) (xy 429.716778 -410.232664) (xy 429.844935 -410.356608)
			(xy 429.967444 -410.486138) (xy 430.084061 -410.620997) (xy 430.194554 -410.760917) (xy 430.298705 -410.90562)
			(xy 430.396307 -411.054819) (xy 430.487165 -411.208218) (xy 430.571099 -411.365512) (xy 430.647944 -411.526388)
			(xy 430.717545 -411.690529) (xy 430.779766 -411.857606) (xy 430.834482 -412.02729) (xy 430.881584 -412.199243)
			(xy 430.92098 -412.373123) (xy 430.952591 -412.548586) (xy 430.976355 -412.725282) (xy 430.992223 -412.902862)
			(xy 431.000165 -413.080972) (xy 431.000662 -413.170116) (xy 431.000165 -413.25926) (xy 430.992223 -413.43737)
			(xy 430.976355 -413.61495) (xy 430.952591 -413.791646) (xy 430.92098 -413.967109) (xy 430.881584 -414.140989)
			(xy 430.834482 -414.312942) (xy 430.779766 -414.482626) (xy 430.717545 -414.649703) (xy 430.647944 -414.813844)
			(xy 430.571099 -414.97472) (xy 430.487165 -415.132014) (xy 430.396307 -415.285413) (xy 430.298705 -415.434612)
			(xy 430.194554 -415.579315) (xy 430.084061 -415.719235) (xy 429.967444 -415.854094) (xy 429.844935 -415.983624)
			(xy 429.716778 -416.107568) (xy 429.583227 -416.22568) (xy 429.444547 -416.337725) (xy 429.301013 -416.443482)
			(xy 429.15291 -416.542739) (xy 429.000533 -416.635301) (xy 428.844184 -416.720982) (xy 428.684173 -416.799614)
			(xy 428.520819 -416.87104) (xy 428.354444 -416.935118) (xy 428.185381 -416.99172) (xy 428.013964 -417.040736)
			(xy 427.840533 -417.082066) (xy 427.665433 -417.11563) (xy 427.489013 -417.14136) (xy 427.311621 -417.159206)
			(xy 427.13361 -417.169132) (xy 426.955333 -417.171118) (xy 426.777146 -417.165161) (xy 426.5994 -417.151271)
			(xy 426.42245 -417.129478) (xy 426.246646 -417.099824) (xy 426.072338 -417.062367) (xy 425.899871 -417.017183)
			(xy 425.729588 -416.964361) (xy 425.561827 -416.904005) (xy 425.396922 -416.836237) (xy 425.235199 -416.761189)
			(xy 425.07698 -416.679012) (xy 424.922579 -416.589869) (xy 424.772302 -416.493935) (xy 424.626447 -416.391403)
			(xy 424.485305 -416.282475) (xy 424.349156 -416.167368) (xy 424.218269 -416.04631) (xy 424.092905 -415.919541)
			(xy 423.973312 -415.787314) (xy 423.859729 -415.649891) (xy 423.75238 -415.507544) (xy 423.651479 -415.360556)
			(xy 423.557226 -415.20922) (xy 423.469808 -415.053835) (xy 423.389398 -414.89471) (xy 423.316157 -414.732161)
			(xy 423.25023 -414.566511) (xy 423.191747 -414.398089) (xy 423.140825 -414.227228) (xy 423.097565 -414.054269)
			(xy 423.062053 -413.879554) (xy 423.034359 -413.70343) (xy 423.014538 -413.526248) (xy 423.00263 -413.348359)
			(xy 422.998658 -413.170116) (xy 417.90754 -413.170116) (xy 417.889382 -413.181786) (xy 417.839802 -413.204429)
			(xy 417.787505 -413.219785) (xy 417.733555 -413.227542) (xy 417.706302 -413.228028) (xy 416.842702 -413.228028)
			(xy 416.81545 -413.227525) (xy 416.761502 -413.219769) (xy 416.709207 -413.204413) (xy 416.659629 -413.181772)
			(xy 416.613778 -413.152306) (xy 416.572587 -413.116614) (xy 416.536895 -413.075424) (xy 416.507429 -413.029573)
			(xy 416.484787 -412.979995) (xy 416.469432 -412.9277) (xy 416.461675 -412.873752) (xy 415.024165 -412.873752)
			(xy 415.024165 -412.873756) (xy 415.016407 -412.927713) (xy 415.001048 -412.980017) (xy 414.978401 -413.029602)
			(xy 414.948928 -413.07546) (xy 414.913229 -413.116655) (xy 414.872029 -413.152351) (xy 414.826169 -413.18182)
			(xy 414.776581 -413.204461) (xy 414.724276 -413.219815) (xy 414.670318 -413.227568) (xy 414.643062 -413.228028)
			(xy 413.779462 -413.228028) (xy 413.752214 -413.227499) (xy 413.698273 -413.219739) (xy 413.645986 -413.204381)
			(xy 413.596416 -413.181739) (xy 413.550573 -413.152273) (xy 413.509389 -413.116584) (xy 413.473704 -413.075397)
			(xy 413.444243 -413.029551) (xy 413.421606 -412.979978) (xy 413.406253 -412.92769) (xy 413.398498 -412.873748)
			(xy 411.960842 -412.873748) (xy 411.960842 -412.873752) (xy 411.953086 -412.9277) (xy 411.937731 -412.979996)
			(xy 411.91509 -413.029574) (xy 411.885625 -413.075426) (xy 411.849934 -413.116618) (xy 411.808744 -413.152311)
			(xy 411.762894 -413.18178) (xy 411.713317 -413.204423) (xy 411.661022 -413.219781) (xy 411.607074 -413.227541)
			(xy 411.579822 -413.228028) (xy 410.716222 -413.228028) (xy 410.68897 -413.227526) (xy 410.635019 -413.219772)
			(xy 410.582721 -413.204419) (xy 410.533141 -413.181779) (xy 410.487288 -413.152313) (xy 410.446094 -413.116621)
			(xy 410.4104 -413.07543) (xy 410.380932 -413.029578) (xy 410.358289 -412.979999) (xy 410.342932 -412.927702)
			(xy 410.335175 -412.873752) (xy 408.897665 -412.873752) (xy 408.897665 -412.873755) (xy 408.889907 -412.927711)
			(xy 408.874549 -412.980013) (xy 408.851904 -413.029597) (xy 408.822433 -413.075453) (xy 408.786736 -413.116648)
			(xy 408.745539 -413.152344) (xy 408.699681 -413.181813) (xy 408.650096 -413.204456) (xy 408.597793 -413.219811)
			(xy 408.543837 -413.227566) (xy 408.516582 -413.228028) (xy 407.652982 -413.228028) (xy 407.625733 -413.227501)
			(xy 407.57179 -413.219742) (xy 407.5195 -413.204387) (xy 407.469928 -413.181746) (xy 407.424082 -413.15228)
			(xy 407.382897 -413.116591) (xy 407.347209 -413.075403) (xy 407.317746 -413.029556) (xy 407.295107 -412.979983)
			(xy 407.279754 -412.927692) (xy 407.271998 -412.873749) (xy 405.834342 -412.873749) (xy 405.834342 -412.873751)
			(xy 405.826586 -412.927698) (xy 405.811233 -412.979992) (xy 405.788593 -413.029569) (xy 405.759129 -413.07542)
			(xy 405.723441 -413.116611) (xy 405.682253 -413.152304) (xy 405.636406 -413.181773) (xy 405.586831 -413.204418)
			(xy 405.534539 -413.219778) (xy 405.480593 -413.227539) (xy 405.453342 -413.228028) (xy 404.589742 -413.228028)
			(xy 404.562489 -413.227528) (xy 404.508536 -413.219776) (xy 404.456236 -413.204424) (xy 404.406653 -413.181785)
			(xy 404.360797 -413.15232) (xy 404.319601 -413.116628) (xy 404.283905 -413.075437) (xy 404.254435 -413.029584)
			(xy 404.23179 -412.980004) (xy 404.216433 -412.927705) (xy 404.208675 -412.873753) (xy 402.771142 -412.873753)
			(xy 402.763385 -412.927703) (xy 402.748029 -412.98) (xy 402.725387 -413.02958) (xy 402.69592 -413.075433)
			(xy 402.660226 -413.116625) (xy 402.619034 -413.152318) (xy 402.573182 -413.181786) (xy 402.523602 -413.204429)
			(xy 402.471305 -413.219785) (xy 402.417355 -413.227542) (xy 402.390102 -413.228028) (xy 401.526502 -413.228028)
			(xy 401.49925 -413.227525) (xy 401.445302 -413.219769) (xy 401.393007 -413.204413) (xy 401.343429 -413.181772)
			(xy 401.297578 -413.152306) (xy 401.256387 -413.116614) (xy 401.220695 -413.075424) (xy 401.191229 -413.029573)
			(xy 401.168587 -412.979995) (xy 401.153232 -412.9277) (xy 401.145475 -412.873752) (xy 399.707965 -412.873752)
			(xy 399.707965 -412.873756) (xy 399.700207 -412.927713) (xy 399.684848 -412.980017) (xy 399.662201 -413.029602)
			(xy 399.632728 -413.07546) (xy 399.597029 -413.116655) (xy 399.555829 -413.152351) (xy 399.509969 -413.18182)
			(xy 399.460381 -413.204461) (xy 399.408076 -413.219815) (xy 399.354118 -413.227568) (xy 399.326862 -413.228028)
			(xy 398.463262 -413.228028) (xy 398.436014 -413.227499) (xy 398.382073 -413.219739) (xy 398.329786 -413.204381)
			(xy 398.280216 -413.181739) (xy 398.234373 -413.152273) (xy 398.193189 -413.116584) (xy 398.157504 -413.075397)
			(xy 398.128043 -413.029551) (xy 398.105406 -412.979978) (xy 398.090053 -412.92769) (xy 398.082298 -412.873748)
			(xy 396.644642 -412.873748) (xy 396.644642 -412.873752) (xy 396.636886 -412.9277) (xy 396.621531 -412.979996)
			(xy 396.59889 -413.029574) (xy 396.569425 -413.075426) (xy 396.533734 -413.116618) (xy 396.492544 -413.152311)
			(xy 396.446694 -413.18178) (xy 396.397117 -413.204423) (xy 396.344822 -413.219781) (xy 396.290874 -413.227541)
			(xy 396.263622 -413.228028) (xy 395.400022 -413.228028) (xy 395.37277 -413.227526) (xy 395.318819 -413.219772)
			(xy 395.266521 -413.204419) (xy 395.216941 -413.181779) (xy 395.171088 -413.152313) (xy 395.129894 -413.116621)
			(xy 395.0942 -413.07543) (xy 395.064732 -413.029578) (xy 395.042089 -412.979999) (xy 395.026732 -412.927702)
			(xy 395.018975 -412.873752) (xy 393.581465 -412.873752) (xy 393.581465 -412.873755) (xy 393.573707 -412.927711)
			(xy 393.558349 -412.980013) (xy 393.535704 -413.029597) (xy 393.506233 -413.075453) (xy 393.470536 -413.116648)
			(xy 393.429339 -413.152344) (xy 393.383481 -413.181813) (xy 393.333896 -413.204456) (xy 393.281593 -413.219811)
			(xy 393.227637 -413.227566) (xy 393.200382 -413.228028) (xy 392.336782 -413.228028) (xy 392.309533 -413.227501)
			(xy 392.25559 -413.219742) (xy 392.2033 -413.204387) (xy 392.153728 -413.181746) (xy 392.107882 -413.15228)
			(xy 392.066697 -413.116591) (xy 392.031009 -413.075403) (xy 392.001546 -413.029556) (xy 391.978907 -412.979983)
			(xy 391.963554 -412.927692) (xy 391.955798 -412.873749) (xy 390.518142 -412.873749) (xy 390.518142 -412.873751)
			(xy 390.510386 -412.927698) (xy 390.495033 -412.979992) (xy 390.472393 -413.029569) (xy 390.442929 -413.07542)
			(xy 390.407241 -413.116611) (xy 390.366053 -413.152304) (xy 390.320206 -413.181773) (xy 390.270631 -413.204418)
			(xy 390.218339 -413.219778) (xy 390.164393 -413.227539) (xy 390.137142 -413.228028) (xy 389.273542 -413.228028)
			(xy 389.246289 -413.227528) (xy 389.192336 -413.219776) (xy 389.140036 -413.204424) (xy 389.090453 -413.181785)
			(xy 389.044597 -413.15232) (xy 389.003401 -413.116628) (xy 388.967705 -413.075437) (xy 388.938235 -413.029584)
			(xy 388.91559 -412.980004) (xy 388.900233 -412.927705) (xy 388.892475 -412.873753) (xy 387.454942 -412.873753)
			(xy 387.447185 -412.927703) (xy 387.431829 -412.98) (xy 387.409187 -413.02958) (xy 387.37972 -413.075433)
			(xy 387.344026 -413.116625) (xy 387.302834 -413.152318) (xy 387.256982 -413.181786) (xy 387.207402 -413.204429)
			(xy 387.155105 -413.219785) (xy 387.101155 -413.227542) (xy 387.073902 -413.228028) (xy 386.210302 -413.228028)
			(xy 386.18305 -413.227525) (xy 386.129102 -413.219769) (xy 386.076807 -413.204413) (xy 386.027229 -413.181772)
			(xy 385.981378 -413.152306) (xy 385.940187 -413.116614) (xy 385.904495 -413.075424) (xy 385.875029 -413.029573)
			(xy 385.852387 -412.979995) (xy 385.837032 -412.9277) (xy 385.829275 -412.873752) (xy 384.391765 -412.873752)
			(xy 384.391765 -412.873756) (xy 384.384007 -412.927713) (xy 384.368648 -412.980017) (xy 384.346001 -413.029602)
			(xy 384.316528 -413.07546) (xy 384.280829 -413.116655) (xy 384.239629 -413.152351) (xy 384.193769 -413.18182)
			(xy 384.144181 -413.204461) (xy 384.091876 -413.219815) (xy 384.037918 -413.227568) (xy 384.010662 -413.228028)
			(xy 383.147062 -413.228028) (xy 383.119814 -413.227499) (xy 383.065873 -413.219739) (xy 383.013586 -413.204381)
			(xy 382.964016 -413.181739) (xy 382.918173 -413.152273) (xy 382.876989 -413.116584) (xy 382.841304 -413.075397)
			(xy 382.811843 -413.029551) (xy 382.789206 -412.979978) (xy 382.773853 -412.92769) (xy 382.766098 -412.873748)
			(xy 381.328442 -412.873748) (xy 381.328442 -412.873752) (xy 381.320686 -412.9277) (xy 381.305331 -412.979996)
			(xy 381.28269 -413.029574) (xy 381.253225 -413.075426) (xy 381.217534 -413.116618) (xy 381.176344 -413.152311)
			(xy 381.130494 -413.18178) (xy 381.080917 -413.204423) (xy 381.028622 -413.219781) (xy 380.974674 -413.227541)
			(xy 380.947422 -413.228028) (xy 380.083822 -413.228028) (xy 380.05657 -413.227526) (xy 380.002619 -413.219772)
			(xy 379.950321 -413.204419) (xy 379.900741 -413.181779) (xy 379.854888 -413.152313) (xy 379.813694 -413.116621)
			(xy 379.778 -413.07543) (xy 379.748532 -413.029578) (xy 379.725889 -412.979999) (xy 379.710532 -412.927702)
			(xy 379.702775 -412.873752) (xy 378.265265 -412.873752) (xy 378.265265 -412.873755) (xy 378.257507 -412.927711)
			(xy 378.242149 -412.980013) (xy 378.219504 -413.029597) (xy 378.190033 -413.075453) (xy 378.154336 -413.116648)
			(xy 378.113139 -413.152344) (xy 378.067281 -413.181813) (xy 378.017696 -413.204456) (xy 377.965393 -413.219811)
			(xy 377.911437 -413.227566) (xy 377.884182 -413.228028) (xy 377.020582 -413.228028) (xy 376.993333 -413.227501)
			(xy 376.93939 -413.219742) (xy 376.8871 -413.204387) (xy 376.837528 -413.181746) (xy 376.791682 -413.15228)
			(xy 376.750497 -413.116591) (xy 376.714809 -413.075403) (xy 376.685346 -413.029556) (xy 376.662707 -412.979983)
			(xy 376.647354 -412.927692) (xy 376.639598 -412.873749) (xy 375.201942 -412.873749) (xy 375.201942 -412.873751)
			(xy 375.194186 -412.927698) (xy 375.178833 -412.979992) (xy 375.156193 -413.029569) (xy 375.126729 -413.07542)
			(xy 375.091041 -413.116611) (xy 375.049853 -413.152304) (xy 375.004006 -413.181773) (xy 374.954431 -413.204418)
			(xy 374.902139 -413.219778) (xy 374.848193 -413.227539) (xy 374.820942 -413.228028) (xy 373.957342 -413.228028)
			(xy 373.930089 -413.227528) (xy 373.876136 -413.219776) (xy 373.823836 -413.204424) (xy 373.774253 -413.181785)
			(xy 373.728397 -413.15232) (xy 373.687201 -413.116628) (xy 373.651505 -413.075437) (xy 373.622035 -413.029584)
			(xy 373.59939 -412.980004) (xy 373.584033 -412.927705) (xy 373.576275 -412.873753) (xy 372.138742 -412.873753)
			(xy 372.130985 -412.927703) (xy 372.115629 -412.98) (xy 372.092987 -413.02958) (xy 372.06352 -413.075433)
			(xy 372.027826 -413.116625) (xy 371.986634 -413.152318) (xy 371.940782 -413.181786) (xy 371.891202 -413.204429)
			(xy 371.838905 -413.219785) (xy 371.784955 -413.227542) (xy 371.757702 -413.228028) (xy 370.894102 -413.228028)
			(xy 370.86685 -413.227525) (xy 370.812902 -413.219769) (xy 370.760607 -413.204413) (xy 370.711029 -413.181772)
			(xy 370.665178 -413.152306) (xy 370.623987 -413.116614) (xy 370.588295 -413.075424) (xy 370.558829 -413.029573)
			(xy 370.536187 -412.979995) (xy 370.520832 -412.9277) (xy 370.513075 -412.873752) (xy 350.987142 -412.873752)
			(xy 350.979385 -412.927702) (xy 350.96403 -412.979999) (xy 350.941388 -413.029579) (xy 350.911921 -413.075431)
			(xy 350.876228 -413.116624) (xy 350.835036 -413.152317) (xy 350.789184 -413.181785) (xy 350.739605 -413.204428)
			(xy 350.687308 -413.219784) (xy 350.633358 -413.227542) (xy 350.606106 -413.228028) (xy 349.742506 -413.228028)
			(xy 349.715254 -413.227525) (xy 349.661306 -413.219769) (xy 349.60901 -413.204415) (xy 349.559431 -413.181774)
			(xy 349.51358 -413.152307) (xy 349.472389 -413.116616) (xy 349.436696 -413.075425) (xy 349.407229 -413.029574)
			(xy 349.384588 -412.979996) (xy 349.369232 -412.9277) (xy 349.361475 -412.873752) (xy 347.923965 -412.873752)
			(xy 347.923965 -412.873756) (xy 347.916207 -412.927713) (xy 347.900848 -412.980016) (xy 347.878202 -413.029601)
			(xy 347.848729 -413.075458) (xy 347.81303 -413.116654) (xy 347.771831 -413.15235) (xy 347.725971 -413.181818)
			(xy 347.676384 -413.20446) (xy 347.624079 -413.219814) (xy 347.570122 -413.227567) (xy 347.542866 -413.228028)
			(xy 346.679266 -413.228028) (xy 346.652018 -413.227499) (xy 346.598077 -413.219739) (xy 346.545789 -413.204382)
			(xy 346.496218 -413.18174) (xy 346.450375 -413.152275) (xy 346.409191 -413.116585) (xy 346.373505 -413.075398)
			(xy 346.344043 -413.029552) (xy 346.321406 -412.979979) (xy 346.306053 -412.92769) (xy 346.298298 -412.873748)
			(xy 344.860642 -412.873748) (xy 344.860642 -412.873751) (xy 344.852886 -412.9277) (xy 344.837531 -412.979995)
			(xy 344.814891 -413.029573) (xy 344.785426 -413.075425) (xy 344.749735 -413.116617) (xy 344.708546 -413.15231)
			(xy 344.662696 -413.181778) (xy 344.61312 -413.204422) (xy 344.560825 -413.21978) (xy 344.506877 -413.22754)
			(xy 344.479626 -413.228028) (xy 343.616026 -413.228028) (xy 343.588773 -413.227526) (xy 343.534822 -413.219773)
			(xy 343.482524 -413.20442) (xy 343.432943 -413.18178) (xy 343.387089 -413.152314) (xy 343.345896 -413.116623)
			(xy 343.310201 -413.075431) (xy 343.280732 -413.029579) (xy 343.258089 -412.98) (xy 343.242733 -412.927703)
			(xy 343.234975 -412.873753) (xy 341.797465 -412.873753) (xy 341.797465 -412.873755) (xy 341.789707 -412.92771)
			(xy 341.77435 -412.980012) (xy 341.751705 -413.029595) (xy 341.722234 -413.075452) (xy 341.686537 -413.116647)
			(xy 341.645341 -413.152343) (xy 341.599483 -413.181812) (xy 341.549899 -413.204455) (xy 341.497596 -413.21981)
			(xy 341.443641 -413.227566) (xy 341.416386 -413.228028) (xy 340.552786 -413.228028) (xy 340.525537 -413.227501)
			(xy 340.471594 -413.219743) (xy 340.419303 -413.204388) (xy 340.36973 -413.181747) (xy 340.323884 -413.152282)
			(xy 340.282698 -413.116592) (xy 340.24701 -413.075404) (xy 340.217546 -413.029557) (xy 340.194908 -412.979984)
			(xy 340.179554 -412.927693) (xy 340.171798 -412.873749) (xy 338.734142 -412.873749) (xy 338.734142 -412.873751)
			(xy 338.726387 -412.927697) (xy 338.711033 -412.979991) (xy 338.688394 -413.029568) (xy 338.65893 -413.075418)
			(xy 338.623242 -413.116609) (xy 338.582055 -413.152303) (xy 338.536208 -413.181772) (xy 338.486634 -413.204417)
			(xy 338.434342 -413.219777) (xy 338.380397 -413.227539) (xy 338.353146 -413.228028) (xy 337.489546 -413.228028)
			(xy 337.462292 -413.227528) (xy 337.408339 -413.219777) (xy 337.356039 -413.204425) (xy 337.306455 -413.181787)
			(xy 337.260599 -413.152321) (xy 337.219403 -413.11663) (xy 337.183706 -413.075438) (xy 337.154235 -413.029585)
			(xy 337.131591 -412.980004) (xy 337.116233 -412.927706) (xy 337.108475 -412.873754) (xy 335.670942 -412.873754)
			(xy 335.663185 -412.927702) (xy 335.64783 -412.979999) (xy 335.625188 -413.029579) (xy 335.595721 -413.075431)
			(xy 335.560028 -413.116624) (xy 335.518836 -413.152317) (xy 335.472984 -413.181785) (xy 335.423405 -413.204428)
			(xy 335.371108 -413.219784) (xy 335.317158 -413.227542) (xy 335.289906 -413.228028) (xy 334.426306 -413.228028)
			(xy 334.399054 -413.227525) (xy 334.345106 -413.219769) (xy 334.29281 -413.204415) (xy 334.243231 -413.181774)
			(xy 334.19738 -413.152307) (xy 334.156189 -413.116616) (xy 334.120496 -413.075425) (xy 334.091029 -413.029574)
			(xy 334.068388 -412.979996) (xy 334.053032 -412.9277) (xy 334.045275 -412.873752) (xy 332.607765 -412.873752)
			(xy 332.607765 -412.873756) (xy 332.600007 -412.927713) (xy 332.584648 -412.980016) (xy 332.562002 -413.029601)
			(xy 332.532529 -413.075458) (xy 332.49683 -413.116654) (xy 332.455631 -413.15235) (xy 332.409771 -413.181818)
			(xy 332.360184 -413.20446) (xy 332.307879 -413.219814) (xy 332.253922 -413.227567) (xy 332.226666 -413.228028)
			(xy 331.363066 -413.228028) (xy 331.335818 -413.227499) (xy 331.281877 -413.219739) (xy 331.229589 -413.204382)
			(xy 331.180018 -413.18174) (xy 331.134175 -413.152275) (xy 331.092991 -413.116585) (xy 331.057305 -413.075398)
			(xy 331.027843 -413.029552) (xy 331.005206 -412.979979) (xy 330.989853 -412.92769) (xy 330.982098 -412.873748)
			(xy 329.544442 -412.873748) (xy 329.544442 -412.873751) (xy 329.536686 -412.9277) (xy 329.521331 -412.979995)
			(xy 329.498691 -413.029573) (xy 329.469226 -413.075425) (xy 329.433535 -413.116617) (xy 329.392346 -413.15231)
			(xy 329.346496 -413.181778) (xy 329.29692 -413.204422) (xy 329.244625 -413.21978) (xy 329.190677 -413.22754)
			(xy 329.163426 -413.228028) (xy 328.299826 -413.228028) (xy 328.272573 -413.227526) (xy 328.218622 -413.219773)
			(xy 328.166324 -413.20442) (xy 328.116743 -413.18178) (xy 328.070889 -413.152314) (xy 328.029696 -413.116623)
			(xy 327.994001 -413.075431) (xy 327.964532 -413.029579) (xy 327.941889 -412.98) (xy 327.926533 -412.927703)
			(xy 327.918775 -412.873753) (xy 326.481265 -412.873753) (xy 326.481265 -412.873755) (xy 326.473507 -412.92771)
			(xy 326.45815 -412.980012) (xy 326.435505 -413.029595) (xy 326.406034 -413.075452) (xy 326.370337 -413.116647)
			(xy 326.329141 -413.152343) (xy 326.283283 -413.181812) (xy 326.233699 -413.204455) (xy 326.181396 -413.21981)
			(xy 326.127441 -413.227566) (xy 326.100186 -413.228028) (xy 325.236586 -413.228028) (xy 325.209337 -413.227501)
			(xy 325.155394 -413.219743) (xy 325.103103 -413.204388) (xy 325.05353 -413.181747) (xy 325.007684 -413.152282)
			(xy 324.966498 -413.116592) (xy 324.93081 -413.075404) (xy 324.901346 -413.029557) (xy 324.878708 -412.979984)
			(xy 324.863354 -412.927693) (xy 324.855598 -412.873749) (xy 323.417942 -412.873749) (xy 323.417942 -412.873751)
			(xy 323.410187 -412.927697) (xy 323.394833 -412.979991) (xy 323.372194 -413.029568) (xy 323.34273 -413.075418)
			(xy 323.307042 -413.116609) (xy 323.265855 -413.152303) (xy 323.220008 -413.181772) (xy 323.170434 -413.204417)
			(xy 323.118142 -413.219777) (xy 323.064197 -413.227539) (xy 323.036946 -413.228028) (xy 322.173346 -413.228028)
			(xy 322.146092 -413.227528) (xy 322.092139 -413.219777) (xy 322.039839 -413.204425) (xy 321.990255 -413.181787)
			(xy 321.944399 -413.152321) (xy 321.903203 -413.11663) (xy 321.867506 -413.075438) (xy 321.838035 -413.029585)
			(xy 321.815391 -412.980004) (xy 321.800033 -412.927706) (xy 321.792275 -412.873754) (xy 320.354742 -412.873754)
			(xy 320.346985 -412.927702) (xy 320.33163 -412.979999) (xy 320.308988 -413.029579) (xy 320.279521 -413.075431)
			(xy 320.243828 -413.116624) (xy 320.202636 -413.152317) (xy 320.156784 -413.181785) (xy 320.107205 -413.204428)
			(xy 320.054908 -413.219784) (xy 320.000958 -413.227542) (xy 319.973706 -413.228028) (xy 319.110106 -413.228028)
			(xy 319.082854 -413.227525) (xy 319.028906 -413.219769) (xy 318.97661 -413.204415) (xy 318.927031 -413.181774)
			(xy 318.88118 -413.152307) (xy 318.839989 -413.116616) (xy 318.804296 -413.075425) (xy 318.774829 -413.029574)
			(xy 318.752188 -412.979996) (xy 318.736832 -412.9277) (xy 318.729075 -412.873752) (xy 317.291565 -412.873752)
			(xy 317.291565 -412.873756) (xy 317.283807 -412.927713) (xy 317.268448 -412.980016) (xy 317.245802 -413.029601)
			(xy 317.216329 -413.075458) (xy 317.18063 -413.116654) (xy 317.139431 -413.15235) (xy 317.093571 -413.181818)
			(xy 317.043984 -413.20446) (xy 316.991679 -413.219814) (xy 316.937722 -413.227567) (xy 316.910466 -413.228028)
			(xy 316.046866 -413.228028) (xy 316.019618 -413.227499) (xy 315.965677 -413.219739) (xy 315.913389 -413.204382)
			(xy 315.863818 -413.18174) (xy 315.817975 -413.152275) (xy 315.776791 -413.116585) (xy 315.741105 -413.075398)
			(xy 315.711643 -413.029552) (xy 315.689006 -412.979979) (xy 315.673653 -412.92769) (xy 315.665898 -412.873748)
			(xy 314.228242 -412.873748) (xy 314.228242 -412.873751) (xy 314.220486 -412.9277) (xy 314.205131 -412.979995)
			(xy 314.182491 -413.029573) (xy 314.153026 -413.075425) (xy 314.117335 -413.116617) (xy 314.076146 -413.15231)
			(xy 314.030296 -413.181778) (xy 313.98072 -413.204422) (xy 313.928425 -413.21978) (xy 313.874477 -413.22754)
			(xy 313.847226 -413.228028) (xy 312.983626 -413.228028) (xy 312.956373 -413.227526) (xy 312.902422 -413.219773)
			(xy 312.850124 -413.20442) (xy 312.800543 -413.18178) (xy 312.754689 -413.152314) (xy 312.713496 -413.116623)
			(xy 312.677801 -413.075431) (xy 312.648332 -413.029579) (xy 312.625689 -412.98) (xy 312.610333 -412.927703)
			(xy 312.602575 -412.873753) (xy 311.165065 -412.873753) (xy 311.165065 -412.873755) (xy 311.157307 -412.92771)
			(xy 311.14195 -412.980012) (xy 311.119305 -413.029595) (xy 311.089834 -413.075452) (xy 311.054137 -413.116647)
			(xy 311.012941 -413.152343) (xy 310.967083 -413.181812) (xy 310.917499 -413.204455) (xy 310.865196 -413.21981)
			(xy 310.811241 -413.227566) (xy 310.783986 -413.228028) (xy 309.920386 -413.228028) (xy 309.893137 -413.227501)
			(xy 309.839194 -413.219743) (xy 309.786903 -413.204388) (xy 309.73733 -413.181747) (xy 309.691484 -413.152282)
			(xy 309.650298 -413.116592) (xy 309.61461 -413.075404) (xy 309.585146 -413.029557) (xy 309.562508 -412.979984)
			(xy 309.547154 -412.927693) (xy 309.539398 -412.873749) (xy 308.101742 -412.873749) (xy 308.101742 -412.873751)
			(xy 308.093987 -412.927697) (xy 308.078633 -412.979991) (xy 308.055994 -413.029568) (xy 308.02653 -413.075418)
			(xy 307.990842 -413.116609) (xy 307.949655 -413.152303) (xy 307.903808 -413.181772) (xy 307.854234 -413.204417)
			(xy 307.801942 -413.219777) (xy 307.747997 -413.227539) (xy 307.720746 -413.228028) (xy 306.857146 -413.228028)
			(xy 306.829892 -413.227528) (xy 306.775939 -413.219777) (xy 306.723639 -413.204425) (xy 306.674055 -413.181787)
			(xy 306.628199 -413.152321) (xy 306.587003 -413.11663) (xy 306.551306 -413.075438) (xy 306.521835 -413.029585)
			(xy 306.499191 -412.980004) (xy 306.483833 -412.927706) (xy 306.476075 -412.873754) (xy 305.038542 -412.873754)
			(xy 305.030785 -412.927702) (xy 305.01543 -412.979999) (xy 304.992788 -413.029579) (xy 304.963321 -413.075431)
			(xy 304.927628 -413.116624) (xy 304.886436 -413.152317) (xy 304.840584 -413.181785) (xy 304.791005 -413.204428)
			(xy 304.738708 -413.219784) (xy 304.684758 -413.227542) (xy 304.657506 -413.228028) (xy 303.793906 -413.228028)
			(xy 303.766654 -413.227525) (xy 303.712706 -413.219769) (xy 303.66041 -413.204415) (xy 303.610831 -413.181774)
			(xy 303.56498 -413.152307) (xy 303.523789 -413.116616) (xy 303.488096 -413.075425) (xy 303.458629 -413.029574)
			(xy 303.435988 -412.979996) (xy 303.420632 -412.9277) (xy 303.412875 -412.873752) (xy 301.559858 -412.873752)
			(xy 301.562459 -412.902862) (xy 301.570401 -413.080972) (xy 301.570898 -413.170116) (xy 301.570401 -413.25926)
			(xy 301.562459 -413.43737) (xy 301.546591 -413.61495) (xy 301.522827 -413.791646) (xy 301.491216 -413.967109)
			(xy 301.45182 -414.140989) (xy 301.404718 -414.312942) (xy 301.350002 -414.482626) (xy 301.287781 -414.649703)
			(xy 301.21818 -414.813844) (xy 301.141335 -414.97472) (xy 301.057401 -415.132014) (xy 300.966543 -415.285413)
			(xy 300.882586 -415.413753) (xy 304.944475 -415.413753) (xy 304.944475 -415.359247) (xy 304.952233 -415.305297)
			(xy 304.967589 -415.253) (xy 304.990232 -415.203421) (xy 305.019701 -415.157569) (xy 305.055396 -415.116377)
			(xy 305.096589 -415.080686) (xy 305.142443 -415.05122) (xy 305.192024 -415.02858) (xy 305.244322 -415.013227)
			(xy 305.298273 -415.005474) (xy 305.325526 -415.005012) (xy 306.189126 -415.005012) (xy 306.216377 -415.00546)
			(xy 306.270325 -415.01322) (xy 306.32262 -415.028578) (xy 306.372196 -415.051222) (xy 306.418046 -415.08069)
			(xy 306.459235 -415.116383) (xy 306.494926 -415.157575) (xy 306.524391 -415.203427) (xy 306.547031 -415.253005)
			(xy 306.562386 -415.3053) (xy 306.570142 -415.359249) (xy 306.570142 -415.413748) (xy 308.007798 -415.413748)
			(xy 308.007798 -415.359252) (xy 308.015553 -415.30531) (xy 308.030906 -415.253021) (xy 308.053543 -415.203448)
			(xy 308.083005 -415.157602) (xy 308.118691 -415.116415) (xy 308.159875 -415.080725) (xy 308.205718 -415.05126)
			(xy 308.255289 -415.028618) (xy 308.307577 -415.013261) (xy 308.361518 -415.005501) (xy 308.388766 -415.005012)
			(xy 309.252366 -415.005012) (xy 309.279622 -415.005433) (xy 309.333579 -415.013186) (xy 309.385884 -415.02854)
			(xy 309.435471 -415.051182) (xy 309.481331 -415.08065) (xy 309.52253 -415.116346) (xy 309.558229 -415.157542)
			(xy 309.587702 -415.203399) (xy 309.610348 -415.252984) (xy 309.625707 -415.305287) (xy 309.633465 -415.359244)
			(xy 309.633465 -415.413752) (xy 311.070975 -415.413752) (xy 311.070975 -415.359248) (xy 311.078732 -415.3053)
			(xy 311.094088 -415.253004) (xy 311.116729 -415.203426) (xy 311.146196 -415.157575) (xy 311.181889 -415.116384)
			(xy 311.22308 -415.080693) (xy 311.268931 -415.051226) (xy 311.31851 -415.028585) (xy 311.370806 -415.013231)
			(xy 311.424754 -415.005475) (xy 311.452006 -415.005012) (xy 312.315606 -415.005012) (xy 312.342858 -415.005458)
			(xy 312.396808 -415.013216) (xy 312.449105 -415.028572) (xy 312.498684 -415.051215) (xy 312.544536 -415.080683)
			(xy 312.585728 -415.116376) (xy 312.621421 -415.157569) (xy 312.650888 -415.203421) (xy 312.67353 -415.253001)
			(xy 312.688885 -415.305298) (xy 312.696642 -415.359248) (xy 312.696642 -415.413752) (xy 312.696642 -415.413754)
			(xy 314.134175 -415.413754) (xy 314.134175 -415.359246) (xy 314.141933 -415.305294) (xy 314.157291 -415.252996)
			(xy 314.179935 -415.203415) (xy 314.209406 -415.157562) (xy 314.245103 -415.11637) (xy 314.286299 -415.080679)
			(xy 314.332155 -415.051213) (xy 314.381739 -415.028575) (xy 314.434039 -415.013223) (xy 314.487992 -415.005472)
			(xy 314.515246 -415.005012) (xy 315.378846 -415.005012) (xy 315.406097 -415.005461) (xy 315.460042 -415.013223)
			(xy 315.512334 -415.028583) (xy 315.561908 -415.051228) (xy 315.607755 -415.080697) (xy 315.648942 -415.116391)
			(xy 315.68463 -415.157582) (xy 315.714094 -415.203432) (xy 315.736733 -415.253009) (xy 315.752087 -415.305303)
			(xy 315.759842 -415.359249) (xy 315.759842 -415.413749) (xy 317.197498 -415.413749) (xy 317.197498 -415.359251)
			(xy 317.205254 -415.305307) (xy 317.220608 -415.253016) (xy 317.243246 -415.203443) (xy 317.27271 -415.157596)
			(xy 317.308398 -415.116408) (xy 317.349584 -415.080718) (xy 317.39543 -415.051253) (xy 317.445003 -415.028612)
			(xy 317.497294 -415.013257) (xy 317.551237 -415.005499) (xy 317.578486 -415.005012) (xy 318.442086 -415.005012)
			(xy 318.469341 -415.005434) (xy 318.523296 -415.01319) (xy 318.575599 -415.028545) (xy 318.625183 -415.051188)
			(xy 318.671041 -415.080657) (xy 318.712237 -415.116353) (xy 318.747934 -415.157548) (xy 318.777405 -415.203405)
			(xy 318.80005 -415.252988) (xy 318.815407 -415.30529) (xy 318.823165 -415.359245) (xy 318.823165 -415.413753)
			(xy 320.260675 -415.413753) (xy 320.260675 -415.359247) (xy 320.268433 -415.305297) (xy 320.283789 -415.253)
			(xy 320.306432 -415.203421) (xy 320.335901 -415.157569) (xy 320.371596 -415.116377) (xy 320.412789 -415.080686)
			(xy 320.458643 -415.05122) (xy 320.508224 -415.02858) (xy 320.560522 -415.013227) (xy 320.614473 -415.005474)
			(xy 320.641726 -415.005012) (xy 321.505326 -415.005012) (xy 321.532577 -415.00546) (xy 321.586525 -415.01322)
			(xy 321.63882 -415.028578) (xy 321.688396 -415.051222) (xy 321.734246 -415.08069) (xy 321.775435 -415.116383)
			(xy 321.811126 -415.157575) (xy 321.840591 -415.203427) (xy 321.863231 -415.253005) (xy 321.878586 -415.3053)
			(xy 321.886342 -415.359249) (xy 321.886342 -415.413748) (xy 323.323998 -415.413748) (xy 323.323998 -415.359252)
			(xy 323.331753 -415.30531) (xy 323.347106 -415.253021) (xy 323.369743 -415.203448) (xy 323.399205 -415.157602)
			(xy 323.434891 -415.116415) (xy 323.476075 -415.080725) (xy 323.521918 -415.05126) (xy 323.571489 -415.028618)
			(xy 323.623777 -415.013261) (xy 323.677718 -415.005501) (xy 323.704966 -415.005012) (xy 324.568566 -415.005012)
			(xy 324.595822 -415.005433) (xy 324.649779 -415.013186) (xy 324.702084 -415.02854) (xy 324.751671 -415.051182)
			(xy 324.797531 -415.08065) (xy 324.83873 -415.116346) (xy 324.874429 -415.157542) (xy 324.903902 -415.203399)
			(xy 324.926548 -415.252984) (xy 324.941907 -415.305287) (xy 324.949665 -415.359244) (xy 324.949665 -415.413752)
			(xy 326.387175 -415.413752) (xy 326.387175 -415.359248) (xy 326.394932 -415.3053) (xy 326.410288 -415.253004)
			(xy 326.432929 -415.203426) (xy 326.462396 -415.157575) (xy 326.498089 -415.116384) (xy 326.53928 -415.080693)
			(xy 326.585131 -415.051226) (xy 326.63471 -415.028585) (xy 326.687006 -415.013231) (xy 326.740954 -415.005475)
			(xy 326.768206 -415.005012) (xy 327.631806 -415.005012) (xy 327.659058 -415.005458) (xy 327.713008 -415.013216)
			(xy 327.765305 -415.028572) (xy 327.814884 -415.051215) (xy 327.860736 -415.080683) (xy 327.901928 -415.116376)
			(xy 327.937621 -415.157569) (xy 327.967088 -415.203421) (xy 327.98973 -415.253001) (xy 328.005085 -415.305298)
			(xy 328.012842 -415.359248) (xy 328.012842 -415.413752) (xy 328.012842 -415.413754) (xy 329.450375 -415.413754)
			(xy 329.450375 -415.359246) (xy 329.458133 -415.305294) (xy 329.473491 -415.252996) (xy 329.496135 -415.203415)
			(xy 329.525606 -415.157562) (xy 329.561303 -415.11637) (xy 329.602499 -415.080679) (xy 329.648355 -415.051213)
			(xy 329.697939 -415.028575) (xy 329.750239 -415.013223) (xy 329.804192 -415.005472) (xy 329.831446 -415.005012)
			(xy 330.695046 -415.005012) (xy 330.722297 -415.005461) (xy 330.776242 -415.013223) (xy 330.828534 -415.028583)
			(xy 330.878108 -415.051228) (xy 330.923955 -415.080697) (xy 330.965142 -415.116391) (xy 331.00083 -415.157582)
			(xy 331.030294 -415.203432) (xy 331.052933 -415.253009) (xy 331.068287 -415.305303) (xy 331.076042 -415.359249)
			(xy 331.076042 -415.413749) (xy 332.513698 -415.413749) (xy 332.513698 -415.359251) (xy 332.521454 -415.305307)
			(xy 332.536808 -415.253016) (xy 332.559446 -415.203443) (xy 332.58891 -415.157596) (xy 332.624598 -415.116408)
			(xy 332.665784 -415.080718) (xy 332.71163 -415.051253) (xy 332.761203 -415.028612) (xy 332.813494 -415.013257)
			(xy 332.867437 -415.005499) (xy 332.894686 -415.005012) (xy 333.758286 -415.005012) (xy 333.785541 -415.005434)
			(xy 333.839496 -415.01319) (xy 333.891799 -415.028545) (xy 333.941383 -415.051188) (xy 333.987241 -415.080657)
			(xy 334.028437 -415.116353) (xy 334.064134 -415.157548) (xy 334.093605 -415.203405) (xy 334.11625 -415.252988)
			(xy 334.131607 -415.30529) (xy 334.139365 -415.359245) (xy 334.139365 -415.413753) (xy 335.576875 -415.413753)
			(xy 335.576875 -415.359247) (xy 335.584633 -415.305297) (xy 335.599989 -415.253) (xy 335.622632 -415.203421)
			(xy 335.652101 -415.157569) (xy 335.687796 -415.116377) (xy 335.728989 -415.080686) (xy 335.774843 -415.05122)
			(xy 335.824424 -415.02858) (xy 335.876722 -415.013227) (xy 335.930673 -415.005474) (xy 335.957926 -415.005012)
			(xy 336.821526 -415.005012) (xy 336.848777 -415.00546) (xy 336.902725 -415.01322) (xy 336.95502 -415.028578)
			(xy 337.004596 -415.051222) (xy 337.050446 -415.08069) (xy 337.091635 -415.116383) (xy 337.127326 -415.157575)
			(xy 337.156791 -415.203427) (xy 337.179431 -415.253005) (xy 337.194786 -415.3053) (xy 337.202542 -415.359249)
			(xy 337.202542 -415.413748) (xy 338.640198 -415.413748) (xy 338.640198 -415.359252) (xy 338.647953 -415.30531)
			(xy 338.663306 -415.253021) (xy 338.685943 -415.203448) (xy 338.715405 -415.157602) (xy 338.751091 -415.116415)
			(xy 338.792275 -415.080725) (xy 338.838118 -415.05126) (xy 338.887689 -415.028618) (xy 338.939977 -415.013261)
			(xy 338.993918 -415.005501) (xy 339.021166 -415.005012) (xy 339.884766 -415.005012) (xy 339.912022 -415.005433)
			(xy 339.965979 -415.013186) (xy 340.018284 -415.02854) (xy 340.067871 -415.051182) (xy 340.113731 -415.08065)
			(xy 340.15493 -415.116346) (xy 340.190629 -415.157542) (xy 340.220102 -415.203399) (xy 340.242748 -415.252984)
			(xy 340.258107 -415.305287) (xy 340.265865 -415.359244) (xy 340.265865 -415.413752) (xy 341.703375 -415.413752)
			(xy 341.703375 -415.359248) (xy 341.711132 -415.3053) (xy 341.726488 -415.253004) (xy 341.749129 -415.203426)
			(xy 341.778596 -415.157575) (xy 341.814289 -415.116384) (xy 341.85548 -415.080693) (xy 341.901331 -415.051226)
			(xy 341.95091 -415.028585) (xy 342.003206 -415.013231) (xy 342.057154 -415.005475) (xy 342.084406 -415.005012)
			(xy 342.948006 -415.005012) (xy 342.975258 -415.005458) (xy 343.029208 -415.013216) (xy 343.081505 -415.028572)
			(xy 343.131084 -415.051215) (xy 343.176936 -415.080683) (xy 343.218128 -415.116376) (xy 343.253821 -415.157569)
			(xy 343.283288 -415.203421) (xy 343.30593 -415.253001) (xy 343.321285 -415.305298) (xy 343.329042 -415.359248)
			(xy 343.329042 -415.413752) (xy 343.329042 -415.413754) (xy 344.766575 -415.413754) (xy 344.766575 -415.359246)
			(xy 344.774333 -415.305294) (xy 344.789691 -415.252996) (xy 344.812335 -415.203415) (xy 344.841806 -415.157562)
			(xy 344.877503 -415.11637) (xy 344.918699 -415.080679) (xy 344.964555 -415.051213) (xy 345.014139 -415.028575)
			(xy 345.066439 -415.013223) (xy 345.120392 -415.005472) (xy 345.147646 -415.005012) (xy 346.011246 -415.005012)
			(xy 346.038497 -415.005461) (xy 346.092442 -415.013223) (xy 346.144734 -415.028583) (xy 346.194308 -415.051228)
			(xy 346.240155 -415.080697) (xy 346.281342 -415.116391) (xy 346.31703 -415.157582) (xy 346.346494 -415.203432)
			(xy 346.369133 -415.253009) (xy 346.384487 -415.305303) (xy 346.392242 -415.359249) (xy 346.392242 -415.413749)
			(xy 347.829898 -415.413749) (xy 347.829898 -415.359251) (xy 347.837654 -415.305307) (xy 347.853008 -415.253016)
			(xy 347.875646 -415.203443) (xy 347.90511 -415.157596) (xy 347.940798 -415.116408) (xy 347.981984 -415.080718)
			(xy 348.02783 -415.051253) (xy 348.077403 -415.028612) (xy 348.129694 -415.013257) (xy 348.183637 -415.005499)
			(xy 348.210886 -415.005012) (xy 349.074486 -415.005012) (xy 349.101741 -415.005434) (xy 349.155696 -415.01319)
			(xy 349.207999 -415.028545) (xy 349.257583 -415.051188) (xy 349.303441 -415.080657) (xy 349.344637 -415.116353)
			(xy 349.380334 -415.157548) (xy 349.409805 -415.203405) (xy 349.43245 -415.252988) (xy 349.447807 -415.30529)
			(xy 349.455565 -415.359245) (xy 349.455565 -415.413753) (xy 350.893075 -415.413753) (xy 350.893075 -415.359247)
			(xy 350.900833 -415.305297) (xy 350.916189 -415.253) (xy 350.938832 -415.203421) (xy 350.968301 -415.157569)
			(xy 351.003996 -415.116377) (xy 351.045189 -415.080686) (xy 351.091043 -415.05122) (xy 351.140624 -415.02858)
			(xy 351.192922 -415.013227) (xy 351.246873 -415.005474) (xy 351.274126 -415.005012) (xy 352.137726 -415.005012)
			(xy 352.164977 -415.00546) (xy 352.218925 -415.01322) (xy 352.27122 -415.028578) (xy 352.320796 -415.051222)
			(xy 352.366646 -415.08069) (xy 352.407835 -415.116383) (xy 352.443526 -415.157575) (xy 352.472991 -415.203427)
			(xy 352.495631 -415.253005) (xy 352.510986 -415.3053) (xy 352.518742 -415.359249) (xy 352.518742 -415.413751)
			(xy 352.518742 -415.413752) (xy 372.044675 -415.413752) (xy 372.044675 -415.359248) (xy 372.052432 -415.305298)
			(xy 372.067789 -415.253001) (xy 372.090432 -415.203422) (xy 372.1199 -415.15757) (xy 372.155594 -415.116379)
			(xy 372.196788 -415.080687) (xy 372.242641 -415.051221) (xy 372.292221 -415.028581) (xy 372.344519 -415.013228)
			(xy 372.39847 -415.005474) (xy 372.425722 -415.005012) (xy 373.289322 -415.005012) (xy 373.316574 -415.005459)
			(xy 373.370522 -415.013219) (xy 373.422817 -415.028577) (xy 373.472394 -415.05122) (xy 373.518244 -415.080689)
			(xy 373.559434 -415.116382) (xy 373.595125 -415.157574) (xy 373.62459 -415.203426) (xy 373.647231 -415.253004)
			(xy 373.662586 -415.3053) (xy 373.670342 -415.359248) (xy 373.670342 -415.413748) (xy 375.107998 -415.413748)
			(xy 375.107998 -415.359252) (xy 375.115753 -415.30531) (xy 375.131106 -415.253022) (xy 375.153743 -415.203449)
			(xy 375.183204 -415.157603) (xy 375.218889 -415.116416) (xy 375.260073 -415.080727) (xy 375.305916 -415.051261)
			(xy 375.355486 -415.028619) (xy 375.407773 -415.013261) (xy 375.461714 -415.005501) (xy 375.488962 -415.005012)
			(xy 376.352562 -415.005012) (xy 376.379818 -415.005432) (xy 376.433776 -415.013185) (xy 376.486081 -415.028539)
			(xy 376.535669 -415.05118) (xy 376.581529 -415.080649) (xy 376.622729 -415.116345) (xy 376.658428 -415.15754)
			(xy 376.687901 -415.203398) (xy 376.710548 -415.252983) (xy 376.725907 -415.305287) (xy 376.733665 -415.359244)
			(xy 376.733665 -415.413752) (xy 378.171175 -415.413752) (xy 378.171175 -415.359248) (xy 378.178932 -415.3053)
			(xy 378.194287 -415.253005) (xy 378.216929 -415.203427) (xy 378.246395 -415.157576) (xy 378.282087 -415.116386)
			(xy 378.323278 -415.080694) (xy 378.369129 -415.051228) (xy 378.418707 -415.028587) (xy 378.471002 -415.013231)
			(xy 378.52495 -415.005475) (xy 378.552202 -415.005012) (xy 379.415802 -415.005012) (xy 379.443055 -415.005458)
			(xy 379.497005 -415.013215) (xy 379.549302 -415.028571) (xy 379.598882 -415.051214) (xy 379.644734 -415.080682)
			(xy 379.685926 -415.116375) (xy 379.72162 -415.157567) (xy 379.751087 -415.20342) (xy 379.773729 -415.253)
			(xy 379.789085 -415.305297) (xy 379.796842 -415.359247) (xy 379.796842 -415.413753) (xy 381.234375 -415.413753)
			(xy 381.234375 -415.359247) (xy 381.242133 -415.305295) (xy 381.25749 -415.252996) (xy 381.280135 -415.203416)
			(xy 381.309605 -415.157563) (xy 381.345301 -415.116372) (xy 381.386497 -415.08068) (xy 381.432353 -415.051215)
			(xy 381.481936 -415.028576) (xy 381.534236 -415.013224) (xy 381.588189 -415.005472) (xy 381.615442 -415.005012)
			(xy 382.479042 -415.005012) (xy 382.506293 -415.005461) (xy 382.560239 -415.013222) (xy 382.612531 -415.028582)
			(xy 382.662106 -415.051227) (xy 382.707953 -415.080696) (xy 382.749141 -415.116389) (xy 382.784829 -415.15758)
			(xy 382.814293 -415.203431) (xy 382.836933 -415.253008) (xy 382.852286 -415.305302) (xy 382.860042 -415.359249)
			(xy 382.860042 -415.413749) (xy 384.297698 -415.413749) (xy 384.297698 -415.359251) (xy 384.305454 -415.305308)
			(xy 384.320807 -415.253017) (xy 384.343446 -415.203444) (xy 384.372909 -415.157597) (xy 384.408597 -415.116409)
			(xy 384.449782 -415.08072) (xy 384.495628 -415.051254) (xy 384.5452 -415.028613) (xy 384.59749 -415.013258)
			(xy 384.651433 -415.005499) (xy 384.678682 -415.005012) (xy 385.542282 -415.005012) (xy 385.569537 -415.005434)
			(xy 385.623493 -415.013189) (xy 385.675796 -415.028544) (xy 385.725381 -415.051187) (xy 385.771239 -415.080656)
			(xy 385.812436 -415.116352) (xy 385.848133 -415.157547) (xy 385.877604 -415.203403) (xy 385.900249 -415.252987)
			(xy 385.915607 -415.305289) (xy 385.923365 -415.359245) (xy 385.923365 -415.413752) (xy 387.360875 -415.413752)
			(xy 387.360875 -415.359248) (xy 387.368632 -415.305298) (xy 387.383989 -415.253001) (xy 387.406632 -415.203422)
			(xy 387.4361 -415.15757) (xy 387.471794 -415.116379) (xy 387.512988 -415.080687) (xy 387.558841 -415.051221)
			(xy 387.608421 -415.028581) (xy 387.660719 -415.013228) (xy 387.71467 -415.005474) (xy 387.741922 -415.005012)
			(xy 388.605522 -415.005012) (xy 388.632774 -415.005459) (xy 388.686722 -415.013219) (xy 388.739017 -415.028577)
			(xy 388.788594 -415.05122) (xy 388.834444 -415.080689) (xy 388.875634 -415.116382) (xy 388.911325 -415.157574)
			(xy 388.94079 -415.203426) (xy 388.963431 -415.253004) (xy 388.978786 -415.3053) (xy 388.986542 -415.359248)
			(xy 388.986542 -415.413748) (xy 390.424198 -415.413748) (xy 390.424198 -415.359252) (xy 390.431953 -415.30531)
			(xy 390.447306 -415.253022) (xy 390.469943 -415.203449) (xy 390.499404 -415.157603) (xy 390.535089 -415.116416)
			(xy 390.576273 -415.080727) (xy 390.622116 -415.051261) (xy 390.671686 -415.028619) (xy 390.723973 -415.013261)
			(xy 390.777914 -415.005501) (xy 390.805162 -415.005012) (xy 391.668762 -415.005012) (xy 391.696018 -415.005432)
			(xy 391.749976 -415.013185) (xy 391.802281 -415.028539) (xy 391.851869 -415.05118) (xy 391.897729 -415.080649)
			(xy 391.938929 -415.116345) (xy 391.974628 -415.15754) (xy 392.004101 -415.203398) (xy 392.026748 -415.252983)
			(xy 392.042107 -415.305287) (xy 392.049865 -415.359244) (xy 392.049865 -415.413752) (xy 393.487375 -415.413752)
			(xy 393.487375 -415.359248) (xy 393.495132 -415.3053) (xy 393.510487 -415.253005) (xy 393.533129 -415.203427)
			(xy 393.562595 -415.157576) (xy 393.598287 -415.116386) (xy 393.639478 -415.080694) (xy 393.685329 -415.051228)
			(xy 393.734907 -415.028587) (xy 393.787202 -415.013231) (xy 393.84115 -415.005475) (xy 393.868402 -415.005012)
			(xy 394.732002 -415.005012) (xy 394.759255 -415.005458) (xy 394.813205 -415.013215) (xy 394.865502 -415.028571)
			(xy 394.915082 -415.051214) (xy 394.960934 -415.080682) (xy 395.002126 -415.116375) (xy 395.03782 -415.157567)
			(xy 395.067287 -415.20342) (xy 395.089929 -415.253) (xy 395.105285 -415.305297) (xy 395.113042 -415.359247)
			(xy 395.113042 -415.413753) (xy 396.550575 -415.413753) (xy 396.550575 -415.359247) (xy 396.558333 -415.305295)
			(xy 396.57369 -415.252996) (xy 396.596335 -415.203416) (xy 396.625805 -415.157563) (xy 396.661501 -415.116372)
			(xy 396.702697 -415.08068) (xy 396.748553 -415.051215) (xy 396.798136 -415.028576) (xy 396.850436 -415.013224)
			(xy 396.904389 -415.005472) (xy 396.931642 -415.005012) (xy 397.795242 -415.005012) (xy 397.822493 -415.005461)
			(xy 397.876439 -415.013222) (xy 397.928731 -415.028582) (xy 397.978306 -415.051227) (xy 398.024153 -415.080696)
			(xy 398.065341 -415.116389) (xy 398.101029 -415.15758) (xy 398.130493 -415.203431) (xy 398.153133 -415.253008)
			(xy 398.168486 -415.305302) (xy 398.176242 -415.359249) (xy 398.176242 -415.413749) (xy 399.613898 -415.413749)
			(xy 399.613898 -415.359251) (xy 399.621654 -415.305308) (xy 399.637007 -415.253017) (xy 399.659646 -415.203444)
			(xy 399.689109 -415.157597) (xy 399.724797 -415.116409) (xy 399.765982 -415.08072) (xy 399.811828 -415.051254)
			(xy 399.8614 -415.028613) (xy 399.91369 -415.013258) (xy 399.967633 -415.005499) (xy 399.994882 -415.005012)
			(xy 400.858482 -415.005012) (xy 400.885737 -415.005434) (xy 400.939693 -415.013189) (xy 400.991996 -415.028544)
			(xy 401.041581 -415.051187) (xy 401.087439 -415.080656) (xy 401.128636 -415.116352) (xy 401.164333 -415.157547)
			(xy 401.193804 -415.203403) (xy 401.216449 -415.252987) (xy 401.231807 -415.305289) (xy 401.239565 -415.359245)
			(xy 401.239565 -415.413752) (xy 402.677075 -415.413752) (xy 402.677075 -415.359248) (xy 402.684832 -415.305298)
			(xy 402.700189 -415.253001) (xy 402.722832 -415.203422) (xy 402.7523 -415.15757) (xy 402.787994 -415.116379)
			(xy 402.829188 -415.080687) (xy 402.875041 -415.051221) (xy 402.924621 -415.028581) (xy 402.976919 -415.013228)
			(xy 403.03087 -415.005474) (xy 403.058122 -415.005012) (xy 403.921722 -415.005012) (xy 403.948974 -415.005459)
			(xy 404.002922 -415.013219) (xy 404.055217 -415.028577) (xy 404.104794 -415.05122) (xy 404.150644 -415.080689)
			(xy 404.191834 -415.116382) (xy 404.227525 -415.157574) (xy 404.25699 -415.203426) (xy 404.279631 -415.253004)
			(xy 404.294986 -415.3053) (xy 404.302742 -415.359248) (xy 404.302742 -415.413748) (xy 405.740398 -415.413748)
			(xy 405.740398 -415.359252) (xy 405.748153 -415.30531) (xy 405.763506 -415.253022) (xy 405.786143 -415.203449)
			(xy 405.815604 -415.157603) (xy 405.851289 -415.116416) (xy 405.892473 -415.080727) (xy 405.938316 -415.051261)
			(xy 405.987886 -415.028619) (xy 406.040173 -415.013261) (xy 406.094114 -415.005501) (xy 406.121362 -415.005012)
			(xy 406.984962 -415.005012) (xy 407.012218 -415.005432) (xy 407.066176 -415.013185) (xy 407.118481 -415.028539)
			(xy 407.168069 -415.05118) (xy 407.213929 -415.080649) (xy 407.255129 -415.116345) (xy 407.290828 -415.15754)
			(xy 407.320301 -415.203398) (xy 407.342948 -415.252983) (xy 407.358307 -415.305287) (xy 407.366065 -415.359244)
			(xy 407.366065 -415.413752) (xy 408.803575 -415.413752) (xy 408.803575 -415.359248) (xy 408.811332 -415.3053)
			(xy 408.826687 -415.253005) (xy 408.849329 -415.203427) (xy 408.878795 -415.157576) (xy 408.914487 -415.116386)
			(xy 408.955678 -415.080694) (xy 409.001529 -415.051228) (xy 409.051107 -415.028587) (xy 409.103402 -415.013231)
			(xy 409.15735 -415.005475) (xy 409.184602 -415.005012) (xy 410.048202 -415.005012) (xy 410.075455 -415.005458)
			(xy 410.129405 -415.013215) (xy 410.181702 -415.028571) (xy 410.231282 -415.051214) (xy 410.277134 -415.080682)
			(xy 410.318326 -415.116375) (xy 410.35402 -415.157567) (xy 410.383487 -415.20342) (xy 410.406129 -415.253)
			(xy 410.421485 -415.305297) (xy 410.429242 -415.359247) (xy 410.429242 -415.413753) (xy 411.866775 -415.413753)
			(xy 411.866775 -415.359247) (xy 411.874533 -415.305295) (xy 411.88989 -415.252996) (xy 411.912535 -415.203416)
			(xy 411.942005 -415.157563) (xy 411.977701 -415.116372) (xy 412.018897 -415.08068) (xy 412.064753 -415.051215)
			(xy 412.114336 -415.028576) (xy 412.166636 -415.013224) (xy 412.220589 -415.005472) (xy 412.247842 -415.005012)
			(xy 413.111442 -415.005012) (xy 413.138693 -415.005461) (xy 413.192639 -415.013222) (xy 413.244931 -415.028582)
			(xy 413.294506 -415.051227) (xy 413.340353 -415.080696) (xy 413.381541 -415.116389) (xy 413.417229 -415.15758)
			(xy 413.446693 -415.203431) (xy 413.469333 -415.253008) (xy 413.484686 -415.305302) (xy 413.492442 -415.359249)
			(xy 413.492442 -415.413749) (xy 414.930098 -415.413749) (xy 414.930098 -415.359251) (xy 414.937854 -415.305308)
			(xy 414.953207 -415.253017) (xy 414.975846 -415.203444) (xy 415.005309 -415.157597) (xy 415.040997 -415.116409)
			(xy 415.082182 -415.08072) (xy 415.128028 -415.051254) (xy 415.1776 -415.028613) (xy 415.22989 -415.013258)
			(xy 415.283833 -415.005499) (xy 415.311082 -415.005012) (xy 416.174682 -415.005012) (xy 416.201937 -415.005434)
			(xy 416.255893 -415.013189) (xy 416.308196 -415.028544) (xy 416.357781 -415.051187) (xy 416.403639 -415.080656)
			(xy 416.444836 -415.116352) (xy 416.480533 -415.157547) (xy 416.510004 -415.203403) (xy 416.532649 -415.252987)
			(xy 416.548007 -415.305289) (xy 416.555765 -415.359245) (xy 416.555765 -415.413752) (xy 417.993275 -415.413752)
			(xy 417.993275 -415.359248) (xy 418.001032 -415.305298) (xy 418.016389 -415.253001) (xy 418.039032 -415.203422)
			(xy 418.0685 -415.15757) (xy 418.104194 -415.116379) (xy 418.145388 -415.080687) (xy 418.191241 -415.051221)
			(xy 418.240821 -415.028581) (xy 418.293119 -415.013228) (xy 418.34707 -415.005474) (xy 418.374322 -415.005012)
			(xy 419.237922 -415.005012) (xy 419.265174 -415.005459) (xy 419.319122 -415.013219) (xy 419.371417 -415.028577)
			(xy 419.420994 -415.05122) (xy 419.466844 -415.080689) (xy 419.508034 -415.116382) (xy 419.543725 -415.157574)
			(xy 419.57319 -415.203426) (xy 419.595831 -415.253004) (xy 419.611186 -415.3053) (xy 419.618942 -415.359248)
			(xy 419.618942 -415.413752) (xy 419.611186 -415.4677) (xy 419.595831 -415.519996) (xy 419.57319 -415.569574)
			(xy 419.543725 -415.615426) (xy 419.508034 -415.656618) (xy 419.466844 -415.692311) (xy 419.420994 -415.72178)
			(xy 419.371417 -415.744423) (xy 419.319122 -415.759781) (xy 419.265174 -415.767541) (xy 419.237922 -415.768028)
			(xy 418.374322 -415.768028) (xy 418.34707 -415.767526) (xy 418.293119 -415.759772) (xy 418.240821 -415.744419)
			(xy 418.191241 -415.721779) (xy 418.145388 -415.692313) (xy 418.104194 -415.656621) (xy 418.0685 -415.61543)
			(xy 418.039032 -415.569578) (xy 418.016389 -415.519999) (xy 418.001032 -415.467702) (xy 417.993275 -415.413752)
			(xy 416.555765 -415.413752) (xy 416.555765 -415.413755) (xy 416.548007 -415.467711) (xy 416.532649 -415.520013)
			(xy 416.510004 -415.569597) (xy 416.480533 -415.615453) (xy 416.444836 -415.656648) (xy 416.403639 -415.692344)
			(xy 416.357781 -415.721813) (xy 416.308196 -415.744456) (xy 416.255893 -415.759811) (xy 416.201937 -415.767566)
			(xy 416.174682 -415.768028) (xy 415.311082 -415.768028) (xy 415.283833 -415.767501) (xy 415.22989 -415.759742)
			(xy 415.1776 -415.744387) (xy 415.128028 -415.721746) (xy 415.082182 -415.69228) (xy 415.040997 -415.656591)
			(xy 415.005309 -415.615403) (xy 414.975846 -415.569556) (xy 414.953207 -415.519983) (xy 414.937854 -415.467692)
			(xy 414.930098 -415.413749) (xy 413.492442 -415.413749) (xy 413.492442 -415.413751) (xy 413.484686 -415.467698)
			(xy 413.469333 -415.519992) (xy 413.446693 -415.569569) (xy 413.417229 -415.61542) (xy 413.381541 -415.656611)
			(xy 413.340353 -415.692304) (xy 413.294506 -415.721773) (xy 413.244931 -415.744418) (xy 413.192639 -415.759778)
			(xy 413.138693 -415.767539) (xy 413.111442 -415.768028) (xy 412.247842 -415.768028) (xy 412.220589 -415.767528)
			(xy 412.166636 -415.759776) (xy 412.114336 -415.744424) (xy 412.064753 -415.721785) (xy 412.018897 -415.69232)
			(xy 411.977701 -415.656628) (xy 411.942005 -415.615437) (xy 411.912535 -415.569584) (xy 411.88989 -415.520004)
			(xy 411.874533 -415.467705) (xy 411.866775 -415.413753) (xy 410.429242 -415.413753) (xy 410.421485 -415.467703)
			(xy 410.406129 -415.52) (xy 410.383487 -415.56958) (xy 410.35402 -415.615433) (xy 410.318326 -415.656625)
			(xy 410.277134 -415.692318) (xy 410.231282 -415.721786) (xy 410.181702 -415.744429) (xy 410.129405 -415.759785)
			(xy 410.075455 -415.767542) (xy 410.048202 -415.768028) (xy 409.184602 -415.768028) (xy 409.15735 -415.767525)
			(xy 409.103402 -415.759769) (xy 409.051107 -415.744413) (xy 409.001529 -415.721772) (xy 408.955678 -415.692306)
			(xy 408.914487 -415.656614) (xy 408.878795 -415.615424) (xy 408.849329 -415.569573) (xy 408.826687 -415.519995)
			(xy 408.811332 -415.4677) (xy 408.803575 -415.413752) (xy 407.366065 -415.413752) (xy 407.366065 -415.413756)
			(xy 407.358307 -415.467713) (xy 407.342948 -415.520017) (xy 407.320301 -415.569602) (xy 407.290828 -415.61546)
			(xy 407.255129 -415.656655) (xy 407.213929 -415.692351) (xy 407.168069 -415.72182) (xy 407.118481 -415.744461)
			(xy 407.066176 -415.759815) (xy 407.012218 -415.767568) (xy 406.984962 -415.768028) (xy 406.121362 -415.768028)
			(xy 406.094114 -415.767499) (xy 406.040173 -415.759739) (xy 405.987886 -415.744381) (xy 405.938316 -415.721739)
			(xy 405.892473 -415.692273) (xy 405.851289 -415.656584) (xy 405.815604 -415.615397) (xy 405.786143 -415.569551)
			(xy 405.763506 -415.519978) (xy 405.748153 -415.46769) (xy 405.740398 -415.413748) (xy 404.302742 -415.413748)
			(xy 404.302742 -415.413752) (xy 404.294986 -415.4677) (xy 404.279631 -415.519996) (xy 404.25699 -415.569574)
			(xy 404.227525 -415.615426) (xy 404.191834 -415.656618) (xy 404.150644 -415.692311) (xy 404.104794 -415.72178)
			(xy 404.055217 -415.744423) (xy 404.002922 -415.759781) (xy 403.948974 -415.767541) (xy 403.921722 -415.768028)
			(xy 403.058122 -415.768028) (xy 403.03087 -415.767526) (xy 402.976919 -415.759772) (xy 402.924621 -415.744419)
			(xy 402.875041 -415.721779) (xy 402.829188 -415.692313) (xy 402.787994 -415.656621) (xy 402.7523 -415.61543)
			(xy 402.722832 -415.569578) (xy 402.700189 -415.519999) (xy 402.684832 -415.467702) (xy 402.677075 -415.413752)
			(xy 401.239565 -415.413752) (xy 401.239565 -415.413755) (xy 401.231807 -415.467711) (xy 401.216449 -415.520013)
			(xy 401.193804 -415.569597) (xy 401.164333 -415.615453) (xy 401.128636 -415.656648) (xy 401.087439 -415.692344)
			(xy 401.041581 -415.721813) (xy 400.991996 -415.744456) (xy 400.939693 -415.759811) (xy 400.885737 -415.767566)
			(xy 400.858482 -415.768028) (xy 399.994882 -415.768028) (xy 399.967633 -415.767501) (xy 399.91369 -415.759742)
			(xy 399.8614 -415.744387) (xy 399.811828 -415.721746) (xy 399.765982 -415.69228) (xy 399.724797 -415.656591)
			(xy 399.689109 -415.615403) (xy 399.659646 -415.569556) (xy 399.637007 -415.519983) (xy 399.621654 -415.467692)
			(xy 399.613898 -415.413749) (xy 398.176242 -415.413749) (xy 398.176242 -415.413751) (xy 398.168486 -415.467698)
			(xy 398.153133 -415.519992) (xy 398.130493 -415.569569) (xy 398.101029 -415.61542) (xy 398.065341 -415.656611)
			(xy 398.024153 -415.692304) (xy 397.978306 -415.721773) (xy 397.928731 -415.744418) (xy 397.876439 -415.759778)
			(xy 397.822493 -415.767539) (xy 397.795242 -415.768028) (xy 396.931642 -415.768028) (xy 396.904389 -415.767528)
			(xy 396.850436 -415.759776) (xy 396.798136 -415.744424) (xy 396.748553 -415.721785) (xy 396.702697 -415.69232)
			(xy 396.661501 -415.656628) (xy 396.625805 -415.615437) (xy 396.596335 -415.569584) (xy 396.57369 -415.520004)
			(xy 396.558333 -415.467705) (xy 396.550575 -415.413753) (xy 395.113042 -415.413753) (xy 395.105285 -415.467703)
			(xy 395.089929 -415.52) (xy 395.067287 -415.56958) (xy 395.03782 -415.615433) (xy 395.002126 -415.656625)
			(xy 394.960934 -415.692318) (xy 394.915082 -415.721786) (xy 394.865502 -415.744429) (xy 394.813205 -415.759785)
			(xy 394.759255 -415.767542) (xy 394.732002 -415.768028) (xy 393.868402 -415.768028) (xy 393.84115 -415.767525)
			(xy 393.787202 -415.759769) (xy 393.734907 -415.744413) (xy 393.685329 -415.721772) (xy 393.639478 -415.692306)
			(xy 393.598287 -415.656614) (xy 393.562595 -415.615424) (xy 393.533129 -415.569573) (xy 393.510487 -415.519995)
			(xy 393.495132 -415.4677) (xy 393.487375 -415.413752) (xy 392.049865 -415.413752) (xy 392.049865 -415.413756)
			(xy 392.042107 -415.467713) (xy 392.026748 -415.520017) (xy 392.004101 -415.569602) (xy 391.974628 -415.61546)
			(xy 391.938929 -415.656655) (xy 391.897729 -415.692351) (xy 391.851869 -415.72182) (xy 391.802281 -415.744461)
			(xy 391.749976 -415.759815) (xy 391.696018 -415.767568) (xy 391.668762 -415.768028) (xy 390.805162 -415.768028)
			(xy 390.777914 -415.767499) (xy 390.723973 -415.759739) (xy 390.671686 -415.744381) (xy 390.622116 -415.721739)
			(xy 390.576273 -415.692273) (xy 390.535089 -415.656584) (xy 390.499404 -415.615397) (xy 390.469943 -415.569551)
			(xy 390.447306 -415.519978) (xy 390.431953 -415.46769) (xy 390.424198 -415.413748) (xy 388.986542 -415.413748)
			(xy 388.986542 -415.413752) (xy 388.978786 -415.4677) (xy 388.963431 -415.519996) (xy 388.94079 -415.569574)
			(xy 388.911325 -415.615426) (xy 388.875634 -415.656618) (xy 388.834444 -415.692311) (xy 388.788594 -415.72178)
			(xy 388.739017 -415.744423) (xy 388.686722 -415.759781) (xy 388.632774 -415.767541) (xy 388.605522 -415.768028)
			(xy 387.741922 -415.768028) (xy 387.71467 -415.767526) (xy 387.660719 -415.759772) (xy 387.608421 -415.744419)
			(xy 387.558841 -415.721779) (xy 387.512988 -415.692313) (xy 387.471794 -415.656621) (xy 387.4361 -415.61543)
			(xy 387.406632 -415.569578) (xy 387.383989 -415.519999) (xy 387.368632 -415.467702) (xy 387.360875 -415.413752)
			(xy 385.923365 -415.413752) (xy 385.923365 -415.413755) (xy 385.915607 -415.467711) (xy 385.900249 -415.520013)
			(xy 385.877604 -415.569597) (xy 385.848133 -415.615453) (xy 385.812436 -415.656648) (xy 385.771239 -415.692344)
			(xy 385.725381 -415.721813) (xy 385.675796 -415.744456) (xy 385.623493 -415.759811) (xy 385.569537 -415.767566)
			(xy 385.542282 -415.768028) (xy 384.678682 -415.768028) (xy 384.651433 -415.767501) (xy 384.59749 -415.759742)
			(xy 384.5452 -415.744387) (xy 384.495628 -415.721746) (xy 384.449782 -415.69228) (xy 384.408597 -415.656591)
			(xy 384.372909 -415.615403) (xy 384.343446 -415.569556) (xy 384.320807 -415.519983) (xy 384.305454 -415.467692)
			(xy 384.297698 -415.413749) (xy 382.860042 -415.413749) (xy 382.860042 -415.413751) (xy 382.852286 -415.467698)
			(xy 382.836933 -415.519992) (xy 382.814293 -415.569569) (xy 382.784829 -415.61542) (xy 382.749141 -415.656611)
			(xy 382.707953 -415.692304) (xy 382.662106 -415.721773) (xy 382.612531 -415.744418) (xy 382.560239 -415.759778)
			(xy 382.506293 -415.767539) (xy 382.479042 -415.768028) (xy 381.615442 -415.768028) (xy 381.588189 -415.767528)
			(xy 381.534236 -415.759776) (xy 381.481936 -415.744424) (xy 381.432353 -415.721785) (xy 381.386497 -415.69232)
			(xy 381.345301 -415.656628) (xy 381.309605 -415.615437) (xy 381.280135 -415.569584) (xy 381.25749 -415.520004)
			(xy 381.242133 -415.467705) (xy 381.234375 -415.413753) (xy 379.796842 -415.413753) (xy 379.789085 -415.467703)
			(xy 379.773729 -415.52) (xy 379.751087 -415.56958) (xy 379.72162 -415.615433) (xy 379.685926 -415.656625)
			(xy 379.644734 -415.692318) (xy 379.598882 -415.721786) (xy 379.549302 -415.744429) (xy 379.497005 -415.759785)
			(xy 379.443055 -415.767542) (xy 379.415802 -415.768028) (xy 378.552202 -415.768028) (xy 378.52495 -415.767525)
			(xy 378.471002 -415.759769) (xy 378.418707 -415.744413) (xy 378.369129 -415.721772) (xy 378.323278 -415.692306)
			(xy 378.282087 -415.656614) (xy 378.246395 -415.615424) (xy 378.216929 -415.569573) (xy 378.194287 -415.519995)
			(xy 378.178932 -415.4677) (xy 378.171175 -415.413752) (xy 376.733665 -415.413752) (xy 376.733665 -415.413756)
			(xy 376.725907 -415.467713) (xy 376.710548 -415.520017) (xy 376.687901 -415.569602) (xy 376.658428 -415.61546)
			(xy 376.622729 -415.656655) (xy 376.581529 -415.692351) (xy 376.535669 -415.72182) (xy 376.486081 -415.744461)
			(xy 376.433776 -415.759815) (xy 376.379818 -415.767568) (xy 376.352562 -415.768028) (xy 375.488962 -415.768028)
			(xy 375.461714 -415.767499) (xy 375.407773 -415.759739) (xy 375.355486 -415.744381) (xy 375.305916 -415.721739)
			(xy 375.260073 -415.692273) (xy 375.218889 -415.656584) (xy 375.183204 -415.615397) (xy 375.153743 -415.569551)
			(xy 375.131106 -415.519978) (xy 375.115753 -415.46769) (xy 375.107998 -415.413748) (xy 373.670342 -415.413748)
			(xy 373.670342 -415.413752) (xy 373.662586 -415.4677) (xy 373.647231 -415.519996) (xy 373.62459 -415.569574)
			(xy 373.595125 -415.615426) (xy 373.559434 -415.656618) (xy 373.518244 -415.692311) (xy 373.472394 -415.72178)
			(xy 373.422817 -415.744423) (xy 373.370522 -415.759781) (xy 373.316574 -415.767541) (xy 373.289322 -415.768028)
			(xy 372.425722 -415.768028) (xy 372.39847 -415.767526) (xy 372.344519 -415.759772) (xy 372.292221 -415.744419)
			(xy 372.242641 -415.721779) (xy 372.196788 -415.692313) (xy 372.155594 -415.656621) (xy 372.1199 -415.61543)
			(xy 372.090432 -415.569578) (xy 372.067789 -415.519999) (xy 372.052432 -415.467702) (xy 372.044675 -415.413752)
			(xy 352.518742 -415.413752) (xy 352.510986 -415.4677) (xy 352.495631 -415.519995) (xy 352.472991 -415.569573)
			(xy 352.443526 -415.615425) (xy 352.407835 -415.656617) (xy 352.366646 -415.69231) (xy 352.320796 -415.721778)
			(xy 352.27122 -415.744422) (xy 352.218925 -415.75978) (xy 352.164977 -415.76754) (xy 352.137726 -415.768028)
			(xy 351.274126 -415.768028) (xy 351.246873 -415.767526) (xy 351.192922 -415.759773) (xy 351.140624 -415.74442)
			(xy 351.091043 -415.72178) (xy 351.045189 -415.692314) (xy 351.003996 -415.656623) (xy 350.968301 -415.615431)
			(xy 350.938832 -415.569579) (xy 350.916189 -415.52) (xy 350.900833 -415.467703) (xy 350.893075 -415.413753)
			(xy 349.455565 -415.413753) (xy 349.455565 -415.413755) (xy 349.447807 -415.46771) (xy 349.43245 -415.520012)
			(xy 349.409805 -415.569595) (xy 349.380334 -415.615452) (xy 349.344637 -415.656647) (xy 349.303441 -415.692343)
			(xy 349.257583 -415.721812) (xy 349.207999 -415.744455) (xy 349.155696 -415.75981) (xy 349.101741 -415.767566)
			(xy 349.074486 -415.768028) (xy 348.210886 -415.768028) (xy 348.183637 -415.767501) (xy 348.129694 -415.759743)
			(xy 348.077403 -415.744388) (xy 348.02783 -415.721747) (xy 347.981984 -415.692282) (xy 347.940798 -415.656592)
			(xy 347.90511 -415.615404) (xy 347.875646 -415.569557) (xy 347.853008 -415.519984) (xy 347.837654 -415.467693)
			(xy 347.829898 -415.413749) (xy 346.392242 -415.413749) (xy 346.392242 -415.413751) (xy 346.384487 -415.467697)
			(xy 346.369133 -415.519991) (xy 346.346494 -415.569568) (xy 346.31703 -415.615418) (xy 346.281342 -415.656609)
			(xy 346.240155 -415.692303) (xy 346.194308 -415.721772) (xy 346.144734 -415.744417) (xy 346.092442 -415.759777)
			(xy 346.038497 -415.767539) (xy 346.011246 -415.768028) (xy 345.147646 -415.768028) (xy 345.120392 -415.767528)
			(xy 345.066439 -415.759777) (xy 345.014139 -415.744425) (xy 344.964555 -415.721787) (xy 344.918699 -415.692321)
			(xy 344.877503 -415.65663) (xy 344.841806 -415.615438) (xy 344.812335 -415.569585) (xy 344.789691 -415.520004)
			(xy 344.774333 -415.467706) (xy 344.766575 -415.413754) (xy 343.329042 -415.413754) (xy 343.321285 -415.467702)
			(xy 343.30593 -415.519999) (xy 343.283288 -415.569579) (xy 343.253821 -415.615431) (xy 343.218128 -415.656624)
			(xy 343.176936 -415.692317) (xy 343.131084 -415.721785) (xy 343.081505 -415.744428) (xy 343.029208 -415.759784)
			(xy 342.975258 -415.767542) (xy 342.948006 -415.768028) (xy 342.084406 -415.768028) (xy 342.057154 -415.767525)
			(xy 342.003206 -415.759769) (xy 341.95091 -415.744415) (xy 341.901331 -415.721774) (xy 341.85548 -415.692307)
			(xy 341.814289 -415.656616) (xy 341.778596 -415.615425) (xy 341.749129 -415.569574) (xy 341.726488 -415.519996)
			(xy 341.711132 -415.4677) (xy 341.703375 -415.413752) (xy 340.265865 -415.413752) (xy 340.265865 -415.413756)
			(xy 340.258107 -415.467713) (xy 340.242748 -415.520016) (xy 340.220102 -415.569601) (xy 340.190629 -415.615458)
			(xy 340.15493 -415.656654) (xy 340.113731 -415.69235) (xy 340.067871 -415.721818) (xy 340.018284 -415.74446)
			(xy 339.965979 -415.759814) (xy 339.912022 -415.767567) (xy 339.884766 -415.768028) (xy 339.021166 -415.768028)
			(xy 338.993918 -415.767499) (xy 338.939977 -415.759739) (xy 338.887689 -415.744382) (xy 338.838118 -415.72174)
			(xy 338.792275 -415.692275) (xy 338.751091 -415.656585) (xy 338.715405 -415.615398) (xy 338.685943 -415.569552)
			(xy 338.663306 -415.519979) (xy 338.647953 -415.46769) (xy 338.640198 -415.413748) (xy 337.202542 -415.413748)
			(xy 337.202542 -415.413751) (xy 337.194786 -415.4677) (xy 337.179431 -415.519995) (xy 337.156791 -415.569573)
			(xy 337.127326 -415.615425) (xy 337.091635 -415.656617) (xy 337.050446 -415.69231) (xy 337.004596 -415.721778)
			(xy 336.95502 -415.744422) (xy 336.902725 -415.75978) (xy 336.848777 -415.76754) (xy 336.821526 -415.768028)
			(xy 335.957926 -415.768028) (xy 335.930673 -415.767526) (xy 335.876722 -415.759773) (xy 335.824424 -415.74442)
			(xy 335.774843 -415.72178) (xy 335.728989 -415.692314) (xy 335.687796 -415.656623) (xy 335.652101 -415.615431)
			(xy 335.622632 -415.569579) (xy 335.599989 -415.52) (xy 335.584633 -415.467703) (xy 335.576875 -415.413753)
			(xy 334.139365 -415.413753) (xy 334.139365 -415.413755) (xy 334.131607 -415.46771) (xy 334.11625 -415.520012)
			(xy 334.093605 -415.569595) (xy 334.064134 -415.615452) (xy 334.028437 -415.656647) (xy 333.987241 -415.692343)
			(xy 333.941383 -415.721812) (xy 333.891799 -415.744455) (xy 333.839496 -415.75981) (xy 333.785541 -415.767566)
			(xy 333.758286 -415.768028) (xy 332.894686 -415.768028) (xy 332.867437 -415.767501) (xy 332.813494 -415.759743)
			(xy 332.761203 -415.744388) (xy 332.71163 -415.721747) (xy 332.665784 -415.692282) (xy 332.624598 -415.656592)
			(xy 332.58891 -415.615404) (xy 332.559446 -415.569557) (xy 332.536808 -415.519984) (xy 332.521454 -415.467693)
			(xy 332.513698 -415.413749) (xy 331.076042 -415.413749) (xy 331.076042 -415.413751) (xy 331.068287 -415.467697)
			(xy 331.052933 -415.519991) (xy 331.030294 -415.569568) (xy 331.00083 -415.615418) (xy 330.965142 -415.656609)
			(xy 330.923955 -415.692303) (xy 330.878108 -415.721772) (xy 330.828534 -415.744417) (xy 330.776242 -415.759777)
			(xy 330.722297 -415.767539) (xy 330.695046 -415.768028) (xy 329.831446 -415.768028) (xy 329.804192 -415.767528)
			(xy 329.750239 -415.759777) (xy 329.697939 -415.744425) (xy 329.648355 -415.721787) (xy 329.602499 -415.692321)
			(xy 329.561303 -415.65663) (xy 329.525606 -415.615438) (xy 329.496135 -415.569585) (xy 329.473491 -415.520004)
			(xy 329.458133 -415.467706) (xy 329.450375 -415.413754) (xy 328.012842 -415.413754) (xy 328.005085 -415.467702)
			(xy 327.98973 -415.519999) (xy 327.967088 -415.569579) (xy 327.937621 -415.615431) (xy 327.901928 -415.656624)
			(xy 327.860736 -415.692317) (xy 327.814884 -415.721785) (xy 327.765305 -415.744428) (xy 327.713008 -415.759784)
			(xy 327.659058 -415.767542) (xy 327.631806 -415.768028) (xy 326.768206 -415.768028) (xy 326.740954 -415.767525)
			(xy 326.687006 -415.759769) (xy 326.63471 -415.744415) (xy 326.585131 -415.721774) (xy 326.53928 -415.692307)
			(xy 326.498089 -415.656616) (xy 326.462396 -415.615425) (xy 326.432929 -415.569574) (xy 326.410288 -415.519996)
			(xy 326.394932 -415.4677) (xy 326.387175 -415.413752) (xy 324.949665 -415.413752) (xy 324.949665 -415.413756)
			(xy 324.941907 -415.467713) (xy 324.926548 -415.520016) (xy 324.903902 -415.569601) (xy 324.874429 -415.615458)
			(xy 324.83873 -415.656654) (xy 324.797531 -415.69235) (xy 324.751671 -415.721818) (xy 324.702084 -415.74446)
			(xy 324.649779 -415.759814) (xy 324.595822 -415.767567) (xy 324.568566 -415.768028) (xy 323.704966 -415.768028)
			(xy 323.677718 -415.767499) (xy 323.623777 -415.759739) (xy 323.571489 -415.744382) (xy 323.521918 -415.72174)
			(xy 323.476075 -415.692275) (xy 323.434891 -415.656585) (xy 323.399205 -415.615398) (xy 323.369743 -415.569552)
			(xy 323.347106 -415.519979) (xy 323.331753 -415.46769) (xy 323.323998 -415.413748) (xy 321.886342 -415.413748)
			(xy 321.886342 -415.413751) (xy 321.878586 -415.4677) (xy 321.863231 -415.519995) (xy 321.840591 -415.569573)
			(xy 321.811126 -415.615425) (xy 321.775435 -415.656617) (xy 321.734246 -415.69231) (xy 321.688396 -415.721778)
			(xy 321.63882 -415.744422) (xy 321.586525 -415.75978) (xy 321.532577 -415.76754) (xy 321.505326 -415.768028)
			(xy 320.641726 -415.768028) (xy 320.614473 -415.767526) (xy 320.560522 -415.759773) (xy 320.508224 -415.74442)
			(xy 320.458643 -415.72178) (xy 320.412789 -415.692314) (xy 320.371596 -415.656623) (xy 320.335901 -415.615431)
			(xy 320.306432 -415.569579) (xy 320.283789 -415.52) (xy 320.268433 -415.467703) (xy 320.260675 -415.413753)
			(xy 318.823165 -415.413753) (xy 318.823165 -415.413755) (xy 318.815407 -415.46771) (xy 318.80005 -415.520012)
			(xy 318.777405 -415.569595) (xy 318.747934 -415.615452) (xy 318.712237 -415.656647) (xy 318.671041 -415.692343)
			(xy 318.625183 -415.721812) (xy 318.575599 -415.744455) (xy 318.523296 -415.75981) (xy 318.469341 -415.767566)
			(xy 318.442086 -415.768028) (xy 317.578486 -415.768028) (xy 317.551237 -415.767501) (xy 317.497294 -415.759743)
			(xy 317.445003 -415.744388) (xy 317.39543 -415.721747) (xy 317.349584 -415.692282) (xy 317.308398 -415.656592)
			(xy 317.27271 -415.615404) (xy 317.243246 -415.569557) (xy 317.220608 -415.519984) (xy 317.205254 -415.467693)
			(xy 317.197498 -415.413749) (xy 315.759842 -415.413749) (xy 315.759842 -415.413751) (xy 315.752087 -415.467697)
			(xy 315.736733 -415.519991) (xy 315.714094 -415.569568) (xy 315.68463 -415.615418) (xy 315.648942 -415.656609)
			(xy 315.607755 -415.692303) (xy 315.561908 -415.721772) (xy 315.512334 -415.744417) (xy 315.460042 -415.759777)
			(xy 315.406097 -415.767539) (xy 315.378846 -415.768028) (xy 314.515246 -415.768028) (xy 314.487992 -415.767528)
			(xy 314.434039 -415.759777) (xy 314.381739 -415.744425) (xy 314.332155 -415.721787) (xy 314.286299 -415.692321)
			(xy 314.245103 -415.65663) (xy 314.209406 -415.615438) (xy 314.179935 -415.569585) (xy 314.157291 -415.520004)
			(xy 314.141933 -415.467706) (xy 314.134175 -415.413754) (xy 312.696642 -415.413754) (xy 312.688885 -415.467702)
			(xy 312.67353 -415.519999) (xy 312.650888 -415.569579) (xy 312.621421 -415.615431) (xy 312.585728 -415.656624)
			(xy 312.544536 -415.692317) (xy 312.498684 -415.721785) (xy 312.449105 -415.744428) (xy 312.396808 -415.759784)
			(xy 312.342858 -415.767542) (xy 312.315606 -415.768028) (xy 311.452006 -415.768028) (xy 311.424754 -415.767525)
			(xy 311.370806 -415.759769) (xy 311.31851 -415.744415) (xy 311.268931 -415.721774) (xy 311.22308 -415.692307)
			(xy 311.181889 -415.656616) (xy 311.146196 -415.615425) (xy 311.116729 -415.569574) (xy 311.094088 -415.519996)
			(xy 311.078732 -415.4677) (xy 311.070975 -415.413752) (xy 309.633465 -415.413752) (xy 309.633465 -415.413756)
			(xy 309.625707 -415.467713) (xy 309.610348 -415.520016) (xy 309.587702 -415.569601) (xy 309.558229 -415.615458)
			(xy 309.52253 -415.656654) (xy 309.481331 -415.69235) (xy 309.435471 -415.721818) (xy 309.385884 -415.74446)
			(xy 309.333579 -415.759814) (xy 309.279622 -415.767567) (xy 309.252366 -415.768028) (xy 308.388766 -415.768028)
			(xy 308.361518 -415.767499) (xy 308.307577 -415.759739) (xy 308.255289 -415.744382) (xy 308.205718 -415.72174)
			(xy 308.159875 -415.692275) (xy 308.118691 -415.656585) (xy 308.083005 -415.615398) (xy 308.053543 -415.569552)
			(xy 308.030906 -415.519979) (xy 308.015553 -415.46769) (xy 308.007798 -415.413748) (xy 306.570142 -415.413748)
			(xy 306.570142 -415.413751) (xy 306.562386 -415.4677) (xy 306.547031 -415.519995) (xy 306.524391 -415.569573)
			(xy 306.494926 -415.615425) (xy 306.459235 -415.656617) (xy 306.418046 -415.69231) (xy 306.372196 -415.721778)
			(xy 306.32262 -415.744422) (xy 306.270325 -415.75978) (xy 306.216377 -415.76754) (xy 306.189126 -415.768028)
			(xy 305.325526 -415.768028) (xy 305.298273 -415.767526) (xy 305.244322 -415.759773) (xy 305.192024 -415.74442)
			(xy 305.142443 -415.72178) (xy 305.096589 -415.692314) (xy 305.055396 -415.656623) (xy 305.019701 -415.615431)
			(xy 304.990232 -415.569579) (xy 304.967589 -415.52) (xy 304.952233 -415.467703) (xy 304.944475 -415.413753)
			(xy 300.882586 -415.413753) (xy 300.868941 -415.434612) (xy 300.76479 -415.579315) (xy 300.654297 -415.719235)
			(xy 300.53768 -415.854094) (xy 300.415171 -415.983624) (xy 300.287014 -416.107568) (xy 300.153463 -416.22568)
			(xy 300.014783 -416.337725) (xy 299.871249 -416.443482) (xy 299.723146 -416.542739) (xy 299.570769 -416.635301)
			(xy 299.41442 -416.720982) (xy 299.254409 -416.799614) (xy 299.091055 -416.87104) (xy 298.92468 -416.935118)
			(xy 298.755617 -416.99172) (xy 298.5842 -417.040736) (xy 298.410769 -417.082066) (xy 298.235669 -417.11563)
			(xy 298.059249 -417.14136) (xy 297.881857 -417.159206) (xy 297.703846 -417.169132) (xy 297.525569 -417.171118)
			(xy 297.347382 -417.165161) (xy 297.169636 -417.151271) (xy 296.992686 -417.129478) (xy 296.816882 -417.099824)
			(xy 296.642574 -417.062367) (xy 296.470107 -417.017183) (xy 296.299824 -416.964361) (xy 296.132063 -416.904005)
			(xy 295.967158 -416.836237) (xy 295.805435 -416.761189) (xy 295.647216 -416.679012) (xy 295.492815 -416.589869)
			(xy 295.342538 -416.493935) (xy 295.196683 -416.391403) (xy 295.055541 -416.282475) (xy 294.919392 -416.167368)
			(xy 294.788505 -416.04631) (xy 294.663141 -415.919541) (xy 294.543548 -415.787314) (xy 294.429965 -415.649891)
			(xy 294.322616 -415.507544) (xy 294.221715 -415.360556) (xy 294.127462 -415.20922) (xy 294.040044 -415.053835)
			(xy 293.959634 -414.89471) (xy 293.886393 -414.732161) (xy 293.820466 -414.566511) (xy 293.761983 -414.398089)
			(xy 293.711061 -414.227228) (xy 293.667801 -414.054269) (xy 293.632289 -413.879554) (xy 293.604595 -413.70343)
			(xy 293.584774 -413.526248) (xy 293.572866 -413.348359) (xy 293.568894 -413.170116) (xy 276.749256 -413.170116)
			(xy 272.414746 -417.504626) (xy 272.396783 -417.521953) (xy 272.356401 -417.55128) (xy 272.311928 -417.573928)
			(xy 272.264459 -417.589339) (xy 272.215164 -417.597133) (xy 272.19021 -417.59759) (xy 235.05033 -417.59759)
			(xy 235.040259 -417.598007) (xy 235.02166 -417.605731) (xy 235.014262 -417.612576) (xy 233.545126 -419.081712)
			(xy 276.721824 -419.081712) (xy 276.721824 -418.218112) (xy 276.72231 -418.190861) (xy 276.730066 -418.136913)
			(xy 276.745421 -418.084618) (xy 276.768063 -418.035041) (xy 276.797529 -417.989191) (xy 276.83322 -417.948)
			(xy 276.874411 -417.912309) (xy 276.920261 -417.882843) (xy 276.969838 -417.860201) (xy 277.022133 -417.844846)
			(xy 277.076081 -417.83709) (xy 277.130583 -417.83709) (xy 277.184531 -417.844846) (xy 277.236826 -417.860201)
			(xy 277.286403 -417.882843) (xy 277.332253 -417.912309) (xy 277.373444 -417.948) (xy 277.409135 -417.989191)
			(xy 277.438601 -418.035041) (xy 277.461243 -418.084618) (xy 277.476598 -418.136913) (xy 277.484354 -418.190861)
			(xy 277.48484 -418.218112) (xy 277.48484 -418.254688) (xy 289.453828 -418.254688) (xy 289.453828 -417.391088)
			(xy 289.454314 -417.363837) (xy 289.46207 -417.309889) (xy 289.477425 -417.257594) (xy 289.500067 -417.208017)
			(xy 289.529533 -417.162167) (xy 289.565224 -417.120976) (xy 289.606415 -417.085285) (xy 289.652265 -417.055819)
			(xy 289.701842 -417.033177) (xy 289.754137 -417.017822) (xy 289.808085 -417.010066) (xy 289.862587 -417.010066)
			(xy 289.916535 -417.017822) (xy 289.96883 -417.033177) (xy 290.018407 -417.055819) (xy 290.064257 -417.085285)
			(xy 290.105448 -417.120976) (xy 290.141139 -417.162167) (xy 290.170605 -417.208017) (xy 290.193247 -417.257594)
			(xy 290.208602 -417.309889) (xy 290.216358 -417.363837) (xy 290.216844 -417.391088) (xy 290.216844 -418.254688)
			(xy 290.216358 -418.281939) (xy 290.208602 -418.335887) (xy 290.193247 -418.388182) (xy 290.170605 -418.437759)
			(xy 290.169514 -418.439456) (xy 304.944423 -418.439456) (xy 304.944423 -418.384944) (xy 304.952181 -418.330986)
			(xy 304.96754 -418.278681) (xy 304.990186 -418.229095) (xy 305.019659 -418.183237) (xy 305.055359 -418.14204)
			(xy 305.096558 -418.106344) (xy 305.142418 -418.076874) (xy 305.192006 -418.054231) (xy 305.244311 -418.038876)
			(xy 305.29827 -418.031121) (xy 305.325526 -418.03066) (xy 306.189126 -418.03066) (xy 306.216374 -418.031212)
			(xy 306.270314 -418.038971) (xy 306.322601 -418.054327) (xy 306.372171 -418.076968) (xy 306.418014 -418.106432)
			(xy 306.459198 -418.142121) (xy 306.494884 -418.183307) (xy 306.524345 -418.229152) (xy 306.546982 -418.278723)
			(xy 306.562335 -418.331011) (xy 306.57009 -418.384952) (xy 306.57009 -418.439448) (xy 306.570089 -418.439452)
			(xy 308.007746 -418.439452) (xy 308.007746 -418.384948) (xy 308.015502 -418.330999) (xy 308.030857 -418.278702)
			(xy 308.053497 -418.229123) (xy 308.082963 -418.183271) (xy 308.118654 -418.142078) (xy 308.159843 -418.106383)
			(xy 308.205693 -418.076914) (xy 308.25527 -418.054269) (xy 308.307565 -418.038909) (xy 308.361514 -418.031148)
			(xy 308.388766 -418.03066) (xy 309.252366 -418.03066) (xy 309.279618 -418.031185) (xy 309.333568 -418.038937)
			(xy 309.385866 -418.054289) (xy 309.435446 -418.076928) (xy 309.4813 -418.106392) (xy 309.522493 -418.142083)
			(xy 309.558187 -418.183273) (xy 309.587656 -418.229124) (xy 309.610299 -418.278702) (xy 309.625655 -418.330999)
			(xy 309.633413 -418.384948) (xy 309.633413 -418.439452) (xy 309.633413 -418.439455) (xy 311.070923 -418.439455)
			(xy 311.070923 -418.384945) (xy 311.078681 -418.330989) (xy 311.094038 -418.278686) (xy 311.116683 -418.229101)
			(xy 311.146154 -418.183244) (xy 311.181852 -418.142047) (xy 311.223049 -418.106351) (xy 311.268906 -418.07688)
			(xy 311.318491 -418.054236) (xy 311.370794 -418.038879) (xy 311.424751 -418.031123) (xy 311.452006 -418.03066)
			(xy 312.315606 -418.03066) (xy 312.342855 -418.031211) (xy 312.396797 -418.038967) (xy 312.449087 -418.054321)
			(xy 312.498659 -418.076961) (xy 312.544505 -418.106425) (xy 312.585691 -418.142113) (xy 312.621379 -418.1833)
			(xy 312.650842 -418.229146) (xy 312.673481 -418.278719) (xy 312.688834 -418.331009) (xy 312.69659 -418.384951)
			(xy 312.69659 -418.439449) (xy 312.696589 -418.439457) (xy 314.134123 -418.439457) (xy 314.134123 -418.384943)
			(xy 314.141882 -418.330983) (xy 314.157242 -418.278677) (xy 314.179889 -418.22909) (xy 314.209364 -418.183231)
			(xy 314.245066 -418.142033) (xy 314.286267 -418.106337) (xy 314.33213 -418.076867) (xy 314.38172 -418.054225)
			(xy 314.434028 -418.038872) (xy 314.487989 -418.03112) (xy 314.515246 -418.03066) (xy 315.378846 -418.03066)
			(xy 315.406093 -418.031213) (xy 315.460031 -418.038975) (xy 315.512316 -418.054332) (xy 315.561883 -418.076974)
			(xy 315.607724 -418.106439) (xy 315.648905 -418.142128) (xy 315.684588 -418.183313) (xy 315.714048 -418.229157)
			(xy 315.736684 -418.278727) (xy 315.752035 -418.331014) (xy 315.75979 -418.384953) (xy 315.75979 -418.439447)
			(xy 315.759789 -418.439453) (xy 317.197446 -418.439453) (xy 317.197446 -418.384947) (xy 317.205203 -418.330996)
			(xy 317.220558 -418.278698) (xy 317.2432 -418.229118) (xy 317.272668 -418.183264) (xy 317.308361 -418.142071)
			(xy 317.349553 -418.106376) (xy 317.395405 -418.076907) (xy 317.444985 -418.054263) (xy 317.497282 -418.038906)
			(xy 317.551233 -418.031147) (xy 317.578486 -418.03066) (xy 318.442086 -418.03066) (xy 318.469337 -418.031186)
			(xy 318.523285 -418.038941) (xy 318.57558 -418.054295) (xy 318.625158 -418.076934) (xy 318.671009 -418.106399)
			(xy 318.7122 -418.14209) (xy 318.747892 -418.18328) (xy 318.777359 -418.22913) (xy 318.800001 -418.278707)
			(xy 318.815356 -418.331001) (xy 318.823113 -418.384949) (xy 318.823113 -418.439451) (xy 318.823112 -418.439456)
			(xy 320.260623 -418.439456) (xy 320.260623 -418.384944) (xy 320.268381 -418.330986) (xy 320.28374 -418.278681)
			(xy 320.306386 -418.229095) (xy 320.335859 -418.183237) (xy 320.371559 -418.14204) (xy 320.412758 -418.106344)
			(xy 320.458618 -418.076874) (xy 320.508206 -418.054231) (xy 320.560511 -418.038876) (xy 320.61447 -418.031121)
			(xy 320.641726 -418.03066) (xy 321.505326 -418.03066) (xy 321.532574 -418.031212) (xy 321.586514 -418.038971)
			(xy 321.638801 -418.054327) (xy 321.688371 -418.076968) (xy 321.734214 -418.106432) (xy 321.775398 -418.142121)
			(xy 321.811084 -418.183307) (xy 321.840545 -418.229152) (xy 321.863182 -418.278723) (xy 321.878535 -418.331011)
			(xy 321.88629 -418.384952) (xy 321.88629 -418.439448) (xy 321.886289 -418.439452) (xy 323.323946 -418.439452)
			(xy 323.323946 -418.384948) (xy 323.331702 -418.330999) (xy 323.347057 -418.278702) (xy 323.369697 -418.229123)
			(xy 323.399163 -418.183271) (xy 323.434854 -418.142078) (xy 323.476043 -418.106383) (xy 323.521893 -418.076914)
			(xy 323.57147 -418.054269) (xy 323.623765 -418.038909) (xy 323.677714 -418.031148) (xy 323.704966 -418.03066)
			(xy 324.568566 -418.03066) (xy 324.595818 -418.031185) (xy 324.649768 -418.038937) (xy 324.702066 -418.054289)
			(xy 324.751646 -418.076928) (xy 324.7975 -418.106392) (xy 324.838693 -418.142083) (xy 324.874387 -418.183273)
			(xy 324.903856 -418.229124) (xy 324.926499 -418.278702) (xy 324.941855 -418.330999) (xy 324.949613 -418.384948)
			(xy 324.949613 -418.439452) (xy 324.949613 -418.439455) (xy 326.387123 -418.439455) (xy 326.387123 -418.384945)
			(xy 326.394881 -418.330989) (xy 326.410238 -418.278686) (xy 326.432883 -418.229101) (xy 326.462354 -418.183244)
			(xy 326.498052 -418.142047) (xy 326.539249 -418.106351) (xy 326.585106 -418.07688) (xy 326.634691 -418.054236)
			(xy 326.686994 -418.038879) (xy 326.740951 -418.031123) (xy 326.768206 -418.03066) (xy 327.631806 -418.03066)
			(xy 327.659055 -418.031211) (xy 327.712997 -418.038967) (xy 327.765287 -418.054321) (xy 327.814859 -418.076961)
			(xy 327.860705 -418.106425) (xy 327.901891 -418.142113) (xy 327.937579 -418.1833) (xy 327.967042 -418.229146)
			(xy 327.989681 -418.278719) (xy 328.005034 -418.331009) (xy 328.01279 -418.384951) (xy 328.01279 -418.439449)
			(xy 328.012789 -418.439457) (xy 329.450323 -418.439457) (xy 329.450323 -418.384943) (xy 329.458082 -418.330983)
			(xy 329.473442 -418.278677) (xy 329.496089 -418.22909) (xy 329.525564 -418.183231) (xy 329.561266 -418.142033)
			(xy 329.602467 -418.106337) (xy 329.64833 -418.076867) (xy 329.69792 -418.054225) (xy 329.750228 -418.038872)
			(xy 329.804189 -418.03112) (xy 329.831446 -418.03066) (xy 330.695046 -418.03066) (xy 330.722293 -418.031213)
			(xy 330.776231 -418.038975) (xy 330.828516 -418.054332) (xy 330.878083 -418.076974) (xy 330.923924 -418.106439)
			(xy 330.965105 -418.142128) (xy 331.000788 -418.183313) (xy 331.030248 -418.229157) (xy 331.052884 -418.278727)
			(xy 331.068235 -418.331014) (xy 331.07599 -418.384953) (xy 331.07599 -418.439447) (xy 331.075989 -418.439453)
			(xy 332.513646 -418.439453) (xy 332.513646 -418.384947) (xy 332.521403 -418.330996) (xy 332.536758 -418.278698)
			(xy 332.5594 -418.229118) (xy 332.588868 -418.183264) (xy 332.624561 -418.142071) (xy 332.665753 -418.106376)
			(xy 332.711605 -418.076907) (xy 332.761185 -418.054263) (xy 332.813482 -418.038906) (xy 332.867433 -418.031147)
			(xy 332.894686 -418.03066) (xy 333.758286 -418.03066) (xy 333.785537 -418.031186) (xy 333.839485 -418.038941)
			(xy 333.89178 -418.054295) (xy 333.941358 -418.076934) (xy 333.987209 -418.106399) (xy 334.0284 -418.14209)
			(xy 334.064092 -418.18328) (xy 334.093559 -418.22913) (xy 334.116201 -418.278707) (xy 334.131556 -418.331001)
			(xy 334.139313 -418.384949) (xy 334.139313 -418.439451) (xy 334.139312 -418.439456) (xy 335.576823 -418.439456)
			(xy 335.576823 -418.384944) (xy 335.584581 -418.330986) (xy 335.59994 -418.278681) (xy 335.622586 -418.229095)
			(xy 335.652059 -418.183237) (xy 335.687759 -418.14204) (xy 335.728958 -418.106344) (xy 335.774818 -418.076874)
			(xy 335.824406 -418.054231) (xy 335.876711 -418.038876) (xy 335.93067 -418.031121) (xy 335.957926 -418.03066)
			(xy 336.821526 -418.03066) (xy 336.848774 -418.031212) (xy 336.902714 -418.038971) (xy 336.955001 -418.054327)
			(xy 337.004571 -418.076968) (xy 337.050414 -418.106432) (xy 337.091598 -418.142121) (xy 337.127284 -418.183307)
			(xy 337.156745 -418.229152) (xy 337.179382 -418.278723) (xy 337.194735 -418.331011) (xy 337.20249 -418.384952)
			(xy 337.20249 -418.439448) (xy 337.202489 -418.439452) (xy 338.640146 -418.439452) (xy 338.640146 -418.384948)
			(xy 338.647902 -418.330999) (xy 338.663257 -418.278702) (xy 338.685897 -418.229123) (xy 338.715363 -418.183271)
			(xy 338.751054 -418.142078) (xy 338.792243 -418.106383) (xy 338.838093 -418.076914) (xy 338.88767 -418.054269)
			(xy 338.939965 -418.038909) (xy 338.993914 -418.031148) (xy 339.021166 -418.03066) (xy 339.884766 -418.03066)
			(xy 339.912018 -418.031185) (xy 339.965968 -418.038937) (xy 340.018266 -418.054289) (xy 340.067846 -418.076928)
			(xy 340.1137 -418.106392) (xy 340.154893 -418.142083) (xy 340.190587 -418.183273) (xy 340.220056 -418.229124)
			(xy 340.242699 -418.278702) (xy 340.258055 -418.330999) (xy 340.265813 -418.384948) (xy 340.265813 -418.439452)
			(xy 340.265813 -418.439455) (xy 341.703323 -418.439455) (xy 341.703323 -418.384945) (xy 341.711081 -418.330989)
			(xy 341.726438 -418.278686) (xy 341.749083 -418.229101) (xy 341.778554 -418.183244) (xy 341.814252 -418.142047)
			(xy 341.855449 -418.106351) (xy 341.901306 -418.07688) (xy 341.950891 -418.054236) (xy 342.003194 -418.038879)
			(xy 342.057151 -418.031123) (xy 342.084406 -418.03066) (xy 342.948006 -418.03066) (xy 342.975255 -418.031211)
			(xy 343.029197 -418.038967) (xy 343.081487 -418.054321) (xy 343.131059 -418.076961) (xy 343.176905 -418.106425)
			(xy 343.218091 -418.142113) (xy 343.253779 -418.1833) (xy 343.283242 -418.229146) (xy 343.305881 -418.278719)
			(xy 343.321234 -418.331009) (xy 343.32899 -418.384951) (xy 343.32899 -418.439449) (xy 343.328989 -418.439457)
			(xy 344.766523 -418.439457) (xy 344.766523 -418.384943) (xy 344.774282 -418.330983) (xy 344.789642 -418.278677)
			(xy 344.812289 -418.22909) (xy 344.841764 -418.183231) (xy 344.877466 -418.142033) (xy 344.918667 -418.106337)
			(xy 344.96453 -418.076867) (xy 345.01412 -418.054225) (xy 345.066428 -418.038872) (xy 345.120389 -418.03112)
			(xy 345.147646 -418.03066) (xy 346.011246 -418.03066) (xy 346.038493 -418.031213) (xy 346.092431 -418.038975)
			(xy 346.144716 -418.054332) (xy 346.194283 -418.076974) (xy 346.240124 -418.106439) (xy 346.281305 -418.142128)
			(xy 346.316988 -418.183313) (xy 346.346448 -418.229157) (xy 346.369084 -418.278727) (xy 346.384435 -418.331014)
			(xy 346.39219 -418.384953) (xy 346.39219 -418.439447) (xy 346.392189 -418.439453) (xy 347.829846 -418.439453)
			(xy 347.829846 -418.384947) (xy 347.837603 -418.330996) (xy 347.852958 -418.278698) (xy 347.8756 -418.229118)
			(xy 347.905068 -418.183264) (xy 347.940761 -418.142071) (xy 347.981953 -418.106376) (xy 348.027805 -418.076907)
			(xy 348.077385 -418.054263) (xy 348.129682 -418.038906) (xy 348.183633 -418.031147) (xy 348.210886 -418.03066)
			(xy 349.074486 -418.03066) (xy 349.101737 -418.031186) (xy 349.155685 -418.038941) (xy 349.20798 -418.054295)
			(xy 349.257558 -418.076934) (xy 349.303409 -418.106399) (xy 349.3446 -418.14209) (xy 349.380292 -418.18328)
			(xy 349.409759 -418.22913) (xy 349.432401 -418.278707) (xy 349.447756 -418.331001) (xy 349.455513 -418.384949)
			(xy 349.455513 -418.439451) (xy 349.455512 -418.439456) (xy 350.893023 -418.439456) (xy 350.893023 -418.384944)
			(xy 350.900781 -418.330986) (xy 350.91614 -418.278681) (xy 350.938786 -418.229095) (xy 350.968259 -418.183237)
			(xy 351.003959 -418.14204) (xy 351.045158 -418.106344) (xy 351.091018 -418.076874) (xy 351.140606 -418.054231)
			(xy 351.192911 -418.038876) (xy 351.24687 -418.031121) (xy 351.274126 -418.03066) (xy 352.137726 -418.03066)
			(xy 352.164974 -418.031212) (xy 352.218914 -418.038971) (xy 352.271201 -418.054327) (xy 352.320771 -418.076968)
			(xy 352.366614 -418.106432) (xy 352.407798 -418.142121) (xy 352.443484 -418.183307) (xy 352.472945 -418.229152)
			(xy 352.495582 -418.278723) (xy 352.510935 -418.331011) (xy 352.51869 -418.384952) (xy 352.51869 -418.439448)
			(xy 352.510935 -418.493389) (xy 352.495582 -418.545677) (xy 352.472945 -418.595248) (xy 352.443484 -418.641093)
			(xy 352.407798 -418.682279) (xy 352.366614 -418.717968) (xy 352.320771 -418.747432) (xy 352.271201 -418.770073)
			(xy 352.218914 -418.785429) (xy 352.164974 -418.793188) (xy 352.137726 -418.793676) (xy 351.274126 -418.793676)
			(xy 351.24687 -418.793279) (xy 351.192911 -418.785524) (xy 351.140606 -418.770169) (xy 351.091018 -418.747526)
			(xy 351.045158 -418.718056) (xy 351.003959 -418.68236) (xy 350.968259 -418.641163) (xy 350.938786 -418.595305)
			(xy 350.91614 -418.545719) (xy 350.900781 -418.493414) (xy 350.893023 -418.439456) (xy 349.455512 -418.439456)
			(xy 349.447756 -418.493399) (xy 349.432401 -418.545693) (xy 349.409759 -418.59527) (xy 349.380292 -418.64112)
			(xy 349.3446 -418.68231) (xy 349.303409 -418.718001) (xy 349.257558 -418.747466) (xy 349.20798 -418.770105)
			(xy 349.155685 -418.785459) (xy 349.101737 -418.793214) (xy 349.074486 -418.793676) (xy 348.210886 -418.793676)
			(xy 348.183633 -418.793253) (xy 348.129682 -418.785494) (xy 348.077385 -418.770137) (xy 348.027805 -418.747493)
			(xy 347.981953 -418.718024) (xy 347.940761 -418.682329) (xy 347.905068 -418.641136) (xy 347.8756 -418.595282)
			(xy 347.852958 -418.545702) (xy 347.837603 -418.493404) (xy 347.829846 -418.439453) (xy 346.392189 -418.439453)
			(xy 346.384435 -418.493386) (xy 346.369084 -418.545673) (xy 346.346448 -418.595243) (xy 346.316988 -418.641087)
			(xy 346.281305 -418.682272) (xy 346.240124 -418.717961) (xy 346.194283 -418.747426) (xy 346.144716 -418.770068)
			(xy 346.092431 -418.785425) (xy 346.038493 -418.793187) (xy 346.011246 -418.793676) (xy 345.147646 -418.793676)
			(xy 345.120389 -418.79328) (xy 345.066428 -418.785528) (xy 345.01412 -418.770175) (xy 344.96453 -418.747533)
			(xy 344.918667 -418.718063) (xy 344.877466 -418.682367) (xy 344.841764 -418.641169) (xy 344.812289 -418.59531)
			(xy 344.789642 -418.545723) (xy 344.774282 -418.493417) (xy 344.766523 -418.439457) (xy 343.328989 -418.439457)
			(xy 343.321234 -418.493391) (xy 343.305881 -418.545681) (xy 343.283242 -418.595254) (xy 343.253779 -418.6411)
			(xy 343.218091 -418.682287) (xy 343.176905 -418.717975) (xy 343.131059 -418.747439) (xy 343.081487 -418.770079)
			(xy 343.029197 -418.785433) (xy 342.975255 -418.793189) (xy 342.948006 -418.793676) (xy 342.084406 -418.793676)
			(xy 342.057151 -418.793277) (xy 342.003194 -418.785521) (xy 341.950891 -418.770164) (xy 341.901306 -418.74752)
			(xy 341.855449 -418.718049) (xy 341.814252 -418.682353) (xy 341.778554 -418.641156) (xy 341.749083 -418.595299)
			(xy 341.726438 -418.545714) (xy 341.711081 -418.493411) (xy 341.703323 -418.439455) (xy 340.265813 -418.439455)
			(xy 340.258055 -418.493402) (xy 340.242699 -418.545698) (xy 340.220056 -418.595276) (xy 340.190587 -418.641127)
			(xy 340.154893 -418.682317) (xy 340.1137 -418.718008) (xy 340.067846 -418.747472) (xy 340.018266 -418.770111)
			(xy 339.965968 -418.785463) (xy 339.912018 -418.793215) (xy 339.884766 -418.793676) (xy 339.021166 -418.793676)
			(xy 338.993914 -418.793252) (xy 338.939965 -418.785491) (xy 338.88767 -418.770131) (xy 338.838093 -418.747486)
			(xy 338.792243 -418.718017) (xy 338.751054 -418.682322) (xy 338.715363 -418.641129) (xy 338.685897 -418.595277)
			(xy 338.663257 -418.545698) (xy 338.647902 -418.493401) (xy 338.640146 -418.439452) (xy 337.202489 -418.439452)
			(xy 337.194735 -418.493389) (xy 337.179382 -418.545677) (xy 337.156745 -418.595248) (xy 337.127284 -418.641093)
			(xy 337.091598 -418.682279) (xy 337.050414 -418.717968) (xy 337.004571 -418.747432) (xy 336.955001 -418.770073)
			(xy 336.902714 -418.785429) (xy 336.848774 -418.793188) (xy 336.821526 -418.793676) (xy 335.957926 -418.793676)
			(xy 335.93067 -418.793279) (xy 335.876711 -418.785524) (xy 335.824406 -418.770169) (xy 335.774818 -418.747526)
			(xy 335.728958 -418.718056) (xy 335.687759 -418.68236) (xy 335.652059 -418.641163) (xy 335.622586 -418.595305)
			(xy 335.59994 -418.545719) (xy 335.584581 -418.493414) (xy 335.576823 -418.439456) (xy 334.139312 -418.439456)
			(xy 334.131556 -418.493399) (xy 334.116201 -418.545693) (xy 334.093559 -418.59527) (xy 334.064092 -418.64112)
			(xy 334.0284 -418.68231) (xy 333.987209 -418.718001) (xy 333.941358 -418.747466) (xy 333.89178 -418.770105)
			(xy 333.839485 -418.785459) (xy 333.785537 -418.793214) (xy 333.758286 -418.793676) (xy 332.894686 -418.793676)
			(xy 332.867433 -418.793253) (xy 332.813482 -418.785494) (xy 332.761185 -418.770137) (xy 332.711605 -418.747493)
			(xy 332.665753 -418.718024) (xy 332.624561 -418.682329) (xy 332.588868 -418.641136) (xy 332.5594 -418.595282)
			(xy 332.536758 -418.545702) (xy 332.521403 -418.493404) (xy 332.513646 -418.439453) (xy 331.075989 -418.439453)
			(xy 331.068235 -418.493386) (xy 331.052884 -418.545673) (xy 331.030248 -418.595243) (xy 331.000788 -418.641087)
			(xy 330.965105 -418.682272) (xy 330.923924 -418.717961) (xy 330.878083 -418.747426) (xy 330.828516 -418.770068)
			(xy 330.776231 -418.785425) (xy 330.722293 -418.793187) (xy 330.695046 -418.793676) (xy 329.831446 -418.793676)
			(xy 329.804189 -418.79328) (xy 329.750228 -418.785528) (xy 329.69792 -418.770175) (xy 329.64833 -418.747533)
			(xy 329.602467 -418.718063) (xy 329.561266 -418.682367) (xy 329.525564 -418.641169) (xy 329.496089 -418.59531)
			(xy 329.473442 -418.545723) (xy 329.458082 -418.493417) (xy 329.450323 -418.439457) (xy 328.012789 -418.439457)
			(xy 328.005034 -418.493391) (xy 327.989681 -418.545681) (xy 327.967042 -418.595254) (xy 327.937579 -418.6411)
			(xy 327.901891 -418.682287) (xy 327.860705 -418.717975) (xy 327.814859 -418.747439) (xy 327.765287 -418.770079)
			(xy 327.712997 -418.785433) (xy 327.659055 -418.793189) (xy 327.631806 -418.793676) (xy 326.768206 -418.793676)
			(xy 326.740951 -418.793277) (xy 326.686994 -418.785521) (xy 326.634691 -418.770164) (xy 326.585106 -418.74752)
			(xy 326.539249 -418.718049) (xy 326.498052 -418.682353) (xy 326.462354 -418.641156) (xy 326.432883 -418.595299)
			(xy 326.410238 -418.545714) (xy 326.394881 -418.493411) (xy 326.387123 -418.439455) (xy 324.949613 -418.439455)
			(xy 324.941855 -418.493402) (xy 324.926499 -418.545698) (xy 324.903856 -418.595276) (xy 324.874387 -418.641127)
			(xy 324.838693 -418.682317) (xy 324.7975 -418.718008) (xy 324.751646 -418.747472) (xy 324.702066 -418.770111)
			(xy 324.649768 -418.785463) (xy 324.595818 -418.793215) (xy 324.568566 -418.793676) (xy 323.704966 -418.793676)
			(xy 323.677714 -418.793252) (xy 323.623765 -418.785491) (xy 323.57147 -418.770131) (xy 323.521893 -418.747486)
			(xy 323.476043 -418.718017) (xy 323.434854 -418.682322) (xy 323.399163 -418.641129) (xy 323.369697 -418.595277)
			(xy 323.347057 -418.545698) (xy 323.331702 -418.493401) (xy 323.323946 -418.439452) (xy 321.886289 -418.439452)
			(xy 321.878535 -418.493389) (xy 321.863182 -418.545677) (xy 321.840545 -418.595248) (xy 321.811084 -418.641093)
			(xy 321.775398 -418.682279) (xy 321.734214 -418.717968) (xy 321.688371 -418.747432) (xy 321.638801 -418.770073)
			(xy 321.586514 -418.785429) (xy 321.532574 -418.793188) (xy 321.505326 -418.793676) (xy 320.641726 -418.793676)
			(xy 320.61447 -418.793279) (xy 320.560511 -418.785524) (xy 320.508206 -418.770169) (xy 320.458618 -418.747526)
			(xy 320.412758 -418.718056) (xy 320.371559 -418.68236) (xy 320.335859 -418.641163) (xy 320.306386 -418.595305)
			(xy 320.28374 -418.545719) (xy 320.268381 -418.493414) (xy 320.260623 -418.439456) (xy 318.823112 -418.439456)
			(xy 318.815356 -418.493399) (xy 318.800001 -418.545693) (xy 318.777359 -418.59527) (xy 318.747892 -418.64112)
			(xy 318.7122 -418.68231) (xy 318.671009 -418.718001) (xy 318.625158 -418.747466) (xy 318.57558 -418.770105)
			(xy 318.523285 -418.785459) (xy 318.469337 -418.793214) (xy 318.442086 -418.793676) (xy 317.578486 -418.793676)
			(xy 317.551233 -418.793253) (xy 317.497282 -418.785494) (xy 317.444985 -418.770137) (xy 317.395405 -418.747493)
			(xy 317.349553 -418.718024) (xy 317.308361 -418.682329) (xy 317.272668 -418.641136) (xy 317.2432 -418.595282)
			(xy 317.220558 -418.545702) (xy 317.205203 -418.493404) (xy 317.197446 -418.439453) (xy 315.759789 -418.439453)
			(xy 315.752035 -418.493386) (xy 315.736684 -418.545673) (xy 315.714048 -418.595243) (xy 315.684588 -418.641087)
			(xy 315.648905 -418.682272) (xy 315.607724 -418.717961) (xy 315.561883 -418.747426) (xy 315.512316 -418.770068)
			(xy 315.460031 -418.785425) (xy 315.406093 -418.793187) (xy 315.378846 -418.793676) (xy 314.515246 -418.793676)
			(xy 314.487989 -418.79328) (xy 314.434028 -418.785528) (xy 314.38172 -418.770175) (xy 314.33213 -418.747533)
			(xy 314.286267 -418.718063) (xy 314.245066 -418.682367) (xy 314.209364 -418.641169) (xy 314.179889 -418.59531)
			(xy 314.157242 -418.545723) (xy 314.141882 -418.493417) (xy 314.134123 -418.439457) (xy 312.696589 -418.439457)
			(xy 312.688834 -418.493391) (xy 312.673481 -418.545681) (xy 312.650842 -418.595254) (xy 312.621379 -418.6411)
			(xy 312.585691 -418.682287) (xy 312.544505 -418.717975) (xy 312.498659 -418.747439) (xy 312.449087 -418.770079)
			(xy 312.396797 -418.785433) (xy 312.342855 -418.793189) (xy 312.315606 -418.793676) (xy 311.452006 -418.793676)
			(xy 311.424751 -418.793277) (xy 311.370794 -418.785521) (xy 311.318491 -418.770164) (xy 311.268906 -418.74752)
			(xy 311.223049 -418.718049) (xy 311.181852 -418.682353) (xy 311.146154 -418.641156) (xy 311.116683 -418.595299)
			(xy 311.094038 -418.545714) (xy 311.078681 -418.493411) (xy 311.070923 -418.439455) (xy 309.633413 -418.439455)
			(xy 309.625655 -418.493402) (xy 309.610299 -418.545698) (xy 309.587656 -418.595276) (xy 309.558187 -418.641127)
			(xy 309.522493 -418.682317) (xy 309.4813 -418.718008) (xy 309.435446 -418.747472) (xy 309.385866 -418.770111)
			(xy 309.333568 -418.785463) (xy 309.279618 -418.793215) (xy 309.252366 -418.793676) (xy 308.388766 -418.793676)
			(xy 308.361514 -418.793252) (xy 308.307565 -418.785491) (xy 308.25527 -418.770131) (xy 308.205693 -418.747486)
			(xy 308.159843 -418.718017) (xy 308.118654 -418.682322) (xy 308.082963 -418.641129) (xy 308.053497 -418.595277)
			(xy 308.030857 -418.545698) (xy 308.015502 -418.493401) (xy 308.007746 -418.439452) (xy 306.570089 -418.439452)
			(xy 306.562335 -418.493389) (xy 306.546982 -418.545677) (xy 306.524345 -418.595248) (xy 306.494884 -418.641093)
			(xy 306.459198 -418.682279) (xy 306.418014 -418.717968) (xy 306.372171 -418.747432) (xy 306.322601 -418.770073)
			(xy 306.270314 -418.785429) (xy 306.216374 -418.793188) (xy 306.189126 -418.793676) (xy 305.325526 -418.793676)
			(xy 305.29827 -418.793279) (xy 305.244311 -418.785524) (xy 305.192006 -418.770169) (xy 305.142418 -418.747526)
			(xy 305.096558 -418.718056) (xy 305.055359 -418.68236) (xy 305.019659 -418.641163) (xy 304.990186 -418.595305)
			(xy 304.96754 -418.545719) (xy 304.952181 -418.493414) (xy 304.944423 -418.439456) (xy 290.169514 -418.439456)
			(xy 290.141139 -418.483609) (xy 290.105448 -418.5248) (xy 290.064257 -418.560491) (xy 290.018407 -418.589957)
			(xy 289.96883 -418.612599) (xy 289.916535 -418.627954) (xy 289.862587 -418.63571) (xy 289.808085 -418.63571)
			(xy 289.754137 -418.627954) (xy 289.701842 -418.612599) (xy 289.652265 -418.589957) (xy 289.606415 -418.560491)
			(xy 289.565224 -418.5248) (xy 289.529533 -418.483609) (xy 289.500067 -418.437759) (xy 289.477425 -418.388182)
			(xy 289.46207 -418.335887) (xy 289.454314 -418.281939) (xy 289.453828 -418.254688) (xy 277.48484 -418.254688)
			(xy 277.48484 -419.081712) (xy 277.484354 -419.108963) (xy 277.476598 -419.162911) (xy 277.461243 -419.215206)
			(xy 277.438601 -419.264783) (xy 277.409135 -419.310633) (xy 277.373444 -419.351824) (xy 277.332253 -419.387515)
			(xy 277.286403 -419.416981) (xy 277.236826 -419.439623) (xy 277.184531 -419.454978) (xy 277.130583 -419.462734)
			(xy 277.076081 -419.462734) (xy 277.022133 -419.454978) (xy 276.969838 -419.439623) (xy 276.920261 -419.416981)
			(xy 276.874411 -419.387515) (xy 276.83322 -419.351824) (xy 276.797529 -419.310633) (xy 276.768063 -419.264783)
			(xy 276.745421 -419.215206) (xy 276.730066 -419.162911) (xy 276.72231 -419.108963) (xy 276.721824 -419.081712)
			(xy 233.545126 -419.081712) (xy 232.102406 -420.524432) (xy 290.829492 -420.524432) (xy 290.829492 -419.660832)
			(xy 290.829978 -419.633563) (xy 290.83774 -419.579579) (xy 290.853105 -419.527249) (xy 290.875762 -419.477639)
			(xy 290.905248 -419.431758) (xy 290.940963 -419.390541) (xy 290.98218 -419.354826) (xy 291.028061 -419.32534)
			(xy 291.077671 -419.302683) (xy 291.130001 -419.287318) (xy 291.183985 -419.279556) (xy 291.238523 -419.279556)
			(xy 291.292507 -419.287318) (xy 291.344837 -419.302683) (xy 291.394447 -419.32534) (xy 291.440328 -419.354826)
			(xy 291.481545 -419.390541) (xy 291.51726 -419.431758) (xy 291.546746 -419.477639) (xy 291.569403 -419.527249)
			(xy 291.584768 -419.579579) (xy 291.59253 -419.633563) (xy 291.593016 -419.660832) (xy 291.593016 -420.524432)
			(xy 291.59253 -420.551701) (xy 291.584768 -420.605685) (xy 291.569403 -420.658015) (xy 291.546746 -420.707625)
			(xy 291.51726 -420.753506) (xy 291.481545 -420.794723) (xy 291.440328 -420.830438) (xy 291.394447 -420.859924)
			(xy 291.344837 -420.882581) (xy 291.292507 -420.897946) (xy 291.238523 -420.905708) (xy 291.183985 -420.905708)
			(xy 291.130001 -420.897946) (xy 291.077671 -420.882581) (xy 291.028061 -420.859924) (xy 290.98218 -420.830438)
			(xy 290.940963 -420.794723) (xy 290.905248 -420.753506) (xy 290.875762 -420.707625) (xy 290.853105 -420.658015)
			(xy 290.83774 -420.605685) (xy 290.829978 -420.551701) (xy 290.829492 -420.524432) (xy 232.102406 -420.524432)
			(xy 231.647383 -420.979455) (xy 303.412823 -420.979455) (xy 303.412823 -420.924945) (xy 303.420581 -420.870989)
			(xy 303.435938 -420.818686) (xy 303.458583 -420.769101) (xy 303.488054 -420.723244) (xy 303.523752 -420.682047)
			(xy 303.564949 -420.646351) (xy 303.610806 -420.61688) (xy 303.660391 -420.594236) (xy 303.712694 -420.578879)
			(xy 303.766651 -420.571123) (xy 303.793906 -420.57066) (xy 304.657506 -420.57066) (xy 304.684755 -420.571211)
			(xy 304.738697 -420.578967) (xy 304.790987 -420.594321) (xy 304.840559 -420.616961) (xy 304.886405 -420.646425)
			(xy 304.927591 -420.682113) (xy 304.963279 -420.7233) (xy 304.992742 -420.769146) (xy 305.015381 -420.818719)
			(xy 305.030734 -420.871009) (xy 305.03849 -420.924951) (xy 305.03849 -420.979449) (xy 305.038489 -420.979457)
			(xy 306.476023 -420.979457) (xy 306.476023 -420.924943) (xy 306.483782 -420.870983) (xy 306.499142 -420.818677)
			(xy 306.521789 -420.76909) (xy 306.551264 -420.723231) (xy 306.586966 -420.682033) (xy 306.628167 -420.646337)
			(xy 306.67403 -420.616867) (xy 306.72362 -420.594225) (xy 306.775928 -420.578872) (xy 306.829889 -420.57112)
			(xy 306.857146 -420.57066) (xy 307.720746 -420.57066) (xy 307.747993 -420.571213) (xy 307.801931 -420.578975)
			(xy 307.854216 -420.594332) (xy 307.903783 -420.616974) (xy 307.949624 -420.646439) (xy 307.990805 -420.682128)
			(xy 308.026488 -420.723313) (xy 308.055948 -420.769157) (xy 308.078584 -420.818727) (xy 308.093935 -420.871014)
			(xy 308.10169 -420.924953) (xy 308.10169 -420.979447) (xy 308.101689 -420.979453) (xy 309.539346 -420.979453)
			(xy 309.539346 -420.924947) (xy 309.547103 -420.870996) (xy 309.562458 -420.818698) (xy 309.5851 -420.769118)
			(xy 309.614568 -420.723264) (xy 309.650261 -420.682071) (xy 309.691453 -420.646376) (xy 309.737305 -420.616907)
			(xy 309.786885 -420.594263) (xy 309.839182 -420.578906) (xy 309.893133 -420.571147) (xy 309.920386 -420.57066)
			(xy 310.783986 -420.57066) (xy 310.811237 -420.571186) (xy 310.865185 -420.578941) (xy 310.91748 -420.594295)
			(xy 310.967058 -420.616934) (xy 311.012909 -420.646399) (xy 311.0541 -420.68209) (xy 311.089792 -420.72328)
			(xy 311.119259 -420.76913) (xy 311.141901 -420.818707) (xy 311.157256 -420.871001) (xy 311.165013 -420.924949)
			(xy 311.165013 -420.979451) (xy 311.165012 -420.979456) (xy 312.602523 -420.979456) (xy 312.602523 -420.924944)
			(xy 312.610281 -420.870986) (xy 312.62564 -420.818681) (xy 312.648286 -420.769095) (xy 312.677759 -420.723237)
			(xy 312.713459 -420.68204) (xy 312.754658 -420.646344) (xy 312.800518 -420.616874) (xy 312.850106 -420.594231)
			(xy 312.902411 -420.578876) (xy 312.95637 -420.571121) (xy 312.983626 -420.57066) (xy 313.847226 -420.57066)
			(xy 313.874474 -420.571212) (xy 313.928414 -420.578971) (xy 313.980701 -420.594327) (xy 314.030271 -420.616968)
			(xy 314.076114 -420.646432) (xy 314.117298 -420.682121) (xy 314.152984 -420.723307) (xy 314.182445 -420.769152)
			(xy 314.205082 -420.818723) (xy 314.220435 -420.871011) (xy 314.22819 -420.924952) (xy 314.22819 -420.979448)
			(xy 314.228189 -420.979452) (xy 315.665846 -420.979452) (xy 315.665846 -420.924948) (xy 315.673602 -420.870999)
			(xy 315.688957 -420.818702) (xy 315.711597 -420.769123) (xy 315.741063 -420.723271) (xy 315.776754 -420.682078)
			(xy 315.817943 -420.646383) (xy 315.863793 -420.616914) (xy 315.91337 -420.594269) (xy 315.965665 -420.578909)
			(xy 316.019614 -420.571148) (xy 316.046866 -420.57066) (xy 316.910466 -420.57066) (xy 316.937718 -420.571185)
			(xy 316.991668 -420.578937) (xy 317.043966 -420.594289) (xy 317.093546 -420.616928) (xy 317.1394 -420.646392)
			(xy 317.180593 -420.682083) (xy 317.216287 -420.723273) (xy 317.245756 -420.769124) (xy 317.268399 -420.818702)
			(xy 317.283755 -420.870999) (xy 317.291513 -420.924948) (xy 317.291513 -420.979452) (xy 317.291513 -420.979455)
			(xy 318.729023 -420.979455) (xy 318.729023 -420.924945) (xy 318.736781 -420.870989) (xy 318.752138 -420.818686)
			(xy 318.774783 -420.769101) (xy 318.804254 -420.723244) (xy 318.839952 -420.682047) (xy 318.881149 -420.646351)
			(xy 318.927006 -420.61688) (xy 318.976591 -420.594236) (xy 319.028894 -420.578879) (xy 319.082851 -420.571123)
			(xy 319.110106 -420.57066) (xy 319.973706 -420.57066) (xy 320.000955 -420.571211) (xy 320.054897 -420.578967)
			(xy 320.107187 -420.594321) (xy 320.156759 -420.616961) (xy 320.202605 -420.646425) (xy 320.243791 -420.682113)
			(xy 320.279479 -420.7233) (xy 320.308942 -420.769146) (xy 320.331581 -420.818719) (xy 320.346934 -420.871009)
			(xy 320.35469 -420.924951) (xy 320.35469 -420.979449) (xy 320.354689 -420.979457) (xy 321.792223 -420.979457)
			(xy 321.792223 -420.924943) (xy 321.799982 -420.870983) (xy 321.815342 -420.818677) (xy 321.837989 -420.76909)
			(xy 321.867464 -420.723231) (xy 321.903166 -420.682033) (xy 321.944367 -420.646337) (xy 321.99023 -420.616867)
			(xy 322.03982 -420.594225) (xy 322.092128 -420.578872) (xy 322.146089 -420.57112) (xy 322.173346 -420.57066)
			(xy 323.036946 -420.57066) (xy 323.064193 -420.571213) (xy 323.118131 -420.578975) (xy 323.170416 -420.594332)
			(xy 323.219983 -420.616974) (xy 323.265824 -420.646439) (xy 323.307005 -420.682128) (xy 323.342688 -420.723313)
			(xy 323.372148 -420.769157) (xy 323.394784 -420.818727) (xy 323.410135 -420.871014) (xy 323.41789 -420.924953)
			(xy 323.41789 -420.979447) (xy 323.417889 -420.979453) (xy 324.855546 -420.979453) (xy 324.855546 -420.924947)
			(xy 324.863303 -420.870996) (xy 324.878658 -420.818698) (xy 324.9013 -420.769118) (xy 324.930768 -420.723264)
			(xy 324.966461 -420.682071) (xy 325.007653 -420.646376) (xy 325.053505 -420.616907) (xy 325.103085 -420.594263)
			(xy 325.155382 -420.578906) (xy 325.209333 -420.571147) (xy 325.236586 -420.57066) (xy 326.100186 -420.57066)
			(xy 326.127437 -420.571186) (xy 326.181385 -420.578941) (xy 326.23368 -420.594295) (xy 326.283258 -420.616934)
			(xy 326.329109 -420.646399) (xy 326.3703 -420.68209) (xy 326.405992 -420.72328) (xy 326.435459 -420.76913)
			(xy 326.458101 -420.818707) (xy 326.473456 -420.871001) (xy 326.481213 -420.924949) (xy 326.481213 -420.979451)
			(xy 326.481212 -420.979456) (xy 327.918723 -420.979456) (xy 327.918723 -420.924944) (xy 327.926481 -420.870986)
			(xy 327.94184 -420.818681) (xy 327.964486 -420.769095) (xy 327.993959 -420.723237) (xy 328.029659 -420.68204)
			(xy 328.070858 -420.646344) (xy 328.116718 -420.616874) (xy 328.166306 -420.594231) (xy 328.218611 -420.578876)
			(xy 328.27257 -420.571121) (xy 328.299826 -420.57066) (xy 329.163426 -420.57066) (xy 329.190674 -420.571212)
			(xy 329.244614 -420.578971) (xy 329.296901 -420.594327) (xy 329.346471 -420.616968) (xy 329.392314 -420.646432)
			(xy 329.433498 -420.682121) (xy 329.469184 -420.723307) (xy 329.498645 -420.769152) (xy 329.521282 -420.818723)
			(xy 329.536635 -420.871011) (xy 329.54439 -420.924952) (xy 329.54439 -420.979448) (xy 329.544389 -420.979452)
			(xy 330.982046 -420.979452) (xy 330.982046 -420.924948) (xy 330.989802 -420.870999) (xy 331.005157 -420.818702)
			(xy 331.027797 -420.769123) (xy 331.057263 -420.723271) (xy 331.092954 -420.682078) (xy 331.134143 -420.646383)
			(xy 331.179993 -420.616914) (xy 331.22957 -420.594269) (xy 331.281865 -420.578909) (xy 331.335814 -420.571148)
			(xy 331.363066 -420.57066) (xy 332.226666 -420.57066) (xy 332.253918 -420.571185) (xy 332.307868 -420.578937)
			(xy 332.360166 -420.594289) (xy 332.409746 -420.616928) (xy 332.4556 -420.646392) (xy 332.496793 -420.682083)
			(xy 332.532487 -420.723273) (xy 332.561956 -420.769124) (xy 332.584599 -420.818702) (xy 332.599955 -420.870999)
			(xy 332.607713 -420.924948) (xy 332.607713 -420.979452) (xy 332.607713 -420.979455) (xy 334.045223 -420.979455)
			(xy 334.045223 -420.924945) (xy 334.052981 -420.870989) (xy 334.068338 -420.818686) (xy 334.090983 -420.769101)
			(xy 334.120454 -420.723244) (xy 334.156152 -420.682047) (xy 334.197349 -420.646351) (xy 334.243206 -420.61688)
			(xy 334.292791 -420.594236) (xy 334.345094 -420.578879) (xy 334.399051 -420.571123) (xy 334.426306 -420.57066)
			(xy 335.289906 -420.57066) (xy 335.317155 -420.571211) (xy 335.371097 -420.578967) (xy 335.423387 -420.594321)
			(xy 335.472959 -420.616961) (xy 335.518805 -420.646425) (xy 335.559991 -420.682113) (xy 335.595679 -420.7233)
			(xy 335.625142 -420.769146) (xy 335.647781 -420.818719) (xy 335.663134 -420.871009) (xy 335.67089 -420.924951)
			(xy 335.67089 -420.979449) (xy 335.670889 -420.979457) (xy 337.108423 -420.979457) (xy 337.108423 -420.924943)
			(xy 337.116182 -420.870983) (xy 337.131542 -420.818677) (xy 337.154189 -420.76909) (xy 337.183664 -420.723231)
			(xy 337.219366 -420.682033) (xy 337.260567 -420.646337) (xy 337.30643 -420.616867) (xy 337.35602 -420.594225)
			(xy 337.408328 -420.578872) (xy 337.462289 -420.57112) (xy 337.489546 -420.57066) (xy 338.353146 -420.57066)
			(xy 338.380393 -420.571213) (xy 338.434331 -420.578975) (xy 338.486616 -420.594332) (xy 338.536183 -420.616974)
			(xy 338.582024 -420.646439) (xy 338.623205 -420.682128) (xy 338.658888 -420.723313) (xy 338.688348 -420.769157)
			(xy 338.710984 -420.818727) (xy 338.726335 -420.871014) (xy 338.73409 -420.924953) (xy 338.73409 -420.979447)
			(xy 338.734089 -420.979453) (xy 340.171746 -420.979453) (xy 340.171746 -420.924947) (xy 340.179503 -420.870996)
			(xy 340.194858 -420.818698) (xy 340.2175 -420.769118) (xy 340.246968 -420.723264) (xy 340.282661 -420.682071)
			(xy 340.323853 -420.646376) (xy 340.369705 -420.616907) (xy 340.419285 -420.594263) (xy 340.471582 -420.578906)
			(xy 340.525533 -420.571147) (xy 340.552786 -420.57066) (xy 341.416386 -420.57066) (xy 341.443637 -420.571186)
			(xy 341.497585 -420.578941) (xy 341.54988 -420.594295) (xy 341.599458 -420.616934) (xy 341.645309 -420.646399)
			(xy 341.6865 -420.68209) (xy 341.722192 -420.72328) (xy 341.751659 -420.76913) (xy 341.774301 -420.818707)
			(xy 341.789656 -420.871001) (xy 341.797413 -420.924949) (xy 341.797413 -420.979451) (xy 341.797412 -420.979456)
			(xy 343.234923 -420.979456) (xy 343.234923 -420.924944) (xy 343.242681 -420.870986) (xy 343.25804 -420.818681)
			(xy 343.280686 -420.769095) (xy 343.310159 -420.723237) (xy 343.345859 -420.68204) (xy 343.387058 -420.646344)
			(xy 343.432918 -420.616874) (xy 343.482506 -420.594231) (xy 343.534811 -420.578876) (xy 343.58877 -420.571121)
			(xy 343.616026 -420.57066) (xy 344.479626 -420.57066) (xy 344.506874 -420.571212) (xy 344.560814 -420.578971)
			(xy 344.613101 -420.594327) (xy 344.662671 -420.616968) (xy 344.708514 -420.646432) (xy 344.749698 -420.682121)
			(xy 344.785384 -420.723307) (xy 344.814845 -420.769152) (xy 344.837482 -420.818723) (xy 344.852835 -420.871011)
			(xy 344.86059 -420.924952) (xy 344.86059 -420.979448) (xy 344.860589 -420.979452) (xy 346.298246 -420.979452)
			(xy 346.298246 -420.924948) (xy 346.306002 -420.870999) (xy 346.321357 -420.818702) (xy 346.343997 -420.769123)
			(xy 346.373463 -420.723271) (xy 346.409154 -420.682078) (xy 346.450343 -420.646383) (xy 346.496193 -420.616914)
			(xy 346.54577 -420.594269) (xy 346.598065 -420.578909) (xy 346.652014 -420.571148) (xy 346.679266 -420.57066)
			(xy 347.542866 -420.57066) (xy 347.570118 -420.571185) (xy 347.624068 -420.578937) (xy 347.676366 -420.594289)
			(xy 347.725946 -420.616928) (xy 347.7718 -420.646392) (xy 347.812993 -420.682083) (xy 347.848687 -420.723273)
			(xy 347.878156 -420.769124) (xy 347.900799 -420.818702) (xy 347.916155 -420.870999) (xy 347.923913 -420.924948)
			(xy 347.923913 -420.979452) (xy 347.923913 -420.979455) (xy 349.361423 -420.979455) (xy 349.361423 -420.924945)
			(xy 349.369181 -420.870989) (xy 349.384538 -420.818686) (xy 349.407183 -420.769101) (xy 349.436654 -420.723244)
			(xy 349.472352 -420.682047) (xy 349.513549 -420.646351) (xy 349.559406 -420.61688) (xy 349.608991 -420.594236)
			(xy 349.661294 -420.578879) (xy 349.715251 -420.571123) (xy 349.742506 -420.57066) (xy 350.606106 -420.57066)
			(xy 350.633355 -420.571211) (xy 350.687297 -420.578967) (xy 350.739587 -420.594321) (xy 350.789159 -420.616961)
			(xy 350.835005 -420.646425) (xy 350.876191 -420.682113) (xy 350.911879 -420.7233) (xy 350.941342 -420.769146)
			(xy 350.963981 -420.818719) (xy 350.979334 -420.871009) (xy 350.98709 -420.924951) (xy 350.98709 -420.979449)
			(xy 350.979334 -421.033391) (xy 350.963981 -421.085681) (xy 350.941342 -421.135254) (xy 350.911879 -421.1811)
			(xy 350.876191 -421.222287) (xy 350.835005 -421.257975) (xy 350.789159 -421.287439) (xy 350.739587 -421.310079)
			(xy 350.687297 -421.325433) (xy 350.633355 -421.333189) (xy 350.606106 -421.333676) (xy 349.742506 -421.333676)
			(xy 349.715251 -421.333277) (xy 349.661294 -421.325521) (xy 349.608991 -421.310164) (xy 349.559406 -421.28752)
			(xy 349.513549 -421.258049) (xy 349.472352 -421.222353) (xy 349.436654 -421.181156) (xy 349.407183 -421.135299)
			(xy 349.384538 -421.085714) (xy 349.369181 -421.033411) (xy 349.361423 -420.979455) (xy 347.923913 -420.979455)
			(xy 347.916155 -421.033402) (xy 347.900799 -421.085698) (xy 347.878156 -421.135276) (xy 347.848687 -421.181127)
			(xy 347.812993 -421.222317) (xy 347.7718 -421.258008) (xy 347.725946 -421.287472) (xy 347.676366 -421.310111)
			(xy 347.624068 -421.325463) (xy 347.570118 -421.333215) (xy 347.542866 -421.333676) (xy 346.679266 -421.333676)
			(xy 346.652014 -421.333252) (xy 346.598065 -421.325491) (xy 346.54577 -421.310131) (xy 346.496193 -421.287486)
			(xy 346.450343 -421.258017) (xy 346.409154 -421.222322) (xy 346.373463 -421.181129) (xy 346.343997 -421.135277)
			(xy 346.321357 -421.085698) (xy 346.306002 -421.033401) (xy 346.298246 -420.979452) (xy 344.860589 -420.979452)
			(xy 344.852835 -421.033389) (xy 344.837482 -421.085677) (xy 344.814845 -421.135248) (xy 344.785384 -421.181093)
			(xy 344.749698 -421.222279) (xy 344.708514 -421.257968) (xy 344.662671 -421.287432) (xy 344.613101 -421.310073)
			(xy 344.560814 -421.325429) (xy 344.506874 -421.333188) (xy 344.479626 -421.333676) (xy 343.616026 -421.333676)
			(xy 343.58877 -421.333279) (xy 343.534811 -421.325524) (xy 343.482506 -421.310169) (xy 343.432918 -421.287526)
			(xy 343.387058 -421.258056) (xy 343.345859 -421.22236) (xy 343.310159 -421.181163) (xy 343.280686 -421.135305)
			(xy 343.25804 -421.085719) (xy 343.242681 -421.033414) (xy 343.234923 -420.979456) (xy 341.797412 -420.979456)
			(xy 341.789656 -421.033399) (xy 341.774301 -421.085693) (xy 341.751659 -421.13527) (xy 341.722192 -421.18112)
			(xy 341.6865 -421.22231) (xy 341.645309 -421.258001) (xy 341.599458 -421.287466) (xy 341.54988 -421.310105)
			(xy 341.497585 -421.325459) (xy 341.443637 -421.333214) (xy 341.416386 -421.333676) (xy 340.552786 -421.333676)
			(xy 340.525533 -421.333253) (xy 340.471582 -421.325494) (xy 340.419285 -421.310137) (xy 340.369705 -421.287493)
			(xy 340.323853 -421.258024) (xy 340.282661 -421.222329) (xy 340.246968 -421.181136) (xy 340.2175 -421.135282)
			(xy 340.194858 -421.085702) (xy 340.179503 -421.033404) (xy 340.171746 -420.979453) (xy 338.734089 -420.979453)
			(xy 338.726335 -421.033386) (xy 338.710984 -421.085673) (xy 338.688348 -421.135243) (xy 338.658888 -421.181087)
			(xy 338.623205 -421.222272) (xy 338.582024 -421.257961) (xy 338.536183 -421.287426) (xy 338.486616 -421.310068)
			(xy 338.434331 -421.325425) (xy 338.380393 -421.333187) (xy 338.353146 -421.333676) (xy 337.489546 -421.333676)
			(xy 337.462289 -421.33328) (xy 337.408328 -421.325528) (xy 337.35602 -421.310175) (xy 337.30643 -421.287533)
			(xy 337.260567 -421.258063) (xy 337.219366 -421.222367) (xy 337.183664 -421.181169) (xy 337.154189 -421.13531)
			(xy 337.131542 -421.085723) (xy 337.116182 -421.033417) (xy 337.108423 -420.979457) (xy 335.670889 -420.979457)
			(xy 335.663134 -421.033391) (xy 335.647781 -421.085681) (xy 335.625142 -421.135254) (xy 335.595679 -421.1811)
			(xy 335.559991 -421.222287) (xy 335.518805 -421.257975) (xy 335.472959 -421.287439) (xy 335.423387 -421.310079)
			(xy 335.371097 -421.325433) (xy 335.317155 -421.333189) (xy 335.289906 -421.333676) (xy 334.426306 -421.333676)
			(xy 334.399051 -421.333277) (xy 334.345094 -421.325521) (xy 334.292791 -421.310164) (xy 334.243206 -421.28752)
			(xy 334.197349 -421.258049) (xy 334.156152 -421.222353) (xy 334.120454 -421.181156) (xy 334.090983 -421.135299)
			(xy 334.068338 -421.085714) (xy 334.052981 -421.033411) (xy 334.045223 -420.979455) (xy 332.607713 -420.979455)
			(xy 332.599955 -421.033402) (xy 332.584599 -421.085698) (xy 332.561956 -421.135276) (xy 332.532487 -421.181127)
			(xy 332.496793 -421.222317) (xy 332.4556 -421.258008) (xy 332.409746 -421.287472) (xy 332.360166 -421.310111)
			(xy 332.307868 -421.325463) (xy 332.253918 -421.333215) (xy 332.226666 -421.333676) (xy 331.363066 -421.333676)
			(xy 331.335814 -421.333252) (xy 331.281865 -421.325491) (xy 331.22957 -421.310131) (xy 331.179993 -421.287486)
			(xy 331.134143 -421.258017) (xy 331.092954 -421.222322) (xy 331.057263 -421.181129) (xy 331.027797 -421.135277)
			(xy 331.005157 -421.085698) (xy 330.989802 -421.033401) (xy 330.982046 -420.979452) (xy 329.544389 -420.979452)
			(xy 329.536635 -421.033389) (xy 329.521282 -421.085677) (xy 329.498645 -421.135248) (xy 329.469184 -421.181093)
			(xy 329.433498 -421.222279) (xy 329.392314 -421.257968) (xy 329.346471 -421.287432) (xy 329.296901 -421.310073)
			(xy 329.244614 -421.325429) (xy 329.190674 -421.333188) (xy 329.163426 -421.333676) (xy 328.299826 -421.333676)
			(xy 328.27257 -421.333279) (xy 328.218611 -421.325524) (xy 328.166306 -421.310169) (xy 328.116718 -421.287526)
			(xy 328.070858 -421.258056) (xy 328.029659 -421.22236) (xy 327.993959 -421.181163) (xy 327.964486 -421.135305)
			(xy 327.94184 -421.085719) (xy 327.926481 -421.033414) (xy 327.918723 -420.979456) (xy 326.481212 -420.979456)
			(xy 326.473456 -421.033399) (xy 326.458101 -421.085693) (xy 326.435459 -421.13527) (xy 326.405992 -421.18112)
			(xy 326.3703 -421.22231) (xy 326.329109 -421.258001) (xy 326.283258 -421.287466) (xy 326.23368 -421.310105)
			(xy 326.181385 -421.325459) (xy 326.127437 -421.333214) (xy 326.100186 -421.333676) (xy 325.236586 -421.333676)
			(xy 325.209333 -421.333253) (xy 325.155382 -421.325494) (xy 325.103085 -421.310137) (xy 325.053505 -421.287493)
			(xy 325.007653 -421.258024) (xy 324.966461 -421.222329) (xy 324.930768 -421.181136) (xy 324.9013 -421.135282)
			(xy 324.878658 -421.085702) (xy 324.863303 -421.033404) (xy 324.855546 -420.979453) (xy 323.417889 -420.979453)
			(xy 323.410135 -421.033386) (xy 323.394784 -421.085673) (xy 323.372148 -421.135243) (xy 323.342688 -421.181087)
			(xy 323.307005 -421.222272) (xy 323.265824 -421.257961) (xy 323.219983 -421.287426) (xy 323.170416 -421.310068)
			(xy 323.118131 -421.325425) (xy 323.064193 -421.333187) (xy 323.036946 -421.333676) (xy 322.173346 -421.333676)
			(xy 322.146089 -421.33328) (xy 322.092128 -421.325528) (xy 322.03982 -421.310175) (xy 321.99023 -421.287533)
			(xy 321.944367 -421.258063) (xy 321.903166 -421.222367) (xy 321.867464 -421.181169) (xy 321.837989 -421.13531)
			(xy 321.815342 -421.085723) (xy 321.799982 -421.033417) (xy 321.792223 -420.979457) (xy 320.354689 -420.979457)
			(xy 320.346934 -421.033391) (xy 320.331581 -421.085681) (xy 320.308942 -421.135254) (xy 320.279479 -421.1811)
			(xy 320.243791 -421.222287) (xy 320.202605 -421.257975) (xy 320.156759 -421.287439) (xy 320.107187 -421.310079)
			(xy 320.054897 -421.325433) (xy 320.000955 -421.333189) (xy 319.973706 -421.333676) (xy 319.110106 -421.333676)
			(xy 319.082851 -421.333277) (xy 319.028894 -421.325521) (xy 318.976591 -421.310164) (xy 318.927006 -421.28752)
			(xy 318.881149 -421.258049) (xy 318.839952 -421.222353) (xy 318.804254 -421.181156) (xy 318.774783 -421.135299)
			(xy 318.752138 -421.085714) (xy 318.736781 -421.033411) (xy 318.729023 -420.979455) (xy 317.291513 -420.979455)
			(xy 317.283755 -421.033402) (xy 317.268399 -421.085698) (xy 317.245756 -421.135276) (xy 317.216287 -421.181127)
			(xy 317.180593 -421.222317) (xy 317.1394 -421.258008) (xy 317.093546 -421.287472) (xy 317.043966 -421.310111)
			(xy 316.991668 -421.325463) (xy 316.937718 -421.333215) (xy 316.910466 -421.333676) (xy 316.046866 -421.333676)
			(xy 316.019614 -421.333252) (xy 315.965665 -421.325491) (xy 315.91337 -421.310131) (xy 315.863793 -421.287486)
			(xy 315.817943 -421.258017) (xy 315.776754 -421.222322) (xy 315.741063 -421.181129) (xy 315.711597 -421.135277)
			(xy 315.688957 -421.085698) (xy 315.673602 -421.033401) (xy 315.665846 -420.979452) (xy 314.228189 -420.979452)
			(xy 314.220435 -421.033389) (xy 314.205082 -421.085677) (xy 314.182445 -421.135248) (xy 314.152984 -421.181093)
			(xy 314.117298 -421.222279) (xy 314.076114 -421.257968) (xy 314.030271 -421.287432) (xy 313.980701 -421.310073)
			(xy 313.928414 -421.325429) (xy 313.874474 -421.333188) (xy 313.847226 -421.333676) (xy 312.983626 -421.333676)
			(xy 312.95637 -421.333279) (xy 312.902411 -421.325524) (xy 312.850106 -421.310169) (xy 312.800518 -421.287526)
			(xy 312.754658 -421.258056) (xy 312.713459 -421.22236) (xy 312.677759 -421.181163) (xy 312.648286 -421.135305)
			(xy 312.62564 -421.085719) (xy 312.610281 -421.033414) (xy 312.602523 -420.979456) (xy 311.165012 -420.979456)
			(xy 311.157256 -421.033399) (xy 311.141901 -421.085693) (xy 311.119259 -421.13527) (xy 311.089792 -421.18112)
			(xy 311.0541 -421.22231) (xy 311.012909 -421.258001) (xy 310.967058 -421.287466) (xy 310.91748 -421.310105)
			(xy 310.865185 -421.325459) (xy 310.811237 -421.333214) (xy 310.783986 -421.333676) (xy 309.920386 -421.333676)
			(xy 309.893133 -421.333253) (xy 309.839182 -421.325494) (xy 309.786885 -421.310137) (xy 309.737305 -421.287493)
			(xy 309.691453 -421.258024) (xy 309.650261 -421.222329) (xy 309.614568 -421.181136) (xy 309.5851 -421.135282)
			(xy 309.562458 -421.085702) (xy 309.547103 -421.033404) (xy 309.539346 -420.979453) (xy 308.101689 -420.979453)
			(xy 308.093935 -421.033386) (xy 308.078584 -421.085673) (xy 308.055948 -421.135243) (xy 308.026488 -421.181087)
			(xy 307.990805 -421.222272) (xy 307.949624 -421.257961) (xy 307.903783 -421.287426) (xy 307.854216 -421.310068)
			(xy 307.801931 -421.325425) (xy 307.747993 -421.333187) (xy 307.720746 -421.333676) (xy 306.857146 -421.333676)
			(xy 306.829889 -421.33328) (xy 306.775928 -421.325528) (xy 306.72362 -421.310175) (xy 306.67403 -421.287533)
			(xy 306.628167 -421.258063) (xy 306.586966 -421.222367) (xy 306.551264 -421.181169) (xy 306.521789 -421.13531)
			(xy 306.499142 -421.085723) (xy 306.483782 -421.033417) (xy 306.476023 -420.979457) (xy 305.038489 -420.979457)
			(xy 305.030734 -421.033391) (xy 305.015381 -421.085681) (xy 304.992742 -421.135254) (xy 304.963279 -421.1811)
			(xy 304.927591 -421.222287) (xy 304.886405 -421.257975) (xy 304.840559 -421.287439) (xy 304.790987 -421.310079)
			(xy 304.738697 -421.325433) (xy 304.684755 -421.333189) (xy 304.657506 -421.333676) (xy 303.793906 -421.333676)
			(xy 303.766651 -421.333277) (xy 303.712694 -421.325521) (xy 303.660391 -421.310164) (xy 303.610806 -421.28752)
			(xy 303.564949 -421.258049) (xy 303.523752 -421.222353) (xy 303.488054 -421.181156) (xy 303.458583 -421.135299)
			(xy 303.435938 -421.085714) (xy 303.420581 -421.033411) (xy 303.412823 -420.979455) (xy 231.647383 -420.979455)
			(xy 230.329486 -422.297352) (xy 230.322673 -422.304773) (xy 230.314938 -422.323356) (xy 230.3145 -422.33342)
			(xy 230.3145 -422.354375) (xy 285.567772 -422.354375) (xy 285.567772 -422.299825) (xy 285.575535 -422.245831)
			(xy 285.590905 -422.193491) (xy 285.613567 -422.143872) (xy 285.64306 -422.097983) (xy 285.678784 -422.056759)
			(xy 285.720012 -422.021038) (xy 285.765903 -421.991549) (xy 285.815525 -421.968892) (xy 285.867866 -421.953528)
			(xy 285.921861 -421.945769) (xy 285.949136 -421.945308) (xy 286.812736 -421.945308) (xy 286.840002 -421.945857)
			(xy 286.893977 -421.953622) (xy 286.946298 -421.968989) (xy 286.9959 -421.991646) (xy 287.041773 -422.02113)
			(xy 287.082983 -422.056843) (xy 287.118691 -422.098056) (xy 287.148172 -422.143932) (xy 287.170823 -422.193536)
			(xy 287.186186 -422.245858) (xy 287.193946 -422.299834) (xy 287.193946 -422.354366) (xy 287.186186 -422.408342)
			(xy 287.170823 -422.460664) (xy 287.148172 -422.510268) (xy 287.118691 -422.556144) (xy 287.082983 -422.597357)
			(xy 287.041773 -422.63307) (xy 286.9959 -422.662554) (xy 286.946298 -422.685211) (xy 286.893977 -422.700578)
			(xy 286.840002 -422.708343) (xy 286.812736 -422.708832) (xy 285.949136 -422.708832) (xy 285.921861 -422.708431)
			(xy 285.867866 -422.700672) (xy 285.815525 -422.685308) (xy 285.765903 -422.662651) (xy 285.720012 -422.633162)
			(xy 285.678784 -422.597441) (xy 285.64306 -422.556217) (xy 285.613567 -422.510328) (xy 285.590905 -422.460709)
			(xy 285.575535 -422.408369) (xy 285.567772 -422.354375) (xy 230.3145 -422.354375) (xy 230.3145 -424.80464)
			(xy 357.679233 -424.80464) (xy 357.679233 -424.6755) (xy 357.687183 -424.546605) (xy 357.703053 -424.418445)
			(xy 357.726782 -424.291504) (xy 357.758281 -424.166265) (xy 357.79743 -424.043202) (xy 357.844081 -423.922783)
			(xy 357.898056 -423.805464) (xy 357.959151 -423.69169) (xy 358.027134 -423.581893) (xy 358.101748 -423.47649)
			(xy 358.182709 -423.37588) (xy 358.269709 -423.280445) (xy 358.36242 -423.190546) (xy 358.46049 -423.106525)
			(xy 358.563545 -423.028701) (xy 358.671196 -422.957369) (xy 358.783035 -422.892799) (xy 358.898636 -422.835237)
			(xy 359.017561 -422.7849) (xy 359.13936 -422.74198) (xy 359.26357 -422.706639) (xy 359.389719 -422.679012)
			(xy 359.517331 -422.659203) (xy 359.64592 -422.647287) (xy 359.774998 -422.643311) (xy 359.904076 -422.647287)
			(xy 360.032665 -422.659203) (xy 360.160277 -422.679012) (xy 360.222212 -422.692576) (xy 365.310928 -422.692576)
			(xy 365.310928 -415.898584) (xy 365.3113 -415.888356) (xy 365.319137 -415.86946) (xy 365.33361 -415.855003)
			(xy 365.352515 -415.847188) (xy 365.362744 -415.846768) (xy 370.261388 -415.846768) (xy 370.271593 -415.847291)
			(xy 370.290451 -415.855097) (xy 370.304887 -415.869525) (xy 370.312703 -415.888379) (xy 370.313204 -415.898584)
			(xy 370.313204 -418.439456) (xy 372.044623 -418.439456) (xy 372.044623 -418.384944) (xy 372.052381 -418.330986)
			(xy 372.06774 -418.278682) (xy 372.090386 -418.229097) (xy 372.119858 -418.183238) (xy 372.155557 -418.142042)
			(xy 372.196756 -418.106345) (xy 372.242616 -418.076875) (xy 372.292203 -418.054232) (xy 372.344508 -418.038877)
			(xy 372.398466 -418.031121) (xy 372.425722 -418.03066) (xy 373.289322 -418.03066) (xy 373.31657 -418.031212)
			(xy 373.370511 -418.03897) (xy 373.422798 -418.054326) (xy 373.472369 -418.076966) (xy 373.518212 -418.106431)
			(xy 373.559396 -418.142119) (xy 373.595083 -418.183305) (xy 373.624544 -418.229151) (xy 373.647182 -418.278722)
			(xy 373.662535 -418.331011) (xy 373.67029 -418.384952) (xy 373.67029 -418.439448) (xy 373.670289 -418.439452)
			(xy 375.107946 -418.439452) (xy 375.107946 -418.384948) (xy 375.115702 -418.330999) (xy 375.131056 -418.278703)
			(xy 375.153697 -418.229124) (xy 375.183162 -418.183272) (xy 375.218852 -418.142079) (xy 375.260041 -418.106385)
			(xy 375.305891 -418.076915) (xy 375.355468 -418.05427) (xy 375.407762 -418.03891) (xy 375.46171 -418.031148)
			(xy 375.488962 -418.03066) (xy 376.352562 -418.03066) (xy 376.379814 -418.031185) (xy 376.433765 -418.038937)
			(xy 376.486063 -418.054288) (xy 376.535644 -418.076926) (xy 376.581498 -418.106391) (xy 376.622691 -418.142082)
			(xy 376.658386 -418.183272) (xy 376.687855 -418.229123) (xy 376.710499 -418.278701) (xy 376.725855 -418.330998)
			(xy 376.733613 -418.384948) (xy 376.733613 -418.439452) (xy 376.733613 -418.439455) (xy 378.171123 -418.439455)
			(xy 378.171123 -418.384945) (xy 378.178881 -418.330989) (xy 378.194238 -418.278687) (xy 378.216883 -418.229102)
			(xy 378.246353 -418.183245) (xy 378.28205 -418.142049) (xy 378.323247 -418.106352) (xy 378.369104 -418.076882)
			(xy 378.418688 -418.054237) (xy 378.470991 -418.03888) (xy 378.524947 -418.031123) (xy 378.552202 -418.03066)
			(xy 379.415802 -418.03066) (xy 379.443051 -418.03121) (xy 379.496994 -418.038966) (xy 379.549284 -418.05432)
			(xy 379.598857 -418.07696) (xy 379.644703 -418.106424) (xy 379.685889 -418.142112) (xy 379.721578 -418.183299)
			(xy 379.751041 -418.229145) (xy 379.77368 -418.278718) (xy 379.789034 -418.331008) (xy 379.79679 -418.384951)
			(xy 379.79679 -418.439449) (xy 379.796789 -418.439457) (xy 381.234323 -418.439457) (xy 381.234323 -418.384943)
			(xy 381.242082 -418.330984) (xy 381.257441 -418.278678) (xy 381.280089 -418.229091) (xy 381.309563 -418.183232)
			(xy 381.345264 -418.142035) (xy 381.386466 -418.106338) (xy 381.432328 -418.076869) (xy 381.481917 -418.054227)
			(xy 381.534225 -418.038873) (xy 381.588185 -418.03112) (xy 381.615442 -418.03066) (xy 382.479042 -418.03066)
			(xy 382.506289 -418.031213) (xy 382.560228 -418.038974) (xy 382.612513 -418.054331) (xy 382.662081 -418.076973)
			(xy 382.707922 -418.106438) (xy 382.749103 -418.142126) (xy 382.784787 -418.183312) (xy 382.814247 -418.229156)
			(xy 382.836883 -418.278727) (xy 382.852235 -418.331014) (xy 382.85999 -418.384953) (xy 382.85999 -418.439447)
			(xy 382.859989 -418.439453) (xy 384.297646 -418.439453) (xy 384.297646 -418.384947) (xy 384.305403 -418.330997)
			(xy 384.320758 -418.278699) (xy 384.3434 -418.229119) (xy 384.372867 -418.183265) (xy 384.408559 -418.142072)
			(xy 384.449751 -418.106378) (xy 384.495603 -418.076908) (xy 384.545182 -418.054264) (xy 384.597479 -418.038906)
			(xy 384.651429 -418.031147) (xy 384.678682 -418.03066) (xy 385.542282 -418.03066) (xy 385.569533 -418.031186)
			(xy 385.623482 -418.03894) (xy 385.675777 -418.054293) (xy 385.725356 -418.076933) (xy 385.771207 -418.106398)
			(xy 385.812399 -418.142089) (xy 385.848091 -418.183278) (xy 385.877558 -418.229129) (xy 385.9002 -418.278706)
			(xy 385.915556 -418.331001) (xy 385.923313 -418.384949) (xy 385.923313 -418.439451) (xy 385.923312 -418.439456)
			(xy 387.360823 -418.439456) (xy 387.360823 -418.384944) (xy 387.368581 -418.330986) (xy 387.38394 -418.278682)
			(xy 387.406586 -418.229097) (xy 387.436058 -418.183238) (xy 387.471757 -418.142042) (xy 387.512956 -418.106345)
			(xy 387.558816 -418.076875) (xy 387.608403 -418.054232) (xy 387.660708 -418.038877) (xy 387.714666 -418.031121)
			(xy 387.741922 -418.03066) (xy 388.605522 -418.03066) (xy 388.63277 -418.031212) (xy 388.686711 -418.03897)
			(xy 388.738998 -418.054326) (xy 388.788569 -418.076966) (xy 388.834412 -418.106431) (xy 388.875596 -418.142119)
			(xy 388.911283 -418.183305) (xy 388.940744 -418.229151) (xy 388.963382 -418.278722) (xy 388.978735 -418.331011)
			(xy 388.98649 -418.384952) (xy 388.98649 -418.439448) (xy 388.986489 -418.439452) (xy 390.424146 -418.439452)
			(xy 390.424146 -418.384948) (xy 390.431902 -418.330999) (xy 390.447256 -418.278703) (xy 390.469897 -418.229124)
			(xy 390.499362 -418.183272) (xy 390.535052 -418.142079) (xy 390.576241 -418.106385) (xy 390.622091 -418.076915)
			(xy 390.671668 -418.05427) (xy 390.723962 -418.03891) (xy 390.77791 -418.031148) (xy 390.805162 -418.03066)
			(xy 391.668762 -418.03066) (xy 391.696014 -418.031185) (xy 391.749965 -418.038937) (xy 391.802263 -418.054288)
			(xy 391.851844 -418.076926) (xy 391.897698 -418.106391) (xy 391.938891 -418.142082) (xy 391.974586 -418.183272)
			(xy 392.004055 -418.229123) (xy 392.026699 -418.278701) (xy 392.042055 -418.330998) (xy 392.049813 -418.384948)
			(xy 392.049813 -418.439452) (xy 392.049813 -418.439455) (xy 393.487323 -418.439455) (xy 393.487323 -418.384945)
			(xy 393.495081 -418.330989) (xy 393.510438 -418.278687) (xy 393.533083 -418.229102) (xy 393.562553 -418.183245)
			(xy 393.59825 -418.142049) (xy 393.639447 -418.106352) (xy 393.685304 -418.076882) (xy 393.734888 -418.054237)
			(xy 393.787191 -418.03888) (xy 393.841147 -418.031123) (xy 393.868402 -418.03066) (xy 394.732002 -418.03066)
			(xy 394.759251 -418.03121) (xy 394.813194 -418.038966) (xy 394.865484 -418.05432) (xy 394.915057 -418.07696)
			(xy 394.960903 -418.106424) (xy 395.002089 -418.142112) (xy 395.037778 -418.183299) (xy 395.067241 -418.229145)
			(xy 395.08988 -418.278718) (xy 395.105234 -418.331008) (xy 395.11299 -418.384951) (xy 395.11299 -418.439449)
			(xy 395.112989 -418.439457) (xy 396.550523 -418.439457) (xy 396.550523 -418.384943) (xy 396.558282 -418.330984)
			(xy 396.573641 -418.278678) (xy 396.596289 -418.229091) (xy 396.625763 -418.183232) (xy 396.661464 -418.142035)
			(xy 396.702666 -418.106338) (xy 396.748528 -418.076869) (xy 396.798117 -418.054227) (xy 396.850425 -418.038873)
			(xy 396.904385 -418.03112) (xy 396.931642 -418.03066) (xy 397.795242 -418.03066) (xy 397.822489 -418.031213)
			(xy 397.876428 -418.038974) (xy 397.928713 -418.054331) (xy 397.978281 -418.076973) (xy 398.024122 -418.106438)
			(xy 398.065303 -418.142126) (xy 398.100987 -418.183312) (xy 398.130447 -418.229156) (xy 398.153083 -418.278727)
			(xy 398.168435 -418.331014) (xy 398.17619 -418.384953) (xy 398.17619 -418.439447) (xy 398.176189 -418.439453)
			(xy 399.613846 -418.439453) (xy 399.613846 -418.384947) (xy 399.621603 -418.330997) (xy 399.636958 -418.278699)
			(xy 399.6596 -418.229119) (xy 399.689067 -418.183265) (xy 399.724759 -418.142072) (xy 399.765951 -418.106378)
			(xy 399.811803 -418.076908) (xy 399.861382 -418.054264) (xy 399.913679 -418.038906) (xy 399.967629 -418.031147)
			(xy 399.994882 -418.03066) (xy 400.858482 -418.03066) (xy 400.885733 -418.031186) (xy 400.939682 -418.03894)
			(xy 400.991977 -418.054293) (xy 401.041556 -418.076933) (xy 401.087407 -418.106398) (xy 401.128599 -418.142089)
			(xy 401.164291 -418.183278) (xy 401.193758 -418.229129) (xy 401.2164 -418.278706) (xy 401.231756 -418.331001)
			(xy 401.239513 -418.384949) (xy 401.239513 -418.439451) (xy 401.239512 -418.439456) (xy 402.677023 -418.439456)
			(xy 402.677023 -418.384944) (xy 402.684781 -418.330986) (xy 402.70014 -418.278682) (xy 402.722786 -418.229097)
			(xy 402.752258 -418.183238) (xy 402.787957 -418.142042) (xy 402.829156 -418.106345) (xy 402.875016 -418.076875)
			(xy 402.924603 -418.054232) (xy 402.976908 -418.038877) (xy 403.030866 -418.031121) (xy 403.058122 -418.03066)
			(xy 403.921722 -418.03066) (xy 403.94897 -418.031212) (xy 404.002911 -418.03897) (xy 404.055198 -418.054326)
			(xy 404.104769 -418.076966) (xy 404.150612 -418.106431) (xy 404.191796 -418.142119) (xy 404.227483 -418.183305)
			(xy 404.256944 -418.229151) (xy 404.279582 -418.278722) (xy 404.294935 -418.331011) (xy 404.30269 -418.384952)
			(xy 404.30269 -418.439448) (xy 404.302689 -418.439452) (xy 405.740346 -418.439452) (xy 405.740346 -418.384948)
			(xy 405.748102 -418.330999) (xy 405.763456 -418.278703) (xy 405.786097 -418.229124) (xy 405.815562 -418.183272)
			(xy 405.851252 -418.142079) (xy 405.892441 -418.106385) (xy 405.938291 -418.076915) (xy 405.987868 -418.05427)
			(xy 406.040162 -418.03891) (xy 406.09411 -418.031148) (xy 406.121362 -418.03066) (xy 406.984962 -418.03066)
			(xy 407.012214 -418.031185) (xy 407.066165 -418.038937) (xy 407.118463 -418.054288) (xy 407.168044 -418.076926)
			(xy 407.213898 -418.106391) (xy 407.255091 -418.142082) (xy 407.290786 -418.183272) (xy 407.320255 -418.229123)
			(xy 407.342899 -418.278701) (xy 407.358255 -418.330998) (xy 407.366013 -418.384948) (xy 407.366013 -418.439452)
			(xy 407.366013 -418.439455) (xy 408.803523 -418.439455) (xy 408.803523 -418.384945) (xy 408.811281 -418.330989)
			(xy 408.826638 -418.278687) (xy 408.849283 -418.229102) (xy 408.878753 -418.183245) (xy 408.91445 -418.142049)
			(xy 408.955647 -418.106352) (xy 409.001504 -418.076882) (xy 409.051088 -418.054237) (xy 409.103391 -418.03888)
			(xy 409.157347 -418.031123) (xy 409.184602 -418.03066) (xy 410.048202 -418.03066) (xy 410.075451 -418.03121)
			(xy 410.129394 -418.038966) (xy 410.181684 -418.05432) (xy 410.231257 -418.07696) (xy 410.277103 -418.106424)
			(xy 410.318289 -418.142112) (xy 410.353978 -418.183299) (xy 410.383441 -418.229145) (xy 410.40608 -418.278718)
			(xy 410.421434 -418.331008) (xy 410.42919 -418.384951) (xy 410.42919 -418.439449) (xy 410.429189 -418.439457)
			(xy 411.866723 -418.439457) (xy 411.866723 -418.384943) (xy 411.874482 -418.330984) (xy 411.889841 -418.278678)
			(xy 411.912489 -418.229091) (xy 411.941963 -418.183232) (xy 411.977664 -418.142035) (xy 412.018866 -418.106338)
			(xy 412.064728 -418.076869) (xy 412.114317 -418.054227) (xy 412.166625 -418.038873) (xy 412.220585 -418.03112)
			(xy 412.247842 -418.03066) (xy 413.111442 -418.03066) (xy 413.138689 -418.031213) (xy 413.192628 -418.038974)
			(xy 413.244913 -418.054331) (xy 413.294481 -418.076973) (xy 413.340322 -418.106438) (xy 413.381503 -418.142126)
			(xy 413.417187 -418.183312) (xy 413.446647 -418.229156) (xy 413.469283 -418.278727) (xy 413.484635 -418.331014)
			(xy 413.49239 -418.384953) (xy 413.49239 -418.439447) (xy 413.492389 -418.439453) (xy 414.930046 -418.439453)
			(xy 414.930046 -418.384947) (xy 414.937803 -418.330997) (xy 414.953158 -418.278699) (xy 414.9758 -418.229119)
			(xy 415.005267 -418.183265) (xy 415.040959 -418.142072) (xy 415.082151 -418.106378) (xy 415.128003 -418.076908)
			(xy 415.177582 -418.054264) (xy 415.229879 -418.038906) (xy 415.283829 -418.031147) (xy 415.311082 -418.03066)
			(xy 416.174682 -418.03066) (xy 416.201933 -418.031186) (xy 416.255882 -418.03894) (xy 416.308177 -418.054293)
			(xy 416.357756 -418.076933) (xy 416.403607 -418.106398) (xy 416.444799 -418.142089) (xy 416.480491 -418.183278)
			(xy 416.509958 -418.229129) (xy 416.5326 -418.278706) (xy 416.547956 -418.331001) (xy 416.555713 -418.384949)
			(xy 416.555713 -418.439451) (xy 416.555712 -418.439456) (xy 417.993223 -418.439456) (xy 417.993223 -418.384944)
			(xy 418.000981 -418.330986) (xy 418.01634 -418.278682) (xy 418.038986 -418.229097) (xy 418.068458 -418.183238)
			(xy 418.104157 -418.142042) (xy 418.145356 -418.106345) (xy 418.191216 -418.076875) (xy 418.240803 -418.054232)
			(xy 418.293108 -418.038877) (xy 418.347066 -418.031121) (xy 418.374322 -418.03066) (xy 419.237922 -418.03066)
			(xy 419.26517 -418.031212) (xy 419.319111 -418.03897) (xy 419.371398 -418.054326) (xy 419.420969 -418.076966)
			(xy 419.466812 -418.106431) (xy 419.507996 -418.142119) (xy 419.543683 -418.183305) (xy 419.573144 -418.229151)
			(xy 419.595782 -418.278722) (xy 419.611135 -418.331011) (xy 419.61889 -418.384952) (xy 419.61889 -418.439448)
			(xy 419.611135 -418.493389) (xy 419.595782 -418.545678) (xy 419.573144 -418.595249) (xy 419.543683 -418.641095)
			(xy 419.507996 -418.682281) (xy 419.466812 -418.717969) (xy 419.420969 -418.747434) (xy 419.371398 -418.770074)
			(xy 419.319111 -418.78543) (xy 419.26517 -418.793188) (xy 419.237922 -418.793676) (xy 418.374322 -418.793676)
			(xy 418.347066 -418.793279) (xy 418.293108 -418.785523) (xy 418.240803 -418.770168) (xy 418.191216 -418.747525)
			(xy 418.145356 -418.718055) (xy 418.104157 -418.682358) (xy 418.068458 -418.641162) (xy 418.038986 -418.595303)
			(xy 418.01634 -418.545718) (xy 418.000981 -418.493414) (xy 417.993223 -418.439456) (xy 416.555712 -418.439456)
			(xy 416.547956 -418.493399) (xy 416.5326 -418.545694) (xy 416.509958 -418.595271) (xy 416.480491 -418.641122)
			(xy 416.444799 -418.682311) (xy 416.403607 -418.718002) (xy 416.357756 -418.747467) (xy 416.308177 -418.770107)
			(xy 416.255882 -418.78546) (xy 416.201933 -418.793214) (xy 416.174682 -418.793676) (xy 415.311082 -418.793676)
			(xy 415.283829 -418.793253) (xy 415.229879 -418.785494) (xy 415.177582 -418.770136) (xy 415.128003 -418.747492)
			(xy 415.082151 -418.718022) (xy 415.040959 -418.682328) (xy 415.005267 -418.641135) (xy 414.9758 -418.595281)
			(xy 414.953158 -418.545701) (xy 414.937803 -418.493403) (xy 414.930046 -418.439453) (xy 413.492389 -418.439453)
			(xy 413.484635 -418.493386) (xy 413.469283 -418.545673) (xy 413.446647 -418.595244) (xy 413.417187 -418.641088)
			(xy 413.381503 -418.682274) (xy 413.340322 -418.717962) (xy 413.294481 -418.747427) (xy 413.244913 -418.770069)
			(xy 413.192628 -418.785426) (xy 413.138689 -418.793187) (xy 413.111442 -418.793676) (xy 412.247842 -418.793676)
			(xy 412.220585 -418.79328) (xy 412.166625 -418.785527) (xy 412.114317 -418.770173) (xy 412.064728 -418.747531)
			(xy 412.018866 -418.718062) (xy 411.977664 -418.682365) (xy 411.941963 -418.641168) (xy 411.912489 -418.595309)
			(xy 411.889841 -418.545722) (xy 411.874482 -418.493416) (xy 411.866723 -418.439457) (xy 410.429189 -418.439457)
			(xy 410.421434 -418.493392) (xy 410.40608 -418.545682) (xy 410.383441 -418.595255) (xy 410.353978 -418.641101)
			(xy 410.318289 -418.682288) (xy 410.277103 -418.717976) (xy 410.231257 -418.74744) (xy 410.181684 -418.77008)
			(xy 410.129394 -418.785434) (xy 410.075451 -418.79319) (xy 410.048202 -418.793676) (xy 409.184602 -418.793676)
			(xy 409.157347 -418.793277) (xy 409.103391 -418.78552) (xy 409.051088 -418.770163) (xy 409.001504 -418.747518)
			(xy 408.955647 -418.718048) (xy 408.91445 -418.682351) (xy 408.878753 -418.641155) (xy 408.849283 -418.595298)
			(xy 408.826638 -418.545713) (xy 408.811281 -418.493411) (xy 408.803523 -418.439455) (xy 407.366013 -418.439455)
			(xy 407.358255 -418.493402) (xy 407.342899 -418.545699) (xy 407.320255 -418.595277) (xy 407.290786 -418.641128)
			(xy 407.255091 -418.682318) (xy 407.213898 -418.718009) (xy 407.168044 -418.747474) (xy 407.118463 -418.770112)
			(xy 407.066165 -418.785463) (xy 407.012214 -418.793215) (xy 406.984962 -418.793676) (xy 406.121362 -418.793676)
			(xy 406.09411 -418.793252) (xy 406.040162 -418.78549) (xy 405.987868 -418.77013) (xy 405.938291 -418.747485)
			(xy 405.892441 -418.718015) (xy 405.851252 -418.682321) (xy 405.815562 -418.641128) (xy 405.786097 -418.595276)
			(xy 405.763456 -418.545697) (xy 405.748102 -418.493401) (xy 405.740346 -418.439452) (xy 404.302689 -418.439452)
			(xy 404.294935 -418.493389) (xy 404.279582 -418.545678) (xy 404.256944 -418.595249) (xy 404.227483 -418.641095)
			(xy 404.191796 -418.682281) (xy 404.150612 -418.717969) (xy 404.104769 -418.747434) (xy 404.055198 -418.770074)
			(xy 404.002911 -418.78543) (xy 403.94897 -418.793188) (xy 403.921722 -418.793676) (xy 403.058122 -418.793676)
			(xy 403.030866 -418.793279) (xy 402.976908 -418.785523) (xy 402.924603 -418.770168) (xy 402.875016 -418.747525)
			(xy 402.829156 -418.718055) (xy 402.787957 -418.682358) (xy 402.752258 -418.641162) (xy 402.722786 -418.595303)
			(xy 402.70014 -418.545718) (xy 402.684781 -418.493414) (xy 402.677023 -418.439456) (xy 401.239512 -418.439456)
			(xy 401.231756 -418.493399) (xy 401.2164 -418.545694) (xy 401.193758 -418.595271) (xy 401.164291 -418.641122)
			(xy 401.128599 -418.682311) (xy 401.087407 -418.718002) (xy 401.041556 -418.747467) (xy 400.991977 -418.770107)
			(xy 400.939682 -418.78546) (xy 400.885733 -418.793214) (xy 400.858482 -418.793676) (xy 399.994882 -418.793676)
			(xy 399.967629 -418.793253) (xy 399.913679 -418.785494) (xy 399.861382 -418.770136) (xy 399.811803 -418.747492)
			(xy 399.765951 -418.718022) (xy 399.724759 -418.682328) (xy 399.689067 -418.641135) (xy 399.6596 -418.595281)
			(xy 399.636958 -418.545701) (xy 399.621603 -418.493403) (xy 399.613846 -418.439453) (xy 398.176189 -418.439453)
			(xy 398.168435 -418.493386) (xy 398.153083 -418.545673) (xy 398.130447 -418.595244) (xy 398.100987 -418.641088)
			(xy 398.065303 -418.682274) (xy 398.024122 -418.717962) (xy 397.978281 -418.747427) (xy 397.928713 -418.770069)
			(xy 397.876428 -418.785426) (xy 397.822489 -418.793187) (xy 397.795242 -418.793676) (xy 396.931642 -418.793676)
			(xy 396.904385 -418.79328) (xy 396.850425 -418.785527) (xy 396.798117 -418.770173) (xy 396.748528 -418.747531)
			(xy 396.702666 -418.718062) (xy 396.661464 -418.682365) (xy 396.625763 -418.641168) (xy 396.596289 -418.595309)
			(xy 396.573641 -418.545722) (xy 396.558282 -418.493416) (xy 396.550523 -418.439457) (xy 395.112989 -418.439457)
			(xy 395.105234 -418.493392) (xy 395.08988 -418.545682) (xy 395.067241 -418.595255) (xy 395.037778 -418.641101)
			(xy 395.002089 -418.682288) (xy 394.960903 -418.717976) (xy 394.915057 -418.74744) (xy 394.865484 -418.77008)
			(xy 394.813194 -418.785434) (xy 394.759251 -418.79319) (xy 394.732002 -418.793676) (xy 393.868402 -418.793676)
			(xy 393.841147 -418.793277) (xy 393.787191 -418.78552) (xy 393.734888 -418.770163) (xy 393.685304 -418.747518)
			(xy 393.639447 -418.718048) (xy 393.59825 -418.682351) (xy 393.562553 -418.641155) (xy 393.533083 -418.595298)
			(xy 393.510438 -418.545713) (xy 393.495081 -418.493411) (xy 393.487323 -418.439455) (xy 392.049813 -418.439455)
			(xy 392.042055 -418.493402) (xy 392.026699 -418.545699) (xy 392.004055 -418.595277) (xy 391.974586 -418.641128)
			(xy 391.938891 -418.682318) (xy 391.897698 -418.718009) (xy 391.851844 -418.747474) (xy 391.802263 -418.770112)
			(xy 391.749965 -418.785463) (xy 391.696014 -418.793215) (xy 391.668762 -418.793676) (xy 390.805162 -418.793676)
			(xy 390.77791 -418.793252) (xy 390.723962 -418.78549) (xy 390.671668 -418.77013) (xy 390.622091 -418.747485)
			(xy 390.576241 -418.718015) (xy 390.535052 -418.682321) (xy 390.499362 -418.641128) (xy 390.469897 -418.595276)
			(xy 390.447256 -418.545697) (xy 390.431902 -418.493401) (xy 390.424146 -418.439452) (xy 388.986489 -418.439452)
			(xy 388.978735 -418.493389) (xy 388.963382 -418.545678) (xy 388.940744 -418.595249) (xy 388.911283 -418.641095)
			(xy 388.875596 -418.682281) (xy 388.834412 -418.717969) (xy 388.788569 -418.747434) (xy 388.738998 -418.770074)
			(xy 388.686711 -418.78543) (xy 388.63277 -418.793188) (xy 388.605522 -418.793676) (xy 387.741922 -418.793676)
			(xy 387.714666 -418.793279) (xy 387.660708 -418.785523) (xy 387.608403 -418.770168) (xy 387.558816 -418.747525)
			(xy 387.512956 -418.718055) (xy 387.471757 -418.682358) (xy 387.436058 -418.641162) (xy 387.406586 -418.595303)
			(xy 387.38394 -418.545718) (xy 387.368581 -418.493414) (xy 387.360823 -418.439456) (xy 385.923312 -418.439456)
			(xy 385.915556 -418.493399) (xy 385.9002 -418.545694) (xy 385.877558 -418.595271) (xy 385.848091 -418.641122)
			(xy 385.812399 -418.682311) (xy 385.771207 -418.718002) (xy 385.725356 -418.747467) (xy 385.675777 -418.770107)
			(xy 385.623482 -418.78546) (xy 385.569533 -418.793214) (xy 385.542282 -418.793676) (xy 384.678682 -418.793676)
			(xy 384.651429 -418.793253) (xy 384.597479 -418.785494) (xy 384.545182 -418.770136) (xy 384.495603 -418.747492)
			(xy 384.449751 -418.718022) (xy 384.408559 -418.682328) (xy 384.372867 -418.641135) (xy 384.3434 -418.595281)
			(xy 384.320758 -418.545701) (xy 384.305403 -418.493403) (xy 384.297646 -418.439453) (xy 382.859989 -418.439453)
			(xy 382.852235 -418.493386) (xy 382.836883 -418.545673) (xy 382.814247 -418.595244) (xy 382.784787 -418.641088)
			(xy 382.749103 -418.682274) (xy 382.707922 -418.717962) (xy 382.662081 -418.747427) (xy 382.612513 -418.770069)
			(xy 382.560228 -418.785426) (xy 382.506289 -418.793187) (xy 382.479042 -418.793676) (xy 381.615442 -418.793676)
			(xy 381.588185 -418.79328) (xy 381.534225 -418.785527) (xy 381.481917 -418.770173) (xy 381.432328 -418.747531)
			(xy 381.386466 -418.718062) (xy 381.345264 -418.682365) (xy 381.309563 -418.641168) (xy 381.280089 -418.595309)
			(xy 381.257441 -418.545722) (xy 381.242082 -418.493416) (xy 381.234323 -418.439457) (xy 379.796789 -418.439457)
			(xy 379.789034 -418.493392) (xy 379.77368 -418.545682) (xy 379.751041 -418.595255) (xy 379.721578 -418.641101)
			(xy 379.685889 -418.682288) (xy 379.644703 -418.717976) (xy 379.598857 -418.74744) (xy 379.549284 -418.77008)
			(xy 379.496994 -418.785434) (xy 379.443051 -418.79319) (xy 379.415802 -418.793676) (xy 378.552202 -418.793676)
			(xy 378.524947 -418.793277) (xy 378.470991 -418.78552) (xy 378.418688 -418.770163) (xy 378.369104 -418.747518)
			(xy 378.323247 -418.718048) (xy 378.28205 -418.682351) (xy 378.246353 -418.641155) (xy 378.216883 -418.595298)
			(xy 378.194238 -418.545713) (xy 378.178881 -418.493411) (xy 378.171123 -418.439455) (xy 376.733613 -418.439455)
			(xy 376.725855 -418.493402) (xy 376.710499 -418.545699) (xy 376.687855 -418.595277) (xy 376.658386 -418.641128)
			(xy 376.622691 -418.682318) (xy 376.581498 -418.718009) (xy 376.535644 -418.747474) (xy 376.486063 -418.770112)
			(xy 376.433765 -418.785463) (xy 376.379814 -418.793215) (xy 376.352562 -418.793676) (xy 375.488962 -418.793676)
			(xy 375.46171 -418.793252) (xy 375.407762 -418.78549) (xy 375.355468 -418.77013) (xy 375.305891 -418.747485)
			(xy 375.260041 -418.718015) (xy 375.218852 -418.682321) (xy 375.183162 -418.641128) (xy 375.153697 -418.595276)
			(xy 375.131056 -418.545697) (xy 375.115702 -418.493401) (xy 375.107946 -418.439452) (xy 373.670289 -418.439452)
			(xy 373.662535 -418.493389) (xy 373.647182 -418.545678) (xy 373.624544 -418.595249) (xy 373.595083 -418.641095)
			(xy 373.559396 -418.682281) (xy 373.518212 -418.717969) (xy 373.472369 -418.747434) (xy 373.422798 -418.770074)
			(xy 373.370511 -418.78543) (xy 373.31657 -418.793188) (xy 373.289322 -418.793676) (xy 372.425722 -418.793676)
			(xy 372.398466 -418.793279) (xy 372.344508 -418.785523) (xy 372.292203 -418.770168) (xy 372.242616 -418.747525)
			(xy 372.196756 -418.718055) (xy 372.155557 -418.682358) (xy 372.119858 -418.641162) (xy 372.090386 -418.595303)
			(xy 372.06774 -418.545718) (xy 372.052381 -418.493414) (xy 372.044623 -418.439456) (xy 370.313204 -418.439456)
			(xy 370.313204 -420.739316) (xy 370.16182 -420.739316) (xy 370.150223 -420.741274) (xy 370.130566 -420.754154)
			(xy 370.118604 -420.774382) (xy 370.117116 -420.786052) (xy 370.117116 -420.979455) (xy 370.513023 -420.979455)
			(xy 370.513023 -420.924945) (xy 370.520781 -420.870989) (xy 370.536138 -420.818687) (xy 370.558783 -420.769102)
			(xy 370.588253 -420.723245) (xy 370.62395 -420.682049) (xy 370.665147 -420.646352) (xy 370.711004 -420.616882)
			(xy 370.760588 -420.594237) (xy 370.812891 -420.57888) (xy 370.866847 -420.571123) (xy 370.894102 -420.57066)
			(xy 371.757702 -420.57066) (xy 371.784951 -420.57121) (xy 371.838894 -420.578966) (xy 371.891184 -420.59432)
			(xy 371.940757 -420.61696) (xy 371.986603 -420.646424) (xy 372.027789 -420.682112) (xy 372.063478 -420.723299)
			(xy 372.092941 -420.769145) (xy 372.11558 -420.818718) (xy 372.130934 -420.871008) (xy 372.13869 -420.924951)
			(xy 372.13869 -420.979449) (xy 372.138689 -420.979457) (xy 373.576223 -420.979457) (xy 373.576223 -420.924943)
			(xy 373.583982 -420.870984) (xy 373.599341 -420.818678) (xy 373.621989 -420.769091) (xy 373.651463 -420.723232)
			(xy 373.687164 -420.682035) (xy 373.728366 -420.646338) (xy 373.774228 -420.616869) (xy 373.823817 -420.594227)
			(xy 373.876125 -420.578873) (xy 373.930085 -420.57112) (xy 373.957342 -420.57066) (xy 374.820942 -420.57066)
			(xy 374.848189 -420.571213) (xy 374.902128 -420.578974) (xy 374.954413 -420.594331) (xy 375.003981 -420.616973)
			(xy 375.049822 -420.646438) (xy 375.091003 -420.682126) (xy 375.126687 -420.723312) (xy 375.156147 -420.769156)
			(xy 375.178783 -420.818727) (xy 375.194135 -420.871014) (xy 375.20189 -420.924953) (xy 375.20189 -420.979447)
			(xy 375.201889 -420.979453) (xy 376.639546 -420.979453) (xy 376.639546 -420.924947) (xy 376.647303 -420.870997)
			(xy 376.662658 -420.818699) (xy 376.6853 -420.769119) (xy 376.714767 -420.723265) (xy 376.750459 -420.682072)
			(xy 376.791651 -420.646378) (xy 376.837503 -420.616908) (xy 376.887082 -420.594264) (xy 376.939379 -420.578906)
			(xy 376.993329 -420.571147) (xy 377.020582 -420.57066) (xy 377.884182 -420.57066) (xy 377.911433 -420.571186)
			(xy 377.965382 -420.57894) (xy 378.017677 -420.594293) (xy 378.067256 -420.616933) (xy 378.113107 -420.646398)
			(xy 378.154299 -420.682089) (xy 378.189991 -420.723278) (xy 378.219458 -420.769129) (xy 378.2421 -420.818706)
			(xy 378.257456 -420.871001) (xy 378.265213 -420.924949) (xy 378.265213 -420.979451) (xy 378.265212 -420.979456)
			(xy 379.702723 -420.979456) (xy 379.702723 -420.924944) (xy 379.710481 -420.870986) (xy 379.72584 -420.818682)
			(xy 379.748486 -420.769097) (xy 379.777958 -420.723238) (xy 379.813657 -420.682042) (xy 379.854856 -420.646345)
			(xy 379.900716 -420.616875) (xy 379.950303 -420.594232) (xy 380.002608 -420.578877) (xy 380.056566 -420.571121)
			(xy 380.083822 -420.57066) (xy 380.947422 -420.57066) (xy 380.97467 -420.571212) (xy 381.028611 -420.57897)
			(xy 381.080898 -420.594326) (xy 381.130469 -420.616966) (xy 381.176312 -420.646431) (xy 381.217496 -420.682119)
			(xy 381.253183 -420.723305) (xy 381.282644 -420.769151) (xy 381.305282 -420.818722) (xy 381.320635 -420.871011)
			(xy 381.32839 -420.924952) (xy 381.32839 -420.979448) (xy 381.328389 -420.979452) (xy 382.766046 -420.979452)
			(xy 382.766046 -420.924948) (xy 382.773802 -420.870999) (xy 382.789156 -420.818703) (xy 382.811797 -420.769124)
			(xy 382.841262 -420.723272) (xy 382.876952 -420.682079) (xy 382.918141 -420.646385) (xy 382.963991 -420.616915)
			(xy 383.013568 -420.59427) (xy 383.065862 -420.57891) (xy 383.11981 -420.571148) (xy 383.147062 -420.57066)
			(xy 384.010662 -420.57066) (xy 384.037914 -420.571185) (xy 384.091865 -420.578937) (xy 384.144163 -420.594288)
			(xy 384.193744 -420.616926) (xy 384.239598 -420.646391) (xy 384.280791 -420.682082) (xy 384.316486 -420.723272)
			(xy 384.345955 -420.769123) (xy 384.368599 -420.818701) (xy 384.383955 -420.870998) (xy 384.391713 -420.924948)
			(xy 384.391713 -420.979452) (xy 384.391713 -420.979455) (xy 385.829223 -420.979455) (xy 385.829223 -420.924945)
			(xy 385.836981 -420.870989) (xy 385.852338 -420.818687) (xy 385.874983 -420.769102) (xy 385.904453 -420.723245)
			(xy 385.94015 -420.682049) (xy 385.981347 -420.646352) (xy 386.027204 -420.616882) (xy 386.076788 -420.594237)
			(xy 386.129091 -420.57888) (xy 386.183047 -420.571123) (xy 386.210302 -420.57066) (xy 387.073902 -420.57066)
			(xy 387.101151 -420.57121) (xy 387.155094 -420.578966) (xy 387.207384 -420.59432) (xy 387.256957 -420.61696)
			(xy 387.302803 -420.646424) (xy 387.343989 -420.682112) (xy 387.379678 -420.723299) (xy 387.409141 -420.769145)
			(xy 387.43178 -420.818718) (xy 387.447134 -420.871008) (xy 387.45489 -420.924951) (xy 387.45489 -420.979449)
			(xy 387.454889 -420.979457) (xy 388.892423 -420.979457) (xy 388.892423 -420.924943) (xy 388.900182 -420.870984)
			(xy 388.915541 -420.818678) (xy 388.938189 -420.769091) (xy 388.967663 -420.723232) (xy 389.003364 -420.682035)
			(xy 389.044566 -420.646338) (xy 389.090428 -420.616869) (xy 389.140017 -420.594227) (xy 389.192325 -420.578873)
			(xy 389.246285 -420.57112) (xy 389.273542 -420.57066) (xy 390.137142 -420.57066) (xy 390.164389 -420.571213)
			(xy 390.218328 -420.578974) (xy 390.270613 -420.594331) (xy 390.320181 -420.616973) (xy 390.366022 -420.646438)
			(xy 390.407203 -420.682126) (xy 390.442887 -420.723312) (xy 390.472347 -420.769156) (xy 390.494983 -420.818727)
			(xy 390.510335 -420.871014) (xy 390.51809 -420.924953) (xy 390.51809 -420.979447) (xy 390.518089 -420.979453)
			(xy 391.955746 -420.979453) (xy 391.955746 -420.924947) (xy 391.963503 -420.870997) (xy 391.978858 -420.818699)
			(xy 392.0015 -420.769119) (xy 392.030967 -420.723265) (xy 392.066659 -420.682072) (xy 392.107851 -420.646378)
			(xy 392.153703 -420.616908) (xy 392.203282 -420.594264) (xy 392.255579 -420.578906) (xy 392.309529 -420.571147)
			(xy 392.336782 -420.57066) (xy 393.200382 -420.57066) (xy 393.227633 -420.571186) (xy 393.281582 -420.57894)
			(xy 393.333877 -420.594293) (xy 393.383456 -420.616933) (xy 393.429307 -420.646398) (xy 393.470499 -420.682089)
			(xy 393.506191 -420.723278) (xy 393.535658 -420.769129) (xy 393.5583 -420.818706) (xy 393.573656 -420.871001)
			(xy 393.581413 -420.924949) (xy 393.581413 -420.979451) (xy 393.581412 -420.979456) (xy 395.018923 -420.979456)
			(xy 395.018923 -420.924944) (xy 395.026681 -420.870986) (xy 395.04204 -420.818682) (xy 395.064686 -420.769097)
			(xy 395.094158 -420.723238) (xy 395.129857 -420.682042) (xy 395.171056 -420.646345) (xy 395.216916 -420.616875)
			(xy 395.266503 -420.594232) (xy 395.318808 -420.578877) (xy 395.372766 -420.571121) (xy 395.400022 -420.57066)
			(xy 396.263622 -420.57066) (xy 396.29087 -420.571212) (xy 396.344811 -420.57897) (xy 396.397098 -420.594326)
			(xy 396.446669 -420.616966) (xy 396.492512 -420.646431) (xy 396.533696 -420.682119) (xy 396.569383 -420.723305)
			(xy 396.598844 -420.769151) (xy 396.621482 -420.818722) (xy 396.636835 -420.871011) (xy 396.64459 -420.924952)
			(xy 396.64459 -420.979448) (xy 396.644589 -420.979452) (xy 398.082246 -420.979452) (xy 398.082246 -420.924948)
			(xy 398.090002 -420.870999) (xy 398.105356 -420.818703) (xy 398.127997 -420.769124) (xy 398.157462 -420.723272)
			(xy 398.193152 -420.682079) (xy 398.234341 -420.646385) (xy 398.280191 -420.616915) (xy 398.329768 -420.59427)
			(xy 398.382062 -420.57891) (xy 398.43601 -420.571148) (xy 398.463262 -420.57066) (xy 399.326862 -420.57066)
			(xy 399.354114 -420.571185) (xy 399.408065 -420.578937) (xy 399.460363 -420.594288) (xy 399.509944 -420.616926)
			(xy 399.555798 -420.646391) (xy 399.596991 -420.682082) (xy 399.632686 -420.723272) (xy 399.662155 -420.769123)
			(xy 399.684799 -420.818701) (xy 399.700155 -420.870998) (xy 399.707913 -420.924948) (xy 399.707913 -420.979452)
			(xy 399.707913 -420.979455) (xy 401.145423 -420.979455) (xy 401.145423 -420.924945) (xy 401.153181 -420.870989)
			(xy 401.168538 -420.818687) (xy 401.191183 -420.769102) (xy 401.220653 -420.723245) (xy 401.25635 -420.682049)
			(xy 401.297547 -420.646352) (xy 401.343404 -420.616882) (xy 401.392988 -420.594237) (xy 401.445291 -420.57888)
			(xy 401.499247 -420.571123) (xy 401.526502 -420.57066) (xy 402.390102 -420.57066) (xy 402.417351 -420.57121)
			(xy 402.471294 -420.578966) (xy 402.523584 -420.59432) (xy 402.573157 -420.61696) (xy 402.619003 -420.646424)
			(xy 402.660189 -420.682112) (xy 402.695878 -420.723299) (xy 402.725341 -420.769145) (xy 402.74798 -420.818718)
			(xy 402.763334 -420.871008) (xy 402.77109 -420.924951) (xy 402.77109 -420.979449) (xy 402.771089 -420.979457)
			(xy 404.208623 -420.979457) (xy 404.208623 -420.924943) (xy 404.216382 -420.870984) (xy 404.231741 -420.818678)
			(xy 404.254389 -420.769091) (xy 404.283863 -420.723232) (xy 404.319564 -420.682035) (xy 404.360766 -420.646338)
			(xy 404.406628 -420.616869) (xy 404.456217 -420.594227) (xy 404.508525 -420.578873) (xy 404.562485 -420.57112)
			(xy 404.589742 -420.57066) (xy 405.453342 -420.57066) (xy 405.480589 -420.571213) (xy 405.534528 -420.578974)
			(xy 405.586813 -420.594331) (xy 405.636381 -420.616973) (xy 405.682222 -420.646438) (xy 405.723403 -420.682126)
			(xy 405.759087 -420.723312) (xy 405.788547 -420.769156) (xy 405.811183 -420.818727) (xy 405.826535 -420.871014)
			(xy 405.83429 -420.924953) (xy 405.83429 -420.979447) (xy 405.834289 -420.979453) (xy 407.271946 -420.979453)
			(xy 407.271946 -420.924947) (xy 407.279703 -420.870997) (xy 407.295058 -420.818699) (xy 407.3177 -420.769119)
			(xy 407.347167 -420.723265) (xy 407.382859 -420.682072) (xy 407.424051 -420.646378) (xy 407.469903 -420.616908)
			(xy 407.519482 -420.594264) (xy 407.571779 -420.578906) (xy 407.625729 -420.571147) (xy 407.652982 -420.57066)
			(xy 408.516582 -420.57066) (xy 408.543833 -420.571186) (xy 408.597782 -420.57894) (xy 408.650077 -420.594293)
			(xy 408.699656 -420.616933) (xy 408.745507 -420.646398) (xy 408.786699 -420.682089) (xy 408.822391 -420.723278)
			(xy 408.851858 -420.769129) (xy 408.8745 -420.818706) (xy 408.889856 -420.871001) (xy 408.897613 -420.924949)
			(xy 408.897613 -420.979451) (xy 408.897612 -420.979456) (xy 410.335123 -420.979456) (xy 410.335123 -420.924944)
			(xy 410.342881 -420.870986) (xy 410.35824 -420.818682) (xy 410.380886 -420.769097) (xy 410.410358 -420.723238)
			(xy 410.446057 -420.682042) (xy 410.487256 -420.646345) (xy 410.533116 -420.616875) (xy 410.582703 -420.594232)
			(xy 410.635008 -420.578877) (xy 410.688966 -420.571121) (xy 410.716222 -420.57066) (xy 411.579822 -420.57066)
			(xy 411.60707 -420.571212) (xy 411.661011 -420.57897) (xy 411.713298 -420.594326) (xy 411.762869 -420.616966)
			(xy 411.808712 -420.646431) (xy 411.849896 -420.682119) (xy 411.885583 -420.723305) (xy 411.915044 -420.769151)
			(xy 411.937682 -420.818722) (xy 411.953035 -420.871011) (xy 411.96079 -420.924952) (xy 411.96079 -420.979448)
			(xy 411.960789 -420.979452) (xy 413.398446 -420.979452) (xy 413.398446 -420.924948) (xy 413.406202 -420.870999)
			(xy 413.421556 -420.818703) (xy 413.444197 -420.769124) (xy 413.473662 -420.723272) (xy 413.509352 -420.682079)
			(xy 413.550541 -420.646385) (xy 413.596391 -420.616915) (xy 413.645968 -420.59427) (xy 413.698262 -420.57891)
			(xy 413.75221 -420.571148) (xy 413.779462 -420.57066) (xy 414.643062 -420.57066) (xy 414.670314 -420.571185)
			(xy 414.724265 -420.578937) (xy 414.776563 -420.594288) (xy 414.826144 -420.616926) (xy 414.871998 -420.646391)
			(xy 414.913191 -420.682082) (xy 414.948886 -420.723272) (xy 414.978355 -420.769123) (xy 415.000999 -420.818701)
			(xy 415.016355 -420.870998) (xy 415.024113 -420.924948) (xy 415.024113 -420.979452) (xy 415.024113 -420.979455)
			(xy 416.461623 -420.979455) (xy 416.461623 -420.924945) (xy 416.469381 -420.870989) (xy 416.484738 -420.818687)
			(xy 416.507383 -420.769102) (xy 416.536853 -420.723245) (xy 416.57255 -420.682049) (xy 416.613747 -420.646352)
			(xy 416.659604 -420.616882) (xy 416.709188 -420.594237) (xy 416.761491 -420.57888) (xy 416.815447 -420.571123)
			(xy 416.842702 -420.57066) (xy 417.706302 -420.57066) (xy 417.733551 -420.57121) (xy 417.787494 -420.578966)
			(xy 417.839784 -420.59432) (xy 417.889357 -420.61696) (xy 417.935203 -420.646424) (xy 417.976389 -420.682112)
			(xy 418.012078 -420.723299) (xy 418.041541 -420.769145) (xy 418.06418 -420.818718) (xy 418.079534 -420.871008)
			(xy 418.08729 -420.924951) (xy 418.08729 -420.979449) (xy 418.079534 -421.033392) (xy 418.06418 -421.085682)
			(xy 418.041541 -421.135255) (xy 418.012078 -421.181101) (xy 417.976389 -421.222288) (xy 417.935203 -421.257976)
			(xy 417.889357 -421.28744) (xy 417.839784 -421.31008) (xy 417.787494 -421.325434) (xy 417.733551 -421.33319)
			(xy 417.706302 -421.333676) (xy 416.842702 -421.333676) (xy 416.815447 -421.333277) (xy 416.761491 -421.32552)
			(xy 416.709188 -421.310163) (xy 416.659604 -421.287518) (xy 416.613747 -421.258048) (xy 416.57255 -421.222351)
			(xy 416.536853 -421.181155) (xy 416.507383 -421.135298) (xy 416.484738 -421.085713) (xy 416.469381 -421.033411)
			(xy 416.461623 -420.979455) (xy 415.024113 -420.979455) (xy 415.016355 -421.033402) (xy 415.000999 -421.085699)
			(xy 414.978355 -421.135277) (xy 414.948886 -421.181128) (xy 414.913191 -421.222318) (xy 414.871998 -421.258009)
			(xy 414.826144 -421.287474) (xy 414.776563 -421.310112) (xy 414.724265 -421.325463) (xy 414.670314 -421.333215)
			(xy 414.643062 -421.333676) (xy 413.779462 -421.333676) (xy 413.75221 -421.333252) (xy 413.698262 -421.32549)
			(xy 413.645968 -421.31013) (xy 413.596391 -421.287485) (xy 413.550541 -421.258015) (xy 413.509352 -421.222321)
			(xy 413.473662 -421.181128) (xy 413.444197 -421.135276) (xy 413.421556 -421.085697) (xy 413.406202 -421.033401)
			(xy 413.398446 -420.979452) (xy 411.960789 -420.979452) (xy 411.953035 -421.033389) (xy 411.937682 -421.085678)
			(xy 411.915044 -421.135249) (xy 411.885583 -421.181095) (xy 411.849896 -421.222281) (xy 411.808712 -421.257969)
			(xy 411.762869 -421.287434) (xy 411.713298 -421.310074) (xy 411.661011 -421.32543) (xy 411.60707 -421.333188)
			(xy 411.579822 -421.333676) (xy 410.716222 -421.333676) (xy 410.688966 -421.333279) (xy 410.635008 -421.325523)
			(xy 410.582703 -421.310168) (xy 410.533116 -421.287525) (xy 410.487256 -421.258055) (xy 410.446057 -421.222358)
			(xy 410.410358 -421.181162) (xy 410.380886 -421.135303) (xy 410.35824 -421.085718) (xy 410.342881 -421.033414)
			(xy 410.335123 -420.979456) (xy 408.897612 -420.979456) (xy 408.889856 -421.033399) (xy 408.8745 -421.085694)
			(xy 408.851858 -421.135271) (xy 408.822391 -421.181122) (xy 408.786699 -421.222311) (xy 408.745507 -421.258002)
			(xy 408.699656 -421.287467) (xy 408.650077 -421.310107) (xy 408.597782 -421.32546) (xy 408.543833 -421.333214)
			(xy 408.516582 -421.333676) (xy 407.652982 -421.333676) (xy 407.625729 -421.333253) (xy 407.571779 -421.325494)
			(xy 407.519482 -421.310136) (xy 407.469903 -421.287492) (xy 407.424051 -421.258022) (xy 407.382859 -421.222328)
			(xy 407.347167 -421.181135) (xy 407.3177 -421.135281) (xy 407.295058 -421.085701) (xy 407.279703 -421.033403)
			(xy 407.271946 -420.979453) (xy 405.834289 -420.979453) (xy 405.826535 -421.033386) (xy 405.811183 -421.085673)
			(xy 405.788547 -421.135244) (xy 405.759087 -421.181088) (xy 405.723403 -421.222274) (xy 405.682222 -421.257962)
			(xy 405.636381 -421.287427) (xy 405.586813 -421.310069) (xy 405.534528 -421.325426) (xy 405.480589 -421.333187)
			(xy 405.453342 -421.333676) (xy 404.589742 -421.333676) (xy 404.562485 -421.33328) (xy 404.508525 -421.325527)
			(xy 404.456217 -421.310173) (xy 404.406628 -421.287531) (xy 404.360766 -421.258062) (xy 404.319564 -421.222365)
			(xy 404.283863 -421.181168) (xy 404.254389 -421.135309) (xy 404.231741 -421.085722) (xy 404.216382 -421.033416)
			(xy 404.208623 -420.979457) (xy 402.771089 -420.979457) (xy 402.763334 -421.033392) (xy 402.74798 -421.085682)
			(xy 402.725341 -421.135255) (xy 402.695878 -421.181101) (xy 402.660189 -421.222288) (xy 402.619003 -421.257976)
			(xy 402.573157 -421.28744) (xy 402.523584 -421.31008) (xy 402.471294 -421.325434) (xy 402.417351 -421.33319)
			(xy 402.390102 -421.333676) (xy 401.526502 -421.333676) (xy 401.499247 -421.333277) (xy 401.445291 -421.32552)
			(xy 401.392988 -421.310163) (xy 401.343404 -421.287518) (xy 401.297547 -421.258048) (xy 401.25635 -421.222351)
			(xy 401.220653 -421.181155) (xy 401.191183 -421.135298) (xy 401.168538 -421.085713) (xy 401.153181 -421.033411)
			(xy 401.145423 -420.979455) (xy 399.707913 -420.979455) (xy 399.700155 -421.033402) (xy 399.684799 -421.085699)
			(xy 399.662155 -421.135277) (xy 399.632686 -421.181128) (xy 399.596991 -421.222318) (xy 399.555798 -421.258009)
			(xy 399.509944 -421.287474) (xy 399.460363 -421.310112) (xy 399.408065 -421.325463) (xy 399.354114 -421.333215)
			(xy 399.326862 -421.333676) (xy 398.463262 -421.333676) (xy 398.43601 -421.333252) (xy 398.382062 -421.32549)
			(xy 398.329768 -421.31013) (xy 398.280191 -421.287485) (xy 398.234341 -421.258015) (xy 398.193152 -421.222321)
			(xy 398.157462 -421.181128) (xy 398.127997 -421.135276) (xy 398.105356 -421.085697) (xy 398.090002 -421.033401)
			(xy 398.082246 -420.979452) (xy 396.644589 -420.979452) (xy 396.636835 -421.033389) (xy 396.621482 -421.085678)
			(xy 396.598844 -421.135249) (xy 396.569383 -421.181095) (xy 396.533696 -421.222281) (xy 396.492512 -421.257969)
			(xy 396.446669 -421.287434) (xy 396.397098 -421.310074) (xy 396.344811 -421.32543) (xy 396.29087 -421.333188)
			(xy 396.263622 -421.333676) (xy 395.400022 -421.333676) (xy 395.372766 -421.333279) (xy 395.318808 -421.325523)
			(xy 395.266503 -421.310168) (xy 395.216916 -421.287525) (xy 395.171056 -421.258055) (xy 395.129857 -421.222358)
			(xy 395.094158 -421.181162) (xy 395.064686 -421.135303) (xy 395.04204 -421.085718) (xy 395.026681 -421.033414)
			(xy 395.018923 -420.979456) (xy 393.581412 -420.979456) (xy 393.573656 -421.033399) (xy 393.5583 -421.085694)
			(xy 393.535658 -421.135271) (xy 393.506191 -421.181122) (xy 393.470499 -421.222311) (xy 393.429307 -421.258002)
			(xy 393.383456 -421.287467) (xy 393.333877 -421.310107) (xy 393.281582 -421.32546) (xy 393.227633 -421.333214)
			(xy 393.200382 -421.333676) (xy 392.336782 -421.333676) (xy 392.309529 -421.333253) (xy 392.255579 -421.325494)
			(xy 392.203282 -421.310136) (xy 392.153703 -421.287492) (xy 392.107851 -421.258022) (xy 392.066659 -421.222328)
			(xy 392.030967 -421.181135) (xy 392.0015 -421.135281) (xy 391.978858 -421.085701) (xy 391.963503 -421.033403)
			(xy 391.955746 -420.979453) (xy 390.518089 -420.979453) (xy 390.510335 -421.033386) (xy 390.494983 -421.085673)
			(xy 390.472347 -421.135244) (xy 390.442887 -421.181088) (xy 390.407203 -421.222274) (xy 390.366022 -421.257962)
			(xy 390.320181 -421.287427) (xy 390.270613 -421.310069) (xy 390.218328 -421.325426) (xy 390.164389 -421.333187)
			(xy 390.137142 -421.333676) (xy 389.273542 -421.333676) (xy 389.246285 -421.33328) (xy 389.192325 -421.325527)
			(xy 389.140017 -421.310173) (xy 389.090428 -421.287531) (xy 389.044566 -421.258062) (xy 389.003364 -421.222365)
			(xy 388.967663 -421.181168) (xy 388.938189 -421.135309) (xy 388.915541 -421.085722) (xy 388.900182 -421.033416)
			(xy 388.892423 -420.979457) (xy 387.454889 -420.979457) (xy 387.447134 -421.033392) (xy 387.43178 -421.085682)
			(xy 387.409141 -421.135255) (xy 387.379678 -421.181101) (xy 387.343989 -421.222288) (xy 387.302803 -421.257976)
			(xy 387.256957 -421.28744) (xy 387.207384 -421.31008) (xy 387.155094 -421.325434) (xy 387.101151 -421.33319)
			(xy 387.073902 -421.333676) (xy 386.210302 -421.333676) (xy 386.183047 -421.333277) (xy 386.129091 -421.32552)
			(xy 386.076788 -421.310163) (xy 386.027204 -421.287518) (xy 385.981347 -421.258048) (xy 385.94015 -421.222351)
			(xy 385.904453 -421.181155) (xy 385.874983 -421.135298) (xy 385.852338 -421.085713) (xy 385.836981 -421.033411)
			(xy 385.829223 -420.979455) (xy 384.391713 -420.979455) (xy 384.383955 -421.033402) (xy 384.368599 -421.085699)
			(xy 384.345955 -421.135277) (xy 384.316486 -421.181128) (xy 384.280791 -421.222318) (xy 384.239598 -421.258009)
			(xy 384.193744 -421.287474) (xy 384.144163 -421.310112) (xy 384.091865 -421.325463) (xy 384.037914 -421.333215)
			(xy 384.010662 -421.333676) (xy 383.147062 -421.333676) (xy 383.11981 -421.333252) (xy 383.065862 -421.32549)
			(xy 383.013568 -421.31013) (xy 382.963991 -421.287485) (xy 382.918141 -421.258015) (xy 382.876952 -421.222321)
			(xy 382.841262 -421.181128) (xy 382.811797 -421.135276) (xy 382.789156 -421.085697) (xy 382.773802 -421.033401)
			(xy 382.766046 -420.979452) (xy 381.328389 -420.979452) (xy 381.320635 -421.033389) (xy 381.305282 -421.085678)
			(xy 381.282644 -421.135249) (xy 381.253183 -421.181095) (xy 381.217496 -421.222281) (xy 381.176312 -421.257969)
			(xy 381.130469 -421.287434) (xy 381.080898 -421.310074) (xy 381.028611 -421.32543) (xy 380.97467 -421.333188)
			(xy 380.947422 -421.333676) (xy 380.083822 -421.333676) (xy 380.056566 -421.333279) (xy 380.002608 -421.325523)
			(xy 379.950303 -421.310168) (xy 379.900716 -421.287525) (xy 379.854856 -421.258055) (xy 379.813657 -421.222358)
			(xy 379.777958 -421.181162) (xy 379.748486 -421.135303) (xy 379.72584 -421.085718) (xy 379.710481 -421.033414)
			(xy 379.702723 -420.979456) (xy 378.265212 -420.979456) (xy 378.257456 -421.033399) (xy 378.2421 -421.085694)
			(xy 378.219458 -421.135271) (xy 378.189991 -421.181122) (xy 378.154299 -421.222311) (xy 378.113107 -421.258002)
			(xy 378.067256 -421.287467) (xy 378.017677 -421.310107) (xy 377.965382 -421.32546) (xy 377.911433 -421.333214)
			(xy 377.884182 -421.333676) (xy 377.020582 -421.333676) (xy 376.993329 -421.333253) (xy 376.939379 -421.325494)
			(xy 376.887082 -421.310136) (xy 376.837503 -421.287492) (xy 376.791651 -421.258022) (xy 376.750459 -421.222328)
			(xy 376.714767 -421.181135) (xy 376.6853 -421.135281) (xy 376.662658 -421.085701) (xy 376.647303 -421.033403)
			(xy 376.639546 -420.979453) (xy 375.201889 -420.979453) (xy 375.194135 -421.033386) (xy 375.178783 -421.085673)
			(xy 375.156147 -421.135244) (xy 375.126687 -421.181088) (xy 375.091003 -421.222274) (xy 375.049822 -421.257962)
			(xy 375.003981 -421.287427) (xy 374.954413 -421.310069) (xy 374.902128 -421.325426) (xy 374.848189 -421.333187)
			(xy 374.820942 -421.333676) (xy 373.957342 -421.333676) (xy 373.930085 -421.33328) (xy 373.876125 -421.325527)
			(xy 373.823817 -421.310173) (xy 373.774228 -421.287531) (xy 373.728366 -421.258062) (xy 373.687164 -421.222365)
			(xy 373.651463 -421.181168) (xy 373.621989 -421.135309) (xy 373.599341 -421.085722) (xy 373.583982 -421.033416)
			(xy 373.576223 -420.979457) (xy 372.138689 -420.979457) (xy 372.130934 -421.033392) (xy 372.11558 -421.085682)
			(xy 372.092941 -421.135255) (xy 372.063478 -421.181101) (xy 372.027789 -421.222288) (xy 371.986603 -421.257976)
			(xy 371.940757 -421.28744) (xy 371.891184 -421.31008) (xy 371.838894 -421.325434) (xy 371.784951 -421.33319)
			(xy 371.757702 -421.333676) (xy 370.894102 -421.333676) (xy 370.866847 -421.333277) (xy 370.812891 -421.32552)
			(xy 370.760588 -421.310163) (xy 370.711004 -421.287518) (xy 370.665147 -421.258048) (xy 370.62395 -421.222351)
			(xy 370.588253 -421.181155) (xy 370.558783 -421.135298) (xy 370.536138 -421.085713) (xy 370.520781 -421.033411)
			(xy 370.513023 -420.979455) (xy 370.117116 -420.979455) (xy 370.117116 -421.132508) (xy 370.118557 -421.144201)
			(xy 370.130472 -421.164489) (xy 370.1502 -421.17731) (xy 370.16182 -421.179244) (xy 370.313204 -421.179244)
			(xy 370.313204 -422.692576) (xy 370.312768 -422.702798) (xy 370.30495 -422.721687) (xy 370.290497 -422.736144)
			(xy 370.27161 -422.743966) (xy 370.261388 -422.744392) (xy 365.362744 -422.744392) (xy 365.352522 -422.743952)
			(xy 365.333631 -422.736138) (xy 365.319173 -422.721686) (xy 365.311352 -422.702798) (xy 365.310928 -422.692576)
			(xy 360.222212 -422.692576) (xy 360.286426 -422.706639) (xy 360.410636 -422.74198) (xy 360.532435 -422.7849)
			(xy 360.65136 -422.835237) (xy 360.766961 -422.892799) (xy 360.8788 -422.957369) (xy 360.986451 -423.028701)
			(xy 361.089506 -423.106525) (xy 361.187576 -423.190546) (xy 361.280287 -423.280445) (xy 361.367287 -423.37588)
			(xy 361.448248 -423.47649) (xy 361.505055 -423.556738) (xy 456.285335 -423.556738) (xy 456.285335 -423.427598)
			(xy 456.293285 -423.298703) (xy 456.309155 -423.170543) (xy 456.332884 -423.043602) (xy 456.364383 -422.918363)
			(xy 456.403532 -422.7953) (xy 456.450183 -422.674881) (xy 456.504158 -422.557562) (xy 456.565253 -422.443788)
			(xy 456.633236 -422.333991) (xy 456.70785 -422.228588) (xy 456.788811 -422.127978) (xy 456.875811 -422.032543)
			(xy 456.968522 -421.942644) (xy 457.066592 -421.858623) (xy 457.169647 -421.780799) (xy 457.277298 -421.709467)
			(xy 457.389137 -421.644897) (xy 457.504738 -421.587335) (xy 457.623663 -421.536998) (xy 457.745462 -421.494078)
			(xy 457.869672 -421.458737) (xy 457.995821 -421.43111) (xy 458.123433 -421.411301) (xy 458.252022 -421.399385)
			(xy 458.3811 -421.395409) (xy 458.510178 -421.399385) (xy 458.638767 -421.411301) (xy 458.766379 -421.43111)
			(xy 458.892528 -421.458737) (xy 459.016738 -421.494078) (xy 459.138537 -421.536998) (xy 459.257462 -421.587335)
			(xy 459.373063 -421.644897) (xy 459.484902 -421.709467) (xy 459.592553 -421.780799) (xy 459.695608 -421.858623)
			(xy 459.793678 -421.942644) (xy 459.886389 -422.032543) (xy 459.973389 -422.127978) (xy 460.05435 -422.228588)
			(xy 460.128964 -422.333991) (xy 460.196947 -422.443788) (xy 460.258042 -422.557562) (xy 460.312017 -422.674881)
			(xy 460.358668 -422.7953) (xy 460.397817 -422.918363) (xy 460.429316 -423.043602) (xy 460.453045 -423.170543)
			(xy 460.468915 -423.298703) (xy 460.476865 -423.427598) (xy 460.477362 -423.492168) (xy 460.476865 -423.556738)
			(xy 460.468915 -423.685633) (xy 460.453045 -423.813793) (xy 460.429316 -423.940734) (xy 460.397817 -424.065973)
			(xy 460.358668 -424.189036) (xy 460.312017 -424.309455) (xy 460.258042 -424.426774) (xy 460.196947 -424.540548)
			(xy 460.128964 -424.650345) (xy 460.05435 -424.755748) (xy 459.973389 -424.856358) (xy 459.886389 -424.951793)
			(xy 459.793678 -425.041692) (xy 459.695608 -425.125713) (xy 459.592553 -425.203537) (xy 459.484902 -425.274869)
			(xy 459.373063 -425.339439) (xy 459.257462 -425.397001) (xy 459.138537 -425.447338) (xy 459.016738 -425.490258)
			(xy 458.892528 -425.525599) (xy 458.766379 -425.553226) (xy 458.638767 -425.573035) (xy 458.510178 -425.584951)
			(xy 458.3811 -425.588928) (xy 458.252022 -425.584951) (xy 458.123433 -425.573035) (xy 457.995821 -425.553226)
			(xy 457.869672 -425.525599) (xy 457.745462 -425.490258) (xy 457.623663 -425.447338) (xy 457.504738 -425.397001)
			(xy 457.389137 -425.339439) (xy 457.277298 -425.274869) (xy 457.169647 -425.203537) (xy 457.066592 -425.125713)
			(xy 456.968522 -425.041692) (xy 456.875811 -424.951793) (xy 456.788811 -424.856358) (xy 456.70785 -424.755748)
			(xy 456.633236 -424.650345) (xy 456.565253 -424.540548) (xy 456.504158 -424.426774) (xy 456.450183 -424.309455)
			(xy 456.403532 -424.189036) (xy 456.364383 -424.065973) (xy 456.332884 -423.940734) (xy 456.309155 -423.813793)
			(xy 456.293285 -423.685633) (xy 456.285335 -423.556738) (xy 361.505055 -423.556738) (xy 361.522862 -423.581893)
			(xy 361.590845 -423.69169) (xy 361.65194 -423.805464) (xy 361.705915 -423.922783) (xy 361.752566 -424.043202)
			(xy 361.791715 -424.166265) (xy 361.823214 -424.291504) (xy 361.846943 -424.418445) (xy 361.862813 -424.546605)
			(xy 361.870763 -424.6755) (xy 361.87126 -424.74007) (xy 361.870763 -424.80464) (xy 361.862813 -424.933535)
			(xy 361.846943 -425.061695) (xy 361.823214 -425.188636) (xy 361.791715 -425.313875) (xy 361.752566 -425.436938)
			(xy 361.705915 -425.557357) (xy 361.65194 -425.674676) (xy 361.590845 -425.78845) (xy 361.522862 -425.898247)
			(xy 361.448248 -426.00365) (xy 361.367287 -426.10426) (xy 361.280287 -426.199695) (xy 361.187576 -426.289594)
			(xy 361.089506 -426.373615) (xy 360.986451 -426.451439) (xy 360.8788 -426.522771) (xy 360.766961 -426.587341)
			(xy 360.65136 -426.644903) (xy 360.532435 -426.69524) (xy 360.410636 -426.73816) (xy 360.286426 -426.773501)
			(xy 360.160277 -426.801128) (xy 360.032665 -426.820937) (xy 359.904076 -426.832853) (xy 359.774998 -426.83683)
			(xy 359.64592 -426.832853) (xy 359.517331 -426.820937) (xy 359.389719 -426.801128) (xy 359.26357 -426.773501)
			(xy 359.13936 -426.73816) (xy 359.017561 -426.69524) (xy 358.898636 -426.644903) (xy 358.783035 -426.587341)
			(xy 358.671196 -426.522771) (xy 358.563545 -426.451439) (xy 358.46049 -426.373615) (xy 358.36242 -426.289594)
			(xy 358.269709 -426.199695) (xy 358.182709 -426.10426) (xy 358.101748 -426.00365) (xy 358.027134 -425.898247)
			(xy 357.959151 -425.78845) (xy 357.898056 -425.674676) (xy 357.844081 -425.557357) (xy 357.79743 -425.436938)
			(xy 357.758281 -425.313875) (xy 357.726782 -425.188636) (xy 357.703053 -425.061695) (xy 357.687183 -424.933535)
			(xy 357.679233 -424.80464) (xy 230.3145 -424.80464) (xy 230.3145 -427.960536) (xy 314.141104 -427.960536)
			(xy 314.141104 -425.419012) (xy 314.14157 -425.406962) (xy 314.149 -425.384036) (xy 314.163139 -425.36452)
			(xy 314.182609 -425.350316) (xy 314.20551 -425.342811) (xy 314.217558 -425.342304) (xy 315.157866 -425.342304)
			(xy 315.16995 -425.342836) (xy 315.192944 -425.350279) (xy 315.212521 -425.36445) (xy 315.226774 -425.383968)
			(xy 315.234313 -425.40693) (xy 315.234828 -425.419012) (xy 315.234828 -427.960536) (xy 315.234371 -427.972585)
			(xy 315.226932 -427.995507) (xy 315.21279 -428.01502) (xy 315.193321 -428.029223) (xy 315.170422 -428.036734)
			(xy 315.158374 -428.037244) (xy 314.218066 -428.037244) (xy 314.205973 -428.036821) (xy 314.182969 -428.029353)
			(xy 314.163388 -428.015156) (xy 314.149139 -427.995612) (xy 314.141611 -427.972628) (xy 314.141104 -427.960536)
			(xy 230.3145 -427.960536) (xy 230.3145 -433.130695) (xy 266.885917 -433.130695) (xy 266.885917 -432.953425)
			(xy 266.89387 -432.776334) (xy 266.909761 -432.599778) (xy 266.933556 -432.424113) (xy 266.965209 -432.249692)
			(xy 267.004655 -432.076867) (xy 267.051815 -431.905986) (xy 267.106594 -431.737392) (xy 267.168882 -431.571427)
			(xy 267.238554 -431.408422) (xy 267.315468 -431.248708) (xy 267.399471 -431.092605) (xy 267.490392 -430.940428)
			(xy 267.588049 -430.792484) (xy 267.692246 -430.64907) (xy 267.802772 -430.510475) (xy 267.919404 -430.376978)
			(xy 268.041909 -430.248849) (xy 268.170038 -430.126344) (xy 268.303535 -430.009712) (xy 268.44213 -429.899186)
			(xy 268.585544 -429.794989) (xy 268.733488 -429.697332) (xy 268.885665 -429.606411) (xy 269.041768 -429.522408)
			(xy 269.201482 -429.445494) (xy 269.364487 -429.375822) (xy 269.530452 -429.313534) (xy 269.699046 -429.258755)
			(xy 269.869927 -429.211595) (xy 270.042752 -429.172149) (xy 270.217173 -429.140496) (xy 270.392838 -429.116701)
			(xy 270.569394 -429.10081) (xy 270.746485 -429.092857) (xy 270.923755 -429.092857) (xy 271.100846 -429.10081)
			(xy 271.277402 -429.116701) (xy 271.453067 -429.140496) (xy 271.627488 -429.172149) (xy 271.800313 -429.211595)
			(xy 271.971194 -429.258755) (xy 272.139788 -429.313534) (xy 272.305753 -429.375822) (xy 272.468758 -429.445494)
			(xy 272.628472 -429.522408) (xy 272.784575 -429.606411) (xy 272.936752 -429.697332) (xy 273.084696 -429.794989)
			(xy 273.22811 -429.899186) (xy 273.366705 -430.009712) (xy 273.500202 -430.126344) (xy 273.628331 -430.248849)
			(xy 273.750836 -430.376978) (xy 273.867468 -430.510475) (xy 273.977994 -430.64907) (xy 274.082191 -430.792484)
			(xy 274.179848 -430.940428) (xy 274.270769 -431.092605) (xy 274.354772 -431.248708) (xy 274.431686 -431.408422)
			(xy 274.496678 -431.560478) (xy 314.141104 -431.560478) (xy 314.141104 -430.833276) (xy 314.141355 -430.824519)
			(xy 314.145335 -430.807461) (xy 314.148978 -430.799494) (xy 314.382404 -430.323244) (xy 314.387132 -430.312738)
			(xy 314.390613 -430.289973) (xy 314.387116 -430.26721) (xy 314.382404 -430.256696) (xy 314.148978 -429.780446)
			(xy 314.145329 -429.77248) (xy 314.141345 -429.755422) (xy 314.141104 -429.746664) (xy 314.141104 -429.018954)
			(xy 314.141567 -429.006866) (xy 314.149032 -428.98387) (xy 314.163221 -428.964293) (xy 314.182753 -428.950043)
			(xy 314.205725 -428.942506) (xy 314.217812 -428.941992) (xy 315.157612 -428.941992) (xy 315.169721 -428.942406)
			(xy 315.192747 -428.949908) (xy 315.207329 -428.960534) (xy 316.1411 -428.960534) (xy 316.1411 -426.41901)
			(xy 316.14162 -426.4069) (xy 316.1491 -426.383863) (xy 316.163331 -426.364265) (xy 316.18292 -426.350022)
			(xy 316.205952 -426.342527) (xy 316.218062 -426.342048) (xy 317.157862 -426.342048) (xy 317.169984 -426.342492)
			(xy 317.193043 -426.349975) (xy 317.21266 -426.36422) (xy 317.226912 -426.383832) (xy 317.234403 -426.406888)
			(xy 317.234824 -426.41901) (xy 317.234824 -427.960536) (xy 318.141096 -427.960536) (xy 318.141096 -425.419012)
			(xy 318.14157 -425.406963) (xy 318.148999 -425.384038) (xy 318.163136 -425.364523) (xy 318.182604 -425.350319)
			(xy 318.205503 -425.342812) (xy 318.21755 -425.342304) (xy 319.157858 -425.342304) (xy 319.169942 -425.342842)
			(xy 319.192935 -425.350283) (xy 319.212513 -425.364453) (xy 319.226766 -425.383969) (xy 319.234305 -425.40693)
			(xy 319.23482 -425.419012) (xy 319.23482 -427.960536) (xy 319.234371 -427.972586) (xy 319.226931 -427.99551)
			(xy 319.212787 -428.015023) (xy 319.193316 -428.029226) (xy 319.170415 -428.036735) (xy 319.158366 -428.037244)
			(xy 318.218058 -428.037244) (xy 318.205965 -428.036828) (xy 318.18296 -428.029358) (xy 318.163379 -428.015159)
			(xy 318.149131 -427.995614) (xy 318.141603 -427.972628) (xy 318.141096 -427.960536) (xy 317.234824 -427.960536)
			(xy 317.234824 -428.960534) (xy 317.234469 -428.972662) (xy 317.226962 -428.995729) (xy 317.212695 -429.015347)
			(xy 317.193064 -429.029595) (xy 317.169991 -429.03708) (xy 317.157862 -429.037496) (xy 316.218062 -429.037496)
			(xy 316.205949 -429.037021) (xy 316.18291 -429.029528) (xy 316.163312 -429.015285) (xy 316.14907 -428.995686)
			(xy 316.141578 -428.972647) (xy 316.1411 -428.960534) (xy 315.207329 -428.960534) (xy 315.212319 -428.96417)
			(xy 315.226514 -428.983792) (xy 315.233936 -429.006844) (xy 315.23432 -429.018954) (xy 315.23432 -431.560478)
			(xy 315.233873 -431.57257) (xy 315.226418 -431.595577) (xy 315.212227 -431.615161) (xy 315.192687 -431.629411)
			(xy 315.169703 -431.636936) (xy 315.157612 -431.63744) (xy 314.217812 -431.63744) (xy 314.205708 -431.636974)
			(xy 314.182688 -431.629483) (xy 314.163118 -431.615232) (xy 314.148922 -431.595624) (xy 314.141493 -431.572583)
			(xy 314.141104 -431.560478) (xy 274.496678 -431.560478) (xy 274.501358 -431.571427) (xy 274.563646 -431.737392)
			(xy 274.618425 -431.905986) (xy 274.665585 -432.076867) (xy 274.705031 -432.249692) (xy 274.736684 -432.424113)
			(xy 274.760479 -432.599778) (xy 274.77637 -432.776334) (xy 274.784323 -432.953425) (xy 274.78482 -433.04206)
			(xy 274.784323 -433.130695) (xy 274.77637 -433.307786) (xy 274.760479 -433.484342) (xy 274.736684 -433.660007)
			(xy 274.705031 -433.834428) (xy 274.665585 -434.007253) (xy 274.618425 -434.178134) (xy 274.563646 -434.346728)
			(xy 274.501358 -434.512693) (xy 274.431686 -434.675698) (xy 274.354772 -434.835412) (xy 274.270769 -434.991515)
			(xy 274.179848 -435.143692) (xy 274.168638 -435.160674) (xy 314.140596 -435.160674) (xy 314.140596 -432.61915)
			(xy 314.141068 -432.607037) (xy 314.148564 -432.583999) (xy 314.162808 -432.564402) (xy 314.182406 -432.550161)
			(xy 314.205445 -432.542667) (xy 314.217558 -432.542188) (xy 315.157358 -432.542188) (xy 315.169465 -432.542747)
			(xy 315.192499 -432.550216) (xy 315.206637 -432.560476) (xy 316.1411 -432.560476) (xy 316.1411 -431.833274)
			(xy 316.141351 -431.824517) (xy 316.145331 -431.807459) (xy 316.148974 -431.799492) (xy 316.3824 -431.323242)
			(xy 316.38713 -431.312736) (xy 316.39061 -431.289971) (xy 316.387112 -431.267208) (xy 316.3824 -431.256694)
			(xy 316.148974 -430.780444) (xy 316.145324 -430.772478) (xy 316.141341 -430.75542) (xy 316.1411 -430.746662)
			(xy 316.1411 -430.018952) (xy 316.141523 -430.006874) (xy 316.149 -429.983904) (xy 316.163207 -429.964367)
			(xy 316.182754 -429.950174) (xy 316.20573 -429.942714) (xy 316.217808 -429.942244) (xy 317.157608 -429.942244)
			(xy 317.169678 -429.942757) (xy 317.192637 -429.950216) (xy 317.21217 -429.964401) (xy 317.226366 -429.983927)
			(xy 317.233837 -430.006882) (xy 317.234316 -430.018952) (xy 317.234316 -431.560478) (xy 318.141096 -431.560478)
			(xy 318.141096 -430.833276) (xy 318.141348 -430.824519) (xy 318.145327 -430.807461) (xy 318.14897 -430.799494)
			(xy 318.382396 -430.323244) (xy 318.387125 -430.312738) (xy 318.390605 -430.289973) (xy 318.387108 -430.26721)
			(xy 318.382396 -430.256696) (xy 318.14897 -429.780446) (xy 318.14532 -429.77248) (xy 318.141337 -429.755422)
			(xy 318.141096 -429.746664) (xy 318.141096 -429.018954) (xy 318.141567 -429.006866) (xy 318.149031 -428.983872)
			(xy 318.163218 -428.964296) (xy 318.182748 -428.950046) (xy 318.205718 -428.942507) (xy 318.217804 -428.941992)
			(xy 319.157604 -428.941992) (xy 319.169712 -428.942413) (xy 319.192738 -428.949912) (xy 319.207317 -428.960534)
			(xy 320.141092 -428.960534) (xy 320.141092 -426.41901) (xy 320.14162 -426.406901) (xy 320.149099 -426.383865)
			(xy 320.163328 -426.364268) (xy 320.182915 -426.350024) (xy 320.205945 -426.342528) (xy 320.218054 -426.342048)
			(xy 321.157854 -426.342048) (xy 321.169975 -426.342499) (xy 321.193034 -426.34998) (xy 321.212651 -426.364223)
			(xy 321.226904 -426.383833) (xy 321.234395 -426.406889) (xy 321.234816 -426.41901) (xy 321.234816 -427.960536)
			(xy 322.141088 -427.960536) (xy 322.141088 -425.419012) (xy 322.14157 -425.406964) (xy 322.148998 -425.38404)
			(xy 322.163133 -425.364526) (xy 322.182598 -425.350321) (xy 322.205495 -425.342813) (xy 322.217542 -425.342304)
			(xy 323.15785 -425.342304) (xy 323.169933 -425.342849) (xy 323.192926 -425.350288) (xy 323.212504 -425.364455)
			(xy 323.226758 -425.383971) (xy 323.234297 -425.406931) (xy 323.234812 -425.419012) (xy 323.234812 -427.960536)
			(xy 323.234371 -427.972587) (xy 323.22693 -427.995512) (xy 323.212784 -428.015026) (xy 323.193311 -428.029228)
			(xy 323.170407 -428.036736) (xy 323.158358 -428.037244) (xy 322.21805 -428.037244) (xy 322.205961 -428.03675)
			(xy 322.18296 -428.029305) (xy 322.163378 -428.015126) (xy 322.149126 -427.995597) (xy 322.141595 -427.972623)
			(xy 322.141088 -427.960536) (xy 321.234816 -427.960536) (xy 321.234816 -428.960534) (xy 321.234468 -428.972663)
			(xy 321.226961 -428.995731) (xy 321.212692 -429.015349) (xy 321.193059 -429.029598) (xy 321.169984 -429.037081)
			(xy 321.157854 -429.037496) (xy 320.218054 -429.037496) (xy 320.20594 -429.037028) (xy 320.182901 -429.029532)
			(xy 320.163303 -429.015288) (xy 320.149062 -428.995688) (xy 320.14157 -428.972648) (xy 320.141092 -428.960534)
			(xy 319.207317 -428.960534) (xy 319.212311 -428.964173) (xy 319.226506 -428.983793) (xy 319.233928 -429.006844)
			(xy 319.234312 -429.018954) (xy 319.234312 -431.560478) (xy 319.233873 -431.572571) (xy 319.226416 -431.595579)
			(xy 319.212224 -431.615164) (xy 319.192682 -431.629413) (xy 319.169696 -431.636937) (xy 319.157604 -431.63744)
			(xy 318.217804 -431.63744) (xy 318.205699 -431.636981) (xy 318.182679 -431.629488) (xy 318.163109 -431.615236)
			(xy 318.148913 -431.595625) (xy 318.141485 -431.572584) (xy 318.141096 -431.560478) (xy 317.234316 -431.560478)
			(xy 317.234316 -432.560476) (xy 317.233867 -432.572557) (xy 317.226407 -432.595537) (xy 317.21221 -432.615087)
			(xy 317.192666 -432.629292) (xy 317.169688 -432.636762) (xy 317.157608 -432.637184) (xy 316.217808 -432.637184)
			(xy 316.205723 -432.63678) (xy 316.182737 -432.629312) (xy 316.163184 -432.615105) (xy 316.148981 -432.595549)
			(xy 316.141517 -432.572561) (xy 316.1411 -432.560476) (xy 315.206637 -432.560476) (xy 315.212097 -432.564438)
			(xy 315.226342 -432.584019) (xy 315.233839 -432.607043) (xy 315.23432 -432.61915) (xy 315.23432 -435.160674)
			(xy 315.233917 -435.1728) (xy 315.226427 -435.195865) (xy 315.212172 -435.215484) (xy 315.19255 -435.229734)
			(xy 315.169484 -435.23722) (xy 315.157358 -435.237636) (xy 314.217558 -435.237636) (xy 314.205439 -435.237224)
			(xy 314.18239 -435.229722) (xy 314.162786 -435.215465) (xy 314.148547 -435.195849) (xy 314.141066 -435.172794)
			(xy 314.140596 -435.160674) (xy 274.168638 -435.160674) (xy 274.082191 -435.291636) (xy 273.977994 -435.43505)
			(xy 273.867468 -435.573645) (xy 273.750836 -435.707142) (xy 273.628331 -435.835271) (xy 273.500202 -435.957776)
			(xy 273.366705 -436.074408) (xy 273.22811 -436.184934) (xy 273.084696 -436.289131) (xy 272.936752 -436.386788)
			(xy 272.784575 -436.477709) (xy 272.628472 -436.561712) (xy 272.468758 -436.638626) (xy 272.305753 -436.708298)
			(xy 272.139788 -436.770586) (xy 271.971194 -436.825365) (xy 271.800313 -436.872525) (xy 271.627488 -436.911971)
			(xy 271.453067 -436.943624) (xy 271.277402 -436.967419) (xy 271.100846 -436.98331) (xy 270.923755 -436.991263)
			(xy 270.746485 -436.991263) (xy 270.569394 -436.98331) (xy 270.392838 -436.967419) (xy 270.217173 -436.943624)
			(xy 270.042752 -436.911971) (xy 269.869927 -436.872525) (xy 269.699046 -436.825365) (xy 269.530452 -436.770586)
			(xy 269.364487 -436.708298) (xy 269.201482 -436.638626) (xy 269.041768 -436.561712) (xy 268.885665 -436.477709)
			(xy 268.733488 -436.386788) (xy 268.585544 -436.289131) (xy 268.44213 -436.184934) (xy 268.303535 -436.074408)
			(xy 268.170038 -435.957776) (xy 268.041909 -435.835271) (xy 267.919404 -435.707142) (xy 267.802772 -435.573645)
			(xy 267.692246 -435.43505) (xy 267.588049 -435.291636) (xy 267.490392 -435.143692) (xy 267.399471 -434.991515)
			(xy 267.315468 -434.835412) (xy 267.238554 -434.675698) (xy 267.168882 -434.512693) (xy 267.106594 -434.346728)
			(xy 267.051815 -434.178134) (xy 267.004655 -434.007253) (xy 266.965209 -433.834428) (xy 266.933556 -433.660007)
			(xy 266.909761 -433.484342) (xy 266.89387 -433.307786) (xy 266.885917 -433.130695) (xy 230.3145 -433.130695)
			(xy 230.3145 -435.873652) (xy 230.314033 -435.898602) (xy 230.306213 -435.947887) (xy 230.29079 -435.995345)
			(xy 230.268141 -436.03981) (xy 230.238824 -436.080191) (xy 230.221536 -436.098188) (xy 229.299008 -437.020716)
			(xy 229.281016 -437.03801) (xy 229.240639 -437.067332) (xy 229.196172 -437.089979) (xy 229.148711 -437.105393)
			(xy 229.099423 -437.113193) (xy 229.074472 -437.11368) (xy 207.302608 -437.11368) (xy 207.27766 -437.113152)
			(xy 207.22838 -437.105344) (xy 207.180923 -437.089933) (xy 207.136457 -437.067299) (xy 207.096072 -437.037997)
			(xy 207.078072 -437.020716) (xy 205.512924 -435.455568) (xy 205.495618 -435.437587) (xy 205.466295 -435.397208)
			(xy 205.44365 -435.352738) (xy 205.42824 -435.305274) (xy 205.420444 -435.255984) (xy 205.41996 -435.231032)
			(xy 205.41996 -431.16881) (xy 205.41954 -431.15874) (xy 205.411817 -431.140141) (xy 205.404974 -431.132742)
			(xy 196.207888 -421.935656) (xy 196.19057 -421.917686) (xy 196.16125 -421.877303) (xy 196.138608 -421.832831)
			(xy 196.1232 -421.785364) (xy 196.115407 -421.736072) (xy 196.114924 -421.71112) (xy 196.114924 -413.329374)
			(xy 196.114532 -413.319301) (xy 196.10679 -413.300702) (xy 196.099938 -413.293306) (xy 195.154296 -412.347664)
			(xy 195.146896 -412.340825) (xy 195.128296 -412.333106) (xy 195.118228 -412.332678) (xy 188.720222 -412.332678)
			(xy 188.695275 -412.332142) (xy 188.645994 -412.324336) (xy 188.598538 -412.308927) (xy 188.554072 -412.286295)
			(xy 188.513686 -412.256994) (xy 188.495686 -412.239714) (xy 187.848748 -411.592776) (xy 187.841328 -411.585961)
			(xy 187.822744 -411.578227) (xy 187.81268 -411.57779) (xy 184.8104 -411.57779) (xy 184.785451 -411.577293)
			(xy 184.736167 -411.569481) (xy 184.68871 -411.554065) (xy 184.644244 -411.531423) (xy 184.603862 -411.502111)
			(xy 184.585864 -411.484826) (xy 184.033922 -410.932884) (xy 184.016624 -410.914896) (xy 183.9873 -410.874519)
			(xy 183.964653 -410.830051) (xy 183.949241 -410.782588) (xy 183.941443 -410.733299) (xy 183.940958 -410.708348)
			(xy 7.00913 -410.708348) (xy 7.00913 -413.4485) (xy 38.974268 -413.4485) (xy 38.974268 -412.5849)
			(xy 38.974754 -412.557631) (xy 38.982516 -412.503647) (xy 38.997881 -412.451317) (xy 39.020538 -412.401707)
			(xy 39.050024 -412.355826) (xy 39.085739 -412.314609) (xy 39.126956 -412.278894) (xy 39.172837 -412.249408)
			(xy 39.222447 -412.226751) (xy 39.274777 -412.211386) (xy 39.328761 -412.203624) (xy 39.383299 -412.203624)
			(xy 39.437283 -412.211386) (xy 39.489613 -412.226751) (xy 39.539223 -412.249408) (xy 39.585104 -412.278894)
			(xy 39.626321 -412.314609) (xy 39.662036 -412.355826) (xy 39.691522 -412.401707) (xy 39.714179 -412.451317)
			(xy 39.729544 -412.503647) (xy 39.737306 -412.557631) (xy 39.737792 -412.5849) (xy 39.737792 -412.597452)
			(xy 47.413146 -412.597452) (xy 47.413146 -412.542948) (xy 47.420902 -412.488999) (xy 47.436257 -412.436703)
			(xy 47.458897 -412.387124) (xy 47.488362 -412.341271) (xy 47.524053 -412.300079) (xy 47.565242 -412.264384)
			(xy 47.611092 -412.234914) (xy 47.660669 -412.212269) (xy 47.712964 -412.19691) (xy 47.766912 -412.189148)
			(xy 47.794164 -412.18866) (xy 48.657764 -412.18866) (xy 48.685016 -412.189185) (xy 48.738967 -412.196937)
			(xy 48.791264 -412.212289) (xy 48.840845 -412.234927) (xy 48.886699 -412.264392) (xy 48.927892 -412.300082)
			(xy 48.963587 -412.341273) (xy 48.993056 -412.387124) (xy 49.015699 -412.436702) (xy 49.031055 -412.488998)
			(xy 49.038813 -412.542948) (xy 49.038813 -412.597452) (xy 49.038813 -412.597455) (xy 50.476323 -412.597455)
			(xy 50.476323 -412.542945) (xy 50.484081 -412.488989) (xy 50.499438 -412.436686) (xy 50.522083 -412.387102)
			(xy 50.551554 -412.341244) (xy 50.587251 -412.300048) (xy 50.628448 -412.264351) (xy 50.674305 -412.234881)
			(xy 50.72389 -412.212237) (xy 50.776193 -412.19688) (xy 50.830149 -412.189123) (xy 50.857404 -412.18866)
			(xy 51.721004 -412.18866) (xy 51.748253 -412.18921) (xy 51.802195 -412.196967) (xy 51.854485 -412.212321)
			(xy 51.904058 -412.23496) (xy 51.949904 -412.264424) (xy 51.99109 -412.300113) (xy 52.026778 -412.341299)
			(xy 52.056242 -412.387146) (xy 52.07888 -412.436718) (xy 52.094234 -412.489008) (xy 52.10199 -412.542951)
			(xy 52.10199 -412.597449) (xy 52.101989 -412.597457) (xy 53.539523 -412.597457) (xy 53.539523 -412.542943)
			(xy 53.547282 -412.488983) (xy 53.562641 -412.436678) (xy 53.585289 -412.38709) (xy 53.614764 -412.341231)
			(xy 53.650465 -412.300034) (xy 53.691667 -412.264337) (xy 53.737529 -412.234868) (xy 53.787119 -412.212226)
			(xy 53.839427 -412.196872) (xy 53.893387 -412.18912) (xy 53.920644 -412.18866) (xy 54.784244 -412.18866)
			(xy 54.811491 -412.189213) (xy 54.865429 -412.196974) (xy 54.917714 -412.212332) (xy 54.967282 -412.234973)
			(xy 55.013123 -412.264438) (xy 55.054304 -412.300127) (xy 55.089988 -412.341313) (xy 55.119448 -412.387157)
			(xy 55.142084 -412.436727) (xy 55.157435 -412.489014) (xy 55.16519 -412.542953) (xy 55.16519 -412.597447)
			(xy 55.165189 -412.597453) (xy 56.602846 -412.597453) (xy 56.602846 -412.542947) (xy 56.610603 -412.488996)
			(xy 56.625958 -412.436698) (xy 56.6486 -412.387118) (xy 56.678067 -412.341265) (xy 56.71376 -412.300071)
			(xy 56.754952 -412.264377) (xy 56.800804 -412.234908) (xy 56.850383 -412.212264) (xy 56.902681 -412.196906)
			(xy 56.956631 -412.189147) (xy 56.983884 -412.18866) (xy 57.847484 -412.18866) (xy 57.874735 -412.189186)
			(xy 57.928683 -412.196941) (xy 57.980979 -412.212294) (xy 58.030557 -412.234934) (xy 58.076408 -412.264399)
			(xy 58.117599 -412.300089) (xy 58.153292 -412.341279) (xy 58.182759 -412.387129) (xy 58.2054 -412.436706)
			(xy 58.220756 -412.489001) (xy 58.228513 -412.542949) (xy 58.228513 -412.597451) (xy 58.228512 -412.597456)
			(xy 59.666023 -412.597456) (xy 59.666023 -412.542944) (xy 59.673781 -412.488986) (xy 59.68914 -412.436682)
			(xy 59.711786 -412.387096) (xy 59.741259 -412.341238) (xy 59.776958 -412.300041) (xy 59.818157 -412.264344)
			(xy 59.864017 -412.234874) (xy 59.913604 -412.212231) (xy 59.96591 -412.196876) (xy 60.019868 -412.189121)
			(xy 60.047124 -412.18866) (xy 60.910724 -412.18866) (xy 60.937972 -412.189212) (xy 60.991912 -412.19697)
			(xy 61.0442 -412.212326) (xy 61.09377 -412.234967) (xy 61.139613 -412.264431) (xy 61.180797 -412.30012)
			(xy 61.216483 -412.341306) (xy 61.245945 -412.387151) (xy 61.268582 -412.436723) (xy 61.283935 -412.489011)
			(xy 61.29169 -412.542952) (xy 61.29169 -412.597448) (xy 61.291689 -412.597452) (xy 62.729346 -412.597452)
			(xy 62.729346 -412.542948) (xy 62.737102 -412.488999) (xy 62.752457 -412.436703) (xy 62.775097 -412.387124)
			(xy 62.804562 -412.341271) (xy 62.840253 -412.300079) (xy 62.881442 -412.264384) (xy 62.927292 -412.234914)
			(xy 62.976869 -412.212269) (xy 63.029164 -412.19691) (xy 63.083112 -412.189148) (xy 63.110364 -412.18866)
			(xy 63.973964 -412.18866) (xy 64.001216 -412.189185) (xy 64.055167 -412.196937) (xy 64.107464 -412.212289)
			(xy 64.157045 -412.234927) (xy 64.202899 -412.264392) (xy 64.244092 -412.300082) (xy 64.279787 -412.341273)
			(xy 64.309256 -412.387124) (xy 64.331899 -412.436702) (xy 64.347255 -412.488998) (xy 64.355013 -412.542948)
			(xy 64.355013 -412.597452) (xy 64.355013 -412.597455) (xy 65.792523 -412.597455) (xy 65.792523 -412.542945)
			(xy 65.800281 -412.488989) (xy 65.815638 -412.436686) (xy 65.838283 -412.387102) (xy 65.867754 -412.341244)
			(xy 65.903451 -412.300048) (xy 65.944648 -412.264351) (xy 65.990505 -412.234881) (xy 66.04009 -412.212237)
			(xy 66.092393 -412.19688) (xy 66.146349 -412.189123) (xy 66.173604 -412.18866) (xy 67.037204 -412.18866)
			(xy 67.064453 -412.18921) (xy 67.118395 -412.196967) (xy 67.170685 -412.212321) (xy 67.220258 -412.23496)
			(xy 67.266104 -412.264424) (xy 67.30729 -412.300113) (xy 67.342978 -412.341299) (xy 67.372442 -412.387146)
			(xy 67.39508 -412.436718) (xy 67.410434 -412.489008) (xy 67.41819 -412.542951) (xy 67.41819 -412.597449)
			(xy 67.418189 -412.597457) (xy 68.855723 -412.597457) (xy 68.855723 -412.542943) (xy 68.863482 -412.488983)
			(xy 68.878841 -412.436678) (xy 68.901489 -412.38709) (xy 68.930964 -412.341231) (xy 68.966665 -412.300034)
			(xy 69.007867 -412.264337) (xy 69.053729 -412.234868) (xy 69.103319 -412.212226) (xy 69.155627 -412.196872)
			(xy 69.209587 -412.18912) (xy 69.236844 -412.18866) (xy 70.100444 -412.18866) (xy 70.127691 -412.189213)
			(xy 70.181629 -412.196974) (xy 70.233914 -412.212332) (xy 70.283482 -412.234973) (xy 70.329323 -412.264438)
			(xy 70.370504 -412.300127) (xy 70.406188 -412.341313) (xy 70.435648 -412.387157) (xy 70.458284 -412.436727)
			(xy 70.473635 -412.489014) (xy 70.48139 -412.542953) (xy 70.48139 -412.597447) (xy 70.481389 -412.597453)
			(xy 71.919046 -412.597453) (xy 71.919046 -412.542947) (xy 71.926803 -412.488996) (xy 71.942158 -412.436698)
			(xy 71.9648 -412.387118) (xy 71.994267 -412.341265) (xy 72.02996 -412.300071) (xy 72.071152 -412.264377)
			(xy 72.117004 -412.234908) (xy 72.166583 -412.212264) (xy 72.218881 -412.196906) (xy 72.272831 -412.189147)
			(xy 72.300084 -412.18866) (xy 73.163684 -412.18866) (xy 73.190935 -412.189186) (xy 73.244883 -412.196941)
			(xy 73.297179 -412.212294) (xy 73.346757 -412.234934) (xy 73.392608 -412.264399) (xy 73.433799 -412.300089)
			(xy 73.469492 -412.341279) (xy 73.498959 -412.387129) (xy 73.5216 -412.436706) (xy 73.536956 -412.489001)
			(xy 73.544713 -412.542949) (xy 73.544713 -412.597451) (xy 73.544712 -412.597456) (xy 74.982223 -412.597456)
			(xy 74.982223 -412.542944) (xy 74.989981 -412.488986) (xy 75.00534 -412.436682) (xy 75.027986 -412.387096)
			(xy 75.057459 -412.341238) (xy 75.093158 -412.300041) (xy 75.134357 -412.264344) (xy 75.180217 -412.234874)
			(xy 75.229804 -412.212231) (xy 75.28211 -412.196876) (xy 75.336068 -412.189121) (xy 75.363324 -412.18866)
			(xy 76.226924 -412.18866) (xy 76.254172 -412.189212) (xy 76.308112 -412.19697) (xy 76.3604 -412.212326)
			(xy 76.40997 -412.234967) (xy 76.455813 -412.264431) (xy 76.496997 -412.30012) (xy 76.532683 -412.341306)
			(xy 76.562145 -412.387151) (xy 76.584782 -412.436723) (xy 76.600135 -412.489011) (xy 76.60789 -412.542952)
			(xy 76.60789 -412.597448) (xy 76.607889 -412.597452) (xy 78.045546 -412.597452) (xy 78.045546 -412.542948)
			(xy 78.053302 -412.488999) (xy 78.068657 -412.436703) (xy 78.091297 -412.387124) (xy 78.120762 -412.341271)
			(xy 78.156453 -412.300079) (xy 78.197642 -412.264384) (xy 78.243492 -412.234914) (xy 78.293069 -412.212269)
			(xy 78.345364 -412.19691) (xy 78.399312 -412.189148) (xy 78.426564 -412.18866) (xy 79.290164 -412.18866)
			(xy 79.317416 -412.189185) (xy 79.371367 -412.196937) (xy 79.423664 -412.212289) (xy 79.473245 -412.234927)
			(xy 79.519099 -412.264392) (xy 79.560292 -412.300082) (xy 79.595987 -412.341273) (xy 79.625456 -412.387124)
			(xy 79.648099 -412.436702) (xy 79.663455 -412.488998) (xy 79.671213 -412.542948) (xy 79.671213 -412.597452)
			(xy 79.671213 -412.597455) (xy 81.108723 -412.597455) (xy 81.108723 -412.542945) (xy 81.116481 -412.488989)
			(xy 81.131838 -412.436686) (xy 81.154483 -412.387102) (xy 81.183954 -412.341244) (xy 81.219651 -412.300048)
			(xy 81.260848 -412.264351) (xy 81.306705 -412.234881) (xy 81.35629 -412.212237) (xy 81.408593 -412.19688)
			(xy 81.462549 -412.189123) (xy 81.489804 -412.18866) (xy 82.353404 -412.18866) (xy 82.380653 -412.18921)
			(xy 82.434595 -412.196967) (xy 82.486885 -412.212321) (xy 82.536458 -412.23496) (xy 82.582304 -412.264424)
			(xy 82.62349 -412.300113) (xy 82.659178 -412.341299) (xy 82.688642 -412.387146) (xy 82.71128 -412.436718)
			(xy 82.726634 -412.489008) (xy 82.73439 -412.542951) (xy 82.73439 -412.597449) (xy 82.734389 -412.597457)
			(xy 84.171923 -412.597457) (xy 84.171923 -412.542943) (xy 84.179682 -412.488983) (xy 84.195041 -412.436678)
			(xy 84.217689 -412.38709) (xy 84.247164 -412.341231) (xy 84.282865 -412.300034) (xy 84.324067 -412.264337)
			(xy 84.369929 -412.234868) (xy 84.419519 -412.212226) (xy 84.471827 -412.196872) (xy 84.525787 -412.18912)
			(xy 84.553044 -412.18866) (xy 85.416644 -412.18866) (xy 85.443891 -412.189213) (xy 85.497829 -412.196974)
			(xy 85.550114 -412.212332) (xy 85.599682 -412.234973) (xy 85.645523 -412.264438) (xy 85.686704 -412.300127)
			(xy 85.722388 -412.341313) (xy 85.751848 -412.387157) (xy 85.774484 -412.436727) (xy 85.789835 -412.489014)
			(xy 85.79759 -412.542953) (xy 85.79759 -412.597447) (xy 85.797589 -412.597453) (xy 87.235246 -412.597453)
			(xy 87.235246 -412.542947) (xy 87.243003 -412.488996) (xy 87.258358 -412.436698) (xy 87.281 -412.387118)
			(xy 87.310467 -412.341265) (xy 87.34616 -412.300071) (xy 87.387352 -412.264377) (xy 87.433204 -412.234908)
			(xy 87.482783 -412.212264) (xy 87.535081 -412.196906) (xy 87.589031 -412.189147) (xy 87.616284 -412.18866)
			(xy 88.479884 -412.18866) (xy 88.507135 -412.189186) (xy 88.561083 -412.196941) (xy 88.613379 -412.212294)
			(xy 88.662957 -412.234934) (xy 88.708808 -412.264399) (xy 88.749999 -412.300089) (xy 88.785692 -412.341279)
			(xy 88.815159 -412.387129) (xy 88.8378 -412.436706) (xy 88.853156 -412.489001) (xy 88.860913 -412.542949)
			(xy 88.860913 -412.597451) (xy 88.860912 -412.597456) (xy 90.298423 -412.597456) (xy 90.298423 -412.542944)
			(xy 90.306181 -412.488986) (xy 90.32154 -412.436682) (xy 90.344186 -412.387096) (xy 90.373659 -412.341238)
			(xy 90.409358 -412.300041) (xy 90.450557 -412.264344) (xy 90.496417 -412.234874) (xy 90.546004 -412.212231)
			(xy 90.59831 -412.196876) (xy 90.652268 -412.189121) (xy 90.679524 -412.18866) (xy 91.543124 -412.18866)
			(xy 91.570372 -412.189212) (xy 91.624312 -412.19697) (xy 91.6766 -412.212326) (xy 91.72617 -412.234967)
			(xy 91.772013 -412.264431) (xy 91.813197 -412.30012) (xy 91.848883 -412.341306) (xy 91.878345 -412.387151)
			(xy 91.900982 -412.436723) (xy 91.916335 -412.489011) (xy 91.92409 -412.542952) (xy 91.92409 -412.597448)
			(xy 91.924089 -412.597452) (xy 93.361746 -412.597452) (xy 93.361746 -412.542948) (xy 93.369502 -412.488999)
			(xy 93.384857 -412.436703) (xy 93.407497 -412.387124) (xy 93.436962 -412.341271) (xy 93.472653 -412.300079)
			(xy 93.513842 -412.264384) (xy 93.559692 -412.234914) (xy 93.609269 -412.212269) (xy 93.661564 -412.19691)
			(xy 93.715512 -412.189148) (xy 93.742764 -412.18866) (xy 94.606364 -412.18866) (xy 94.633616 -412.189185)
			(xy 94.687567 -412.196937) (xy 94.739864 -412.212289) (xy 94.789445 -412.234927) (xy 94.835299 -412.264392)
			(xy 94.876492 -412.300082) (xy 94.912187 -412.341273) (xy 94.941656 -412.387124) (xy 94.964299 -412.436702)
			(xy 94.979655 -412.488998) (xy 94.987413 -412.542948) (xy 94.987413 -412.597452) (xy 94.987413 -412.597455)
			(xy 114.513023 -412.597455) (xy 114.513023 -412.542945) (xy 114.520781 -412.488989) (xy 114.536138 -412.436686)
			(xy 114.558783 -412.387101) (xy 114.588254 -412.341244) (xy 114.623952 -412.300047) (xy 114.665149 -412.264351)
			(xy 114.711006 -412.23488) (xy 114.760591 -412.212236) (xy 114.812894 -412.196879) (xy 114.866851 -412.189123)
			(xy 114.894106 -412.18866) (xy 115.757706 -412.18866) (xy 115.784955 -412.189211) (xy 115.838897 -412.196967)
			(xy 115.891187 -412.212321) (xy 115.940759 -412.234961) (xy 115.986605 -412.264425) (xy 116.027791 -412.300113)
			(xy 116.063479 -412.3413) (xy 116.092942 -412.387146) (xy 116.115581 -412.436719) (xy 116.130934 -412.489009)
			(xy 116.13869 -412.542951) (xy 116.13869 -412.597449) (xy 116.138689 -412.597457) (xy 117.576223 -412.597457)
			(xy 117.576223 -412.542943) (xy 117.583982 -412.488983) (xy 117.599342 -412.436677) (xy 117.621989 -412.38709)
			(xy 117.651464 -412.341231) (xy 117.687166 -412.300033) (xy 117.728367 -412.264337) (xy 117.77423 -412.234867)
			(xy 117.82382 -412.212225) (xy 117.876128 -412.196872) (xy 117.930089 -412.18912) (xy 117.957346 -412.18866)
			(xy 118.820946 -412.18866) (xy 118.848193 -412.189213) (xy 118.902131 -412.196975) (xy 118.954416 -412.212332)
			(xy 119.003983 -412.234974) (xy 119.049824 -412.264439) (xy 119.091005 -412.300128) (xy 119.126688 -412.341313)
			(xy 119.156148 -412.387157) (xy 119.178784 -412.436727) (xy 119.194135 -412.489014) (xy 119.20189 -412.542953)
			(xy 119.20189 -412.597447) (xy 119.201889 -412.597453) (xy 120.639546 -412.597453) (xy 120.639546 -412.542947)
			(xy 120.647303 -412.488996) (xy 120.662658 -412.436698) (xy 120.6853 -412.387118) (xy 120.714768 -412.341264)
			(xy 120.750461 -412.300071) (xy 120.791653 -412.264376) (xy 120.837505 -412.234907) (xy 120.887085 -412.212263)
			(xy 120.939382 -412.196906) (xy 120.993333 -412.189147) (xy 121.020586 -412.18866) (xy 121.884186 -412.18866)
			(xy 121.911437 -412.189186) (xy 121.965385 -412.196941) (xy 122.01768 -412.212295) (xy 122.067258 -412.234934)
			(xy 122.113109 -412.264399) (xy 122.1543 -412.30009) (xy 122.189992 -412.34128) (xy 122.219459 -412.38713)
			(xy 122.242101 -412.436707) (xy 122.257456 -412.489001) (xy 122.265213 -412.542949) (xy 122.265213 -412.597451)
			(xy 122.265212 -412.597456) (xy 123.702723 -412.597456) (xy 123.702723 -412.542944) (xy 123.710481 -412.488986)
			(xy 123.72584 -412.436681) (xy 123.748486 -412.387095) (xy 123.777959 -412.341237) (xy 123.813659 -412.30004)
			(xy 123.854858 -412.264344) (xy 123.900718 -412.234874) (xy 123.950306 -412.212231) (xy 124.002611 -412.196876)
			(xy 124.05657 -412.189121) (xy 124.083826 -412.18866) (xy 124.947426 -412.18866) (xy 124.974674 -412.189212)
			(xy 125.028614 -412.196971) (xy 125.080901 -412.212327) (xy 125.130471 -412.234968) (xy 125.176314 -412.264432)
			(xy 125.217498 -412.300121) (xy 125.253184 -412.341307) (xy 125.282645 -412.387152) (xy 125.305282 -412.436723)
			(xy 125.320635 -412.489011) (xy 125.32839 -412.542952) (xy 125.32839 -412.597448) (xy 125.328389 -412.597452)
			(xy 126.766046 -412.597452) (xy 126.766046 -412.542948) (xy 126.773802 -412.488999) (xy 126.789157 -412.436702)
			(xy 126.811797 -412.387123) (xy 126.841263 -412.341271) (xy 126.876954 -412.300078) (xy 126.918143 -412.264383)
			(xy 126.963993 -412.234914) (xy 127.01357 -412.212269) (xy 127.065865 -412.196909) (xy 127.119814 -412.189148)
			(xy 127.147066 -412.18866) (xy 128.010666 -412.18866) (xy 128.037918 -412.189185) (xy 128.091868 -412.196937)
			(xy 128.144166 -412.212289) (xy 128.193746 -412.234928) (xy 128.2396 -412.264392) (xy 128.280793 -412.300083)
			(xy 128.316487 -412.341273) (xy 128.345956 -412.387124) (xy 128.368599 -412.436702) (xy 128.383955 -412.488999)
			(xy 128.391713 -412.542948) (xy 128.391713 -412.597452) (xy 128.391713 -412.597455) (xy 129.829223 -412.597455)
			(xy 129.829223 -412.542945) (xy 129.836981 -412.488989) (xy 129.852338 -412.436686) (xy 129.874983 -412.387101)
			(xy 129.904454 -412.341244) (xy 129.940152 -412.300047) (xy 129.981349 -412.264351) (xy 130.027206 -412.23488)
			(xy 130.076791 -412.212236) (xy 130.129094 -412.196879) (xy 130.183051 -412.189123) (xy 130.210306 -412.18866)
			(xy 131.073906 -412.18866) (xy 131.101155 -412.189211) (xy 131.155097 -412.196967) (xy 131.207387 -412.212321)
			(xy 131.256959 -412.234961) (xy 131.302805 -412.264425) (xy 131.343991 -412.300113) (xy 131.379679 -412.3413)
			(xy 131.409142 -412.387146) (xy 131.431781 -412.436719) (xy 131.447134 -412.489009) (xy 131.45489 -412.542951)
			(xy 131.45489 -412.597449) (xy 131.454889 -412.597457) (xy 132.892423 -412.597457) (xy 132.892423 -412.542943)
			(xy 132.900182 -412.488983) (xy 132.915542 -412.436677) (xy 132.938189 -412.38709) (xy 132.967664 -412.341231)
			(xy 133.003366 -412.300033) (xy 133.044567 -412.264337) (xy 133.09043 -412.234867) (xy 133.14002 -412.212225)
			(xy 133.192328 -412.196872) (xy 133.246289 -412.18912) (xy 133.273546 -412.18866) (xy 134.137146 -412.18866)
			(xy 134.164393 -412.189213) (xy 134.218331 -412.196975) (xy 134.270616 -412.212332) (xy 134.320183 -412.234974)
			(xy 134.366024 -412.264439) (xy 134.407205 -412.300128) (xy 134.442888 -412.341313) (xy 134.472348 -412.387157)
			(xy 134.494984 -412.436727) (xy 134.510335 -412.489014) (xy 134.51809 -412.542953) (xy 134.51809 -412.597447)
			(xy 134.518089 -412.597453) (xy 135.955746 -412.597453) (xy 135.955746 -412.542947) (xy 135.963503 -412.488996)
			(xy 135.978858 -412.436698) (xy 136.0015 -412.387118) (xy 136.030968 -412.341264) (xy 136.066661 -412.300071)
			(xy 136.107853 -412.264376) (xy 136.153705 -412.234907) (xy 136.203285 -412.212263) (xy 136.255582 -412.196906)
			(xy 136.309533 -412.189147) (xy 136.336786 -412.18866) (xy 137.200386 -412.18866) (xy 137.227637 -412.189186)
			(xy 137.281585 -412.196941) (xy 137.33388 -412.212295) (xy 137.383458 -412.234934) (xy 137.429309 -412.264399)
			(xy 137.4705 -412.30009) (xy 137.506192 -412.34128) (xy 137.535659 -412.38713) (xy 137.558301 -412.436707)
			(xy 137.573656 -412.489001) (xy 137.581413 -412.542949) (xy 137.581413 -412.597451) (xy 137.581412 -412.597456)
			(xy 139.018923 -412.597456) (xy 139.018923 -412.542944) (xy 139.026681 -412.488986) (xy 139.04204 -412.436681)
			(xy 139.064686 -412.387095) (xy 139.094159 -412.341237) (xy 139.129859 -412.30004) (xy 139.171058 -412.264344)
			(xy 139.216918 -412.234874) (xy 139.266506 -412.212231) (xy 139.318811 -412.196876) (xy 139.37277 -412.189121)
			(xy 139.400026 -412.18866) (xy 140.263626 -412.18866) (xy 140.290874 -412.189212) (xy 140.344814 -412.196971)
			(xy 140.397101 -412.212327) (xy 140.446671 -412.234968) (xy 140.492514 -412.264432) (xy 140.533698 -412.300121)
			(xy 140.569384 -412.341307) (xy 140.598845 -412.387152) (xy 140.621482 -412.436723) (xy 140.636835 -412.489011)
			(xy 140.64459 -412.542952) (xy 140.64459 -412.597448) (xy 140.644589 -412.597452) (xy 142.082246 -412.597452)
			(xy 142.082246 -412.542948) (xy 142.090002 -412.488999) (xy 142.105357 -412.436702) (xy 142.127997 -412.387123)
			(xy 142.157463 -412.341271) (xy 142.193154 -412.300078) (xy 142.234343 -412.264383) (xy 142.280193 -412.234914)
			(xy 142.32977 -412.212269) (xy 142.382065 -412.196909) (xy 142.436014 -412.189148) (xy 142.463266 -412.18866)
			(xy 143.326866 -412.18866) (xy 143.354118 -412.189185) (xy 143.408068 -412.196937) (xy 143.460366 -412.212289)
			(xy 143.509946 -412.234928) (xy 143.5558 -412.264392) (xy 143.596993 -412.300083) (xy 143.632687 -412.341273)
			(xy 143.662156 -412.387124) (xy 143.684799 -412.436702) (xy 143.700155 -412.488999) (xy 143.707913 -412.542948)
			(xy 143.707913 -412.597452) (xy 143.707913 -412.597455) (xy 145.145423 -412.597455) (xy 145.145423 -412.542945)
			(xy 145.153181 -412.488989) (xy 145.168538 -412.436686) (xy 145.191183 -412.387101) (xy 145.220654 -412.341244)
			(xy 145.256352 -412.300047) (xy 145.297549 -412.264351) (xy 145.343406 -412.23488) (xy 145.392991 -412.212236)
			(xy 145.445294 -412.196879) (xy 145.499251 -412.189123) (xy 145.526506 -412.18866) (xy 146.390106 -412.18866)
			(xy 146.417355 -412.189211) (xy 146.471297 -412.196967) (xy 146.523587 -412.212321) (xy 146.573159 -412.234961)
			(xy 146.619005 -412.264425) (xy 146.660191 -412.300113) (xy 146.695879 -412.3413) (xy 146.725342 -412.387146)
			(xy 146.747981 -412.436719) (xy 146.763334 -412.489009) (xy 146.77109 -412.542951) (xy 146.77109 -412.597449)
			(xy 146.771089 -412.597457) (xy 148.208623 -412.597457) (xy 148.208623 -412.542943) (xy 148.216382 -412.488983)
			(xy 148.231742 -412.436677) (xy 148.254389 -412.38709) (xy 148.283864 -412.341231) (xy 148.319566 -412.300033)
			(xy 148.360767 -412.264337) (xy 148.40663 -412.234867) (xy 148.45622 -412.212225) (xy 148.508528 -412.196872)
			(xy 148.562489 -412.18912) (xy 148.589746 -412.18866) (xy 149.453346 -412.18866) (xy 149.480593 -412.189213)
			(xy 149.534531 -412.196975) (xy 149.586816 -412.212332) (xy 149.636383 -412.234974) (xy 149.682224 -412.264439)
			(xy 149.723405 -412.300128) (xy 149.759088 -412.341313) (xy 149.788548 -412.387157) (xy 149.811184 -412.436727)
			(xy 149.826535 -412.489014) (xy 149.83429 -412.542953) (xy 149.83429 -412.597447) (xy 149.834289 -412.597453)
			(xy 151.271946 -412.597453) (xy 151.271946 -412.542947) (xy 151.279703 -412.488996) (xy 151.295058 -412.436698)
			(xy 151.3177 -412.387118) (xy 151.347168 -412.341264) (xy 151.382861 -412.300071) (xy 151.424053 -412.264376)
			(xy 151.469905 -412.234907) (xy 151.519485 -412.212263) (xy 151.571782 -412.196906) (xy 151.625733 -412.189147)
			(xy 151.652986 -412.18866) (xy 152.516586 -412.18866) (xy 152.543837 -412.189186) (xy 152.597785 -412.196941)
			(xy 152.65008 -412.212295) (xy 152.699658 -412.234934) (xy 152.745509 -412.264399) (xy 152.7867 -412.30009)
			(xy 152.822392 -412.34128) (xy 152.851859 -412.38713) (xy 152.874501 -412.436707) (xy 152.889856 -412.489001)
			(xy 152.897613 -412.542949) (xy 152.897613 -412.597451) (xy 152.897612 -412.597456) (xy 154.335123 -412.597456)
			(xy 154.335123 -412.542944) (xy 154.342881 -412.488986) (xy 154.35824 -412.436681) (xy 154.380886 -412.387095)
			(xy 154.410359 -412.341237) (xy 154.446059 -412.30004) (xy 154.487258 -412.264344) (xy 154.533118 -412.234874)
			(xy 154.582706 -412.212231) (xy 154.635011 -412.196876) (xy 154.68897 -412.189121) (xy 154.716226 -412.18866)
			(xy 155.579826 -412.18866) (xy 155.607074 -412.189212) (xy 155.661014 -412.196971) (xy 155.713301 -412.212327)
			(xy 155.762871 -412.234968) (xy 155.808714 -412.264432) (xy 155.849898 -412.300121) (xy 155.885584 -412.341307)
			(xy 155.915045 -412.387152) (xy 155.937682 -412.436723) (xy 155.953035 -412.489011) (xy 155.96079 -412.542952)
			(xy 155.96079 -412.597448) (xy 155.960789 -412.597452) (xy 157.398446 -412.597452) (xy 157.398446 -412.542948)
			(xy 157.406202 -412.488999) (xy 157.421557 -412.436702) (xy 157.444197 -412.387123) (xy 157.473663 -412.341271)
			(xy 157.509354 -412.300078) (xy 157.550543 -412.264383) (xy 157.596393 -412.234914) (xy 157.64597 -412.212269)
			(xy 157.698265 -412.196909) (xy 157.752214 -412.189148) (xy 157.779466 -412.18866) (xy 158.643066 -412.18866)
			(xy 158.670318 -412.189185) (xy 158.724268 -412.196937) (xy 158.776566 -412.212289) (xy 158.826146 -412.234928)
			(xy 158.872 -412.264392) (xy 158.913193 -412.300083) (xy 158.948887 -412.341273) (xy 158.978356 -412.387124)
			(xy 159.000999 -412.436702) (xy 159.016355 -412.488999) (xy 159.024113 -412.542948) (xy 159.024113 -412.597452)
			(xy 159.024113 -412.597455) (xy 160.461623 -412.597455) (xy 160.461623 -412.542945) (xy 160.469381 -412.488989)
			(xy 160.484738 -412.436686) (xy 160.507383 -412.387101) (xy 160.536854 -412.341244) (xy 160.572552 -412.300047)
			(xy 160.613749 -412.264351) (xy 160.659606 -412.23488) (xy 160.709191 -412.212236) (xy 160.761494 -412.196879)
			(xy 160.815451 -412.189123) (xy 160.842706 -412.18866) (xy 161.706306 -412.18866) (xy 161.733555 -412.189211)
			(xy 161.787497 -412.196967) (xy 161.839787 -412.212321) (xy 161.889359 -412.234961) (xy 161.935205 -412.264425)
			(xy 161.976391 -412.300113) (xy 162.012079 -412.3413) (xy 162.041542 -412.387146) (xy 162.064181 -412.436719)
			(xy 162.079534 -412.489009) (xy 162.08729 -412.542951) (xy 162.08729 -412.597449) (xy 162.079534 -412.651391)
			(xy 162.064181 -412.703681) (xy 162.041542 -412.753254) (xy 162.012079 -412.7991) (xy 161.976391 -412.840287)
			(xy 161.935205 -412.875975) (xy 161.889359 -412.905439) (xy 161.839787 -412.928079) (xy 161.787497 -412.943433)
			(xy 161.733555 -412.951189) (xy 161.706306 -412.951676) (xy 160.842706 -412.951676) (xy 160.815451 -412.951277)
			(xy 160.761494 -412.943521) (xy 160.709191 -412.928164) (xy 160.659606 -412.90552) (xy 160.613749 -412.876049)
			(xy 160.572552 -412.840353) (xy 160.536854 -412.799156) (xy 160.507383 -412.753299) (xy 160.484738 -412.703714)
			(xy 160.469381 -412.651411) (xy 160.461623 -412.597455) (xy 159.024113 -412.597455) (xy 159.016355 -412.651402)
			(xy 159.000999 -412.703698) (xy 158.978356 -412.753276) (xy 158.948887 -412.799127) (xy 158.913193 -412.840317)
			(xy 158.872 -412.876008) (xy 158.826146 -412.905472) (xy 158.776566 -412.928111) (xy 158.724268 -412.943463)
			(xy 158.670318 -412.951215) (xy 158.643066 -412.951676) (xy 157.779466 -412.951676) (xy 157.752214 -412.951252)
			(xy 157.698265 -412.943491) (xy 157.64597 -412.928131) (xy 157.596393 -412.905486) (xy 157.550543 -412.876017)
			(xy 157.509354 -412.840322) (xy 157.473663 -412.799129) (xy 157.444197 -412.753277) (xy 157.421557 -412.703698)
			(xy 157.406202 -412.651401) (xy 157.398446 -412.597452) (xy 155.960789 -412.597452) (xy 155.953035 -412.651389)
			(xy 155.937682 -412.703677) (xy 155.915045 -412.753248) (xy 155.885584 -412.799093) (xy 155.849898 -412.840279)
			(xy 155.808714 -412.875968) (xy 155.762871 -412.905432) (xy 155.713301 -412.928073) (xy 155.661014 -412.943429)
			(xy 155.607074 -412.951188) (xy 155.579826 -412.951676) (xy 154.716226 -412.951676) (xy 154.68897 -412.951279)
			(xy 154.635011 -412.943524) (xy 154.582706 -412.928169) (xy 154.533118 -412.905526) (xy 154.487258 -412.876056)
			(xy 154.446059 -412.84036) (xy 154.410359 -412.799163) (xy 154.380886 -412.753305) (xy 154.35824 -412.703719)
			(xy 154.342881 -412.651414) (xy 154.335123 -412.597456) (xy 152.897612 -412.597456) (xy 152.889856 -412.651399)
			(xy 152.874501 -412.703693) (xy 152.851859 -412.75327) (xy 152.822392 -412.79912) (xy 152.7867 -412.84031)
			(xy 152.745509 -412.876001) (xy 152.699658 -412.905466) (xy 152.65008 -412.928105) (xy 152.597785 -412.943459)
			(xy 152.543837 -412.951214) (xy 152.516586 -412.951676) (xy 151.652986 -412.951676) (xy 151.625733 -412.951253)
			(xy 151.571782 -412.943494) (xy 151.519485 -412.928137) (xy 151.469905 -412.905493) (xy 151.424053 -412.876024)
			(xy 151.382861 -412.840329) (xy 151.347168 -412.799136) (xy 151.3177 -412.753282) (xy 151.295058 -412.703702)
			(xy 151.279703 -412.651404) (xy 151.271946 -412.597453) (xy 149.834289 -412.597453) (xy 149.826535 -412.651386)
			(xy 149.811184 -412.703673) (xy 149.788548 -412.753243) (xy 149.759088 -412.799087) (xy 149.723405 -412.840272)
			(xy 149.682224 -412.875961) (xy 149.636383 -412.905426) (xy 149.586816 -412.928068) (xy 149.534531 -412.943425)
			(xy 149.480593 -412.951187) (xy 149.453346 -412.951676) (xy 148.589746 -412.951676) (xy 148.562489 -412.95128)
			(xy 148.508528 -412.943528) (xy 148.45622 -412.928175) (xy 148.40663 -412.905533) (xy 148.360767 -412.876063)
			(xy 148.319566 -412.840367) (xy 148.283864 -412.799169) (xy 148.254389 -412.75331) (xy 148.231742 -412.703723)
			(xy 148.216382 -412.651417) (xy 148.208623 -412.597457) (xy 146.771089 -412.597457) (xy 146.763334 -412.651391)
			(xy 146.747981 -412.703681) (xy 146.725342 -412.753254) (xy 146.695879 -412.7991) (xy 146.660191 -412.840287)
			(xy 146.619005 -412.875975) (xy 146.573159 -412.905439) (xy 146.523587 -412.928079) (xy 146.471297 -412.943433)
			(xy 146.417355 -412.951189) (xy 146.390106 -412.951676) (xy 145.526506 -412.951676) (xy 145.499251 -412.951277)
			(xy 145.445294 -412.943521) (xy 145.392991 -412.928164) (xy 145.343406 -412.90552) (xy 145.297549 -412.876049)
			(xy 145.256352 -412.840353) (xy 145.220654 -412.799156) (xy 145.191183 -412.753299) (xy 145.168538 -412.703714)
			(xy 145.153181 -412.651411) (xy 145.145423 -412.597455) (xy 143.707913 -412.597455) (xy 143.700155 -412.651402)
			(xy 143.684799 -412.703698) (xy 143.662156 -412.753276) (xy 143.632687 -412.799127) (xy 143.596993 -412.840317)
			(xy 143.5558 -412.876008) (xy 143.509946 -412.905472) (xy 143.460366 -412.928111) (xy 143.408068 -412.943463)
			(xy 143.354118 -412.951215) (xy 143.326866 -412.951676) (xy 142.463266 -412.951676) (xy 142.436014 -412.951252)
			(xy 142.382065 -412.943491) (xy 142.32977 -412.928131) (xy 142.280193 -412.905486) (xy 142.234343 -412.876017)
			(xy 142.193154 -412.840322) (xy 142.157463 -412.799129) (xy 142.127997 -412.753277) (xy 142.105357 -412.703698)
			(xy 142.090002 -412.651401) (xy 142.082246 -412.597452) (xy 140.644589 -412.597452) (xy 140.636835 -412.651389)
			(xy 140.621482 -412.703677) (xy 140.598845 -412.753248) (xy 140.569384 -412.799093) (xy 140.533698 -412.840279)
			(xy 140.492514 -412.875968) (xy 140.446671 -412.905432) (xy 140.397101 -412.928073) (xy 140.344814 -412.943429)
			(xy 140.290874 -412.951188) (xy 140.263626 -412.951676) (xy 139.400026 -412.951676) (xy 139.37277 -412.951279)
			(xy 139.318811 -412.943524) (xy 139.266506 -412.928169) (xy 139.216918 -412.905526) (xy 139.171058 -412.876056)
			(xy 139.129859 -412.84036) (xy 139.094159 -412.799163) (xy 139.064686 -412.753305) (xy 139.04204 -412.703719)
			(xy 139.026681 -412.651414) (xy 139.018923 -412.597456) (xy 137.581412 -412.597456) (xy 137.573656 -412.651399)
			(xy 137.558301 -412.703693) (xy 137.535659 -412.75327) (xy 137.506192 -412.79912) (xy 137.4705 -412.84031)
			(xy 137.429309 -412.876001) (xy 137.383458 -412.905466) (xy 137.33388 -412.928105) (xy 137.281585 -412.943459)
			(xy 137.227637 -412.951214) (xy 137.200386 -412.951676) (xy 136.336786 -412.951676) (xy 136.309533 -412.951253)
			(xy 136.255582 -412.943494) (xy 136.203285 -412.928137) (xy 136.153705 -412.905493) (xy 136.107853 -412.876024)
			(xy 136.066661 -412.840329) (xy 136.030968 -412.799136) (xy 136.0015 -412.753282) (xy 135.978858 -412.703702)
			(xy 135.963503 -412.651404) (xy 135.955746 -412.597453) (xy 134.518089 -412.597453) (xy 134.510335 -412.651386)
			(xy 134.494984 -412.703673) (xy 134.472348 -412.753243) (xy 134.442888 -412.799087) (xy 134.407205 -412.840272)
			(xy 134.366024 -412.875961) (xy 134.320183 -412.905426) (xy 134.270616 -412.928068) (xy 134.218331 -412.943425)
			(xy 134.164393 -412.951187) (xy 134.137146 -412.951676) (xy 133.273546 -412.951676) (xy 133.246289 -412.95128)
			(xy 133.192328 -412.943528) (xy 133.14002 -412.928175) (xy 133.09043 -412.905533) (xy 133.044567 -412.876063)
			(xy 133.003366 -412.840367) (xy 132.967664 -412.799169) (xy 132.938189 -412.75331) (xy 132.915542 -412.703723)
			(xy 132.900182 -412.651417) (xy 132.892423 -412.597457) (xy 131.454889 -412.597457) (xy 131.447134 -412.651391)
			(xy 131.431781 -412.703681) (xy 131.409142 -412.753254) (xy 131.379679 -412.7991) (xy 131.343991 -412.840287)
			(xy 131.302805 -412.875975) (xy 131.256959 -412.905439) (xy 131.207387 -412.928079) (xy 131.155097 -412.943433)
			(xy 131.101155 -412.951189) (xy 131.073906 -412.951676) (xy 130.210306 -412.951676) (xy 130.183051 -412.951277)
			(xy 130.129094 -412.943521) (xy 130.076791 -412.928164) (xy 130.027206 -412.90552) (xy 129.981349 -412.876049)
			(xy 129.940152 -412.840353) (xy 129.904454 -412.799156) (xy 129.874983 -412.753299) (xy 129.852338 -412.703714)
			(xy 129.836981 -412.651411) (xy 129.829223 -412.597455) (xy 128.391713 -412.597455) (xy 128.383955 -412.651402)
			(xy 128.368599 -412.703698) (xy 128.345956 -412.753276) (xy 128.316487 -412.799127) (xy 128.280793 -412.840317)
			(xy 128.2396 -412.876008) (xy 128.193746 -412.905472) (xy 128.144166 -412.928111) (xy 128.091868 -412.943463)
			(xy 128.037918 -412.951215) (xy 128.010666 -412.951676) (xy 127.147066 -412.951676) (xy 127.119814 -412.951252)
			(xy 127.065865 -412.943491) (xy 127.01357 -412.928131) (xy 126.963993 -412.905486) (xy 126.918143 -412.876017)
			(xy 126.876954 -412.840322) (xy 126.841263 -412.799129) (xy 126.811797 -412.753277) (xy 126.789157 -412.703698)
			(xy 126.773802 -412.651401) (xy 126.766046 -412.597452) (xy 125.328389 -412.597452) (xy 125.320635 -412.651389)
			(xy 125.305282 -412.703677) (xy 125.282645 -412.753248) (xy 125.253184 -412.799093) (xy 125.217498 -412.840279)
			(xy 125.176314 -412.875968) (xy 125.130471 -412.905432) (xy 125.080901 -412.928073) (xy 125.028614 -412.943429)
			(xy 124.974674 -412.951188) (xy 124.947426 -412.951676) (xy 124.083826 -412.951676) (xy 124.05657 -412.951279)
			(xy 124.002611 -412.943524) (xy 123.950306 -412.928169) (xy 123.900718 -412.905526) (xy 123.854858 -412.876056)
			(xy 123.813659 -412.84036) (xy 123.777959 -412.799163) (xy 123.748486 -412.753305) (xy 123.72584 -412.703719)
			(xy 123.710481 -412.651414) (xy 123.702723 -412.597456) (xy 122.265212 -412.597456) (xy 122.257456 -412.651399)
			(xy 122.242101 -412.703693) (xy 122.219459 -412.75327) (xy 122.189992 -412.79912) (xy 122.1543 -412.84031)
			(xy 122.113109 -412.876001) (xy 122.067258 -412.905466) (xy 122.01768 -412.928105) (xy 121.965385 -412.943459)
			(xy 121.911437 -412.951214) (xy 121.884186 -412.951676) (xy 121.020586 -412.951676) (xy 120.993333 -412.951253)
			(xy 120.939382 -412.943494) (xy 120.887085 -412.928137) (xy 120.837505 -412.905493) (xy 120.791653 -412.876024)
			(xy 120.750461 -412.840329) (xy 120.714768 -412.799136) (xy 120.6853 -412.753282) (xy 120.662658 -412.703702)
			(xy 120.647303 -412.651404) (xy 120.639546 -412.597453) (xy 119.201889 -412.597453) (xy 119.194135 -412.651386)
			(xy 119.178784 -412.703673) (xy 119.156148 -412.753243) (xy 119.126688 -412.799087) (xy 119.091005 -412.840272)
			(xy 119.049824 -412.875961) (xy 119.003983 -412.905426) (xy 118.954416 -412.928068) (xy 118.902131 -412.943425)
			(xy 118.848193 -412.951187) (xy 118.820946 -412.951676) (xy 117.957346 -412.951676) (xy 117.930089 -412.95128)
			(xy 117.876128 -412.943528) (xy 117.82382 -412.928175) (xy 117.77423 -412.905533) (xy 117.728367 -412.876063)
			(xy 117.687166 -412.840367) (xy 117.651464 -412.799169) (xy 117.621989 -412.75331) (xy 117.599342 -412.703723)
			(xy 117.583982 -412.651417) (xy 117.576223 -412.597457) (xy 116.138689 -412.597457) (xy 116.130934 -412.651391)
			(xy 116.115581 -412.703681) (xy 116.092942 -412.753254) (xy 116.063479 -412.7991) (xy 116.027791 -412.840287)
			(xy 115.986605 -412.875975) (xy 115.940759 -412.905439) (xy 115.891187 -412.928079) (xy 115.838897 -412.943433)
			(xy 115.784955 -412.951189) (xy 115.757706 -412.951676) (xy 114.894106 -412.951676) (xy 114.866851 -412.951277)
			(xy 114.812894 -412.943521) (xy 114.760591 -412.928164) (xy 114.711006 -412.90552) (xy 114.665149 -412.876049)
			(xy 114.623952 -412.840353) (xy 114.588254 -412.799156) (xy 114.558783 -412.753299) (xy 114.536138 -412.703714)
			(xy 114.520781 -412.651411) (xy 114.513023 -412.597455) (xy 94.987413 -412.597455) (xy 94.979655 -412.651402)
			(xy 94.964299 -412.703698) (xy 94.941656 -412.753276) (xy 94.912187 -412.799127) (xy 94.876492 -412.840318)
			(xy 94.835299 -412.876008) (xy 94.789445 -412.905473) (xy 94.739864 -412.928111) (xy 94.687567 -412.943463)
			(xy 94.633616 -412.951215) (xy 94.606364 -412.951676) (xy 93.742764 -412.951676) (xy 93.715512 -412.951252)
			(xy 93.661564 -412.94349) (xy 93.609269 -412.928131) (xy 93.559692 -412.905486) (xy 93.513842 -412.876016)
			(xy 93.472653 -412.840321) (xy 93.436962 -412.799129) (xy 93.407497 -412.753276) (xy 93.384857 -412.703697)
			(xy 93.369502 -412.651401) (xy 93.361746 -412.597452) (xy 91.924089 -412.597452) (xy 91.916335 -412.651389)
			(xy 91.900982 -412.703677) (xy 91.878345 -412.753249) (xy 91.848883 -412.799094) (xy 91.813197 -412.84028)
			(xy 91.772013 -412.875969) (xy 91.72617 -412.905433) (xy 91.6766 -412.928074) (xy 91.624312 -412.94343)
			(xy 91.570372 -412.951188) (xy 91.543124 -412.951676) (xy 90.679524 -412.951676) (xy 90.652268 -412.951279)
			(xy 90.59831 -412.943524) (xy 90.546004 -412.928169) (xy 90.496417 -412.905526) (xy 90.450557 -412.876056)
			(xy 90.409358 -412.840359) (xy 90.373659 -412.799162) (xy 90.344186 -412.753304) (xy 90.32154 -412.703718)
			(xy 90.306181 -412.651414) (xy 90.298423 -412.597456) (xy 88.860912 -412.597456) (xy 88.853156 -412.651399)
			(xy 88.8378 -412.703694) (xy 88.815159 -412.753271) (xy 88.785692 -412.799121) (xy 88.749999 -412.840311)
			(xy 88.708808 -412.876001) (xy 88.662957 -412.905466) (xy 88.613379 -412.928106) (xy 88.561083 -412.943459)
			(xy 88.507135 -412.951214) (xy 88.479884 -412.951676) (xy 87.616284 -412.951676) (xy 87.589031 -412.951253)
			(xy 87.535081 -412.943494) (xy 87.482783 -412.928136) (xy 87.433204 -412.905492) (xy 87.387352 -412.876023)
			(xy 87.34616 -412.840329) (xy 87.310467 -412.799135) (xy 87.281 -412.753282) (xy 87.258358 -412.703702)
			(xy 87.243003 -412.651404) (xy 87.235246 -412.597453) (xy 85.797589 -412.597453) (xy 85.789835 -412.651386)
			(xy 85.774484 -412.703673) (xy 85.751848 -412.753243) (xy 85.722388 -412.799087) (xy 85.686704 -412.840273)
			(xy 85.645523 -412.875962) (xy 85.599682 -412.905427) (xy 85.550114 -412.928068) (xy 85.497829 -412.943426)
			(xy 85.443891 -412.951187) (xy 85.416644 -412.951676) (xy 84.553044 -412.951676) (xy 84.525787 -412.95128)
			(xy 84.471827 -412.943528) (xy 84.419519 -412.928174) (xy 84.369929 -412.905532) (xy 84.324067 -412.876063)
			(xy 84.282865 -412.840366) (xy 84.247164 -412.799169) (xy 84.217689 -412.75331) (xy 84.195041 -412.703722)
			(xy 84.179682 -412.651417) (xy 84.171923 -412.597457) (xy 82.734389 -412.597457) (xy 82.726634 -412.651392)
			(xy 82.71128 -412.703682) (xy 82.688642 -412.753254) (xy 82.659178 -412.799101) (xy 82.62349 -412.840287)
			(xy 82.582304 -412.875976) (xy 82.536458 -412.90544) (xy 82.486885 -412.928079) (xy 82.434595 -412.943433)
			(xy 82.380653 -412.95119) (xy 82.353404 -412.951676) (xy 81.489804 -412.951676) (xy 81.462549 -412.951277)
			(xy 81.408593 -412.94352) (xy 81.35629 -412.928163) (xy 81.306705 -412.905519) (xy 81.260848 -412.876049)
			(xy 81.219651 -412.840352) (xy 81.183954 -412.799156) (xy 81.154483 -412.753298) (xy 81.131838 -412.703714)
			(xy 81.116481 -412.651411) (xy 81.108723 -412.597455) (xy 79.671213 -412.597455) (xy 79.663455 -412.651402)
			(xy 79.648099 -412.703698) (xy 79.625456 -412.753276) (xy 79.595987 -412.799127) (xy 79.560292 -412.840318)
			(xy 79.519099 -412.876008) (xy 79.473245 -412.905473) (xy 79.423664 -412.928111) (xy 79.371367 -412.943463)
			(xy 79.317416 -412.951215) (xy 79.290164 -412.951676) (xy 78.426564 -412.951676) (xy 78.399312 -412.951252)
			(xy 78.345364 -412.94349) (xy 78.293069 -412.928131) (xy 78.243492 -412.905486) (xy 78.197642 -412.876016)
			(xy 78.156453 -412.840321) (xy 78.120762 -412.799129) (xy 78.091297 -412.753276) (xy 78.068657 -412.703697)
			(xy 78.053302 -412.651401) (xy 78.045546 -412.597452) (xy 76.607889 -412.597452) (xy 76.600135 -412.651389)
			(xy 76.584782 -412.703677) (xy 76.562145 -412.753249) (xy 76.532683 -412.799094) (xy 76.496997 -412.84028)
			(xy 76.455813 -412.875969) (xy 76.40997 -412.905433) (xy 76.3604 -412.928074) (xy 76.308112 -412.94343)
			(xy 76.254172 -412.951188) (xy 76.226924 -412.951676) (xy 75.363324 -412.951676) (xy 75.336068 -412.951279)
			(xy 75.28211 -412.943524) (xy 75.229804 -412.928169) (xy 75.180217 -412.905526) (xy 75.134357 -412.876056)
			(xy 75.093158 -412.840359) (xy 75.057459 -412.799162) (xy 75.027986 -412.753304) (xy 75.00534 -412.703718)
			(xy 74.989981 -412.651414) (xy 74.982223 -412.597456) (xy 73.544712 -412.597456) (xy 73.536956 -412.651399)
			(xy 73.5216 -412.703694) (xy 73.498959 -412.753271) (xy 73.469492 -412.799121) (xy 73.433799 -412.840311)
			(xy 73.392608 -412.876001) (xy 73.346757 -412.905466) (xy 73.297179 -412.928106) (xy 73.244883 -412.943459)
			(xy 73.190935 -412.951214) (xy 73.163684 -412.951676) (xy 72.300084 -412.951676) (xy 72.272831 -412.951253)
			(xy 72.218881 -412.943494) (xy 72.166583 -412.928136) (xy 72.117004 -412.905492) (xy 72.071152 -412.876023)
			(xy 72.02996 -412.840329) (xy 71.994267 -412.799135) (xy 71.9648 -412.753282) (xy 71.942158 -412.703702)
			(xy 71.926803 -412.651404) (xy 71.919046 -412.597453) (xy 70.481389 -412.597453) (xy 70.473635 -412.651386)
			(xy 70.458284 -412.703673) (xy 70.435648 -412.753243) (xy 70.406188 -412.799087) (xy 70.370504 -412.840273)
			(xy 70.329323 -412.875962) (xy 70.283482 -412.905427) (xy 70.233914 -412.928068) (xy 70.181629 -412.943426)
			(xy 70.127691 -412.951187) (xy 70.100444 -412.951676) (xy 69.236844 -412.951676) (xy 69.209587 -412.95128)
			(xy 69.155627 -412.943528) (xy 69.103319 -412.928174) (xy 69.053729 -412.905532) (xy 69.007867 -412.876063)
			(xy 68.966665 -412.840366) (xy 68.930964 -412.799169) (xy 68.901489 -412.75331) (xy 68.878841 -412.703722)
			(xy 68.863482 -412.651417) (xy 68.855723 -412.597457) (xy 67.418189 -412.597457) (xy 67.410434 -412.651392)
			(xy 67.39508 -412.703682) (xy 67.372442 -412.753254) (xy 67.342978 -412.799101) (xy 67.30729 -412.840287)
			(xy 67.266104 -412.875976) (xy 67.220258 -412.90544) (xy 67.170685 -412.928079) (xy 67.118395 -412.943433)
			(xy 67.064453 -412.95119) (xy 67.037204 -412.951676) (xy 66.173604 -412.951676) (xy 66.146349 -412.951277)
			(xy 66.092393 -412.94352) (xy 66.04009 -412.928163) (xy 65.990505 -412.905519) (xy 65.944648 -412.876049)
			(xy 65.903451 -412.840352) (xy 65.867754 -412.799156) (xy 65.838283 -412.753298) (xy 65.815638 -412.703714)
			(xy 65.800281 -412.651411) (xy 65.792523 -412.597455) (xy 64.355013 -412.597455) (xy 64.347255 -412.651402)
			(xy 64.331899 -412.703698) (xy 64.309256 -412.753276) (xy 64.279787 -412.799127) (xy 64.244092 -412.840318)
			(xy 64.202899 -412.876008) (xy 64.157045 -412.905473) (xy 64.107464 -412.928111) (xy 64.055167 -412.943463)
			(xy 64.001216 -412.951215) (xy 63.973964 -412.951676) (xy 63.110364 -412.951676) (xy 63.083112 -412.951252)
			(xy 63.029164 -412.94349) (xy 62.976869 -412.928131) (xy 62.927292 -412.905486) (xy 62.881442 -412.876016)
			(xy 62.840253 -412.840321) (xy 62.804562 -412.799129) (xy 62.775097 -412.753276) (xy 62.752457 -412.703697)
			(xy 62.737102 -412.651401) (xy 62.729346 -412.597452) (xy 61.291689 -412.597452) (xy 61.283935 -412.651389)
			(xy 61.268582 -412.703677) (xy 61.245945 -412.753249) (xy 61.216483 -412.799094) (xy 61.180797 -412.84028)
			(xy 61.139613 -412.875969) (xy 61.09377 -412.905433) (xy 61.0442 -412.928074) (xy 60.991912 -412.94343)
			(xy 60.937972 -412.951188) (xy 60.910724 -412.951676) (xy 60.047124 -412.951676) (xy 60.019868 -412.951279)
			(xy 59.96591 -412.943524) (xy 59.913604 -412.928169) (xy 59.864017 -412.905526) (xy 59.818157 -412.876056)
			(xy 59.776958 -412.840359) (xy 59.741259 -412.799162) (xy 59.711786 -412.753304) (xy 59.68914 -412.703718)
			(xy 59.673781 -412.651414) (xy 59.666023 -412.597456) (xy 58.228512 -412.597456) (xy 58.220756 -412.651399)
			(xy 58.2054 -412.703694) (xy 58.182759 -412.753271) (xy 58.153292 -412.799121) (xy 58.117599 -412.840311)
			(xy 58.076408 -412.876001) (xy 58.030557 -412.905466) (xy 57.980979 -412.928106) (xy 57.928683 -412.943459)
			(xy 57.874735 -412.951214) (xy 57.847484 -412.951676) (xy 56.983884 -412.951676) (xy 56.956631 -412.951253)
			(xy 56.902681 -412.943494) (xy 56.850383 -412.928136) (xy 56.800804 -412.905492) (xy 56.754952 -412.876023)
			(xy 56.71376 -412.840329) (xy 56.678067 -412.799135) (xy 56.6486 -412.753282) (xy 56.625958 -412.703702)
			(xy 56.610603 -412.651404) (xy 56.602846 -412.597453) (xy 55.165189 -412.597453) (xy 55.157435 -412.651386)
			(xy 55.142084 -412.703673) (xy 55.119448 -412.753243) (xy 55.089988 -412.799087) (xy 55.054304 -412.840273)
			(xy 55.013123 -412.875962) (xy 54.967282 -412.905427) (xy 54.917714 -412.928068) (xy 54.865429 -412.943426)
			(xy 54.811491 -412.951187) (xy 54.784244 -412.951676) (xy 53.920644 -412.951676) (xy 53.893387 -412.95128)
			(xy 53.839427 -412.943528) (xy 53.787119 -412.928174) (xy 53.737529 -412.905532) (xy 53.691667 -412.876063)
			(xy 53.650465 -412.840366) (xy 53.614764 -412.799169) (xy 53.585289 -412.75331) (xy 53.562641 -412.703722)
			(xy 53.547282 -412.651417) (xy 53.539523 -412.597457) (xy 52.101989 -412.597457) (xy 52.094234 -412.651392)
			(xy 52.07888 -412.703682) (xy 52.056242 -412.753254) (xy 52.026778 -412.799101) (xy 51.99109 -412.840287)
			(xy 51.949904 -412.875976) (xy 51.904058 -412.90544) (xy 51.854485 -412.928079) (xy 51.802195 -412.943433)
			(xy 51.748253 -412.95119) (xy 51.721004 -412.951676) (xy 50.857404 -412.951676) (xy 50.830149 -412.951277)
			(xy 50.776193 -412.94352) (xy 50.72389 -412.928163) (xy 50.674305 -412.905519) (xy 50.628448 -412.876049)
			(xy 50.587251 -412.840352) (xy 50.551554 -412.799156) (xy 50.522083 -412.753298) (xy 50.499438 -412.703714)
			(xy 50.484081 -412.651411) (xy 50.476323 -412.597455) (xy 49.038813 -412.597455) (xy 49.031055 -412.651402)
			(xy 49.015699 -412.703698) (xy 48.993056 -412.753276) (xy 48.963587 -412.799127) (xy 48.927892 -412.840318)
			(xy 48.886699 -412.876008) (xy 48.840845 -412.905473) (xy 48.791264 -412.928111) (xy 48.738967 -412.943463)
			(xy 48.685016 -412.951215) (xy 48.657764 -412.951676) (xy 47.794164 -412.951676) (xy 47.766912 -412.951252)
			(xy 47.712964 -412.94349) (xy 47.660669 -412.928131) (xy 47.611092 -412.905486) (xy 47.565242 -412.876016)
			(xy 47.524053 -412.840321) (xy 47.488362 -412.799129) (xy 47.458897 -412.753276) (xy 47.436257 -412.703697)
			(xy 47.420902 -412.651401) (xy 47.413146 -412.597452) (xy 39.737792 -412.597452) (xy 39.737792 -413.4485)
			(xy 39.737556 -413.461769) (xy 105.629431 -413.461769) (xy 105.629431 -413.407231) (xy 105.637193 -413.353247)
			(xy 105.652559 -413.300918) (xy 105.675215 -413.251308) (xy 105.704702 -413.205427) (xy 105.740417 -413.16421)
			(xy 105.781635 -413.128496) (xy 105.827517 -413.099011) (xy 105.877127 -413.076355) (xy 105.929457 -413.060991)
			(xy 105.983441 -413.053231) (xy 106.01071 -413.052768) (xy 106.87431 -413.052768) (xy 106.901581 -413.053195)
			(xy 106.955568 -413.060959) (xy 107.0079 -413.076326) (xy 107.057513 -413.098985) (xy 107.103396 -413.128473)
			(xy 107.144616 -413.164191) (xy 107.180333 -413.205412) (xy 107.20982 -413.251296) (xy 107.232477 -413.300909)
			(xy 107.247844 -413.353242) (xy 107.255606 -413.407229) (xy 107.255606 -413.461771) (xy 107.247844 -413.515758)
			(xy 107.232477 -413.568091) (xy 107.20982 -413.617704) (xy 107.180333 -413.663588) (xy 107.144616 -413.704809)
			(xy 107.103396 -413.740527) (xy 107.057513 -413.770015) (xy 107.0079 -413.792674) (xy 106.955568 -413.808041)
			(xy 106.901581 -413.815805) (xy 106.87431 -413.816292) (xy 106.01071 -413.816292) (xy 105.983441 -413.815769)
			(xy 105.929457 -413.808009) (xy 105.877127 -413.792645) (xy 105.827517 -413.769989) (xy 105.781635 -413.740504)
			(xy 105.740417 -413.70479) (xy 105.704702 -413.663573) (xy 105.675215 -413.617692) (xy 105.652559 -413.568082)
			(xy 105.637193 -413.515753) (xy 105.629431 -413.461769) (xy 39.737556 -413.461769) (xy 39.737306 -413.475769)
			(xy 39.729544 -413.529753) (xy 39.714179 -413.582083) (xy 39.691522 -413.631693) (xy 39.662036 -413.677574)
			(xy 39.626321 -413.718791) (xy 39.585104 -413.754506) (xy 39.539223 -413.783992) (xy 39.489613 -413.806649)
			(xy 39.437283 -413.822014) (xy 39.383299 -413.829776) (xy 39.328761 -413.829776) (xy 39.274777 -413.822014)
			(xy 39.222447 -413.806649) (xy 39.172837 -413.783992) (xy 39.126956 -413.754506) (xy 39.085739 -413.718791)
			(xy 39.050024 -413.677574) (xy 39.020538 -413.631693) (xy 38.997881 -413.582083) (xy 38.982516 -413.529753)
			(xy 38.974754 -413.475769) (xy 38.974268 -413.4485) (xy 7.00913 -413.4485) (xy 7.00913 -415.383726)
			(xy 41.206928 -415.383726) (xy 41.206928 -414.520126) (xy 41.207414 -414.492857) (xy 41.215176 -414.438873)
			(xy 41.230541 -414.386543) (xy 41.253198 -414.336933) (xy 41.282684 -414.291052) (xy 41.318399 -414.249835)
			(xy 41.359616 -414.21412) (xy 41.405497 -414.184634) (xy 41.455107 -414.161977) (xy 41.507437 -414.146612)
			(xy 41.561421 -414.13885) (xy 41.615959 -414.13885) (xy 41.669943 -414.146612) (xy 41.722273 -414.161977)
			(xy 41.771883 -414.184634) (xy 41.817764 -414.21412) (xy 41.858981 -414.249835) (xy 41.894696 -414.291052)
			(xy 41.924182 -414.336933) (xy 41.946839 -414.386543) (xy 41.962204 -414.438873) (xy 41.969966 -414.492857)
			(xy 41.970452 -414.520126) (xy 41.970452 -415.383726) (xy 41.969966 -415.410995) (xy 41.962204 -415.464979)
			(xy 41.946839 -415.517309) (xy 41.924182 -415.566919) (xy 41.894696 -415.6128) (xy 41.858981 -415.654017)
			(xy 41.817764 -415.689732) (xy 41.771883 -415.719218) (xy 41.722273 -415.741875) (xy 41.669943 -415.75724)
			(xy 41.615959 -415.765002) (xy 41.561421 -415.765002) (xy 41.507437 -415.75724) (xy 41.455107 -415.741875)
			(xy 41.405497 -415.719218) (xy 41.359616 -415.689732) (xy 41.318399 -415.654017) (xy 41.282684 -415.6128)
			(xy 41.253198 -415.566919) (xy 41.230541 -415.517309) (xy 41.215176 -415.464979) (xy 41.207414 -415.410995)
			(xy 41.206928 -415.383726) (xy 7.00913 -415.383726) (xy 7.00913 -417.465002) (xy 35.832796 -417.465002)
			(xy 35.832796 -416.601402) (xy 35.833282 -416.574151) (xy 35.841038 -416.520203) (xy 35.856393 -416.467908)
			(xy 35.879035 -416.418331) (xy 35.908501 -416.372481) (xy 35.944192 -416.33129) (xy 35.985383 -416.295599)
			(xy 36.031233 -416.266133) (xy 36.08081 -416.243491) (xy 36.133105 -416.228136) (xy 36.187053 -416.22038)
			(xy 36.241555 -416.22038) (xy 36.295503 -416.228136) (xy 36.347798 -416.243491) (xy 36.397375 -416.266133)
			(xy 36.443225 -416.295599) (xy 36.484416 -416.33129) (xy 36.520107 -416.372481) (xy 36.549573 -416.418331)
			(xy 36.572215 -416.467908) (xy 36.58757 -416.520203) (xy 36.595326 -416.574151) (xy 36.595812 -416.601402)
			(xy 36.595812 -417.436808) (xy 48.812704 -417.436808) (xy 48.812704 -416.573208) (xy 48.81319 -416.545939)
			(xy 48.820952 -416.491955) (xy 48.836317 -416.439625) (xy 48.858974 -416.390015) (xy 48.88846 -416.344134)
			(xy 48.924175 -416.302917) (xy 48.965392 -416.267202) (xy 49.011273 -416.237716) (xy 49.060883 -416.215059)
			(xy 49.113213 -416.199694) (xy 49.167197 -416.191932) (xy 49.221735 -416.191932) (xy 49.275719 -416.199694)
			(xy 49.328049 -416.215059) (xy 49.377659 -416.237716) (xy 49.42354 -416.267202) (xy 49.464757 -416.302917)
			(xy 49.500472 -416.344134) (xy 49.529958 -416.390015) (xy 49.552615 -416.439625) (xy 49.56798 -416.491955)
			(xy 49.575742 -416.545939) (xy 49.576228 -416.573208) (xy 49.576228 -417.436808) (xy 49.575742 -417.464077)
			(xy 49.56798 -417.518061) (xy 49.552615 -417.570391) (xy 49.529958 -417.620001) (xy 49.500472 -417.665882)
			(xy 49.464757 -417.707099) (xy 49.42354 -417.742814) (xy 49.377659 -417.7723) (xy 49.328049 -417.794957)
			(xy 49.275719 -417.810322) (xy 49.221735 -417.818084) (xy 49.167197 -417.818084) (xy 49.113213 -417.810322)
			(xy 49.060883 -417.794957) (xy 49.011273 -417.7723) (xy 48.965392 -417.742814) (xy 48.924175 -417.707099)
			(xy 48.88846 -417.665882) (xy 48.858974 -417.620001) (xy 48.836317 -417.570391) (xy 48.820952 -417.518061)
			(xy 48.81319 -417.464077) (xy 48.812704 -417.436808) (xy 36.595812 -417.436808) (xy 36.595812 -417.465002)
			(xy 36.595326 -417.492253) (xy 36.58757 -417.546201) (xy 36.572215 -417.598496) (xy 36.549573 -417.648073)
			(xy 36.520107 -417.693923) (xy 36.484416 -417.735114) (xy 36.443225 -417.770805) (xy 36.397375 -417.800271)
			(xy 36.347798 -417.822913) (xy 36.295503 -417.838268) (xy 36.241555 -417.846024) (xy 36.187053 -417.846024)
			(xy 36.133105 -417.838268) (xy 36.08081 -417.822913) (xy 36.031233 -417.800271) (xy 35.985383 -417.770805)
			(xy 35.944192 -417.735114) (xy 35.908501 -417.693923) (xy 35.879035 -417.648073) (xy 35.856393 -417.598496)
			(xy 35.841038 -417.546201) (xy 35.833282 -417.492253) (xy 35.832796 -417.465002) (xy 7.00913 -417.465002)
			(xy 7.00913 -419.64102) (xy 51.809904 -419.64102) (xy 51.809904 -418.77742) (xy 51.81039 -418.750151)
			(xy 51.818152 -418.696167) (xy 51.833517 -418.643837) (xy 51.856174 -418.594227) (xy 51.88566 -418.548346)
			(xy 51.921375 -418.507129) (xy 51.962592 -418.471414) (xy 52.008473 -418.441928) (xy 52.058083 -418.419271)
			(xy 52.110413 -418.403906) (xy 52.164397 -418.396144) (xy 52.218935 -418.396144) (xy 52.272919 -418.403906)
			(xy 52.325249 -418.419271) (xy 52.374859 -418.441928) (xy 52.42074 -418.471414) (xy 52.461957 -418.507129)
			(xy 52.497672 -418.548346) (xy 52.527158 -418.594227) (xy 52.549815 -418.643837) (xy 52.56518 -418.696167)
			(xy 52.572942 -418.750151) (xy 52.573428 -418.77742) (xy 52.573428 -419.64102) (xy 52.572942 -419.668289)
			(xy 52.56518 -419.722273) (xy 52.549815 -419.774603) (xy 52.527158 -419.824213) (xy 52.497672 -419.870094)
			(xy 52.461957 -419.911311) (xy 52.42074 -419.947026) (xy 52.374859 -419.976512) (xy 52.325249 -419.999169)
			(xy 52.272919 -420.014534) (xy 52.218935 -420.022296) (xy 52.164397 -420.022296) (xy 52.110413 -420.014534)
			(xy 52.058083 -419.999169) (xy 52.008473 -419.976512) (xy 51.962592 -419.947026) (xy 51.921375 -419.911311)
			(xy 51.88566 -419.870094) (xy 51.856174 -419.824213) (xy 51.833517 -419.774603) (xy 51.818152 -419.722273)
			(xy 51.81039 -419.668289) (xy 51.809904 -419.64102) (xy 7.00913 -419.64102) (xy 7.00913 -421.200326)
			(xy 10.01268 -421.200326) (xy 10.01268 -420.336726) (xy 10.013166 -420.309475) (xy 10.020922 -420.255527)
			(xy 10.036277 -420.203232) (xy 10.058919 -420.153655) (xy 10.088385 -420.107805) (xy 10.124076 -420.066614)
			(xy 10.165267 -420.030923) (xy 10.211117 -420.001457) (xy 10.260694 -419.978815) (xy 10.312989 -419.96346)
			(xy 10.366937 -419.955704) (xy 10.421439 -419.955704) (xy 10.475387 -419.96346) (xy 10.527682 -419.978815)
			(xy 10.577259 -420.001457) (xy 10.623109 -420.030923) (xy 10.6643 -420.066614) (xy 10.699991 -420.107805)
			(xy 10.729457 -420.153655) (xy 10.752099 -420.203232) (xy 10.767454 -420.255527) (xy 10.77521 -420.309475)
			(xy 10.775696 -420.336726) (xy 10.775696 -421.200326) (xy 10.77521 -421.227577) (xy 10.769122 -421.269922)
			(xy 21.420836 -421.269922) (xy 21.420836 -420.406322) (xy 21.421322 -420.379071) (xy 21.429078 -420.325123)
			(xy 21.444433 -420.272828) (xy 21.467075 -420.223251) (xy 21.496541 -420.177401) (xy 21.532232 -420.13621)
			(xy 21.573423 -420.100519) (xy 21.619273 -420.071053) (xy 21.66885 -420.048411) (xy 21.721145 -420.033056)
			(xy 21.775093 -420.0253) (xy 21.829595 -420.0253) (xy 21.883543 -420.033056) (xy 21.935838 -420.048411)
			(xy 21.985415 -420.071053) (xy 22.031265 -420.100519) (xy 22.072456 -420.13621) (xy 22.108147 -420.177401)
			(xy 22.137613 -420.223251) (xy 22.160255 -420.272828) (xy 22.17561 -420.325123) (xy 22.183366 -420.379071)
			(xy 22.183852 -420.406322) (xy 22.183852 -420.760398) (xy 58.141108 -420.760398) (xy 58.141108 -418.218874)
			(xy 58.141589 -418.206761) (xy 58.14908 -418.183722) (xy 58.16332 -418.164123) (xy 58.182918 -418.149882)
			(xy 58.205957 -418.14239) (xy 58.21807 -418.141912) (xy 59.15787 -418.141912) (xy 59.169989 -418.142385)
			(xy 59.193042 -418.149866) (xy 59.212655 -418.164105) (xy 59.226908 -418.183708) (xy 59.234406 -418.206756)
			(xy 59.234832 -418.218874) (xy 59.234832 -420.760398) (xy 59.234438 -420.772524) (xy 59.226942 -420.795587)
			(xy 59.212685 -420.815205) (xy 59.193062 -420.829455) (xy 59.169996 -420.836942) (xy 59.15787 -420.83736)
			(xy 58.21807 -420.83736) (xy 58.205954 -420.836914) (xy 58.182909 -420.829418) (xy 58.163308 -420.81517)
			(xy 58.149067 -420.795562) (xy 58.141581 -420.772515) (xy 58.141108 -420.760398) (xy 22.183852 -420.760398)
			(xy 22.183852 -421.269922) (xy 22.183366 -421.297173) (xy 22.17561 -421.351121) (xy 22.160255 -421.403416)
			(xy 22.137613 -421.452993) (xy 22.108147 -421.498843) (xy 22.072456 -421.540034) (xy 22.031265 -421.575725)
			(xy 21.985415 -421.605191) (xy 21.935838 -421.627833) (xy 21.883543 -421.643188) (xy 21.829595 -421.650944)
			(xy 21.775093 -421.650944) (xy 21.721145 -421.643188) (xy 21.66885 -421.627833) (xy 21.619273 -421.605191)
			(xy 21.573423 -421.575725) (xy 21.532232 -421.540034) (xy 21.496541 -421.498843) (xy 21.467075 -421.452993)
			(xy 21.444433 -421.403416) (xy 21.429078 -421.351121) (xy 21.421322 -421.297173) (xy 21.420836 -421.269922)
			(xy 10.769122 -421.269922) (xy 10.767454 -421.281525) (xy 10.752099 -421.33382) (xy 10.729457 -421.383397)
			(xy 10.699991 -421.429247) (xy 10.6643 -421.470438) (xy 10.623109 -421.506129) (xy 10.577259 -421.535595)
			(xy 10.527682 -421.558237) (xy 10.475387 -421.573592) (xy 10.421439 -421.581348) (xy 10.366937 -421.581348)
			(xy 10.312989 -421.573592) (xy 10.260694 -421.558237) (xy 10.211117 -421.535595) (xy 10.165267 -421.506129)
			(xy 10.124076 -421.470438) (xy 10.088385 -421.429247) (xy 10.058919 -421.383397) (xy 10.036277 -421.33382)
			(xy 10.020922 -421.281525) (xy 10.013166 -421.227577) (xy 10.01268 -421.200326) (xy 7.00913 -421.200326)
			(xy 7.00913 -422.130474) (xy 24.87676 -422.130474) (xy 24.87676 -421.266874) (xy 24.877246 -421.239605)
			(xy 24.885008 -421.185621) (xy 24.900373 -421.133291) (xy 24.92303 -421.083681) (xy 24.952516 -421.0378)
			(xy 24.988231 -420.996583) (xy 25.029448 -420.960868) (xy 25.075329 -420.931382) (xy 25.124939 -420.908725)
			(xy 25.177269 -420.89336) (xy 25.231253 -420.885598) (xy 25.285791 -420.885598) (xy 25.339775 -420.89336)
			(xy 25.392105 -420.908725) (xy 25.441715 -420.931382) (xy 25.487596 -420.960868) (xy 25.528813 -420.996583)
			(xy 25.564528 -421.0378) (xy 25.594014 -421.083681) (xy 25.616671 -421.133291) (xy 25.632036 -421.185621)
			(xy 25.639798 -421.239605) (xy 25.640284 -421.266874) (xy 25.640284 -421.726974) (xy 27.323192 -421.726974)
			(xy 27.323192 -421.672426) (xy 27.330955 -421.618434) (xy 27.346324 -421.566097) (xy 27.368985 -421.51648)
			(xy 27.398477 -421.470593) (xy 27.4342 -421.429371) (xy 27.475427 -421.393652) (xy 27.521317 -421.364165)
			(xy 27.570936 -421.341509) (xy 27.623276 -421.326146) (xy 27.677268 -421.318389) (xy 27.704542 -421.317928)
			(xy 28.568142 -421.317928) (xy 28.595409 -421.318437) (xy 28.649386 -421.326204) (xy 28.701709 -421.341572)
			(xy 28.751313 -421.36423) (xy 28.797187 -421.393716) (xy 28.838399 -421.429431) (xy 28.874109 -421.470646)
			(xy 28.90359 -421.516524) (xy 28.926243 -421.56613) (xy 28.941605 -421.618455) (xy 28.949366 -421.672433)
			(xy 28.949366 -421.726967) (xy 28.941605 -421.780945) (xy 28.926243 -421.83327) (xy 28.90359 -421.882876)
			(xy 28.874109 -421.928754) (xy 28.838399 -421.969969) (xy 28.797187 -422.005684) (xy 28.751313 -422.03517)
			(xy 28.701709 -422.057828) (xy 28.649386 -422.073196) (xy 28.595409 -422.080963) (xy 28.568142 -422.081452)
			(xy 27.704542 -422.081452) (xy 27.677268 -422.081011) (xy 27.623276 -422.073254) (xy 27.570936 -422.057891)
			(xy 27.521317 -422.035235) (xy 27.475427 -422.005748) (xy 27.4342 -421.970029) (xy 27.398477 -421.928807)
			(xy 27.368985 -421.88292) (xy 27.346324 -421.833303) (xy 27.330955 -421.780966) (xy 27.323192 -421.726974)
			(xy 25.640284 -421.726974) (xy 25.640284 -422.130474) (xy 25.639798 -422.157743) (xy 25.632036 -422.211727)
			(xy 25.616671 -422.264057) (xy 25.594014 -422.313667) (xy 25.564528 -422.359548) (xy 25.528813 -422.400765)
			(xy 25.487596 -422.43648) (xy 25.441715 -422.465966) (xy 25.392105 -422.488623) (xy 25.339775 -422.503988)
			(xy 25.285791 -422.51175) (xy 25.231253 -422.51175) (xy 25.177269 -422.503988) (xy 25.124939 -422.488623)
			(xy 25.075329 -422.465966) (xy 25.029448 -422.43648) (xy 24.988231 -422.400765) (xy 24.952516 -422.359548)
			(xy 24.92303 -422.313667) (xy 24.900373 -422.264057) (xy 24.885008 -422.211727) (xy 24.877246 -422.157743)
			(xy 24.87676 -422.130474) (xy 7.00913 -422.130474) (xy 7.00913 -422.66627) (xy 38.762906 -422.66627)
			(xy 38.762906 -422.61173) (xy 38.770668 -422.557744) (xy 38.786034 -422.505412) (xy 38.808691 -422.4558)
			(xy 38.838178 -422.409918) (xy 38.873894 -422.368698) (xy 38.915113 -422.332981) (xy 38.960995 -422.303494)
			(xy 39.010607 -422.280836) (xy 39.062938 -422.26547) (xy 39.116924 -422.257707) (xy 39.144194 -422.25722)
			(xy 40.007794 -422.25722) (xy 40.035064 -422.257719) (xy 40.089049 -422.26548) (xy 40.14138 -422.280845)
			(xy 40.190991 -422.303501) (xy 40.236874 -422.332987) (xy 40.278093 -422.368703) (xy 40.313809 -422.409921)
			(xy 40.343296 -422.455803) (xy 40.365953 -422.505414) (xy 40.381319 -422.557745) (xy 40.389081 -422.61173)
			(xy 40.389081 -422.66627) (xy 40.381319 -422.720255) (xy 40.365953 -422.772586) (xy 40.343296 -422.822197)
			(xy 40.313809 -422.868079) (xy 40.278093 -422.909297) (xy 40.236874 -422.945013) (xy 40.190991 -422.974499)
			(xy 40.14138 -422.997155) (xy 40.089049 -423.01252) (xy 40.035064 -423.020281) (xy 40.007794 -423.020744)
			(xy 39.144194 -423.020744) (xy 39.116924 -423.020293) (xy 39.062938 -423.01253) (xy 39.010607 -422.997164)
			(xy 38.960995 -422.974506) (xy 38.915113 -422.945019) (xy 38.873894 -422.909302) (xy 38.838178 -422.868082)
			(xy 38.808691 -422.8222) (xy 38.786034 -422.772588) (xy 38.770668 -422.720256) (xy 38.762906 -422.66627)
			(xy 7.00913 -422.66627) (xy 7.00913 -423.057828) (xy 41.652952 -423.057828) (xy 41.652952 -422.194228)
			(xy 41.653438 -422.166959) (xy 41.6612 -422.112975) (xy 41.676565 -422.060645) (xy 41.699222 -422.011035)
			(xy 41.728708 -421.965154) (xy 41.764423 -421.923937) (xy 41.80564 -421.888222) (xy 41.851521 -421.858736)
			(xy 41.901131 -421.836079) (xy 41.953461 -421.820714) (xy 42.007445 -421.812952) (xy 42.061983 -421.812952)
			(xy 42.115967 -421.820714) (xy 42.168297 -421.836079) (xy 42.217907 -421.858736) (xy 42.263788 -421.888222)
			(xy 42.305005 -421.923937) (xy 42.34072 -421.965154) (xy 42.370206 -422.011035) (xy 42.392863 -422.060645)
			(xy 42.408228 -422.112975) (xy 42.41599 -422.166959) (xy 42.416476 -422.194228) (xy 42.416476 -423.057828)
			(xy 42.41599 -423.085097) (xy 42.408228 -423.139081) (xy 42.392863 -423.191411) (xy 42.370206 -423.241021)
			(xy 42.34072 -423.286902) (xy 42.305005 -423.328119) (xy 42.263788 -423.363834) (xy 42.217907 -423.39332)
			(xy 42.168297 -423.415977) (xy 42.115967 -423.431342) (xy 42.061983 -423.439104) (xy 42.007445 -423.439104)
			(xy 41.953461 -423.431342) (xy 41.901131 -423.415977) (xy 41.851521 -423.39332) (xy 41.80564 -423.363834)
			(xy 41.764423 -423.328119) (xy 41.728708 -423.286902) (xy 41.699222 -423.241021) (xy 41.676565 -423.191411)
			(xy 41.6612 -423.139081) (xy 41.653438 -423.085097) (xy 41.652952 -423.057828) (xy 7.00913 -423.057828)
			(xy 7.00913 -425.887642) (xy 10.204704 -425.887642) (xy 10.204704 -425.024042) (xy 10.20519 -424.996773)
			(xy 10.212952 -424.942789) (xy 10.228317 -424.890459) (xy 10.250974 -424.840849) (xy 10.28046 -424.794968)
			(xy 10.316175 -424.753751) (xy 10.357392 -424.718036) (xy 10.403273 -424.68855) (xy 10.452883 -424.665893)
			(xy 10.505213 -424.650528) (xy 10.559197 -424.642766) (xy 10.613735 -424.642766) (xy 10.667719 -424.650528)
			(xy 10.720049 -424.665893) (xy 10.769659 -424.68855) (xy 10.81554 -424.718036) (xy 10.856757 -424.753751)
			(xy 10.892472 -424.794968) (xy 10.921958 -424.840849) (xy 10.944615 -424.890459) (xy 10.95998 -424.942789)
			(xy 10.967742 -424.996773) (xy 10.968228 -425.024042) (xy 10.968228 -425.328334) (xy 21.942552 -425.328334)
			(xy 21.942552 -424.464734) (xy 21.943038 -424.437465) (xy 21.9508 -424.383481) (xy 21.966165 -424.331151)
			(xy 21.988822 -424.281541) (xy 22.018308 -424.23566) (xy 22.054023 -424.194443) (xy 22.09524 -424.158728)
			(xy 22.141121 -424.129242) (xy 22.190731 -424.106585) (xy 22.243061 -424.09122) (xy 22.297045 -424.083458)
			(xy 22.351583 -424.083458) (xy 22.405567 -424.09122) (xy 22.457897 -424.106585) (xy 22.507507 -424.129242)
			(xy 22.553388 -424.158728) (xy 22.594605 -424.194443) (xy 22.63032 -424.23566) (xy 22.659806 -424.281541)
			(xy 22.682463 -424.331151) (xy 22.691108 -424.360594) (xy 58.141108 -424.360594) (xy 58.141108 -421.81907)
			(xy 58.141586 -421.806957) (xy 58.149077 -421.783918) (xy 58.163319 -421.764319) (xy 58.182918 -421.750077)
			(xy 58.205957 -421.742586) (xy 58.21807 -421.742108) (xy 59.15787 -421.742108) (xy 59.16998 -421.742637)
			(xy 59.193017 -421.750112) (xy 59.207184 -421.760396) (xy 60.141104 -421.760396) (xy 60.141104 -419.218872)
			(xy 60.141536 -419.20682) (xy 60.148977 -419.183893) (xy 60.163125 -419.164377) (xy 60.182601 -419.150175)
			(xy 60.205507 -419.14267) (xy 60.217558 -419.142164) (xy 61.157866 -419.142164) (xy 61.169956 -419.142637)
			(xy 61.19296 -419.150087) (xy 61.212542 -419.164271) (xy 61.226793 -419.183805) (xy 61.234322 -419.206783)
			(xy 61.234828 -419.218872) (xy 61.234828 -421.760396) (xy 61.234337 -421.772443) (xy 61.226909 -421.795364)
			(xy 61.212775 -421.814877) (xy 61.193313 -421.829082) (xy 61.170419 -421.836593) (xy 61.158374 -421.837104)
			(xy 60.218066 -421.837104) (xy 60.205979 -421.836623) (xy 60.182985 -421.829162) (xy 60.163409 -421.814977)
			(xy 60.149158 -421.79545) (xy 60.141619 -421.772481) (xy 60.141104 -421.760396) (xy 59.207184 -421.760396)
			(xy 59.212617 -421.76434) (xy 59.22686 -421.783929) (xy 59.234354 -421.80696) (xy 59.234832 -421.81907)
			(xy 59.234832 -424.360594) (xy 62.1411 -424.360594) (xy 62.1411 -421.81907) (xy 62.141585 -421.806958)
			(xy 62.149076 -421.78392) (xy 62.163316 -421.764322) (xy 62.182913 -421.75008) (xy 62.20595 -421.742587)
			(xy 62.218062 -421.742108) (xy 63.157862 -421.742108) (xy 63.16998 -421.742592) (xy 63.193032 -421.75007)
			(xy 63.207258 -421.760396) (xy 68.141088 -421.760396) (xy 68.141088 -419.218872) (xy 68.141536 -419.206822)
			(xy 68.148975 -419.183897) (xy 68.163119 -419.164383) (xy 68.182591 -419.15018) (xy 68.205493 -419.142672)
			(xy 68.217542 -419.142164) (xy 69.15785 -419.142164) (xy 69.169939 -419.14265) (xy 69.192942 -419.150096)
			(xy 69.212525 -419.164277) (xy 69.226777 -419.183808) (xy 69.234306 -419.206784) (xy 69.234812 -419.218872)
			(xy 69.234812 -420.760398) (xy 70.141084 -420.760398) (xy 70.141084 -418.218874) (xy 70.141438 -418.206745)
			(xy 70.148943 -418.183678) (xy 70.16321 -418.164059) (xy 70.182842 -418.14981) (xy 70.205917 -418.142327)
			(xy 70.218046 -418.141912) (xy 71.157846 -418.141912) (xy 71.16996 -418.142372) (xy 71.193001 -418.149869)
			(xy 71.212599 -418.164115) (xy 71.22684 -418.183717) (xy 71.234331 -418.20676) (xy 71.234808 -418.218874)
			(xy 71.234808 -418.3761) (xy 77.661008 -418.3761) (xy 77.661008 -417.5125) (xy 77.661494 -417.485231)
			(xy 77.669256 -417.431247) (xy 77.684621 -417.378917) (xy 77.707278 -417.329307) (xy 77.736764 -417.283426)
			(xy 77.772479 -417.242209) (xy 77.813696 -417.206494) (xy 77.859577 -417.177008) (xy 77.909187 -417.154351)
			(xy 77.961517 -417.138986) (xy 78.015501 -417.131224) (xy 78.070039 -417.131224) (xy 78.124023 -417.138986)
			(xy 78.176353 -417.154351) (xy 78.225963 -417.177008) (xy 78.271844 -417.206494) (xy 78.313061 -417.242209)
			(xy 78.348776 -417.283426) (xy 78.378262 -417.329307) (xy 78.400919 -417.378917) (xy 78.416284 -417.431247)
			(xy 78.424046 -417.485231) (xy 78.424532 -417.5125) (xy 78.424532 -418.3761) (xy 78.424046 -418.403369)
			(xy 78.416284 -418.457353) (xy 78.400919 -418.509683) (xy 78.378262 -418.559293) (xy 78.348776 -418.605174)
			(xy 78.313061 -418.646391) (xy 78.271844 -418.682106) (xy 78.225963 -418.711592) (xy 78.176353 -418.734249)
			(xy 78.124023 -418.749614) (xy 78.070039 -418.757376) (xy 78.015501 -418.757376) (xy 77.961517 -418.749614)
			(xy 77.909187 -418.734249) (xy 77.859577 -418.711592) (xy 77.813696 -418.682106) (xy 77.772479 -418.646391)
			(xy 77.736764 -418.605174) (xy 77.707278 -418.559293) (xy 77.684621 -418.509683) (xy 77.669256 -418.457353)
			(xy 77.661494 -418.403369) (xy 77.661008 -418.3761) (xy 71.234808 -418.3761) (xy 71.234808 -420.760398)
			(xy 71.234287 -420.772508) (xy 71.226806 -420.795543) (xy 71.212575 -420.815141) (xy 71.192986 -420.829384)
			(xy 71.169956 -420.83688) (xy 71.157846 -420.83736) (xy 70.218046 -420.83736) (xy 70.205925 -420.836901)
			(xy 70.182868 -420.829421) (xy 70.163252 -420.81518) (xy 70.148999 -420.795572) (xy 70.141506 -420.772518)
			(xy 70.141084 -420.760398) (xy 69.234812 -420.760398) (xy 69.234812 -421.760396) (xy 69.234337 -421.772445)
			(xy 69.226907 -421.795368) (xy 69.212769 -421.814883) (xy 69.193303 -421.829087) (xy 69.170405 -421.836595)
			(xy 69.158358 -421.837104) (xy 68.21805 -421.837104) (xy 68.205967 -421.836551) (xy 68.182976 -421.829113)
			(xy 68.163399 -421.814947) (xy 68.149145 -421.795434) (xy 68.141604 -421.772476) (xy 68.141088 -421.760396)
			(xy 63.207258 -421.760396) (xy 63.212645 -421.764306) (xy 63.226899 -421.783907) (xy 63.234398 -421.806953)
			(xy 63.234824 -421.81907) (xy 63.234824 -424.360594) (xy 63.234434 -424.37272) (xy 63.226939 -424.395785)
			(xy 63.212681 -424.415404) (xy 63.193057 -424.429654) (xy 63.169988 -424.437139) (xy 63.157862 -424.437556)
			(xy 62.218062 -424.437556) (xy 62.205945 -424.437121) (xy 62.182899 -424.429622) (xy 62.163298 -424.415371)
			(xy 62.149058 -424.395761) (xy 62.141572 -424.372711) (xy 62.1411 -424.360594) (xy 59.234832 -424.360594)
			(xy 59.234434 -424.372719) (xy 59.22694 -424.395783) (xy 59.212684 -424.415401) (xy 59.193062 -424.429651)
			(xy 59.169996 -424.437138) (xy 59.15787 -424.437556) (xy 58.21807 -424.437556) (xy 58.205953 -424.437114)
			(xy 58.182908 -424.429618) (xy 58.163306 -424.415368) (xy 58.149066 -424.39576) (xy 58.14158 -424.372711)
			(xy 58.141108 -424.360594) (xy 22.691108 -424.360594) (xy 22.697828 -424.383481) (xy 22.70559 -424.437465)
			(xy 22.706076 -424.464734) (xy 22.706076 -425.328334) (xy 22.70559 -425.355603) (xy 22.697828 -425.409587)
			(xy 22.682463 -425.461917) (xy 22.659806 -425.511527) (xy 22.63032 -425.557408) (xy 22.594605 -425.598625)
			(xy 22.553388 -425.63434) (xy 22.507507 -425.663826) (xy 22.457897 -425.686483) (xy 22.405567 -425.701848)
			(xy 22.351583 -425.70961) (xy 22.297045 -425.70961) (xy 22.243061 -425.701848) (xy 22.190731 -425.686483)
			(xy 22.141121 -425.663826) (xy 22.09524 -425.63434) (xy 22.054023 -425.598625) (xy 22.018308 -425.557408)
			(xy 21.988822 -425.511527) (xy 21.966165 -425.461917) (xy 21.9508 -425.409587) (xy 21.943038 -425.355603)
			(xy 21.942552 -425.328334) (xy 10.968228 -425.328334) (xy 10.968228 -425.887642) (xy 10.967742 -425.914911)
			(xy 10.964527 -425.937273) (xy 38.737196 -425.937273) (xy 38.737196 -425.882727) (xy 38.744959 -425.828736)
			(xy 38.760327 -425.776399) (xy 38.782988 -425.726782) (xy 38.81248 -425.680896) (xy 38.848202 -425.639674)
			(xy 38.889428 -425.603956) (xy 38.935317 -425.574469) (xy 38.984936 -425.551813) (xy 39.037275 -425.53645)
			(xy 39.091267 -425.528693) (xy 39.11854 -425.528232) (xy 39.98214 -425.528232) (xy 40.009407 -425.528733)
			(xy 40.063385 -425.536499) (xy 40.115709 -425.551868) (xy 40.165314 -425.574526) (xy 40.211189 -425.604012)
			(xy 40.252401 -425.639727) (xy 40.288112 -425.680943) (xy 40.317593 -425.726821) (xy 40.340246 -425.776428)
			(xy 40.355609 -425.828754) (xy 40.36337 -425.882733) (xy 40.36337 -425.937267) (xy 40.355609 -425.991246)
			(xy 40.340246 -426.043572) (xy 40.317593 -426.093179) (xy 40.288112 -426.139057) (xy 40.252401 -426.180273)
			(xy 40.211189 -426.215988) (xy 40.165314 -426.245474) (xy 40.115709 -426.268132) (xy 40.063385 -426.283501)
			(xy 40.009407 -426.291267) (xy 39.98214 -426.291756) (xy 39.11854 -426.291756) (xy 39.091267 -426.291307)
			(xy 39.037275 -426.28355) (xy 38.984936 -426.268187) (xy 38.935317 -426.245531) (xy 38.889428 -426.216044)
			(xy 38.848202 -426.180326) (xy 38.81248 -426.139104) (xy 38.782988 -426.093218) (xy 38.760327 -426.043601)
			(xy 38.744959 -425.991264) (xy 38.737196 -425.937273) (xy 10.964527 -425.937273) (xy 10.95998 -425.968895)
			(xy 10.944615 -426.021225) (xy 10.921958 -426.070835) (xy 10.892472 -426.116716) (xy 10.856757 -426.157933)
			(xy 10.81554 -426.193648) (xy 10.769659 -426.223134) (xy 10.720049 -426.245791) (xy 10.667719 -426.261156)
			(xy 10.613735 -426.268918) (xy 10.559197 -426.268918) (xy 10.505213 -426.261156) (xy 10.452883 -426.245791)
			(xy 10.403273 -426.223134) (xy 10.357392 -426.193648) (xy 10.316175 -426.157933) (xy 10.28046 -426.116716)
			(xy 10.250974 -426.070835) (xy 10.228317 -426.021225) (xy 10.212952 -425.968895) (xy 10.20519 -425.914911)
			(xy 10.204704 -425.887642) (xy 7.00913 -425.887642) (xy 7.00913 -426.333158) (xy 41.613836 -426.333158)
			(xy 41.613836 -425.469558) (xy 41.614322 -425.442307) (xy 41.622078 -425.388359) (xy 41.637433 -425.336064)
			(xy 41.660075 -425.286487) (xy 41.689541 -425.240637) (xy 41.725232 -425.199446) (xy 41.766423 -425.163755)
			(xy 41.812273 -425.134289) (xy 41.86185 -425.111647) (xy 41.914145 -425.096292) (xy 41.968093 -425.088536)
			(xy 42.022595 -425.088536) (xy 42.076543 -425.096292) (xy 42.128838 -425.111647) (xy 42.178415 -425.134289)
			(xy 42.224265 -425.163755) (xy 42.265456 -425.199446) (xy 42.301147 -425.240637) (xy 42.330613 -425.286487)
			(xy 42.353255 -425.336064) (xy 42.36861 -425.388359) (xy 42.376366 -425.442307) (xy 42.376852 -425.469558)
			(xy 42.376852 -426.333158) (xy 42.376366 -426.360409) (xy 42.36861 -426.414357) (xy 42.353255 -426.466652)
			(xy 42.330613 -426.516229) (xy 42.301147 -426.562079) (xy 42.265456 -426.60327) (xy 42.224265 -426.638961)
			(xy 42.178415 -426.668427) (xy 42.128838 -426.691069) (xy 42.076543 -426.706424) (xy 42.022595 -426.71418)
			(xy 41.968093 -426.71418) (xy 41.914145 -426.706424) (xy 41.86185 -426.691069) (xy 41.812273 -426.668427)
			(xy 41.766423 -426.638961) (xy 41.725232 -426.60327) (xy 41.689541 -426.562079) (xy 41.660075 -426.516229)
			(xy 41.637433 -426.466652) (xy 41.622078 -426.414357) (xy 41.614322 -426.360409) (xy 41.613836 -426.333158)
			(xy 7.00913 -426.333158) (xy 7.00913 -428.615602) (xy 25.13076 -428.615602) (xy 25.13076 -427.752002)
			(xy 25.131246 -427.724733) (xy 25.139008 -427.670749) (xy 25.154373 -427.618419) (xy 25.17703 -427.568809)
			(xy 25.206516 -427.522928) (xy 25.242231 -427.481711) (xy 25.283448 -427.445996) (xy 25.329329 -427.41651)
			(xy 25.378939 -427.393853) (xy 25.431269 -427.378488) (xy 25.485253 -427.370726) (xy 25.539791 -427.370726)
			(xy 25.593775 -427.378488) (xy 25.646105 -427.393853) (xy 25.695715 -427.41651) (xy 25.741596 -427.445996)
			(xy 25.782813 -427.481711) (xy 25.818528 -427.522928) (xy 25.848014 -427.568809) (xy 25.870671 -427.618419)
			(xy 25.886036 -427.670749) (xy 25.893798 -427.724733) (xy 25.894284 -427.752002) (xy 25.894284 -428.211072)
			(xy 26.941204 -428.211072) (xy 26.941204 -428.156528) (xy 26.948966 -428.102539) (xy 26.964334 -428.050205)
			(xy 26.986993 -428.00059) (xy 27.016483 -427.954705) (xy 27.052203 -427.913485) (xy 27.093426 -427.877767)
			(xy 27.139313 -427.848281) (xy 27.188929 -427.825625) (xy 27.241265 -427.810261) (xy 27.295254 -427.802502)
			(xy 27.322526 -427.80204) (xy 28.186126 -427.80204) (xy 28.213394 -427.802524) (xy 28.267375 -427.810289)
			(xy 28.319702 -427.825657) (xy 28.369309 -427.848314) (xy 28.415187 -427.877801) (xy 28.456402 -427.913517)
			(xy 28.492114 -427.954734) (xy 28.495843 -427.960536) (xy 58.141108 -427.960536) (xy 58.141108 -425.419012)
			(xy 58.14157 -425.406962) (xy 58.149001 -425.384035) (xy 58.163141 -425.364518) (xy 58.182611 -425.350315)
			(xy 58.205513 -425.34281) (xy 58.217562 -425.342304) (xy 59.15787 -425.342304) (xy 59.169954 -425.342832)
			(xy 59.192948 -425.350276) (xy 59.212525 -425.364448) (xy 59.226778 -425.383967) (xy 59.234317 -425.40693)
			(xy 59.234832 -425.419012) (xy 59.234832 -427.960536) (xy 59.234372 -427.972585) (xy 59.226933 -427.995506)
			(xy 59.212791 -428.015019) (xy 59.193323 -428.029222) (xy 59.170425 -428.036733) (xy 59.158378 -428.037244)
			(xy 58.21807 -428.037244) (xy 58.205977 -428.036818) (xy 58.182973 -428.029351) (xy 58.163392 -428.015154)
			(xy 58.149143 -427.995612) (xy 58.141615 -427.972627) (xy 58.141108 -427.960536) (xy 28.495843 -427.960536)
			(xy 28.521598 -428.000614) (xy 28.544253 -428.050222) (xy 28.559617 -428.10255) (xy 28.567378 -428.156532)
			(xy 28.567378 -428.211068) (xy 28.559617 -428.26505) (xy 28.544253 -428.317378) (xy 28.521598 -428.366986)
			(xy 28.492114 -428.412866) (xy 28.456402 -428.454083) (xy 28.415187 -428.489799) (xy 28.369309 -428.519286)
			(xy 28.319702 -428.541943) (xy 28.267375 -428.557311) (xy 28.213394 -428.565076) (xy 28.186126 -428.565564)
			(xy 27.322526 -428.565564) (xy 27.295254 -428.565098) (xy 27.241265 -428.557339) (xy 27.188929 -428.541975)
			(xy 27.139313 -428.519319) (xy 27.093426 -428.489833) (xy 27.052203 -428.454115) (xy 27.016483 -428.412895)
			(xy 26.986993 -428.36701) (xy 26.964334 -428.317395) (xy 26.948966 -428.265061) (xy 26.941204 -428.211072)
			(xy 25.894284 -428.211072) (xy 25.894284 -428.615602) (xy 25.893798 -428.642871) (xy 25.886036 -428.696855)
			(xy 25.870671 -428.749185) (xy 25.848014 -428.798795) (xy 25.818528 -428.844676) (xy 25.782813 -428.885893)
			(xy 25.741596 -428.921608) (xy 25.695715 -428.951094) (xy 25.646105 -428.973751) (xy 25.593775 -428.989116)
			(xy 25.539791 -428.996878) (xy 25.485253 -428.996878) (xy 25.431269 -428.989116) (xy 25.378939 -428.973751)
			(xy 25.329329 -428.951094) (xy 25.283448 -428.921608) (xy 25.242231 -428.885893) (xy 25.206516 -428.844676)
			(xy 25.17703 -428.798795) (xy 25.154373 -428.749185) (xy 25.139008 -428.696855) (xy 25.131246 -428.642871)
			(xy 25.13076 -428.615602) (xy 7.00913 -428.615602) (xy 7.00913 -431.560478) (xy 58.141108 -431.560478)
			(xy 58.141108 -430.83353) (xy 58.141421 -430.82476) (xy 58.145529 -430.807702) (xy 58.149236 -430.799748)
			(xy 58.149236 -430.79924) (xy 58.382662 -430.323244) (xy 58.387387 -430.312737) (xy 58.390865 -430.289973)
			(xy 58.387371 -430.267211) (xy 58.382662 -430.256696) (xy 58.149236 -429.7807) (xy 58.149236 -429.780192)
			(xy 58.145507 -429.772245) (xy 58.141403 -429.755183) (xy 58.141108 -429.74641) (xy 58.141108 -429.018954)
			(xy 58.141572 -429.00684) (xy 58.149068 -428.9838) (xy 58.163313 -428.964202) (xy 58.182915 -428.949961)
			(xy 58.205956 -428.94247) (xy 58.21807 -428.941992) (xy 59.15787 -428.941992) (xy 59.169978 -428.942537)
			(xy 59.193013 -428.95001) (xy 59.207512 -428.960534) (xy 60.141104 -428.960534) (xy 60.141104 -426.41901)
			(xy 60.14162 -426.406899) (xy 60.1491 -426.383862) (xy 60.163332 -426.364263) (xy 60.182923 -426.35002)
			(xy 60.205956 -426.342527) (xy 60.218066 -426.342048) (xy 61.157866 -426.342048) (xy 61.169988 -426.342489)
			(xy 61.193047 -426.349973) (xy 61.212664 -426.364219) (xy 61.226916 -426.383831) (xy 61.234407 -426.406888)
			(xy 61.234828 -426.41901) (xy 61.234828 -427.960536) (xy 62.1411 -427.960536) (xy 62.1411 -425.419012)
			(xy 62.14157 -425.406962) (xy 62.149 -425.384037) (xy 62.163138 -425.364521) (xy 62.182606 -425.350318)
			(xy 62.205506 -425.342811) (xy 62.217554 -425.342304) (xy 63.157862 -425.342304) (xy 63.169946 -425.342839)
			(xy 63.192939 -425.350281) (xy 63.207185 -425.360592) (xy 64.141096 -425.360592) (xy 64.141096 -422.819068)
			(xy 64.141532 -422.807017) (xy 64.148973 -422.784091) (xy 64.16312 -422.764576) (xy 64.182595 -422.750373)
			(xy 64.2055 -422.742867) (xy 64.21755 -422.74236) (xy 65.157858 -422.74236) (xy 65.169947 -422.742843)
			(xy 65.19295 -422.750291) (xy 65.212532 -422.764473) (xy 65.226784 -422.784004) (xy 65.234313 -422.80698)
			(xy 65.23482 -422.819068) (xy 65.23482 -425.360592) (xy 65.234334 -425.37264) (xy 65.226905 -425.395562)
			(xy 65.212771 -425.415076) (xy 65.193307 -425.42928) (xy 65.170412 -425.43679) (xy 65.158366 -425.4373)
			(xy 64.218058 -425.4373) (xy 64.20597 -425.436829) (xy 64.182975 -425.429366) (xy 64.163399 -425.415179)
			(xy 64.149149 -425.395649) (xy 64.141611 -425.372678) (xy 64.141096 -425.360592) (xy 63.207185 -425.360592)
			(xy 63.212517 -425.364451) (xy 63.22677 -425.383968) (xy 63.234309 -425.40693) (xy 63.234824 -425.419012)
			(xy 63.234824 -427.960536) (xy 63.234371 -427.972586) (xy 63.226932 -427.995508) (xy 63.212788 -428.015022)
			(xy 63.193318 -428.029225) (xy 63.170418 -428.036734) (xy 63.15837 -428.037244) (xy 62.218062 -428.037244)
			(xy 62.205969 -428.036825) (xy 62.182964 -428.029356) (xy 62.163384 -428.015157) (xy 62.149135 -427.995613)
			(xy 62.141607 -427.972628) (xy 62.1411 -427.960536) (xy 61.234828 -427.960536) (xy 61.234828 -428.960534)
			(xy 61.234417 -428.972654) (xy 61.226916 -428.995704) (xy 61.21266 -429.015308) (xy 61.193043 -429.029547)
			(xy 61.169986 -429.037027) (xy 61.157866 -429.037496) (xy 60.218066 -429.037496) (xy 60.205953 -429.037018)
			(xy 60.182914 -429.029525) (xy 60.163316 -429.015284) (xy 60.149075 -428.995686) (xy 60.141582 -428.972647)
			(xy 60.141104 -428.960534) (xy 59.207512 -428.960534) (xy 59.212611 -428.964235) (xy 59.226855 -428.983819)
			(xy 59.234351 -429.006846) (xy 59.234832 -429.018954) (xy 59.234832 -431.560478) (xy 59.234421 -431.572603)
			(xy 59.226931 -431.595666) (xy 59.212678 -431.615284) (xy 59.193059 -431.629535) (xy 59.169995 -431.637022)
			(xy 59.15787 -431.63744) (xy 58.21807 -431.63744) (xy 58.205952 -431.637014) (xy 58.182904 -431.629515)
			(xy 58.163301 -431.615262) (xy 58.149061 -431.59565) (xy 58.141578 -431.572597) (xy 58.141108 -431.560478)
			(xy 7.00913 -431.560478) (xy 7.00913 -435.16042) (xy 58.141108 -435.16042) (xy 58.141108 -432.618896)
			(xy 58.141557 -432.606845) (xy 58.148992 -432.583918) (xy 58.163135 -432.564401) (xy 58.182608 -432.550199)
			(xy 58.205512 -432.542694) (xy 58.217562 -432.542188) (xy 59.15787 -432.542188) (xy 59.169963 -432.542634)
			(xy 59.19297 -432.550088) (xy 59.207307 -432.560476) (xy 60.141104 -432.560476) (xy 60.141104 -431.833528)
			(xy 60.141417 -431.824758) (xy 60.145525 -431.8077) (xy 60.149232 -431.799746) (xy 60.149232 -431.799238)
			(xy 60.382658 -431.323242) (xy 60.387385 -431.312736) (xy 60.390862 -431.289971) (xy 60.387367 -431.267209)
			(xy 60.382658 -431.256694) (xy 60.149232 -430.780698) (xy 60.149232 -430.78019) (xy 60.145503 -430.772244)
			(xy 60.141399 -430.755181) (xy 60.141104 -430.746408) (xy 60.141104 -430.018952) (xy 60.141519 -430.006899)
			(xy 60.148965 -429.983971) (xy 60.163118 -429.964456) (xy 60.182597 -429.950254) (xy 60.205506 -429.94275)
			(xy 60.217558 -429.942244) (xy 61.157866 -429.942244) (xy 61.169954 -429.942736) (xy 61.192954 -429.950184)
			(xy 61.212535 -429.964364) (xy 61.226787 -429.983893) (xy 61.234319 -430.006866) (xy 61.234828 -430.018952)
			(xy 61.234828 -431.560478) (xy 62.1411 -431.560478) (xy 62.1411 -430.83353) (xy 62.141404 -430.824759)
			(xy 62.145517 -430.807701) (xy 62.149228 -430.799748) (xy 62.149228 -430.79924) (xy 62.382654 -430.323244)
			(xy 62.387379 -430.312737) (xy 62.390858 -430.289973) (xy 62.387363 -430.267211) (xy 62.382654 -430.256696)
			(xy 62.149228 -429.7807) (xy 62.149228 -429.780192) (xy 62.145499 -429.772246) (xy 62.141395 -429.755183)
			(xy 62.1411 -429.74641) (xy 62.1411 -429.018954) (xy 62.141572 -429.006841) (xy 62.149067 -428.983803)
			(xy 62.163311 -428.964205) (xy 62.18291 -428.949964) (xy 62.205949 -428.942471) (xy 62.218062 -428.941992)
			(xy 63.157862 -428.941992) (xy 63.16997 -428.942543) (xy 63.193004 -428.950015) (xy 63.207499 -428.960534)
			(xy 64.141096 -428.960534) (xy 64.141096 -426.41901) (xy 64.14162 -426.4069) (xy 64.149099 -426.383864)
			(xy 64.163329 -426.364266) (xy 64.182918 -426.350023) (xy 64.205948 -426.342528) (xy 64.218058 -426.342048)
			(xy 65.157858 -426.342048) (xy 65.16998 -426.342496) (xy 65.193039 -426.349978) (xy 65.212655 -426.364222)
			(xy 65.226908 -426.383833) (xy 65.234399 -426.406889) (xy 65.23482 -426.41901) (xy 65.23482 -427.960536)
			(xy 66.141092 -427.960536) (xy 66.141092 -425.419012) (xy 66.14157 -425.406963) (xy 66.148998 -425.384039)
			(xy 66.163135 -425.364524) (xy 66.182601 -425.35032) (xy 66.205499 -425.342812) (xy 66.217546 -425.342304)
			(xy 67.157854 -425.342304) (xy 67.169938 -425.342846) (xy 67.192931 -425.350286) (xy 67.207172 -425.360592)
			(xy 68.141088 -425.360592) (xy 68.141088 -422.819068) (xy 68.141532 -422.807017) (xy 68.148972 -422.784093)
			(xy 68.163118 -422.764578) (xy 68.18259 -422.750376) (xy 68.205493 -422.742868) (xy 68.217542 -422.74236)
			(xy 69.15785 -422.74236) (xy 69.169939 -422.74285) (xy 69.192941 -422.750296) (xy 69.212524 -422.764475)
			(xy 69.226775 -422.784006) (xy 69.234305 -422.806981) (xy 69.234812 -422.819068) (xy 69.234812 -424.360594)
			(xy 70.141084 -424.360594) (xy 70.141084 -421.81907) (xy 70.141435 -421.806941) (xy 70.148941 -421.783873)
			(xy 70.163209 -421.764255) (xy 70.182842 -421.750006) (xy 70.205917 -421.742523) (xy 70.218046 -421.742108)
			(xy 71.157846 -421.742108) (xy 71.16996 -421.742572) (xy 71.193 -421.750068) (xy 71.207209 -421.760396)
			(xy 72.14108 -421.760396) (xy 72.14108 -419.218872) (xy 72.141535 -419.206822) (xy 72.148973 -419.183899)
			(xy 72.163116 -419.164386) (xy 72.182586 -419.150182) (xy 72.205486 -419.142673) (xy 72.217534 -419.142164)
			(xy 73.157842 -419.142164) (xy 73.169936 -419.142572) (xy 73.192942 -419.150043) (xy 73.212524 -419.164244)
			(xy 73.226772 -419.183791) (xy 73.234298 -419.206779) (xy 73.234804 -419.218872) (xy 73.234804 -420.921688)
			(xy 75.13828 -420.921688) (xy 75.13828 -420.058088) (xy 75.138766 -420.030819) (xy 75.146528 -419.976835)
			(xy 75.161893 -419.924505) (xy 75.18455 -419.874895) (xy 75.214036 -419.829014) (xy 75.249751 -419.787797)
			(xy 75.290968 -419.752082) (xy 75.336849 -419.722596) (xy 75.386459 -419.699939) (xy 75.438789 -419.684574)
			(xy 75.492773 -419.676812) (xy 75.547311 -419.676812) (xy 75.601295 -419.684574) (xy 75.653625 -419.699939)
			(xy 75.703235 -419.722596) (xy 75.749116 -419.752082) (xy 75.790333 -419.787797) (xy 75.826048 -419.829014)
			(xy 75.855534 -419.874895) (xy 75.878191 -419.924505) (xy 75.893556 -419.976835) (xy 75.901318 -420.030819)
			(xy 75.901804 -420.058088) (xy 75.901804 -420.921688) (xy 75.901318 -420.948957) (xy 75.893556 -421.002941)
			(xy 75.878191 -421.055271) (xy 75.855534 -421.104881) (xy 75.844472 -421.122094) (xy 97.149412 -421.122094)
			(xy 97.149412 -414.328102) (xy 97.149934 -414.317948) (xy 97.157703 -414.299183) (xy 97.17206 -414.284819)
			(xy 97.19082 -414.27704) (xy 97.200974 -414.27654) (xy 102.099618 -414.27654) (xy 102.109777 -414.277018)
			(xy 102.128547 -414.284799) (xy 102.142912 -414.29917) (xy 102.150685 -414.317943) (xy 102.15118 -414.328102)
			(xy 102.15118 -421.122094) (xy 102.150662 -421.132249) (xy 102.142893 -421.151015) (xy 102.128535 -421.16538)
			(xy 102.109773 -421.173157) (xy 102.099618 -421.173656) (xy 97.200974 -421.173656) (xy 97.190814 -421.173188)
			(xy 97.172043 -421.165404) (xy 97.157678 -421.15103) (xy 97.149906 -421.132255) (xy 97.149412 -421.122094)
			(xy 75.844472 -421.122094) (xy 75.826048 -421.150762) (xy 75.790333 -421.191979) (xy 75.749116 -421.227694)
			(xy 75.703235 -421.25718) (xy 75.653625 -421.279837) (xy 75.601295 -421.295202) (xy 75.547311 -421.302964)
			(xy 75.492773 -421.302964) (xy 75.438789 -421.295202) (xy 75.386459 -421.279837) (xy 75.336849 -421.25718)
			(xy 75.290968 -421.227694) (xy 75.249751 -421.191979) (xy 75.214036 -421.150762) (xy 75.18455 -421.104881)
			(xy 75.161893 -421.055271) (xy 75.146528 -421.002941) (xy 75.138766 -420.948957) (xy 75.13828 -420.921688)
			(xy 73.234804 -420.921688) (xy 73.234804 -421.760396) (xy 73.234337 -421.772446) (xy 73.226906 -421.79537)
			(xy 73.212766 -421.814886) (xy 73.193298 -421.829089) (xy 73.170398 -421.836596) (xy 73.15835 -421.837104)
			(xy 72.218042 -421.837104) (xy 72.205959 -421.836558) (xy 72.182967 -421.829118) (xy 72.16339 -421.81495)
			(xy 72.149137 -421.795436) (xy 72.141596 -421.772477) (xy 72.14108 -421.760396) (xy 71.207209 -421.760396)
			(xy 71.212598 -421.764313) (xy 71.226839 -421.783915) (xy 71.23433 -421.806956) (xy 71.234808 -421.81907)
			(xy 71.234808 -424.360594) (xy 71.234284 -424.372704) (xy 71.226804 -424.395739) (xy 71.212574 -424.415337)
			(xy 71.192985 -424.42958) (xy 71.169955 -424.437076) (xy 71.157846 -424.437556) (xy 70.218046 -424.437556)
			(xy 70.205925 -424.437101) (xy 70.182867 -424.429621) (xy 70.16325 -424.415378) (xy 70.148998 -424.395769)
			(xy 70.141505 -424.372715) (xy 70.141084 -424.360594) (xy 69.234812 -424.360594) (xy 69.234812 -425.360592)
			(xy 69.234333 -425.372641) (xy 69.226904 -425.395564) (xy 69.212768 -425.415079) (xy 69.193302 -425.429283)
			(xy 69.170405 -425.436791) (xy 69.158358 -425.4373) (xy 68.21805 -425.4373) (xy 68.205967 -425.436751)
			(xy 68.182975 -425.429313) (xy 68.163397 -425.415146) (xy 68.149144 -425.395632) (xy 68.141603 -425.372673)
			(xy 68.141088 -425.360592) (xy 67.207172 -425.360592) (xy 67.212508 -425.364454) (xy 67.226762 -425.38397)
			(xy 67.234301 -425.40693) (xy 67.234816 -425.419012) (xy 67.234816 -427.960536) (xy 67.234371 -427.972587)
			(xy 67.226931 -427.995511) (xy 67.212785 -428.015024) (xy 67.193313 -428.029227) (xy 67.170411 -428.036735)
			(xy 67.158362 -428.037244) (xy 66.218054 -428.037244) (xy 66.20596 -428.036832) (xy 66.182956 -428.02936)
			(xy 66.163375 -428.01516) (xy 66.149127 -427.995615) (xy 66.141599 -427.972628) (xy 66.141092 -427.960536)
			(xy 65.23482 -427.960536) (xy 65.23482 -428.960534) (xy 65.234469 -428.972663) (xy 65.226962 -428.99573)
			(xy 65.212694 -429.015348) (xy 65.193062 -429.029597) (xy 65.169987 -429.03708) (xy 65.157858 -429.037496)
			(xy 64.218058 -429.037496) (xy 64.205945 -429.037025) (xy 64.182906 -429.02953) (xy 64.163308 -429.015287)
			(xy 64.149066 -428.995687) (xy 64.141574 -428.972647) (xy 64.141096 -428.960534) (xy 63.207499 -428.960534)
			(xy 63.212603 -428.964238) (xy 63.226847 -428.98382) (xy 63.234343 -429.006847) (xy 63.234824 -429.018954)
			(xy 63.234824 -431.560478) (xy 63.234421 -431.572603) (xy 63.22693 -431.595668) (xy 63.212675 -431.615287)
			(xy 63.193054 -431.629537) (xy 63.169987 -431.637023) (xy 63.157862 -431.63744) (xy 62.218062 -431.63744)
			(xy 62.205943 -431.63702) (xy 62.182895 -431.62952) (xy 62.163292 -431.615265) (xy 62.149053 -431.595651)
			(xy 62.14157 -431.572597) (xy 62.1411 -431.560478) (xy 61.234828 -431.560478) (xy 61.234828 -432.560476)
			(xy 61.23432 -432.572522) (xy 61.226897 -432.595442) (xy 61.212768 -432.614956) (xy 61.193309 -432.629161)
			(xy 61.170418 -432.636673) (xy 61.158374 -432.637184) (xy 60.218066 -432.637184) (xy 60.205977 -432.636722)
			(xy 60.182979 -432.629259) (xy 60.163402 -432.61507) (xy 60.149152 -432.595538) (xy 60.141616 -432.572563)
			(xy 60.141104 -432.560476) (xy 59.207307 -432.560476) (xy 59.212555 -432.564278) (xy 59.226805 -432.58382)
			(xy 59.234329 -432.606805) (xy 59.234832 -432.618896) (xy 59.234832 -435.16042) (xy 59.234358 -435.172468)
			(xy 59.226923 -435.195389) (xy 59.212785 -435.214901) (xy 59.19332 -435.229105) (xy 59.170424 -435.236616)
			(xy 59.158378 -435.237128) (xy 58.21807 -435.237128) (xy 58.205976 -435.236718) (xy 58.182969 -435.229249)
			(xy 58.163386 -435.215049) (xy 58.149138 -435.195502) (xy 58.141612 -435.172513) (xy 58.141108 -435.16042)
			(xy 7.00913 -435.16042) (xy 7.00913 -438.760616) (xy 58.141108 -438.760616) (xy 58.141108 -436.219092)
			(xy 58.141553 -436.207041) (xy 58.148989 -436.184113) (xy 58.163134 -436.164597) (xy 58.182607 -436.150394)
			(xy 58.205512 -436.14289) (xy 58.217562 -436.142384) (xy 59.15787 -436.142384) (xy 59.169962 -436.142834)
			(xy 59.192969 -436.150288) (xy 59.206951 -436.160418) (xy 60.141104 -436.160418) (xy 60.141104 -433.618894)
			(xy 60.141606 -433.606783) (xy 60.149091 -433.583745) (xy 60.163326 -433.564146) (xy 60.18292 -433.549904)
			(xy 60.205955 -433.542411) (xy 60.218066 -433.541932) (xy 61.157866 -433.541932) (xy 61.169986 -433.542389)
			(xy 61.193043 -433.549871) (xy 61.212658 -433.564113) (xy 61.226911 -433.583721) (xy 61.234405 -433.606774)
			(xy 61.234828 -433.618894) (xy 61.234828 -435.16042) (xy 62.1411 -435.16042) (xy 62.1411 -432.618896)
			(xy 62.141557 -432.606846) (xy 62.14899 -432.58392) (xy 62.163132 -432.564404) (xy 62.182603 -432.550201)
			(xy 62.205505 -432.542695) (xy 62.217554 -432.542188) (xy 63.157862 -432.542188) (xy 63.169954 -432.542641)
			(xy 63.192962 -432.550093) (xy 63.207295 -432.560476) (xy 64.141096 -432.560476) (xy 64.141096 -431.833528)
			(xy 64.1414 -431.824757) (xy 64.145513 -431.807699) (xy 64.149224 -431.799746) (xy 64.149224 -431.799238)
			(xy 64.38265 -431.323242) (xy 64.387377 -431.312736) (xy 64.390855 -431.289971) (xy 64.38736 -431.267209)
			(xy 64.38265 -431.256694) (xy 64.149224 -430.780698) (xy 64.149224 -430.78019) (xy 64.145494 -430.772244)
			(xy 64.141391 -430.755181) (xy 64.141096 -430.746408) (xy 64.141096 -430.018952) (xy 64.141519 -430.0069)
			(xy 64.148964 -429.983973) (xy 64.163115 -429.964459) (xy 64.182592 -429.950257) (xy 64.205499 -429.942751)
			(xy 64.21755 -429.942244) (xy 65.157858 -429.942244) (xy 65.169946 -429.942743) (xy 65.192946 -429.950189)
			(xy 65.212527 -429.964367) (xy 65.226779 -429.983894) (xy 65.234311 -430.006866) (xy 65.23482 -430.018952)
			(xy 65.23482 -431.560478) (xy 66.141092 -431.560478) (xy 66.141092 -430.83353) (xy 66.141397 -430.824759)
			(xy 66.14551 -430.807702) (xy 66.14922 -430.799748) (xy 66.14922 -430.79924) (xy 66.382646 -430.323244)
			(xy 66.387372 -430.312737) (xy 66.39085 -430.289973) (xy 66.387356 -430.267211) (xy 66.382646 -430.256696)
			(xy 66.14922 -429.7807) (xy 66.14922 -429.780192) (xy 66.145491 -429.772246) (xy 66.141387 -429.755183)
			(xy 66.141092 -429.74641) (xy 66.141092 -429.018954) (xy 66.141572 -429.006842) (xy 66.149066 -428.983805)
			(xy 66.163308 -428.964208) (xy 66.182905 -428.949966) (xy 66.205942 -428.942472) (xy 66.218054 -428.941992)
			(xy 67.157854 -428.941992) (xy 67.169962 -428.94255) (xy 67.192996 -428.950019) (xy 67.207487 -428.960534)
			(xy 68.141088 -428.960534) (xy 68.141088 -426.41901) (xy 68.14162 -426.406901) (xy 68.149098 -426.383867)
			(xy 68.163326 -426.364269) (xy 68.182913 -426.350025) (xy 68.205941 -426.342529) (xy 68.21805 -426.342048)
			(xy 69.15785 -426.342048) (xy 69.169968 -426.342469) (xy 69.193015 -426.349972) (xy 69.212616 -426.364226)
			(xy 69.226856 -426.383839) (xy 69.23434 -426.406891) (xy 69.234812 -426.41901) (xy 69.234812 -427.960536)
			(xy 70.141084 -427.960536) (xy 70.141084 -425.419012) (xy 70.14157 -425.406964) (xy 70.148997 -425.384042)
			(xy 70.163132 -425.364527) (xy 70.182596 -425.350323) (xy 70.205492 -425.342813) (xy 70.217538 -425.342304)
			(xy 71.157846 -425.342304) (xy 71.169934 -425.342767) (xy 71.19293 -425.350232) (xy 71.207224 -425.360592)
			(xy 72.14108 -425.360592) (xy 72.14108 -422.819068) (xy 72.141532 -422.807018) (xy 72.148971 -422.784095)
			(xy 72.163115 -422.764581) (xy 72.182585 -422.750378) (xy 72.205486 -422.742869) (xy 72.217534 -422.74236)
			(xy 73.157842 -422.74236) (xy 73.169936 -422.742772) (xy 73.192941 -422.750243) (xy 73.212522 -422.764443)
			(xy 73.226771 -422.783989) (xy 73.234298 -422.806975) (xy 73.234804 -422.819068) (xy 73.234804 -424.80464)
			(xy 109.929157 -424.80464) (xy 109.929157 -424.6755) (xy 109.937107 -424.546605) (xy 109.952977 -424.418445)
			(xy 109.976706 -424.291504) (xy 110.008205 -424.166265) (xy 110.047354 -424.043202) (xy 110.094005 -423.922783)
			(xy 110.14798 -423.805464) (xy 110.209075 -423.69169) (xy 110.277058 -423.581893) (xy 110.351672 -423.47649)
			(xy 110.432633 -423.37588) (xy 110.519633 -423.280445) (xy 110.612344 -423.190546) (xy 110.710414 -423.106525)
			(xy 110.813469 -423.028701) (xy 110.92112 -422.957369) (xy 111.032959 -422.892799) (xy 111.14856 -422.835237)
			(xy 111.267485 -422.7849) (xy 111.389284 -422.74198) (xy 111.513494 -422.706639) (xy 111.639643 -422.679012)
			(xy 111.767255 -422.659203) (xy 111.895844 -422.647287) (xy 112.024922 -422.643311) (xy 112.154 -422.647287)
			(xy 112.282589 -422.659203) (xy 112.410201 -422.679012) (xy 112.53635 -422.706639) (xy 112.66056 -422.74198)
			(xy 112.782359 -422.7849) (xy 112.901284 -422.835237) (xy 113.016885 -422.892799) (xy 113.128724 -422.957369)
			(xy 113.236375 -423.028701) (xy 113.33943 -423.106525) (xy 113.4375 -423.190546) (xy 113.530211 -423.280445)
			(xy 113.617211 -423.37588) (xy 113.698172 -423.47649) (xy 113.772786 -423.581893) (xy 113.840769 -423.69169)
			(xy 113.901864 -423.805464) (xy 113.955839 -423.922783) (xy 114.00249 -424.043202) (xy 114.041639 -424.166265)
			(xy 114.073138 -424.291504) (xy 114.096867 -424.418445) (xy 114.112737 -424.546605) (xy 114.120687 -424.6755)
			(xy 114.121184 -424.74007) (xy 114.120687 -424.80464) (xy 114.112737 -424.933535) (xy 114.096867 -425.061695)
			(xy 114.073138 -425.188636) (xy 114.041639 -425.313875) (xy 114.00249 -425.436938) (xy 113.955839 -425.557357)
			(xy 113.901864 -425.674676) (xy 113.840769 -425.78845) (xy 113.772786 -425.898247) (xy 113.698172 -426.00365)
			(xy 113.617211 -426.10426) (xy 113.530211 -426.199695) (xy 113.4375 -426.289594) (xy 113.33943 -426.373615)
			(xy 113.236375 -426.451439) (xy 113.128724 -426.522771) (xy 113.016885 -426.587341) (xy 112.901284 -426.644903)
			(xy 112.782359 -426.69524) (xy 112.66056 -426.73816) (xy 112.53635 -426.773501) (xy 112.410201 -426.801128)
			(xy 112.282589 -426.820937) (xy 112.154 -426.832853) (xy 112.024922 -426.83683) (xy 111.895844 -426.832853)
			(xy 111.767255 -426.820937) (xy 111.639643 -426.801128) (xy 111.513494 -426.773501) (xy 111.389284 -426.73816)
			(xy 111.267485 -426.69524) (xy 111.14856 -426.644903) (xy 111.032959 -426.587341) (xy 110.92112 -426.522771)
			(xy 110.813469 -426.451439) (xy 110.710414 -426.373615) (xy 110.612344 -426.289594) (xy 110.519633 -426.199695)
			(xy 110.432633 -426.10426) (xy 110.351672 -426.00365) (xy 110.277058 -425.898247) (xy 110.209075 -425.78845)
			(xy 110.14798 -425.674676) (xy 110.094005 -425.557357) (xy 110.047354 -425.436938) (xy 110.008205 -425.313875)
			(xy 109.976706 -425.188636) (xy 109.952977 -425.061695) (xy 109.937107 -424.933535) (xy 109.929157 -424.80464)
			(xy 73.234804 -424.80464) (xy 73.234804 -425.360592) (xy 73.234333 -425.372641) (xy 73.226903 -425.395566)
			(xy 73.212765 -425.415082) (xy 73.193297 -425.429285) (xy 73.170398 -425.436792) (xy 73.15835 -425.4373)
			(xy 72.218042 -425.4373) (xy 72.205959 -425.436758) (xy 72.182966 -425.429317) (xy 72.163389 -425.415149)
			(xy 72.149135 -425.395633) (xy 72.141595 -425.372673) (xy 72.14108 -425.360592) (xy 71.207224 -425.360592)
			(xy 71.212507 -425.364421) (xy 71.226757 -425.383953) (xy 71.234294 -425.406925) (xy 71.234808 -425.419012)
			(xy 71.234808 -427.960536) (xy 71.234371 -427.972587) (xy 71.226929 -427.995513) (xy 71.212782 -428.015027)
			(xy 71.193308 -428.02923) (xy 71.170404 -428.036736) (xy 71.158354 -428.037244) (xy 70.218046 -428.037244)
			(xy 70.205957 -428.036753) (xy 70.182955 -428.029307) (xy 70.163373 -428.015127) (xy 70.149122 -427.995597)
			(xy 70.141591 -427.972623) (xy 70.141084 -427.960536) (xy 69.234812 -427.960536) (xy 69.234812 -428.960534)
			(xy 69.234318 -428.972645) (xy 69.226828 -428.995681) (xy 69.21259 -429.015278) (xy 69.192996 -429.02952)
			(xy 69.169961 -429.037016) (xy 69.15785 -429.037496) (xy 68.21805 -429.037496) (xy 68.205936 -429.037031)
			(xy 68.182897 -429.029535) (xy 68.163299 -429.015289) (xy 68.149058 -428.995689) (xy 68.141566 -428.972648)
			(xy 68.141088 -428.960534) (xy 67.207487 -428.960534) (xy 67.212594 -428.96424) (xy 67.226839 -428.983822)
			(xy 67.234335 -429.006847) (xy 67.234816 -429.018954) (xy 67.234816 -431.560478) (xy 67.234421 -431.572604)
			(xy 67.226929 -431.59567) (xy 67.212672 -431.61529) (xy 67.193049 -431.62954) (xy 67.16998 -431.637024)
			(xy 67.157854 -431.63744) (xy 66.218054 -431.63744) (xy 66.205935 -431.637027) (xy 66.182886 -431.629525)
			(xy 66.163284 -431.615268) (xy 66.149044 -431.595653) (xy 66.141562 -431.572598) (xy 66.141092 -431.560478)
			(xy 65.23482 -431.560478) (xy 65.23482 -432.560476) (xy 65.23432 -432.572523) (xy 65.226896 -432.595444)
			(xy 65.212765 -432.614959) (xy 65.193304 -432.629164) (xy 65.170411 -432.636674) (xy 65.158366 -432.637184)
			(xy 64.218058 -432.637184) (xy 64.205969 -432.636729) (xy 64.182971 -432.629264) (xy 64.163393 -432.615073)
			(xy 64.149143 -432.595539) (xy 64.141608 -432.572564) (xy 64.141096 -432.560476) (xy 63.207295 -432.560476)
			(xy 63.212547 -432.564281) (xy 63.226797 -432.583821) (xy 63.234321 -432.606805) (xy 63.234824 -432.618896)
			(xy 63.234824 -435.16042) (xy 63.234357 -435.172469) (xy 63.226922 -435.195391) (xy 63.212782 -435.214904)
			(xy 63.193315 -435.229108) (xy 63.170417 -435.236618) (xy 63.15837 -435.237128) (xy 62.218062 -435.237128)
			(xy 62.205967 -435.236724) (xy 62.18296 -435.229253) (xy 62.163378 -435.215052) (xy 62.14913 -435.195503)
			(xy 62.141604 -435.172514) (xy 62.1411 -435.16042) (xy 61.234828 -435.16042) (xy 61.234828 -436.160418)
			(xy 61.234455 -436.172545) (xy 61.226953 -436.19561) (xy 61.212691 -436.215228) (xy 61.193064 -436.229477)
			(xy 61.169993 -436.236963) (xy 61.157866 -436.23738) (xy 60.218066 -436.23738) (xy 60.205951 -436.236918)
			(xy 60.18291 -436.229423) (xy 60.16331 -436.215178) (xy 60.149069 -436.195576) (xy 60.14158 -436.172533)
			(xy 60.141104 -436.160418) (xy 59.206951 -436.160418) (xy 59.212554 -436.164477) (xy 59.226804 -436.184017)
			(xy 59.234329 -436.207001) (xy 59.234832 -436.219092) (xy 59.234832 -438.760616) (xy 59.234354 -438.772664)
			(xy 59.226921 -438.795584) (xy 59.212784 -438.815097) (xy 59.193319 -438.829301) (xy 59.170424 -438.836812)
			(xy 59.158378 -438.837324) (xy 58.21807 -438.837324) (xy 58.205975 -438.836918) (xy 58.182968 -438.829448)
			(xy 58.163385 -438.815247) (xy 58.149137 -438.795699) (xy 58.141612 -438.77271) (xy 58.141108 -438.760616)
			(xy 7.00913 -438.760616) (xy 7.00913 -439.760614) (xy 60.141104 -439.760614) (xy 60.141104 -437.21909)
			(xy 60.141603 -437.206978) (xy 60.149089 -437.183941) (xy 60.163325 -437.164342) (xy 60.182919 -437.1501)
			(xy 60.205954 -437.142607) (xy 60.218066 -437.142128) (xy 61.157866 -437.142128) (xy 61.169986 -437.142589)
			(xy 61.193042 -437.15007) (xy 61.212657 -437.164312) (xy 61.22691 -437.183918) (xy 61.234404 -437.20697)
			(xy 61.234828 -437.21909) (xy 61.234828 -438.760616) (xy 62.1411 -438.760616) (xy 62.1411 -436.219092)
			(xy 62.141553 -436.207041) (xy 62.148988 -436.184116) (xy 62.163131 -436.1646) (xy 62.182602 -436.150397)
			(xy 62.205505 -436.142891) (xy 62.217554 -436.142384) (xy 63.157862 -436.142384) (xy 63.169954 -436.142841)
			(xy 63.192961 -436.150292) (xy 63.206938 -436.160418) (xy 64.141096 -436.160418) (xy 64.141096 -433.618894)
			(xy 64.141606 -433.606783) (xy 64.14909 -433.583747) (xy 64.163324 -433.564149) (xy 64.182915 -433.549906)
			(xy 64.205948 -433.542412) (xy 64.218058 -433.541932) (xy 65.157858 -433.541932) (xy 65.169978 -433.542396)
			(xy 65.193034 -433.549876) (xy 65.21265 -433.564116) (xy 65.226903 -433.583722) (xy 65.234397 -433.606774)
			(xy 65.23482 -433.618894) (xy 65.23482 -435.16042) (xy 66.141092 -435.16042) (xy 66.141092 -432.618896)
			(xy 66.141556 -432.606846) (xy 66.148989 -432.583922) (xy 66.163129 -432.564407) (xy 66.182598 -432.550204)
			(xy 66.205498 -432.542696) (xy 66.217546 -432.542188) (xy 67.157854 -432.542188) (xy 67.169946 -432.542647)
			(xy 67.192953 -432.550097) (xy 67.207281 -432.560476) (xy 68.141088 -432.560476) (xy 68.141088 -431.833528)
			(xy 68.141393 -431.824757) (xy 68.145506 -431.8077) (xy 68.149216 -431.799746) (xy 68.149216 -431.799238)
			(xy 68.382642 -431.323242) (xy 68.387369 -431.312736) (xy 68.390848 -431.289971) (xy 68.387352 -431.267209)
			(xy 68.382642 -431.256694) (xy 68.149216 -430.780698) (xy 68.149216 -430.78019) (xy 68.145486 -430.772244)
			(xy 68.141383 -430.755181) (xy 68.141088 -430.746408) (xy 68.141088 -430.018952) (xy 68.141519 -430.0069)
			(xy 68.148963 -429.983975) (xy 68.163112 -429.964461) (xy 68.182587 -429.950259) (xy 68.205492 -429.942752)
			(xy 68.217542 -429.942244) (xy 69.15785 -429.942244) (xy 69.169937 -429.94275) (xy 69.192937 -429.950193)
			(xy 69.212518 -429.96437) (xy 69.22677 -429.983896) (xy 69.234303 -430.006866) (xy 69.234812 -430.018952)
			(xy 69.234812 -431.560478) (xy 70.141084 -431.560478) (xy 70.141084 -430.83353) (xy 70.14139 -430.824759)
			(xy 70.145502 -430.807702) (xy 70.149212 -430.799748) (xy 70.149212 -430.79924) (xy 70.382638 -430.323244)
			(xy 70.387364 -430.312737) (xy 70.390843 -430.289973) (xy 70.387348 -430.267211) (xy 70.382638 -430.256696)
			(xy 70.149212 -429.7807) (xy 70.149212 -429.780192) (xy 70.145482 -429.772246) (xy 70.141379 -429.755183)
			(xy 70.141084 -429.74641) (xy 70.141084 -429.018954) (xy 70.141473 -429.006832) (xy 70.148979 -428.98378)
			(xy 70.16324 -428.964175) (xy 70.182862 -428.949937) (xy 70.205924 -428.942459) (xy 70.218046 -428.941992)
			(xy 71.157846 -428.941992) (xy 71.169958 -428.942472) (xy 71.192995 -428.949966) (xy 71.207537 -428.960534)
			(xy 72.14108 -428.960534) (xy 72.14108 -426.41901) (xy 72.141469 -426.406884) (xy 72.148964 -426.383818)
			(xy 72.163222 -426.364199) (xy 72.182847 -426.349949) (xy 72.205915 -426.342464) (xy 72.218042 -426.342048)
			(xy 73.157842 -426.342048) (xy 73.16996 -426.342476) (xy 73.193006 -426.349976) (xy 73.212608 -426.364229)
			(xy 73.226848 -426.383841) (xy 73.234332 -426.406892) (xy 73.234804 -426.41901) (xy 73.234804 -427.960536)
			(xy 75.141328 -427.960536) (xy 75.141328 -425.419012) (xy 75.141724 -425.406926) (xy 75.149192 -425.383938)
			(xy 75.163402 -425.364384) (xy 75.18296 -425.350181) (xy 75.20595 -425.34272) (xy 75.218036 -425.342304)
			(xy 76.157836 -425.342304) (xy 76.169914 -425.342734) (xy 76.192884 -425.350207) (xy 76.212422 -425.364413)
			(xy 76.226615 -425.383959) (xy 76.234074 -425.406934) (xy 76.234544 -425.419012) (xy 76.234544 -427.960536)
			(xy 76.234067 -427.972609) (xy 76.226599 -427.995571) (xy 76.212405 -428.015105) (xy 76.192871 -428.029299)
			(xy 76.169909 -428.036767) (xy 76.157836 -428.037244) (xy 75.218036 -428.037244) (xy 75.205967 -428.036706)
			(xy 75.183007 -428.029258) (xy 75.163472 -428.015079) (xy 75.149275 -427.995558) (xy 75.141806 -427.972605)
			(xy 75.141328 -427.960536) (xy 73.234804 -427.960536) (xy 73.234804 -428.960534) (xy 73.234318 -428.972646)
			(xy 73.226827 -428.995683) (xy 73.212587 -429.015281) (xy 73.192991 -429.029523) (xy 73.169954 -429.037017)
			(xy 73.157842 -429.037496) (xy 72.218042 -429.037496) (xy 72.205925 -429.037005) (xy 72.182873 -429.029528)
			(xy 72.16326 -429.015294) (xy 72.149006 -428.995695) (xy 72.141507 -428.972651) (xy 72.14108 -428.960534)
			(xy 71.207537 -428.960534) (xy 71.212592 -428.964208) (xy 71.226834 -428.983805) (xy 71.234328 -429.006842)
			(xy 71.234808 -429.018954) (xy 71.234808 -431.560478) (xy 71.23427 -431.572587) (xy 71.226795 -431.595622)
			(xy 71.212568 -431.61522) (xy 71.192983 -431.629464) (xy 71.169954 -431.636959) (xy 71.157846 -431.63744)
			(xy 70.218046 -431.63744) (xy 70.205923 -431.637001) (xy 70.182862 -431.629518) (xy 70.163245 -431.615273)
			(xy 70.148993 -431.595659) (xy 70.141503 -431.5726) (xy 70.141084 -431.560478) (xy 69.234812 -431.560478)
			(xy 69.234812 -432.560476) (xy 69.23432 -432.572524) (xy 69.226895 -432.595447) (xy 69.212762 -432.614962)
			(xy 69.193299 -432.629166) (xy 69.170404 -432.636675) (xy 69.158358 -432.637184) (xy 68.21805 -432.637184)
			(xy 68.205965 -432.636651) (xy 68.18297 -432.62921) (xy 68.163392 -432.61504) (xy 68.149139 -432.595522)
			(xy 68.141601 -432.572559) (xy 68.141088 -432.560476) (xy 67.207281 -432.560476) (xy 67.212538 -432.564284)
			(xy 67.226788 -432.583823) (xy 67.234313 -432.606806) (xy 67.234816 -432.618896) (xy 67.234816 -435.16042)
			(xy 67.234357 -435.17247) (xy 67.226921 -435.195393) (xy 67.212779 -435.214907) (xy 67.19331 -435.22911)
			(xy 67.17041 -435.236619) (xy 67.158362 -435.237128) (xy 66.218054 -435.237128) (xy 66.205959 -435.236731)
			(xy 66.182951 -435.229258) (xy 66.163369 -435.215054) (xy 66.149122 -435.195505) (xy 66.141596 -435.172514)
			(xy 66.141092 -435.16042) (xy 65.23482 -435.16042) (xy 65.23482 -436.160418) (xy 65.234454 -436.172546)
			(xy 65.226952 -436.195612) (xy 65.212688 -436.215231) (xy 65.193058 -436.22948) (xy 65.169986 -436.236964)
			(xy 65.157858 -436.23738) (xy 64.218058 -436.23738) (xy 64.205943 -436.236924) (xy 64.182901 -436.229428)
			(xy 64.163302 -436.215181) (xy 64.149061 -436.195577) (xy 64.141572 -436.172533) (xy 64.141096 -436.160418)
			(xy 63.206938 -436.160418) (xy 63.212545 -436.16448) (xy 63.226795 -436.184019) (xy 63.234321 -436.207002)
			(xy 63.234824 -436.219092) (xy 63.234824 -438.760616) (xy 63.234354 -438.772665) (xy 63.22692 -438.795587)
			(xy 63.212781 -438.8151) (xy 63.193314 -438.829304) (xy 63.170417 -438.836814) (xy 63.15837 -438.837324)
			(xy 62.218062 -438.837324) (xy 62.205967 -438.836924) (xy 62.182959 -438.829453) (xy 62.163377 -438.81525)
			(xy 62.149129 -438.795701) (xy 62.141604 -438.77271) (xy 62.1411 -438.760616) (xy 61.234828 -438.760616)
			(xy 61.234828 -439.760614) (xy 64.141096 -439.760614) (xy 64.141096 -437.21909) (xy 64.141603 -437.206979)
			(xy 64.149088 -437.183943) (xy 64.163322 -437.164345) (xy 64.182914 -437.150102) (xy 64.205947 -437.142608)
			(xy 64.218058 -437.142128) (xy 65.157858 -437.142128) (xy 65.169978 -437.142595) (xy 65.193033 -437.150075)
			(xy 65.212648 -437.164315) (xy 65.226901 -437.18392) (xy 65.234396 -437.206971) (xy 65.23482 -437.21909)
			(xy 65.23482 -438.760616) (xy 66.141092 -438.760616) (xy 66.141092 -436.219092) (xy 66.141553 -436.207042)
			(xy 66.148987 -436.184118) (xy 66.163128 -436.164603) (xy 66.182597 -436.1504) (xy 66.205498 -436.142892)
			(xy 66.217546 -436.142384) (xy 67.157854 -436.142384) (xy 67.169946 -436.142847) (xy 67.192952 -436.150297)
			(xy 67.206925 -436.160418) (xy 68.141088 -436.160418) (xy 68.141088 -433.618894) (xy 68.141606 -433.606784)
			(xy 68.149089 -433.583749) (xy 68.163321 -433.564152) (xy 68.18291 -433.549909) (xy 68.20594 -433.542413)
			(xy 68.21805 -433.541932) (xy 69.15785 -433.541932) (xy 69.169967 -433.542369) (xy 69.19301 -433.549869)
			(xy 69.212611 -433.564121) (xy 69.226851 -433.583729) (xy 69.234338 -433.606777) (xy 69.234812 -433.618894)
			(xy 69.234812 -435.16042) (xy 70.141084 -435.16042) (xy 70.141084 -432.618896) (xy 70.141556 -432.606847)
			(xy 70.148988 -432.583924) (xy 70.163126 -432.56441) (xy 70.182593 -432.550206) (xy 70.205491 -432.542697)
			(xy 70.217538 -432.542188) (xy 71.157846 -432.542188) (xy 71.169943 -432.542569) (xy 71.192953 -432.550044)
			(xy 71.207333 -432.560476) (xy 72.14108 -432.560476) (xy 72.14108 -431.833528) (xy 72.141385 -431.824757)
			(xy 72.145498 -431.8077) (xy 72.149208 -431.799746) (xy 72.149208 -431.799238) (xy 72.382634 -431.323242)
			(xy 72.387362 -431.312736) (xy 72.39084 -431.289971) (xy 72.387345 -431.267209) (xy 72.382634 -431.256694)
			(xy 72.149208 -430.780698) (xy 72.149208 -430.78019) (xy 72.145477 -430.772244) (xy 72.141374 -430.755181)
			(xy 72.14108 -430.746408) (xy 72.14108 -430.018952) (xy 72.141519 -430.006901) (xy 72.148962 -429.983977)
			(xy 72.163109 -429.964464) (xy 72.182582 -429.950262) (xy 72.205485 -429.942753) (xy 72.217534 -429.942244)
			(xy 73.157842 -429.942244) (xy 73.169934 -429.942672) (xy 73.192937 -429.95014) (xy 73.212516 -429.964337)
			(xy 73.226765 -429.983879) (xy 73.234296 -430.006861) (xy 73.234804 -430.018952) (xy 73.234804 -431.560478)
			(xy 75.141328 -431.560478) (xy 75.141328 -430.833276) (xy 75.141577 -430.824519) (xy 75.145558 -430.807461)
			(xy 75.149202 -430.799494) (xy 75.382628 -430.323244) (xy 75.387355 -430.312738) (xy 75.390834 -430.289973)
			(xy 75.387339 -430.267211) (xy 75.382628 -430.256696) (xy 75.149202 -429.780446) (xy 75.145554 -429.772479)
			(xy 75.141569 -429.755422) (xy 75.141328 -429.746664) (xy 75.141328 -429.018954) (xy 75.141768 -429.006863)
			(xy 75.149236 -428.983863) (xy 75.16343 -428.964285) (xy 75.182968 -428.950036) (xy 75.205947 -428.942503)
			(xy 75.218036 -428.941992) (xy 76.157836 -428.941992) (xy 76.169946 -428.942386) (xy 76.192973 -428.949894)
			(xy 76.207568 -428.960534) (xy 77.141324 -428.960534) (xy 77.141324 -426.41901) (xy 77.141816 -426.406923)
			(xy 77.149268 -426.383925) (xy 77.163449 -426.364346) (xy 77.182976 -426.350095) (xy 77.205946 -426.34256)
			(xy 77.218032 -426.342048) (xy 78.157832 -426.342048) (xy 78.169937 -426.342488) (xy 78.192957 -426.34999)
			(xy 78.212525 -426.364248) (xy 78.22672 -426.38386) (xy 78.234149 -426.406903) (xy 78.23454 -426.41901)
			(xy 78.23454 -427.960536) (xy 79.14132 -427.960536) (xy 79.14132 -425.419012) (xy 79.141724 -425.406927)
			(xy 79.149191 -425.38394) (xy 79.163399 -425.364387) (xy 79.182954 -425.350184) (xy 79.205943 -425.342721)
			(xy 79.218028 -425.342304) (xy 80.157828 -425.342304) (xy 80.169905 -425.34274) (xy 80.192875 -425.350212)
			(xy 80.212413 -425.364415) (xy 80.226606 -425.38396) (xy 80.234066 -425.406935) (xy 80.234536 -425.419012)
			(xy 80.234536 -427.960536) (xy 80.234067 -427.97261) (xy 80.226598 -427.995573) (xy 80.212402 -428.015107)
			(xy 80.192866 -428.029302) (xy 80.169902 -428.036768) (xy 80.157828 -428.037244) (xy 79.218028 -428.037244)
			(xy 79.205958 -428.036713) (xy 79.182998 -428.029262) (xy 79.163464 -428.015082) (xy 79.149267 -427.995559)
			(xy 79.141797 -427.972605) (xy 79.14132 -427.960536) (xy 78.23454 -427.960536) (xy 78.23454 -428.960534)
			(xy 78.234121 -428.972627) (xy 78.226653 -428.995632) (xy 78.212454 -429.015214) (xy 78.19291 -429.029462)
			(xy 78.169924 -429.03699) (xy 78.157832 -429.037496) (xy 77.218032 -429.037496) (xy 77.205924 -429.037056)
			(xy 77.182898 -429.029565) (xy 77.163324 -429.01531) (xy 77.149128 -428.995692) (xy 77.141707 -428.972643)
			(xy 77.141324 -428.960534) (xy 76.207568 -428.960534) (xy 76.212545 -428.964162) (xy 76.226738 -428.983787)
			(xy 76.23416 -429.006843) (xy 76.234544 -429.018954) (xy 76.234544 -431.560478) (xy 76.234074 -431.572568)
			(xy 76.226621 -431.595571) (xy 76.212436 -431.615152) (xy 76.192902 -431.629403) (xy 76.169924 -431.636933)
			(xy 76.157836 -431.63744) (xy 75.218036 -431.63744) (xy 75.205933 -431.636953) (xy 75.182914 -431.629469)
			(xy 75.163344 -431.615224) (xy 75.149146 -431.595619) (xy 75.141718 -431.572582) (xy 75.141328 -431.560478)
			(xy 73.234804 -431.560478) (xy 73.234804 -432.560476) (xy 73.23432 -432.572525) (xy 73.226894 -432.595449)
			(xy 73.212759 -432.614964) (xy 73.193294 -432.629169) (xy 73.170397 -432.636676) (xy 73.15835 -432.637184)
			(xy 72.218042 -432.637184) (xy 72.205957 -432.636657) (xy 72.182962 -432.629215) (xy 72.163383 -432.615043)
			(xy 72.14913 -432.595523) (xy 72.141593 -432.572559) (xy 72.14108 -432.560476) (xy 71.207333 -432.560476)
			(xy 71.212536 -432.564251) (xy 71.226784 -432.583805) (xy 71.234306 -432.6068) (xy 71.234808 -432.618896)
			(xy 71.234808 -435.16042) (xy 71.234357 -435.17247) (xy 71.22692 -435.195395) (xy 71.212776 -435.21491)
			(xy 71.193305 -435.229113) (xy 71.170403 -435.23662) (xy 71.158354 -435.237128) (xy 70.218046 -435.237128)
			(xy 70.205956 -435.236653) (xy 70.182951 -435.229205) (xy 70.163368 -435.215022) (xy 70.149117 -435.195487)
			(xy 70.141589 -435.172509) (xy 70.141084 -435.16042) (xy 69.234812 -435.16042) (xy 69.234812 -436.160418)
			(xy 69.234305 -436.172529) (xy 69.226818 -436.195564) (xy 69.212584 -436.215161) (xy 69.192993 -436.229404)
			(xy 69.16996 -436.2369) (xy 69.15785 -436.23738) (xy 68.21805 -436.23738) (xy 68.205935 -436.236931)
			(xy 68.182893 -436.229432) (xy 68.163293 -436.215184) (xy 68.149053 -436.195578) (xy 68.141564 -436.172534)
			(xy 68.141088 -436.160418) (xy 67.206925 -436.160418) (xy 67.212537 -436.164483) (xy 67.226787 -436.18402)
			(xy 67.234312 -436.207002) (xy 67.234816 -436.219092) (xy 67.234816 -438.760616) (xy 67.234354 -438.772665)
			(xy 67.226919 -438.795589) (xy 67.212778 -438.815103) (xy 67.193309 -438.829306) (xy 67.17041 -438.836815)
			(xy 67.158362 -438.837324) (xy 66.218054 -438.837324) (xy 66.205958 -438.836931) (xy 66.18295 -438.829457)
			(xy 66.163368 -438.815253) (xy 66.14912 -438.795702) (xy 66.141596 -438.77271) (xy 66.141092 -438.760616)
			(xy 65.23482 -438.760616) (xy 65.23482 -439.760614) (xy 68.141088 -439.760614) (xy 68.141088 -437.21909)
			(xy 68.141603 -437.20698) (xy 68.149087 -437.183945) (xy 68.163319 -437.164348) (xy 68.182909 -437.150105)
			(xy 68.20594 -437.142609) (xy 68.21805 -437.142128) (xy 69.15785 -437.142128) (xy 69.169966 -437.142569)
			(xy 69.193009 -437.150069) (xy 69.212609 -437.164319) (xy 69.22685 -437.183927) (xy 69.234337 -437.206974)
			(xy 69.234812 -437.21909) (xy 69.234812 -438.760616) (xy 70.141084 -438.760616) (xy 70.141084 -436.219092)
			(xy 70.141553 -436.207043) (xy 70.148986 -436.18412) (xy 70.163125 -436.164606) (xy 70.182592 -436.150402)
			(xy 70.205491 -436.142893) (xy 70.217538 -436.142384) (xy 71.157846 -436.142384) (xy 71.169942 -436.142769)
			(xy 71.192952 -436.150244) (xy 71.206977 -436.160418) (xy 72.14108 -436.160418) (xy 72.14108 -433.618894)
			(xy 72.141456 -433.606767) (xy 72.148955 -433.583701) (xy 72.163216 -433.564082) (xy 72.182844 -433.549833)
			(xy 72.205915 -433.542348) (xy 72.218042 -433.541932) (xy 73.157842 -433.541932) (xy 73.169958 -433.542376)
			(xy 73.193002 -433.549874) (xy 73.212602 -433.564123) (xy 73.226843 -433.583731) (xy 73.23433 -433.606778)
			(xy 73.234804 -433.618894) (xy 73.234804 -435.16042) (xy 75.141328 -435.16042) (xy 75.141328 -432.618896)
			(xy 75.14171 -432.606809) (xy 75.149183 -432.58382) (xy 75.163396 -432.564267) (xy 75.182956 -432.550064)
			(xy 75.205949 -432.542603) (xy 75.218036 -432.542188) (xy 76.157836 -432.542188) (xy 76.169912 -432.542633)
			(xy 76.19288 -432.550105) (xy 76.207146 -432.560476) (xy 77.141324 -432.560476) (xy 77.141324 -431.833274)
			(xy 77.141573 -431.824517) (xy 77.145554 -431.807459) (xy 77.149198 -431.799492) (xy 77.382624 -431.323242)
			(xy 77.387352 -431.312736) (xy 77.390831 -431.289971) (xy 77.387335 -431.267209) (xy 77.382624 -431.256694)
			(xy 77.149198 -430.780444) (xy 77.145549 -430.772478) (xy 77.141565 -430.75542) (xy 77.141324 -430.746662)
			(xy 77.141324 -430.018952) (xy 77.141724 -430.006872) (xy 77.149203 -429.983898) (xy 77.163415 -429.964358)
			(xy 77.182969 -429.950167) (xy 77.205951 -429.942711) (xy 77.218032 -429.942244) (xy 78.157832 -429.942244)
			(xy 78.169903 -429.942736) (xy 78.192864 -429.950201) (xy 78.212396 -429.964393) (xy 78.226591 -429.983922)
			(xy 78.234062 -430.006881) (xy 78.23454 -430.018952) (xy 78.23454 -431.560478) (xy 79.14132 -431.560478)
			(xy 79.14132 -430.833276) (xy 79.14157 -430.824519) (xy 79.14555 -430.807461) (xy 79.149194 -430.799494)
			(xy 79.38262 -430.323244) (xy 79.387347 -430.312738) (xy 79.390827 -430.289973) (xy 79.387331 -430.267211)
			(xy 79.38262 -430.256696) (xy 79.149194 -429.780446) (xy 79.145546 -429.77248) (xy 79.141561 -429.755422)
			(xy 79.14132 -429.746664) (xy 79.14132 -429.018954) (xy 79.141768 -429.006864) (xy 79.149235 -428.983865)
			(xy 79.163427 -428.964288) (xy 79.182963 -428.950038) (xy 79.205939 -428.942504) (xy 79.218028 -428.941992)
			(xy 80.157828 -428.941992) (xy 80.169938 -428.942392) (xy 80.192964 -428.949899) (xy 80.207555 -428.960534)
			(xy 81.141316 -428.960534) (xy 81.141316 -426.41901) (xy 81.141816 -426.406923) (xy 81.149267 -426.383927)
			(xy 81.163446 -426.364349) (xy 81.182971 -426.350097) (xy 81.205939 -426.342561) (xy 81.218024 -426.342048)
			(xy 82.157824 -426.342048) (xy 82.169929 -426.342495) (xy 82.192948 -426.349995) (xy 82.212516 -426.36425)
			(xy 82.226712 -426.383862) (xy 82.234141 -426.406904) (xy 82.234532 -426.41901) (xy 82.234532 -427.960536)
			(xy 83.141312 -427.960536) (xy 83.141312 -425.419012) (xy 83.141723 -425.406928) (xy 83.14919 -425.383942)
			(xy 83.163396 -425.36439) (xy 83.182949 -425.350186) (xy 83.205936 -425.342722) (xy 83.21802 -425.342304)
			(xy 84.15782 -425.342304) (xy 84.169897 -425.342748) (xy 84.192867 -425.350217) (xy 84.212404 -425.364419)
			(xy 84.226598 -425.383962) (xy 84.234057 -425.406935) (xy 84.234528 -425.419012) (xy 84.234528 -427.960536)
			(xy 84.234067 -427.97261) (xy 84.226597 -427.995576) (xy 84.212399 -428.01511) (xy 84.192861 -428.029304)
			(xy 84.169895 -428.036769) (xy 84.15782 -428.037244) (xy 83.21802 -428.037244) (xy 83.20595 -428.036719)
			(xy 83.18299 -428.029267) (xy 83.163455 -428.015085) (xy 83.149259 -427.995561) (xy 83.141789 -427.972606)
			(xy 83.141312 -427.960536) (xy 82.234532 -427.960536) (xy 82.234532 -428.960534) (xy 82.234121 -428.972628)
			(xy 82.226652 -428.995635) (xy 82.212452 -429.015216) (xy 82.192905 -429.029465) (xy 82.169917 -429.036991)
			(xy 82.157824 -429.037496) (xy 81.218024 -429.037496) (xy 81.205916 -429.037063) (xy 81.182889 -429.02957)
			(xy 81.163315 -429.015313) (xy 81.14912 -428.995694) (xy 81.141699 -428.972643) (xy 81.141316 -428.960534)
			(xy 80.207555 -428.960534) (xy 80.212536 -428.964165) (xy 80.22673 -428.983789) (xy 80.234152 -429.006843)
			(xy 80.234536 -429.018954) (xy 80.234536 -431.560478) (xy 80.234073 -431.572569) (xy 80.22662 -431.595573)
			(xy 80.212433 -431.615155) (xy 80.192897 -431.629405) (xy 80.169917 -431.636934) (xy 80.157828 -431.63744)
			(xy 79.218028 -431.63744) (xy 79.205925 -431.63696) (xy 79.182905 -431.629473) (xy 79.163335 -431.615227)
			(xy 79.149138 -431.595621) (xy 79.141709 -431.572582) (xy 79.14132 -431.560478) (xy 78.23454 -431.560478)
			(xy 78.23454 -432.560476) (xy 78.234016 -432.572546) (xy 78.226564 -432.595507) (xy 78.212382 -432.615042)
			(xy 78.192857 -432.629238) (xy 78.169902 -432.636707) (xy 78.157832 -432.637184) (xy 77.218032 -432.637184)
			(xy 77.205949 -432.63676) (xy 77.182963 -432.629298) (xy 77.16341 -432.615096) (xy 77.149206 -432.595544)
			(xy 77.141742 -432.572559) (xy 77.141324 -432.560476) (xy 76.207146 -432.560476) (xy 76.212416 -432.564307)
			(xy 76.226609 -432.583849) (xy 76.234072 -432.60682) (xy 76.234544 -432.618896) (xy 76.234544 -435.16042)
			(xy 76.234053 -435.172492) (xy 76.22659 -435.195454) (xy 76.212399 -435.214987) (xy 76.192868 -435.229182)
			(xy 76.169908 -435.236651) (xy 76.157836 -435.237128) (xy 75.218036 -435.237128) (xy 75.205957 -435.236657)
			(xy 75.182979 -435.229202) (xy 75.16343 -435.21501) (xy 75.149224 -435.195471) (xy 75.141752 -435.172499)
			(xy 75.141328 -435.16042) (xy 73.234804 -435.16042) (xy 73.234804 -436.160418) (xy 73.234304 -436.172529)
			(xy 73.226817 -436.195566) (xy 73.212581 -436.215164) (xy 73.192988 -436.229406) (xy 73.169953 -436.236901)
			(xy 73.157842 -436.23738) (xy 72.218042 -436.23738) (xy 72.205923 -436.236905) (xy 72.182869 -436.229426)
			(xy 72.163255 -436.215188) (xy 72.149001 -436.195585) (xy 72.141505 -436.172536) (xy 72.14108 -436.160418)
			(xy 71.206977 -436.160418) (xy 71.212535 -436.16445) (xy 71.226782 -436.184003) (xy 71.234305 -436.206997)
			(xy 71.234808 -436.219092) (xy 71.234808 -438.760616) (xy 71.234354 -438.772666) (xy 71.226918 -438.795591)
			(xy 71.212775 -438.815106) (xy 71.193304 -438.829309) (xy 71.170403 -438.836816) (xy 71.158354 -438.837324)
			(xy 70.218046 -438.837324) (xy 70.205955 -438.836853) (xy 70.18295 -438.829404) (xy 70.163366 -438.81522)
			(xy 70.149115 -438.795685) (xy 70.141589 -438.772705) (xy 70.141084 -438.760616) (xy 69.234812 -438.760616)
			(xy 69.234812 -439.760614) (xy 72.14108 -439.760614) (xy 72.14108 -437.21909) (xy 72.141452 -437.206963)
			(xy 72.148952 -437.183896) (xy 72.163215 -437.164278) (xy 72.182843 -437.150029) (xy 72.205914 -437.142544)
			(xy 72.218042 -437.142128) (xy 73.157842 -437.142128) (xy 73.169958 -437.142576) (xy 73.193001 -437.150073)
			(xy 73.212601 -437.164322) (xy 73.226841 -437.183928) (xy 73.234329 -437.206974) (xy 73.234804 -437.21909)
			(xy 73.234804 -438.760616) (xy 75.141328 -438.760616) (xy 75.141328 -436.219092) (xy 75.141706 -436.207005)
			(xy 75.14918 -436.184016) (xy 75.163394 -436.164463) (xy 75.182956 -436.15026) (xy 75.205949 -436.142799)
			(xy 75.218036 -436.142384) (xy 76.157836 -436.142384) (xy 76.169912 -436.142833) (xy 76.192879 -436.150305)
			(xy 76.206792 -436.160418) (xy 77.141324 -436.160418) (xy 77.141324 -433.618894) (xy 77.141802 -433.606806)
			(xy 77.149259 -433.583808) (xy 77.163443 -433.564229) (xy 77.182973 -433.549978) (xy 77.205945 -433.542444)
			(xy 77.218032 -433.541932) (xy 78.157832 -433.541932) (xy 78.169946 -433.542289) (xy 78.19298 -433.549802)
			(xy 78.212555 -433.564077) (xy 78.226747 -433.583713) (xy 78.234161 -433.606779) (xy 78.23454 -433.618894)
			(xy 78.23454 -435.16042) (xy 79.14132 -435.16042) (xy 79.14132 -432.618896) (xy 79.141709 -432.60681)
			(xy 79.149182 -432.583823) (xy 79.163393 -432.56427) (xy 79.182951 -432.550067) (xy 79.205942 -432.542604)
			(xy 79.218028 -432.542188) (xy 80.157828 -432.542188) (xy 80.169904 -432.54264) (xy 80.192871 -432.55011)
			(xy 80.207132 -432.560476) (xy 81.141316 -432.560476) (xy 81.141316 -431.833274) (xy 81.141565 -431.824517)
			(xy 81.145546 -431.807459) (xy 81.14919 -431.799492) (xy 81.382616 -431.323242) (xy 81.387345 -431.312736)
			(xy 81.390824 -431.289971) (xy 81.387328 -431.267209) (xy 81.382616 -431.256694) (xy 81.14919 -430.780444)
			(xy 81.145541 -430.772478) (xy 81.141557 -430.75542) (xy 81.141316 -430.746662) (xy 81.141316 -430.018952)
			(xy 81.141724 -430.006873) (xy 81.149202 -429.9839) (xy 81.163413 -429.964361) (xy 81.182964 -429.950169)
			(xy 81.205944 -429.942712) (xy 81.218024 -429.942244) (xy 82.157824 -429.942244) (xy 82.169895 -429.942743)
			(xy 82.192855 -429.950206) (xy 82.212387 -429.964396) (xy 82.226583 -429.983924) (xy 82.234053 -430.006881)
			(xy 82.234532 -430.018952) (xy 82.234532 -431.560478) (xy 83.141312 -431.560478) (xy 83.141312 -430.833276)
			(xy 83.141562 -430.824519) (xy 83.145542 -430.807461) (xy 83.149186 -430.799494) (xy 83.382612 -430.323244)
			(xy 83.38734 -430.312738) (xy 83.39082 -430.289973) (xy 83.387323 -430.267211) (xy 83.382612 -430.256696)
			(xy 83.149186 -429.780446) (xy 83.145537 -429.77248) (xy 83.141553 -429.755422) (xy 83.141312 -429.746664)
			(xy 83.141312 -429.018954) (xy 83.141768 -429.006865) (xy 83.149234 -428.983867) (xy 83.163424 -428.964291)
			(xy 83.182958 -428.950041) (xy 83.205932 -428.942505) (xy 83.21802 -428.941992) (xy 84.15782 -428.941992)
			(xy 84.169929 -428.942399) (xy 84.192956 -428.949903) (xy 84.207543 -428.960534) (xy 85.141308 -428.960534)
			(xy 85.141308 -426.41901) (xy 85.141815 -426.406924) (xy 85.149265 -426.383929) (xy 85.163443 -426.364352)
			(xy 85.182966 -426.3501) (xy 85.205932 -426.342562) (xy 85.218016 -426.342048) (xy 86.157816 -426.342048)
			(xy 86.169921 -426.342502) (xy 86.192939 -426.349999) (xy 86.212508 -426.364253) (xy 86.226704 -426.383863)
			(xy 86.234133 -426.406904) (xy 86.234524 -426.41901) (xy 86.234524 -427.960536) (xy 87.141304 -427.960536)
			(xy 87.141304 -425.419012) (xy 87.141723 -425.406929) (xy 87.149189 -425.383944) (xy 87.163393 -425.364393)
			(xy 87.182944 -425.350189) (xy 87.205929 -425.342723) (xy 87.218012 -425.342304) (xy 88.157812 -425.342304)
			(xy 88.169888 -425.342754) (xy 88.192858 -425.350222) (xy 88.212396 -425.364421) (xy 88.226589 -425.383964)
			(xy 88.234049 -425.406935) (xy 88.23452 -425.419012) (xy 88.23452 -427.960536) (xy 88.234067 -427.972611)
			(xy 88.226596 -427.995578) (xy 88.212396 -428.015113) (xy 88.192856 -428.029307) (xy 88.169887 -428.036771)
			(xy 88.157812 -428.037244) (xy 87.218012 -428.037244) (xy 87.205942 -428.036726) (xy 87.182981 -428.029271)
			(xy 87.163447 -428.015087) (xy 87.149251 -427.995562) (xy 87.141781 -427.972606) (xy 87.141304 -427.960536)
			(xy 86.234524 -427.960536) (xy 86.234524 -428.960534) (xy 86.234121 -428.972629) (xy 86.226651 -428.995637)
			(xy 86.212449 -429.015219) (xy 86.1929 -429.029467) (xy 86.16991 -429.036992) (xy 86.157816 -429.037496)
			(xy 85.218016 -429.037496) (xy 85.205908 -429.03707) (xy 85.18288 -429.029574) (xy 85.163307 -429.015315)
			(xy 85.149112 -428.995695) (xy 85.141691 -428.972644) (xy 85.141308 -428.960534) (xy 84.207543 -428.960534)
			(xy 84.212528 -428.964167) (xy 84.226722 -428.98379) (xy 84.234144 -429.006843) (xy 84.234528 -429.018954)
			(xy 84.234528 -431.560478) (xy 84.234073 -431.57257) (xy 84.226619 -431.595575) (xy 84.21243 -431.615158)
			(xy 84.192892 -431.629408) (xy 84.16991 -431.636935) (xy 84.15782 -431.63744) (xy 83.21802 -431.63744)
			(xy 83.205916 -431.636967) (xy 83.182896 -431.629478) (xy 83.163327 -431.61523) (xy 83.14913 -431.595622)
			(xy 83.141701 -431.572583) (xy 83.141312 -431.560478) (xy 82.234532 -431.560478) (xy 82.234532 -432.560476)
			(xy 82.234016 -432.572547) (xy 82.226563 -432.595509) (xy 82.212379 -432.615045) (xy 82.192852 -432.629241)
			(xy 82.169895 -432.636708) (xy 82.157824 -432.637184) (xy 81.218024 -432.637184) (xy 81.20594 -432.636766)
			(xy 81.182954 -432.629303) (xy 81.163401 -432.615099) (xy 81.149197 -432.595546) (xy 81.141734 -432.57256)
			(xy 81.141316 -432.560476) (xy 80.207132 -432.560476) (xy 80.212407 -432.56431) (xy 80.226601 -432.58385)
			(xy 80.234064 -432.60682) (xy 80.234536 -432.618896) (xy 80.234536 -435.16042) (xy 80.234053 -435.172493)
			(xy 80.226588 -435.195456) (xy 80.212396 -435.21499) (xy 80.192863 -435.229185) (xy 80.169901 -435.236652)
			(xy 80.157828 -435.237128) (xy 79.218028 -435.237128) (xy 79.205949 -435.236664) (xy 79.18297 -435.229206)
			(xy 79.163421 -435.215013) (xy 79.149216 -435.195473) (xy 79.141744 -435.172499) (xy 79.14132 -435.16042)
			(xy 78.23454 -435.16042) (xy 78.23454 -436.160418) (xy 78.234108 -436.172511) (xy 78.226644 -436.195515)
			(xy 78.212449 -436.215097) (xy 78.192907 -436.229346) (xy 78.169923 -436.236874) (xy 78.157832 -436.23738)
			(xy 77.218032 -436.23738) (xy 77.205923 -436.236956) (xy 77.182893 -436.229463) (xy 77.163318 -436.215204)
			(xy 77.149123 -436.195582) (xy 77.141705 -436.172528) (xy 77.141324 -436.160418) (xy 76.206792 -436.160418)
			(xy 76.212415 -436.164505) (xy 76.226608 -436.184046) (xy 76.234071 -436.207016) (xy 76.234544 -436.219092)
			(xy 76.234544 -438.760616) (xy 76.23405 -438.772688) (xy 76.226587 -438.795649) (xy 76.212397 -438.815183)
			(xy 76.192867 -438.829378) (xy 76.169908 -438.836847) (xy 76.157836 -438.837324) (xy 75.218036 -438.837324)
			(xy 75.205957 -438.836857) (xy 75.182978 -438.829401) (xy 75.163428 -438.815209) (xy 75.149223 -438.795669)
			(xy 75.141751 -438.772695) (xy 75.141328 -438.760616) (xy 73.234804 -438.760616) (xy 73.234804 -439.760614)
			(xy 77.141324 -439.760614) (xy 77.141324 -437.21909) (xy 77.141799 -437.207002) (xy 77.149256 -437.184003)
			(xy 77.163441 -437.164425) (xy 77.182972 -437.150174) (xy 77.205945 -437.14264) (xy 77.218032 -437.142128)
			(xy 78.157832 -437.142128) (xy 78.169945 -437.142489) (xy 78.192978 -437.150001) (xy 78.212553 -437.164276)
			(xy 78.226746 -437.183911) (xy 78.234161 -437.206975) (xy 78.23454 -437.21909) (xy 78.23454 -438.760616)
			(xy 79.14132 -438.760616) (xy 79.14132 -436.219092) (xy 79.141706 -436.207006) (xy 79.149179 -436.184018)
			(xy 79.163391 -436.164466) (xy 79.182951 -436.150263) (xy 79.205942 -436.1428) (xy 79.218028 -436.142384)
			(xy 80.157828 -436.142384) (xy 80.169903 -436.14284) (xy 80.19287 -436.150309) (xy 80.206779 -436.160418)
			(xy 81.141316 -436.160418) (xy 81.141316 -433.618894) (xy 81.141802 -433.606807) (xy 81.149257 -433.58381)
			(xy 81.16344 -433.564232) (xy 81.182968 -433.549981) (xy 81.205938 -433.542445) (xy 81.218024 -433.541932)
			(xy 82.157824 -433.541932) (xy 82.169937 -433.542296) (xy 82.192971 -433.549806) (xy 82.212546 -433.56408)
			(xy 82.226739 -433.583715) (xy 82.234153 -433.606779) (xy 82.234532 -433.618894) (xy 82.234532 -435.16042)
			(xy 83.141312 -435.16042) (xy 83.141312 -432.618896) (xy 83.141709 -432.606811) (xy 83.14918 -432.583825)
			(xy 83.16339 -432.564273) (xy 83.182946 -432.550069) (xy 83.205935 -432.542606) (xy 83.21802 -432.542188)
			(xy 84.15782 -432.542188) (xy 84.169895 -432.542647) (xy 84.192862 -432.550115) (xy 84.207119 -432.560476)
			(xy 85.141308 -432.560476) (xy 85.141308 -431.833274) (xy 85.141558 -431.824517) (xy 85.145538 -431.807459)
			(xy 85.149182 -431.799492) (xy 85.382608 -431.323242) (xy 85.387337 -431.312736) (xy 85.390817 -431.289971)
			(xy 85.38732 -431.267208) (xy 85.382608 -431.256694) (xy 85.149182 -430.780444) (xy 85.145532 -430.772478)
			(xy 85.141549 -430.75542) (xy 85.141308 -430.746662) (xy 85.141308 -430.018952) (xy 85.141723 -430.006873)
			(xy 85.149201 -429.983902) (xy 85.16341 -429.964364) (xy 85.182959 -429.950172) (xy 85.205937 -429.942713)
			(xy 85.218016 -429.942244) (xy 86.157816 -429.942244) (xy 86.169887 -429.94275) (xy 86.192846 -429.950211)
			(xy 86.212379 -429.964399) (xy 86.226574 -429.983925) (xy 86.234045 -430.006882) (xy 86.234524 -430.018952)
			(xy 86.234524 -431.560478) (xy 87.141304 -431.560478) (xy 87.141304 -430.833276) (xy 87.141555 -430.824519)
			(xy 87.145535 -430.807461) (xy 87.149178 -430.799494) (xy 87.382604 -430.323244) (xy 87.387332 -430.312738)
			(xy 87.390813 -430.289973) (xy 87.387316 -430.26721) (xy 87.382604 -430.256696) (xy 87.149178 -429.780446)
			(xy 87.145529 -429.77248) (xy 87.141545 -429.755422) (xy 87.141304 -429.746664) (xy 87.141304 -429.018954)
			(xy 87.141767 -429.006866) (xy 87.149232 -428.98387) (xy 87.163421 -428.964293) (xy 87.182953 -428.950043)
			(xy 87.205925 -428.942506) (xy 87.218012 -428.941992) (xy 88.157812 -428.941992) (xy 88.169921 -428.942406)
			(xy 88.192947 -428.949908) (xy 88.207529 -428.960534) (xy 89.1413 -428.960534) (xy 89.1413 -426.41901)
			(xy 89.141815 -426.406925) (xy 89.149264 -426.383931) (xy 89.16344 -426.364355) (xy 89.182961 -426.350103)
			(xy 89.205925 -426.342563) (xy 89.218008 -426.342048) (xy 90.157808 -426.342048) (xy 90.169912 -426.342509)
			(xy 90.192931 -426.350004) (xy 90.212499 -426.364256) (xy 90.226696 -426.383865) (xy 90.234125 -426.406905)
			(xy 90.234516 -426.41901) (xy 90.234516 -428.960534) (xy 90.234121 -428.97263) (xy 90.226649 -428.995639)
			(xy 90.212446 -429.015222) (xy 90.192895 -429.02947) (xy 90.169903 -429.036993) (xy 90.157808 -429.037496)
			(xy 89.218008 -429.037496) (xy 89.205899 -429.037077) (xy 89.182871 -429.029579) (xy 89.163298 -429.015319)
			(xy 89.149103 -428.995697) (xy 89.141683 -428.972644) (xy 89.1413 -428.960534) (xy 88.207529 -428.960534)
			(xy 88.212519 -428.96417) (xy 88.226714 -428.983792) (xy 88.234136 -429.006844) (xy 88.23452 -429.018954)
			(xy 88.23452 -431.560478) (xy 88.234073 -431.57257) (xy 88.226618 -431.595577) (xy 88.212427 -431.615161)
			(xy 88.192887 -431.629411) (xy 88.169903 -431.636936) (xy 88.157812 -431.63744) (xy 87.218012 -431.63744)
			(xy 87.205908 -431.636974) (xy 87.182888 -431.629483) (xy 87.163318 -431.615232) (xy 87.149122 -431.595624)
			(xy 87.141693 -431.572583) (xy 87.141304 -431.560478) (xy 86.234524 -431.560478) (xy 86.234524 -432.560476)
			(xy 86.234067 -432.572556) (xy 86.226608 -432.595535) (xy 86.212413 -432.615084) (xy 86.192871 -432.62929)
			(xy 86.169896 -432.636761) (xy 86.157816 -432.637184) (xy 85.218016 -432.637184) (xy 85.205932 -432.636773)
			(xy 85.182946 -432.629307) (xy 85.163393 -432.615101) (xy 85.149189 -432.595547) (xy 85.141726 -432.57256)
			(xy 85.141308 -432.560476) (xy 84.207119 -432.560476) (xy 84.212399 -432.564313) (xy 84.226593 -432.583852)
			(xy 84.234055 -432.606821) (xy 84.234528 -432.618896) (xy 84.234528 -435.16042) (xy 84.234053 -435.172494)
			(xy 84.226587 -435.195458) (xy 84.212393 -435.214993) (xy 84.192858 -435.229187) (xy 84.169894 -435.236653)
			(xy 84.15782 -435.237128) (xy 83.21802 -435.237128) (xy 83.205948 -435.236619) (xy 83.182985 -435.229165)
			(xy 83.16345 -435.214979) (xy 83.149254 -435.195451) (xy 83.141787 -435.172491) (xy 83.141312 -435.16042)
			(xy 82.234532 -435.16042) (xy 82.234532 -436.160418) (xy 82.234108 -436.172511) (xy 82.226643 -436.195517)
			(xy 82.212446 -436.215099) (xy 82.192902 -436.229348) (xy 82.169916 -436.236875) (xy 82.157824 -436.23738)
			(xy 81.218024 -436.23738) (xy 81.205914 -436.236963) (xy 81.182885 -436.229468) (xy 81.163309 -436.215207)
			(xy 81.149115 -436.195584) (xy 81.141697 -436.172529) (xy 81.141316 -436.160418) (xy 80.206779 -436.160418)
			(xy 80.212406 -436.164508) (xy 80.2266 -436.184048) (xy 80.234063 -436.207017) (xy 80.234536 -436.219092)
			(xy 80.234536 -438.760616) (xy 80.23405 -438.772689) (xy 80.226586 -438.795651) (xy 80.212394 -438.815186)
			(xy 80.192862 -438.829381) (xy 80.169901 -438.836848) (xy 80.157828 -438.837324) (xy 79.218028 -438.837324)
			(xy 79.205948 -438.836864) (xy 79.182969 -438.829406) (xy 79.16342 -438.815211) (xy 79.149214 -438.79567)
			(xy 79.141743 -438.772695) (xy 79.14132 -438.760616) (xy 78.23454 -438.760616) (xy 78.23454 -439.760614)
			(xy 81.141316 -439.760614) (xy 81.141316 -437.21909) (xy 81.141799 -437.207002) (xy 81.149255 -437.184006)
			(xy 81.163439 -437.164428) (xy 81.182967 -437.150177) (xy 81.205938 -437.142641) (xy 81.218024 -437.142128)
			(xy 82.157824 -437.142128) (xy 82.169937 -437.142496) (xy 82.19297 -437.150006) (xy 82.212545 -437.164279)
			(xy 82.226738 -437.183912) (xy 82.234153 -437.206975) (xy 82.234532 -437.21909) (xy 82.234532 -438.760616)
			(xy 83.141312 -438.760616) (xy 83.141312 -436.219092) (xy 83.141706 -436.207007) (xy 83.149178 -436.18402)
			(xy 83.163388 -436.164469) (xy 83.182946 -436.150265) (xy 83.205935 -436.142802) (xy 83.21802 -436.142384)
			(xy 84.15782 -436.142384) (xy 84.169895 -436.142847) (xy 84.192861 -436.150314) (xy 84.206765 -436.160418)
			(xy 85.141308 -436.160418) (xy 85.141308 -433.618894) (xy 85.141802 -433.606807) (xy 85.149256 -433.583812)
			(xy 85.163437 -433.564235) (xy 85.182963 -433.549984) (xy 85.205931 -433.542446) (xy 85.218016 -433.541932)
			(xy 86.157816 -433.541932) (xy 86.169929 -433.542303) (xy 86.192962 -433.549811) (xy 86.212538 -433.564083)
			(xy 86.226731 -433.583716) (xy 86.234145 -433.606779) (xy 86.234524 -433.618894) (xy 86.234524 -435.16042)
			(xy 87.141304 -435.16042) (xy 87.141304 -432.618896) (xy 87.141709 -432.606812) (xy 87.149179 -432.583827)
			(xy 87.163387 -432.564276) (xy 87.182941 -432.550072) (xy 87.205928 -432.542607) (xy 87.218012 -432.542188)
			(xy 88.157812 -432.542188) (xy 88.169887 -432.542654) (xy 88.192854 -432.550119) (xy 88.207106 -432.560476)
			(xy 89.1413 -432.560476) (xy 89.1413 -431.833274) (xy 89.141551 -431.824517) (xy 89.145531 -431.807459)
			(xy 89.149174 -431.799492) (xy 89.3826 -431.323242) (xy 89.38733 -431.312736) (xy 89.39081 -431.289971)
			(xy 89.387312 -431.267208) (xy 89.3826 -431.256694) (xy 89.149174 -430.780444) (xy 89.145524 -430.772478)
			(xy 89.141541 -430.75542) (xy 89.1413 -430.746662) (xy 89.1413 -430.018952) (xy 89.141723 -430.006874)
			(xy 89.1492 -429.983904) (xy 89.163407 -429.964367) (xy 89.182954 -429.950174) (xy 89.20593 -429.942714)
			(xy 89.218008 -429.942244) (xy 90.157808 -429.942244) (xy 90.169878 -429.942757) (xy 90.192837 -429.950216)
			(xy 90.21237 -429.964401) (xy 90.226566 -429.983927) (xy 90.234037 -430.006882) (xy 90.234516 -430.018952)
			(xy 90.234516 -431.360072) (xy 108.40466 -431.360072) (xy 108.405158 -431.275192) (xy 108.413115 -431.105619)
			(xy 108.429011 -430.936605) (xy 108.452812 -430.768522) (xy 108.484466 -430.601739) (xy 108.523902 -430.436623)
			(xy 108.571034 -430.273538) (xy 108.625758 -430.11284) (xy 108.687955 -429.954885) (xy 108.757487 -429.800018)
			(xy 108.834202 -429.648581) (xy 108.91793 -429.500905) (xy 109.008488 -429.357317) (xy 109.105677 -429.218131)
			(xy 109.209284 -429.083654) (xy 109.319079 -428.954181) (xy 109.434823 -428.829996) (xy 109.55626 -428.711373)
			(xy 109.683124 -428.598572) (xy 109.815135 -428.491842) (xy 109.952005 -428.391417) (xy 110.09343 -428.297518)
			(xy 110.239102 -428.21035) (xy 110.3887 -428.130107) (xy 110.541894 -428.056963) (xy 110.698348 -427.991081)
			(xy 110.857718 -427.932604) (xy 111.019654 -427.881662) (xy 111.1838 -427.838366) (xy 111.349795 -427.802811)
			(xy 111.517274 -427.775076) (xy 111.685869 -427.755222) (xy 111.855209 -427.743292) (xy 112.024922 -427.739313)
			(xy 112.194635 -427.743292) (xy 112.363975 -427.755222) (xy 112.53257 -427.775076) (xy 112.700049 -427.802811)
			(xy 112.866044 -427.838366) (xy 113.03019 -427.881662) (xy 113.192126 -427.932604) (xy 113.26825 -427.960536)
			(xy 125.241304 -427.960536) (xy 125.241304 -425.419012) (xy 125.241723 -425.406929) (xy 125.249189 -425.383944)
			(xy 125.263393 -425.364393) (xy 125.282944 -425.350189) (xy 125.305929 -425.342723) (xy 125.318012 -425.342304)
			(xy 126.257812 -425.342304) (xy 126.269888 -425.342754) (xy 126.292858 -425.350222) (xy 126.312396 -425.364421)
			(xy 126.326589 -425.383964) (xy 126.334049 -425.406935) (xy 126.33452 -425.419012) (xy 126.33452 -427.960536)
			(xy 126.334067 -427.972611) (xy 126.326596 -427.995578) (xy 126.312396 -428.015113) (xy 126.292856 -428.029307)
			(xy 126.269887 -428.036771) (xy 126.257812 -428.037244) (xy 125.318012 -428.037244) (xy 125.305942 -428.036726)
			(xy 125.282981 -428.029271) (xy 125.263447 -428.015087) (xy 125.249251 -427.995562) (xy 125.241781 -427.972606)
			(xy 125.241304 -427.960536) (xy 113.26825 -427.960536) (xy 113.351496 -427.991081) (xy 113.50795 -428.056963)
			(xy 113.661144 -428.130107) (xy 113.810742 -428.21035) (xy 113.956414 -428.297518) (xy 114.097839 -428.391417)
			(xy 114.234709 -428.491842) (xy 114.36672 -428.598572) (xy 114.493584 -428.711373) (xy 114.615021 -428.829996)
			(xy 114.730765 -428.954181) (xy 114.84056 -429.083654) (xy 114.944167 -429.218131) (xy 115.041356 -429.357317)
			(xy 115.131914 -429.500905) (xy 115.215642 -429.648581) (xy 115.292357 -429.800018) (xy 115.361889 -429.954885)
			(xy 115.424086 -430.11284) (xy 115.47881 -430.273538) (xy 115.525942 -430.436623) (xy 115.565378 -430.601739)
			(xy 115.597032 -430.768522) (xy 115.620833 -430.936605) (xy 115.636729 -431.105619) (xy 115.644686 -431.275192)
			(xy 115.645184 -431.360072) (xy 115.644698 -431.445674) (xy 115.639268 -431.560478) (xy 125.241304 -431.560478)
			(xy 125.241304 -430.833276) (xy 125.241555 -430.824519) (xy 125.245535 -430.807461) (xy 125.249178 -430.799494)
			(xy 125.482604 -430.323244) (xy 125.487332 -430.312738) (xy 125.490813 -430.289973) (xy 125.487316 -430.26721)
			(xy 125.482604 -430.256696) (xy 125.249178 -429.780446) (xy 125.245529 -429.77248) (xy 125.241545 -429.755422)
			(xy 125.241304 -429.746664) (xy 125.241304 -429.018954) (xy 125.241767 -429.006866) (xy 125.249232 -428.98387)
			(xy 125.263421 -428.964293) (xy 125.282953 -428.950043) (xy 125.305925 -428.942506) (xy 125.318012 -428.941992)
			(xy 126.257812 -428.941992) (xy 126.269921 -428.942406) (xy 126.292947 -428.949908) (xy 126.307529 -428.960534)
			(xy 127.2413 -428.960534) (xy 127.2413 -426.41901) (xy 127.241815 -426.406925) (xy 127.249264 -426.383931)
			(xy 127.26344 -426.364355) (xy 127.282961 -426.350103) (xy 127.305925 -426.342563) (xy 127.318008 -426.342048)
			(xy 128.257808 -426.342048) (xy 128.269912 -426.342509) (xy 128.292931 -426.350004) (xy 128.312499 -426.364256)
			(xy 128.326696 -426.383865) (xy 128.334125 -426.406905) (xy 128.334516 -426.41901) (xy 128.334516 -427.960536)
			(xy 129.241296 -427.960536) (xy 129.241296 -425.419012) (xy 129.241723 -425.40693) (xy 129.249188 -425.383947)
			(xy 129.26339 -425.364396) (xy 129.282939 -425.350191) (xy 129.305922 -425.342724) (xy 129.318004 -425.342304)
			(xy 130.257804 -425.342304) (xy 130.269888 -425.342709) (xy 130.292873 -425.350179) (xy 130.312424 -425.364387)
			(xy 130.326628 -425.383941) (xy 130.334093 -425.406928) (xy 130.334512 -425.419012) (xy 130.334512 -427.960536)
			(xy 130.334067 -427.972612) (xy 130.326595 -427.99558) (xy 130.312393 -428.015116) (xy 130.292851 -428.029309)
			(xy 130.26988 -428.036772) (xy 130.257804 -428.037244) (xy 129.318004 -428.037244) (xy 129.305933 -428.036733)
			(xy 129.282972 -428.029276) (xy 129.263438 -428.01509) (xy 129.249242 -427.995564) (xy 129.241773 -427.972607)
			(xy 129.241296 -427.960536) (xy 128.334516 -427.960536) (xy 128.334516 -428.960534) (xy 128.334121 -428.97263)
			(xy 128.326649 -428.995639) (xy 128.312446 -429.015222) (xy 128.292895 -429.02947) (xy 128.269903 -429.036993)
			(xy 128.257808 -429.037496) (xy 127.318008 -429.037496) (xy 127.305899 -429.037077) (xy 127.282871 -429.029579)
			(xy 127.263298 -429.015319) (xy 127.249103 -428.995697) (xy 127.241683 -428.972644) (xy 127.2413 -428.960534)
			(xy 126.307529 -428.960534) (xy 126.312519 -428.96417) (xy 126.326714 -428.983792) (xy 126.334136 -429.006844)
			(xy 126.33452 -429.018954) (xy 126.33452 -431.560478) (xy 126.334073 -431.57257) (xy 126.326618 -431.595577)
			(xy 126.312427 -431.615161) (xy 126.292887 -431.629411) (xy 126.269903 -431.636936) (xy 126.257812 -431.63744)
			(xy 125.318012 -431.63744) (xy 125.305908 -431.636974) (xy 125.282888 -431.629483) (xy 125.263318 -431.615232)
			(xy 125.249122 -431.595624) (xy 125.241693 -431.572583) (xy 125.241304 -431.560478) (xy 115.639268 -431.560478)
			(xy 115.63661 -431.616688) (xy 115.620446 -431.787128) (xy 115.596243 -431.956613) (xy 115.564055 -432.124765)
			(xy 115.523953 -432.291207) (xy 115.476027 -432.455567) (xy 115.420385 -432.617477) (xy 115.35715 -432.776576)
			(xy 115.286464 -432.932508) (xy 115.208486 -433.084923) (xy 115.12339 -433.233482) (xy 115.031365 -433.377851)
			(xy 114.932619 -433.517709) (xy 114.82737 -433.652742) (xy 114.715856 -433.782648) (xy 114.598325 -433.907137)
			(xy 114.47504 -434.02593) (xy 114.346277 -434.138763) (xy 114.212324 -434.245381) (xy 114.07348 -434.345548)
			(xy 113.930056 -434.439039) (xy 113.782372 -434.525645) (xy 113.630759 -434.605172) (xy 113.475556 -434.677443)
			(xy 113.396522 -434.710332) (xy 113.388621 -434.713964) (xy 113.375731 -434.725623) (xy 113.367472 -434.740915)
			(xy 113.365788 -434.749448) (xy 113.35004 -434.849016) (xy 113.359438 -434.873654) (xy 113.369852 -434.88229)
			(xy 113.419298 -434.924299) (xy 113.513487 -435.013553) (xy 113.601975 -435.108462) (xy 113.644936 -435.160674)
			(xy 125.240796 -435.160674) (xy 125.240796 -432.61915) (xy 125.241268 -432.607037) (xy 125.248764 -432.583999)
			(xy 125.263008 -432.564402) (xy 125.282606 -432.550161) (xy 125.305645 -432.542667) (xy 125.317758 -432.542188)
			(xy 126.257558 -432.542188) (xy 126.269665 -432.542747) (xy 126.292699 -432.550216) (xy 126.306837 -432.560476)
			(xy 127.2413 -432.560476) (xy 127.2413 -431.833274) (xy 127.241551 -431.824517) (xy 127.245531 -431.807459)
			(xy 127.249174 -431.799492) (xy 127.4826 -431.323242) (xy 127.48733 -431.312736) (xy 127.49081 -431.289971)
			(xy 127.487312 -431.267208) (xy 127.4826 -431.256694) (xy 127.249174 -430.780444) (xy 127.245524 -430.772478)
			(xy 127.241541 -430.75542) (xy 127.2413 -430.746662) (xy 127.2413 -430.018952) (xy 127.241723 -430.006874)
			(xy 127.2492 -429.983904) (xy 127.263407 -429.964367) (xy 127.282954 -429.950174) (xy 127.30593 -429.942714)
			(xy 127.318008 -429.942244) (xy 128.257808 -429.942244) (xy 128.269878 -429.942757) (xy 128.292837 -429.950216)
			(xy 128.31237 -429.964401) (xy 128.326566 -429.983927) (xy 128.334037 -430.006882) (xy 128.334516 -430.018952)
			(xy 128.334516 -431.560478) (xy 129.241296 -431.560478) (xy 129.241296 -430.833276) (xy 129.241548 -430.824519)
			(xy 129.245527 -430.807461) (xy 129.24917 -430.799494) (xy 129.482596 -430.323244) (xy 129.487325 -430.312738)
			(xy 129.490805 -430.289973) (xy 129.487308 -430.26721) (xy 129.482596 -430.256696) (xy 129.24917 -429.780446)
			(xy 129.24552 -429.77248) (xy 129.241537 -429.755422) (xy 129.241296 -429.746664) (xy 129.241296 -429.018954)
			(xy 129.241767 -429.006866) (xy 129.249231 -428.983872) (xy 129.263418 -428.964296) (xy 129.282948 -428.950046)
			(xy 129.305918 -428.942507) (xy 129.318004 -428.941992) (xy 130.257804 -428.941992) (xy 130.269912 -428.942413)
			(xy 130.292938 -428.949912) (xy 130.307517 -428.960534) (xy 131.241292 -428.960534) (xy 131.241292 -426.41901)
			(xy 131.241815 -426.406926) (xy 131.249263 -426.383934) (xy 131.263437 -426.364358) (xy 131.282956 -426.350105)
			(xy 131.305918 -426.342564) (xy 131.318 -426.342048) (xy 132.2578 -426.342048) (xy 132.269904 -426.342515)
			(xy 132.292922 -426.350009) (xy 132.312491 -426.364259) (xy 132.326687 -426.383866) (xy 132.334117 -426.406905)
			(xy 132.334508 -426.41901) (xy 132.334508 -427.960536) (xy 133.241288 -427.960536) (xy 133.241288 -425.419012)
			(xy 133.241723 -425.40693) (xy 133.249187 -425.383949) (xy 133.263387 -425.364399) (xy 133.282934 -425.350194)
			(xy 133.305914 -425.342726) (xy 133.317996 -425.342304) (xy 134.257796 -425.342304) (xy 134.26988 -425.342716)
			(xy 134.292864 -425.350184) (xy 134.312416 -425.36439) (xy 134.32662 -425.383943) (xy 134.334085 -425.406928)
			(xy 134.334504 -425.419012) (xy 134.334504 -427.960536) (xy 134.334067 -427.972613) (xy 134.326594 -427.995582)
			(xy 134.31239 -428.015119) (xy 134.292846 -428.029312) (xy 134.269873 -428.036773) (xy 134.257796 -428.037244)
			(xy 133.317996 -428.037244) (xy 133.305925 -428.03674) (xy 133.282964 -428.02928) (xy 133.26343 -428.015093)
			(xy 133.249234 -427.995565) (xy 133.241765 -427.972607) (xy 133.241288 -427.960536) (xy 132.334508 -427.960536)
			(xy 132.334508 -428.960534) (xy 132.334023 -428.972621) (xy 132.326562 -428.995614) (xy 132.312379 -429.01519)
			(xy 132.292853 -429.029441) (xy 132.269885 -429.03698) (xy 132.2578 -429.037496) (xy 131.318 -429.037496)
			(xy 131.305891 -429.037084) (xy 131.282863 -429.029584) (xy 131.263289 -429.015321) (xy 131.249095 -428.995699)
			(xy 131.241675 -428.972645) (xy 131.241292 -428.960534) (xy 130.307517 -428.960534) (xy 130.312511 -428.964173)
			(xy 130.326706 -428.983793) (xy 130.334128 -429.006844) (xy 130.334512 -429.018954) (xy 130.334512 -431.560478)
			(xy 130.334073 -431.572571) (xy 130.326616 -431.595579) (xy 130.312424 -431.615164) (xy 130.292882 -431.629413)
			(xy 130.269896 -431.636937) (xy 130.257804 -431.63744) (xy 129.318004 -431.63744) (xy 129.305899 -431.636981)
			(xy 129.282879 -431.629488) (xy 129.263309 -431.615236) (xy 129.249113 -431.595625) (xy 129.241685 -431.572584)
			(xy 129.241296 -431.560478) (xy 128.334516 -431.560478) (xy 128.334516 -432.560476) (xy 128.334067 -432.572557)
			(xy 128.326607 -432.595537) (xy 128.31241 -432.615087) (xy 128.292866 -432.629292) (xy 128.269888 -432.636762)
			(xy 128.257808 -432.637184) (xy 127.318008 -432.637184) (xy 127.305923 -432.63678) (xy 127.282937 -432.629312)
			(xy 127.263384 -432.615105) (xy 127.249181 -432.595549) (xy 127.241717 -432.572561) (xy 127.2413 -432.560476)
			(xy 126.306837 -432.560476) (xy 126.312297 -432.564438) (xy 126.326542 -432.584019) (xy 126.334039 -432.607043)
			(xy 126.33452 -432.61915) (xy 126.33452 -435.160674) (xy 126.334117 -435.1728) (xy 126.326627 -435.195865)
			(xy 126.312372 -435.215484) (xy 126.29275 -435.229734) (xy 126.269684 -435.23722) (xy 126.257558 -435.237636)
			(xy 125.317758 -435.237636) (xy 125.305639 -435.237224) (xy 125.28259 -435.229722) (xy 125.262986 -435.215465)
			(xy 125.248747 -435.195849) (xy 125.241266 -435.172794) (xy 125.240796 -435.160674) (xy 113.644936 -435.160674)
			(xy 113.684422 -435.208663) (xy 113.760513 -435.313772) (xy 113.829956 -435.423387) (xy 113.892486 -435.537087)
			(xy 113.947862 -435.654438) (xy 113.995874 -435.77499) (xy 114.036336 -435.89828) (xy 114.069094 -436.023838)
			(xy 114.094022 -436.151181) (xy 114.111025 -436.279823) (xy 114.120038 -436.40927) (xy 114.121027 -436.539027)
			(xy 114.113986 -436.668596) (xy 114.098945 -436.797482) (xy 114.075959 -436.92519) (xy 114.045118 -437.051232)
			(xy 114.006538 -437.175125) (xy 113.960369 -437.296394) (xy 113.906786 -437.414574) (xy 113.845996 -437.529214)
			(xy 113.77823 -437.639874) (xy 113.703749 -437.74613) (xy 113.622838 -437.847575) (xy 113.535806 -437.943821)
			(xy 113.442988 -438.034499) (xy 113.344738 -438.119261) (xy 113.241432 -438.197784) (xy 113.133467 -438.269766)
			(xy 113.021257 -438.334931) (xy 112.90523 -438.39303) (xy 112.785831 -438.443841) (xy 112.663518 -438.487169)
			(xy 112.538759 -438.522847) (xy 112.412032 -438.550739) (xy 112.283822 -438.570739) (xy 112.15462 -438.58277)
			(xy 112.024922 -438.586785) (xy 111.895224 -438.58277) (xy 111.766022 -438.570739) (xy 111.637812 -438.550739)
			(xy 111.511085 -438.522847) (xy 111.386326 -438.487169) (xy 111.264013 -438.443841) (xy 111.144614 -438.39303)
			(xy 111.028587 -438.334931) (xy 110.916377 -438.269766) (xy 110.808412 -438.197784) (xy 110.705106 -438.119261)
			(xy 110.606856 -438.034499) (xy 110.514038 -437.943821) (xy 110.427006 -437.847575) (xy 110.346095 -437.74613)
			(xy 110.271614 -437.639874) (xy 110.203848 -437.529214) (xy 110.143058 -437.414574) (xy 110.089475 -437.296394)
			(xy 110.043306 -437.175125) (xy 110.004726 -437.051232) (xy 109.973885 -436.92519) (xy 109.950899 -436.797482)
			(xy 109.935858 -436.668596) (xy 109.928817 -436.539027) (xy 109.929806 -436.40927) (xy 109.938819 -436.279823)
			(xy 109.955822 -436.151181) (xy 109.98075 -436.023838) (xy 110.013508 -435.89828) (xy 110.05397 -435.77499)
			(xy 110.101982 -435.654438) (xy 110.157358 -435.537087) (xy 110.219888 -435.423387) (xy 110.289331 -435.313772)
			(xy 110.365422 -435.208663) (xy 110.447869 -435.108462) (xy 110.536357 -435.013553) (xy 110.630546 -434.924299)
			(xy 110.679992 -434.88229) (xy 110.690406 -434.873654) (xy 110.699804 -434.849016) (xy 110.682024 -434.73624)
			(xy 110.665768 -434.715412) (xy 110.653322 -434.710332) (xy 110.574304 -434.677407) (xy 110.419107 -434.605131)
			(xy 110.267499 -434.5256) (xy 110.119821 -434.438991) (xy 109.976402 -434.345497) (xy 109.837562 -434.245328)
			(xy 109.703613 -434.138709) (xy 109.574854 -434.025876) (xy 109.451573 -433.907083) (xy 109.334045 -433.782595)
			(xy 109.222533 -433.65269) (xy 109.117287 -433.517659) (xy 109.018541 -433.377804) (xy 108.926517 -433.233438)
			(xy 108.84142 -433.084883) (xy 108.763441 -432.932471) (xy 108.692754 -432.776543) (xy 108.629516 -432.617449)
			(xy 108.57387 -432.455542) (xy 108.52594 -432.291187) (xy 108.485833 -432.124749) (xy 108.453638 -431.956601)
			(xy 108.429428 -431.78712) (xy 108.413257 -431.616683) (xy 108.405161 -431.445673) (xy 108.40466 -431.360072)
			(xy 90.234516 -431.360072) (xy 90.234516 -432.560476) (xy 90.234067 -432.572557) (xy 90.226607 -432.595537)
			(xy 90.21241 -432.615087) (xy 90.192866 -432.629292) (xy 90.169888 -432.636762) (xy 90.157808 -432.637184)
			(xy 89.218008 -432.637184) (xy 89.205923 -432.63678) (xy 89.182937 -432.629312) (xy 89.163384 -432.615105)
			(xy 89.149181 -432.595549) (xy 89.141717 -432.572561) (xy 89.1413 -432.560476) (xy 88.207106 -432.560476)
			(xy 88.21239 -432.564316) (xy 88.226584 -432.583854) (xy 88.234047 -432.606821) (xy 88.23452 -432.618896)
			(xy 88.23452 -435.16042) (xy 88.234053 -435.172494) (xy 88.226586 -435.19546) (xy 88.21239 -435.214996)
			(xy 88.192853 -435.22919) (xy 88.169886 -435.236654) (xy 88.157812 -435.237128) (xy 87.218012 -435.237128)
			(xy 87.20594 -435.236626) (xy 87.182977 -435.229169) (xy 87.163441 -435.214982) (xy 87.149246 -435.195452)
			(xy 87.141779 -435.172492) (xy 87.141304 -435.16042) (xy 86.234524 -435.16042) (xy 86.234524 -436.160418)
			(xy 86.234107 -436.172512) (xy 86.226641 -436.195519) (xy 86.212443 -436.215102) (xy 86.192897 -436.229351)
			(xy 86.169909 -436.236876) (xy 86.157816 -436.23738) (xy 85.218016 -436.23738) (xy 85.205906 -436.23697)
			(xy 85.182876 -436.229472) (xy 85.163301 -436.21521) (xy 85.149106 -436.195585) (xy 85.141689 -436.172529)
			(xy 85.141308 -436.160418) (xy 84.206765 -436.160418) (xy 84.212397 -436.164511) (xy 84.226591 -436.18405)
			(xy 84.234055 -436.207017) (xy 84.234528 -436.219092) (xy 84.234528 -438.760616) (xy 84.23405 -438.772689)
			(xy 84.226585 -438.795654) (xy 84.212391 -438.815189) (xy 84.192857 -438.829383) (xy 84.169893 -438.836849)
			(xy 84.15782 -438.837324) (xy 83.21802 -438.837324) (xy 83.20594 -438.83687) (xy 83.182961 -438.82941)
			(xy 83.163411 -438.815214) (xy 83.149206 -438.795672) (xy 83.141735 -438.772696) (xy 83.141312 -438.760616)
			(xy 82.234532 -438.760616) (xy 82.234532 -439.760614) (xy 85.141308 -439.760614) (xy 85.141308 -437.21909)
			(xy 85.141798 -437.207003) (xy 85.149254 -437.184008) (xy 85.163436 -437.164431) (xy 85.182962 -437.150179)
			(xy 85.205931 -437.142642) (xy 85.218016 -437.142128) (xy 86.157816 -437.142128) (xy 86.169929 -437.142503)
			(xy 86.192961 -437.15001) (xy 86.212536 -437.164281) (xy 86.226729 -437.183914) (xy 86.234145 -437.206976)
			(xy 86.234524 -437.21909) (xy 86.234524 -438.760616) (xy 87.141304 -438.760616) (xy 87.141304 -436.219092)
			(xy 87.141706 -436.207008) (xy 87.149177 -436.184023) (xy 87.163386 -436.164471) (xy 87.182941 -436.150268)
			(xy 87.205928 -436.142803) (xy 87.218012 -436.142384) (xy 88.157812 -436.142384) (xy 88.169886 -436.142854)
			(xy 88.192853 -436.150319) (xy 88.206752 -436.160418) (xy 89.1413 -436.160418) (xy 89.1413 -433.618894)
			(xy 89.141802 -433.606808) (xy 89.149255 -433.583814) (xy 89.163434 -433.564238) (xy 89.182958 -433.549986)
			(xy 89.205924 -433.542447) (xy 89.218008 -433.541932) (xy 90.157808 -433.541932) (xy 90.169921 -433.54231)
			(xy 90.192954 -433.549815) (xy 90.212529 -433.564086) (xy 90.226723 -433.583717) (xy 90.234137 -433.60678)
			(xy 90.234516 -433.618894) (xy 90.234516 -436.160418) (xy 90.234107 -436.172513) (xy 90.22664 -436.195522)
			(xy 90.21244 -436.215105) (xy 90.192892 -436.229353) (xy 90.169902 -436.236877) (xy 90.157808 -436.23738)
			(xy 89.218008 -436.23738) (xy 89.205898 -436.236977) (xy 89.182867 -436.229477) (xy 89.163292 -436.215213)
			(xy 89.149098 -436.195587) (xy 89.14168 -436.17253) (xy 89.1413 -436.160418) (xy 88.206752 -436.160418)
			(xy 88.212389 -436.164514) (xy 88.226583 -436.184051) (xy 88.234047 -436.207018) (xy 88.23452 -436.219092)
			(xy 88.23452 -438.760616) (xy 88.234049 -438.77269) (xy 88.226584 -438.795656) (xy 88.212389 -438.815191)
			(xy 88.192852 -438.829386) (xy 88.169886 -438.83685) (xy 88.157812 -438.837324) (xy 87.218012 -438.837324)
			(xy 87.20594 -438.836826) (xy 87.182976 -438.829369) (xy 87.16344 -438.81518) (xy 87.149244 -438.79565)
			(xy 87.141779 -438.772688) (xy 87.141304 -438.760616) (xy 86.234524 -438.760616) (xy 86.234524 -439.760614)
			(xy 89.1413 -439.760614) (xy 89.1413 -437.21909) (xy 89.141798 -437.207004) (xy 89.149253 -437.18401)
			(xy 89.163433 -437.164434) (xy 89.182957 -437.150182) (xy 89.205924 -437.142643) (xy 89.218008 -437.142128)
			(xy 90.157808 -437.142128) (xy 90.16992 -437.14251) (xy 90.192952 -437.150015) (xy 90.212528 -437.164284)
			(xy 90.226721 -437.183915) (xy 90.234137 -437.206976) (xy 90.234516 -437.21909) (xy 90.234516 -438.760616)
			(xy 125.241304 -438.760616) (xy 125.241304 -436.219092) (xy 125.241706 -436.207008) (xy 125.249177 -436.184023)
			(xy 125.263386 -436.164471) (xy 125.282941 -436.150268) (xy 125.305928 -436.142803) (xy 125.318012 -436.142384)
			(xy 126.257812 -436.142384) (xy 126.269886 -436.142854) (xy 126.292853 -436.150319) (xy 126.307101 -436.160672)
			(xy 127.240792 -436.160672) (xy 127.240792 -433.619148) (xy 127.241301 -433.607101) (xy 127.248719 -433.584178)
			(xy 127.262848 -433.564662) (xy 127.282308 -433.550457) (xy 127.305201 -433.542948) (xy 127.317246 -433.54244)
			(xy 128.257554 -433.54244) (xy 128.269641 -433.542947) (xy 128.29264 -433.550391) (xy 128.312221 -433.564567)
			(xy 128.326473 -433.584093) (xy 128.334006 -433.607063) (xy 128.334516 -433.619148) (xy 128.334516 -435.160674)
			(xy 129.240788 -435.160674) (xy 129.240788 -432.61915) (xy 129.241268 -432.607038) (xy 129.248763 -432.584001)
			(xy 129.263005 -432.564405) (xy 129.282601 -432.550163) (xy 129.305638 -432.542668) (xy 129.31775 -432.542188)
			(xy 130.25755 -432.542188) (xy 130.269662 -432.542668) (xy 130.292699 -432.550163) (xy 130.306889 -432.560476)
			(xy 131.241292 -432.560476) (xy 131.241292 -431.833274) (xy 131.241544 -431.824517) (xy 131.245523 -431.807459)
			(xy 131.249166 -431.799492) (xy 131.482592 -431.323242) (xy 131.487322 -431.312737) (xy 131.490803 -431.289971)
			(xy 131.487305 -431.267208) (xy 131.482592 -431.256694) (xy 131.249166 -430.780444) (xy 131.245515 -430.772478)
			(xy 131.241533 -430.755421) (xy 131.241292 -430.746662) (xy 131.241292 -430.018952) (xy 131.241723 -430.006875)
			(xy 131.249199 -429.983906) (xy 131.263404 -429.96437) (xy 131.282949 -429.950177) (xy 131.305923 -429.942716)
			(xy 131.318 -429.942244) (xy 132.2578 -429.942244) (xy 132.26987 -429.942764) (xy 132.292829 -429.95022)
			(xy 132.312362 -429.964404) (xy 132.326558 -429.983928) (xy 132.334029 -430.006883) (xy 132.334508 -430.018952)
			(xy 132.334508 -431.560478) (xy 133.241288 -431.560478) (xy 133.241288 -430.833276) (xy 133.241541 -430.824519)
			(xy 133.245519 -430.807462) (xy 133.249162 -430.799494) (xy 133.482588 -430.323244) (xy 133.487317 -430.312738)
			(xy 133.490798 -430.289973) (xy 133.4873 -430.26721) (xy 133.482588 -430.256696) (xy 133.249162 -429.780446)
			(xy 133.245512 -429.77248) (xy 133.241529 -429.755422) (xy 133.241288 -429.746664) (xy 133.241288 -429.018954)
			(xy 133.241669 -429.006857) (xy 133.249144 -428.983847) (xy 133.263351 -428.964264) (xy 133.282905 -428.950016)
			(xy 133.3059 -428.942494) (xy 133.317996 -428.941992) (xy 134.257796 -428.941992) (xy 134.269904 -428.942419)
			(xy 134.29293 -428.949917) (xy 134.307503 -428.960534) (xy 135.241284 -428.960534) (xy 135.241284 -426.41901)
			(xy 135.241717 -426.406917) (xy 135.249176 -426.383909) (xy 135.26337 -426.364325) (xy 135.282914 -426.350076)
			(xy 135.3059 -426.342551) (xy 135.317992 -426.342048) (xy 136.257792 -426.342048) (xy 136.269895 -426.342522)
			(xy 136.292914 -426.350013) (xy 136.312482 -426.364262) (xy 136.326679 -426.383868) (xy 136.334109 -426.406906)
			(xy 136.3345 -426.41901) (xy 136.3345 -427.960536) (xy 137.24128 -427.960536) (xy 137.24128 -425.419012)
			(xy 137.241774 -425.406939) (xy 137.249232 -425.383974) (xy 137.263421 -425.364438) (xy 137.282953 -425.350243)
			(xy 137.305915 -425.342778) (xy 137.317988 -425.342304) (xy 138.257788 -425.342304) (xy 138.269871 -425.342723)
			(xy 138.292856 -425.350189) (xy 138.312407 -425.364393) (xy 138.326611 -425.383944) (xy 138.334077 -425.406929)
			(xy 138.334496 -425.419012) (xy 138.334496 -427.960536) (xy 138.334066 -427.972614) (xy 138.326593 -427.995584)
			(xy 138.312387 -428.015122) (xy 138.292841 -428.029315) (xy 138.269866 -428.036774) (xy 138.257788 -428.037244)
			(xy 137.317988 -428.037244) (xy 137.305916 -428.036746) (xy 137.282955 -428.029285) (xy 137.263421 -428.015096)
			(xy 137.249226 -427.995567) (xy 137.241757 -427.972607) (xy 137.24128 -427.960536) (xy 136.3345 -427.960536)
			(xy 136.3345 -428.960534) (xy 136.334022 -428.972621) (xy 136.326561 -428.995616) (xy 136.312376 -429.015192)
			(xy 136.292848 -429.029443) (xy 136.269878 -429.036981) (xy 136.257792 -429.037496) (xy 135.317992 -429.037496)
			(xy 135.305882 -429.037091) (xy 135.282854 -429.029588) (xy 135.263281 -429.015324) (xy 135.249086 -428.9957)
			(xy 135.241667 -428.972645) (xy 135.241284 -428.960534) (xy 134.307503 -428.960534) (xy 134.312502 -428.964176)
			(xy 134.326697 -428.983795) (xy 134.33412 -429.006845) (xy 134.334504 -429.018954) (xy 134.334504 -431.560478)
			(xy 134.333975 -431.572562) (xy 134.326529 -431.595555) (xy 134.312357 -431.615131) (xy 134.29284 -431.629384)
			(xy 134.269878 -431.636924) (xy 134.257796 -431.63744) (xy 133.317996 -431.63744) (xy 133.305891 -431.636988)
			(xy 133.28287 -431.629492) (xy 133.263301 -431.615238) (xy 133.249105 -431.595627) (xy 133.241677 -431.572584)
			(xy 133.241288 -431.560478) (xy 132.334508 -431.560478) (xy 132.334508 -432.560476) (xy 132.334067 -432.572557)
			(xy 132.326606 -432.595539) (xy 132.312407 -432.61509) (xy 132.292861 -432.629295) (xy 132.269881 -432.636763)
			(xy 132.2578 -432.637184) (xy 131.318 -432.637184) (xy 131.305915 -432.636787) (xy 131.282928 -432.629317)
			(xy 131.263376 -432.615107) (xy 131.249172 -432.59555) (xy 131.241709 -432.572561) (xy 131.241292 -432.560476)
			(xy 130.306889 -432.560476) (xy 130.312295 -432.564405) (xy 130.326537 -432.584001) (xy 130.334032 -432.607038)
			(xy 130.334512 -432.61915) (xy 130.334512 -435.160674) (xy 130.333967 -435.172782) (xy 130.326493 -435.195816)
			(xy 130.312268 -435.215414) (xy 130.292684 -435.229658) (xy 130.269658 -435.237155) (xy 130.25755 -435.237636)
			(xy 129.31775 -435.237636) (xy 129.30563 -435.23723) (xy 129.282581 -435.229726) (xy 129.262978 -435.215468)
			(xy 129.248739 -435.195851) (xy 129.241258 -435.172794) (xy 129.240788 -435.160674) (xy 128.334516 -435.160674)
			(xy 128.334516 -436.160672) (xy 128.334017 -436.172719) (xy 128.326593 -436.195641) (xy 128.312462 -436.215156)
			(xy 128.293001 -436.229361) (xy 128.270107 -436.236871) (xy 128.258062 -436.23738) (xy 127.317754 -436.23738)
			(xy 127.305664 -436.236932) (xy 127.282665 -436.229465) (xy 127.263088 -436.215273) (xy 127.248838 -436.195737)
			(xy 127.241304 -436.172761) (xy 127.240792 -436.160672) (xy 126.307101 -436.160672) (xy 126.312389 -436.164514)
			(xy 126.326583 -436.184051) (xy 126.334047 -436.207018) (xy 126.33452 -436.219092) (xy 126.33452 -438.760616)
			(xy 126.334049 -438.77269) (xy 126.326584 -438.795656) (xy 126.312389 -438.815191) (xy 126.292852 -438.829386)
			(xy 126.269886 -438.83685) (xy 126.257812 -438.837324) (xy 125.318012 -438.837324) (xy 125.30594 -438.836826)
			(xy 125.282976 -438.829369) (xy 125.26344 -438.81518) (xy 125.249244 -438.79565) (xy 125.241779 -438.772688)
			(xy 125.241304 -438.760616) (xy 90.234516 -438.760616) (xy 90.234516 -439.760614) (xy 127.2413 -439.760614)
			(xy 127.2413 -437.21909) (xy 127.241798 -437.207004) (xy 127.249253 -437.18401) (xy 127.263433 -437.164434)
			(xy 127.282957 -437.150182) (xy 127.305924 -437.142643) (xy 127.318008 -437.142128) (xy 128.257808 -437.142128)
			(xy 128.26992 -437.14251) (xy 128.292952 -437.150015) (xy 128.312528 -437.164284) (xy 128.326721 -437.183915)
			(xy 128.334137 -437.206976) (xy 128.334516 -437.21909) (xy 128.334516 -438.760616) (xy 129.241296 -438.760616)
			(xy 129.241296 -436.219092) (xy 129.241758 -436.207017) (xy 129.249223 -436.184049) (xy 129.26342 -436.164511)
			(xy 129.282959 -436.150317) (xy 129.305929 -436.142856) (xy 129.318004 -436.142384) (xy 130.257804 -436.142384)
			(xy 130.269878 -436.142861) (xy 130.292844 -436.150323) (xy 130.307088 -436.160672) (xy 131.240784 -436.160672)
			(xy 131.240784 -433.619148) (xy 131.2413 -433.607102) (xy 131.248718 -433.58418) (xy 131.262845 -433.564665)
			(xy 131.282303 -433.55046) (xy 131.305194 -433.54295) (xy 131.317238 -433.54244) (xy 132.257546 -433.54244)
			(xy 132.269638 -433.542868) (xy 132.29264 -433.550338) (xy 132.312219 -433.564534) (xy 132.326468 -433.584075)
			(xy 132.333999 -433.607057) (xy 132.334508 -433.619148) (xy 132.334508 -435.160674) (xy 133.24078 -435.160674)
			(xy 133.24078 -432.61915) (xy 133.24117 -432.607029) (xy 133.248676 -432.583977) (xy 133.262938 -432.564372)
			(xy 133.282559 -432.550134) (xy 133.30562 -432.542655) (xy 133.317742 -432.542188) (xy 134.257542 -432.542188)
			(xy 134.269654 -432.542675) (xy 134.29269 -432.550168) (xy 134.306876 -432.560476) (xy 135.241284 -432.560476)
			(xy 135.241284 -431.833274) (xy 135.241537 -431.824517) (xy 135.245515 -431.80746) (xy 135.249158 -431.799492)
			(xy 135.482584 -431.323242) (xy 135.487314 -431.312737) (xy 135.490795 -431.289971) (xy 135.487297 -431.267208)
			(xy 135.482584 -431.256694) (xy 135.249158 -430.780444) (xy 135.245507 -430.772479) (xy 135.241524 -430.755421)
			(xy 135.241284 -430.746662) (xy 135.241284 -430.018952) (xy 135.241723 -430.006876) (xy 135.249198 -429.983908)
			(xy 135.263401 -429.964373) (xy 135.282944 -429.95018) (xy 135.305915 -429.942717) (xy 135.317992 -429.942244)
			(xy 136.257792 -429.942244) (xy 136.269861 -429.94277) (xy 136.29282 -429.950225) (xy 136.312353 -429.964407)
			(xy 136.32655 -429.98393) (xy 136.334021 -430.006883) (xy 136.3345 -430.018952) (xy 136.3345 -431.560478)
			(xy 137.24128 -431.560478) (xy 137.24128 -430.833276) (xy 137.241534 -430.824519) (xy 137.245512 -430.807462)
			(xy 137.249154 -430.799494) (xy 137.48258 -430.323244) (xy 137.487309 -430.312738) (xy 137.490791 -430.289973)
			(xy 137.487293 -430.26721) (xy 137.48258 -430.256696) (xy 137.249154 -429.780446) (xy 137.245503 -429.77248)
			(xy 137.241521 -429.755423) (xy 137.24128 -429.746664) (xy 137.24128 -429.018954) (xy 137.241669 -429.006858)
			(xy 137.249143 -428.983849) (xy 137.263348 -428.964267) (xy 137.2829 -428.950019) (xy 137.305893 -428.942495)
			(xy 137.317988 -428.941992) (xy 138.257788 -428.941992) (xy 138.269895 -428.942427) (xy 138.292921 -428.949922)
			(xy 138.307489 -428.960534) (xy 139.241276 -428.960534) (xy 139.241276 -426.41901) (xy 139.241717 -426.406917)
			(xy 139.249175 -426.383911) (xy 139.263367 -426.364328) (xy 139.282909 -426.350078) (xy 139.305893 -426.342553)
			(xy 139.317984 -426.342048) (xy 140.257784 -426.342048) (xy 140.269887 -426.342529) (xy 140.292905 -426.350018)
			(xy 140.312473 -426.364265) (xy 140.32667 -426.383869) (xy 140.334101 -426.406906) (xy 140.334492 -426.41901)
			(xy 140.334492 -427.960536) (xy 142.241016 -427.960536) (xy 142.241016 -425.419012) (xy 142.24147 -425.406961)
			(xy 142.248902 -425.384033) (xy 142.263043 -425.364516) (xy 142.282516 -425.350313) (xy 142.30542 -425.342809)
			(xy 142.31747 -425.342304) (xy 143.257778 -425.342304) (xy 143.269863 -425.342825) (xy 143.292857 -425.350272)
			(xy 143.312434 -425.364446) (xy 143.326686 -425.383966) (xy 143.334225 -425.406929) (xy 143.33474 -425.419012)
			(xy 143.33474 -427.960536) (xy 143.334272 -427.972584) (xy 143.326834 -427.995504) (xy 143.312694 -428.015016)
			(xy 143.293228 -428.029219) (xy 143.270333 -428.036732) (xy 143.258286 -428.037244) (xy 142.317978 -428.037244)
			(xy 142.305886 -428.036811) (xy 142.282882 -428.029347) (xy 142.263301 -428.015152) (xy 142.249051 -427.99561)
			(xy 142.241523 -427.972627) (xy 142.241016 -427.960536) (xy 140.334492 -427.960536) (xy 140.334492 -428.960534)
			(xy 140.334022 -428.972622) (xy 140.32656 -428.995619) (xy 140.312373 -429.015195) (xy 140.292843 -429.029446)
			(xy 140.269871 -429.036983) (xy 140.257784 -429.037496) (xy 139.317984 -429.037496) (xy 139.305874 -429.037097)
			(xy 139.282845 -429.029593) (xy 139.263272 -429.015327) (xy 139.249078 -428.995702) (xy 139.241659 -428.972646)
			(xy 139.241276 -428.960534) (xy 138.307489 -428.960534) (xy 138.312493 -428.964179) (xy 138.326689 -428.983796)
			(xy 138.334111 -429.006845) (xy 138.334496 -429.018954) (xy 138.334496 -431.560478) (xy 138.333975 -431.572563)
			(xy 138.326528 -431.595557) (xy 138.312354 -431.615134) (xy 138.292834 -431.629386) (xy 138.269871 -431.636925)
			(xy 138.257788 -431.63744) (xy 137.317988 -431.63744) (xy 137.305882 -431.636995) (xy 137.282862 -431.629497)
			(xy 137.263292 -431.615241) (xy 137.249096 -431.595628) (xy 137.241669 -431.572585) (xy 137.24128 -431.560478)
			(xy 136.3345 -431.560478) (xy 136.3345 -432.560476) (xy 136.334067 -432.572558) (xy 136.326605 -432.595542)
			(xy 136.312404 -432.615093) (xy 136.292856 -432.629297) (xy 136.269874 -432.636764) (xy 136.257792 -432.637184)
			(xy 135.317992 -432.637184) (xy 135.305906 -432.636794) (xy 135.282919 -432.629321) (xy 135.263367 -432.61511)
			(xy 135.249164 -432.595552) (xy 135.241701 -432.572562) (xy 135.241284 -432.560476) (xy 134.306876 -432.560476)
			(xy 134.312287 -432.564408) (xy 134.326529 -432.584003) (xy 134.334024 -432.607038) (xy 134.334504 -432.61915)
			(xy 134.334504 -435.160674) (xy 134.333967 -435.172783) (xy 134.326492 -435.195818) (xy 134.312265 -435.215417)
			(xy 134.292679 -435.229661) (xy 134.269651 -435.237156) (xy 134.257542 -435.237636) (xy 133.317742 -435.237636)
			(xy 133.305619 -435.237204) (xy 133.282557 -435.22972) (xy 133.262939 -435.215473) (xy 133.248687 -435.195857)
			(xy 133.241199 -435.172797) (xy 133.24078 -435.160674) (xy 132.334508 -435.160674) (xy 132.334508 -436.160672)
			(xy 132.334016 -436.17272) (xy 132.326592 -436.195643) (xy 132.312459 -436.215159) (xy 132.292996 -436.229363)
			(xy 132.2701 -436.236872) (xy 132.258054 -436.23738) (xy 131.317746 -436.23738) (xy 131.305661 -436.236854)
			(xy 131.282665 -436.229412) (xy 131.263086 -436.21524) (xy 131.248833 -436.19572) (xy 131.241297 -436.172755)
			(xy 131.240784 -436.160672) (xy 130.307088 -436.160672) (xy 130.31238 -436.164517) (xy 130.326575 -436.184053)
			(xy 130.334039 -436.207018) (xy 130.334512 -436.219092) (xy 130.334512 -438.760616) (xy 130.334049 -438.772691)
			(xy 130.326583 -438.795658) (xy 130.312386 -438.815194) (xy 130.292847 -438.829388) (xy 130.269879 -438.836851)
			(xy 130.257804 -438.837324) (xy 129.318004 -438.837324) (xy 129.305931 -438.836833) (xy 129.282967 -438.829373)
			(xy 129.263431 -438.815183) (xy 129.249236 -438.795651) (xy 129.241771 -438.772689) (xy 129.241296 -438.760616)
			(xy 128.334516 -438.760616) (xy 128.334516 -439.760614) (xy 131.241292 -439.760614) (xy 131.241292 -437.21909)
			(xy 131.241798 -437.207005) (xy 131.249252 -437.184012) (xy 131.26343 -437.164436) (xy 131.282952 -437.150184)
			(xy 131.305917 -437.142644) (xy 131.318 -437.142128) (xy 132.2578 -437.142128) (xy 132.269912 -437.142516)
			(xy 132.292944 -437.150019) (xy 132.312519 -437.164287) (xy 132.326713 -437.183916) (xy 132.334129 -437.206977)
			(xy 132.334508 -437.21909) (xy 132.334508 -438.760616) (xy 133.241288 -438.760616) (xy 133.241288 -436.219092)
			(xy 133.241757 -436.207017) (xy 133.249222 -436.184051) (xy 133.263417 -436.164514) (xy 133.282954 -436.15032)
			(xy 133.305921 -436.142857) (xy 133.317996 -436.142384) (xy 134.257796 -436.142384) (xy 134.26987 -436.142868)
			(xy 134.292835 -436.150328) (xy 134.307075 -436.160672) (xy 135.240776 -436.160672) (xy 135.240776 -433.619148)
			(xy 135.2413 -433.607103) (xy 135.248717 -433.584183) (xy 135.262842 -433.564668) (xy 135.282298 -433.550462)
			(xy 135.305187 -433.542951) (xy 135.31723 -433.54244) (xy 136.257538 -433.54244) (xy 136.26963 -433.542875)
			(xy 136.292631 -433.550342) (xy 136.312211 -433.564537) (xy 136.32646 -433.584077) (xy 136.333991 -433.607058)
			(xy 136.3345 -433.619148) (xy 136.3345 -435.160674) (xy 137.240772 -435.160674) (xy 137.240772 -432.61915)
			(xy 137.24117 -432.607029) (xy 137.248675 -432.583979) (xy 137.262935 -432.564375) (xy 137.282554 -432.550136)
			(xy 137.305613 -432.542656) (xy 137.317734 -432.542188) (xy 138.257534 -432.542188) (xy 138.269645 -432.542682)
			(xy 138.292681 -432.550172) (xy 138.306863 -432.560476) (xy 139.241276 -432.560476) (xy 139.241276 -431.833274)
			(xy 139.241529 -431.824517) (xy 139.245508 -431.80746) (xy 139.24915 -431.799492) (xy 139.482576 -431.323242)
			(xy 139.487307 -431.312737) (xy 139.490788 -431.289971) (xy 139.487289 -431.267208) (xy 139.482576 -431.256694)
			(xy 139.24915 -430.780444) (xy 139.245499 -430.772479) (xy 139.241516 -430.755421) (xy 139.241276 -430.746662)
			(xy 139.241276 -430.018952) (xy 139.241723 -430.006877) (xy 139.249197 -429.98391) (xy 139.263398 -429.964376)
			(xy 139.282939 -429.950182) (xy 139.305908 -429.942718) (xy 139.317984 -429.942244) (xy 140.257784 -429.942244)
			(xy 140.269853 -429.942777) (xy 140.292812 -429.950229) (xy 140.312345 -429.96441) (xy 140.326541 -429.983931)
			(xy 140.334013 -430.006883) (xy 140.334492 -430.018952) (xy 140.334492 -431.560478) (xy 142.241524 -431.560478)
			(xy 142.241524 -430.833276) (xy 142.241773 -430.824519) (xy 142.245754 -430.807461) (xy 142.249398 -430.799494)
			(xy 142.482824 -430.323244) (xy 142.487551 -430.312738) (xy 142.491031 -430.289973) (xy 142.487535 -430.267211)
			(xy 142.482824 -430.256696) (xy 142.249398 -429.780446) (xy 142.24575 -429.772479) (xy 142.241765 -429.755422)
			(xy 142.241524 -429.746664) (xy 142.241524 -429.018954) (xy 142.241968 -429.006864) (xy 142.249435 -428.983864)
			(xy 142.263628 -428.964286) (xy 142.283165 -428.950037) (xy 142.306143 -428.942503) (xy 142.318232 -428.941992)
			(xy 143.258032 -428.941992) (xy 143.270142 -428.942389) (xy 143.293169 -428.949896) (xy 143.307763 -428.960534)
			(xy 144.241012 -428.960534) (xy 144.241012 -426.41901) (xy 144.24152 -426.406899) (xy 144.249001 -426.38386)
			(xy 144.263235 -426.36426) (xy 144.282828 -426.350018) (xy 144.305863 -426.342526) (xy 144.317974 -426.342048)
			(xy 145.257774 -426.342048) (xy 145.269896 -426.342482) (xy 145.292956 -426.349969) (xy 145.312572 -426.364216)
			(xy 145.326824 -426.38383) (xy 145.334315 -426.406888) (xy 145.334736 -426.41901) (xy 145.334736 -427.960536)
			(xy 146.241008 -427.960536) (xy 146.241008 -425.419012) (xy 146.24147 -425.406962) (xy 146.248901 -425.384035)
			(xy 146.263041 -425.364518) (xy 146.282511 -425.350315) (xy 146.305413 -425.34281) (xy 146.317462 -425.342304)
			(xy 147.25777 -425.342304) (xy 147.269854 -425.342832) (xy 147.292848 -425.350276) (xy 147.312425 -425.364448)
			(xy 147.326678 -425.383967) (xy 147.334217 -425.40693) (xy 147.334732 -425.419012) (xy 147.334732 -427.960536)
			(xy 147.334272 -427.972585) (xy 147.326833 -427.995506) (xy 147.312691 -428.015019) (xy 147.293223 -428.029222)
			(xy 147.270325 -428.036733) (xy 147.258278 -428.037244) (xy 146.31797 -428.037244) (xy 146.305877 -428.036818)
			(xy 146.282873 -428.029351) (xy 146.263292 -428.015154) (xy 146.249043 -427.995612) (xy 146.241515 -427.972627)
			(xy 146.241008 -427.960536) (xy 145.334736 -427.960536) (xy 145.334736 -428.960534) (xy 145.334317 -428.972653)
			(xy 145.326817 -428.995702) (xy 145.312562 -429.015305) (xy 145.292948 -429.029545) (xy 145.269893 -429.037026)
			(xy 145.257774 -429.037496) (xy 144.317974 -429.037496) (xy 144.305861 -429.037011) (xy 144.282823 -429.029521)
			(xy 144.263225 -429.015281) (xy 144.248983 -428.995684) (xy 144.24149 -428.972646) (xy 144.241012 -428.960534)
			(xy 143.307763 -428.960534) (xy 143.312741 -428.964163) (xy 143.326934 -428.983788) (xy 143.334356 -429.006843)
			(xy 143.33474 -429.018954) (xy 143.33474 -431.560478) (xy 143.334273 -431.572568) (xy 143.32682 -431.595572)
			(xy 143.312634 -431.615154) (xy 143.293099 -431.629404) (xy 143.270121 -431.636933) (xy 143.258032 -431.63744)
			(xy 142.318232 -431.63744) (xy 142.306129 -431.636957) (xy 142.283109 -431.629471) (xy 142.263539 -431.615225)
			(xy 142.249342 -431.59562) (xy 142.241913 -431.572582) (xy 142.241524 -431.560478) (xy 140.334492 -431.560478)
			(xy 140.334492 -432.560476) (xy 140.334067 -432.572559) (xy 140.326604 -432.595544) (xy 140.312401 -432.615096)
			(xy 140.292851 -432.6293) (xy 140.269867 -432.636765) (xy 140.257784 -432.637184) (xy 139.317984 -432.637184)
			(xy 139.305898 -432.636801) (xy 139.282911 -432.629326) (xy 139.263359 -432.615113) (xy 139.249156 -432.595553)
			(xy 139.241693 -432.572562) (xy 139.241276 -432.560476) (xy 138.306863 -432.560476) (xy 138.312278 -432.56441)
			(xy 138.32652 -432.584004) (xy 138.334016 -432.607039) (xy 138.334496 -432.61915) (xy 138.334496 -435.160674)
			(xy 138.333967 -435.172784) (xy 138.326491 -435.19582) (xy 138.312262 -435.21542) (xy 138.292674 -435.229663)
			(xy 138.269643 -435.237157) (xy 138.257534 -435.237636) (xy 137.317734 -435.237636) (xy 137.30561 -435.237211)
			(xy 137.282548 -435.229725) (xy 137.26293 -435.215475) (xy 137.248679 -435.195859) (xy 137.241191 -435.172798)
			(xy 137.240772 -435.160674) (xy 136.3345 -435.160674) (xy 136.3345 -436.160672) (xy 136.334016 -436.172721)
			(xy 136.326591 -436.195645) (xy 136.312457 -436.215162) (xy 136.292991 -436.229366) (xy 136.270093 -436.236873)
			(xy 136.258046 -436.23738) (xy 135.317738 -436.23738) (xy 135.305652 -436.236861) (xy 135.282656 -436.229417)
			(xy 135.263078 -436.215243) (xy 135.248825 -436.195721) (xy 135.241289 -436.172756) (xy 135.240776 -436.160672)
			(xy 134.307075 -436.160672) (xy 134.312372 -436.16452) (xy 134.326567 -436.184054) (xy 134.334031 -436.207019)
			(xy 134.334504 -436.219092) (xy 134.334504 -438.760616) (xy 134.334049 -438.772692) (xy 134.326582 -438.79566)
			(xy 134.312383 -438.815197) (xy 134.292842 -438.829391) (xy 134.269872 -438.836852) (xy 134.257796 -438.837324)
			(xy 133.317996 -438.837324) (xy 133.305923 -438.836839) (xy 133.282958 -438.829378) (xy 133.263423 -438.815186)
			(xy 133.249228 -438.795652) (xy 133.241763 -438.772689) (xy 133.241288 -438.760616) (xy 132.334508 -438.760616)
			(xy 132.334508 -439.760614) (xy 135.241284 -439.760614) (xy 135.241284 -437.21909) (xy 135.2417 -437.206996)
			(xy 135.249165 -437.183987) (xy 135.263363 -437.164404) (xy 135.28291 -437.150155) (xy 135.305899 -437.142631)
			(xy 135.317992 -437.142128) (xy 136.257792 -437.142128) (xy 136.269903 -437.142523) (xy 136.292935 -437.150024)
			(xy 136.312511 -437.16429) (xy 136.326705 -437.183918) (xy 136.334121 -437.206977) (xy 136.3345 -437.21909)
			(xy 136.3345 -438.760616) (xy 137.24128 -438.760616) (xy 137.24128 -436.219092) (xy 137.241757 -436.207018)
			(xy 137.249221 -436.184053) (xy 137.263414 -436.164517) (xy 137.282949 -436.150322) (xy 137.305914 -436.142858)
			(xy 137.317988 -436.142384) (xy 138.257788 -436.142384) (xy 138.269869 -436.142823) (xy 138.29285 -436.150286)
			(xy 138.307149 -436.160672) (xy 139.240768 -436.160672) (xy 139.240768 -433.619148) (xy 139.2413 -433.607103)
			(xy 139.248716 -433.584185) (xy 139.262839 -433.564671) (xy 139.282293 -433.550465) (xy 139.30518 -433.542952)
			(xy 139.317222 -433.54244) (xy 140.25753 -433.54244) (xy 140.269621 -433.542882) (xy 140.292623 -433.550347)
			(xy 140.312202 -433.56454) (xy 140.326452 -433.584078) (xy 140.333983 -433.607058) (xy 140.334492 -433.619148)
			(xy 140.334492 -435.160674) (xy 142.241016 -435.160674) (xy 142.241016 -432.61915) (xy 142.241469 -432.607035)
			(xy 142.248967 -432.583994) (xy 142.263215 -432.564395) (xy 142.282819 -432.550154) (xy 142.305863 -432.542664)
			(xy 142.317978 -432.542188) (xy 143.257778 -432.542188) (xy 143.269886 -432.54273) (xy 143.29292 -432.550205)
			(xy 143.30707 -432.560476) (xy 144.24152 -432.560476) (xy 144.24152 -431.833274) (xy 144.241769 -431.824517)
			(xy 144.24575 -431.807459) (xy 144.249394 -431.799492) (xy 144.48282 -431.323242) (xy 144.487549 -431.312736)
			(xy 144.491028 -431.289971) (xy 144.487531 -431.267209) (xy 144.48282 -431.256694) (xy 144.249394 -430.780444)
			(xy 144.245745 -430.772478) (xy 144.241761 -430.75542) (xy 144.24152 -430.746662) (xy 144.24152 -430.018952)
			(xy 144.241924 -430.006872) (xy 144.249403 -429.983899) (xy 144.263614 -429.96436) (xy 144.283167 -429.950168)
			(xy 144.306148 -429.942712) (xy 144.318228 -429.942244) (xy 145.258028 -429.942244) (xy 145.270099 -429.942739)
			(xy 145.293059 -429.950204) (xy 145.312592 -429.964394) (xy 145.326787 -429.983923) (xy 145.334258 -430.006881)
			(xy 145.334736 -430.018952) (xy 145.334736 -431.560478) (xy 146.241516 -431.560478) (xy 146.241516 -430.833276)
			(xy 146.241766 -430.824519) (xy 146.245746 -430.807461) (xy 146.24939 -430.799494) (xy 146.482816 -430.323244)
			(xy 146.487543 -430.312738) (xy 146.491023 -430.289973) (xy 146.487527 -430.267211) (xy 146.482816 -430.256696)
			(xy 146.24939 -429.780446) (xy 146.245741 -429.77248) (xy 146.241757 -429.755422) (xy 146.241516 -429.746664)
			(xy 146.241516 -429.018954) (xy 146.241968 -429.006864) (xy 146.249434 -428.983866) (xy 146.263626 -428.964289)
			(xy 146.28316 -428.950039) (xy 146.306136 -428.942504) (xy 146.318224 -428.941992) (xy 147.258024 -428.941992)
			(xy 147.270133 -428.942396) (xy 147.29316 -428.949901) (xy 147.307749 -428.960534) (xy 148.241004 -428.960534)
			(xy 148.241004 -426.41901) (xy 148.24152 -426.406899) (xy 148.249 -426.383862) (xy 148.263232 -426.364263)
			(xy 148.282823 -426.35002) (xy 148.305856 -426.342527) (xy 148.317966 -426.342048) (xy 149.257766 -426.342048)
			(xy 149.269888 -426.342489) (xy 149.292947 -426.349973) (xy 149.312564 -426.364219) (xy 149.326816 -426.383831)
			(xy 149.334307 -426.406888) (xy 149.334728 -426.41901) (xy 149.334728 -427.960536) (xy 150.241 -427.960536)
			(xy 150.241 -425.419012) (xy 150.24147 -425.406962) (xy 150.2489 -425.384037) (xy 150.263038 -425.364521)
			(xy 150.282506 -425.350318) (xy 150.305406 -425.342811) (xy 150.317454 -425.342304) (xy 151.257762 -425.342304)
			(xy 151.269846 -425.342839) (xy 151.292839 -425.350281) (xy 151.312417 -425.364451) (xy 151.32667 -425.383968)
			(xy 151.334209 -425.40693) (xy 151.334724 -425.419012) (xy 151.334724 -427.960536) (xy 151.334271 -427.972586)
			(xy 151.326832 -427.995508) (xy 151.312688 -428.015022) (xy 151.293218 -428.029225) (xy 151.270318 -428.036734)
			(xy 151.25827 -428.037244) (xy 150.317962 -428.037244) (xy 150.305869 -428.036825) (xy 150.282864 -428.029356)
			(xy 150.263284 -428.015157) (xy 150.249035 -427.995613) (xy 150.241507 -427.972628) (xy 150.241 -427.960536)
			(xy 149.334728 -427.960536) (xy 149.334728 -428.960534) (xy 149.334317 -428.972654) (xy 149.326816 -428.995704)
			(xy 149.31256 -429.015308) (xy 149.292943 -429.029547) (xy 149.269886 -429.037027) (xy 149.257766 -429.037496)
			(xy 148.317966 -429.037496) (xy 148.305853 -429.037018) (xy 148.282814 -429.029525) (xy 148.263216 -429.015284)
			(xy 148.248975 -428.995686) (xy 148.241482 -428.972647) (xy 148.241004 -428.960534) (xy 147.307749 -428.960534)
			(xy 147.312732 -428.964166) (xy 147.326926 -428.983789) (xy 147.334348 -429.006843) (xy 147.334732 -429.018954)
			(xy 147.334732 -431.560478) (xy 147.334273 -431.572569) (xy 147.326819 -431.595574) (xy 147.312632 -431.615156)
			(xy 147.293094 -431.629407) (xy 147.270114 -431.636934) (xy 147.258024 -431.63744) (xy 146.318224 -431.63744)
			(xy 146.30612 -431.636964) (xy 146.283101 -431.629476) (xy 146.263531 -431.615228) (xy 146.249334 -431.595622)
			(xy 146.241905 -431.572583) (xy 146.241516 -431.560478) (xy 145.334736 -431.560478) (xy 145.334736 -432.560476)
			(xy 145.334216 -432.572547) (xy 145.326763 -432.595508) (xy 145.31258 -432.615043) (xy 145.293055 -432.62924)
			(xy 145.270098 -432.636708) (xy 145.258028 -432.637184) (xy 144.318228 -432.637184) (xy 144.306144 -432.636763)
			(xy 144.283159 -432.6293) (xy 144.263606 -432.615097) (xy 144.249402 -432.595545) (xy 144.241938 -432.57256)
			(xy 144.24152 -432.560476) (xy 143.30707 -432.560476) (xy 143.312518 -432.564431) (xy 143.326762 -432.584015)
			(xy 143.334259 -432.607042) (xy 143.33474 -432.61915) (xy 143.33474 -435.160674) (xy 143.334318 -435.172798)
			(xy 143.32683 -435.195859) (xy 143.31258 -435.215477) (xy 143.292963 -435.229728) (xy 143.269902 -435.237217)
			(xy 143.257778 -435.237636) (xy 142.317978 -435.237636) (xy 142.305852 -435.237258) (xy 142.282788 -435.229757)
			(xy 142.263171 -435.215495) (xy 142.248921 -435.195869) (xy 142.241434 -435.172801) (xy 142.241016 -435.160674)
			(xy 140.334492 -435.160674) (xy 140.334492 -436.160672) (xy 140.334016 -436.172722) (xy 140.32659 -436.195648)
			(xy 140.312454 -436.215164) (xy 140.292986 -436.229368) (xy 140.270086 -436.236874) (xy 140.258038 -436.23738)
			(xy 139.31773 -436.23738) (xy 139.305644 -436.236867) (xy 139.282648 -436.229421) (xy 139.263069 -436.215246)
			(xy 139.248817 -436.195723) (xy 139.24128 -436.172756) (xy 139.240768 -436.160672) (xy 138.307149 -436.160672)
			(xy 138.3124 -436.164486) (xy 138.326605 -436.184032) (xy 138.334074 -436.207011) (xy 138.334496 -436.219092)
			(xy 138.334496 -438.760616) (xy 138.334049 -438.772693) (xy 138.326581 -438.795662) (xy 138.31238 -438.8152)
			(xy 138.292837 -438.829394) (xy 138.269865 -438.836853) (xy 138.257788 -438.837324) (xy 137.317988 -438.837324)
			(xy 137.305914 -438.836846) (xy 137.28295 -438.829382) (xy 137.263414 -438.815189) (xy 137.24922 -438.795654)
			(xy 137.241755 -438.77269) (xy 137.24128 -438.760616) (xy 136.3345 -438.760616) (xy 136.3345 -439.760614)
			(xy 139.241276 -439.760614) (xy 139.241276 -437.21909) (xy 139.2417 -437.206996) (xy 139.249164 -437.183989)
			(xy 139.26336 -437.164407) (xy 139.282905 -437.150158) (xy 139.305892 -437.142632) (xy 139.317984 -437.142128)
			(xy 140.257784 -437.142128) (xy 140.269895 -437.14253) (xy 140.292926 -437.150029) (xy 140.312502 -437.164293)
			(xy 140.326696 -437.18392) (xy 140.334112 -437.206978) (xy 140.334492 -437.21909) (xy 140.334492 -438.760616)
			(xy 142.241016 -438.760616) (xy 142.241016 -436.219092) (xy 142.241454 -436.20704) (xy 142.24889 -436.184111)
			(xy 142.263036 -436.164594) (xy 142.282512 -436.150392) (xy 142.305419 -436.142889) (xy 142.31747 -436.142384)
			(xy 143.257778 -436.142384) (xy 143.269871 -436.142827) (xy 143.292878 -436.150283) (xy 143.307215 -436.160672)
			(xy 144.241012 -436.160672) (xy 144.241012 -433.619148) (xy 144.241501 -433.607099) (xy 144.248922 -433.584173)
			(xy 144.263055 -433.564655) (xy 144.28252 -433.550451) (xy 144.305419 -433.542946) (xy 144.317466 -433.54244)
			(xy 145.257774 -433.54244) (xy 145.269862 -433.54293) (xy 145.292862 -433.550379) (xy 145.312442 -433.56456)
			(xy 145.326694 -433.584089) (xy 145.334226 -433.607062) (xy 145.334736 -433.619148) (xy 145.334736 -435.160674)
			(xy 146.241008 -435.160674) (xy 146.241008 -432.61915) (xy 146.241469 -432.607036) (xy 146.248966 -432.583996)
			(xy 146.263212 -432.564398) (xy 146.282814 -432.550157) (xy 146.305856 -432.542666) (xy 146.31797 -432.542188)
			(xy 147.25777 -432.542188) (xy 147.269878 -432.542737) (xy 147.292912 -432.550209) (xy 147.307058 -432.560476)
			(xy 148.241512 -432.560476) (xy 148.241512 -431.833274) (xy 148.241762 -431.824517) (xy 148.245742 -431.807459)
			(xy 148.249386 -431.799492) (xy 148.482812 -431.323242) (xy 148.487541 -431.312736) (xy 148.491021 -431.289971)
			(xy 148.487524 -431.267209) (xy 148.482812 -431.256694) (xy 148.249386 -430.780444) (xy 148.245737 -430.772478)
			(xy 148.241753 -430.75542) (xy 148.241512 -430.746662) (xy 148.241512 -430.018952) (xy 148.241924 -430.006873)
			(xy 148.249402 -429.983901) (xy 148.263611 -429.964363) (xy 148.283162 -429.950171) (xy 148.306141 -429.942713)
			(xy 148.31822 -429.942244) (xy 149.25802 -429.942244) (xy 149.270091 -429.942747) (xy 149.29305 -429.950209)
			(xy 149.312583 -429.964397) (xy 149.326778 -429.983924) (xy 149.334249 -430.006881) (xy 149.334728 -430.018952)
			(xy 149.334728 -431.560478) (xy 150.241508 -431.560478) (xy 150.241508 -430.833276) (xy 150.241759 -430.824519)
			(xy 150.245738 -430.807461) (xy 150.249382 -430.799494) (xy 150.482808 -430.323244) (xy 150.487536 -430.312738)
			(xy 150.491016 -430.289973) (xy 150.48752 -430.26721) (xy 150.482808 -430.256696) (xy 150.249382 -429.780446)
			(xy 150.245733 -429.77248) (xy 150.241749 -429.755422) (xy 150.241508 -429.746664) (xy 150.241508 -429.018954)
			(xy 150.241968 -429.006865) (xy 150.249433 -428.983868) (xy 150.263623 -428.964292) (xy 150.283155 -428.950042)
			(xy 150.306129 -428.942505) (xy 150.318216 -428.941992) (xy 151.258016 -428.941992) (xy 151.270125 -428.942402)
			(xy 151.293151 -428.949905) (xy 151.307736 -428.960534) (xy 152.240996 -428.960534) (xy 152.240996 -426.41901)
			(xy 152.24152 -426.4069) (xy 152.248999 -426.383864) (xy 152.263229 -426.364266) (xy 152.282818 -426.350023)
			(xy 152.305848 -426.342528) (xy 152.317958 -426.342048) (xy 153.257758 -426.342048) (xy 153.26988 -426.342496)
			(xy 153.292939 -426.349978) (xy 153.312555 -426.364222) (xy 153.326808 -426.383833) (xy 153.334299 -426.406889)
			(xy 153.33472 -426.41901) (xy 153.33472 -427.960536) (xy 154.240992 -427.960536) (xy 154.240992 -425.419012)
			(xy 154.24147 -425.406963) (xy 154.248898 -425.384039) (xy 154.263035 -425.364524) (xy 154.282501 -425.35032)
			(xy 154.305399 -425.342812) (xy 154.317446 -425.342304) (xy 155.257754 -425.342304) (xy 155.269838 -425.342846)
			(xy 155.292831 -425.350286) (xy 155.312408 -425.364454) (xy 155.326662 -425.38397) (xy 155.334201 -425.40693)
			(xy 155.334716 -425.419012) (xy 155.334716 -427.960536) (xy 155.334271 -427.972587) (xy 155.326831 -427.995511)
			(xy 155.312685 -428.015024) (xy 155.293213 -428.029227) (xy 155.270311 -428.036735) (xy 155.258262 -428.037244)
			(xy 154.317954 -428.037244) (xy 154.30586 -428.036832) (xy 154.282856 -428.02936) (xy 154.263275 -428.01516)
			(xy 154.249027 -427.995615) (xy 154.241499 -427.972628) (xy 154.240992 -427.960536) (xy 153.33472 -427.960536)
			(xy 153.33472 -428.960534) (xy 153.334369 -428.972663) (xy 153.326862 -428.99573) (xy 153.312594 -429.015348)
			(xy 153.292962 -429.029597) (xy 153.269887 -429.03708) (xy 153.257758 -429.037496) (xy 152.317958 -429.037496)
			(xy 152.305845 -429.037025) (xy 152.282806 -429.02953) (xy 152.263208 -429.015287) (xy 152.248966 -428.995687)
			(xy 152.241474 -428.972647) (xy 152.240996 -428.960534) (xy 151.307736 -428.960534) (xy 151.312724 -428.964169)
			(xy 151.326918 -428.983791) (xy 151.33434 -429.006844) (xy 151.334724 -429.018954) (xy 151.334724 -431.560478)
			(xy 151.334273 -431.57257) (xy 151.326818 -431.595576) (xy 151.312629 -431.615159) (xy 151.293089 -431.629409)
			(xy 151.270106 -431.636935) (xy 151.258016 -431.63744) (xy 150.318216 -431.63744) (xy 150.306112 -431.63697)
			(xy 150.283092 -431.62948) (xy 150.263522 -431.615231) (xy 150.249326 -431.595623) (xy 150.241897 -431.572583)
			(xy 150.241508 -431.560478) (xy 149.334728 -431.560478) (xy 149.334728 -432.560476) (xy 149.334267 -432.572555)
			(xy 149.326809 -432.595534) (xy 149.312614 -432.615083) (xy 149.293073 -432.629288) (xy 149.270099 -432.63676)
			(xy 149.25802 -432.637184) (xy 148.31822 -432.637184) (xy 148.306136 -432.63677) (xy 148.28315 -432.629305)
			(xy 148.263597 -432.6151) (xy 148.249393 -432.595547) (xy 148.24193 -432.57256) (xy 148.241512 -432.560476)
			(xy 147.307058 -432.560476) (xy 147.31251 -432.564433) (xy 147.326754 -432.584016) (xy 147.334251 -432.607042)
			(xy 147.334732 -432.61915) (xy 147.334732 -435.160674) (xy 147.334317 -435.172798) (xy 147.326829 -435.195861)
			(xy 147.312577 -435.21548) (xy 147.292958 -435.229731) (xy 147.269894 -435.237218) (xy 147.25777 -435.237636)
			(xy 146.31797 -435.237636) (xy 146.305851 -435.237214) (xy 146.282803 -435.229715) (xy 146.263199 -435.215461)
			(xy 146.24896 -435.195847) (xy 146.241478 -435.172793) (xy 146.241008 -435.160674) (xy 145.334736 -435.160674)
			(xy 145.334736 -436.160672) (xy 145.334217 -436.172717) (xy 145.326796 -436.195636) (xy 145.312669 -436.215149)
			(xy 145.293214 -436.229354) (xy 145.270325 -436.236868) (xy 145.258282 -436.23738) (xy 144.317974 -436.23738)
			(xy 144.305885 -436.236915) (xy 144.282887 -436.229454) (xy 144.263309 -436.215266) (xy 144.249059 -436.195734)
			(xy 144.241524 -436.172759) (xy 144.241012 -436.160672) (xy 143.307215 -436.160672) (xy 143.312462 -436.164474)
			(xy 143.326712 -436.184016) (xy 143.334237 -436.207001) (xy 143.33474 -436.219092) (xy 143.33474 -438.760616)
			(xy 143.334254 -438.772663) (xy 143.326822 -438.795582) (xy 143.312686 -438.815094) (xy 143.293224 -438.829298)
			(xy 143.270331 -438.836811) (xy 143.258286 -438.837324) (xy 142.317978 -438.837324) (xy 142.305884 -438.836911)
			(xy 142.282876 -438.829444) (xy 142.263294 -438.815245) (xy 142.249045 -438.795698) (xy 142.24152 -438.772709)
			(xy 142.241016 -438.760616) (xy 140.334492 -438.760616) (xy 140.334492 -439.760614) (xy 144.241012 -439.760614)
			(xy 144.241012 -437.21909) (xy 144.241503 -437.206978) (xy 144.24899 -437.183938) (xy 144.263228 -437.164339)
			(xy 144.282824 -437.150097) (xy 144.305862 -437.142606) (xy 144.317974 -437.142128) (xy 145.257774 -437.142128)
			(xy 145.269894 -437.142582) (xy 145.292951 -437.150066) (xy 145.312565 -437.164309) (xy 145.326818 -437.183917)
			(xy 145.334312 -437.20697) (xy 145.334736 -437.21909) (xy 145.334736 -438.760616) (xy 146.241008 -438.760616)
			(xy 146.241008 -436.219092) (xy 146.241453 -436.207041) (xy 146.248889 -436.184113) (xy 146.263034 -436.164597)
			(xy 146.282507 -436.150394) (xy 146.305412 -436.14289) (xy 146.317462 -436.142384) (xy 147.25777 -436.142384)
			(xy 147.269862 -436.142834) (xy 147.292869 -436.150288) (xy 147.307202 -436.160672) (xy 148.241004 -436.160672)
			(xy 148.241004 -433.619148) (xy 148.241501 -433.6071) (xy 148.248921 -433.584175) (xy 148.263052 -433.564658)
			(xy 148.282515 -433.550453) (xy 148.305412 -433.542947) (xy 148.317458 -433.54244) (xy 149.257766 -433.54244)
			(xy 149.269854 -433.542936) (xy 149.292853 -433.550384) (xy 149.312434 -433.564563) (xy 149.326686 -433.58409)
			(xy 149.334218 -433.607062) (xy 149.334728 -433.619148) (xy 149.334728 -435.160674) (xy 150.241 -435.160674)
			(xy 150.241 -432.61915) (xy 150.241469 -432.607037) (xy 150.248965 -432.583998) (xy 150.263209 -432.564401)
			(xy 150.282809 -432.550159) (xy 150.305849 -432.542667) (xy 150.317962 -432.542188) (xy 151.257762 -432.542188)
			(xy 151.26987 -432.542743) (xy 151.292903 -432.550214) (xy 151.307044 -432.560476) (xy 152.241504 -432.560476)
			(xy 152.241504 -431.833274) (xy 152.241755 -431.824517) (xy 152.245734 -431.807459) (xy 152.249378 -431.799492)
			(xy 152.482804 -431.323242) (xy 152.487534 -431.312736) (xy 152.491014 -431.289971) (xy 152.487516 -431.267208)
			(xy 152.482804 -431.256694) (xy 152.249378 -430.780444) (xy 152.245728 -430.772478) (xy 152.241745 -430.75542)
			(xy 152.241504 -430.746662) (xy 152.241504 -430.018952) (xy 152.241923 -430.006874) (xy 152.249401 -429.983903)
			(xy 152.263608 -429.964366) (xy 152.283157 -429.950173) (xy 152.306133 -429.942714) (xy 152.318212 -429.942244)
			(xy 153.258012 -429.942244) (xy 153.270082 -429.942753) (xy 153.293042 -429.950213) (xy 153.312574 -429.9644)
			(xy 153.32677 -429.983926) (xy 153.334241 -430.006882) (xy 153.33472 -430.018952) (xy 153.33472 -431.560478)
			(xy 154.2415 -431.560478) (xy 154.2415 -430.833276) (xy 154.241752 -430.824519) (xy 154.245731 -430.807461)
			(xy 154.249374 -430.799494) (xy 154.4828 -430.323244) (xy 154.487528 -430.312738) (xy 154.491009 -430.289973)
			(xy 154.487512 -430.26721) (xy 154.4828 -430.256696) (xy 154.249374 -429.780446) (xy 154.245724 -429.77248)
			(xy 154.241741 -429.755422) (xy 154.2415 -429.746664) (xy 154.2415 -429.018954) (xy 154.241967 -429.006866)
			(xy 154.249432 -428.983871) (xy 154.26362 -428.964295) (xy 154.28315 -428.950044) (xy 154.306122 -428.942507)
			(xy 154.318208 -428.941992) (xy 155.258008 -428.941992) (xy 155.270117 -428.942409) (xy 155.293143 -428.94991)
			(xy 155.307723 -428.960534) (xy 156.240988 -428.960534) (xy 156.240988 -426.41901) (xy 156.24152 -426.406901)
			(xy 156.248998 -426.383867) (xy 156.263226 -426.364269) (xy 156.282813 -426.350025) (xy 156.305841 -426.342529)
			(xy 156.31795 -426.342048) (xy 157.25775 -426.342048) (xy 157.269868 -426.342469) (xy 157.292915 -426.349972)
			(xy 157.312516 -426.364226) (xy 157.326756 -426.383839) (xy 157.33424 -426.406891) (xy 157.334712 -426.41901)
			(xy 157.334712 -428.960534) (xy 157.334218 -428.972645) (xy 157.326728 -428.995681) (xy 157.31249 -429.015278)
			(xy 157.292896 -429.02952) (xy 157.269861 -429.037016) (xy 157.25775 -429.037496) (xy 156.31795 -429.037496)
			(xy 156.305836 -429.037031) (xy 156.282797 -429.029535) (xy 156.263199 -429.015289) (xy 156.248958 -428.995689)
			(xy 156.241466 -428.972648) (xy 156.240988 -428.960534) (xy 155.307723 -428.960534) (xy 155.312715 -428.964172)
			(xy 155.32691 -428.983792) (xy 155.334332 -429.006844) (xy 155.334716 -429.018954) (xy 155.334716 -431.560478)
			(xy 155.334273 -431.572571) (xy 155.326817 -431.595578) (xy 155.312626 -431.615162) (xy 155.293084 -431.629412)
			(xy 155.270099 -431.636937) (xy 155.258008 -431.63744) (xy 154.318208 -431.63744) (xy 154.306104 -431.636978)
			(xy 154.283083 -431.629485) (xy 154.263513 -431.615234) (xy 154.249317 -431.595625) (xy 154.241889 -431.572584)
			(xy 154.2415 -431.560478) (xy 153.33472 -431.560478) (xy 153.33472 -432.560476) (xy 153.334267 -432.572556)
			(xy 153.326807 -432.595536) (xy 153.312611 -432.615086) (xy 153.293068 -432.629291) (xy 153.270092 -432.636761)
			(xy 153.258012 -432.637184) (xy 152.318212 -432.637184) (xy 152.306128 -432.636777) (xy 152.283141 -432.629309)
			(xy 152.263589 -432.615103) (xy 152.249385 -432.595548) (xy 152.241922 -432.572561) (xy 152.241504 -432.560476)
			(xy 151.307044 -432.560476) (xy 151.312501 -432.564436) (xy 151.326746 -432.584018) (xy 151.334243 -432.607043)
			(xy 151.334724 -432.61915) (xy 151.334724 -435.160674) (xy 151.334317 -435.172799) (xy 151.326828 -435.195864)
			(xy 151.312574 -435.215482) (xy 151.292953 -435.229733) (xy 151.269887 -435.237219) (xy 151.257762 -435.237636)
			(xy 150.317962 -435.237636) (xy 150.305843 -435.23722) (xy 150.282794 -435.229719) (xy 150.263191 -435.215464)
			(xy 150.248951 -435.195849) (xy 150.24147 -435.172794) (xy 150.241 -435.160674) (xy 149.334728 -435.160674)
			(xy 149.334728 -436.160672) (xy 149.334217 -436.172718) (xy 149.326795 -436.195638) (xy 149.312667 -436.215152)
			(xy 149.293209 -436.229357) (xy 149.270318 -436.236869) (xy 149.258274 -436.23738) (xy 148.317966 -436.23738)
			(xy 148.305877 -436.236922) (xy 148.282878 -436.229458) (xy 148.263301 -436.215269) (xy 148.24905 -436.195735)
			(xy 148.241516 -436.17276) (xy 148.241004 -436.160672) (xy 147.307202 -436.160672) (xy 147.312454 -436.164477)
			(xy 147.326704 -436.184017) (xy 147.334229 -436.207001) (xy 147.334732 -436.219092) (xy 147.334732 -438.760616)
			(xy 147.334254 -438.772664) (xy 147.326821 -438.795584) (xy 147.312684 -438.815097) (xy 147.293219 -438.829301)
			(xy 147.270324 -438.836812) (xy 147.258278 -438.837324) (xy 146.31797 -438.837324) (xy 146.305875 -438.836918)
			(xy 146.282868 -438.829448) (xy 146.263285 -438.815247) (xy 146.249037 -438.795699) (xy 146.241512 -438.77271)
			(xy 146.241008 -438.760616) (xy 145.334736 -438.760616) (xy 145.334736 -439.760614) (xy 148.241004 -439.760614)
			(xy 148.241004 -437.21909) (xy 148.241503 -437.206978) (xy 148.248989 -437.183941) (xy 148.263225 -437.164342)
			(xy 148.282819 -437.1501) (xy 148.305854 -437.142607) (xy 148.317966 -437.142128) (xy 149.257766 -437.142128)
			(xy 149.269886 -437.142589) (xy 149.292942 -437.15007) (xy 149.312557 -437.164312) (xy 149.32681 -437.183918)
			(xy 149.334304 -437.20697) (xy 149.334728 -437.21909) (xy 149.334728 -438.760616) (xy 150.241 -438.760616)
			(xy 150.241 -436.219092) (xy 150.241453 -436.207041) (xy 150.248888 -436.184116) (xy 150.263031 -436.1646)
			(xy 150.282502 -436.150397) (xy 150.305405 -436.142891) (xy 150.317454 -436.142384) (xy 151.257762 -436.142384)
			(xy 151.269854 -436.142841) (xy 151.292861 -436.150292) (xy 151.307189 -436.160672) (xy 152.240996 -436.160672)
			(xy 152.240996 -433.619148) (xy 152.241501 -433.607101) (xy 152.24892 -433.584177) (xy 152.263049 -433.564661)
			(xy 152.28251 -433.550456) (xy 152.305405 -433.542948) (xy 152.31745 -433.54244) (xy 153.257758 -433.54244)
			(xy 153.269845 -433.542943) (xy 153.292845 -433.550388) (xy 153.312425 -433.564566) (xy 153.326677 -433.584092)
			(xy 153.33421 -433.607062) (xy 153.33472 -433.619148) (xy 153.33472 -435.160674) (xy 154.240992 -435.160674)
			(xy 154.240992 -432.61915) (xy 154.241468 -432.607037) (xy 154.248964 -432.584) (xy 154.263206 -432.564403)
			(xy 154.282804 -432.550162) (xy 154.305841 -432.542668) (xy 154.317954 -432.542188) (xy 155.257754 -432.542188)
			(xy 155.269861 -432.54275) (xy 155.292895 -432.550219) (xy 155.307031 -432.560476) (xy 156.241496 -432.560476)
			(xy 156.241496 -431.833274) (xy 156.241747 -431.824517) (xy 156.245727 -431.807459) (xy 156.24937 -431.799492)
			(xy 156.482796 -431.323242) (xy 156.487526 -431.312737) (xy 156.491006 -431.289971) (xy 156.487509 -431.267208)
			(xy 156.482796 -431.256694) (xy 156.24937 -430.780444) (xy 156.24572 -430.772478) (xy 156.241737 -430.75542)
			(xy 156.241496 -430.746662) (xy 156.241496 -430.018952) (xy 156.241923 -430.006875) (xy 156.249399 -429.983905)
			(xy 156.263605 -429.964368) (xy 156.283152 -429.950176) (xy 156.306126 -429.942715) (xy 156.318204 -429.942244)
			(xy 157.258004 -429.942244) (xy 157.270074 -429.94276) (xy 157.293033 -429.950218) (xy 157.312566 -429.964403)
			(xy 157.326762 -429.983927) (xy 157.334233 -430.006882) (xy 157.334712 -430.018952) (xy 157.334712 -432.560476)
			(xy 157.334267 -432.572557) (xy 157.326806 -432.595538) (xy 157.312609 -432.615089) (xy 157.293063 -432.629294)
			(xy 157.270085 -432.636762) (xy 157.258004 -432.637184) (xy 156.318204 -432.637184) (xy 156.306119 -432.636784)
			(xy 156.283132 -432.629314) (xy 156.26358 -432.615106) (xy 156.249376 -432.59555) (xy 156.241913 -432.572561)
			(xy 156.241496 -432.560476) (xy 155.307031 -432.560476) (xy 155.312493 -432.564439) (xy 155.326738 -432.584019)
			(xy 155.334235 -432.607043) (xy 155.334716 -432.61915) (xy 155.334716 -433.130695) (xy 197.035917 -433.130695)
			(xy 197.035917 -432.953425) (xy 197.04387 -432.776334) (xy 197.059761 -432.599778) (xy 197.083556 -432.424113)
			(xy 197.115209 -432.249692) (xy 197.154655 -432.076867) (xy 197.201815 -431.905986) (xy 197.256594 -431.737392)
			(xy 197.318882 -431.571427) (xy 197.388554 -431.408422) (xy 197.465468 -431.248708) (xy 197.549471 -431.092605)
			(xy 197.640392 -430.940428) (xy 197.738049 -430.792484) (xy 197.842246 -430.64907) (xy 197.952772 -430.510475)
			(xy 198.069404 -430.376978) (xy 198.191909 -430.248849) (xy 198.320038 -430.126344) (xy 198.453535 -430.009712)
			(xy 198.59213 -429.899186) (xy 198.735544 -429.794989) (xy 198.883488 -429.697332) (xy 199.035665 -429.606411)
			(xy 199.191768 -429.522408) (xy 199.351482 -429.445494) (xy 199.514487 -429.375822) (xy 199.680452 -429.313534)
			(xy 199.849046 -429.258755) (xy 200.019927 -429.211595) (xy 200.192752 -429.172149) (xy 200.367173 -429.140496)
			(xy 200.542838 -429.116701) (xy 200.719394 -429.10081) (xy 200.896485 -429.092857) (xy 201.073755 -429.092857)
			(xy 201.250846 -429.10081) (xy 201.427402 -429.116701) (xy 201.603067 -429.140496) (xy 201.777488 -429.172149)
			(xy 201.950313 -429.211595) (xy 202.121194 -429.258755) (xy 202.289788 -429.313534) (xy 202.455753 -429.375822)
			(xy 202.618758 -429.445494) (xy 202.778472 -429.522408) (xy 202.934575 -429.606411) (xy 203.086752 -429.697332)
			(xy 203.234696 -429.794989) (xy 203.37811 -429.899186) (xy 203.516705 -430.009712) (xy 203.650202 -430.126344)
			(xy 203.778331 -430.248849) (xy 203.900836 -430.376978) (xy 204.017468 -430.510475) (xy 204.127994 -430.64907)
			(xy 204.232191 -430.792484) (xy 204.329848 -430.940428) (xy 204.420769 -431.092605) (xy 204.504772 -431.248708)
			(xy 204.581686 -431.408422) (xy 204.651358 -431.571427) (xy 204.713646 -431.737392) (xy 204.768425 -431.905986)
			(xy 204.815585 -432.076867) (xy 204.855031 -432.249692) (xy 204.886684 -432.424113) (xy 204.910479 -432.599778)
			(xy 204.92637 -432.776334) (xy 204.934323 -432.953425) (xy 204.93482 -433.04206) (xy 204.934323 -433.130695)
			(xy 204.92637 -433.307786) (xy 204.910479 -433.484342) (xy 204.886684 -433.660007) (xy 204.855031 -433.834428)
			(xy 204.815585 -434.007253) (xy 204.768425 -434.178134) (xy 204.713646 -434.346728) (xy 204.651358 -434.512693)
			(xy 204.581686 -434.675698) (xy 204.504772 -434.835412) (xy 204.420769 -434.991515) (xy 204.329848 -435.143692)
			(xy 204.232191 -435.291636) (xy 204.127994 -435.43505) (xy 204.017468 -435.573645) (xy 203.900836 -435.707142)
			(xy 203.778331 -435.835271) (xy 203.650202 -435.957776) (xy 203.516705 -436.074408) (xy 203.37811 -436.184934)
			(xy 203.234696 -436.289131) (xy 203.086752 -436.386788) (xy 202.934575 -436.477709) (xy 202.778472 -436.561712)
			(xy 202.618758 -436.638626) (xy 202.455753 -436.708298) (xy 202.289788 -436.770586) (xy 202.121194 -436.825365)
			(xy 201.950313 -436.872525) (xy 201.777488 -436.911971) (xy 201.603067 -436.943624) (xy 201.427402 -436.967419)
			(xy 201.250846 -436.98331) (xy 201.073755 -436.991263) (xy 200.896485 -436.991263) (xy 200.719394 -436.98331)
			(xy 200.542838 -436.967419) (xy 200.367173 -436.943624) (xy 200.192752 -436.911971) (xy 200.019927 -436.872525)
			(xy 199.849046 -436.825365) (xy 199.680452 -436.770586) (xy 199.514487 -436.708298) (xy 199.351482 -436.638626)
			(xy 199.191768 -436.561712) (xy 199.035665 -436.477709) (xy 198.883488 -436.386788) (xy 198.735544 -436.289131)
			(xy 198.59213 -436.184934) (xy 198.453535 -436.074408) (xy 198.320038 -435.957776) (xy 198.191909 -435.835271)
			(xy 198.069404 -435.707142) (xy 197.952772 -435.573645) (xy 197.842246 -435.43505) (xy 197.738049 -435.291636)
			(xy 197.640392 -435.143692) (xy 197.549471 -434.991515) (xy 197.465468 -434.835412) (xy 197.388554 -434.675698)
			(xy 197.318882 -434.512693) (xy 197.256594 -434.346728) (xy 197.201815 -434.178134) (xy 197.154655 -434.007253)
			(xy 197.115209 -433.834428) (xy 197.083556 -433.660007) (xy 197.059761 -433.484342) (xy 197.04387 -433.307786)
			(xy 197.035917 -433.130695) (xy 155.334716 -433.130695) (xy 155.334716 -435.160674) (xy 155.334317 -435.1728)
			(xy 155.326827 -435.195866) (xy 155.312571 -435.215485) (xy 155.292948 -435.229736) (xy 155.26988 -435.23722)
			(xy 155.257754 -435.237636) (xy 154.317954 -435.237636) (xy 154.305834 -435.237227) (xy 154.282785 -435.229724)
			(xy 154.263182 -435.215467) (xy 154.248943 -435.19585) (xy 154.241462 -435.172794) (xy 154.240992 -435.160674)
			(xy 153.33472 -435.160674) (xy 153.33472 -436.160672) (xy 153.334217 -436.172719) (xy 153.326794 -436.19564)
			(xy 153.312664 -436.215155) (xy 153.293204 -436.22936) (xy 153.270311 -436.23687) (xy 153.258266 -436.23738)
			(xy 152.317958 -436.23738) (xy 152.305868 -436.236929) (xy 152.28287 -436.229463) (xy 152.263292 -436.215272)
			(xy 152.249042 -436.195737) (xy 152.241508 -436.17276) (xy 152.240996 -436.160672) (xy 151.307189 -436.160672)
			(xy 151.312445 -436.16448) (xy 151.326695 -436.184019) (xy 151.334221 -436.207002) (xy 151.334724 -436.219092)
			(xy 151.334724 -438.760616) (xy 151.334254 -438.772665) (xy 151.32682 -438.795587) (xy 151.312681 -438.8151)
			(xy 151.293214 -438.829304) (xy 151.270317 -438.836814) (xy 151.25827 -438.837324) (xy 150.317962 -438.837324)
			(xy 150.305867 -438.836924) (xy 150.282859 -438.829453) (xy 150.263277 -438.81525) (xy 150.249029 -438.795701)
			(xy 150.241504 -438.77271) (xy 150.241 -438.760616) (xy 149.334728 -438.760616) (xy 149.334728 -439.760614)
			(xy 152.240996 -439.760614) (xy 152.240996 -437.21909) (xy 152.241503 -437.206979) (xy 152.248988 -437.183943)
			(xy 152.263222 -437.164345) (xy 152.282814 -437.150102) (xy 152.305847 -437.142608) (xy 152.317958 -437.142128)
			(xy 153.257758 -437.142128) (xy 153.269878 -437.142595) (xy 153.292933 -437.150075) (xy 153.312548 -437.164315)
			(xy 153.326801 -437.18392) (xy 153.334296 -437.206971) (xy 153.33472 -437.21909) (xy 153.33472 -438.760616)
			(xy 154.240992 -438.760616) (xy 154.240992 -436.219092) (xy 154.241453 -436.207042) (xy 154.248887 -436.184118)
			(xy 154.263028 -436.164603) (xy 154.282497 -436.1504) (xy 154.305398 -436.142892) (xy 154.317446 -436.142384)
			(xy 155.257754 -436.142384) (xy 155.269846 -436.142847) (xy 155.292852 -436.150297) (xy 155.307176 -436.160672)
			(xy 156.240988 -436.160672) (xy 156.240988 -433.619148) (xy 156.2415 -433.607101) (xy 156.248919 -433.584179)
			(xy 156.263046 -433.564664) (xy 156.282505 -433.550458) (xy 156.305397 -433.542949) (xy 156.317442 -433.54244)
			(xy 157.25775 -433.54244) (xy 157.269837 -433.54295) (xy 157.292836 -433.550393) (xy 157.312417 -433.564568)
			(xy 157.326669 -433.584093) (xy 157.334202 -433.607063) (xy 157.334712 -433.619148) (xy 157.334712 -436.160672)
			(xy 157.334216 -436.17272) (xy 157.326793 -436.195642) (xy 157.312661 -436.215157) (xy 157.293199 -436.229362)
			(xy 157.270304 -436.236871) (xy 157.258258 -436.23738) (xy 156.31795 -436.23738) (xy 156.305865 -436.23685)
			(xy 156.282869 -436.22941) (xy 156.26329 -436.215239) (xy 156.249037 -436.195719) (xy 156.241501 -436.172755)
			(xy 156.240988 -436.160672) (xy 155.307176 -436.160672) (xy 155.312437 -436.164483) (xy 155.326687 -436.18402)
			(xy 155.334212 -436.207002) (xy 155.334716 -436.219092) (xy 155.334716 -438.760616) (xy 155.334254 -438.772665)
			(xy 155.326819 -438.795589) (xy 155.312678 -438.815103) (xy 155.293209 -438.829306) (xy 155.27031 -438.836815)
			(xy 155.258262 -438.837324) (xy 154.317954 -438.837324) (xy 154.305858 -438.836931) (xy 154.28285 -438.829457)
			(xy 154.263268 -438.815253) (xy 154.24902 -438.795702) (xy 154.241496 -438.77271) (xy 154.240992 -438.760616)
			(xy 153.33472 -438.760616) (xy 153.33472 -439.760614) (xy 156.240988 -439.760614) (xy 156.240988 -437.21909)
			(xy 156.241503 -437.20698) (xy 156.248987 -437.183945) (xy 156.263219 -437.164348) (xy 156.282809 -437.150105)
			(xy 156.30584 -437.142609) (xy 156.31795 -437.142128) (xy 157.25775 -437.142128) (xy 157.269866 -437.142569)
			(xy 157.292909 -437.150069) (xy 157.312509 -437.164319) (xy 157.32675 -437.183927) (xy 157.334237 -437.206974)
			(xy 157.334712 -437.21909) (xy 157.334712 -438.760616) (xy 314.141104 -438.760616) (xy 314.141104 -436.219092)
			(xy 314.141553 -436.207041) (xy 314.148989 -436.184115) (xy 314.163132 -436.164599) (xy 314.182605 -436.150396)
			(xy 314.205509 -436.14289) (xy 314.217558 -436.142384) (xy 315.157866 -436.142384) (xy 315.169958 -436.142837)
			(xy 315.192965 -436.15029) (xy 315.207295 -436.160672) (xy 316.140592 -436.160672) (xy 316.140592 -433.619148)
			(xy 316.141101 -433.607101) (xy 316.148519 -433.584178) (xy 316.162648 -433.564662) (xy 316.182108 -433.550457)
			(xy 316.205001 -433.542948) (xy 316.217046 -433.54244) (xy 317.157354 -433.54244) (xy 317.169441 -433.542947)
			(xy 317.19244 -433.550391) (xy 317.212021 -433.564567) (xy 317.226273 -433.584093) (xy 317.233806 -433.607063)
			(xy 317.234316 -433.619148) (xy 317.234316 -435.160674) (xy 318.140588 -435.160674) (xy 318.140588 -432.61915)
			(xy 318.141068 -432.607038) (xy 318.148563 -432.584001) (xy 318.162805 -432.564405) (xy 318.182401 -432.550163)
			(xy 318.205438 -432.542668) (xy 318.21755 -432.542188) (xy 319.15735 -432.542188) (xy 319.169462 -432.542668)
			(xy 319.192499 -432.550163) (xy 319.206689 -432.560476) (xy 320.141092 -432.560476) (xy 320.141092 -431.833274)
			(xy 320.141344 -431.824517) (xy 320.145323 -431.807459) (xy 320.148966 -431.799492) (xy 320.382392 -431.323242)
			(xy 320.387122 -431.312737) (xy 320.390603 -431.289971) (xy 320.387105 -431.267208) (xy 320.382392 -431.256694)
			(xy 320.148966 -430.780444) (xy 320.145315 -430.772478) (xy 320.141333 -430.755421) (xy 320.141092 -430.746662)
			(xy 320.141092 -430.018952) (xy 320.141523 -430.006875) (xy 320.148999 -429.983906) (xy 320.163204 -429.96437)
			(xy 320.182749 -429.950177) (xy 320.205723 -429.942716) (xy 320.2178 -429.942244) (xy 321.1576 -429.942244)
			(xy 321.16967 -429.942764) (xy 321.192629 -429.95022) (xy 321.212162 -429.964404) (xy 321.226358 -429.983928)
			(xy 321.233829 -430.006883) (xy 321.234308 -430.018952) (xy 321.234308 -431.560478) (xy 322.141088 -431.560478)
			(xy 322.141088 -430.833276) (xy 322.141341 -430.824519) (xy 322.145319 -430.807462) (xy 322.148962 -430.799494)
			(xy 322.382388 -430.323244) (xy 322.387117 -430.312738) (xy 322.390598 -430.289973) (xy 322.3871 -430.26721)
			(xy 322.382388 -430.256696) (xy 322.148962 -429.780446) (xy 322.145312 -429.77248) (xy 322.141329 -429.755422)
			(xy 322.141088 -429.746664) (xy 322.141088 -429.018954) (xy 322.141469 -429.006857) (xy 322.148944 -428.983847)
			(xy 322.163151 -428.964264) (xy 322.182705 -428.950016) (xy 322.2057 -428.942494) (xy 322.217796 -428.941992)
			(xy 323.157596 -428.941992) (xy 323.169704 -428.942419) (xy 323.19273 -428.949917) (xy 323.207303 -428.960534)
			(xy 324.141084 -428.960534) (xy 324.141084 -426.41901) (xy 324.141469 -426.406883) (xy 324.148964 -426.383817)
			(xy 324.163223 -426.364198) (xy 324.182849 -426.349948) (xy 324.205919 -426.342464) (xy 324.218046 -426.342048)
			(xy 325.157846 -426.342048) (xy 325.169964 -426.342473) (xy 325.19301 -426.349974) (xy 325.212612 -426.364228)
			(xy 325.226852 -426.38384) (xy 325.234336 -426.406892) (xy 325.234808 -426.41901) (xy 325.234808 -427.960536)
			(xy 326.14108 -427.960536) (xy 326.14108 -425.419012) (xy 326.14157 -425.406964) (xy 326.148997 -425.384043)
			(xy 326.163131 -425.364528) (xy 326.182593 -425.350324) (xy 326.205488 -425.342814) (xy 326.217534 -425.342304)
			(xy 327.157842 -425.342304) (xy 327.16993 -425.342771) (xy 327.192926 -425.350235) (xy 327.212502 -425.364423)
			(xy 327.226753 -425.383953) (xy 327.23429 -425.406925) (xy 327.234804 -425.419012) (xy 327.234804 -427.960536)
			(xy 327.234371 -427.972588) (xy 327.226929 -427.995514) (xy 327.212781 -428.015029) (xy 327.193306 -428.029231)
			(xy 327.1704 -428.036737) (xy 327.15835 -428.037244) (xy 326.218042 -428.037244) (xy 326.205953 -428.036757)
			(xy 326.182951 -428.029309) (xy 326.163369 -428.015129) (xy 326.149118 -427.995598) (xy 326.141587 -427.972623)
			(xy 326.14108 -427.960536) (xy 325.234808 -427.960536) (xy 325.234808 -428.960534) (xy 325.234318 -428.972646)
			(xy 325.226827 -428.995682) (xy 325.212588 -429.01528) (xy 325.192993 -429.029522) (xy 325.169958 -429.037016)
			(xy 325.157846 -429.037496) (xy 324.218046 -429.037496) (xy 324.205929 -429.037002) (xy 324.182877 -429.029526)
			(xy 324.163264 -429.015292) (xy 324.149011 -428.995694) (xy 324.141511 -428.972651) (xy 324.141084 -428.960534)
			(xy 323.207303 -428.960534) (xy 323.212302 -428.964176) (xy 323.226497 -428.983795) (xy 323.23392 -429.006845)
			(xy 323.234304 -429.018954) (xy 323.234304 -431.560478) (xy 323.233775 -431.572562) (xy 323.226329 -431.595555)
			(xy 323.212157 -431.615131) (xy 323.19264 -431.629384) (xy 323.169678 -431.636924) (xy 323.157596 -431.63744)
			(xy 322.217796 -431.63744) (xy 322.205691 -431.636988) (xy 322.18267 -431.629492) (xy 322.163101 -431.615238)
			(xy 322.148905 -431.595627) (xy 322.141477 -431.572584) (xy 322.141088 -431.560478) (xy 321.234308 -431.560478)
			(xy 321.234308 -432.560476) (xy 321.233867 -432.572557) (xy 321.226406 -432.595539) (xy 321.212207 -432.61509)
			(xy 321.192661 -432.629295) (xy 321.169681 -432.636763) (xy 321.1576 -432.637184) (xy 320.2178 -432.637184)
			(xy 320.205715 -432.636787) (xy 320.182728 -432.629317) (xy 320.163176 -432.615107) (xy 320.148972 -432.59555)
			(xy 320.141509 -432.572561) (xy 320.141092 -432.560476) (xy 319.206689 -432.560476) (xy 319.212095 -432.564405)
			(xy 319.226337 -432.584001) (xy 319.233832 -432.607038) (xy 319.234312 -432.61915) (xy 319.234312 -435.160674)
			(xy 319.233767 -435.172782) (xy 319.226293 -435.195816) (xy 319.212068 -435.215414) (xy 319.192484 -435.229658)
			(xy 319.169458 -435.237155) (xy 319.15735 -435.237636) (xy 318.21755 -435.237636) (xy 318.20543 -435.23723)
			(xy 318.182381 -435.229726) (xy 318.162778 -435.215468) (xy 318.148539 -435.195851) (xy 318.141058 -435.172794)
			(xy 318.140588 -435.160674) (xy 317.234316 -435.160674) (xy 317.234316 -436.160672) (xy 317.233817 -436.172719)
			(xy 317.226393 -436.195641) (xy 317.212262 -436.215156) (xy 317.192801 -436.229361) (xy 317.169907 -436.236871)
			(xy 317.157862 -436.23738) (xy 316.217554 -436.23738) (xy 316.205464 -436.236932) (xy 316.182465 -436.229465)
			(xy 316.162888 -436.215273) (xy 316.148638 -436.195737) (xy 316.141104 -436.172761) (xy 316.140592 -436.160672)
			(xy 315.207295 -436.160672) (xy 315.212549 -436.164478) (xy 315.2268 -436.184018) (xy 315.234325 -436.207001)
			(xy 315.234828 -436.219092) (xy 315.234828 -438.760616) (xy 315.234354 -438.772664) (xy 315.22692 -438.795586)
			(xy 315.212782 -438.815099) (xy 315.193317 -438.829302) (xy 315.170421 -438.836813) (xy 315.158374 -438.837324)
			(xy 314.218066 -438.837324) (xy 314.205971 -438.836921) (xy 314.182963 -438.829451) (xy 314.163381 -438.815249)
			(xy 314.149133 -438.7957) (xy 314.141608 -438.77271) (xy 314.141104 -438.760616) (xy 157.334712 -438.760616)
			(xy 157.334712 -439.760614) (xy 316.1411 -439.760614) (xy 316.1411 -437.21909) (xy 316.141603 -437.206979)
			(xy 316.149088 -437.183942) (xy 316.163324 -437.164343) (xy 316.182917 -437.150101) (xy 316.205951 -437.142607)
			(xy 316.218062 -437.142128) (xy 317.157862 -437.142128) (xy 317.169982 -437.142592) (xy 317.193038 -437.150073)
			(xy 317.212653 -437.164313) (xy 317.226905 -437.183919) (xy 317.2344 -437.20697) (xy 317.234824 -437.21909)
			(xy 317.234824 -438.760616) (xy 318.141096 -438.760616) (xy 318.141096 -436.219092) (xy 318.141553 -436.207042)
			(xy 318.148988 -436.184117) (xy 318.163129 -436.164601) (xy 318.1826 -436.150398) (xy 318.205501 -436.142892)
			(xy 318.21755 -436.142384) (xy 319.157858 -436.142384) (xy 319.16995 -436.142844) (xy 319.192956 -436.150294)
			(xy 319.207283 -436.160672) (xy 320.140584 -436.160672) (xy 320.140584 -433.619148) (xy 320.1411 -433.607102)
			(xy 320.148518 -433.58418) (xy 320.162645 -433.564665) (xy 320.182103 -433.55046) (xy 320.204994 -433.54295)
			(xy 320.217038 -433.54244) (xy 321.157346 -433.54244) (xy 321.169438 -433.542868) (xy 321.19244 -433.550338)
			(xy 321.212019 -433.564534) (xy 321.226268 -433.584075) (xy 321.233799 -433.607057) (xy 321.234308 -433.619148)
			(xy 321.234308 -435.160674) (xy 322.14058 -435.160674) (xy 322.14058 -432.61915) (xy 322.14097 -432.607029)
			(xy 322.148476 -432.583977) (xy 322.162738 -432.564372) (xy 322.182359 -432.550134) (xy 322.20542 -432.542655)
			(xy 322.217542 -432.542188) (xy 323.157342 -432.542188) (xy 323.169454 -432.542675) (xy 323.19249 -432.550168)
			(xy 323.206676 -432.560476) (xy 324.141084 -432.560476) (xy 324.141084 -431.833274) (xy 324.141337 -431.824517)
			(xy 324.145315 -431.80746) (xy 324.148958 -431.799492) (xy 324.382384 -431.323242) (xy 324.387114 -431.312737)
			(xy 324.390595 -431.289971) (xy 324.387097 -431.267208) (xy 324.382384 -431.256694) (xy 324.148958 -430.780444)
			(xy 324.145307 -430.772479) (xy 324.141324 -430.755421) (xy 324.141084 -430.746662) (xy 324.141084 -430.018952)
			(xy 324.141523 -430.006876) (xy 324.148998 -429.983908) (xy 324.163201 -429.964373) (xy 324.182744 -429.95018)
			(xy 324.205715 -429.942717) (xy 324.217792 -429.942244) (xy 325.157592 -429.942244) (xy 325.169661 -429.94277)
			(xy 325.19262 -429.950225) (xy 325.212153 -429.964407) (xy 325.22635 -429.98393) (xy 325.233821 -430.006883)
			(xy 325.2343 -430.018952) (xy 325.2343 -431.560478) (xy 326.14108 -431.560478) (xy 326.14108 -430.833276)
			(xy 326.141334 -430.824519) (xy 326.145312 -430.807462) (xy 326.148954 -430.799494) (xy 326.38238 -430.323244)
			(xy 326.387109 -430.312738) (xy 326.390591 -430.289973) (xy 326.387093 -430.26721) (xy 326.38238 -430.256696)
			(xy 326.148954 -429.780446) (xy 326.145303 -429.77248) (xy 326.141321 -429.755423) (xy 326.14108 -429.746664)
			(xy 326.14108 -429.018954) (xy 326.141469 -429.006858) (xy 326.148943 -428.983849) (xy 326.163148 -428.964267)
			(xy 326.1827 -428.950019) (xy 326.205693 -428.942495) (xy 326.217788 -428.941992) (xy 327.157588 -428.941992)
			(xy 327.169695 -428.942427) (xy 327.192721 -428.949922) (xy 327.207289 -428.960534) (xy 328.141076 -428.960534)
			(xy 328.141076 -426.41901) (xy 328.141469 -426.406884) (xy 328.148963 -426.383819) (xy 328.16322 -426.364201)
			(xy 328.182844 -426.34995) (xy 328.205912 -426.342465) (xy 328.218038 -426.342048) (xy 329.157838 -426.342048)
			(xy 329.169956 -426.342479) (xy 329.193002 -426.349978) (xy 329.212604 -426.36423) (xy 329.226844 -426.383841)
			(xy 329.234328 -426.406892) (xy 329.2348 -426.41901) (xy 329.2348 -427.960536) (xy 331.141324 -427.960536)
			(xy 331.141324 -425.419012) (xy 331.141724 -425.406927) (xy 331.149192 -425.383939) (xy 331.1634 -425.364386)
			(xy 331.182957 -425.350183) (xy 331.205947 -425.34272) (xy 331.218032 -425.342304) (xy 332.157832 -425.342304)
			(xy 332.169909 -425.342737) (xy 332.19288 -425.35021) (xy 332.212417 -425.364414) (xy 332.22661 -425.38396)
			(xy 332.23407 -425.406934) (xy 332.23454 -425.419012) (xy 332.23454 -427.960536) (xy 332.234067 -427.972609)
			(xy 332.226599 -427.995572) (xy 332.212403 -428.015106) (xy 332.192869 -428.0293) (xy 332.169905 -428.036768)
			(xy 332.157832 -428.037244) (xy 331.218032 -428.037244) (xy 331.205963 -428.036709) (xy 331.183003 -428.02926)
			(xy 331.163468 -428.01508) (xy 331.149271 -427.995558) (xy 331.141801 -427.972605) (xy 331.141324 -427.960536)
			(xy 329.2348 -427.960536) (xy 329.2348 -428.960534) (xy 329.234318 -428.972647) (xy 329.226826 -428.995684)
			(xy 329.212585 -429.015282) (xy 329.192988 -429.029524) (xy 329.169951 -429.037017) (xy 329.157838 -429.037496)
			(xy 328.218038 -429.037496) (xy 328.205921 -429.037008) (xy 328.182869 -429.029531) (xy 328.163256 -429.015295)
			(xy 328.149002 -428.995696) (xy 328.141503 -428.972651) (xy 328.141076 -428.960534) (xy 327.207289 -428.960534)
			(xy 327.212293 -428.964179) (xy 327.226489 -428.983796) (xy 327.233911 -429.006845) (xy 327.234296 -429.018954)
			(xy 327.234296 -431.560478) (xy 327.233775 -431.572563) (xy 327.226328 -431.595557) (xy 327.212154 -431.615134)
			(xy 327.192634 -431.629386) (xy 327.169671 -431.636925) (xy 327.157588 -431.63744) (xy 326.217788 -431.63744)
			(xy 326.205682 -431.636995) (xy 326.182662 -431.629497) (xy 326.163092 -431.615241) (xy 326.148896 -431.595628)
			(xy 326.141469 -431.572585) (xy 326.14108 -431.560478) (xy 325.2343 -431.560478) (xy 325.2343 -432.560476)
			(xy 325.233867 -432.572558) (xy 325.226405 -432.595542) (xy 325.212204 -432.615093) (xy 325.192656 -432.629297)
			(xy 325.169674 -432.636764) (xy 325.157592 -432.637184) (xy 324.217792 -432.637184) (xy 324.205706 -432.636794)
			(xy 324.182719 -432.629321) (xy 324.163167 -432.61511) (xy 324.148964 -432.595552) (xy 324.141501 -432.572562)
			(xy 324.141084 -432.560476) (xy 323.206676 -432.560476) (xy 323.212087 -432.564408) (xy 323.226329 -432.584003)
			(xy 323.233824 -432.607038) (xy 323.234304 -432.61915) (xy 323.234304 -435.160674) (xy 323.233767 -435.172783)
			(xy 323.226292 -435.195818) (xy 323.212065 -435.215417) (xy 323.192479 -435.229661) (xy 323.169451 -435.237156)
			(xy 323.157342 -435.237636) (xy 322.217542 -435.237636) (xy 322.205419 -435.237204) (xy 322.182357 -435.22972)
			(xy 322.162739 -435.215473) (xy 322.148487 -435.195857) (xy 322.140999 -435.172797) (xy 322.14058 -435.160674)
			(xy 321.234308 -435.160674) (xy 321.234308 -436.160672) (xy 321.233816 -436.17272) (xy 321.226392 -436.195643)
			(xy 321.212259 -436.215159) (xy 321.192796 -436.229363) (xy 321.1699 -436.236872) (xy 321.157854 -436.23738)
			(xy 320.217546 -436.23738) (xy 320.205461 -436.236854) (xy 320.182465 -436.229412) (xy 320.162886 -436.21524)
			(xy 320.148633 -436.19572) (xy 320.141097 -436.172755) (xy 320.140584 -436.160672) (xy 319.207283 -436.160672)
			(xy 319.212541 -436.164481) (xy 319.226791 -436.184019) (xy 319.234316 -436.207002) (xy 319.23482 -436.219092)
			(xy 319.23482 -438.760616) (xy 319.234354 -438.772665) (xy 319.226919 -438.795588) (xy 319.212779 -438.815101)
			(xy 319.193312 -438.829305) (xy 319.170413 -438.836814) (xy 319.158366 -438.837324) (xy 318.218058 -438.837324)
			(xy 318.205963 -438.836928) (xy 318.182955 -438.829455) (xy 318.163372 -438.815252) (xy 318.149124 -438.795701)
			(xy 318.1416 -438.77271) (xy 318.141096 -438.760616) (xy 317.234824 -438.760616) (xy 317.234824 -439.760614)
			(xy 320.141092 -439.760614) (xy 320.141092 -437.21909) (xy 320.141603 -437.20698) (xy 320.149087 -437.183944)
			(xy 320.163321 -437.164346) (xy 320.182912 -437.150104) (xy 320.205944 -437.142608) (xy 320.218054 -437.142128)
			(xy 321.157854 -437.142128) (xy 321.169973 -437.142599) (xy 321.193029 -437.150077) (xy 321.212644 -437.164316)
			(xy 321.226897 -437.183921) (xy 321.234392 -437.206971) (xy 321.234816 -437.21909) (xy 321.234816 -438.760616)
			(xy 322.141088 -438.760616) (xy 322.141088 -436.219092) (xy 322.141553 -436.207043) (xy 322.148986 -436.184119)
			(xy 322.163126 -436.164604) (xy 322.182595 -436.150401) (xy 322.205494 -436.142893) (xy 322.217542 -436.142384)
			(xy 323.15785 -436.142384) (xy 323.169941 -436.142851) (xy 323.192948 -436.150299) (xy 323.207269 -436.160672)
			(xy 324.140576 -436.160672) (xy 324.140576 -433.619148) (xy 324.1411 -433.607103) (xy 324.148517 -433.584183)
			(xy 324.162642 -433.564668) (xy 324.182098 -433.550462) (xy 324.204987 -433.542951) (xy 324.21703 -433.54244)
			(xy 325.157338 -433.54244) (xy 325.16943 -433.542875) (xy 325.192431 -433.550342) (xy 325.212011 -433.564537)
			(xy 325.22626 -433.584077) (xy 325.233791 -433.607058) (xy 325.2343 -433.619148) (xy 325.2343 -435.160674)
			(xy 326.140572 -435.160674) (xy 326.140572 -432.61915) (xy 326.14097 -432.607029) (xy 326.148475 -432.583979)
			(xy 326.162735 -432.564375) (xy 326.182354 -432.550136) (xy 326.205413 -432.542656) (xy 326.217534 -432.542188)
			(xy 327.157334 -432.542188) (xy 327.169445 -432.542682) (xy 327.192481 -432.550172) (xy 327.206663 -432.560476)
			(xy 328.141076 -432.560476) (xy 328.141076 -431.833274) (xy 328.141329 -431.824517) (xy 328.145308 -431.80746)
			(xy 328.14895 -431.799492) (xy 328.382376 -431.323242) (xy 328.387107 -431.312737) (xy 328.390588 -431.289971)
			(xy 328.387089 -431.267208) (xy 328.382376 -431.256694) (xy 328.14895 -430.780444) (xy 328.145299 -430.772479)
			(xy 328.141316 -430.755421) (xy 328.141076 -430.746662) (xy 328.141076 -430.018952) (xy 328.141523 -430.006877)
			(xy 328.148997 -429.98391) (xy 328.163198 -429.964376) (xy 328.182739 -429.950182) (xy 328.205708 -429.942718)
			(xy 328.217784 -429.942244) (xy 329.157584 -429.942244) (xy 329.169653 -429.942777) (xy 329.192612 -429.950229)
			(xy 329.212145 -429.96441) (xy 329.226341 -429.983931) (xy 329.233813 -430.006883) (xy 329.234292 -430.018952)
			(xy 329.234292 -431.560478) (xy 331.141324 -431.560478) (xy 331.141324 -430.833276) (xy 331.141573 -430.824519)
			(xy 331.145554 -430.807461) (xy 331.149198 -430.799494) (xy 331.382624 -430.323244) (xy 331.387351 -430.312738)
			(xy 331.390831 -430.289973) (xy 331.387335 -430.267211) (xy 331.382624 -430.256696) (xy 331.149198 -429.780446)
			(xy 331.14555 -429.772479) (xy 331.141565 -429.755422) (xy 331.141324 -429.746664) (xy 331.141324 -429.018954)
			(xy 331.141768 -429.006864) (xy 331.149235 -428.983864) (xy 331.163428 -428.964286) (xy 331.182965 -428.950037)
			(xy 331.205943 -428.942503) (xy 331.218032 -428.941992) (xy 332.157832 -428.941992) (xy 332.169942 -428.942389)
			(xy 332.192969 -428.949896) (xy 332.207563 -428.960534) (xy 333.14132 -428.960534) (xy 333.14132 -426.41901)
			(xy 333.141816 -426.406923) (xy 333.149267 -426.383926) (xy 333.163447 -426.364348) (xy 333.182973 -426.350096)
			(xy 333.205943 -426.34256) (xy 333.218028 -426.342048) (xy 334.157828 -426.342048) (xy 334.169933 -426.342492)
			(xy 334.192952 -426.349993) (xy 334.212521 -426.364249) (xy 334.226716 -426.383861) (xy 334.234145 -426.406904)
			(xy 334.234536 -426.41901) (xy 334.234536 -427.960536) (xy 335.141316 -427.960536) (xy 335.141316 -425.419012)
			(xy 335.141723 -425.406928) (xy 335.149191 -425.383941) (xy 335.163397 -425.364389) (xy 335.182952 -425.350185)
			(xy 335.205939 -425.342722) (xy 335.218024 -425.342304) (xy 336.157824 -425.342304) (xy 336.169901 -425.342744)
			(xy 336.192871 -425.350215) (xy 336.212409 -425.364417) (xy 336.226602 -425.383961) (xy 336.234061 -425.406935)
			(xy 336.234532 -425.419012) (xy 336.234532 -427.960536) (xy 336.234067 -427.97261) (xy 336.226598 -427.995574)
			(xy 336.2124 -428.015109) (xy 336.192864 -428.029303) (xy 336.169898 -428.036769) (xy 336.157824 -428.037244)
			(xy 335.218024 -428.037244) (xy 335.205954 -428.036716) (xy 335.182994 -428.029264) (xy 335.16346 -428.015083)
			(xy 335.149263 -427.99556) (xy 335.141793 -427.972605) (xy 335.141316 -427.960536) (xy 334.234536 -427.960536)
			(xy 334.234536 -428.960534) (xy 334.234121 -428.972628) (xy 334.226652 -428.995634) (xy 334.212453 -429.015215)
			(xy 334.192907 -429.029464) (xy 334.16992 -429.03699) (xy 334.157828 -429.037496) (xy 333.218028 -429.037496)
			(xy 333.20592 -429.03706) (xy 333.182893 -429.029567) (xy 333.163319 -429.015311) (xy 333.149124 -428.995693)
			(xy 333.141703 -428.972643) (xy 333.14132 -428.960534) (xy 332.207563 -428.960534) (xy 332.212541 -428.964163)
			(xy 332.226734 -428.983788) (xy 332.234156 -429.006843) (xy 332.23454 -429.018954) (xy 332.23454 -431.560478)
			(xy 332.234073 -431.572568) (xy 332.22662 -431.595572) (xy 332.212434 -431.615154) (xy 332.192899 -431.629404)
			(xy 332.169921 -431.636933) (xy 332.157832 -431.63744) (xy 331.218032 -431.63744) (xy 331.205929 -431.636957)
			(xy 331.182909 -431.629471) (xy 331.163339 -431.615225) (xy 331.149142 -431.59562) (xy 331.141713 -431.572582)
			(xy 331.141324 -431.560478) (xy 329.234292 -431.560478) (xy 329.234292 -432.560476) (xy 329.233867 -432.572559)
			(xy 329.226404 -432.595544) (xy 329.212201 -432.615096) (xy 329.192651 -432.6293) (xy 329.169667 -432.636765)
			(xy 329.157584 -432.637184) (xy 328.217784 -432.637184) (xy 328.205698 -432.636801) (xy 328.182711 -432.629326)
			(xy 328.163159 -432.615113) (xy 328.148956 -432.595553) (xy 328.141493 -432.572562) (xy 328.141076 -432.560476)
			(xy 327.206663 -432.560476) (xy 327.212078 -432.56441) (xy 327.22632 -432.584004) (xy 327.233816 -432.607039)
			(xy 327.234296 -432.61915) (xy 327.234296 -435.160674) (xy 327.233767 -435.172784) (xy 327.226291 -435.19582)
			(xy 327.212062 -435.21542) (xy 327.192474 -435.229663) (xy 327.169443 -435.237157) (xy 327.157334 -435.237636)
			(xy 326.217534 -435.237636) (xy 326.20541 -435.237211) (xy 326.182348 -435.229725) (xy 326.16273 -435.215475)
			(xy 326.148479 -435.195859) (xy 326.140991 -435.172798) (xy 326.140572 -435.160674) (xy 325.2343 -435.160674)
			(xy 325.2343 -436.160672) (xy 325.233816 -436.172721) (xy 325.226391 -436.195645) (xy 325.212257 -436.215162)
			(xy 325.192791 -436.229366) (xy 325.169893 -436.236873) (xy 325.157846 -436.23738) (xy 324.217538 -436.23738)
			(xy 324.205452 -436.236861) (xy 324.182456 -436.229417) (xy 324.162878 -436.215243) (xy 324.148625 -436.195721)
			(xy 324.141089 -436.172756) (xy 324.140576 -436.160672) (xy 323.207269 -436.160672) (xy 323.212532 -436.164484)
			(xy 323.226783 -436.184021) (xy 323.234308 -436.207002) (xy 323.234812 -436.219092) (xy 323.234812 -438.760616)
			(xy 323.234354 -438.772666) (xy 323.226918 -438.79559) (xy 323.212776 -438.815104) (xy 323.193307 -438.829307)
			(xy 323.170406 -438.836815) (xy 323.158358 -438.837324) (xy 322.21805 -438.837324) (xy 322.205959 -438.836849)
			(xy 322.182954 -438.829402) (xy 322.16337 -438.815219) (xy 322.149119 -438.795684) (xy 322.141593 -438.772705)
			(xy 322.141088 -438.760616) (xy 321.234816 -438.760616) (xy 321.234816 -439.760614) (xy 324.141084 -439.760614)
			(xy 324.141084 -437.21909) (xy 324.141452 -437.206962) (xy 324.148953 -437.183895) (xy 324.163216 -437.164276)
			(xy 324.182845 -437.150027) (xy 324.205918 -437.142544) (xy 324.218046 -437.142128) (xy 325.157846 -437.142128)
			(xy 325.169962 -437.142572) (xy 325.193005 -437.150071) (xy 325.212605 -437.164321) (xy 325.226845 -437.183927)
			(xy 325.234333 -437.206974) (xy 325.234808 -437.21909) (xy 325.234808 -438.760616) (xy 326.14108 -438.760616)
			(xy 326.14108 -436.219092) (xy 326.141553 -436.207043) (xy 326.148985 -436.184121) (xy 326.163124 -436.164607)
			(xy 326.18259 -436.150403) (xy 326.205487 -436.142894) (xy 326.217534 -436.142384) (xy 327.157842 -436.142384)
			(xy 327.169938 -436.142772) (xy 327.192948 -436.150246) (xy 327.207321 -436.160672) (xy 328.140568 -436.160672)
			(xy 328.140568 -433.619148) (xy 328.1411 -433.607103) (xy 328.148516 -433.584185) (xy 328.162639 -433.564671)
			(xy 328.182093 -433.550465) (xy 328.20498 -433.542952) (xy 328.217022 -433.54244) (xy 329.15733 -433.54244)
			(xy 329.169421 -433.542882) (xy 329.192423 -433.550347) (xy 329.212002 -433.56454) (xy 329.226252 -433.584078)
			(xy 329.233783 -433.607058) (xy 329.234292 -433.619148) (xy 329.234292 -435.160674) (xy 331.140816 -435.160674)
			(xy 331.140816 -432.61915) (xy 331.141269 -432.607035) (xy 331.148767 -432.583994) (xy 331.163015 -432.564395)
			(xy 331.182619 -432.550154) (xy 331.205663 -432.542664) (xy 331.217778 -432.542188) (xy 332.157578 -432.542188)
			(xy 332.169686 -432.54273) (xy 332.19272 -432.550205) (xy 332.20687 -432.560476) (xy 333.14132 -432.560476)
			(xy 333.14132 -431.833274) (xy 333.141569 -431.824517) (xy 333.14555 -431.807459) (xy 333.149194 -431.799492)
			(xy 333.38262 -431.323242) (xy 333.387349 -431.312736) (xy 333.390828 -431.289971) (xy 333.387331 -431.267209)
			(xy 333.38262 -431.256694) (xy 333.149194 -430.780444) (xy 333.145545 -430.772478) (xy 333.141561 -430.75542)
			(xy 333.14132 -430.746662) (xy 333.14132 -430.018952) (xy 333.141724 -430.006872) (xy 333.149203 -429.983899)
			(xy 333.163414 -429.96436) (xy 333.182967 -429.950168) (xy 333.205948 -429.942712) (xy 333.218028 -429.942244)
			(xy 334.157828 -429.942244) (xy 334.169899 -429.942739) (xy 334.192859 -429.950204) (xy 334.212392 -429.964394)
			(xy 334.226587 -429.983923) (xy 334.234058 -430.006881) (xy 334.234536 -430.018952) (xy 334.234536 -431.560478)
			(xy 335.141316 -431.560478) (xy 335.141316 -430.833276) (xy 335.141566 -430.824519) (xy 335.145546 -430.807461)
			(xy 335.14919 -430.799494) (xy 335.382616 -430.323244) (xy 335.387343 -430.312738) (xy 335.390823 -430.289973)
			(xy 335.387327 -430.267211) (xy 335.382616 -430.256696) (xy 335.14919 -429.780446) (xy 335.145541 -429.77248)
			(xy 335.141557 -429.755422) (xy 335.141316 -429.746664) (xy 335.141316 -429.018954) (xy 335.141768 -429.006864)
			(xy 335.149234 -428.983866) (xy 335.163426 -428.964289) (xy 335.18296 -428.950039) (xy 335.205936 -428.942504)
			(xy 335.218024 -428.941992) (xy 336.157824 -428.941992) (xy 336.169933 -428.942396) (xy 336.19296 -428.949901)
			(xy 336.207549 -428.960534) (xy 337.141312 -428.960534) (xy 337.141312 -426.41901) (xy 337.141815 -426.406924)
			(xy 337.149266 -426.383928) (xy 337.163444 -426.364351) (xy 337.182968 -426.350099) (xy 337.205936 -426.342562)
			(xy 337.21802 -426.342048) (xy 338.15782 -426.342048) (xy 338.169925 -426.342499) (xy 338.192944 -426.349997)
			(xy 338.212512 -426.364252) (xy 338.226708 -426.383863) (xy 338.234137 -426.406904) (xy 338.234528 -426.41901)
			(xy 338.234528 -427.960536) (xy 339.141308 -427.960536) (xy 339.141308 -425.419012) (xy 339.141723 -425.406928)
			(xy 339.149189 -425.383943) (xy 339.163394 -425.364392) (xy 339.182947 -425.350188) (xy 339.205932 -425.342723)
			(xy 339.218016 -425.342304) (xy 340.157816 -425.342304) (xy 340.169893 -425.342751) (xy 340.192862 -425.350219)
			(xy 340.2124 -425.36442) (xy 340.226594 -425.383963) (xy 340.234053 -425.406935) (xy 340.234524 -425.419012)
			(xy 340.234524 -427.960536) (xy 340.234067 -427.972611) (xy 340.226596 -427.995577) (xy 340.212397 -428.015112)
			(xy 340.192859 -428.029306) (xy 340.169891 -428.03677) (xy 340.157816 -428.037244) (xy 339.218016 -428.037244)
			(xy 339.205946 -428.036723) (xy 339.182985 -428.029269) (xy 339.163451 -428.015086) (xy 339.149255 -427.995561)
			(xy 339.141785 -427.972606) (xy 339.141308 -427.960536) (xy 338.234528 -427.960536) (xy 338.234528 -428.960534)
			(xy 338.234121 -428.972629) (xy 338.226651 -428.995636) (xy 338.21245 -429.015218) (xy 338.192902 -429.029466)
			(xy 338.169913 -429.036992) (xy 338.15782 -429.037496) (xy 337.21802 -429.037496) (xy 337.205912 -429.037066)
			(xy 337.182885 -429.029572) (xy 337.163311 -429.015314) (xy 337.149116 -428.995695) (xy 337.141695 -428.972643)
			(xy 337.141312 -428.960534) (xy 336.207549 -428.960534) (xy 336.212532 -428.964166) (xy 336.226726 -428.983789)
			(xy 336.234148 -429.006843) (xy 336.234532 -429.018954) (xy 336.234532 -431.560478) (xy 336.234073 -431.572569)
			(xy 336.226619 -431.595574) (xy 336.212432 -431.615156) (xy 336.192894 -431.629407) (xy 336.169914 -431.636934)
			(xy 336.157824 -431.63744) (xy 335.218024 -431.63744) (xy 335.20592 -431.636964) (xy 335.182901 -431.629476)
			(xy 335.163331 -431.615228) (xy 335.149134 -431.595622) (xy 335.141705 -431.572583) (xy 335.141316 -431.560478)
			(xy 334.234536 -431.560478) (xy 334.234536 -432.560476) (xy 334.234016 -432.572547) (xy 334.226563 -432.595508)
			(xy 334.21238 -432.615043) (xy 334.192855 -432.62924) (xy 334.169898 -432.636708) (xy 334.157828 -432.637184)
			(xy 333.218028 -432.637184) (xy 333.205944 -432.636763) (xy 333.182959 -432.6293) (xy 333.163406 -432.615097)
			(xy 333.149202 -432.595545) (xy 333.141738 -432.57256) (xy 333.14132 -432.560476) (xy 332.20687 -432.560476)
			(xy 332.212318 -432.564431) (xy 332.226562 -432.584015) (xy 332.234059 -432.607042) (xy 332.23454 -432.61915)
			(xy 332.23454 -435.160674) (xy 332.234118 -435.172798) (xy 332.22663 -435.195859) (xy 332.21238 -435.215477)
			(xy 332.192763 -435.229728) (xy 332.169702 -435.237217) (xy 332.157578 -435.237636) (xy 331.217778 -435.237636)
			(xy 331.205652 -435.237258) (xy 331.182588 -435.229757) (xy 331.162971 -435.215495) (xy 331.148721 -435.195869)
			(xy 331.141234 -435.172801) (xy 331.140816 -435.160674) (xy 329.234292 -435.160674) (xy 329.234292 -436.160672)
			(xy 329.233816 -436.172722) (xy 329.22639 -436.195648) (xy 329.212254 -436.215164) (xy 329.192786 -436.229368)
			(xy 329.169886 -436.236874) (xy 329.157838 -436.23738) (xy 328.21753 -436.23738) (xy 328.205444 -436.236867)
			(xy 328.182448 -436.229421) (xy 328.162869 -436.215246) (xy 328.148617 -436.195723) (xy 328.14108 -436.172756)
			(xy 328.140568 -436.160672) (xy 327.207321 -436.160672) (xy 327.212531 -436.164451) (xy 327.226778 -436.184004)
			(xy 327.234301 -436.206997) (xy 327.234804 -436.219092) (xy 327.234804 -438.760616) (xy 327.234354 -438.772667)
			(xy 327.226917 -438.795592) (xy 327.212774 -438.815107) (xy 327.193302 -438.82931) (xy 327.170399 -438.836816)
			(xy 327.15835 -438.837324) (xy 326.218042 -438.837324) (xy 326.205951 -438.836856) (xy 326.182946 -438.829407)
			(xy 326.163362 -438.815222) (xy 326.149111 -438.795686) (xy 326.141585 -438.772705) (xy 326.14108 -438.760616)
			(xy 325.234808 -438.760616) (xy 325.234808 -439.760614) (xy 328.141076 -439.760614) (xy 328.141076 -437.21909)
			(xy 328.141452 -437.206963) (xy 328.148952 -437.183897) (xy 328.163213 -437.164279) (xy 328.18284 -437.15003)
			(xy 328.205911 -437.142545) (xy 328.218038 -437.142128) (xy 329.157838 -437.142128) (xy 329.169954 -437.142579)
			(xy 329.192996 -437.150076) (xy 329.212597 -437.164323) (xy 329.226837 -437.183929) (xy 329.234325 -437.206974)
			(xy 329.2348 -437.21909) (xy 329.2348 -438.760616) (xy 331.141324 -438.760616) (xy 331.141324 -436.219092)
			(xy 331.141706 -436.207006) (xy 331.14918 -436.184017) (xy 331.163393 -436.164464) (xy 331.182953 -436.150262)
			(xy 331.205945 -436.1428) (xy 331.218032 -436.142384) (xy 332.157832 -436.142384) (xy 332.169907 -436.142837)
			(xy 332.192874 -436.150307) (xy 332.207134 -436.160672) (xy 333.140812 -436.160672) (xy 333.140812 -433.619148)
			(xy 333.141301 -433.607099) (xy 333.148722 -433.584173) (xy 333.162855 -433.564655) (xy 333.18232 -433.550451)
			(xy 333.205219 -433.542946) (xy 333.217266 -433.54244) (xy 334.157574 -433.54244) (xy 334.169662 -433.54293)
			(xy 334.192662 -433.550379) (xy 334.212242 -433.56456) (xy 334.226494 -433.584089) (xy 334.234026 -433.607062)
			(xy 334.234536 -433.619148) (xy 334.234536 -435.160674) (xy 335.140808 -435.160674) (xy 335.140808 -432.61915)
			(xy 335.141269 -432.607036) (xy 335.148766 -432.583996) (xy 335.163012 -432.564398) (xy 335.182614 -432.550157)
			(xy 335.205656 -432.542666) (xy 335.21777 -432.542188) (xy 336.15757 -432.542188) (xy 336.169678 -432.542737)
			(xy 336.192712 -432.550209) (xy 336.206858 -432.560476) (xy 337.141312 -432.560476) (xy 337.141312 -431.833274)
			(xy 337.141562 -431.824517) (xy 337.145542 -431.807459) (xy 337.149186 -431.799492) (xy 337.382612 -431.323242)
			(xy 337.387341 -431.312736) (xy 337.390821 -431.289971) (xy 337.387324 -431.267209) (xy 337.382612 -431.256694)
			(xy 337.149186 -430.780444) (xy 337.145537 -430.772478) (xy 337.141553 -430.75542) (xy 337.141312 -430.746662)
			(xy 337.141312 -430.018952) (xy 337.141724 -430.006873) (xy 337.149202 -429.983901) (xy 337.163411 -429.964363)
			(xy 337.182962 -429.950171) (xy 337.205941 -429.942713) (xy 337.21802 -429.942244) (xy 338.15782 -429.942244)
			(xy 338.169891 -429.942747) (xy 338.19285 -429.950209) (xy 338.212383 -429.964397) (xy 338.226578 -429.983924)
			(xy 338.234049 -430.006881) (xy 338.234528 -430.018952) (xy 338.234528 -431.560478) (xy 339.141308 -431.560478)
			(xy 339.141308 -430.833276) (xy 339.141559 -430.824519) (xy 339.145538 -430.807461) (xy 339.149182 -430.799494)
			(xy 339.382608 -430.323244) (xy 339.387336 -430.312738) (xy 339.390816 -430.289973) (xy 339.38732 -430.26721)
			(xy 339.382608 -430.256696) (xy 339.149182 -429.780446) (xy 339.145533 -429.77248) (xy 339.141549 -429.755422)
			(xy 339.141308 -429.746664) (xy 339.141308 -429.018954) (xy 339.141768 -429.006865) (xy 339.149233 -428.983868)
			(xy 339.163423 -428.964292) (xy 339.182955 -428.950042) (xy 339.205929 -428.942505) (xy 339.218016 -428.941992)
			(xy 340.157816 -428.941992) (xy 340.169925 -428.942402) (xy 340.192951 -428.949905) (xy 340.207536 -428.960534)
			(xy 341.141304 -428.960534) (xy 341.141304 -426.41901) (xy 341.141815 -426.406925) (xy 341.149265 -426.38393)
			(xy 341.163441 -426.364353) (xy 341.182963 -426.350101) (xy 341.205928 -426.342563) (xy 341.218012 -426.342048)
			(xy 342.157812 -426.342048) (xy 342.169916 -426.342505) (xy 342.192935 -426.350002) (xy 342.212504 -426.364255)
			(xy 342.2267 -426.383864) (xy 342.234129 -426.406905) (xy 342.23452 -426.41901) (xy 342.23452 -427.960536)
			(xy 343.1413 -427.960536) (xy 343.1413 -425.419012) (xy 343.141723 -425.406929) (xy 343.149188 -425.383946)
			(xy 343.163392 -425.364394) (xy 343.182942 -425.35019) (xy 343.205925 -425.342724) (xy 343.218008 -425.342304)
			(xy 344.157808 -425.342304) (xy 344.169892 -425.342706) (xy 344.192877 -425.350177) (xy 344.212429 -425.364386)
			(xy 344.226632 -425.383941) (xy 344.234097 -425.406928) (xy 344.234516 -425.419012) (xy 344.234516 -427.960536)
			(xy 344.234067 -427.972612) (xy 344.226595 -427.995579) (xy 344.212395 -428.015115) (xy 344.192854 -428.029308)
			(xy 344.169884 -428.036771) (xy 344.157808 -428.037244) (xy 343.218008 -428.037244) (xy 343.205937 -428.03673)
			(xy 343.182977 -428.029274) (xy 343.163443 -428.015089) (xy 343.149247 -427.995563) (xy 343.141777 -427.972606)
			(xy 343.1413 -427.960536) (xy 342.23452 -427.960536) (xy 342.23452 -428.960534) (xy 342.234121 -428.972629)
			(xy 342.22665 -428.995638) (xy 342.212447 -429.015221) (xy 342.192897 -429.029469) (xy 342.169906 -429.036993)
			(xy 342.157812 -429.037496) (xy 341.218012 -429.037496) (xy 341.205903 -429.037073) (xy 341.182876 -429.029577)
			(xy 341.163302 -429.015317) (xy 341.149107 -428.995696) (xy 341.141687 -428.972644) (xy 341.141304 -428.960534)
			(xy 340.207536 -428.960534) (xy 340.212524 -428.964169) (xy 340.226718 -428.983791) (xy 340.23414 -429.006844)
			(xy 340.234524 -429.018954) (xy 340.234524 -431.560478) (xy 340.234073 -431.57257) (xy 340.226618 -431.595576)
			(xy 340.212429 -431.615159) (xy 340.192889 -431.629409) (xy 340.169906 -431.636935) (xy 340.157816 -431.63744)
			(xy 339.218016 -431.63744) (xy 339.205912 -431.63697) (xy 339.182892 -431.62948) (xy 339.163322 -431.615231)
			(xy 339.149126 -431.595623) (xy 339.141697 -431.572583) (xy 339.141308 -431.560478) (xy 338.234528 -431.560478)
			(xy 338.234528 -432.560476) (xy 338.234067 -432.572555) (xy 338.226609 -432.595534) (xy 338.212414 -432.615083)
			(xy 338.192873 -432.629288) (xy 338.169899 -432.63676) (xy 338.15782 -432.637184) (xy 337.21802 -432.637184)
			(xy 337.205936 -432.63677) (xy 337.18295 -432.629305) (xy 337.163397 -432.6151) (xy 337.149193 -432.595547)
			(xy 337.14173 -432.57256) (xy 337.141312 -432.560476) (xy 336.206858 -432.560476) (xy 336.21231 -432.564433)
			(xy 336.226554 -432.584016) (xy 336.234051 -432.607042) (xy 336.234532 -432.61915) (xy 336.234532 -435.160674)
			(xy 336.234117 -435.172798) (xy 336.226629 -435.195861) (xy 336.212377 -435.21548) (xy 336.192758 -435.229731)
			(xy 336.169694 -435.237218) (xy 336.15757 -435.237636) (xy 335.21777 -435.237636) (xy 335.205651 -435.237214)
			(xy 335.182603 -435.229715) (xy 335.162999 -435.215461) (xy 335.14876 -435.195847) (xy 335.141278 -435.172793)
			(xy 335.140808 -435.160674) (xy 334.234536 -435.160674) (xy 334.234536 -436.160672) (xy 334.234017 -436.172717)
			(xy 334.226596 -436.195636) (xy 334.212469 -436.215149) (xy 334.193014 -436.229354) (xy 334.170125 -436.236868)
			(xy 334.158082 -436.23738) (xy 333.217774 -436.23738) (xy 333.205685 -436.236915) (xy 333.182687 -436.229454)
			(xy 333.163109 -436.215266) (xy 333.148859 -436.195734) (xy 333.141324 -436.172759) (xy 333.140812 -436.160672)
			(xy 332.207134 -436.160672) (xy 332.21241 -436.164507) (xy 332.226604 -436.184047) (xy 332.234067 -436.207016)
			(xy 332.23454 -436.219092) (xy 332.23454 -438.760616) (xy 332.23405 -438.772688) (xy 332.226587 -438.79565)
			(xy 332.212396 -438.815184) (xy 332.192865 -438.829379) (xy 332.169904 -438.836847) (xy 332.157832 -438.837324)
			(xy 331.218032 -438.837324) (xy 331.205953 -438.83686) (xy 331.182974 -438.829403) (xy 331.163424 -438.81521)
			(xy 331.149218 -438.795669) (xy 331.141747 -438.772695) (xy 331.141324 -438.760616) (xy 329.2348 -438.760616)
			(xy 329.2348 -439.760614) (xy 333.14132 -439.760614) (xy 333.14132 -437.21909) (xy 333.141799 -437.207002)
			(xy 333.149256 -437.184004) (xy 333.16344 -437.164426) (xy 333.18297 -437.150176) (xy 333.205942 -437.14264)
			(xy 333.218028 -437.142128) (xy 334.157828 -437.142128) (xy 334.169941 -437.142493) (xy 334.192974 -437.150003)
			(xy 334.212549 -437.164277) (xy 334.226742 -437.183911) (xy 334.234157 -437.206975) (xy 334.234536 -437.21909)
			(xy 334.234536 -438.760616) (xy 335.141316 -438.760616) (xy 335.141316 -436.219092) (xy 335.141706 -436.207006)
			(xy 335.149179 -436.184019) (xy 335.16339 -436.164467) (xy 335.182948 -436.150264) (xy 335.205938 -436.142801)
			(xy 335.218024 -436.142384) (xy 336.157824 -436.142384) (xy 336.169899 -436.142844) (xy 336.192866 -436.150312)
			(xy 336.20712 -436.160672) (xy 337.140804 -436.160672) (xy 337.140804 -433.619148) (xy 337.141301 -433.6071)
			(xy 337.148721 -433.584175) (xy 337.162852 -433.564658) (xy 337.182315 -433.550453) (xy 337.205212 -433.542947)
			(xy 337.217258 -433.54244) (xy 338.157566 -433.54244) (xy 338.169654 -433.542936) (xy 338.192653 -433.550384)
			(xy 338.212234 -433.564563) (xy 338.226486 -433.58409) (xy 338.234018 -433.607062) (xy 338.234528 -433.619148)
			(xy 338.234528 -435.160674) (xy 339.1408 -435.160674) (xy 339.1408 -432.61915) (xy 339.141269 -432.607037)
			(xy 339.148765 -432.583998) (xy 339.163009 -432.564401) (xy 339.182609 -432.550159) (xy 339.205649 -432.542667)
			(xy 339.217762 -432.542188) (xy 340.157562 -432.542188) (xy 340.16967 -432.542743) (xy 340.192703 -432.550214)
			(xy 340.206844 -432.560476) (xy 341.141304 -432.560476) (xy 341.141304 -431.833274) (xy 341.141555 -431.824517)
			(xy 341.145534 -431.807459) (xy 341.149178 -431.799492) (xy 341.382604 -431.323242) (xy 341.387334 -431.312736)
			(xy 341.390814 -431.289971) (xy 341.387316 -431.267208) (xy 341.382604 -431.256694) (xy 341.149178 -430.780444)
			(xy 341.145528 -430.772478) (xy 341.141545 -430.75542) (xy 341.141304 -430.746662) (xy 341.141304 -430.018952)
			(xy 341.141723 -430.006874) (xy 341.149201 -429.983903) (xy 341.163408 -429.964366) (xy 341.182957 -429.950173)
			(xy 341.205933 -429.942714) (xy 341.218012 -429.942244) (xy 342.157812 -429.942244) (xy 342.169882 -429.942753)
			(xy 342.192842 -429.950213) (xy 342.212374 -429.9644) (xy 342.22657 -429.983926) (xy 342.234041 -430.006882)
			(xy 342.23452 -430.018952) (xy 342.23452 -431.560478) (xy 343.1413 -431.560478) (xy 343.1413 -430.833276)
			(xy 343.141552 -430.824519) (xy 343.145531 -430.807461) (xy 343.149174 -430.799494) (xy 343.3826 -430.323244)
			(xy 343.387328 -430.312738) (xy 343.390809 -430.289973) (xy 343.387312 -430.26721) (xy 343.3826 -430.256696)
			(xy 343.149174 -429.780446) (xy 343.145524 -429.77248) (xy 343.141541 -429.755422) (xy 343.1413 -429.746664)
			(xy 343.1413 -429.018954) (xy 343.141767 -429.006866) (xy 343.149232 -428.983871) (xy 343.16342 -428.964295)
			(xy 343.18295 -428.950044) (xy 343.205922 -428.942507) (xy 343.218008 -428.941992) (xy 344.157808 -428.941992)
			(xy 344.169917 -428.942409) (xy 344.192943 -428.94991) (xy 344.207523 -428.960534) (xy 345.141296 -428.960534)
			(xy 345.141296 -426.41901) (xy 345.141815 -426.406925) (xy 345.149264 -426.383932) (xy 345.163439 -426.364356)
			(xy 345.182958 -426.350104) (xy 345.205921 -426.342564) (xy 345.218004 -426.342048) (xy 346.157804 -426.342048)
			(xy 346.169908 -426.342512) (xy 346.192927 -426.350006) (xy 346.212495 -426.364257) (xy 346.226691 -426.383866)
			(xy 346.234121 -426.406905) (xy 346.234512 -426.41901) (xy 346.234512 -428.960534) (xy 346.234121 -428.97263)
			(xy 346.226649 -428.99564) (xy 346.212444 -429.015223) (xy 346.192892 -429.029471) (xy 346.169899 -429.036994)
			(xy 346.157804 -429.037496) (xy 345.218004 -429.037496) (xy 345.205895 -429.03708) (xy 345.182867 -429.029582)
			(xy 345.163293 -429.01532) (xy 345.149099 -428.995698) (xy 345.141679 -428.972644) (xy 345.141296 -428.960534)
			(xy 344.207523 -428.960534) (xy 344.212515 -428.964172) (xy 344.22671 -428.983792) (xy 344.234132 -429.006844)
			(xy 344.234516 -429.018954) (xy 344.234516 -431.560478) (xy 344.234073 -431.572571) (xy 344.226617 -431.595578)
			(xy 344.212426 -431.615162) (xy 344.192884 -431.629412) (xy 344.169899 -431.636937) (xy 344.157808 -431.63744)
			(xy 343.218008 -431.63744) (xy 343.205904 -431.636978) (xy 343.182883 -431.629485) (xy 343.163313 -431.615234)
			(xy 343.149117 -431.595625) (xy 343.141689 -431.572584) (xy 343.1413 -431.560478) (xy 342.23452 -431.560478)
			(xy 342.23452 -432.560476) (xy 342.234067 -432.572556) (xy 342.226607 -432.595536) (xy 342.212411 -432.615086)
			(xy 342.192868 -432.629291) (xy 342.169892 -432.636761) (xy 342.157812 -432.637184) (xy 341.218012 -432.637184)
			(xy 341.205928 -432.636777) (xy 341.182941 -432.629309) (xy 341.163389 -432.615103) (xy 341.149185 -432.595548)
			(xy 341.141722 -432.572561) (xy 341.141304 -432.560476) (xy 340.206844 -432.560476) (xy 340.212301 -432.564436)
			(xy 340.226546 -432.584018) (xy 340.234043 -432.607043) (xy 340.234524 -432.61915) (xy 340.234524 -435.160674)
			(xy 340.234117 -435.172799) (xy 340.226628 -435.195864) (xy 340.212374 -435.215482) (xy 340.192753 -435.229733)
			(xy 340.169687 -435.237219) (xy 340.157562 -435.237636) (xy 339.217762 -435.237636) (xy 339.205643 -435.23722)
			(xy 339.182594 -435.229719) (xy 339.162991 -435.215464) (xy 339.148751 -435.195849) (xy 339.14127 -435.172794)
			(xy 339.1408 -435.160674) (xy 338.234528 -435.160674) (xy 338.234528 -436.160672) (xy 338.234017 -436.172718)
			(xy 338.226595 -436.195638) (xy 338.212467 -436.215152) (xy 338.193009 -436.229357) (xy 338.170118 -436.236869)
			(xy 338.158074 -436.23738) (xy 337.217766 -436.23738) (xy 337.205677 -436.236922) (xy 337.182678 -436.229458)
			(xy 337.163101 -436.215269) (xy 337.14885 -436.195735) (xy 337.141316 -436.17276) (xy 337.140804 -436.160672)
			(xy 336.20712 -436.160672) (xy 336.212401 -436.16451) (xy 336.226595 -436.184049) (xy 336.234059 -436.207017)
			(xy 336.234532 -436.219092) (xy 336.234532 -438.760616) (xy 336.23405 -438.772689) (xy 336.226586 -438.795653)
			(xy 336.212393 -438.815187) (xy 336.19286 -438.829382) (xy 336.169897 -438.836848) (xy 336.157824 -438.837324)
			(xy 335.218024 -438.837324) (xy 335.205944 -438.836867) (xy 335.182965 -438.829408) (xy 335.163416 -438.815213)
			(xy 335.14921 -438.795671) (xy 335.141739 -438.772696) (xy 335.141316 -438.760616) (xy 334.234536 -438.760616)
			(xy 334.234536 -439.760614) (xy 337.141312 -439.760614) (xy 337.141312 -437.21909) (xy 337.141799 -437.207003)
			(xy 337.149255 -437.184007) (xy 337.163437 -437.164429) (xy 337.182965 -437.150178) (xy 337.205934 -437.142641)
			(xy 337.21802 -437.142128) (xy 338.15782 -437.142128) (xy 338.169933 -437.1425) (xy 338.192965 -437.150008)
			(xy 338.212541 -437.16428) (xy 338.226734 -437.183913) (xy 338.234149 -437.206976) (xy 338.234528 -437.21909)
			(xy 338.234528 -438.760616) (xy 339.141308 -438.760616) (xy 339.141308 -436.219092) (xy 339.141706 -436.207007)
			(xy 339.149178 -436.184021) (xy 339.163387 -436.16447) (xy 339.182943 -436.150267) (xy 339.205931 -436.142802)
			(xy 339.218016 -436.142384) (xy 340.157816 -436.142384) (xy 340.169891 -436.142851) (xy 340.192857 -436.150317)
			(xy 340.207107 -436.160672) (xy 341.140796 -436.160672) (xy 341.140796 -433.619148) (xy 341.141301 -433.607101)
			(xy 341.14872 -433.584177) (xy 341.162849 -433.564661) (xy 341.18231 -433.550456) (xy 341.205205 -433.542948)
			(xy 341.21725 -433.54244) (xy 342.157558 -433.54244) (xy 342.169645 -433.542943) (xy 342.192645 -433.550388)
			(xy 342.212225 -433.564566) (xy 342.226477 -433.584092) (xy 342.23401 -433.607062) (xy 342.23452 -433.619148)
			(xy 342.23452 -435.160674) (xy 343.140792 -435.160674) (xy 343.140792 -432.61915) (xy 343.141268 -432.607037)
			(xy 343.148764 -432.584) (xy 343.163006 -432.564403) (xy 343.182604 -432.550162) (xy 343.205641 -432.542668)
			(xy 343.217754 -432.542188) (xy 344.157554 -432.542188) (xy 344.169661 -432.54275) (xy 344.192695 -432.550219)
			(xy 344.206831 -432.560476) (xy 345.141296 -432.560476) (xy 345.141296 -431.833274) (xy 345.141547 -431.824517)
			(xy 345.145527 -431.807459) (xy 345.14917 -431.799492) (xy 345.382596 -431.323242) (xy 345.387326 -431.312737)
			(xy 345.390806 -431.289971) (xy 345.387309 -431.267208) (xy 345.382596 -431.256694) (xy 345.14917 -430.780444)
			(xy 345.14552 -430.772478) (xy 345.141537 -430.75542) (xy 345.141296 -430.746662) (xy 345.141296 -430.018952)
			(xy 345.141723 -430.006875) (xy 345.149199 -429.983905) (xy 345.163405 -429.964368) (xy 345.182952 -429.950176)
			(xy 345.205926 -429.942715) (xy 345.218004 -429.942244) (xy 346.157804 -429.942244) (xy 346.169874 -429.94276)
			(xy 346.192833 -429.950218) (xy 346.212366 -429.964403) (xy 346.226562 -429.983927) (xy 346.234033 -430.006882)
			(xy 346.234512 -430.018952) (xy 346.234512 -431.360072) (xy 356.154736 -431.360072) (xy 356.155234 -431.275192)
			(xy 356.163191 -431.105619) (xy 356.179087 -430.936605) (xy 356.202888 -430.768522) (xy 356.234542 -430.601739)
			(xy 356.273978 -430.436623) (xy 356.32111 -430.273538) (xy 356.375834 -430.11284) (xy 356.438031 -429.954885)
			(xy 356.507563 -429.800018) (xy 356.584278 -429.648581) (xy 356.668006 -429.500905) (xy 356.758564 -429.357317)
			(xy 356.855753 -429.218131) (xy 356.95936 -429.083654) (xy 357.069155 -428.954181) (xy 357.184899 -428.829996)
			(xy 357.306336 -428.711373) (xy 357.4332 -428.598572) (xy 357.565211 -428.491842) (xy 357.702081 -428.391417)
			(xy 357.843506 -428.297518) (xy 357.989178 -428.21035) (xy 358.138776 -428.130107) (xy 358.29197 -428.056963)
			(xy 358.448424 -427.991081) (xy 358.607794 -427.932604) (xy 358.76973 -427.881662) (xy 358.933876 -427.838366)
			(xy 359.099871 -427.802811) (xy 359.26735 -427.775076) (xy 359.435945 -427.755222) (xy 359.605285 -427.743292)
			(xy 359.774998 -427.739313) (xy 359.944711 -427.743292) (xy 360.114051 -427.755222) (xy 360.282646 -427.775076)
			(xy 360.450125 -427.802811) (xy 360.61612 -427.838366) (xy 360.780266 -427.881662) (xy 360.942202 -427.932604)
			(xy 361.018326 -427.960536) (xy 381.2413 -427.960536) (xy 381.2413 -425.419012) (xy 381.241723 -425.406929)
			(xy 381.249188 -425.383946) (xy 381.263392 -425.364394) (xy 381.282942 -425.35019) (xy 381.305925 -425.342724)
			(xy 381.318008 -425.342304) (xy 382.257808 -425.342304) (xy 382.269892 -425.342706) (xy 382.292877 -425.350177)
			(xy 382.312429 -425.364386) (xy 382.326632 -425.383941) (xy 382.334097 -425.406928) (xy 382.334516 -425.419012)
			(xy 382.334516 -427.960536) (xy 382.334067 -427.972612) (xy 382.326595 -427.995579) (xy 382.312395 -428.015115)
			(xy 382.292854 -428.029308) (xy 382.269884 -428.036771) (xy 382.257808 -428.037244) (xy 381.318008 -428.037244)
			(xy 381.305937 -428.03673) (xy 381.282977 -428.029274) (xy 381.263443 -428.015089) (xy 381.249247 -427.995563)
			(xy 381.241777 -427.972606) (xy 381.2413 -427.960536) (xy 361.018326 -427.960536) (xy 361.101572 -427.991081)
			(xy 361.258026 -428.056963) (xy 361.41122 -428.130107) (xy 361.560818 -428.21035) (xy 361.70649 -428.297518)
			(xy 361.847915 -428.391417) (xy 361.984785 -428.491842) (xy 362.116796 -428.598572) (xy 362.24366 -428.711373)
			(xy 362.365097 -428.829996) (xy 362.480841 -428.954181) (xy 362.590636 -429.083654) (xy 362.694243 -429.218131)
			(xy 362.791432 -429.357317) (xy 362.88199 -429.500905) (xy 362.965718 -429.648581) (xy 363.042433 -429.800018)
			(xy 363.111965 -429.954885) (xy 363.174162 -430.11284) (xy 363.228886 -430.273538) (xy 363.276018 -430.436623)
			(xy 363.315454 -430.601739) (xy 363.347108 -430.768522) (xy 363.370909 -430.936605) (xy 363.386805 -431.105619)
			(xy 363.394762 -431.275192) (xy 363.39526 -431.360072) (xy 363.394788 -431.445675) (xy 363.389359 -431.560478)
			(xy 381.2413 -431.560478) (xy 381.2413 -430.833276) (xy 381.241552 -430.824519) (xy 381.245531 -430.807461)
			(xy 381.249174 -430.799494) (xy 381.4826 -430.323244) (xy 381.487328 -430.312738) (xy 381.490809 -430.289973)
			(xy 381.487312 -430.26721) (xy 381.4826 -430.256696) (xy 381.249174 -429.780446) (xy 381.245524 -429.77248)
			(xy 381.241541 -429.755422) (xy 381.2413 -429.746664) (xy 381.2413 -429.018954) (xy 381.241767 -429.006866)
			(xy 381.249232 -428.983871) (xy 381.26342 -428.964295) (xy 381.28295 -428.950044) (xy 381.305922 -428.942507)
			(xy 381.318008 -428.941992) (xy 382.257808 -428.941992) (xy 382.269917 -428.942409) (xy 382.292943 -428.94991)
			(xy 382.307523 -428.960534) (xy 383.241296 -428.960534) (xy 383.241296 -426.41901) (xy 383.241815 -426.406925)
			(xy 383.249264 -426.383932) (xy 383.263439 -426.364356) (xy 383.282958 -426.350104) (xy 383.305921 -426.342564)
			(xy 383.318004 -426.342048) (xy 384.257804 -426.342048) (xy 384.269908 -426.342512) (xy 384.292927 -426.350006)
			(xy 384.312495 -426.364257) (xy 384.326691 -426.383866) (xy 384.334121 -426.406905) (xy 384.334512 -426.41901)
			(xy 384.334512 -427.960536) (xy 385.241292 -427.960536) (xy 385.241292 -425.419012) (xy 385.241723 -425.40693)
			(xy 385.249187 -425.383948) (xy 385.263389 -425.364397) (xy 385.282937 -425.350193) (xy 385.305918 -425.342725)
			(xy 385.318 -425.342304) (xy 386.2578 -425.342304) (xy 386.269884 -425.342713) (xy 386.292869 -425.350182)
			(xy 386.31242 -425.364388) (xy 386.326624 -425.383942) (xy 386.334089 -425.406928) (xy 386.334508 -425.419012)
			(xy 386.334508 -427.960536) (xy 386.334067 -427.972612) (xy 386.326594 -427.995581) (xy 386.312392 -428.015117)
			(xy 386.292849 -428.029311) (xy 386.269877 -428.036772) (xy 386.2578 -428.037244) (xy 385.318 -428.037244)
			(xy 385.305929 -428.036736) (xy 385.282968 -428.029278) (xy 385.263434 -428.015092) (xy 385.249238 -427.995564)
			(xy 385.241769 -427.972607) (xy 385.241292 -427.960536) (xy 384.334512 -427.960536) (xy 384.334512 -428.960534)
			(xy 384.334121 -428.97263) (xy 384.326649 -428.99564) (xy 384.312444 -429.015223) (xy 384.292892 -429.029471)
			(xy 384.269899 -429.036994) (xy 384.257804 -429.037496) (xy 383.318004 -429.037496) (xy 383.305895 -429.03708)
			(xy 383.282867 -429.029582) (xy 383.263293 -429.01532) (xy 383.249099 -428.995698) (xy 383.241679 -428.972644)
			(xy 383.241296 -428.960534) (xy 382.307523 -428.960534) (xy 382.312515 -428.964172) (xy 382.32671 -428.983792)
			(xy 382.334132 -429.006844) (xy 382.334516 -429.018954) (xy 382.334516 -431.560478) (xy 382.334073 -431.572571)
			(xy 382.326617 -431.595578) (xy 382.312426 -431.615162) (xy 382.292884 -431.629412) (xy 382.269899 -431.636937)
			(xy 382.257808 -431.63744) (xy 381.318008 -431.63744) (xy 381.305904 -431.636978) (xy 381.282883 -431.629485)
			(xy 381.263313 -431.615234) (xy 381.249117 -431.595625) (xy 381.241689 -431.572584) (xy 381.2413 -431.560478)
			(xy 363.389359 -431.560478) (xy 363.386701 -431.616689) (xy 363.370537 -431.787129) (xy 363.346334 -431.956615)
			(xy 363.314145 -432.124767) (xy 363.274043 -432.291209) (xy 363.226117 -432.455569) (xy 363.170474 -432.61748)
			(xy 363.107239 -432.776579) (xy 363.036553 -432.932511) (xy 362.958574 -433.084927) (xy 362.873477 -433.233486)
			(xy 362.781452 -433.377855) (xy 362.682704 -433.517713) (xy 362.577455 -433.652746) (xy 362.46594 -433.782652)
			(xy 362.348408 -433.907141) (xy 362.225123 -434.025934) (xy 362.096359 -434.138766) (xy 361.962404 -434.245385)
			(xy 361.82356 -434.345551) (xy 361.680135 -434.439042) (xy 361.53245 -434.525647) (xy 361.380836 -434.605174)
			(xy 361.225632 -434.677444) (xy 361.146598 -434.710332) (xy 361.138713 -434.713995) (xy 361.125816 -434.725637)
			(xy 361.117551 -434.740919) (xy 361.115864 -434.749448) (xy 361.100116 -434.849016) (xy 361.109514 -434.873654)
			(xy 361.119928 -434.88229) (xy 361.169374 -434.924299) (xy 361.263563 -435.013553) (xy 361.352051 -435.108462)
			(xy 361.395012 -435.160674) (xy 381.240792 -435.160674) (xy 381.240792 -432.61915) (xy 381.241268 -432.607037)
			(xy 381.248764 -432.584) (xy 381.263006 -432.564403) (xy 381.282604 -432.550162) (xy 381.305641 -432.542668)
			(xy 381.317754 -432.542188) (xy 382.257554 -432.542188) (xy 382.269661 -432.54275) (xy 382.292695 -432.550219)
			(xy 382.306831 -432.560476) (xy 383.241296 -432.560476) (xy 383.241296 -431.833274) (xy 383.241547 -431.824517)
			(xy 383.245527 -431.807459) (xy 383.24917 -431.799492) (xy 383.482596 -431.323242) (xy 383.487326 -431.312737)
			(xy 383.490806 -431.289971) (xy 383.487309 -431.267208) (xy 383.482596 -431.256694) (xy 383.24917 -430.780444)
			(xy 383.24552 -430.772478) (xy 383.241537 -430.75542) (xy 383.241296 -430.746662) (xy 383.241296 -430.018952)
			(xy 383.241723 -430.006875) (xy 383.249199 -429.983905) (xy 383.263405 -429.964368) (xy 383.282952 -429.950176)
			(xy 383.305926 -429.942715) (xy 383.318004 -429.942244) (xy 384.257804 -429.942244) (xy 384.269874 -429.94276)
			(xy 384.292833 -429.950218) (xy 384.312366 -429.964403) (xy 384.326562 -429.983927) (xy 384.334033 -430.006882)
			(xy 384.334512 -430.018952) (xy 384.334512 -431.560478) (xy 385.241292 -431.560478) (xy 385.241292 -430.833276)
			(xy 385.241544 -430.824519) (xy 385.245523 -430.807462) (xy 385.249166 -430.799494) (xy 385.482592 -430.323244)
			(xy 385.48732 -430.312738) (xy 385.490801 -430.289973) (xy 385.487304 -430.26721) (xy 385.482592 -430.256696)
			(xy 385.249166 -429.780446) (xy 385.245516 -429.77248) (xy 385.241533 -429.755422) (xy 385.241292 -429.746664)
			(xy 385.241292 -429.018954) (xy 385.241767 -429.006867) (xy 385.249231 -428.983873) (xy 385.263417 -428.964298)
			(xy 385.282945 -428.950047) (xy 385.305914 -428.942508) (xy 385.318 -428.941992) (xy 386.2578 -428.941992)
			(xy 386.269908 -428.942416) (xy 386.292934 -428.949914) (xy 386.307511 -428.960534) (xy 387.241288 -428.960534)
			(xy 387.241288 -426.41901) (xy 387.241717 -426.406916) (xy 387.249177 -426.383908) (xy 387.263371 -426.364324)
			(xy 387.282916 -426.350075) (xy 387.305904 -426.342551) (xy 387.317996 -426.342048) (xy 388.257796 -426.342048)
			(xy 388.269899 -426.342519) (xy 388.292918 -426.350011) (xy 388.312487 -426.36426) (xy 388.326683 -426.383867)
			(xy 388.334113 -426.406905) (xy 388.334504 -426.41901) (xy 388.334504 -427.960536) (xy 389.241284 -427.960536)
			(xy 389.241284 -425.419012) (xy 389.241723 -425.406931) (xy 389.249186 -425.38395) (xy 389.263386 -425.3644)
			(xy 389.282932 -425.350195) (xy 389.305911 -425.342726) (xy 389.317992 -425.342304) (xy 390.257792 -425.342304)
			(xy 390.269876 -425.342719) (xy 390.29286 -425.350186) (xy 390.312412 -425.364391) (xy 390.326616 -425.383943)
			(xy 390.334081 -425.406928) (xy 390.3345 -425.419012) (xy 390.3345 -427.960536) (xy 390.334067 -427.972613)
			(xy 390.326593 -427.995583) (xy 390.312389 -428.01512) (xy 390.292844 -428.029313) (xy 390.26987 -428.036773)
			(xy 390.257792 -428.037244) (xy 389.317992 -428.037244) (xy 389.305921 -428.036743) (xy 389.282959 -428.029283)
			(xy 389.263426 -428.015094) (xy 389.24923 -427.995566) (xy 389.241761 -427.972607) (xy 389.241284 -427.960536)
			(xy 388.334504 -427.960536) (xy 388.334504 -428.960534) (xy 388.334023 -428.972621) (xy 388.326562 -428.995615)
			(xy 388.312377 -429.015191) (xy 388.29285 -429.029442) (xy 388.269881 -429.036981) (xy 388.257796 -429.037496)
			(xy 387.317996 -429.037496) (xy 387.305887 -429.037087) (xy 387.282858 -429.029586) (xy 387.263285 -429.015323)
			(xy 387.249091 -428.995699) (xy 387.241671 -428.972645) (xy 387.241288 -428.960534) (xy 386.307511 -428.960534)
			(xy 386.312507 -428.964174) (xy 386.326701 -428.983794) (xy 386.334124 -429.006845) (xy 386.334508 -429.018954)
			(xy 386.334508 -431.560478) (xy 386.333975 -431.572562) (xy 386.32653 -431.595553) (xy 386.312359 -431.61513)
			(xy 386.292842 -431.629383) (xy 386.269882 -431.636924) (xy 386.2578 -431.63744) (xy 385.318 -431.63744)
			(xy 385.305895 -431.636984) (xy 385.282875 -431.62949) (xy 385.263305 -431.615237) (xy 385.249109 -431.595626)
			(xy 385.241681 -431.572584) (xy 385.241292 -431.560478) (xy 384.334512 -431.560478) (xy 384.334512 -432.560476)
			(xy 384.334067 -432.572557) (xy 384.326606 -432.595538) (xy 384.312409 -432.615089) (xy 384.292863 -432.629294)
			(xy 384.269885 -432.636762) (xy 384.257804 -432.637184) (xy 383.318004 -432.637184) (xy 383.305919 -432.636784)
			(xy 383.282932 -432.629314) (xy 383.26338 -432.615106) (xy 383.249176 -432.59555) (xy 383.241713 -432.572561)
			(xy 383.241296 -432.560476) (xy 382.306831 -432.560476) (xy 382.312293 -432.564439) (xy 382.326538 -432.584019)
			(xy 382.334035 -432.607043) (xy 382.334516 -432.61915) (xy 382.334516 -435.160674) (xy 382.334117 -435.1728)
			(xy 382.326627 -435.195866) (xy 382.312371 -435.215485) (xy 382.292748 -435.229736) (xy 382.26968 -435.23722)
			(xy 382.257554 -435.237636) (xy 381.317754 -435.237636) (xy 381.305634 -435.237227) (xy 381.282585 -435.229724)
			(xy 381.262982 -435.215467) (xy 381.248743 -435.19585) (xy 381.241262 -435.172794) (xy 381.240792 -435.160674)
			(xy 361.395012 -435.160674) (xy 361.434498 -435.208663) (xy 361.510589 -435.313772) (xy 361.580032 -435.423387)
			(xy 361.642562 -435.537087) (xy 361.697938 -435.654438) (xy 361.74595 -435.77499) (xy 361.786412 -435.89828)
			(xy 361.81917 -436.023838) (xy 361.844098 -436.151181) (xy 361.861101 -436.279823) (xy 361.870114 -436.40927)
			(xy 361.871103 -436.539027) (xy 361.864062 -436.668596) (xy 361.849021 -436.797482) (xy 361.826035 -436.92519)
			(xy 361.795194 -437.051232) (xy 361.756614 -437.175125) (xy 361.710445 -437.296394) (xy 361.656862 -437.414574)
			(xy 361.596072 -437.529214) (xy 361.528306 -437.639874) (xy 361.453825 -437.74613) (xy 361.372914 -437.847575)
			(xy 361.285882 -437.943821) (xy 361.193064 -438.034499) (xy 361.094814 -438.119261) (xy 360.991508 -438.197784)
			(xy 360.883543 -438.269766) (xy 360.771333 -438.334931) (xy 360.655306 -438.39303) (xy 360.535907 -438.443841)
			(xy 360.413594 -438.487169) (xy 360.288835 -438.522847) (xy 360.162108 -438.550739) (xy 360.033898 -438.570739)
			(xy 359.904696 -438.58277) (xy 359.774998 -438.586785) (xy 359.6453 -438.58277) (xy 359.516098 -438.570739)
			(xy 359.387888 -438.550739) (xy 359.261161 -438.522847) (xy 359.136402 -438.487169) (xy 359.014089 -438.443841)
			(xy 358.89469 -438.39303) (xy 358.778663 -438.334931) (xy 358.666453 -438.269766) (xy 358.558488 -438.197784)
			(xy 358.455182 -438.119261) (xy 358.356932 -438.034499) (xy 358.264114 -437.943821) (xy 358.177082 -437.847575)
			(xy 358.096171 -437.74613) (xy 358.02169 -437.639874) (xy 357.953924 -437.529214) (xy 357.893134 -437.414574)
			(xy 357.839551 -437.296394) (xy 357.793382 -437.175125) (xy 357.754802 -437.051232) (xy 357.723961 -436.92519)
			(xy 357.700975 -436.797482) (xy 357.685934 -436.668596) (xy 357.678893 -436.539027) (xy 357.679882 -436.40927)
			(xy 357.688895 -436.279823) (xy 357.705898 -436.151181) (xy 357.730826 -436.023838) (xy 357.763584 -435.89828)
			(xy 357.804046 -435.77499) (xy 357.852058 -435.654438) (xy 357.907434 -435.537087) (xy 357.969964 -435.423387)
			(xy 358.039407 -435.313772) (xy 358.115498 -435.208663) (xy 358.197945 -435.108462) (xy 358.286433 -435.013553)
			(xy 358.380622 -434.924299) (xy 358.430068 -434.88229) (xy 358.440228 -434.873908) (xy 358.449626 -434.849016)
			(xy 358.4321 -434.73624) (xy 358.415844 -434.715412) (xy 358.403398 -434.710332) (xy 358.325295 -434.677853)
			(xy 358.1719 -434.606515) (xy 358.022004 -434.52809) (xy 357.875935 -434.44275) (xy 357.734012 -434.350681)
			(xy 357.596544 -434.252083) (xy 357.463831 -434.147172) (xy 357.336162 -434.036176) (xy 357.213818 -433.919339)
			(xy 357.097064 -433.796915) (xy 356.986156 -433.669172) (xy 356.881335 -433.536387) (xy 356.782831 -433.398852)
			(xy 356.690858 -433.256866) (xy 356.605617 -433.110739) (xy 356.527295 -432.96079) (xy 356.456061 -432.807346)
			(xy 356.392073 -432.650743) (xy 356.335468 -432.491322) (xy 356.286372 -432.329431) (xy 356.244891 -432.165424)
			(xy 356.211115 -431.999658) (xy 356.185119 -431.832496) (xy 356.166958 -431.664301) (xy 356.156674 -431.495443)
			(xy 356.15499 -431.410872) (xy 356.155244 -431.410872) (xy 356.154736 -431.360072) (xy 346.234512 -431.360072)
			(xy 346.234512 -432.560476) (xy 346.234067 -432.572557) (xy 346.226606 -432.595538) (xy 346.212409 -432.615089)
			(xy 346.192863 -432.629294) (xy 346.169885 -432.636762) (xy 346.157804 -432.637184) (xy 345.218004 -432.637184)
			(xy 345.205919 -432.636784) (xy 345.182932 -432.629314) (xy 345.16338 -432.615106) (xy 345.149176 -432.59555)
			(xy 345.141713 -432.572561) (xy 345.141296 -432.560476) (xy 344.206831 -432.560476) (xy 344.212293 -432.564439)
			(xy 344.226538 -432.584019) (xy 344.234035 -432.607043) (xy 344.234516 -432.61915) (xy 344.234516 -435.160674)
			(xy 344.234117 -435.1728) (xy 344.226627 -435.195866) (xy 344.212371 -435.215485) (xy 344.192748 -435.229736)
			(xy 344.16968 -435.23722) (xy 344.157554 -435.237636) (xy 343.217754 -435.237636) (xy 343.205634 -435.237227)
			(xy 343.182585 -435.229724) (xy 343.162982 -435.215467) (xy 343.148743 -435.19585) (xy 343.141262 -435.172794)
			(xy 343.140792 -435.160674) (xy 342.23452 -435.160674) (xy 342.23452 -436.160672) (xy 342.234017 -436.172719)
			(xy 342.226594 -436.19564) (xy 342.212464 -436.215155) (xy 342.193004 -436.22936) (xy 342.170111 -436.23687)
			(xy 342.158066 -436.23738) (xy 341.217758 -436.23738) (xy 341.205668 -436.236929) (xy 341.18267 -436.229463)
			(xy 341.163092 -436.215272) (xy 341.148842 -436.195737) (xy 341.141308 -436.17276) (xy 341.140796 -436.160672)
			(xy 340.207107 -436.160672) (xy 340.212393 -436.164513) (xy 340.226587 -436.18405) (xy 340.234051 -436.207017)
			(xy 340.234524 -436.219092) (xy 340.234524 -438.760616) (xy 340.23405 -438.77269) (xy 340.226585 -438.795655)
			(xy 340.21239 -438.81519) (xy 340.192855 -438.829385) (xy 340.16989 -438.83685) (xy 340.157816 -438.837324)
			(xy 339.218016 -438.837324) (xy 339.205944 -438.836822) (xy 339.18298 -438.829366) (xy 339.163444 -438.815179)
			(xy 339.149248 -438.795649) (xy 339.141783 -438.772688) (xy 339.141308 -438.760616) (xy 338.234528 -438.760616)
			(xy 338.234528 -439.760614) (xy 341.141304 -439.760614) (xy 341.141304 -437.21909) (xy 341.141798 -437.207004)
			(xy 341.149253 -437.184009) (xy 341.163434 -437.164432) (xy 341.18296 -437.150181) (xy 341.205927 -437.142643)
			(xy 341.218012 -437.142128) (xy 342.157812 -437.142128) (xy 342.169924 -437.142506) (xy 342.192957 -437.150012)
			(xy 342.212532 -437.164283) (xy 342.226725 -437.183914) (xy 342.234141 -437.206976) (xy 342.23452 -437.21909)
			(xy 342.23452 -438.760616) (xy 343.1413 -438.760616) (xy 343.1413 -436.219092) (xy 343.141758 -436.207016)
			(xy 343.149223 -436.184047) (xy 343.163421 -436.16451) (xy 343.182962 -436.150316) (xy 343.205932 -436.142855)
			(xy 343.218008 -436.142384) (xy 344.157808 -436.142384) (xy 344.169882 -436.142857) (xy 344.192848 -436.150321)
			(xy 344.207094 -436.160672) (xy 345.140788 -436.160672) (xy 345.140788 -433.619148) (xy 345.1413 -433.607101)
			(xy 345.148719 -433.584179) (xy 345.162846 -433.564664) (xy 345.182305 -433.550458) (xy 345.205197 -433.542949)
			(xy 345.217242 -433.54244) (xy 346.15755 -433.54244) (xy 346.169637 -433.54295) (xy 346.192636 -433.550393)
			(xy 346.212217 -433.564568) (xy 346.226469 -433.584093) (xy 346.234002 -433.607063) (xy 346.234512 -433.619148)
			(xy 346.234512 -436.160672) (xy 346.234016 -436.17272) (xy 346.226593 -436.195642) (xy 346.212461 -436.215157)
			(xy 346.192999 -436.229362) (xy 346.170104 -436.236871) (xy 346.158058 -436.23738) (xy 345.21775 -436.23738)
			(xy 345.205665 -436.23685) (xy 345.182669 -436.22941) (xy 345.16309 -436.215239) (xy 345.148837 -436.195719)
			(xy 345.141301 -436.172755) (xy 345.140788 -436.160672) (xy 344.207094 -436.160672) (xy 344.212384 -436.164516)
			(xy 344.226579 -436.184052) (xy 344.234043 -436.207018) (xy 344.234516 -436.219092) (xy 344.234516 -438.760616)
			(xy 344.234049 -438.772691) (xy 344.226583 -438.795657) (xy 344.212387 -438.815193) (xy 344.19285 -438.829387)
			(xy 344.169883 -438.836851) (xy 344.157808 -438.837324) (xy 343.218008 -438.837324) (xy 343.205935 -438.836829)
			(xy 343.182971 -438.829371) (xy 343.163435 -438.815182) (xy 343.14924 -438.79565) (xy 343.141775 -438.772688)
			(xy 343.1413 -438.760616) (xy 342.23452 -438.760616) (xy 342.23452 -439.760614) (xy 345.141296 -439.760614)
			(xy 345.141296 -437.21909) (xy 345.141798 -437.207004) (xy 345.149252 -437.184011) (xy 345.163431 -437.164435)
			(xy 345.182955 -437.150183) (xy 345.20592 -437.142644) (xy 345.218004 -437.142128) (xy 346.157804 -437.142128)
			(xy 346.169916 -437.142513) (xy 346.192948 -437.150017) (xy 346.212524 -437.164286) (xy 346.226717 -437.183916)
			(xy 346.234133 -437.206977) (xy 346.234512 -437.21909) (xy 346.234512 -438.760616) (xy 381.2413 -438.760616)
			(xy 381.2413 -436.219092) (xy 381.241758 -436.207016) (xy 381.249223 -436.184047) (xy 381.263421 -436.16451)
			(xy 381.282962 -436.150316) (xy 381.305932 -436.142855) (xy 381.318008 -436.142384) (xy 382.257808 -436.142384)
			(xy 382.269882 -436.142857) (xy 382.292848 -436.150321) (xy 382.307094 -436.160672) (xy 383.240788 -436.160672)
			(xy 383.240788 -433.619148) (xy 383.2413 -433.607101) (xy 383.248719 -433.584179) (xy 383.262846 -433.564664)
			(xy 383.282305 -433.550458) (xy 383.305197 -433.542949) (xy 383.317242 -433.54244) (xy 384.25755 -433.54244)
			(xy 384.269637 -433.54295) (xy 384.292636 -433.550393) (xy 384.312217 -433.564568) (xy 384.326469 -433.584093)
			(xy 384.334002 -433.607063) (xy 384.334512 -433.619148) (xy 384.334512 -435.160674) (xy 385.240784 -435.160674)
			(xy 385.240784 -432.61915) (xy 385.24117 -432.607028) (xy 385.248676 -432.583976) (xy 385.262939 -432.564371)
			(xy 385.282562 -432.550133) (xy 385.305624 -432.542655) (xy 385.317746 -432.542188) (xy 386.257546 -432.542188)
			(xy 386.269658 -432.542672) (xy 386.292694 -432.550166) (xy 386.306883 -432.560476) (xy 387.241288 -432.560476)
			(xy 387.241288 -431.833274) (xy 387.24154 -431.824517) (xy 387.245519 -431.80746) (xy 387.249162 -431.799492)
			(xy 387.482588 -431.323242) (xy 387.487318 -431.312736) (xy 387.490799 -431.289971) (xy 387.487301 -431.267208)
			(xy 387.482588 -431.256694) (xy 387.249162 -430.780444) (xy 387.245511 -430.772479) (xy 387.241529 -430.755421)
			(xy 387.241288 -430.746662) (xy 387.241288 -430.018952) (xy 387.241723 -430.006875) (xy 387.249198 -429.983907)
			(xy 387.263403 -429.964371) (xy 387.282947 -429.950178) (xy 387.305919 -429.942716) (xy 387.317996 -429.942244)
			(xy 388.257796 -429.942244) (xy 388.269866 -429.942767) (xy 388.292824 -429.950222) (xy 388.312357 -429.964406)
			(xy 388.326554 -429.983929) (xy 388.334025 -430.006883) (xy 388.334504 -430.018952) (xy 388.334504 -431.560478)
			(xy 389.241284 -431.560478) (xy 389.241284 -430.833276) (xy 389.241537 -430.824519) (xy 389.245516 -430.807462)
			(xy 389.249158 -430.799494) (xy 389.482584 -430.323244) (xy 389.487313 -430.312738) (xy 389.490794 -430.289973)
			(xy 389.487297 -430.26721) (xy 389.482584 -430.256696) (xy 389.249158 -429.780446) (xy 389.245508 -429.77248)
			(xy 389.241525 -429.755422) (xy 389.241284 -429.746664) (xy 389.241284 -429.018954) (xy 389.241669 -429.006858)
			(xy 389.249144 -428.983848) (xy 389.26335 -428.964265) (xy 389.282903 -428.950018) (xy 389.305897 -428.942495)
			(xy 389.317992 -428.941992) (xy 390.257792 -428.941992) (xy 390.2699 -428.942423) (xy 390.292925 -428.949919)
			(xy 390.307497 -428.960534) (xy 391.24128 -428.960534) (xy 391.24128 -426.41901) (xy 391.241717 -426.406917)
			(xy 391.249176 -426.38391) (xy 391.263369 -426.364326) (xy 391.282911 -426.350077) (xy 391.305896 -426.342552)
			(xy 391.317988 -426.342048) (xy 392.257788 -426.342048) (xy 392.269891 -426.342526) (xy 392.292909 -426.350016)
			(xy 392.312478 -426.364263) (xy 392.326675 -426.383869) (xy 392.334105 -426.406906) (xy 392.334496 -426.41901)
			(xy 392.334496 -427.960536) (xy 393.241276 -427.960536) (xy 393.241276 -425.419012) (xy 393.241774 -425.40694)
			(xy 393.249231 -425.383976) (xy 393.26342 -425.36444) (xy 393.28295 -425.350244) (xy 393.305912 -425.342779)
			(xy 393.317984 -425.342304) (xy 394.257784 -425.342304) (xy 394.269867 -425.342727) (xy 394.292851 -425.350191)
			(xy 394.312403 -425.364394) (xy 394.326607 -425.383945) (xy 394.334073 -425.406929) (xy 394.334492 -425.419012)
			(xy 394.334492 -427.960536) (xy 394.334066 -427.972614) (xy 394.326592 -427.995585) (xy 394.312386 -428.015123)
			(xy 394.292839 -428.029316) (xy 394.269862 -428.036775) (xy 394.257784 -428.037244) (xy 393.317984 -428.037244)
			(xy 393.305912 -428.03675) (xy 393.282951 -428.029287) (xy 393.263417 -428.015097) (xy 393.249222 -427.995567)
			(xy 393.241753 -427.972608) (xy 393.241276 -427.960536) (xy 392.334496 -427.960536) (xy 392.334496 -428.960534)
			(xy 392.334022 -428.972622) (xy 392.326561 -428.995617) (xy 392.312374 -429.015194) (xy 392.292845 -429.029444)
			(xy 392.269874 -429.036982) (xy 392.257788 -429.037496) (xy 391.317988 -429.037496) (xy 391.305878 -429.037094)
			(xy 391.28285 -429.029591) (xy 391.263276 -429.015326) (xy 391.249082 -428.995701) (xy 391.241663 -428.972645)
			(xy 391.24128 -428.960534) (xy 390.307497 -428.960534) (xy 390.312498 -428.964177) (xy 390.326693 -428.983795)
			(xy 390.334116 -429.006845) (xy 390.3345 -429.018954) (xy 390.3345 -431.560478) (xy 390.333975 -431.572562)
			(xy 390.326529 -431.595556) (xy 390.312356 -431.615132) (xy 390.292837 -431.629385) (xy 390.269874 -431.636925)
			(xy 390.257792 -431.63744) (xy 389.317992 -431.63744) (xy 389.305887 -431.636991) (xy 389.282866 -431.629494)
			(xy 389.263296 -431.61524) (xy 389.249101 -431.595628) (xy 389.241673 -431.572585) (xy 389.241284 -431.560478)
			(xy 388.334504 -431.560478) (xy 388.334504 -432.560476) (xy 388.334067 -432.572558) (xy 388.326605 -432.59554)
			(xy 388.312406 -432.615091) (xy 388.292858 -432.629296) (xy 388.269878 -432.636764) (xy 388.257796 -432.637184)
			(xy 387.317996 -432.637184) (xy 387.305911 -432.636791) (xy 387.282924 -432.629319) (xy 387.263371 -432.615109)
			(xy 387.249168 -432.595551) (xy 387.241705 -432.572562) (xy 387.241288 -432.560476) (xy 386.306883 -432.560476)
			(xy 386.312291 -432.564406) (xy 386.326533 -432.584002) (xy 386.334028 -432.607038) (xy 386.334508 -432.61915)
			(xy 386.334508 -435.160674) (xy 386.333967 -435.172783) (xy 386.326492 -435.195817) (xy 386.312267 -435.215415)
			(xy 386.292682 -435.229659) (xy 386.269654 -435.237155) (xy 386.257546 -435.237636) (xy 385.317746 -435.237636)
			(xy 385.305623 -435.237201) (xy 385.282561 -435.229718) (xy 385.262943 -435.215471) (xy 385.248691 -435.195857)
			(xy 385.241203 -435.172797) (xy 385.240784 -435.160674) (xy 384.334512 -435.160674) (xy 384.334512 -436.160672)
			(xy 384.334016 -436.17272) (xy 384.326593 -436.195642) (xy 384.312461 -436.215157) (xy 384.292999 -436.229362)
			(xy 384.270104 -436.236871) (xy 384.258058 -436.23738) (xy 383.31775 -436.23738) (xy 383.305665 -436.23685)
			(xy 383.282669 -436.22941) (xy 383.26309 -436.215239) (xy 383.248837 -436.195719) (xy 383.241301 -436.172755)
			(xy 383.240788 -436.160672) (xy 382.307094 -436.160672) (xy 382.312384 -436.164516) (xy 382.326579 -436.184052)
			(xy 382.334043 -436.207018) (xy 382.334516 -436.219092) (xy 382.334516 -438.760616) (xy 382.334049 -438.772691)
			(xy 382.326583 -438.795657) (xy 382.312387 -438.815193) (xy 382.29285 -438.829387) (xy 382.269883 -438.836851)
			(xy 382.257808 -438.837324) (xy 381.318008 -438.837324) (xy 381.305935 -438.836829) (xy 381.282971 -438.829371)
			(xy 381.263435 -438.815182) (xy 381.24924 -438.79565) (xy 381.241775 -438.772688) (xy 381.2413 -438.760616)
			(xy 346.234512 -438.760616) (xy 346.234512 -439.760614) (xy 383.241296 -439.760614) (xy 383.241296 -437.21909)
			(xy 383.241798 -437.207004) (xy 383.249252 -437.184011) (xy 383.263431 -437.164435) (xy 383.282955 -437.150183)
			(xy 383.30592 -437.142644) (xy 383.318004 -437.142128) (xy 384.257804 -437.142128) (xy 384.269916 -437.142513)
			(xy 384.292948 -437.150017) (xy 384.312524 -437.164286) (xy 384.326717 -437.183916) (xy 384.334133 -437.206977)
			(xy 384.334512 -437.21909) (xy 384.334512 -438.760616) (xy 385.241292 -438.760616) (xy 385.241292 -436.219092)
			(xy 385.241758 -436.207017) (xy 385.249222 -436.18405) (xy 385.263418 -436.164513) (xy 385.282957 -436.150319)
			(xy 385.305925 -436.142856) (xy 385.318 -436.142384) (xy 386.2578 -436.142384) (xy 386.269874 -436.142864)
			(xy 386.29284 -436.150326) (xy 386.307082 -436.160672) (xy 387.24078 -436.160672) (xy 387.24078 -433.619148)
			(xy 387.2413 -433.607102) (xy 387.248717 -433.584182) (xy 387.262843 -433.564667) (xy 387.2823 -433.550461)
			(xy 387.30519 -433.54295) (xy 387.317234 -433.54244) (xy 388.257542 -433.54244) (xy 388.269634 -433.542872)
			(xy 388.292636 -433.55034) (xy 388.312215 -433.564536) (xy 388.326464 -433.584076) (xy 388.333995 -433.607058)
			(xy 388.334504 -433.619148) (xy 388.334504 -435.160674) (xy 389.240776 -435.160674) (xy 389.240776 -432.61915)
			(xy 389.24117 -432.607029) (xy 389.248675 -432.583978) (xy 389.262936 -432.564374) (xy 389.282557 -432.550135)
			(xy 389.305617 -432.542656) (xy 389.317738 -432.542188) (xy 390.257538 -432.542188) (xy 390.26965 -432.542678)
			(xy 390.292686 -432.55017) (xy 390.306869 -432.560476) (xy 391.24128 -432.560476) (xy 391.24128 -431.833274)
			(xy 391.241533 -431.824517) (xy 391.245511 -431.80746) (xy 391.249154 -431.799492) (xy 391.48258 -431.323242)
			(xy 391.48731 -431.312737) (xy 391.490791 -431.289971) (xy 391.487293 -431.267208) (xy 391.48258 -431.256694)
			(xy 391.249154 -430.780444) (xy 391.245503 -430.772479) (xy 391.24152 -430.755421) (xy 391.24128 -430.746662)
			(xy 391.24128 -430.018952) (xy 391.241723 -430.006876) (xy 391.249197 -429.983909) (xy 391.2634 -429.964374)
			(xy 391.282942 -429.950181) (xy 391.305912 -429.942717) (xy 391.317988 -429.942244) (xy 392.257788 -429.942244)
			(xy 392.269857 -429.942774) (xy 392.292816 -429.950227) (xy 392.312349 -429.964408) (xy 392.326546 -429.98393)
			(xy 392.334017 -430.006883) (xy 392.334496 -430.018952) (xy 392.334496 -431.560478) (xy 393.241276 -431.560478)
			(xy 393.241276 -430.833276) (xy 393.24153 -430.824519) (xy 393.245508 -430.807462) (xy 393.24915 -430.799494)
			(xy 393.482576 -430.323244) (xy 393.487305 -430.312738) (xy 393.490787 -430.289973) (xy 393.487289 -430.26721)
			(xy 393.482576 -430.256696) (xy 393.24915 -429.780446) (xy 393.245499 -429.772481) (xy 393.241517 -429.755423)
			(xy 393.241276 -429.746664) (xy 393.241276 -429.018954) (xy 393.241669 -429.006858) (xy 393.249143 -428.98385)
			(xy 393.263347 -428.964268) (xy 393.282898 -428.95002) (xy 393.30589 -428.942496) (xy 393.317984 -428.941992)
			(xy 394.257784 -428.941992) (xy 394.269891 -428.94243) (xy 394.292917 -428.949924) (xy 394.307483 -428.960534)
			(xy 395.241272 -428.960534) (xy 395.241272 -426.41901) (xy 395.241717 -426.406918) (xy 395.249174 -426.383912)
			(xy 395.263366 -426.364329) (xy 395.282906 -426.35008) (xy 395.305889 -426.342553) (xy 395.31798 -426.342048)
			(xy 396.25778 -426.342048) (xy 396.269883 -426.342533) (xy 396.2929 -426.35002) (xy 396.312469 -426.364266)
			(xy 396.326666 -426.38387) (xy 396.334097 -426.406906) (xy 396.334488 -426.41901) (xy 396.334488 -427.960536)
			(xy 398.241012 -427.960536) (xy 398.241012 -425.419012) (xy 398.24147 -425.406961) (xy 398.248901 -425.384034)
			(xy 398.263042 -425.364517) (xy 398.282514 -425.350314) (xy 398.305417 -425.342809) (xy 398.317466 -425.342304)
			(xy 399.257774 -425.342304) (xy 399.269859 -425.342829) (xy 399.292852 -425.350274) (xy 399.31243 -425.364447)
			(xy 399.326682 -425.383966) (xy 399.334221 -425.406929) (xy 399.334736 -425.419012) (xy 399.334736 -427.960536)
			(xy 399.334272 -427.972585) (xy 399.326833 -427.995505) (xy 399.312692 -428.015017) (xy 399.293226 -428.029221)
			(xy 399.270329 -428.036732) (xy 399.258282 -428.037244) (xy 398.317974 -428.037244) (xy 398.305881 -428.036815)
			(xy 398.282877 -428.029349) (xy 398.263296 -428.015153) (xy 398.249047 -427.995611) (xy 398.241519 -427.972627)
			(xy 398.241012 -427.960536) (xy 396.334488 -427.960536) (xy 396.334488 -428.960534) (xy 396.334022 -428.972623)
			(xy 396.32656 -428.99562) (xy 396.312372 -429.015197) (xy 396.29284 -429.029447) (xy 396.269867 -429.036983)
			(xy 396.25778 -429.037496) (xy 395.31798 -429.037496) (xy 395.30587 -429.037101) (xy 395.282841 -429.029595)
			(xy 395.263268 -429.015328) (xy 395.249074 -428.995702) (xy 395.241655 -428.972646) (xy 395.241272 -428.960534)
			(xy 394.307483 -428.960534) (xy 394.312489 -428.96418) (xy 394.326685 -428.983797) (xy 394.334107 -429.006846)
			(xy 394.334492 -429.018954) (xy 394.334492 -431.560478) (xy 394.333974 -431.572563) (xy 394.326528 -431.595558)
			(xy 394.312353 -431.615135) (xy 394.292832 -431.629388) (xy 394.269867 -431.636926) (xy 394.257784 -431.63744)
			(xy 393.317984 -431.63744) (xy 393.305878 -431.636998) (xy 393.282857 -431.629499) (xy 393.263288 -431.615243)
			(xy 393.249092 -431.595629) (xy 393.241665 -431.572585) (xy 393.241276 -431.560478) (xy 392.334496 -431.560478)
			(xy 392.334496 -432.560476) (xy 392.334067 -432.572559) (xy 392.326604 -432.595543) (xy 392.312403 -432.615094)
			(xy 392.292853 -432.629299) (xy 392.269871 -432.636765) (xy 392.257788 -432.637184) (xy 391.317988 -432.637184)
			(xy 391.305902 -432.636797) (xy 391.282915 -432.629324) (xy 391.263363 -432.615112) (xy 391.24916 -432.595553)
			(xy 391.241697 -432.572562) (xy 391.24128 -432.560476) (xy 390.306869 -432.560476) (xy 390.312282 -432.564409)
			(xy 390.326524 -432.584004) (xy 390.33402 -432.607039) (xy 390.3345 -432.61915) (xy 390.3345 -435.160674)
			(xy 390.333967 -435.172783) (xy 390.326491 -435.195819) (xy 390.312264 -435.215418) (xy 390.292677 -435.229662)
			(xy 390.269647 -435.237157) (xy 390.257538 -435.237636) (xy 389.317738 -435.237636) (xy 389.305615 -435.237207)
			(xy 389.282553 -435.229722) (xy 389.262935 -435.215474) (xy 389.248683 -435.195858) (xy 389.241195 -435.172797)
			(xy 389.240776 -435.160674) (xy 388.334504 -435.160674) (xy 388.334504 -436.160672) (xy 388.334016 -436.17272)
			(xy 388.326592 -436.195644) (xy 388.312458 -436.21516) (xy 388.292994 -436.229365) (xy 388.270097 -436.236872)
			(xy 388.25805 -436.23738) (xy 387.317742 -436.23738) (xy 387.305657 -436.236857) (xy 387.282661 -436.229415)
			(xy 387.263082 -436.215242) (xy 387.248829 -436.195721) (xy 387.241293 -436.172755) (xy 387.24078 -436.160672)
			(xy 386.307082 -436.160672) (xy 386.312376 -436.164518) (xy 386.326571 -436.184053) (xy 386.334035 -436.207018)
			(xy 386.334508 -436.219092) (xy 386.334508 -438.760616) (xy 386.334049 -438.772691) (xy 386.326582 -438.795659)
			(xy 386.312384 -438.815196) (xy 386.292845 -438.82939) (xy 386.269875 -438.836852) (xy 386.2578 -438.837324)
			(xy 385.318 -438.837324) (xy 385.305927 -438.836836) (xy 385.282963 -438.829375) (xy 385.263427 -438.815184)
			(xy 385.249232 -438.795652) (xy 385.241767 -438.772689) (xy 385.241292 -438.760616) (xy 384.334512 -438.760616)
			(xy 384.334512 -439.760614) (xy 387.241288 -439.760614) (xy 387.241288 -437.21909) (xy 387.2417 -437.206995)
			(xy 387.249165 -437.183986) (xy 387.263364 -437.164402) (xy 387.282912 -437.150154) (xy 387.305902 -437.142631)
			(xy 387.317996 -437.142128) (xy 388.257796 -437.142128) (xy 388.269907 -437.14252) (xy 388.292939 -437.150022)
			(xy 388.312515 -437.164288) (xy 388.326709 -437.183917) (xy 388.334125 -437.206977) (xy 388.334504 -437.21909)
			(xy 388.334504 -438.760616) (xy 389.241284 -438.760616) (xy 389.241284 -436.219092) (xy 389.241757 -436.207018)
			(xy 389.249221 -436.184052) (xy 389.263416 -436.164516) (xy 389.282952 -436.150321) (xy 389.305918 -436.142857)
			(xy 389.317992 -436.142384) (xy 390.257792 -436.142384) (xy 390.269865 -436.142871) (xy 390.292831 -436.15033)
			(xy 390.307068 -436.160672) (xy 391.240772 -436.160672) (xy 391.240772 -433.619148) (xy 391.2413 -433.607103)
			(xy 391.248716 -433.584184) (xy 391.26284 -433.56467) (xy 391.282295 -433.550464) (xy 391.305183 -433.542951)
			(xy 391.317226 -433.54244) (xy 392.257534 -433.54244) (xy 392.269625 -433.542878) (xy 392.292627 -433.550344)
			(xy 392.312206 -433.564538) (xy 392.326456 -433.584078) (xy 392.333987 -433.607058) (xy 392.334496 -433.619148)
			(xy 392.334496 -435.160674) (xy 393.240768 -435.160674) (xy 393.240768 -432.61915) (xy 393.24117 -432.60703)
			(xy 393.248674 -432.58398) (xy 393.262933 -432.564376) (xy 393.282552 -432.550138) (xy 393.305609 -432.542657)
			(xy 393.31773 -432.542188) (xy 394.25753 -432.542188) (xy 394.269641 -432.542685) (xy 394.292677 -432.550175)
			(xy 394.306856 -432.560476) (xy 395.241272 -432.560476) (xy 395.241272 -431.833274) (xy 395.241526 -431.824517)
			(xy 395.245504 -431.80746) (xy 395.249146 -431.799492) (xy 395.482572 -431.323242) (xy 395.487303 -431.312737)
			(xy 395.490784 -431.289971) (xy 395.487285 -431.267208) (xy 395.482572 -431.256694) (xy 395.249146 -430.780444)
			(xy 395.245494 -430.772479) (xy 395.241512 -430.755421) (xy 395.241272 -430.746662) (xy 395.241272 -430.018952)
			(xy 395.241723 -430.006877) (xy 395.249196 -429.983912) (xy 395.263397 -429.964377) (xy 395.282937 -429.950183)
			(xy 395.305905 -429.942718) (xy 395.31798 -429.942244) (xy 396.25778 -429.942244) (xy 396.269849 -429.94278)
			(xy 396.292807 -429.950232) (xy 396.31234 -429.964411) (xy 396.326537 -429.983932) (xy 396.334009 -430.006884)
			(xy 396.334488 -430.018952) (xy 396.334488 -431.560478) (xy 398.24152 -431.560478) (xy 398.24152 -430.833276)
			(xy 398.24177 -430.824519) (xy 398.24575 -430.807461) (xy 398.249394 -430.799494) (xy 398.48282 -430.323244)
			(xy 398.487547 -430.312738) (xy 398.491027 -430.289973) (xy 398.487531 -430.267211) (xy 398.48282 -430.256696)
			(xy 398.249394 -429.780446) (xy 398.245746 -429.77248) (xy 398.241761 -429.755422) (xy 398.24152 -429.746664)
			(xy 398.24152 -429.018954) (xy 398.241968 -429.006864) (xy 398.249435 -428.983865) (xy 398.263627 -428.964288)
			(xy 398.283163 -428.950038) (xy 398.306139 -428.942504) (xy 398.318228 -428.941992) (xy 399.258028 -428.941992)
			(xy 399.270138 -428.942392) (xy 399.293164 -428.949899) (xy 399.307755 -428.960534) (xy 400.241008 -428.960534)
			(xy 400.241008 -426.41901) (xy 400.24152 -426.406899) (xy 400.249001 -426.383861) (xy 400.263233 -426.364262)
			(xy 400.282825 -426.350019) (xy 400.305859 -426.342526) (xy 400.31797 -426.342048) (xy 401.25777 -426.342048)
			(xy 401.269892 -426.342486) (xy 401.292952 -426.349971) (xy 401.312568 -426.364218) (xy 401.32682 -426.38383)
			(xy 401.334311 -426.406888) (xy 401.334732 -426.41901) (xy 401.334732 -427.960536) (xy 402.241004 -427.960536)
			(xy 402.241004 -425.419012) (xy 402.24147 -425.406962) (xy 402.2489 -425.384036) (xy 402.263039 -425.36452)
			(xy 402.282509 -425.350316) (xy 402.30541 -425.342811) (xy 402.317458 -425.342304) (xy 403.257766 -425.342304)
			(xy 403.26985 -425.342836) (xy 403.292844 -425.350279) (xy 403.312421 -425.36445) (xy 403.326674 -425.383968)
			(xy 403.334213 -425.40693) (xy 403.334728 -425.419012) (xy 403.334728 -427.960536) (xy 403.334271 -427.972585)
			(xy 403.326832 -427.995507) (xy 403.31269 -428.01502) (xy 403.293221 -428.029223) (xy 403.270322 -428.036734)
			(xy 403.258274 -428.037244) (xy 402.317966 -428.037244) (xy 402.305873 -428.036821) (xy 402.282869 -428.029353)
			(xy 402.263288 -428.015156) (xy 402.249039 -427.995612) (xy 402.241511 -427.972628) (xy 402.241004 -427.960536)
			(xy 401.334732 -427.960536) (xy 401.334732 -428.960534) (xy 401.334317 -428.972653) (xy 401.326817 -428.995703)
			(xy 401.312561 -429.015307) (xy 401.292945 -429.029546) (xy 401.26989 -429.037027) (xy 401.25777 -429.037496)
			(xy 400.31797 -429.037496) (xy 400.305857 -429.037014) (xy 400.282819 -429.029523) (xy 400.26322 -429.015282)
			(xy 400.248979 -428.995685) (xy 400.241486 -428.972647) (xy 400.241008 -428.960534) (xy 399.307755 -428.960534)
			(xy 399.312736 -428.964165) (xy 399.32693 -428.983789) (xy 399.334352 -429.006843) (xy 399.334736 -429.018954)
			(xy 399.334736 -431.560478) (xy 399.334273 -431.572569) (xy 399.32682 -431.595573) (xy 399.312633 -431.615155)
			(xy 399.293097 -431.629405) (xy 399.270117 -431.636934) (xy 399.258028 -431.63744) (xy 398.318228 -431.63744)
			(xy 398.306125 -431.63696) (xy 398.283105 -431.629473) (xy 398.263535 -431.615227) (xy 398.249338 -431.595621)
			(xy 398.241909 -431.572582) (xy 398.24152 -431.560478) (xy 396.334488 -431.560478) (xy 396.334488 -432.560476)
			(xy 396.334066 -432.572559) (xy 396.326603 -432.595545) (xy 396.3124 -432.615097) (xy 396.292848 -432.629301)
			(xy 396.269863 -432.636766) (xy 396.25778 -432.637184) (xy 395.31798 -432.637184) (xy 395.305894 -432.636804)
			(xy 395.282906 -432.629328) (xy 395.263354 -432.615114) (xy 395.249152 -432.595554) (xy 395.241689 -432.572562)
			(xy 395.241272 -432.560476) (xy 394.306856 -432.560476) (xy 394.312274 -432.564412) (xy 394.326516 -432.584005)
			(xy 394.334012 -432.607039) (xy 394.334492 -432.61915) (xy 394.334492 -435.160674) (xy 394.333967 -435.172784)
			(xy 394.32649 -435.195822) (xy 394.312261 -435.215421) (xy 394.292672 -435.229665) (xy 394.26964 -435.237158)
			(xy 394.25753 -435.237636) (xy 393.31773 -435.237636) (xy 393.305606 -435.237214) (xy 393.282544 -435.229727)
			(xy 393.262926 -435.215477) (xy 393.248675 -435.19586) (xy 393.241186 -435.172798) (xy 393.240768 -435.160674)
			(xy 392.334496 -435.160674) (xy 392.334496 -436.160672) (xy 392.334016 -436.172721) (xy 392.326591 -436.195646)
			(xy 392.312455 -436.215163) (xy 392.292988 -436.229367) (xy 392.270089 -436.236873) (xy 392.258042 -436.23738)
			(xy 391.317734 -436.23738) (xy 391.305648 -436.236864) (xy 391.282652 -436.229419) (xy 391.263073 -436.215244)
			(xy 391.248821 -436.195722) (xy 391.241285 -436.172756) (xy 391.240772 -436.160672) (xy 390.307068 -436.160672)
			(xy 390.312367 -436.164521) (xy 390.326562 -436.184055) (xy 390.334027 -436.207019) (xy 390.3345 -436.219092)
			(xy 390.3345 -438.760616) (xy 390.334049 -438.772692) (xy 390.326581 -438.795661) (xy 390.312382 -438.815199)
			(xy 390.29284 -438.829392) (xy 390.269868 -438.836853) (xy 390.257792 -438.837324) (xy 389.317992 -438.837324)
			(xy 389.305919 -438.836843) (xy 389.282954 -438.82938) (xy 389.263418 -438.815187) (xy 389.249224 -438.795653)
			(xy 389.241759 -438.772689) (xy 389.241284 -438.760616) (xy 388.334504 -438.760616) (xy 388.334504 -439.760614)
			(xy 391.24128 -439.760614) (xy 391.24128 -437.21909) (xy 391.2417 -437.206996) (xy 391.249164 -437.183988)
			(xy 391.263361 -437.164405) (xy 391.282907 -437.150156) (xy 391.305895 -437.142632) (xy 391.317988 -437.142128)
			(xy 392.257788 -437.142128) (xy 392.269899 -437.142527) (xy 392.292931 -437.150027) (xy 392.312506 -437.164292)
			(xy 392.3267 -437.183919) (xy 392.334116 -437.206978) (xy 392.334496 -437.21909) (xy 392.334496 -438.760616)
			(xy 393.241276 -438.760616) (xy 393.241276 -436.219092) (xy 393.241757 -436.207019) (xy 393.24922 -436.184054)
			(xy 393.263413 -436.164518) (xy 393.282947 -436.150324) (xy 393.305911 -436.142859) (xy 393.317984 -436.142384)
			(xy 394.257784 -436.142384) (xy 394.269865 -436.142826) (xy 394.292846 -436.150288) (xy 394.307143 -436.160672)
			(xy 395.240764 -436.160672) (xy 395.240764 -433.619148) (xy 395.2413 -433.607104) (xy 395.248715 -433.584186)
			(xy 395.262838 -433.564672) (xy 395.28229 -433.550466) (xy 395.305176 -433.542952) (xy 395.317218 -433.54244)
			(xy 396.257526 -433.54244) (xy 396.269617 -433.542885) (xy 396.292618 -433.550349) (xy 396.312198 -433.564541)
			(xy 396.326448 -433.584079) (xy 396.333979 -433.607059) (xy 396.334488 -433.619148) (xy 396.334488 -435.160674)
			(xy 398.241012 -435.160674) (xy 398.241012 -432.61915) (xy 398.241469 -432.607035) (xy 398.248967 -432.583995)
			(xy 398.263213 -432.564396) (xy 398.282817 -432.550156) (xy 398.305859 -432.542665) (xy 398.317974 -432.542188)
			(xy 399.257774 -432.542188) (xy 399.269882 -432.542733) (xy 399.292916 -432.550207) (xy 399.307064 -432.560476)
			(xy 400.241516 -432.560476) (xy 400.241516 -431.833274) (xy 400.241765 -431.824517) (xy 400.245746 -431.807459)
			(xy 400.24939 -431.799492) (xy 400.482816 -431.323242) (xy 400.487545 -431.312736) (xy 400.491024 -431.289971)
			(xy 400.487528 -431.267209) (xy 400.482816 -431.256694) (xy 400.24939 -430.780444) (xy 400.245741 -430.772478)
			(xy 400.241757 -430.75542) (xy 400.241516 -430.746662) (xy 400.241516 -430.018952) (xy 400.241924 -430.006873)
			(xy 400.249402 -429.9839) (xy 400.263613 -429.964361) (xy 400.283164 -429.950169) (xy 400.306144 -429.942712)
			(xy 400.318224 -429.942244) (xy 401.258024 -429.942244) (xy 401.270095 -429.942743) (xy 401.293055 -429.950206)
			(xy 401.312587 -429.964396) (xy 401.326783 -429.983924) (xy 401.334253 -430.006881) (xy 401.334732 -430.018952)
			(xy 401.334732 -431.560478) (xy 402.241512 -431.560478) (xy 402.241512 -430.833276) (xy 402.241762 -430.824519)
			(xy 402.245742 -430.807461) (xy 402.249386 -430.799494) (xy 402.482812 -430.323244) (xy 402.48754 -430.312738)
			(xy 402.49102 -430.289973) (xy 402.487523 -430.267211) (xy 402.482812 -430.256696) (xy 402.249386 -429.780446)
			(xy 402.245737 -429.77248) (xy 402.241753 -429.755422) (xy 402.241512 -429.746664) (xy 402.241512 -429.018954)
			(xy 402.241968 -429.006865) (xy 402.249434 -428.983867) (xy 402.263624 -428.964291) (xy 402.283158 -428.950041)
			(xy 402.306132 -428.942505) (xy 402.31822 -428.941992) (xy 403.25802 -428.941992) (xy 403.270129 -428.942399)
			(xy 403.293156 -428.949903) (xy 403.307743 -428.960534) (xy 404.241 -428.960534) (xy 404.241 -426.41901)
			(xy 404.24152 -426.4069) (xy 404.249 -426.383863) (xy 404.263231 -426.364265) (xy 404.28282 -426.350022)
			(xy 404.305852 -426.342527) (xy 404.317962 -426.342048) (xy 405.257762 -426.342048) (xy 405.269884 -426.342492)
			(xy 405.292943 -426.349975) (xy 405.31256 -426.36422) (xy 405.326812 -426.383832) (xy 405.334303 -426.406888)
			(xy 405.334724 -426.41901) (xy 405.334724 -427.960536) (xy 406.240996 -427.960536) (xy 406.240996 -425.419012)
			(xy 406.24147 -425.406963) (xy 406.248899 -425.384038) (xy 406.263036 -425.364523) (xy 406.282504 -425.350319)
			(xy 406.305403 -425.342812) (xy 406.31745 -425.342304) (xy 407.257758 -425.342304) (xy 407.269842 -425.342842)
			(xy 407.292835 -425.350283) (xy 407.312413 -425.364453) (xy 407.326666 -425.383969) (xy 407.334205 -425.40693)
			(xy 407.33472 -425.419012) (xy 407.33472 -427.960536) (xy 407.334271 -427.972586) (xy 407.326831 -427.99551)
			(xy 407.312687 -428.015023) (xy 407.293216 -428.029226) (xy 407.270315 -428.036735) (xy 407.258266 -428.037244)
			(xy 406.317958 -428.037244) (xy 406.305865 -428.036828) (xy 406.28286 -428.029358) (xy 406.263279 -428.015159)
			(xy 406.249031 -427.995614) (xy 406.241503 -427.972628) (xy 406.240996 -427.960536) (xy 405.334724 -427.960536)
			(xy 405.334724 -428.960534) (xy 405.334369 -428.972662) (xy 405.326862 -428.995729) (xy 405.312595 -429.015347)
			(xy 405.292964 -429.029595) (xy 405.269891 -429.03708) (xy 405.257762 -429.037496) (xy 404.317962 -429.037496)
			(xy 404.305849 -429.037021) (xy 404.28281 -429.029528) (xy 404.263212 -429.015285) (xy 404.24897 -428.995686)
			(xy 404.241478 -428.972647) (xy 404.241 -428.960534) (xy 403.307743 -428.960534) (xy 403.312728 -428.964167)
			(xy 403.326922 -428.98379) (xy 403.334344 -429.006843) (xy 403.334728 -429.018954) (xy 403.334728 -431.560478)
			(xy 403.334273 -431.57257) (xy 403.326819 -431.595575) (xy 403.31263 -431.615158) (xy 403.293092 -431.629408)
			(xy 403.27011 -431.636935) (xy 403.25802 -431.63744) (xy 402.31822 -431.63744) (xy 402.306116 -431.636967)
			(xy 402.283096 -431.629478) (xy 402.263527 -431.61523) (xy 402.24933 -431.595622) (xy 402.241901 -431.572583)
			(xy 402.241512 -431.560478) (xy 401.334732 -431.560478) (xy 401.334732 -432.560476) (xy 401.334216 -432.572547)
			(xy 401.326763 -432.595509) (xy 401.312579 -432.615045) (xy 401.293052 -432.629241) (xy 401.270095 -432.636708)
			(xy 401.258024 -432.637184) (xy 400.318224 -432.637184) (xy 400.30614 -432.636766) (xy 400.283154 -432.629303)
			(xy 400.263601 -432.615099) (xy 400.249397 -432.595546) (xy 400.241934 -432.57256) (xy 400.241516 -432.560476)
			(xy 399.307064 -432.560476) (xy 399.312514 -432.564432) (xy 399.326758 -432.584016) (xy 399.334255 -432.607042)
			(xy 399.334736 -432.61915) (xy 399.334736 -435.160674) (xy 399.334318 -435.172798) (xy 399.326829 -435.19586)
			(xy 399.312578 -435.215478) (xy 399.29296 -435.229729) (xy 399.269898 -435.237218) (xy 399.257774 -435.237636)
			(xy 398.317974 -435.237636) (xy 398.305855 -435.23721) (xy 398.282807 -435.229713) (xy 398.263203 -435.21546)
			(xy 398.248964 -435.195846) (xy 398.241482 -435.172793) (xy 398.241012 -435.160674) (xy 396.334488 -435.160674)
			(xy 396.334488 -436.160672) (xy 396.334016 -436.172722) (xy 396.32659 -436.195649) (xy 396.312452 -436.215166)
			(xy 396.292983 -436.22937) (xy 396.270082 -436.236875) (xy 396.258034 -436.23738) (xy 395.317726 -436.23738)
			(xy 395.30564 -436.236871) (xy 395.282643 -436.229424) (xy 395.263065 -436.215247) (xy 395.248813 -436.195724)
			(xy 395.241276 -436.172756) (xy 395.240764 -436.160672) (xy 394.307143 -436.160672) (xy 394.312396 -436.164487)
			(xy 394.326601 -436.184033) (xy 394.33407 -436.207011) (xy 394.334492 -436.219092) (xy 394.334492 -438.760616)
			(xy 394.334049 -438.772693) (xy 394.32658 -438.795663) (xy 394.312379 -438.815201) (xy 394.292835 -438.829395)
			(xy 394.269861 -438.836854) (xy 394.257784 -438.837324) (xy 393.317984 -438.837324) (xy 393.30591 -438.83685)
			(xy 393.282945 -438.829385) (xy 393.26341 -438.81519) (xy 393.249215 -438.795655) (xy 393.24175 -438.77269)
			(xy 393.241276 -438.760616) (xy 392.334496 -438.760616) (xy 392.334496 -439.760614) (xy 395.241272 -439.760614)
			(xy 395.241272 -437.21909) (xy 395.2417 -437.206997) (xy 395.249163 -437.183991) (xy 395.263359 -437.164408)
			(xy 395.282902 -437.150159) (xy 395.305888 -437.142633) (xy 395.31798 -437.142128) (xy 396.25778 -437.142128)
			(xy 396.269891 -437.142534) (xy 396.292922 -437.150031) (xy 396.312498 -437.164294) (xy 396.326692 -437.18392)
			(xy 396.334108 -437.206978) (xy 396.334488 -437.21909) (xy 396.334488 -438.760616) (xy 398.241012 -438.760616)
			(xy 398.241012 -436.219092) (xy 398.241453 -436.20704) (xy 398.24889 -436.184112) (xy 398.263035 -436.164596)
			(xy 398.28251 -436.150393) (xy 398.305416 -436.142889) (xy 398.317466 -436.142384) (xy 399.257774 -436.142384)
			(xy 399.269867 -436.14283) (xy 399.292874 -436.150285) (xy 399.307208 -436.160672) (xy 400.241008 -436.160672)
			(xy 400.241008 -433.619148) (xy 400.241501 -433.607099) (xy 400.248921 -433.584174) (xy 400.263053 -433.564657)
			(xy 400.282518 -433.550452) (xy 400.305415 -433.542946) (xy 400.317462 -433.54244) (xy 401.25777 -433.54244)
			(xy 401.269858 -433.542933) (xy 401.292858 -433.550381) (xy 401.312438 -433.564561) (xy 401.32669 -433.58409)
			(xy 401.334222 -433.607062) (xy 401.334732 -433.619148) (xy 401.334732 -435.160674) (xy 402.241004 -435.160674)
			(xy 402.241004 -432.61915) (xy 402.241469 -432.607036) (xy 402.248965 -432.583997) (xy 402.263211 -432.564399)
			(xy 402.282811 -432.550158) (xy 402.305852 -432.542666) (xy 402.317966 -432.542188) (xy 403.257766 -432.542188)
			(xy 403.269874 -432.54274) (xy 403.292908 -432.550212) (xy 403.307051 -432.560476) (xy 404.241508 -432.560476)
			(xy 404.241508 -431.833274) (xy 404.241758 -431.824517) (xy 404.245738 -431.807459) (xy 404.249382 -431.799492)
			(xy 404.482808 -431.323242) (xy 404.487537 -431.312736) (xy 404.491017 -431.289971) (xy 404.48752 -431.267208)
			(xy 404.482808 -431.256694) (xy 404.249382 -430.780444) (xy 404.245732 -430.772478) (xy 404.241749 -430.75542)
			(xy 404.241508 -430.746662) (xy 404.241508 -430.018952) (xy 404.241923 -430.006873) (xy 404.249401 -429.983902)
			(xy 404.26361 -429.964364) (xy 404.283159 -429.950172) (xy 404.306137 -429.942713) (xy 404.318216 -429.942244)
			(xy 405.258016 -429.942244) (xy 405.270087 -429.94275) (xy 405.293046 -429.950211) (xy 405.312579 -429.964399)
			(xy 405.326774 -429.983925) (xy 405.334245 -430.006882) (xy 405.334724 -430.018952) (xy 405.334724 -431.560478)
			(xy 406.241504 -431.560478) (xy 406.241504 -430.833276) (xy 406.241755 -430.824519) (xy 406.245735 -430.807461)
			(xy 406.249378 -430.799494) (xy 406.482804 -430.323244) (xy 406.487532 -430.312738) (xy 406.491013 -430.289973)
			(xy 406.487516 -430.26721) (xy 406.482804 -430.256696) (xy 406.249378 -429.780446) (xy 406.245729 -429.77248)
			(xy 406.241745 -429.755422) (xy 406.241504 -429.746664) (xy 406.241504 -429.018954) (xy 406.241967 -429.006866)
			(xy 406.249432 -428.98387) (xy 406.263621 -428.964293) (xy 406.283153 -428.950043) (xy 406.306125 -428.942506)
			(xy 406.318212 -428.941992) (xy 407.258012 -428.941992) (xy 407.270121 -428.942406) (xy 407.293147 -428.949908)
			(xy 407.307729 -428.960534) (xy 408.240992 -428.960534) (xy 408.240992 -426.41901) (xy 408.24152 -426.406901)
			(xy 408.248999 -426.383865) (xy 408.263228 -426.364268) (xy 408.282815 -426.350024) (xy 408.305845 -426.342528)
			(xy 408.317954 -426.342048) (xy 409.257754 -426.342048) (xy 409.269875 -426.342499) (xy 409.292934 -426.34998)
			(xy 409.312551 -426.364223) (xy 409.326804 -426.383833) (xy 409.334295 -426.406889) (xy 409.334716 -426.41901)
			(xy 409.334716 -427.960536) (xy 410.240988 -427.960536) (xy 410.240988 -425.419012) (xy 410.24147 -425.406964)
			(xy 410.248898 -425.38404) (xy 410.263033 -425.364526) (xy 410.282498 -425.350321) (xy 410.305395 -425.342813)
			(xy 410.317442 -425.342304) (xy 411.25775 -425.342304) (xy 411.269833 -425.342849) (xy 411.292826 -425.350288)
			(xy 411.312404 -425.364455) (xy 411.326658 -425.383971) (xy 411.334197 -425.406931) (xy 411.334712 -425.419012)
			(xy 411.334712 -427.960536) (xy 411.334271 -427.972587) (xy 411.32683 -427.995512) (xy 411.312684 -428.015026)
			(xy 411.293211 -428.029228) (xy 411.270307 -428.036736) (xy 411.258258 -428.037244) (xy 410.31795 -428.037244)
			(xy 410.305861 -428.03675) (xy 410.28286 -428.029305) (xy 410.263278 -428.015126) (xy 410.249026 -427.995597)
			(xy 410.241495 -427.972623) (xy 410.240988 -427.960536) (xy 409.334716 -427.960536) (xy 409.334716 -428.960534)
			(xy 409.334368 -428.972663) (xy 409.326861 -428.995731) (xy 409.312592 -429.015349) (xy 409.292959 -429.029598)
			(xy 409.269884 -429.037081) (xy 409.257754 -429.037496) (xy 408.317954 -429.037496) (xy 408.30584 -429.037028)
			(xy 408.282801 -429.029532) (xy 408.263203 -429.015288) (xy 408.248962 -428.995688) (xy 408.24147 -428.972648)
			(xy 408.240992 -428.960534) (xy 407.307729 -428.960534) (xy 407.312719 -428.96417) (xy 407.326914 -428.983792)
			(xy 407.334336 -429.006844) (xy 407.33472 -429.018954) (xy 407.33472 -431.560478) (xy 407.334273 -431.57257)
			(xy 407.326818 -431.595577) (xy 407.312627 -431.615161) (xy 407.293087 -431.629411) (xy 407.270103 -431.636936)
			(xy 407.258012 -431.63744) (xy 406.318212 -431.63744) (xy 406.306108 -431.636974) (xy 406.283088 -431.629483)
			(xy 406.263518 -431.615232) (xy 406.249322 -431.595624) (xy 406.241893 -431.572583) (xy 406.241504 -431.560478)
			(xy 405.334724 -431.560478) (xy 405.334724 -432.560476) (xy 405.334267 -432.572556) (xy 405.326808 -432.595535)
			(xy 405.312613 -432.615084) (xy 405.293071 -432.62929) (xy 405.270096 -432.636761) (xy 405.258016 -432.637184)
			(xy 404.318216 -432.637184) (xy 404.306132 -432.636773) (xy 404.283146 -432.629307) (xy 404.263593 -432.615101)
			(xy 404.249389 -432.595547) (xy 404.241926 -432.57256) (xy 404.241508 -432.560476) (xy 403.307051 -432.560476)
			(xy 403.312506 -432.564435) (xy 403.32675 -432.584017) (xy 403.334247 -432.607043) (xy 403.334728 -432.61915)
			(xy 403.334728 -435.160674) (xy 403.334317 -435.172799) (xy 403.326828 -435.195863) (xy 403.312575 -435.215481)
			(xy 403.292955 -435.229732) (xy 403.269891 -435.237219) (xy 403.257766 -435.237636) (xy 402.317966 -435.237636)
			(xy 402.305847 -435.237217) (xy 402.282798 -435.229717) (xy 402.263195 -435.215462) (xy 402.248955 -435.195848)
			(xy 402.241474 -435.172793) (xy 402.241004 -435.160674) (xy 401.334732 -435.160674) (xy 401.334732 -436.160672)
			(xy 401.334217 -436.172718) (xy 401.326796 -436.195637) (xy 401.312668 -436.21515) (xy 401.293211 -436.229356)
			(xy 401.270322 -436.236868) (xy 401.258278 -436.23738) (xy 400.31797 -436.23738) (xy 400.305881 -436.236919)
			(xy 400.282883 -436.229456) (xy 400.263305 -436.215267) (xy 400.249055 -436.195734) (xy 400.24152 -436.17276)
			(xy 400.241008 -436.160672) (xy 399.307208 -436.160672) (xy 399.312458 -436.164476) (xy 399.326708 -436.184017)
			(xy 399.334233 -436.207001) (xy 399.334736 -436.219092) (xy 399.334736 -438.760616) (xy 399.334254 -438.772663)
			(xy 399.326821 -438.795583) (xy 399.312685 -438.815096) (xy 399.293222 -438.8293) (xy 399.270328 -438.836812)
			(xy 399.258282 -438.837324) (xy 398.317974 -438.837324) (xy 398.305879 -438.836914) (xy 398.282872 -438.829446)
			(xy 398.263289 -438.815246) (xy 398.249041 -438.795698) (xy 398.241516 -438.772709) (xy 398.241012 -438.760616)
			(xy 396.334488 -438.760616) (xy 396.334488 -439.760614) (xy 400.241008 -439.760614) (xy 400.241008 -437.21909)
			(xy 400.241503 -437.206978) (xy 400.248989 -437.18394) (xy 400.263226 -437.164341) (xy 400.282822 -437.150098)
			(xy 400.305858 -437.142606) (xy 400.31797 -437.142128) (xy 401.25777 -437.142128) (xy 401.26989 -437.142585)
			(xy 401.292946 -437.150068) (xy 401.312561 -437.16431) (xy 401.326814 -437.183918) (xy 401.334308 -437.20697)
			(xy 401.334732 -437.21909) (xy 401.334732 -438.760616) (xy 402.241004 -438.760616) (xy 402.241004 -436.219092)
			(xy 402.241453 -436.207041) (xy 402.248889 -436.184115) (xy 402.263032 -436.164599) (xy 402.282505 -436.150396)
			(xy 402.305409 -436.14289) (xy 402.317458 -436.142384) (xy 403.257766 -436.142384) (xy 403.269858 -436.142837)
			(xy 403.292865 -436.15029) (xy 403.307195 -436.160672) (xy 404.241 -436.160672) (xy 404.241 -433.619148)
			(xy 404.241501 -433.6071) (xy 404.24892 -433.584176) (xy 404.26305 -433.56466) (xy 404.282513 -433.550455)
			(xy 404.305408 -433.542947) (xy 404.317454 -433.54244) (xy 405.257762 -433.54244) (xy 405.26985 -433.54294)
			(xy 405.292849 -433.550386) (xy 405.31243 -433.564564) (xy 405.326681 -433.584091) (xy 405.334214 -433.607062)
			(xy 405.334724 -433.619148) (xy 405.334724 -435.160674) (xy 406.240996 -435.160674) (xy 406.240996 -432.61915)
			(xy 406.241468 -432.607037) (xy 406.248964 -432.583999) (xy 406.263208 -432.564402) (xy 406.282806 -432.550161)
			(xy 406.305845 -432.542667) (xy 406.317958 -432.542188) (xy 407.257758 -432.542188) (xy 407.269865 -432.542747)
			(xy 407.292899 -432.550216) (xy 407.307037 -432.560476) (xy 408.2415 -432.560476) (xy 408.2415 -431.833274)
			(xy 408.241751 -431.824517) (xy 408.245731 -431.807459) (xy 408.249374 -431.799492) (xy 408.4828 -431.323242)
			(xy 408.48753 -431.312736) (xy 408.49101 -431.289971) (xy 408.487512 -431.267208) (xy 408.4828 -431.256694)
			(xy 408.249374 -430.780444) (xy 408.245724 -430.772478) (xy 408.241741 -430.75542) (xy 408.2415 -430.746662)
			(xy 408.2415 -430.018952) (xy 408.241923 -430.006874) (xy 408.2494 -429.983904) (xy 408.263607 -429.964367)
			(xy 408.283154 -429.950174) (xy 408.30613 -429.942714) (xy 408.318208 -429.942244) (xy 409.258008 -429.942244)
			(xy 409.270078 -429.942757) (xy 409.293037 -429.950216) (xy 409.31257 -429.964401) (xy 409.326766 -429.983927)
			(xy 409.334237 -430.006882) (xy 409.334716 -430.018952) (xy 409.334716 -431.560478) (xy 410.241496 -431.560478)
			(xy 410.241496 -430.833276) (xy 410.241748 -430.824519) (xy 410.245727 -430.807461) (xy 410.24937 -430.799494)
			(xy 410.482796 -430.323244) (xy 410.487525 -430.312738) (xy 410.491005 -430.289973) (xy 410.487508 -430.26721)
			(xy 410.482796 -430.256696) (xy 410.24937 -429.780446) (xy 410.24572 -429.77248) (xy 410.241737 -429.755422)
			(xy 410.241496 -429.746664) (xy 410.241496 -429.018954) (xy 410.241967 -429.006866) (xy 410.249431 -428.983872)
			(xy 410.263618 -428.964296) (xy 410.283148 -428.950046) (xy 410.306118 -428.942507) (xy 410.318204 -428.941992)
			(xy 411.258004 -428.941992) (xy 411.270112 -428.942413) (xy 411.293138 -428.949912) (xy 411.307717 -428.960534)
			(xy 412.240984 -428.960534) (xy 412.240984 -426.41901) (xy 412.241369 -426.406883) (xy 412.248864 -426.383817)
			(xy 412.263123 -426.364198) (xy 412.282749 -426.349948) (xy 412.305819 -426.342464) (xy 412.317946 -426.342048)
			(xy 413.257746 -426.342048) (xy 413.269864 -426.342473) (xy 413.29291 -426.349974) (xy 413.312512 -426.364228)
			(xy 413.326752 -426.38384) (xy 413.334236 -426.406892) (xy 413.334708 -426.41901) (xy 413.334708 -428.960534)
			(xy 413.334218 -428.972646) (xy 413.326727 -428.995682) (xy 413.312488 -429.01528) (xy 413.292893 -429.029522)
			(xy 413.269858 -429.037016) (xy 413.257746 -429.037496) (xy 412.317946 -429.037496) (xy 412.305829 -429.037002)
			(xy 412.282777 -429.029526) (xy 412.263164 -429.015292) (xy 412.248911 -428.995694) (xy 412.241411 -428.972651)
			(xy 412.240984 -428.960534) (xy 411.307717 -428.960534) (xy 411.312711 -428.964173) (xy 411.326906 -428.983793)
			(xy 411.334328 -429.006844) (xy 411.334712 -429.018954) (xy 411.334712 -431.560478) (xy 411.334273 -431.572571)
			(xy 411.326816 -431.595579) (xy 411.312624 -431.615164) (xy 411.293082 -431.629413) (xy 411.270096 -431.636937)
			(xy 411.258004 -431.63744) (xy 410.318204 -431.63744) (xy 410.306099 -431.636981) (xy 410.283079 -431.629488)
			(xy 410.263509 -431.615236) (xy 410.249313 -431.595625) (xy 410.241885 -431.572584) (xy 410.241496 -431.560478)
			(xy 409.334716 -431.560478) (xy 409.334716 -432.560476) (xy 409.334267 -432.572557) (xy 409.326807 -432.595537)
			(xy 409.31261 -432.615087) (xy 409.293066 -432.629292) (xy 409.270088 -432.636762) (xy 409.258008 -432.637184)
			(xy 408.318208 -432.637184) (xy 408.306123 -432.63678) (xy 408.283137 -432.629312) (xy 408.263584 -432.615105)
			(xy 408.249381 -432.595549) (xy 408.241917 -432.572561) (xy 408.2415 -432.560476) (xy 407.307037 -432.560476)
			(xy 407.312497 -432.564438) (xy 407.326742 -432.584019) (xy 407.334239 -432.607043) (xy 407.33472 -432.61915)
			(xy 407.33472 -435.160674) (xy 407.334317 -435.1728) (xy 407.326827 -435.195865) (xy 407.312572 -435.215484)
			(xy 407.29295 -435.229734) (xy 407.269884 -435.23722) (xy 407.257758 -435.237636) (xy 406.317958 -435.237636)
			(xy 406.305839 -435.237224) (xy 406.28279 -435.229722) (xy 406.263186 -435.215465) (xy 406.248947 -435.195849)
			(xy 406.241466 -435.172794) (xy 406.240996 -435.160674) (xy 405.334724 -435.160674) (xy 405.334724 -436.160672)
			(xy 405.334217 -436.172718) (xy 405.326795 -436.195639) (xy 405.312665 -436.215153) (xy 405.293206 -436.229358)
			(xy 405.270314 -436.236869) (xy 405.25827 -436.23738) (xy 404.317962 -436.23738) (xy 404.305872 -436.236925)
			(xy 404.282874 -436.229461) (xy 404.263296 -436.21527) (xy 404.249046 -436.195736) (xy 404.241512 -436.17276)
			(xy 404.241 -436.160672) (xy 403.307195 -436.160672) (xy 403.312449 -436.164478) (xy 403.3267 -436.184018)
			(xy 403.334225 -436.207001) (xy 403.334728 -436.219092) (xy 403.334728 -438.760616) (xy 403.334254 -438.772664)
			(xy 403.32682 -438.795586) (xy 403.312682 -438.815099) (xy 403.293217 -438.829302) (xy 403.270321 -438.836813)
			(xy 403.258274 -438.837324) (xy 402.317966 -438.837324) (xy 402.305871 -438.836921) (xy 402.282863 -438.829451)
			(xy 402.263281 -438.815249) (xy 402.249033 -438.7957) (xy 402.241508 -438.77271) (xy 402.241004 -438.760616)
			(xy 401.334732 -438.760616) (xy 401.334732 -439.760614) (xy 404.241 -439.760614) (xy 404.241 -437.21909)
			(xy 404.241503 -437.206979) (xy 404.248988 -437.183942) (xy 404.263224 -437.164343) (xy 404.282817 -437.150101)
			(xy 404.305851 -437.142607) (xy 404.317962 -437.142128) (xy 405.257762 -437.142128) (xy 405.269882 -437.142592)
			(xy 405.292938 -437.150073) (xy 405.312553 -437.164313) (xy 405.326805 -437.183919) (xy 405.3343 -437.20697)
			(xy 405.334724 -437.21909) (xy 405.334724 -438.760616) (xy 406.240996 -438.760616) (xy 406.240996 -436.219092)
			(xy 406.241453 -436.207042) (xy 406.248888 -436.184117) (xy 406.263029 -436.164601) (xy 406.2825 -436.150398)
			(xy 406.305401 -436.142892) (xy 406.31745 -436.142384) (xy 407.257758 -436.142384) (xy 407.26985 -436.142844)
			(xy 407.292856 -436.150294) (xy 407.307183 -436.160672) (xy 408.240992 -436.160672) (xy 408.240992 -433.619148)
			(xy 408.241501 -433.607101) (xy 408.248919 -433.584178) (xy 408.263048 -433.564662) (xy 408.282508 -433.550457)
			(xy 408.305401 -433.542948) (xy 408.317446 -433.54244) (xy 409.257754 -433.54244) (xy 409.269841 -433.542947)
			(xy 409.29284 -433.550391) (xy 409.312421 -433.564567) (xy 409.326673 -433.584093) (xy 409.334206 -433.607063)
			(xy 409.334716 -433.619148) (xy 409.334716 -435.160674) (xy 410.240988 -435.160674) (xy 410.240988 -432.61915)
			(xy 410.241468 -432.607038) (xy 410.248963 -432.584001) (xy 410.263205 -432.564405) (xy 410.282801 -432.550163)
			(xy 410.305838 -432.542668) (xy 410.31795 -432.542188) (xy 411.25775 -432.542188) (xy 411.269862 -432.542668)
			(xy 411.292899 -432.550163) (xy 411.307089 -432.560476) (xy 412.241492 -432.560476) (xy 412.241492 -431.833274)
			(xy 412.241744 -431.824517) (xy 412.245723 -431.807459) (xy 412.249366 -431.799492) (xy 412.482792 -431.323242)
			(xy 412.487522 -431.312737) (xy 412.491003 -431.289971) (xy 412.487505 -431.267208) (xy 412.482792 -431.256694)
			(xy 412.249366 -430.780444) (xy 412.245715 -430.772478) (xy 412.241733 -430.755421) (xy 412.241492 -430.746662)
			(xy 412.241492 -430.018952) (xy 412.241923 -430.006875) (xy 412.249399 -429.983906) (xy 412.263604 -429.96437)
			(xy 412.283149 -429.950177) (xy 412.306123 -429.942716) (xy 412.3182 -429.942244) (xy 413.258 -429.942244)
			(xy 413.27007 -429.942764) (xy 413.293029 -429.95022) (xy 413.312562 -429.964404) (xy 413.326758 -429.983928)
			(xy 413.334229 -430.006883) (xy 413.334708 -430.018952) (xy 413.334708 -432.560476) (xy 413.334267 -432.572557)
			(xy 413.326806 -432.595539) (xy 413.312607 -432.61509) (xy 413.293061 -432.629295) (xy 413.270081 -432.636763)
			(xy 413.258 -432.637184) (xy 412.3182 -432.637184) (xy 412.306115 -432.636787) (xy 412.283128 -432.629317)
			(xy 412.263576 -432.615107) (xy 412.249372 -432.59555) (xy 412.241909 -432.572561) (xy 412.241492 -432.560476)
			(xy 411.307089 -432.560476) (xy 411.312495 -432.564405) (xy 411.326737 -432.584001) (xy 411.334232 -432.607038)
			(xy 411.334712 -432.61915) (xy 411.334712 -435.160674) (xy 411.334167 -435.172782) (xy 411.326693 -435.195816)
			(xy 411.312468 -435.215414) (xy 411.292884 -435.229658) (xy 411.269858 -435.237155) (xy 411.25775 -435.237636)
			(xy 410.31795 -435.237636) (xy 410.30583 -435.23723) (xy 410.282781 -435.229726) (xy 410.263178 -435.215468)
			(xy 410.248939 -435.195851) (xy 410.241458 -435.172794) (xy 410.240988 -435.160674) (xy 409.334716 -435.160674)
			(xy 409.334716 -436.160672) (xy 409.334217 -436.172719) (xy 409.326793 -436.195641) (xy 409.312662 -436.215156)
			(xy 409.293201 -436.229361) (xy 409.270307 -436.236871) (xy 409.258262 -436.23738) (xy 408.317954 -436.23738)
			(xy 408.305864 -436.236932) (xy 408.282865 -436.229465) (xy 408.263288 -436.215273) (xy 408.249038 -436.195737)
			(xy 408.241504 -436.172761) (xy 408.240992 -436.160672) (xy 407.307183 -436.160672) (xy 407.312441 -436.164481)
			(xy 407.326691 -436.184019) (xy 407.334216 -436.207002) (xy 407.33472 -436.219092) (xy 407.33472 -438.760616)
			(xy 407.334254 -438.772665) (xy 407.326819 -438.795588) (xy 407.312679 -438.815101) (xy 407.293212 -438.829305)
			(xy 407.270313 -438.836814) (xy 407.258266 -438.837324) (xy 406.317958 -438.837324) (xy 406.305863 -438.836928)
			(xy 406.282855 -438.829455) (xy 406.263272 -438.815252) (xy 406.249024 -438.795701) (xy 406.2415 -438.77271)
			(xy 406.240996 -438.760616) (xy 405.334724 -438.760616) (xy 405.334724 -439.760614) (xy 408.240992 -439.760614)
			(xy 408.240992 -437.21909) (xy 408.241503 -437.20698) (xy 408.248987 -437.183944) (xy 408.263221 -437.164346)
			(xy 408.282812 -437.150104) (xy 408.305844 -437.142608) (xy 408.317954 -437.142128) (xy 409.257754 -437.142128)
			(xy 409.269873 -437.142599) (xy 409.292929 -437.150077) (xy 409.312544 -437.164316) (xy 409.326797 -437.183921)
			(xy 409.334292 -437.206971) (xy 409.334716 -437.21909) (xy 409.334716 -438.760616) (xy 410.240988 -438.760616)
			(xy 410.240988 -436.219092) (xy 410.241453 -436.207043) (xy 410.248886 -436.184119) (xy 410.263026 -436.164604)
			(xy 410.282495 -436.150401) (xy 410.305394 -436.142893) (xy 410.317442 -436.142384) (xy 411.25775 -436.142384)
			(xy 411.269841 -436.142851) (xy 411.292848 -436.150299) (xy 411.307169 -436.160672) (xy 412.240984 -436.160672)
			(xy 412.240984 -433.619148) (xy 412.2415 -433.607102) (xy 412.248918 -433.58418) (xy 412.263045 -433.564665)
			(xy 412.282503 -433.55046) (xy 412.305394 -433.54295) (xy 412.317438 -433.54244) (xy 413.257746 -433.54244)
			(xy 413.269838 -433.542868) (xy 413.29284 -433.550338) (xy 413.312419 -433.564534) (xy 413.326668 -433.584075)
			(xy 413.334199 -433.607057) (xy 413.334708 -433.619148) (xy 413.334708 -435.59984) (xy 446.741306 -435.59984)
			(xy 446.745288 -435.471854) (xy 446.75722 -435.344363) (xy 446.777054 -435.21786) (xy 446.804715 -435.092835)
			(xy 446.840095 -434.969772) (xy 446.883057 -434.849146) (xy 446.933435 -434.731425) (xy 446.991035 -434.617063)
			(xy 447.055633 -434.506504) (xy 447.12698 -434.400174) (xy 447.204799 -434.298486) (xy 447.288789 -434.201832)
			(xy 447.378626 -434.110587) (xy 447.473962 -434.025104) (xy 447.574427 -433.945713) (xy 447.679635 -433.872721)
			(xy 447.789176 -433.806412) (xy 447.902628 -433.747041) (xy 448.019552 -433.694837) (xy 448.139495 -433.650004)
			(xy 448.261993 -433.612715) (xy 448.386573 -433.583113) (xy 448.512751 -433.561314) (xy 448.640041 -433.547401)
			(xy 448.76795 -433.541429) (xy 448.895983 -433.54342) (xy 449.023644 -433.553368) (xy 449.15044 -433.571232)
			(xy 449.275879 -433.596945) (xy 449.399478 -433.630407) (xy 449.520757 -433.671488) (xy 449.639248 -433.72003)
			(xy 449.754492 -433.775844) (xy 449.866042 -433.838715) (xy 449.973469 -433.908399) (xy 450.076355 -433.984627)
			(xy 450.174303 -434.067104) (xy 450.266934 -434.155511) (xy 450.35389 -434.249506) (xy 450.434834 -434.348725)
			(xy 450.509453 -434.452784) (xy 450.577458 -434.561281) (xy 450.638586 -434.673796) (xy 450.692601 -434.789894)
			(xy 450.739294 -434.909125) (xy 450.778484 -435.031029) (xy 450.81002 -435.155133) (xy 450.833779 -435.280957)
			(xy 450.849669 -435.408016) (xy 450.85763 -435.535816) (xy 450.858128 -435.59984) (xy 450.85763 -435.663864)
			(xy 450.849669 -435.791664) (xy 450.833779 -435.918723) (xy 450.81002 -436.044547) (xy 450.778484 -436.168651)
			(xy 450.739294 -436.290555) (xy 450.692601 -436.409786) (xy 450.638586 -436.525884) (xy 450.577458 -436.638399)
			(xy 450.509453 -436.746896) (xy 450.434834 -436.850955) (xy 450.35389 -436.950174) (xy 450.266934 -437.044169)
			(xy 450.174303 -437.132576) (xy 450.076355 -437.215053) (xy 449.973469 -437.291281) (xy 449.866042 -437.360965)
			(xy 449.754492 -437.423836) (xy 449.639248 -437.47965) (xy 449.520757 -437.528192) (xy 449.399478 -437.569273)
			(xy 449.275879 -437.602735) (xy 449.15044 -437.628448) (xy 449.023644 -437.646312) (xy 448.895983 -437.65626)
			(xy 448.76795 -437.658251) (xy 448.640041 -437.652279) (xy 448.512751 -437.638366) (xy 448.386573 -437.616567)
			(xy 448.261993 -437.586965) (xy 448.139495 -437.549676) (xy 448.019552 -437.504843) (xy 447.902628 -437.452639)
			(xy 447.789176 -437.393268) (xy 447.679635 -437.326959) (xy 447.574427 -437.253967) (xy 447.473962 -437.174576)
			(xy 447.378626 -437.089093) (xy 447.288789 -436.997848) (xy 447.204799 -436.901194) (xy 447.12698 -436.799506)
			(xy 447.055633 -436.693176) (xy 446.991035 -436.582617) (xy 446.933435 -436.468255) (xy 446.883057 -436.350534)
			(xy 446.840095 -436.229908) (xy 446.804715 -436.106845) (xy 446.777054 -435.98182) (xy 446.75722 -435.855317)
			(xy 446.745288 -435.727826) (xy 446.741306 -435.59984) (xy 413.334708 -435.59984) (xy 413.334708 -436.160672)
			(xy 413.334216 -436.17272) (xy 413.326792 -436.195643) (xy 413.312659 -436.215159) (xy 413.293196 -436.229363)
			(xy 413.2703 -436.236872) (xy 413.258254 -436.23738) (xy 412.317946 -436.23738) (xy 412.305861 -436.236854)
			(xy 412.282865 -436.229412) (xy 412.263286 -436.21524) (xy 412.249033 -436.19572) (xy 412.241497 -436.172755)
			(xy 412.240984 -436.160672) (xy 411.307169 -436.160672) (xy 411.312432 -436.164484) (xy 411.326683 -436.184021)
			(xy 411.334208 -436.207002) (xy 411.334712 -436.219092) (xy 411.334712 -438.760616) (xy 411.334254 -438.772666)
			(xy 411.326818 -438.79559) (xy 411.312676 -438.815104) (xy 411.293207 -438.829307) (xy 411.270306 -438.836815)
			(xy 411.258258 -438.837324) (xy 410.31795 -438.837324) (xy 410.305859 -438.836849) (xy 410.282854 -438.829402)
			(xy 410.26327 -438.815219) (xy 410.249019 -438.795684) (xy 410.241493 -438.772705) (xy 410.240988 -438.760616)
			(xy 409.334716 -438.760616) (xy 409.334716 -439.760614) (xy 412.240984 -439.760614) (xy 412.240984 -437.21909)
			(xy 412.241352 -437.206962) (xy 412.248853 -437.183895) (xy 412.263116 -437.164276) (xy 412.282745 -437.150027)
			(xy 412.305818 -437.142544) (xy 412.317946 -437.142128) (xy 413.257746 -437.142128) (xy 413.269862 -437.142572)
			(xy 413.292905 -437.150071) (xy 413.312505 -437.164321) (xy 413.326745 -437.183927) (xy 413.334233 -437.206974)
			(xy 413.334708 -437.21909) (xy 413.334708 -439.760614) (xy 413.334201 -439.772725) (xy 413.326716 -439.795761)
			(xy 413.312481 -439.815358) (xy 413.292889 -439.829601) (xy 413.269857 -439.837096) (xy 413.257746 -439.837576)
			(xy 412.317946 -439.837576) (xy 412.305827 -439.837101) (xy 412.282772 -439.829623) (xy 412.263157 -439.815385)
			(xy 412.248904 -439.795782) (xy 412.241408 -439.772733) (xy 412.240984 -439.760614) (xy 409.334716 -439.760614)
			(xy 409.334351 -439.772742) (xy 409.326849 -439.795809) (xy 409.312585 -439.815428) (xy 409.292955 -439.829677)
			(xy 409.269882 -439.83716) (xy 409.257754 -439.837576) (xy 408.317954 -439.837576) (xy 408.305838 -439.837128)
			(xy 408.282796 -439.82963) (xy 408.263196 -439.815381) (xy 408.248956 -439.795775) (xy 408.241467 -439.77273)
			(xy 408.240992 -439.760614) (xy 405.334724 -439.760614) (xy 405.334351 -439.772741) (xy 405.32685 -439.795807)
			(xy 405.312588 -439.815425) (xy 405.29296 -439.829674) (xy 405.26989 -439.837159) (xy 405.257762 -439.837576)
			(xy 404.317962 -439.837576) (xy 404.305847 -439.837121) (xy 404.282805 -439.829625) (xy 404.263205 -439.815378)
			(xy 404.248964 -439.795774) (xy 404.241475 -439.772729) (xy 404.241 -439.760614) (xy 401.334732 -439.760614)
			(xy 401.334351 -439.77274) (xy 401.326852 -439.795805) (xy 401.312591 -439.815422) (xy 401.292965 -439.829672)
			(xy 401.269897 -439.837158) (xy 401.25777 -439.837576) (xy 400.31797 -439.837576) (xy 400.305855 -439.837114)
			(xy 400.282813 -439.82962) (xy 400.263213 -439.815375) (xy 400.248972 -439.795772) (xy 400.241483 -439.772729)
			(xy 400.241008 -439.760614) (xy 396.334488 -439.760614) (xy 396.334005 -439.772702) (xy 396.326548 -439.795698)
			(xy 396.312365 -439.815275) (xy 396.292836 -439.829526) (xy 396.269866 -439.837063) (xy 396.25778 -439.837576)
			(xy 395.31798 -439.837576) (xy 395.305868 -439.8372) (xy 395.282836 -439.829693) (xy 395.263261 -439.815421)
			(xy 395.249068 -439.79579) (xy 395.241652 -439.772728) (xy 395.241272 -439.760614) (xy 392.334496 -439.760614)
			(xy 392.334005 -439.772701) (xy 392.326549 -439.795696) (xy 392.312367 -439.815272) (xy 392.292841 -439.829524)
			(xy 392.269873 -439.837062) (xy 392.257788 -439.837576) (xy 391.317988 -439.837576) (xy 391.305876 -439.837194)
			(xy 391.282844 -439.829688) (xy 391.263269 -439.815419) (xy 391.249076 -439.795788) (xy 391.24166 -439.772727)
			(xy 391.24128 -439.760614) (xy 388.334504 -439.760614) (xy 388.334006 -439.7727) (xy 388.32655 -439.795694)
			(xy 388.31237 -439.81527) (xy 388.292846 -439.829521) (xy 388.26988 -439.837061) (xy 388.257796 -439.837576)
			(xy 387.317996 -439.837576) (xy 387.305885 -439.837187) (xy 387.282853 -439.829683) (xy 387.263278 -439.815416)
			(xy 387.249084 -439.795787) (xy 387.241668 -439.772727) (xy 387.241288 -439.760614) (xy 384.334512 -439.760614)
			(xy 384.334104 -439.772709) (xy 384.326638 -439.795718) (xy 384.312437 -439.815302) (xy 384.292889 -439.829551)
			(xy 384.269898 -439.837074) (xy 384.257804 -439.837576) (xy 383.318004 -439.837576) (xy 383.305893 -439.83718)
			(xy 383.282862 -439.829679) (xy 383.263286 -439.815413) (xy 383.249092 -439.795785) (xy 383.241676 -439.772727)
			(xy 383.241296 -439.760614) (xy 346.234512 -439.760614) (xy 346.234104 -439.772709) (xy 346.226638 -439.795718)
			(xy 346.212437 -439.815302) (xy 346.192889 -439.829551) (xy 346.169898 -439.837074) (xy 346.157804 -439.837576)
			(xy 345.218004 -439.837576) (xy 345.205893 -439.83718) (xy 345.182862 -439.829679) (xy 345.163286 -439.815413)
			(xy 345.149092 -439.795785) (xy 345.141676 -439.772727) (xy 345.141296 -439.760614) (xy 342.23452 -439.760614)
			(xy 342.234104 -439.772708) (xy 342.226639 -439.795716) (xy 342.21244 -439.815299) (xy 342.192894 -439.829548)
			(xy 342.169905 -439.837073) (xy 342.157812 -439.837576) (xy 341.218012 -439.837576) (xy 341.205901 -439.837173)
			(xy 341.18287 -439.829674) (xy 341.163295 -439.81541) (xy 341.149101 -439.795784) (xy 341.141684 -439.772726)
			(xy 341.141304 -439.760614) (xy 338.234528 -439.760614) (xy 338.234104 -439.772708) (xy 338.22664 -439.795714)
			(xy 338.212443 -439.815297) (xy 338.192899 -439.829546) (xy 338.169912 -439.837072) (xy 338.15782 -439.837576)
			(xy 337.21802 -439.837576) (xy 337.20591 -439.837166) (xy 337.182879 -439.829669) (xy 337.163304 -439.815407)
			(xy 337.149109 -439.795782) (xy 337.141692 -439.772726) (xy 337.141312 -439.760614) (xy 334.234536 -439.760614)
			(xy 334.234104 -439.772707) (xy 334.226641 -439.795712) (xy 334.212446 -439.815294) (xy 334.192904 -439.829543)
			(xy 334.169919 -439.83707) (xy 334.157828 -439.837576) (xy 333.218028 -439.837576) (xy 333.205918 -439.837159)
			(xy 333.182888 -439.829665) (xy 333.163312 -439.815404) (xy 333.149117 -439.795781) (xy 333.1417 -439.772725)
			(xy 333.14132 -439.760614) (xy 329.2348 -439.760614) (xy 329.234301 -439.772726) (xy 329.226815 -439.795763)
			(xy 329.212578 -439.815361) (xy 329.192984 -439.829604) (xy 329.169949 -439.837097) (xy 329.157838 -439.837576)
			(xy 328.218038 -439.837576) (xy 328.205919 -439.837108) (xy 328.182863 -439.829628) (xy 328.163249 -439.815388)
			(xy 328.148996 -439.795783) (xy 328.1415 -439.772733) (xy 328.141076 -439.760614) (xy 325.234808 -439.760614)
			(xy 325.234301 -439.772725) (xy 325.226816 -439.795761) (xy 325.212581 -439.815358) (xy 325.192989 -439.829601)
			(xy 325.169957 -439.837096) (xy 325.157846 -439.837576) (xy 324.218046 -439.837576) (xy 324.205927 -439.837101)
			(xy 324.182872 -439.829623) (xy 324.163257 -439.815385) (xy 324.149004 -439.795782) (xy 324.141508 -439.772733)
			(xy 324.141084 -439.760614) (xy 321.234816 -439.760614) (xy 321.234451 -439.772742) (xy 321.226949 -439.795809)
			(xy 321.212685 -439.815428) (xy 321.193055 -439.829677) (xy 321.169982 -439.83716) (xy 321.157854 -439.837576)
			(xy 320.218054 -439.837576) (xy 320.205938 -439.837128) (xy 320.182896 -439.82963) (xy 320.163296 -439.815381)
			(xy 320.149056 -439.795775) (xy 320.141567 -439.77273) (xy 320.141092 -439.760614) (xy 317.234824 -439.760614)
			(xy 317.234451 -439.772741) (xy 317.22695 -439.795807) (xy 317.212688 -439.815425) (xy 317.19306 -439.829674)
			(xy 317.16999 -439.837159) (xy 317.157862 -439.837576) (xy 316.218062 -439.837576) (xy 316.205947 -439.837121)
			(xy 316.182905 -439.829625) (xy 316.163305 -439.815378) (xy 316.149064 -439.795774) (xy 316.141575 -439.772729)
			(xy 316.1411 -439.760614) (xy 157.334712 -439.760614) (xy 157.334201 -439.772724) (xy 157.326716 -439.79576)
			(xy 157.312482 -439.815357) (xy 157.292892 -439.8296) (xy 157.26986 -439.837096) (xy 157.25775 -439.837576)
			(xy 156.31795 -439.837576) (xy 156.305834 -439.837131) (xy 156.282792 -439.829632) (xy 156.263192 -439.815382)
			(xy 156.248952 -439.795776) (xy 156.241463 -439.77273) (xy 156.240988 -439.760614) (xy 153.33472 -439.760614)
			(xy 153.334351 -439.772742) (xy 153.32685 -439.795808) (xy 153.312586 -439.815426) (xy 153.292958 -439.829675)
			(xy 153.269886 -439.83716) (xy 153.257758 -439.837576) (xy 152.317958 -439.837576) (xy 152.305843 -439.837124)
			(xy 152.2828 -439.829627) (xy 152.263201 -439.815379) (xy 152.24896 -439.795774) (xy 152.241471 -439.77273)
			(xy 152.240996 -439.760614) (xy 149.334728 -439.760614) (xy 149.334351 -439.772741) (xy 149.326851 -439.795806)
			(xy 149.312589 -439.815424) (xy 149.292963 -439.829673) (xy 149.269893 -439.837159) (xy 149.257766 -439.837576)
			(xy 148.317966 -439.837576) (xy 148.305851 -439.837118) (xy 148.282809 -439.829623) (xy 148.263209 -439.815377)
			(xy 148.248968 -439.795773) (xy 148.241479 -439.772729) (xy 148.241004 -439.760614) (xy 145.334736 -439.760614)
			(xy 145.334351 -439.77274) (xy 145.326852 -439.795804) (xy 145.312592 -439.815421) (xy 145.292968 -439.82967)
			(xy 145.2699 -439.837158) (xy 145.257774 -439.837576) (xy 144.317974 -439.837576) (xy 144.305859 -439.837111)
			(xy 144.282818 -439.829618) (xy 144.263218 -439.815374) (xy 144.248976 -439.795772) (xy 144.241487 -439.772729)
			(xy 144.241012 -439.760614) (xy 140.334492 -439.760614) (xy 140.334005 -439.772701) (xy 140.326549 -439.795697)
			(xy 140.312366 -439.815274) (xy 140.292839 -439.829525) (xy 140.269869 -439.837062) (xy 140.257784 -439.837576)
			(xy 139.317984 -439.837576) (xy 139.305872 -439.837197) (xy 139.28284 -439.82969) (xy 139.263265 -439.81542)
			(xy 139.249072 -439.795789) (xy 139.241656 -439.772728) (xy 139.241276 -439.760614) (xy 136.3345 -439.760614)
			(xy 136.334006 -439.7727) (xy 136.32655 -439.795695) (xy 136.312369 -439.815271) (xy 136.292844 -439.829523)
			(xy 136.269877 -439.837061) (xy 136.257792 -439.837576) (xy 135.317992 -439.837576) (xy 135.30588 -439.83719)
			(xy 135.282849 -439.829686) (xy 135.263274 -439.815417) (xy 135.24908 -439.795788) (xy 135.241664 -439.772727)
			(xy 135.241284 -439.760614) (xy 132.334508 -439.760614) (xy 132.334006 -439.7727) (xy 132.326551 -439.795693)
			(xy 132.312372 -439.815268) (xy 132.292849 -439.82952) (xy 132.269884 -439.83706) (xy 132.2578 -439.837576)
			(xy 131.318 -439.837576) (xy 131.305889 -439.837184) (xy 131.282857 -439.829681) (xy 131.263282 -439.815414)
			(xy 131.249088 -439.795786) (xy 131.241672 -439.772727) (xy 131.241292 -439.760614) (xy 128.334516 -439.760614)
			(xy 128.334104 -439.772709) (xy 128.326638 -439.795717) (xy 128.312439 -439.815301) (xy 128.292891 -439.829549)
			(xy 128.269901 -439.837073) (xy 128.257808 -439.837576) (xy 127.318008 -439.837576) (xy 127.305897 -439.837177)
			(xy 127.282866 -439.829677) (xy 127.263291 -439.815412) (xy 127.249096 -439.795785) (xy 127.24168 -439.772726)
			(xy 127.2413 -439.760614) (xy 90.234516 -439.760614) (xy 90.234104 -439.772709) (xy 90.226638 -439.795717)
			(xy 90.212439 -439.815301) (xy 90.192891 -439.829549) (xy 90.169901 -439.837073) (xy 90.157808 -439.837576)
			(xy 89.218008 -439.837576) (xy 89.205897 -439.837177) (xy 89.182866 -439.829677) (xy 89.163291 -439.815412)
			(xy 89.149096 -439.795785) (xy 89.14168 -439.772726) (xy 89.1413 -439.760614) (xy 86.234524 -439.760614)
			(xy 86.234104 -439.772708) (xy 86.226639 -439.795715) (xy 86.212442 -439.815298) (xy 86.192896 -439.829547)
			(xy 86.169909 -439.837072) (xy 86.157816 -439.837576) (xy 85.218016 -439.837576) (xy 85.205906 -439.83717)
			(xy 85.182875 -439.829672) (xy 85.163299 -439.815408) (xy 85.149105 -439.795783) (xy 85.141688 -439.772726)
			(xy 85.141308 -439.760614) (xy 82.234532 -439.760614) (xy 82.234104 -439.772707) (xy 82.22664 -439.795713)
			(xy 82.212445 -439.815295) (xy 82.192901 -439.829544) (xy 82.169916 -439.837071) (xy 82.157824 -439.837576)
			(xy 81.218024 -439.837576) (xy 81.205914 -439.837163) (xy 81.182883 -439.829667) (xy 81.163308 -439.815406)
			(xy 81.149113 -439.795781) (xy 81.141696 -439.772725) (xy 81.141316 -439.760614) (xy 78.23454 -439.760614)
			(xy 78.234104 -439.772706) (xy 78.226641 -439.795711) (xy 78.212447 -439.815292) (xy 78.192906 -439.829542)
			(xy 78.169923 -439.83707) (xy 78.157832 -439.837576) (xy 77.218032 -439.837576) (xy 77.205922 -439.837156)
			(xy 77.182892 -439.829663) (xy 77.163316 -439.815403) (xy 77.149122 -439.79578) (xy 77.141704 -439.772725)
			(xy 77.141324 -439.760614) (xy 73.234804 -439.760614) (xy 73.234301 -439.772725) (xy 73.226815 -439.795762)
			(xy 73.21258 -439.81536) (xy 73.192987 -439.829602) (xy 73.169953 -439.837097) (xy 73.157842 -439.837576)
			(xy 72.218042 -439.837576) (xy 72.205923 -439.837105) (xy 72.182868 -439.829626) (xy 72.163253 -439.815387)
			(xy 72.149 -439.795783) (xy 72.141504 -439.772733) (xy 72.14108 -439.760614) (xy 69.234812 -439.760614)
			(xy 69.234301 -439.772724) (xy 69.226816 -439.79576) (xy 69.212582 -439.815357) (xy 69.192992 -439.8296)
			(xy 69.16996 -439.837096) (xy 69.15785 -439.837576) (xy 68.21805 -439.837576) (xy 68.205934 -439.837131)
			(xy 68.182892 -439.829632) (xy 68.163292 -439.815382) (xy 68.149052 -439.795776) (xy 68.141563 -439.77273)
			(xy 68.141088 -439.760614) (xy 65.23482 -439.760614) (xy 65.234451 -439.772742) (xy 65.22695 -439.795808)
			(xy 65.212686 -439.815426) (xy 65.193058 -439.829675) (xy 65.169986 -439.83716) (xy 65.157858 -439.837576)
			(xy 64.218058 -439.837576) (xy 64.205943 -439.837124) (xy 64.1829 -439.829627) (xy 64.163301 -439.815379)
			(xy 64.14906 -439.795774) (xy 64.141571 -439.77273) (xy 64.141096 -439.760614) (xy 61.234828 -439.760614)
			(xy 61.234451 -439.772741) (xy 61.226951 -439.795806) (xy 61.212689 -439.815424) (xy 61.193063 -439.829673)
			(xy 61.169993 -439.837159) (xy 61.157866 -439.837576) (xy 60.218066 -439.837576) (xy 60.205951 -439.837118)
			(xy 60.182909 -439.829623) (xy 60.163309 -439.815377) (xy 60.149068 -439.795773) (xy 60.141579 -439.772729)
			(xy 60.141104 -439.760614) (xy 7.00913 -439.760614) (xy 7.00913 -439.989976) (xy 7.009638 -440.045746)
			(xy 7.017973 -440.156973) (xy 7.034597 -440.267266) (xy 7.059417 -440.376009) (xy 7.092293 -440.482593)
			(xy 7.133043 -440.586422) (xy 7.181438 -440.686915) (xy 7.237207 -440.783511) (xy 7.300039 -440.87567)
			(xy 7.369583 -440.962874) (xy 7.445449 -441.044639) (xy 7.527212 -441.120505) (xy 7.614417 -441.190048)
			(xy 7.706575 -441.252881) (xy 7.803171 -441.30865) (xy 7.903664 -441.357045) (xy 8.007493 -441.397795)
			(xy 8.114077 -441.430672) (xy 8.22282 -441.455492) (xy 8.333113 -441.472116) (xy 8.44434 -441.480451)
			(xy 8.50011 -441.480956)
		)
		(stroke
			(width 0)
			(type solid)
		)
		(fill yes)
		(layer "In10.Cu")
		(net "GND")
	)
	(gr_line
		(start 1.414272 -79.914242)
		(end 0.585724 -79.085694)
		(stroke
			(width 1.016)
			(type default)
		)
		(layer "In10.Cu")
	)
	(gr_line
		(start 1.999996 -403.371558)
		(end 1.999996 -81.328514)
		(stroke
			(width 1.016)
			(type default)
		)
		(layer "In10.Cu")
	)
	(gr_arc
		(start 1.999996 -403.371558)
		(mid 2.152159 -404.136965)
		(end 2.58572 -404.78583)
		(stroke
			(width 1.016)
			(type default)
		)
		(layer "In10.Cu")
	)
	(gr_arc
		(start 1.999996 -81.328514)
		(mid 1.847755 -80.563149)
		(end 1.414272 -79.914242)
		(stroke
			(width 1.016)
			(type default)
		)
		(layer "In10.Cu")
	)
	(gr_arc
		(start 1.999996 -11.780012)
		(mid 0.585785 -12.365797)
		(end 0 -13.780008)
		(stroke
			(width 1.016)
			(type default)
		)
		(layer "In10.Cu")
	)
	(gr_line
		(start 1.999996 -11.780012)
		(end 11.102086 -11.780012)
		(stroke
			(width 1.016)
			(type default)
		)
		(layer "In10.Cu")
	)
	(gr_line
		(start 5.914136 -408.114246)
		(end 2.58572 -404.78583)
		(stroke
			(width 1.016)
			(type default)
		)
		(layer "In10.Cu")
	)
	(gr_line
		(start 6.500114 -439.989976)
		(end 6.500114 -409.528518)
		(stroke
			(width 1.016)
			(type default)
		)
		(layer "In10.Cu")
	)
	(gr_arc
		(start 6.500114 -439.989976)
		(mid 7.085891 -441.404199)
		(end 8.50011 -441.989972)
		(stroke
			(width 1.016)
			(type default)
		)
		(layer "In10.Cu")
	)
	(gr_arc
		(start 6.500114 -409.528518)
		(mid 6.347771 -408.763109)
		(end 5.914136 -408.114246)
		(stroke
			(width 1.016)
			(type default)
		)
		(layer "In10.Cu")
	)
	(gr_arc
		(start 11.102086 -11.780012)
		(mid 12.516297 -11.194227)
		(end 13.102082 -9.780016)
		(stroke
			(width 1.016)
			(type default)
		)
		(layer "In10.Cu")
	)
	(gr_line
		(start 13.102082 -9.780016)
		(end 13.102082 -0.500126)
		(stroke
			(width 1.016)
			(type default)
		)
		(layer "In10.Cu")
	)
	(gr_arc
		(start 13.601954 0)
		(mid 13.24848 -0.146572)
		(end 13.102082 -0.500126)
		(stroke
			(width 1.016)
			(type default)
		)
		(layer "In10.Cu")
	)
	(gr_line
		(start 13.601954 0)
		(end 81.202022 0)
		(stroke
			(width 1.016)
			(type default)
		)
		(layer "In10.Cu")
	)
	(gr_circle
		(center 25.82545 -40.816276)
		(end 26.71445 -40.816276)
		(stroke
			(width 0.2)
			(type default)
		)
		(fill no)
		(layer "In10.Cu")
	)
	(gr_circle
		(center 29.291534 -348.709488)
		(end 30.171644 -348.709488)
		(stroke
			(width 0.2)
			(type default)
		)
		(fill no)
		(layer "In10.Cu")
	)
	(gr_circle
		(center 29.908754 -348.709488)
		(end 30.788864 -348.709488)
		(stroke
			(width 0.2)
			(type default)
		)
		(fill no)
		(layer "In10.Cu")
	)
	(gr_circle
		(center 30.525974 -348.709488)
		(end 31.406084 -348.709488)
		(stroke
			(width 0.2)
			(type default)
		)
		(fill no)
		(layer "In10.Cu")
	)
	(gr_circle
		(center 30.795214 -347.966538)
		(end 31.684214 -347.966538)
		(stroke
			(width 0.2)
			(type default)
		)
		(fill no)
		(layer "In10.Cu")
	)
	(gr_circle
		(center 30.795214 -347.229938)
		(end 31.684214 -347.229938)
		(stroke
			(width 0.2)
			(type default)
		)
		(fill no)
		(layer "In10.Cu")
	)
	(gr_circle
		(center 31.22803 -350.318578)
		(end 32.11703 -350.318578)
		(stroke
			(width 0.2)
			(type default)
		)
		(fill no)
		(layer "In10.Cu")
	)
	(gr_circle
		(center 31.22803 -349.581978)
		(end 32.11703 -349.581978)
		(stroke
			(width 0.2)
			(type default)
		)
		(fill no)
		(layer "In10.Cu")
	)
	(gr_circle
		(center 31.752794 -349.142558)
		(end 32.641794 -349.142558)
		(stroke
			(width 0.2)
			(type default)
		)
		(fill no)
		(layer "In10.Cu")
	)
	(gr_circle
		(center 31.778194 -349.904558)
		(end 32.667194 -349.904558)
		(stroke
			(width 0.2)
			(type default)
		)
		(fill no)
		(layer "In10.Cu")
	)
	(gr_circle
		(center 32.311594 -350.260158)
		(end 33.200594 -350.260158)
		(stroke
			(width 0.2)
			(type default)
		)
		(fill no)
		(layer "In10.Cu")
	)
	(gr_circle
		(center 32.311594 -349.523558)
		(end 33.200594 -349.523558)
		(stroke
			(width 0.2)
			(type default)
		)
		(fill no)
		(layer "In10.Cu")
	)
	(gr_circle
		(center 32.311594 -348.786958)
		(end 33.200594 -348.786958)
		(stroke
			(width 0.2)
			(type default)
		)
		(fill no)
		(layer "In10.Cu")
	)
	(gr_circle
		(center 37.571934 -348.709488)
		(end 38.452044 -348.709488)
		(stroke
			(width 0.2)
			(type default)
		)
		(fill no)
		(layer "In10.Cu")
	)
	(gr_circle
		(center 38.189154 -348.709488)
		(end 39.069264 -348.709488)
		(stroke
			(width 0.2)
			(type default)
		)
		(fill no)
		(layer "In10.Cu")
	)
	(gr_circle
		(center 38.806374 -348.709488)
		(end 39.686484 -348.709488)
		(stroke
			(width 0.2)
			(type default)
		)
		(fill no)
		(layer "In10.Cu")
	)
	(gr_circle
		(center 39.050214 -347.974158)
		(end 39.939214 -347.974158)
		(stroke
			(width 0.2)
			(type default)
		)
		(fill no)
		(layer "In10.Cu")
	)
	(gr_circle
		(center 39.050214 -347.237558)
		(end 39.939214 -347.237558)
		(stroke
			(width 0.2)
			(type default)
		)
		(fill no)
		(layer "In10.Cu")
	)
	(gr_circle
		(center 39.50843 -350.318578)
		(end 40.39743 -350.318578)
		(stroke
			(width 0.2)
			(type default)
		)
		(fill no)
		(layer "In10.Cu")
	)
	(gr_circle
		(center 39.50843 -349.581978)
		(end 40.39743 -349.581978)
		(stroke
			(width 0.2)
			(type default)
		)
		(fill no)
		(layer "In10.Cu")
	)
	(gr_circle
		(center 40.033194 -349.142558)
		(end 40.922194 -349.142558)
		(stroke
			(width 0.2)
			(type default)
		)
		(fill no)
		(layer "In10.Cu")
	)
	(gr_circle
		(center 40.058594 -349.904558)
		(end 40.947594 -349.904558)
		(stroke
			(width 0.2)
			(type default)
		)
		(fill no)
		(layer "In10.Cu")
	)
	(gr_circle
		(center 40.591994 -350.260158)
		(end 41.480994 -350.260158)
		(stroke
			(width 0.2)
			(type default)
		)
		(fill no)
		(layer "In10.Cu")
	)
	(gr_circle
		(center 40.591994 -349.523558)
		(end 41.480994 -349.523558)
		(stroke
			(width 0.2)
			(type default)
		)
		(fill no)
		(layer "In10.Cu")
	)
	(gr_circle
		(center 40.591994 -348.786958)
		(end 41.480994 -348.786958)
		(stroke
			(width 0.2)
			(type default)
		)
		(fill no)
		(layer "In10.Cu")
	)
	(gr_circle
		(center 41.369742 -358.549194)
		(end 42.258742 -358.549194)
		(stroke
			(width 0.2)
			(type default)
		)
		(fill no)
		(layer "In10.Cu")
	)
	(gr_circle
		(center 41.417494 -357.898192)
		(end 42.306494 -357.898192)
		(stroke
			(width 0.2)
			(type default)
		)
		(fill no)
		(layer "In10.Cu")
	)
	(gr_circle
		(center 41.417494 -357.263192)
		(end 42.306494 -357.263192)
		(stroke
			(width 0.2)
			(type default)
		)
		(fill no)
		(layer "In10.Cu")
	)
	(gr_circle
		(center 41.427146 -359.2576)
		(end 42.316146 -359.2576)
		(stroke
			(width 0.2)
			(type default)
		)
		(fill no)
		(layer "In10.Cu")
	)
	(gr_circle
		(center 43.935904 -358.51084)
		(end 44.824904 -358.51084)
		(stroke
			(width 0.2)
			(type default)
		)
		(fill no)
		(layer "In10.Cu")
	)
	(gr_circle
		(center 43.983656 -357.859838)
		(end 44.872656 -357.859838)
		(stroke
			(width 0.2)
			(type default)
		)
		(fill no)
		(layer "In10.Cu")
	)
	(gr_circle
		(center 43.983656 -357.224838)
		(end 44.872656 -357.224838)
		(stroke
			(width 0.2)
			(type default)
		)
		(fill no)
		(layer "In10.Cu")
	)
	(gr_circle
		(center 43.993308 -359.219246)
		(end 44.882308 -359.219246)
		(stroke
			(width 0.2)
			(type default)
		)
		(fill no)
		(layer "In10.Cu")
	)
	(gr_circle
		(center 45.877734 -348.709488)
		(end 46.757844 -348.709488)
		(stroke
			(width 0.2)
			(type default)
		)
		(fill no)
		(layer "In10.Cu")
	)
	(gr_circle
		(center 46.494954 -348.709488)
		(end 47.375064 -348.709488)
		(stroke
			(width 0.2)
			(type default)
		)
		(fill no)
		(layer "In10.Cu")
	)
	(gr_circle
		(center 47.112174 -348.709488)
		(end 47.992284 -348.709488)
		(stroke
			(width 0.2)
			(type default)
		)
		(fill no)
		(layer "In10.Cu")
	)
	(gr_circle
		(center 47.366174 -348.017338)
		(end 48.255174 -348.017338)
		(stroke
			(width 0.2)
			(type default)
		)
		(fill no)
		(layer "In10.Cu")
	)
	(gr_circle
		(center 47.366174 -347.280738)
		(end 48.255174 -347.280738)
		(stroke
			(width 0.2)
			(type default)
		)
		(fill no)
		(layer "In10.Cu")
	)
	(gr_circle
		(center 47.81423 -350.318578)
		(end 48.70323 -350.318578)
		(stroke
			(width 0.2)
			(type default)
		)
		(fill no)
		(layer "In10.Cu")
	)
	(gr_circle
		(center 47.81423 -349.581978)
		(end 48.70323 -349.581978)
		(stroke
			(width 0.2)
			(type default)
		)
		(fill no)
		(layer "In10.Cu")
	)
	(gr_circle
		(center 47.880778 -358.108504)
		(end 48.769778 -358.108504)
		(stroke
			(width 0.2)
			(type default)
		)
		(fill no)
		(layer "In10.Cu")
	)
	(gr_circle
		(center 47.92853 -357.457502)
		(end 48.81753 -357.457502)
		(stroke
			(width 0.2)
			(type default)
		)
		(fill no)
		(layer "In10.Cu")
	)
	(gr_circle
		(center 47.92853 -356.822502)
		(end 48.81753 -356.822502)
		(stroke
			(width 0.2)
			(type default)
		)
		(fill no)
		(layer "In10.Cu")
	)
	(gr_circle
		(center 48.338994 -349.142558)
		(end 49.227994 -349.142558)
		(stroke
			(width 0.2)
			(type default)
		)
		(fill no)
		(layer "In10.Cu")
	)
	(gr_circle
		(center 48.364394 -349.904558)
		(end 49.253394 -349.904558)
		(stroke
			(width 0.2)
			(type default)
		)
		(fill no)
		(layer "In10.Cu")
	)
	(gr_circle
		(center 48.718978 -358.108504)
		(end 49.607978 -358.108504)
		(stroke
			(width 0.2)
			(type default)
		)
		(fill no)
		(layer "In10.Cu")
	)
	(gr_circle
		(center 48.76673 -357.457502)
		(end 49.65573 -357.457502)
		(stroke
			(width 0.2)
			(type default)
		)
		(fill no)
		(layer "In10.Cu")
	)
	(gr_circle
		(center 48.76673 -356.822502)
		(end 49.65573 -356.822502)
		(stroke
			(width 0.2)
			(type default)
		)
		(fill no)
		(layer "In10.Cu")
	)
	(gr_circle
		(center 48.897794 -350.260158)
		(end 49.786794 -350.260158)
		(stroke
			(width 0.2)
			(type default)
		)
		(fill no)
		(layer "In10.Cu")
	)
	(gr_circle
		(center 48.897794 -349.523558)
		(end 49.786794 -349.523558)
		(stroke
			(width 0.2)
			(type default)
		)
		(fill no)
		(layer "In10.Cu")
	)
	(gr_circle
		(center 48.897794 -348.786958)
		(end 49.786794 -348.786958)
		(stroke
			(width 0.2)
			(type default)
		)
		(fill no)
		(layer "In10.Cu")
	)
	(gr_circle
		(center 49.353978 -358.108504)
		(end 50.242978 -358.108504)
		(stroke
			(width 0.2)
			(type default)
		)
		(fill no)
		(layer "In10.Cu")
	)
	(gr_circle
		(center 49.40173 -357.457502)
		(end 50.29073 -357.457502)
		(stroke
			(width 0.2)
			(type default)
		)
		(fill no)
		(layer "In10.Cu")
	)
	(gr_circle
		(center 49.40173 -356.822502)
		(end 50.29073 -356.822502)
		(stroke
			(width 0.2)
			(type default)
		)
		(fill no)
		(layer "In10.Cu")
	)
	(gr_circle
		(center 49.988978 -358.108504)
		(end 50.877978 -358.108504)
		(stroke
			(width 0.2)
			(type default)
		)
		(fill no)
		(layer "In10.Cu")
	)
	(gr_circle
		(center 50.03673 -357.457502)
		(end 50.92573 -357.457502)
		(stroke
			(width 0.2)
			(type default)
		)
		(fill no)
		(layer "In10.Cu")
	)
	(gr_circle
		(center 50.03673 -356.822502)
		(end 50.92573 -356.822502)
		(stroke
			(width 0.2)
			(type default)
		)
		(fill no)
		(layer "In10.Cu")
	)
	(gr_circle
		(center 50.623978 -358.108504)
		(end 51.512978 -358.108504)
		(stroke
			(width 0.2)
			(type default)
		)
		(fill no)
		(layer "In10.Cu")
	)
	(gr_circle
		(center 50.67173 -357.457502)
		(end 51.56073 -357.457502)
		(stroke
			(width 0.2)
			(type default)
		)
		(fill no)
		(layer "In10.Cu")
	)
	(gr_circle
		(center 50.67173 -356.822502)
		(end 51.56073 -356.822502)
		(stroke
			(width 0.2)
			(type default)
		)
		(fill no)
		(layer "In10.Cu")
	)
	(gr_circle
		(center 54.234334 -348.709488)
		(end 55.114444 -348.709488)
		(stroke
			(width 0.2)
			(type default)
		)
		(fill no)
		(layer "In10.Cu")
	)
	(gr_circle
		(center 54.851554 -348.709488)
		(end 55.731664 -348.709488)
		(stroke
			(width 0.2)
			(type default)
		)
		(fill no)
		(layer "In10.Cu")
	)
	(gr_circle
		(center 55.468774 -348.709488)
		(end 56.348884 -348.709488)
		(stroke
			(width 0.2)
			(type default)
		)
		(fill no)
		(layer "In10.Cu")
	)
	(gr_circle
		(center 55.727854 -347.997018)
		(end 56.616854 -347.997018)
		(stroke
			(width 0.2)
			(type default)
		)
		(fill no)
		(layer "In10.Cu")
	)
	(gr_circle
		(center 55.727854 -347.260418)
		(end 56.616854 -347.260418)
		(stroke
			(width 0.2)
			(type default)
		)
		(fill no)
		(layer "In10.Cu")
	)
	(gr_circle
		(center 56.17083 -350.318578)
		(end 57.05983 -350.318578)
		(stroke
			(width 0.2)
			(type default)
		)
		(fill no)
		(layer "In10.Cu")
	)
	(gr_circle
		(center 56.17083 -349.581978)
		(end 57.05983 -349.581978)
		(stroke
			(width 0.2)
			(type default)
		)
		(fill no)
		(layer "In10.Cu")
	)
	(gr_circle
		(center 56.695594 -349.142558)
		(end 57.584594 -349.142558)
		(stroke
			(width 0.2)
			(type default)
		)
		(fill no)
		(layer "In10.Cu")
	)
	(gr_circle
		(center 56.720994 -349.904558)
		(end 57.609994 -349.904558)
		(stroke
			(width 0.2)
			(type default)
		)
		(fill no)
		(layer "In10.Cu")
	)
	(gr_circle
		(center 57.254394 -350.260158)
		(end 58.143394 -350.260158)
		(stroke
			(width 0.2)
			(type default)
		)
		(fill no)
		(layer "In10.Cu")
	)
	(gr_circle
		(center 57.254394 -349.523558)
		(end 58.143394 -349.523558)
		(stroke
			(width 0.2)
			(type default)
		)
		(fill no)
		(layer "In10.Cu")
	)
	(gr_circle
		(center 57.254394 -348.786958)
		(end 58.143394 -348.786958)
		(stroke
			(width 0.2)
			(type default)
		)
		(fill no)
		(layer "In10.Cu")
	)
	(gr_circle
		(center 61.93663 -166.86276)
		(end 62.82563 -166.86276)
		(stroke
			(width 0.2)
			(type default)
		)
		(fill no)
		(layer "In10.Cu")
	)
	(gr_circle
		(center 61.93663 -166.12616)
		(end 62.82563 -166.12616)
		(stroke
			(width 0.2)
			(type default)
		)
		(fill no)
		(layer "In10.Cu")
	)
	(gr_circle
		(center 61.93663 -165.38956)
		(end 62.82563 -165.38956)
		(stroke
			(width 0.2)
			(type default)
		)
		(fill no)
		(layer "In10.Cu")
	)
	(gr_circle
		(center 62.47003 -165.74516)
		(end 63.35903 -165.74516)
		(stroke
			(width 0.2)
			(type default)
		)
		(fill no)
		(layer "In10.Cu")
	)
	(gr_circle
		(center 62.49543 -166.50716)
		(end 63.38443 -166.50716)
		(stroke
			(width 0.2)
			(type default)
		)
		(fill no)
		(layer "In10.Cu")
	)
	(gr_circle
		(center 62.565534 -348.709488)
		(end 63.445644 -348.709488)
		(stroke
			(width 0.2)
			(type default)
		)
		(fill no)
		(layer "In10.Cu")
	)
	(gr_circle
		(center 63.020194 -166.06774)
		(end 63.909194 -166.06774)
		(stroke
			(width 0.2)
			(type default)
		)
		(fill no)
		(layer "In10.Cu")
	)
	(gr_circle
		(center 63.020194 -165.33114)
		(end 63.909194 -165.33114)
		(stroke
			(width 0.2)
			(type default)
		)
		(fill no)
		(layer "In10.Cu")
	)
	(gr_circle
		(center 63.182754 -348.709488)
		(end 64.062864 -348.709488)
		(stroke
			(width 0.2)
			(type default)
		)
		(fill no)
		(layer "In10.Cu")
	)
	(gr_circle
		(center 63.199264 -12.43711)
		(end 64.088264 -12.43711)
		(stroke
			(width 0.2)
			(type default)
		)
		(fill no)
		(layer "In10.Cu")
	)
	(gr_circle
		(center 63.579248 -168.42232)
		(end 64.468248 -168.42232)
		(stroke
			(width 0.2)
			(type default)
		)
		(fill no)
		(layer "In10.Cu")
	)
	(gr_circle
		(center 63.579248 -167.68572)
		(end 64.468248 -167.68572)
		(stroke
			(width 0.2)
			(type default)
		)
		(fill no)
		(layer "In10.Cu")
	)
	(gr_circle
		(center 63.631064 -13.09751)
		(end 64.520064 -13.09751)
		(stroke
			(width 0.2)
			(type default)
		)
		(fill no)
		(layer "In10.Cu")
	)
	(gr_circle
		(center 63.72225 -166.94023)
		(end 64.60236 -166.94023)
		(stroke
			(width 0.2)
			(type default)
		)
		(fill no)
		(layer "In10.Cu")
	)
	(gr_circle
		(center 63.799974 -348.709488)
		(end 64.680084 -348.709488)
		(stroke
			(width 0.2)
			(type default)
		)
		(fill no)
		(layer "In10.Cu")
	)
	(gr_circle
		(center 64.061594 -348.038928)
		(end 64.941704 -348.038928)
		(stroke
			(width 0.2)
			(type default)
		)
		(fill no)
		(layer "In10.Cu")
	)
	(gr_circle
		(center 64.061594 -347.302328)
		(end 64.941704 -347.302328)
		(stroke
			(width 0.2)
			(type default)
		)
		(fill no)
		(layer "In10.Cu")
	)
	(gr_circle
		(center 64.088264 -12.43711)
		(end 64.977264 -12.43711)
		(stroke
			(width 0.2)
			(type default)
		)
		(fill no)
		(layer "In10.Cu")
	)
	(gr_circle
		(center 64.33947 -166.94023)
		(end 65.21958 -166.94023)
		(stroke
			(width 0.2)
			(type default)
		)
		(fill no)
		(layer "In10.Cu")
	)
	(gr_circle
		(center 64.50203 -350.318578)
		(end 65.39103 -350.318578)
		(stroke
			(width 0.2)
			(type default)
		)
		(fill no)
		(layer "In10.Cu")
	)
	(gr_circle
		(center 64.50203 -349.581978)
		(end 65.39103 -349.581978)
		(stroke
			(width 0.2)
			(type default)
		)
		(fill no)
		(layer "In10.Cu")
	)
	(gr_circle
		(center 64.520064 -13.09751)
		(end 65.409064 -13.09751)
		(stroke
			(width 0.2)
			(type default)
		)
		(fill no)
		(layer "In10.Cu")
	)
	(gr_circle
		(center 64.95669 -166.94023)
		(end 65.8368 -166.94023)
		(stroke
			(width 0.2)
			(type default)
		)
		(fill no)
		(layer "In10.Cu")
	)
	(gr_circle
		(center 64.977264 -12.43711)
		(end 65.866264 -12.43711)
		(stroke
			(width 0.2)
			(type default)
		)
		(fill no)
		(layer "In10.Cu")
	)
	(gr_circle
		(center 65.026794 -349.142558)
		(end 65.915794 -349.142558)
		(stroke
			(width 0.2)
			(type default)
		)
		(fill no)
		(layer "In10.Cu")
	)
	(gr_circle
		(center 65.052194 -349.904558)
		(end 65.941194 -349.904558)
		(stroke
			(width 0.2)
			(type default)
		)
		(fill no)
		(layer "In10.Cu")
	)
	(gr_circle
		(center 65.409064 -13.09751)
		(end 66.298064 -13.09751)
		(stroke
			(width 0.2)
			(type default)
		)
		(fill no)
		(layer "In10.Cu")
	)
	(gr_circle
		(center 65.585594 -350.260158)
		(end 66.474594 -350.260158)
		(stroke
			(width 0.2)
			(type default)
		)
		(fill no)
		(layer "In10.Cu")
	)
	(gr_circle
		(center 65.585594 -349.523558)
		(end 66.474594 -349.523558)
		(stroke
			(width 0.2)
			(type default)
		)
		(fill no)
		(layer "In10.Cu")
	)
	(gr_circle
		(center 65.585594 -348.786958)
		(end 66.474594 -348.786958)
		(stroke
			(width 0.2)
			(type default)
		)
		(fill no)
		(layer "In10.Cu")
	)
	(gr_circle
		(center 65.866264 -12.43711)
		(end 66.755264 -12.43711)
		(stroke
			(width 0.2)
			(type default)
		)
		(fill no)
		(layer "In10.Cu")
	)
	(gr_circle
		(center 66.298064 -13.09751)
		(end 67.187064 -13.09751)
		(stroke
			(width 0.2)
			(type default)
		)
		(fill no)
		(layer "In10.Cu")
	)
	(gr_circle
		(center 66.399664 -25.56891)
		(end 67.288664 -25.56891)
		(stroke
			(width 0.2)
			(type default)
		)
		(fill no)
		(layer "In10.Cu")
	)
	(gr_circle
		(center 66.501264 -12.43711)
		(end 67.390264 -12.43711)
		(stroke
			(width 0.2)
			(type default)
		)
		(fill no)
		(layer "In10.Cu")
	)
	(gr_circle
		(center 66.774822 -20.327366)
		(end 67.663822 -20.327366)
		(stroke
			(width 0.2)
			(type default)
		)
		(fill no)
		(layer "In10.Cu")
	)
	(gr_circle
		(center 66.774822 -19.692366)
		(end 67.663822 -19.692366)
		(stroke
			(width 0.2)
			(type default)
		)
		(fill no)
		(layer "In10.Cu")
	)
	(gr_circle
		(center 66.780664 -24.88311)
		(end 67.669664 -24.88311)
		(stroke
			(width 0.2)
			(type default)
		)
		(fill no)
		(layer "In10.Cu")
	)
	(gr_circle
		(center 66.848228 -18.642584)
		(end 67.737228 -18.642584)
		(stroke
			(width 0.2)
			(type default)
		)
		(fill no)
		(layer "In10.Cu")
	)
	(gr_circle
		(center 66.882264 -22.26691)
		(end 67.771264 -22.26691)
		(stroke
			(width 0.2)
			(type default)
		)
		(fill no)
		(layer "In10.Cu")
	)
	(gr_circle
		(center 66.933064 -13.09751)
		(end 67.822064 -13.09751)
		(stroke
			(width 0.2)
			(type default)
		)
		(fill no)
		(layer "In10.Cu")
	)
	(gr_circle
		(center 67.288664 -25.56891)
		(end 68.177664 -25.56891)
		(stroke
			(width 0.2)
			(type default)
		)
		(fill no)
		(layer "In10.Cu")
	)
	(gr_circle
		(center 67.40271 -12.489434)
		(end 68.29171 -12.489434)
		(stroke
			(width 0.2)
			(type default)
		)
		(fill no)
		(layer "In10.Cu")
	)
	(gr_circle
		(center 67.669664 -24.88311)
		(end 68.558664 -24.88311)
		(stroke
			(width 0.2)
			(type default)
		)
		(fill no)
		(layer "In10.Cu")
	)
	(gr_circle
		(center 68.177664 -25.56891)
		(end 69.066664 -25.56891)
		(stroke
			(width 0.2)
			(type default)
		)
		(fill no)
		(layer "In10.Cu")
	)
	(gr_circle
		(center 68.54444 -18.476214)
		(end 69.43344 -18.476214)
		(stroke
			(width 0.2)
			(type default)
		)
		(fill no)
		(layer "In10.Cu")
	)
	(gr_circle
		(center 68.558664 -24.88311)
		(end 69.447664 -24.88311)
		(stroke
			(width 0.2)
			(type default)
		)
		(fill no)
		(layer "In10.Cu")
	)
	(gr_circle
		(center 69.498464 -24.55291)
		(end 70.387464 -24.55291)
		(stroke
			(width 0.2)
			(type default)
		)
		(fill no)
		(layer "In10.Cu")
	)
	(gr_circle
		(center 70.25005 -175.559974)
		(end 71.13905 -175.559974)
		(stroke
			(width 0.2)
			(type default)
		)
		(fill no)
		(layer "In10.Cu")
	)
	(gr_circle
		(center 70.25005 -174.823374)
		(end 71.13905 -174.823374)
		(stroke
			(width 0.2)
			(type default)
		)
		(fill no)
		(layer "In10.Cu")
	)
	(gr_circle
		(center 70.25005 -174.086774)
		(end 71.13905 -174.086774)
		(stroke
			(width 0.2)
			(type default)
		)
		(fill no)
		(layer "In10.Cu")
	)
	(gr_circle
		(center 70.78345 -174.442374)
		(end 71.67245 -174.442374)
		(stroke
			(width 0.2)
			(type default)
		)
		(fill no)
		(layer "In10.Cu")
	)
	(gr_circle
		(center 70.80885 -175.204374)
		(end 71.69785 -175.204374)
		(stroke
			(width 0.2)
			(type default)
		)
		(fill no)
		(layer "In10.Cu")
	)
	(gr_circle
		(center 71.099934 -336.988404)
		(end 71.980044 -336.988404)
		(stroke
			(width 0.2)
			(type default)
		)
		(fill no)
		(layer "In10.Cu")
	)
	(gr_circle
		(center 71.333614 -174.764954)
		(end 72.222614 -174.764954)
		(stroke
			(width 0.2)
			(type default)
		)
		(fill no)
		(layer "In10.Cu")
	)
	(gr_circle
		(center 71.333614 -174.028354)
		(end 72.222614 -174.028354)
		(stroke
			(width 0.2)
			(type default)
		)
		(fill no)
		(layer "In10.Cu")
	)
	(gr_circle
		(center 71.717154 -336.988404)
		(end 72.597264 -336.988404)
		(stroke
			(width 0.2)
			(type default)
		)
		(fill no)
		(layer "In10.Cu")
	)
	(gr_circle
		(center 71.892668 -177.10912)
		(end 72.781668 -177.10912)
		(stroke
			(width 0.2)
			(type default)
		)
		(fill no)
		(layer "In10.Cu")
	)
	(gr_circle
		(center 71.892668 -176.37252)
		(end 72.781668 -176.37252)
		(stroke
			(width 0.2)
			(type default)
		)
		(fill no)
		(layer "In10.Cu")
	)
	(gr_circle
		(center 72.03567 -175.639222)
		(end 72.91578 -175.639222)
		(stroke
			(width 0.2)
			(type default)
		)
		(fill no)
		(layer "In10.Cu")
	)
	(gr_circle
		(center 72.334374 -336.988404)
		(end 73.214484 -336.988404)
		(stroke
			(width 0.2)
			(type default)
		)
		(fill no)
		(layer "In10.Cu")
	)
	(gr_circle
		(center 72.616314 -336.255868)
		(end 73.496424 -336.255868)
		(stroke
			(width 0.2)
			(type default)
		)
		(fill no)
		(layer "In10.Cu")
	)
	(gr_circle
		(center 72.616314 -335.519268)
		(end 73.496424 -335.519268)
		(stroke
			(width 0.2)
			(type default)
		)
		(fill no)
		(layer "In10.Cu")
	)
	(gr_circle
		(center 72.65289 -175.639222)
		(end 73.533 -175.639222)
		(stroke
			(width 0.2)
			(type default)
		)
		(fill no)
		(layer "In10.Cu")
	)
	(gr_circle
		(center 73.03643 -338.597494)
		(end 73.92543 -338.597494)
		(stroke
			(width 0.2)
			(type default)
		)
		(fill no)
		(layer "In10.Cu")
	)
	(gr_circle
		(center 73.03643 -337.860894)
		(end 73.92543 -337.860894)
		(stroke
			(width 0.2)
			(type default)
		)
		(fill no)
		(layer "In10.Cu")
	)
	(gr_circle
		(center 73.27011 -175.639222)
		(end 74.15022 -175.639222)
		(stroke
			(width 0.2)
			(type default)
		)
		(fill no)
		(layer "In10.Cu")
	)
	(gr_circle
		(center 73.561194 -337.421474)
		(end 74.450194 -337.421474)
		(stroke
			(width 0.2)
			(type default)
		)
		(fill no)
		(layer "In10.Cu")
	)
	(gr_circle
		(center 73.586594 -338.183474)
		(end 74.475594 -338.183474)
		(stroke
			(width 0.2)
			(type default)
		)
		(fill no)
		(layer "In10.Cu")
	)
	(gr_circle
		(center 74.119994 -338.539074)
		(end 75.008994 -338.539074)
		(stroke
			(width 0.2)
			(type default)
		)
		(fill no)
		(layer "In10.Cu")
	)
	(gr_circle
		(center 74.119994 -337.802474)
		(end 75.008994 -337.802474)
		(stroke
			(width 0.2)
			(type default)
		)
		(fill no)
		(layer "In10.Cu")
	)
	(gr_circle
		(center 74.119994 -337.065874)
		(end 75.008994 -337.065874)
		(stroke
			(width 0.2)
			(type default)
		)
		(fill no)
		(layer "In10.Cu")
	)
	(gr_circle
		(center 74.811382 -351.637854)
		(end 75.700382 -351.637854)
		(stroke
			(width 0.2)
			(type default)
		)
		(fill no)
		(layer "In10.Cu")
	)
	(gr_circle
		(center 74.849482 -353.131374)
		(end 75.738482 -353.131374)
		(stroke
			(width 0.2)
			(type default)
		)
		(fill no)
		(layer "In10.Cu")
	)
	(gr_circle
		(center 74.849736 -352.30816)
		(end 75.738736 -352.30816)
		(stroke
			(width 0.2)
			(type default)
		)
		(fill no)
		(layer "In10.Cu")
	)
	(gr_circle
		(center 74.86015 -350.929448)
		(end 75.74915 -350.929448)
		(stroke
			(width 0.2)
			(type default)
		)
		(fill no)
		(layer "In10.Cu")
	)
	(gr_circle
		(center 77.178408 -16.520668)
		(end 78.067408 -16.520668)
		(stroke
			(width 0.2)
			(type default)
		)
		(fill no)
		(layer "In10.Cu")
	)
	(gr_circle
		(center 77.473048 -351.5995)
		(end 78.362048 -351.5995)
		(stroke
			(width 0.2)
			(type default)
		)
		(fill no)
		(layer "In10.Cu")
	)
	(gr_circle
		(center 77.511402 -352.978212)
		(end 78.400402 -352.978212)
		(stroke
			(width 0.2)
			(type default)
		)
		(fill no)
		(layer "In10.Cu")
	)
	(gr_circle
		(center 77.511402 -352.269806)
		(end 78.400402 -352.269806)
		(stroke
			(width 0.2)
			(type default)
		)
		(fill no)
		(layer "In10.Cu")
	)
	(gr_circle
		(center 77.521816 -350.891094)
		(end 78.410816 -350.891094)
		(stroke
			(width 0.2)
			(type default)
		)
		(fill no)
		(layer "In10.Cu")
	)
	(gr_circle
		(center 77.84338 -16.55064)
		(end 78.73238 -16.55064)
		(stroke
			(width 0.2)
			(type default)
		)
		(fill no)
		(layer "In10.Cu")
	)
	(gr_circle
		(center 78.85303 -178.798474)
		(end 79.74203 -178.798474)
		(stroke
			(width 0.2)
			(type default)
		)
		(fill no)
		(layer "In10.Cu")
	)
	(gr_circle
		(center 78.85303 -178.036474)
		(end 79.74203 -178.036474)
		(stroke
			(width 0.2)
			(type default)
		)
		(fill no)
		(layer "In10.Cu")
	)
	(gr_circle
		(center 79.10703 -179.560474)
		(end 79.99603 -179.560474)
		(stroke
			(width 0.2)
			(type default)
		)
		(fill no)
		(layer "In10.Cu")
	)
	(gr_circle
		(center 79.13243 -180.322474)
		(end 80.02143 -180.322474)
		(stroke
			(width 0.2)
			(type default)
		)
		(fill no)
		(layer "In10.Cu")
	)
	(gr_circle
		(center 79.403194 -178.384454)
		(end 80.292194 -178.384454)
		(stroke
			(width 0.2)
			(type default)
		)
		(fill no)
		(layer "In10.Cu")
	)
	(gr_circle
		(center 79.455518 -336.981292)
		(end 80.335628 -336.981292)
		(stroke
			(width 0.2)
			(type default)
		)
		(fill no)
		(layer "In10.Cu")
	)
	(gr_circle
		(center 79.657194 -179.883054)
		(end 80.546194 -179.883054)
		(stroke
			(width 0.2)
			(type default)
		)
		(fill no)
		(layer "In10.Cu")
	)
	(gr_circle
		(center 79.657194 -179.146454)
		(end 80.546194 -179.146454)
		(stroke
			(width 0.2)
			(type default)
		)
		(fill no)
		(layer "In10.Cu")
	)
	(gr_circle
		(center 79.921862 -18.238724)
		(end 80.810862 -18.238724)
		(stroke
			(width 0.2)
			(type default)
		)
		(fill no)
		(layer "In10.Cu")
	)
	(gr_circle
		(center 79.921862 -17.502124)
		(end 80.810862 -17.502124)
		(stroke
			(width 0.2)
			(type default)
		)
		(fill no)
		(layer "In10.Cu")
	)
	(gr_circle
		(center 80.072738 -336.981292)
		(end 80.952848 -336.981292)
		(stroke
			(width 0.2)
			(type default)
		)
		(fill no)
		(layer "In10.Cu")
	)
	(gr_circle
		(center 80.241648 -182.2196)
		(end 81.130648 -182.2196)
		(stroke
			(width 0.2)
			(type default)
		)
		(fill no)
		(layer "In10.Cu")
	)
	(gr_circle
		(center 80.241648 -181.483)
		(end 81.130648 -181.483)
		(stroke
			(width 0.2)
			(type default)
		)
		(fill no)
		(layer "In10.Cu")
	)
	(gr_circle
		(center 80.35925 -180.755544)
		(end 81.23936 -180.755544)
		(stroke
			(width 0.2)
			(type default)
		)
		(fill no)
		(layer "In10.Cu")
	)
	(gr_circle
		(center 80.689958 -336.981292)
		(end 81.570068 -336.981292)
		(stroke
			(width 0.2)
			(type default)
		)
		(fill no)
		(layer "In10.Cu")
	)
	(gr_circle
		(center 80.97647 -180.755544)
		(end 81.85658 -180.755544)
		(stroke
			(width 0.2)
			(type default)
		)
		(fill no)
		(layer "In10.Cu")
	)
	(gr_circle
		(center 80.977994 -336.245708)
		(end 81.858104 -336.245708)
		(stroke
			(width 0.2)
			(type default)
		)
		(fill no)
		(layer "In10.Cu")
	)
	(gr_circle
		(center 80.977994 -335.509108)
		(end 81.858104 -335.509108)
		(stroke
			(width 0.2)
			(type default)
		)
		(fill no)
		(layer "In10.Cu")
	)
	(gr_circle
		(center 81.392014 -338.590382)
		(end 82.281014 -338.590382)
		(stroke
			(width 0.2)
			(type default)
		)
		(fill no)
		(layer "In10.Cu")
	)
	(gr_circle
		(center 81.392014 -337.853782)
		(end 82.281014 -337.853782)
		(stroke
			(width 0.2)
			(type default)
		)
		(fill no)
		(layer "In10.Cu")
	)
	(gr_circle
		(center 81.59369 -180.755544)
		(end 82.4738 -180.755544)
		(stroke
			(width 0.2)
			(type default)
		)
		(fill no)
		(layer "In10.Cu")
	)
	(gr_arc
		(start 81.701894 -9.780016)
		(mid 82.287679 -11.194227)
		(end 83.70189 -11.780012)
		(stroke
			(width 1.016)
			(type default)
		)
		(layer "In10.Cu")
	)
	(gr_arc
		(start 81.701894 -0.500126)
		(mid 81.555625 -0.146451)
		(end 81.202022 0)
		(stroke
			(width 1.016)
			(type default)
		)
		(layer "In10.Cu")
	)
	(gr_line
		(start 81.701894 -0.500126)
		(end 81.701894 -9.780016)
		(stroke
			(width 1.016)
			(type default)
		)
		(layer "In10.Cu")
	)
	(gr_circle
		(center 81.916778 -337.414362)
		(end 82.805778 -337.414362)
		(stroke
			(width 0.2)
			(type default)
		)
		(fill no)
		(layer "In10.Cu")
	)
	(gr_circle
		(center 81.942178 -338.176362)
		(end 82.831178 -338.176362)
		(stroke
			(width 0.2)
			(type default)
		)
		(fill no)
		(layer "In10.Cu")
	)
	(gr_circle
		(center 82.183986 -348.89948)
		(end 83.072986 -348.89948)
		(stroke
			(width 0.2)
			(type default)
		)
		(fill no)
		(layer "In10.Cu")
	)
	(gr_circle
		(center 82.222086 -350.393)
		(end 83.111086 -350.393)
		(stroke
			(width 0.2)
			(type default)
		)
		(fill no)
		(layer "In10.Cu")
	)
	(gr_circle
		(center 82.22234 -349.569786)
		(end 83.11134 -349.569786)
		(stroke
			(width 0.2)
			(type default)
		)
		(fill no)
		(layer "In10.Cu")
	)
	(gr_circle
		(center 82.232754 -348.191074)
		(end 83.121754 -348.191074)
		(stroke
			(width 0.2)
			(type default)
		)
		(fill no)
		(layer "In10.Cu")
	)
	(gr_circle
		(center 82.475578 -338.531962)
		(end 83.364578 -338.531962)
		(stroke
			(width 0.2)
			(type default)
		)
		(fill no)
		(layer "In10.Cu")
	)
	(gr_circle
		(center 82.475578 -337.795362)
		(end 83.364578 -337.795362)
		(stroke
			(width 0.2)
			(type default)
		)
		(fill no)
		(layer "In10.Cu")
	)
	(gr_circle
		(center 82.475578 -337.058762)
		(end 83.364578 -337.058762)
		(stroke
			(width 0.2)
			(type default)
		)
		(fill no)
		(layer "In10.Cu")
	)
	(gr_circle
		(center 82.989674 -165.962076)
		(end 84.386674 -165.962076)
		(stroke
			(width 0.2)
			(type default)
		)
		(fill no)
		(layer "In10.Cu")
	)
	(gr_line
		(start 83.70189 -11.780012)
		(end 124.102114 -11.780012)
		(stroke
			(width 1.016)
			(type default)
		)
		(layer "In10.Cu")
	)
	(gr_circle
		(center 84.845652 -348.861126)
		(end 85.734652 -348.861126)
		(stroke
			(width 0.2)
			(type default)
		)
		(fill no)
		(layer "In10.Cu")
	)
	(gr_circle
		(center 84.884006 -350.239838)
		(end 85.773006 -350.239838)
		(stroke
			(width 0.2)
			(type default)
		)
		(fill no)
		(layer "In10.Cu")
	)
	(gr_circle
		(center 84.884006 -349.531432)
		(end 85.773006 -349.531432)
		(stroke
			(width 0.2)
			(type default)
		)
		(fill no)
		(layer "In10.Cu")
	)
	(gr_circle
		(center 84.89442 -348.15272)
		(end 85.78342 -348.15272)
		(stroke
			(width 0.2)
			(type default)
		)
		(fill no)
		(layer "In10.Cu")
	)
	(gr_circle
		(center 86.97087 -180.610002)
		(end 87.85987 -180.610002)
		(stroke
			(width 0.2)
			(type default)
		)
		(fill no)
		(layer "In10.Cu")
	)
	(gr_circle
		(center 86.97087 -179.873402)
		(end 87.85987 -179.873402)
		(stroke
			(width 0.2)
			(type default)
		)
		(fill no)
		(layer "In10.Cu")
	)
	(gr_circle
		(center 86.97087 -179.136802)
		(end 87.85987 -179.136802)
		(stroke
			(width 0.2)
			(type default)
		)
		(fill no)
		(layer "In10.Cu")
	)
	(gr_circle
		(center 87.01913 -164.097716)
		(end 87.90813 -164.097716)
		(stroke
			(width 0.2)
			(type default)
		)
		(fill no)
		(layer "In10.Cu")
	)
	(gr_circle
		(center 87.03945 -163.447476)
		(end 87.92845 -163.447476)
		(stroke
			(width 0.2)
			(type default)
		)
		(fill no)
		(layer "In10.Cu")
	)
	(gr_circle
		(center 87.03945 -162.812476)
		(end 87.92845 -162.812476)
		(stroke
			(width 0.2)
			(type default)
		)
		(fill no)
		(layer "In10.Cu")
	)
	(gr_circle
		(center 87.50427 -179.492402)
		(end 88.39327 -179.492402)
		(stroke
			(width 0.2)
			(type default)
		)
		(fill no)
		(layer "In10.Cu")
	)
	(gr_circle
		(center 87.52967 -180.254402)
		(end 88.41867 -180.254402)
		(stroke
			(width 0.2)
			(type default)
		)
		(fill no)
		(layer "In10.Cu")
	)
	(gr_circle
		(center 87.65413 -164.097716)
		(end 88.54313 -164.097716)
		(stroke
			(width 0.2)
			(type default)
		)
		(fill no)
		(layer "In10.Cu")
	)
	(gr_circle
		(center 87.67445 -163.447476)
		(end 88.56345 -163.447476)
		(stroke
			(width 0.2)
			(type default)
		)
		(fill no)
		(layer "In10.Cu")
	)
	(gr_circle
		(center 87.67445 -162.812476)
		(end 88.56345 -162.812476)
		(stroke
			(width 0.2)
			(type default)
		)
		(fill no)
		(layer "In10.Cu")
	)
	(gr_circle
		(center 87.813134 -336.966814)
		(end 88.693244 -336.966814)
		(stroke
			(width 0.2)
			(type default)
		)
		(fill no)
		(layer "In10.Cu")
	)
	(gr_circle
		(center 88.054434 -179.814982)
		(end 88.943434 -179.814982)
		(stroke
			(width 0.2)
			(type default)
		)
		(fill no)
		(layer "In10.Cu")
	)
	(gr_circle
		(center 88.054434 -179.078382)
		(end 88.943434 -179.078382)
		(stroke
			(width 0.2)
			(type default)
		)
		(fill no)
		(layer "In10.Cu")
	)
	(gr_circle
		(center 88.28913 -164.097716)
		(end 89.17813 -164.097716)
		(stroke
			(width 0.2)
			(type default)
		)
		(fill no)
		(layer "In10.Cu")
	)
	(gr_circle
		(center 88.30945 -163.447476)
		(end 89.19845 -163.447476)
		(stroke
			(width 0.2)
			(type default)
		)
		(fill no)
		(layer "In10.Cu")
	)
	(gr_circle
		(center 88.30945 -162.812476)
		(end 89.19845 -162.812476)
		(stroke
			(width 0.2)
			(type default)
		)
		(fill no)
		(layer "In10.Cu")
	)
	(gr_circle
		(center 88.430354 -336.966814)
		(end 89.310464 -336.966814)
		(stroke
			(width 0.2)
			(type default)
		)
		(fill no)
		(layer "In10.Cu")
	)
	(gr_circle
		(center 88.49233 -182.13324)
		(end 89.38133 -182.13324)
		(stroke
			(width 0.2)
			(type default)
		)
		(fill no)
		(layer "In10.Cu")
	)
	(gr_circle
		(center 88.49233 -181.39664)
		(end 89.38133 -181.39664)
		(stroke
			(width 0.2)
			(type default)
		)
		(fill no)
		(layer "In10.Cu")
	)
	(gr_circle
		(center 88.75649 -180.687472)
		(end 89.6366 -180.687472)
		(stroke
			(width 0.2)
			(type default)
		)
		(fill no)
		(layer "In10.Cu")
	)
	(gr_circle
		(center 88.92413 -164.097716)
		(end 89.81313 -164.097716)
		(stroke
			(width 0.2)
			(type default)
		)
		(fill no)
		(layer "In10.Cu")
	)
	(gr_circle
		(center 88.94445 -163.447476)
		(end 89.83345 -163.447476)
		(stroke
			(width 0.2)
			(type default)
		)
		(fill no)
		(layer "In10.Cu")
	)
	(gr_circle
		(center 88.94445 -162.812476)
		(end 89.83345 -162.812476)
		(stroke
			(width 0.2)
			(type default)
		)
		(fill no)
		(layer "In10.Cu")
	)
	(gr_circle
		(center 89.047574 -336.966814)
		(end 89.927684 -336.966814)
		(stroke
			(width 0.2)
			(type default)
		)
		(fill no)
		(layer "In10.Cu")
	)
	(gr_circle
		(center 89.314528 -345.237562)
		(end 90.203528 -345.237562)
		(stroke
			(width 0.2)
			(type default)
		)
		(fill no)
		(layer "In10.Cu")
	)
	(gr_circle
		(center 89.319354 -336.255868)
		(end 90.199464 -336.255868)
		(stroke
			(width 0.2)
			(type default)
		)
		(fill no)
		(layer "In10.Cu")
	)
	(gr_circle
		(center 89.319354 -335.519268)
		(end 90.199464 -335.519268)
		(stroke
			(width 0.2)
			(type default)
		)
		(fill no)
		(layer "In10.Cu")
	)
	(gr_circle
		(center 89.350088 -345.96959)
		(end 90.239088 -345.96959)
		(stroke
			(width 0.2)
			(type default)
		)
		(fill no)
		(layer "In10.Cu")
	)
	(gr_circle
		(center 89.37371 -180.687472)
		(end 90.25382 -180.687472)
		(stroke
			(width 0.2)
			(type default)
		)
		(fill no)
		(layer "In10.Cu")
	)
	(gr_circle
		(center 89.388442 -346.639896)
		(end 90.277442 -346.639896)
		(stroke
			(width 0.2)
			(type default)
		)
		(fill no)
		(layer "In10.Cu")
	)
	(gr_circle
		(center 89.55913 -164.097716)
		(end 90.44813 -164.097716)
		(stroke
			(width 0.2)
			(type default)
		)
		(fill no)
		(layer "In10.Cu")
	)
	(gr_circle
		(center 89.57945 -163.447476)
		(end 90.46845 -163.447476)
		(stroke
			(width 0.2)
			(type default)
		)
		(fill no)
		(layer "In10.Cu")
	)
	(gr_circle
		(center 89.57945 -162.812476)
		(end 90.46845 -162.812476)
		(stroke
			(width 0.2)
			(type default)
		)
		(fill no)
		(layer "In10.Cu")
	)
	(gr_circle
		(center 89.74963 -338.575904)
		(end 90.63863 -338.575904)
		(stroke
			(width 0.2)
			(type default)
		)
		(fill no)
		(layer "In10.Cu")
	)
	(gr_circle
		(center 89.74963 -337.839304)
		(end 90.63863 -337.839304)
		(stroke
			(width 0.2)
			(type default)
		)
		(fill no)
		(layer "In10.Cu")
	)
	(gr_circle
		(center 89.983056 -345.261184)
		(end 90.872056 -345.261184)
		(stroke
			(width 0.2)
			(type default)
		)
		(fill no)
		(layer "In10.Cu")
	)
	(gr_circle
		(center 89.985088 -345.96959)
		(end 90.874088 -345.96959)
		(stroke
			(width 0.2)
			(type default)
		)
		(fill no)
		(layer "In10.Cu")
	)
	(gr_circle
		(center 89.99093 -180.687472)
		(end 90.87104 -180.687472)
		(stroke
			(width 0.2)
			(type default)
		)
		(fill no)
		(layer "In10.Cu")
	)
	(gr_circle
		(center 90.023442 -346.639896)
		(end 90.912442 -346.639896)
		(stroke
			(width 0.2)
			(type default)
		)
		(fill no)
		(layer "In10.Cu")
	)
	(gr_circle
		(center 90.21953 -164.107876)
		(end 91.10853 -164.107876)
		(stroke
			(width 0.2)
			(type default)
		)
		(fill no)
		(layer "In10.Cu")
	)
	(gr_circle
		(center 90.23985 -163.457636)
		(end 91.12885 -163.457636)
		(stroke
			(width 0.2)
			(type default)
		)
		(fill no)
		(layer "In10.Cu")
	)
	(gr_circle
		(center 90.23985 -162.822636)
		(end 91.12885 -162.822636)
		(stroke
			(width 0.2)
			(type default)
		)
		(fill no)
		(layer "In10.Cu")
	)
	(gr_circle
		(center 90.274394 -337.399884)
		(end 91.163394 -337.399884)
		(stroke
			(width 0.2)
			(type default)
		)
		(fill no)
		(layer "In10.Cu")
	)
	(gr_circle
		(center 90.299794 -338.161884)
		(end 91.188794 -338.161884)
		(stroke
			(width 0.2)
			(type default)
		)
		(fill no)
		(layer "In10.Cu")
	)
	(gr_circle
		(center 90.618056 -345.261184)
		(end 91.507056 -345.261184)
		(stroke
			(width 0.2)
			(type default)
		)
		(fill no)
		(layer "In10.Cu")
	)
	(gr_circle
		(center 90.620088 -345.96959)
		(end 91.509088 -345.96959)
		(stroke
			(width 0.2)
			(type default)
		)
		(fill no)
		(layer "In10.Cu")
	)
	(gr_circle
		(center 90.658442 -346.639896)
		(end 91.547442 -346.639896)
		(stroke
			(width 0.2)
			(type default)
		)
		(fill no)
		(layer "In10.Cu")
	)
	(gr_circle
		(center 90.833194 -338.517484)
		(end 91.722194 -338.517484)
		(stroke
			(width 0.2)
			(type default)
		)
		(fill no)
		(layer "In10.Cu")
	)
	(gr_circle
		(center 90.833194 -337.780884)
		(end 91.722194 -337.780884)
		(stroke
			(width 0.2)
			(type default)
		)
		(fill no)
		(layer "In10.Cu")
	)
	(gr_circle
		(center 90.833194 -337.044284)
		(end 91.722194 -337.044284)
		(stroke
			(width 0.2)
			(type default)
		)
		(fill no)
		(layer "In10.Cu")
	)
	(gr_circle
		(center 91.255088 -345.96959)
		(end 92.144088 -345.96959)
		(stroke
			(width 0.2)
			(type default)
		)
		(fill no)
		(layer "In10.Cu")
	)
	(gr_circle
		(center 91.293442 -346.639896)
		(end 92.182442 -346.639896)
		(stroke
			(width 0.2)
			(type default)
		)
		(fill no)
		(layer "In10.Cu")
	)
	(gr_circle
		(center 91.380056 -345.261184)
		(end 92.269056 -345.261184)
		(stroke
			(width 0.2)
			(type default)
		)
		(fill no)
		(layer "In10.Cu")
	)
	(gr_circle
		(center 91.966288 -345.96959)
		(end 92.855288 -345.96959)
		(stroke
			(width 0.2)
			(type default)
		)
		(fill no)
		(layer "In10.Cu")
	)
	(gr_circle
		(center 92.004642 -346.639896)
		(end 92.893642 -346.639896)
		(stroke
			(width 0.2)
			(type default)
		)
		(fill no)
		(layer "In10.Cu")
	)
	(gr_circle
		(center 92.015056 -345.261184)
		(end 92.904056 -345.261184)
		(stroke
			(width 0.2)
			(type default)
		)
		(fill no)
		(layer "In10.Cu")
	)
	(gr_circle
		(center 92.387674 -165.962076)
		(end 93.784674 -165.962076)
		(stroke
			(width 0.2)
			(type default)
		)
		(fill no)
		(layer "In10.Cu")
	)
	(gr_circle
		(center 92.601288 -345.96959)
		(end 93.490288 -345.96959)
		(stroke
			(width 0.2)
			(type default)
		)
		(fill no)
		(layer "In10.Cu")
	)
	(gr_circle
		(center 92.639642 -346.639896)
		(end 93.528642 -346.639896)
		(stroke
			(width 0.2)
			(type default)
		)
		(fill no)
		(layer "In10.Cu")
	)
	(gr_circle
		(center 92.650056 -345.261184)
		(end 93.539056 -345.261184)
		(stroke
			(width 0.2)
			(type default)
		)
		(fill no)
		(layer "In10.Cu")
	)
	(gr_circle
		(center 95.36303 -180.627274)
		(end 96.25203 -180.627274)
		(stroke
			(width 0.2)
			(type default)
		)
		(fill no)
		(layer "In10.Cu")
	)
	(gr_circle
		(center 95.36303 -179.890674)
		(end 96.25203 -179.890674)
		(stroke
			(width 0.2)
			(type default)
		)
		(fill no)
		(layer "In10.Cu")
	)
	(gr_circle
		(center 95.36303 -179.154074)
		(end 96.25203 -179.154074)
		(stroke
			(width 0.2)
			(type default)
		)
		(fill no)
		(layer "In10.Cu")
	)
	(gr_circle
		(center 95.89643 -179.509674)
		(end 96.78543 -179.509674)
		(stroke
			(width 0.2)
			(type default)
		)
		(fill no)
		(layer "In10.Cu")
	)
	(gr_circle
		(center 95.92183 -180.271674)
		(end 96.81083 -180.271674)
		(stroke
			(width 0.2)
			(type default)
		)
		(fill no)
		(layer "In10.Cu")
	)
	(gr_circle
		(center 96.144334 -337.017614)
		(end 97.024444 -337.017614)
		(stroke
			(width 0.2)
			(type default)
		)
		(fill no)
		(layer "In10.Cu")
	)
	(gr_circle
		(center 96.446594 -179.832254)
		(end 97.335594 -179.832254)
		(stroke
			(width 0.2)
			(type default)
		)
		(fill no)
		(layer "In10.Cu")
	)
	(gr_circle
		(center 96.446594 -179.095654)
		(end 97.335594 -179.095654)
		(stroke
			(width 0.2)
			(type default)
		)
		(fill no)
		(layer "In10.Cu")
	)
	(gr_circle
		(center 96.761554 -337.017614)
		(end 97.641664 -337.017614)
		(stroke
			(width 0.2)
			(type default)
		)
		(fill no)
		(layer "In10.Cu")
	)
	(gr_circle
		(center 96.980248 -182.13324)
		(end 97.869248 -182.13324)
		(stroke
			(width 0.2)
			(type default)
		)
		(fill no)
		(layer "In10.Cu")
	)
	(gr_circle
		(center 96.980248 -181.39664)
		(end 97.869248 -181.39664)
		(stroke
			(width 0.2)
			(type default)
		)
		(fill no)
		(layer "In10.Cu")
	)
	(gr_circle
		(center 97.14865 -180.704744)
		(end 98.02876 -180.704744)
		(stroke
			(width 0.2)
			(type default)
		)
		(fill no)
		(layer "In10.Cu")
	)
	(gr_circle
		(center 97.378774 -337.017614)
		(end 98.258884 -337.017614)
		(stroke
			(width 0.2)
			(type default)
		)
		(fill no)
		(layer "In10.Cu")
	)
	(gr_circle
		(center 97.658174 -336.319368)
		(end 98.538284 -336.319368)
		(stroke
			(width 0.2)
			(type default)
		)
		(fill no)
		(layer "In10.Cu")
	)
	(gr_circle
		(center 97.658174 -335.582768)
		(end 98.538284 -335.582768)
		(stroke
			(width 0.2)
			(type default)
		)
		(fill no)
		(layer "In10.Cu")
	)
	(gr_circle
		(center 97.76587 -180.704744)
		(end 98.64598 -180.704744)
		(stroke
			(width 0.2)
			(type default)
		)
		(fill no)
		(layer "In10.Cu")
	)
	(gr_circle
		(center 97.981008 -278.13635)
		(end 98.235008 -278.13635)
		(stroke
			(width 0.1016)
			(type default)
		)
		(fill no)
		(layer "In10.Cu")
	)
	(gr_circle
		(center 97.981008 -276.516338)
		(end 98.235008 -276.516338)
		(stroke
			(width 0.1016)
			(type default)
		)
		(fill no)
		(layer "In10.Cu")
	)
	(gr_circle
		(center 97.981008 -274.896326)
		(end 98.235008 -274.896326)
		(stroke
			(width 0.1016)
			(type default)
		)
		(fill no)
		(layer "In10.Cu")
	)
	(gr_circle
		(center 97.981008 -273.276314)
		(end 98.235008 -273.276314)
		(stroke
			(width 0.1016)
			(type default)
		)
		(fill no)
		(layer "In10.Cu")
	)
	(gr_circle
		(center 97.981008 -271.656302)
		(end 98.235008 -271.656302)
		(stroke
			(width 0.1016)
			(type default)
		)
		(fill no)
		(layer "In10.Cu")
	)
	(gr_circle
		(center 97.981008 -270.03629)
		(end 98.235008 -270.03629)
		(stroke
			(width 0.1016)
			(type default)
		)
		(fill no)
		(layer "In10.Cu")
	)
	(gr_circle
		(center 98.08083 -338.626704)
		(end 98.96983 -338.626704)
		(stroke
			(width 0.2)
			(type default)
		)
		(fill no)
		(layer "In10.Cu")
	)
	(gr_circle
		(center 98.08083 -337.890104)
		(end 98.96983 -337.890104)
		(stroke
			(width 0.2)
			(type default)
		)
		(fill no)
		(layer "In10.Cu")
	)
	(gr_circle
		(center 98.199194 -339.358224)
		(end 99.088194 -339.358224)
		(stroke
			(width 0.2)
			(type default)
		)
		(fill no)
		(layer "In10.Cu")
	)
	(gr_circle
		(center 98.38309 -180.704744)
		(end 99.2632 -180.704744)
		(stroke
			(width 0.2)
			(type default)
		)
		(fill no)
		(layer "In10.Cu")
	)
	(gr_circle
		(center 98.605594 -337.450684)
		(end 99.494594 -337.450684)
		(stroke
			(width 0.2)
			(type default)
		)
		(fill no)
		(layer "In10.Cu")
	)
	(gr_circle
		(center 98.630994 -338.212684)
		(end 99.519994 -338.212684)
		(stroke
			(width 0.2)
			(type default)
		)
		(fill no)
		(layer "In10.Cu")
	)
	(gr_circle
		(center 98.747834 -339.736684)
		(end 99.636834 -339.736684)
		(stroke
			(width 0.2)
			(type default)
		)
		(fill no)
		(layer "In10.Cu")
	)
	(gr_circle
		(center 98.747834 -338.974684)
		(end 99.636834 -338.974684)
		(stroke
			(width 0.2)
			(type default)
		)
		(fill no)
		(layer "In10.Cu")
	)
	(gr_circle
		(center 98.921062 -278.13635)
		(end 99.175062 -278.13635)
		(stroke
			(width 0.1016)
			(type default)
		)
		(fill no)
		(layer "In10.Cu")
	)
	(gr_circle
		(center 98.921062 -276.516338)
		(end 99.175062 -276.516338)
		(stroke
			(width 0.1016)
			(type default)
		)
		(fill no)
		(layer "In10.Cu")
	)
	(gr_circle
		(center 98.921062 -274.896326)
		(end 99.175062 -274.896326)
		(stroke
			(width 0.1016)
			(type default)
		)
		(fill no)
		(layer "In10.Cu")
	)
	(gr_circle
		(center 98.921062 -273.276314)
		(end 99.175062 -273.276314)
		(stroke
			(width 0.1016)
			(type default)
		)
		(fill no)
		(layer "In10.Cu")
	)
	(gr_circle
		(center 98.921062 -271.656302)
		(end 99.175062 -271.656302)
		(stroke
			(width 0.1016)
			(type default)
		)
		(fill no)
		(layer "In10.Cu")
	)
	(gr_circle
		(center 98.921062 -270.03629)
		(end 99.175062 -270.03629)
		(stroke
			(width 0.1016)
			(type default)
		)
		(fill no)
		(layer "In10.Cu")
	)
	(gr_circle
		(center 100.800916 -278.13635)
		(end 101.054916 -278.13635)
		(stroke
			(width 0.1016)
			(type default)
		)
		(fill no)
		(layer "In10.Cu")
	)
	(gr_circle
		(center 100.800916 -276.516338)
		(end 101.054916 -276.516338)
		(stroke
			(width 0.1016)
			(type default)
		)
		(fill no)
		(layer "In10.Cu")
	)
	(gr_circle
		(center 100.800916 -274.896326)
		(end 101.054916 -274.896326)
		(stroke
			(width 0.1016)
			(type default)
		)
		(fill no)
		(layer "In10.Cu")
	)
	(gr_circle
		(center 100.800916 -273.276314)
		(end 101.054916 -273.276314)
		(stroke
			(width 0.1016)
			(type default)
		)
		(fill no)
		(layer "In10.Cu")
	)
	(gr_circle
		(center 100.800916 -271.656302)
		(end 101.054916 -271.656302)
		(stroke
			(width 0.1016)
			(type default)
		)
		(fill no)
		(layer "In10.Cu")
	)
	(gr_circle
		(center 100.800916 -270.03629)
		(end 101.054916 -270.03629)
		(stroke
			(width 0.1016)
			(type default)
		)
		(fill no)
		(layer "In10.Cu")
	)
	(gr_circle
		(center 101.74097 -278.13635)
		(end 101.99497 -278.13635)
		(stroke
			(width 0.1016)
			(type default)
		)
		(fill no)
		(layer "In10.Cu")
	)
	(gr_circle
		(center 101.74097 -276.516338)
		(end 101.99497 -276.516338)
		(stroke
			(width 0.1016)
			(type default)
		)
		(fill no)
		(layer "In10.Cu")
	)
	(gr_circle
		(center 101.74097 -274.896326)
		(end 101.99497 -274.896326)
		(stroke
			(width 0.1016)
			(type default)
		)
		(fill no)
		(layer "In10.Cu")
	)
	(gr_circle
		(center 101.74097 -273.276314)
		(end 101.99497 -273.276314)
		(stroke
			(width 0.1016)
			(type default)
		)
		(fill no)
		(layer "In10.Cu")
	)
	(gr_circle
		(center 101.74097 -271.656302)
		(end 101.99497 -271.656302)
		(stroke
			(width 0.1016)
			(type default)
		)
		(fill no)
		(layer "In10.Cu")
	)
	(gr_circle
		(center 101.74097 -270.03629)
		(end 101.99497 -270.03629)
		(stroke
			(width 0.1016)
			(type default)
		)
		(fill no)
		(layer "In10.Cu")
	)
	(gr_circle
		(center 103.621078 -278.13635)
		(end 103.875078 -278.13635)
		(stroke
			(width 0.1016)
			(type default)
		)
		(fill no)
		(layer "In10.Cu")
	)
	(gr_circle
		(center 103.621078 -276.516338)
		(end 103.875078 -276.516338)
		(stroke
			(width 0.1016)
			(type default)
		)
		(fill no)
		(layer "In10.Cu")
	)
	(gr_circle
		(center 103.621078 -274.896326)
		(end 103.875078 -274.896326)
		(stroke
			(width 0.1016)
			(type default)
		)
		(fill no)
		(layer "In10.Cu")
	)
	(gr_circle
		(center 103.621078 -273.276314)
		(end 103.875078 -273.276314)
		(stroke
			(width 0.1016)
			(type default)
		)
		(fill no)
		(layer "In10.Cu")
	)
	(gr_circle
		(center 103.621078 -271.656302)
		(end 103.875078 -271.656302)
		(stroke
			(width 0.1016)
			(type default)
		)
		(fill no)
		(layer "In10.Cu")
	)
	(gr_circle
		(center 103.621078 -270.03629)
		(end 103.875078 -270.03629)
		(stroke
			(width 0.1016)
			(type default)
		)
		(fill no)
		(layer "In10.Cu")
	)
	(gr_circle
		(center 103.74503 -176.106074)
		(end 104.63403 -176.106074)
		(stroke
			(width 0.2)
			(type default)
		)
		(fill no)
		(layer "In10.Cu")
	)
	(gr_circle
		(center 103.74503 -175.369474)
		(end 104.63403 -175.369474)
		(stroke
			(width 0.2)
			(type default)
		)
		(fill no)
		(layer "In10.Cu")
	)
	(gr_circle
		(center 103.74503 -174.632874)
		(end 104.63403 -174.632874)
		(stroke
			(width 0.2)
			(type default)
		)
		(fill no)
		(layer "In10.Cu")
	)
	(gr_circle
		(center 104.27843 -174.988474)
		(end 105.16743 -174.988474)
		(stroke
			(width 0.2)
			(type default)
		)
		(fill no)
		(layer "In10.Cu")
	)
	(gr_circle
		(center 104.30383 -175.750474)
		(end 105.19283 -175.750474)
		(stroke
			(width 0.2)
			(type default)
		)
		(fill no)
		(layer "In10.Cu")
	)
	(gr_circle
		(center 104.420162 -341.927688)
		(end 105.300272 -341.927688)
		(stroke
			(width 0.2)
			(type default)
		)
		(fill no)
		(layer "In10.Cu")
	)
	(gr_circle
		(center 104.561132 -278.13635)
		(end 104.815132 -278.13635)
		(stroke
			(width 0.1016)
			(type default)
		)
		(fill no)
		(layer "In10.Cu")
	)
	(gr_circle
		(center 104.561132 -276.516338)
		(end 104.815132 -276.516338)
		(stroke
			(width 0.1016)
			(type default)
		)
		(fill no)
		(layer "In10.Cu")
	)
	(gr_circle
		(center 104.561132 -274.896326)
		(end 104.815132 -274.896326)
		(stroke
			(width 0.1016)
			(type default)
		)
		(fill no)
		(layer "In10.Cu")
	)
	(gr_circle
		(center 104.561132 -273.276314)
		(end 104.815132 -273.276314)
		(stroke
			(width 0.1016)
			(type default)
		)
		(fill no)
		(layer "In10.Cu")
	)
	(gr_circle
		(center 104.561132 -271.656302)
		(end 104.815132 -271.656302)
		(stroke
			(width 0.1016)
			(type default)
		)
		(fill no)
		(layer "In10.Cu")
	)
	(gr_circle
		(center 104.561132 -270.03629)
		(end 104.815132 -270.03629)
		(stroke
			(width 0.1016)
			(type default)
		)
		(fill no)
		(layer "In10.Cu")
	)
	(gr_circle
		(center 104.828594 -175.311054)
		(end 105.717594 -175.311054)
		(stroke
			(width 0.2)
			(type default)
		)
		(fill no)
		(layer "In10.Cu")
	)
	(gr_circle
		(center 104.828594 -174.574454)
		(end 105.717594 -174.574454)
		(stroke
			(width 0.2)
			(type default)
		)
		(fill no)
		(layer "In10.Cu")
	)
	(gr_circle
		(center 105.037382 -341.927688)
		(end 105.917492 -341.927688)
		(stroke
			(width 0.2)
			(type default)
		)
		(fill no)
		(layer "In10.Cu")
	)
	(gr_circle
		(center 105.336848 -177.65776)
		(end 106.225848 -177.65776)
		(stroke
			(width 0.2)
			(type default)
		)
		(fill no)
		(layer "In10.Cu")
	)
	(gr_circle
		(center 105.336848 -176.92116)
		(end 106.225848 -176.92116)
		(stroke
			(width 0.2)
			(type default)
		)
		(fill no)
		(layer "In10.Cu")
	)
	(gr_circle
		(center 105.53065 -176.183544)
		(end 106.41076 -176.183544)
		(stroke
			(width 0.2)
			(type default)
		)
		(fill no)
		(layer "In10.Cu")
	)
	(gr_circle
		(center 105.654602 -341.927688)
		(end 106.534712 -341.927688)
		(stroke
			(width 0.2)
			(type default)
		)
		(fill no)
		(layer "In10.Cu")
	)
	(gr_circle
		(center 105.934002 -341.229442)
		(end 106.814112 -341.229442)
		(stroke
			(width 0.2)
			(type default)
		)
		(fill no)
		(layer "In10.Cu")
	)
	(gr_circle
		(center 105.934002 -340.492842)
		(end 106.814112 -340.492842)
		(stroke
			(width 0.2)
			(type default)
		)
		(fill no)
		(layer "In10.Cu")
	)
	(gr_circle
		(center 106.14787 -176.183544)
		(end 107.02798 -176.183544)
		(stroke
			(width 0.2)
			(type default)
		)
		(fill no)
		(layer "In10.Cu")
	)
	(gr_circle
		(center 106.34345 -343.450164)
		(end 107.23245 -343.450164)
		(stroke
			(width 0.2)
			(type default)
		)
		(fill no)
		(layer "In10.Cu")
	)
	(gr_circle
		(center 106.34345 -342.713564)
		(end 107.23245 -342.713564)
		(stroke
			(width 0.2)
			(type default)
		)
		(fill no)
		(layer "In10.Cu")
	)
	(gr_circle
		(center 106.440986 -279.756362)
		(end 106.694986 -279.756362)
		(stroke
			(width 0.1016)
			(type default)
		)
		(fill no)
		(layer "In10.Cu")
	)
	(gr_circle
		(center 106.440986 -278.13635)
		(end 106.694986 -278.13635)
		(stroke
			(width 0.1016)
			(type default)
		)
		(fill no)
		(layer "In10.Cu")
	)
	(gr_circle
		(center 106.440986 -276.516338)
		(end 106.694986 -276.516338)
		(stroke
			(width 0.1016)
			(type default)
		)
		(fill no)
		(layer "In10.Cu")
	)
	(gr_circle
		(center 106.440986 -274.896326)
		(end 106.694986 -274.896326)
		(stroke
			(width 0.1016)
			(type default)
		)
		(fill no)
		(layer "In10.Cu")
	)
	(gr_circle
		(center 106.440986 -273.276314)
		(end 106.694986 -273.276314)
		(stroke
			(width 0.1016)
			(type default)
		)
		(fill no)
		(layer "In10.Cu")
	)
	(gr_circle
		(center 106.440986 -271.656302)
		(end 106.694986 -271.656302)
		(stroke
			(width 0.1016)
			(type default)
		)
		(fill no)
		(layer "In10.Cu")
	)
	(gr_circle
		(center 106.440986 -270.03629)
		(end 106.694986 -270.03629)
		(stroke
			(width 0.1016)
			(type default)
		)
		(fill no)
		(layer "In10.Cu")
	)
	(gr_circle
		(center 106.76509 -176.183544)
		(end 107.6452 -176.183544)
		(stroke
			(width 0.2)
			(type default)
		)
		(fill no)
		(layer "In10.Cu")
	)
	(gr_circle
		(center 106.98607 -342.540844)
		(end 107.87507 -342.540844)
		(stroke
			(width 0.2)
			(type default)
		)
		(fill no)
		(layer "In10.Cu")
	)
	(gr_circle
		(center 106.98607 -341.804244)
		(end 107.87507 -341.804244)
		(stroke
			(width 0.2)
			(type default)
		)
		(fill no)
		(layer "In10.Cu")
	)
	(gr_circle
		(center 107.01401 -343.986104)
		(end 107.90301 -343.986104)
		(stroke
			(width 0.2)
			(type default)
		)
		(fill no)
		(layer "In10.Cu")
	)
	(gr_circle
		(center 107.01401 -343.249504)
		(end 107.90301 -343.249504)
		(stroke
			(width 0.2)
			(type default)
		)
		(fill no)
		(layer "In10.Cu")
	)
	(gr_circle
		(center 107.38104 -279.756362)
		(end 107.63504 -279.756362)
		(stroke
			(width 0.1016)
			(type default)
		)
		(fill no)
		(layer "In10.Cu")
	)
	(gr_circle
		(center 107.38104 -278.13635)
		(end 107.63504 -278.13635)
		(stroke
			(width 0.1016)
			(type default)
		)
		(fill no)
		(layer "In10.Cu")
	)
	(gr_circle
		(center 107.38104 -276.516338)
		(end 107.63504 -276.516338)
		(stroke
			(width 0.1016)
			(type default)
		)
		(fill no)
		(layer "In10.Cu")
	)
	(gr_circle
		(center 107.38104 -274.896326)
		(end 107.63504 -274.896326)
		(stroke
			(width 0.1016)
			(type default)
		)
		(fill no)
		(layer "In10.Cu")
	)
	(gr_circle
		(center 107.38104 -273.276314)
		(end 107.63504 -273.276314)
		(stroke
			(width 0.1016)
			(type default)
		)
		(fill no)
		(layer "In10.Cu")
	)
	(gr_circle
		(center 107.38104 -271.656302)
		(end 107.63504 -271.656302)
		(stroke
			(width 0.1016)
			(type default)
		)
		(fill no)
		(layer "In10.Cu")
	)
	(gr_circle
		(center 107.38104 -270.03629)
		(end 107.63504 -270.03629)
		(stroke
			(width 0.1016)
			(type default)
		)
		(fill no)
		(layer "In10.Cu")
	)
	(gr_circle
		(center 108.790994 -278.946356)
		(end 109.044994 -278.946356)
		(stroke
			(width 0.1016)
			(type default)
		)
		(fill no)
		(layer "In10.Cu")
	)
	(gr_circle
		(center 108.790994 -277.326344)
		(end 109.044994 -277.326344)
		(stroke
			(width 0.1016)
			(type default)
		)
		(fill no)
		(layer "In10.Cu")
	)
	(gr_circle
		(center 108.790994 -275.706332)
		(end 109.044994 -275.706332)
		(stroke
			(width 0.1016)
			(type default)
		)
		(fill no)
		(layer "In10.Cu")
	)
	(gr_circle
		(center 108.790994 -274.08632)
		(end 109.044994 -274.08632)
		(stroke
			(width 0.1016)
			(type default)
		)
		(fill no)
		(layer "In10.Cu")
	)
	(gr_circle
		(center 108.790994 -272.466308)
		(end 109.044994 -272.466308)
		(stroke
			(width 0.1016)
			(type default)
		)
		(fill no)
		(layer "In10.Cu")
	)
	(gr_circle
		(center 108.790994 -270.846296)
		(end 109.044994 -270.846296)
		(stroke
			(width 0.1016)
			(type default)
		)
		(fill no)
		(layer "In10.Cu")
	)
	(gr_circle
		(center 108.790994 -269.226284)
		(end 109.044994 -269.226284)
		(stroke
			(width 0.1016)
			(type default)
		)
		(fill no)
		(layer "In10.Cu")
	)
	(gr_circle
		(center 109.731048 -278.946356)
		(end 109.985048 -278.946356)
		(stroke
			(width 0.1016)
			(type default)
		)
		(fill no)
		(layer "In10.Cu")
	)
	(gr_circle
		(center 109.731048 -277.326344)
		(end 109.985048 -277.326344)
		(stroke
			(width 0.1016)
			(type default)
		)
		(fill no)
		(layer "In10.Cu")
	)
	(gr_circle
		(center 109.731048 -275.706332)
		(end 109.985048 -275.706332)
		(stroke
			(width 0.1016)
			(type default)
		)
		(fill no)
		(layer "In10.Cu")
	)
	(gr_circle
		(center 109.731048 -274.08632)
		(end 109.985048 -274.08632)
		(stroke
			(width 0.1016)
			(type default)
		)
		(fill no)
		(layer "In10.Cu")
	)
	(gr_circle
		(center 109.731048 -272.466308)
		(end 109.985048 -272.466308)
		(stroke
			(width 0.1016)
			(type default)
		)
		(fill no)
		(layer "In10.Cu")
	)
	(gr_circle
		(center 109.731048 -270.846296)
		(end 109.985048 -270.846296)
		(stroke
			(width 0.1016)
			(type default)
		)
		(fill no)
		(layer "In10.Cu")
	)
	(gr_circle
		(center 109.731048 -269.226284)
		(end 109.985048 -269.226284)
		(stroke
			(width 0.1016)
			(type default)
		)
		(fill no)
		(layer "In10.Cu")
	)
	(gr_circle
		(center 110.140496 -150.941786)
		(end 111.537496 -150.941786)
		(stroke
			(width 0.2)
			(type default)
		)
		(fill no)
		(layer "In10.Cu")
	)
	(gr_circle
		(center 111.97463 -169.857674)
		(end 112.86363 -169.857674)
		(stroke
			(width 0.2)
			(type default)
		)
		(fill no)
		(layer "In10.Cu")
	)
	(gr_circle
		(center 111.97463 -169.121074)
		(end 112.86363 -169.121074)
		(stroke
			(width 0.2)
			(type default)
		)
		(fill no)
		(layer "In10.Cu")
	)
	(gr_circle
		(center 111.97463 -168.384474)
		(end 112.86363 -168.384474)
		(stroke
			(width 0.2)
			(type default)
		)
		(fill no)
		(layer "In10.Cu")
	)
	(gr_circle
		(center 112.50803 -168.740074)
		(end 113.39703 -168.740074)
		(stroke
			(width 0.2)
			(type default)
		)
		(fill no)
		(layer "In10.Cu")
	)
	(gr_circle
		(center 112.53343 -169.502074)
		(end 113.42243 -169.502074)
		(stroke
			(width 0.2)
			(type default)
		)
		(fill no)
		(layer "In10.Cu")
	)
	(gr_circle
		(center 113.058194 -169.062654)
		(end 113.947194 -169.062654)
		(stroke
			(width 0.2)
			(type default)
		)
		(fill no)
		(layer "In10.Cu")
	)
	(gr_circle
		(center 113.058194 -168.326054)
		(end 113.947194 -168.326054)
		(stroke
			(width 0.2)
			(type default)
		)
		(fill no)
		(layer "In10.Cu")
	)
	(gr_circle
		(center 113.591848 -171.33316)
		(end 114.480848 -171.33316)
		(stroke
			(width 0.2)
			(type default)
		)
		(fill no)
		(layer "In10.Cu")
	)
	(gr_circle
		(center 113.591848 -170.59656)
		(end 114.480848 -170.59656)
		(stroke
			(width 0.2)
			(type default)
		)
		(fill no)
		(layer "In10.Cu")
	)
	(gr_circle
		(center 113.76025 -169.935144)
		(end 114.64036 -169.935144)
		(stroke
			(width 0.2)
			(type default)
		)
		(fill no)
		(layer "In10.Cu")
	)
	(gr_circle
		(center 114.37747 -169.935144)
		(end 115.25758 -169.935144)
		(stroke
			(width 0.2)
			(type default)
		)
		(fill no)
		(layer "In10.Cu")
	)
	(gr_circle
		(center 114.424714 -278.946356)
		(end 114.678714 -278.946356)
		(stroke
			(width 0.1016)
			(type default)
		)
		(fill no)
		(layer "In10.Cu")
	)
	(gr_circle
		(center 114.424714 -277.326344)
		(end 114.678714 -277.326344)
		(stroke
			(width 0.1016)
			(type default)
		)
		(fill no)
		(layer "In10.Cu")
	)
	(gr_circle
		(center 114.424714 -275.706332)
		(end 114.678714 -275.706332)
		(stroke
			(width 0.1016)
			(type default)
		)
		(fill no)
		(layer "In10.Cu")
	)
	(gr_circle
		(center 114.424714 -274.08632)
		(end 114.678714 -274.08632)
		(stroke
			(width 0.1016)
			(type default)
		)
		(fill no)
		(layer "In10.Cu")
	)
	(gr_circle
		(center 114.424714 -272.466308)
		(end 114.678714 -272.466308)
		(stroke
			(width 0.1016)
			(type default)
		)
		(fill no)
		(layer "In10.Cu")
	)
	(gr_circle
		(center 114.424714 -270.846296)
		(end 114.678714 -270.846296)
		(stroke
			(width 0.1016)
			(type default)
		)
		(fill no)
		(layer "In10.Cu")
	)
	(gr_circle
		(center 114.424714 -269.226284)
		(end 114.678714 -269.226284)
		(stroke
			(width 0.1016)
			(type default)
		)
		(fill no)
		(layer "In10.Cu")
	)
	(gr_circle
		(center 114.99469 -169.935144)
		(end 115.8748 -169.935144)
		(stroke
			(width 0.2)
			(type default)
		)
		(fill no)
		(layer "In10.Cu")
	)
	(gr_circle
		(center 115.364768 -278.946356)
		(end 115.618768 -278.946356)
		(stroke
			(width 0.1016)
			(type default)
		)
		(fill no)
		(layer "In10.Cu")
	)
	(gr_circle
		(center 115.364768 -277.326344)
		(end 115.618768 -277.326344)
		(stroke
			(width 0.1016)
			(type default)
		)
		(fill no)
		(layer "In10.Cu")
	)
	(gr_circle
		(center 115.364768 -275.706332)
		(end 115.618768 -275.706332)
		(stroke
			(width 0.1016)
			(type default)
		)
		(fill no)
		(layer "In10.Cu")
	)
	(gr_circle
		(center 115.364768 -274.08632)
		(end 115.618768 -274.08632)
		(stroke
			(width 0.1016)
			(type default)
		)
		(fill no)
		(layer "In10.Cu")
	)
	(gr_circle
		(center 115.364768 -272.466308)
		(end 115.618768 -272.466308)
		(stroke
			(width 0.1016)
			(type default)
		)
		(fill no)
		(layer "In10.Cu")
	)
	(gr_circle
		(center 115.364768 -270.846296)
		(end 115.618768 -270.846296)
		(stroke
			(width 0.1016)
			(type default)
		)
		(fill no)
		(layer "In10.Cu")
	)
	(gr_circle
		(center 115.364768 -269.226284)
		(end 115.618768 -269.226284)
		(stroke
			(width 0.1016)
			(type default)
		)
		(fill no)
		(layer "In10.Cu")
	)
	(gr_circle
		(center 116.258594 -152.657556)
		(end 117.147594 -152.657556)
		(stroke
			(width 0.2)
			(type default)
		)
		(fill no)
		(layer "In10.Cu")
	)
	(gr_circle
		(center 116.258594 -152.022556)
		(end 117.147594 -152.022556)
		(stroke
			(width 0.2)
			(type default)
		)
		(fill no)
		(layer "In10.Cu")
	)
	(gr_circle
		(center 116.774722 -279.756362)
		(end 117.028722 -279.756362)
		(stroke
			(width 0.1016)
			(type default)
		)
		(fill no)
		(layer "In10.Cu")
	)
	(gr_circle
		(center 116.774722 -278.13635)
		(end 117.028722 -278.13635)
		(stroke
			(width 0.1016)
			(type default)
		)
		(fill no)
		(layer "In10.Cu")
	)
	(gr_circle
		(center 116.774722 -276.516338)
		(end 117.028722 -276.516338)
		(stroke
			(width 0.1016)
			(type default)
		)
		(fill no)
		(layer "In10.Cu")
	)
	(gr_circle
		(center 116.774722 -274.896326)
		(end 117.028722 -274.896326)
		(stroke
			(width 0.1016)
			(type default)
		)
		(fill no)
		(layer "In10.Cu")
	)
	(gr_circle
		(center 116.774722 -273.276314)
		(end 117.028722 -273.276314)
		(stroke
			(width 0.1016)
			(type default)
		)
		(fill no)
		(layer "In10.Cu")
	)
	(gr_circle
		(center 116.774722 -271.656302)
		(end 117.028722 -271.656302)
		(stroke
			(width 0.1016)
			(type default)
		)
		(fill no)
		(layer "In10.Cu")
	)
	(gr_circle
		(center 116.774722 -270.03629)
		(end 117.028722 -270.03629)
		(stroke
			(width 0.1016)
			(type default)
		)
		(fill no)
		(layer "In10.Cu")
	)
	(gr_circle
		(center 116.893594 -152.657556)
		(end 117.782594 -152.657556)
		(stroke
			(width 0.2)
			(type default)
		)
		(fill no)
		(layer "In10.Cu")
	)
	(gr_circle
		(center 116.893594 -152.022556)
		(end 117.782594 -152.022556)
		(stroke
			(width 0.2)
			(type default)
		)
		(fill no)
		(layer "In10.Cu")
	)
	(gr_circle
		(center 117.559074 -152.657556)
		(end 118.448074 -152.657556)
		(stroke
			(width 0.2)
			(type default)
		)
		(fill no)
		(layer "In10.Cu")
	)
	(gr_circle
		(center 117.559074 -152.022556)
		(end 118.448074 -152.022556)
		(stroke
			(width 0.2)
			(type default)
		)
		(fill no)
		(layer "In10.Cu")
	)
	(gr_circle
		(center 117.714776 -279.756362)
		(end 117.968776 -279.756362)
		(stroke
			(width 0.1016)
			(type default)
		)
		(fill no)
		(layer "In10.Cu")
	)
	(gr_circle
		(center 117.714776 -278.13635)
		(end 117.968776 -278.13635)
		(stroke
			(width 0.1016)
			(type default)
		)
		(fill no)
		(layer "In10.Cu")
	)
	(gr_circle
		(center 117.714776 -276.516338)
		(end 117.968776 -276.516338)
		(stroke
			(width 0.1016)
			(type default)
		)
		(fill no)
		(layer "In10.Cu")
	)
	(gr_circle
		(center 117.714776 -274.896326)
		(end 117.968776 -274.896326)
		(stroke
			(width 0.1016)
			(type default)
		)
		(fill no)
		(layer "In10.Cu")
	)
	(gr_circle
		(center 117.714776 -273.276314)
		(end 117.968776 -273.276314)
		(stroke
			(width 0.1016)
			(type default)
		)
		(fill no)
		(layer "In10.Cu")
	)
	(gr_circle
		(center 117.714776 -271.656302)
		(end 117.968776 -271.656302)
		(stroke
			(width 0.1016)
			(type default)
		)
		(fill no)
		(layer "In10.Cu")
	)
	(gr_circle
		(center 117.714776 -270.03629)
		(end 117.968776 -270.03629)
		(stroke
			(width 0.1016)
			(type default)
		)
		(fill no)
		(layer "In10.Cu")
	)
	(gr_circle
		(center 118.194074 -152.657556)
		(end 119.083074 -152.657556)
		(stroke
			(width 0.2)
			(type default)
		)
		(fill no)
		(layer "In10.Cu")
	)
	(gr_circle
		(center 118.194074 -152.022556)
		(end 119.083074 -152.022556)
		(stroke
			(width 0.2)
			(type default)
		)
		(fill no)
		(layer "In10.Cu")
	)
	(gr_circle
		(center 118.829074 -152.657556)
		(end 119.718074 -152.657556)
		(stroke
			(width 0.2)
			(type default)
		)
		(fill no)
		(layer "In10.Cu")
	)
	(gr_circle
		(center 118.829074 -152.022556)
		(end 119.718074 -152.022556)
		(stroke
			(width 0.2)
			(type default)
		)
		(fill no)
		(layer "In10.Cu")
	)
	(gr_circle
		(center 119.464074 -152.657556)
		(end 120.353074 -152.657556)
		(stroke
			(width 0.2)
			(type default)
		)
		(fill no)
		(layer "In10.Cu")
	)
	(gr_circle
		(center 119.464074 -152.022556)
		(end 120.353074 -152.022556)
		(stroke
			(width 0.2)
			(type default)
		)
		(fill no)
		(layer "In10.Cu")
	)
	(gr_circle
		(center 119.59463 -278.13635)
		(end 119.84863 -278.13635)
		(stroke
			(width 0.1016)
			(type default)
		)
		(fill no)
		(layer "In10.Cu")
	)
	(gr_circle
		(center 119.59463 -276.516338)
		(end 119.84863 -276.516338)
		(stroke
			(width 0.1016)
			(type default)
		)
		(fill no)
		(layer "In10.Cu")
	)
	(gr_circle
		(center 119.59463 -274.896326)
		(end 119.84863 -274.896326)
		(stroke
			(width 0.1016)
			(type default)
		)
		(fill no)
		(layer "In10.Cu")
	)
	(gr_circle
		(center 119.59463 -273.276314)
		(end 119.84863 -273.276314)
		(stroke
			(width 0.1016)
			(type default)
		)
		(fill no)
		(layer "In10.Cu")
	)
	(gr_circle
		(center 119.59463 -271.656302)
		(end 119.84863 -271.656302)
		(stroke
			(width 0.1016)
			(type default)
		)
		(fill no)
		(layer "In10.Cu")
	)
	(gr_circle
		(center 119.59463 -270.03629)
		(end 119.84863 -270.03629)
		(stroke
			(width 0.1016)
			(type default)
		)
		(fill no)
		(layer "In10.Cu")
	)
	(gr_circle
		(center 120.25503 -163.126674)
		(end 121.14403 -163.126674)
		(stroke
			(width 0.2)
			(type default)
		)
		(fill no)
		(layer "In10.Cu")
	)
	(gr_circle
		(center 120.25503 -162.390074)
		(end 121.14403 -162.390074)
		(stroke
			(width 0.2)
			(type default)
		)
		(fill no)
		(layer "In10.Cu")
	)
	(gr_circle
		(center 120.25503 -161.653474)
		(end 121.14403 -161.653474)
		(stroke
			(width 0.2)
			(type default)
		)
		(fill no)
		(layer "In10.Cu")
	)
	(gr_circle
		(center 120.534684 -278.13635)
		(end 120.788684 -278.13635)
		(stroke
			(width 0.1016)
			(type default)
		)
		(fill no)
		(layer "In10.Cu")
	)
	(gr_circle
		(center 120.534684 -276.516338)
		(end 120.788684 -276.516338)
		(stroke
			(width 0.1016)
			(type default)
		)
		(fill no)
		(layer "In10.Cu")
	)
	(gr_circle
		(center 120.534684 -274.896326)
		(end 120.788684 -274.896326)
		(stroke
			(width 0.1016)
			(type default)
		)
		(fill no)
		(layer "In10.Cu")
	)
	(gr_circle
		(center 120.534684 -273.276314)
		(end 120.788684 -273.276314)
		(stroke
			(width 0.1016)
			(type default)
		)
		(fill no)
		(layer "In10.Cu")
	)
	(gr_circle
		(center 120.534684 -271.656302)
		(end 120.788684 -271.656302)
		(stroke
			(width 0.1016)
			(type default)
		)
		(fill no)
		(layer "In10.Cu")
	)
	(gr_circle
		(center 120.534684 -270.03629)
		(end 120.788684 -270.03629)
		(stroke
			(width 0.1016)
			(type default)
		)
		(fill no)
		(layer "In10.Cu")
	)
	(gr_circle
		(center 120.78843 -162.009074)
		(end 121.67743 -162.009074)
		(stroke
			(width 0.2)
			(type default)
		)
		(fill no)
		(layer "In10.Cu")
	)
	(gr_circle
		(center 120.81383 -162.771074)
		(end 121.70283 -162.771074)
		(stroke
			(width 0.2)
			(type default)
		)
		(fill no)
		(layer "In10.Cu")
	)
	(gr_circle
		(center 121.338594 -162.331654)
		(end 122.227594 -162.331654)
		(stroke
			(width 0.2)
			(type default)
		)
		(fill no)
		(layer "In10.Cu")
	)
	(gr_circle
		(center 121.338594 -161.595054)
		(end 122.227594 -161.595054)
		(stroke
			(width 0.2)
			(type default)
		)
		(fill no)
		(layer "In10.Cu")
	)
	(gr_circle
		(center 121.872248 -164.62756)
		(end 122.761248 -164.62756)
		(stroke
			(width 0.2)
			(type default)
		)
		(fill no)
		(layer "In10.Cu")
	)
	(gr_circle
		(center 121.872248 -163.89096)
		(end 122.761248 -163.89096)
		(stroke
			(width 0.2)
			(type default)
		)
		(fill no)
		(layer "In10.Cu")
	)
	(gr_circle
		(center 122.04065 -163.204144)
		(end 122.92076 -163.204144)
		(stroke
			(width 0.2)
			(type default)
		)
		(fill no)
		(layer "In10.Cu")
	)
	(gr_circle
		(center 122.414792 -278.13635)
		(end 122.668792 -278.13635)
		(stroke
			(width 0.1016)
			(type default)
		)
		(fill no)
		(layer "In10.Cu")
	)
	(gr_circle
		(center 122.414792 -276.516338)
		(end 122.668792 -276.516338)
		(stroke
			(width 0.1016)
			(type default)
		)
		(fill no)
		(layer "In10.Cu")
	)
	(gr_circle
		(center 122.414792 -274.896326)
		(end 122.668792 -274.896326)
		(stroke
			(width 0.1016)
			(type default)
		)
		(fill no)
		(layer "In10.Cu")
	)
	(gr_circle
		(center 122.414792 -273.276314)
		(end 122.668792 -273.276314)
		(stroke
			(width 0.1016)
			(type default)
		)
		(fill no)
		(layer "In10.Cu")
	)
	(gr_circle
		(center 122.414792 -271.656302)
		(end 122.668792 -271.656302)
		(stroke
			(width 0.1016)
			(type default)
		)
		(fill no)
		(layer "In10.Cu")
	)
	(gr_circle
		(center 122.414792 -270.03629)
		(end 122.668792 -270.03629)
		(stroke
			(width 0.1016)
			(type default)
		)
		(fill no)
		(layer "In10.Cu")
	)
	(gr_circle
		(center 122.65787 -163.204144)
		(end 123.53798 -163.204144)
		(stroke
			(width 0.2)
			(type default)
		)
		(fill no)
		(layer "In10.Cu")
	)
	(gr_circle
		(center 123.27509 -163.204144)
		(end 124.1552 -163.204144)
		(stroke
			(width 0.2)
			(type default)
		)
		(fill no)
		(layer "In10.Cu")
	)
	(gr_circle
		(center 123.354846 -278.13635)
		(end 123.608846 -278.13635)
		(stroke
			(width 0.1016)
			(type default)
		)
		(fill no)
		(layer "In10.Cu")
	)
	(gr_circle
		(center 123.354846 -276.516338)
		(end 123.608846 -276.516338)
		(stroke
			(width 0.1016)
			(type default)
		)
		(fill no)
		(layer "In10.Cu")
	)
	(gr_circle
		(center 123.354846 -274.896326)
		(end 123.608846 -274.896326)
		(stroke
			(width 0.1016)
			(type default)
		)
		(fill no)
		(layer "In10.Cu")
	)
	(gr_circle
		(center 123.354846 -273.276314)
		(end 123.608846 -273.276314)
		(stroke
			(width 0.1016)
			(type default)
		)
		(fill no)
		(layer "In10.Cu")
	)
	(gr_circle
		(center 123.354846 -271.656302)
		(end 123.608846 -271.656302)
		(stroke
			(width 0.1016)
			(type default)
		)
		(fill no)
		(layer "In10.Cu")
	)
	(gr_circle
		(center 123.354846 -270.03629)
		(end 123.608846 -270.03629)
		(stroke
			(width 0.1016)
			(type default)
		)
		(fill no)
		(layer "In10.Cu")
	)
	(gr_arc
		(start 124.102114 -11.780012)
		(mid 125.516325 -11.194227)
		(end 126.10211 -9.780016)
		(stroke
			(width 1.016)
			(type default)
		)
		(layer "In10.Cu")
	)
	(gr_circle
		(center 125.2347 -278.13635)
		(end 125.4887 -278.13635)
		(stroke
			(width 0.1016)
			(type default)
		)
		(fill no)
		(layer "In10.Cu")
	)
	(gr_circle
		(center 125.2347 -276.516338)
		(end 125.4887 -276.516338)
		(stroke
			(width 0.1016)
			(type default)
		)
		(fill no)
		(layer "In10.Cu")
	)
	(gr_circle
		(center 125.2347 -274.896326)
		(end 125.4887 -274.896326)
		(stroke
			(width 0.1016)
			(type default)
		)
		(fill no)
		(layer "In10.Cu")
	)
	(gr_circle
		(center 125.2347 -273.276314)
		(end 125.4887 -273.276314)
		(stroke
			(width 0.1016)
			(type default)
		)
		(fill no)
		(layer "In10.Cu")
	)
	(gr_circle
		(center 125.2347 -271.656302)
		(end 125.4887 -271.656302)
		(stroke
			(width 0.1016)
			(type default)
		)
		(fill no)
		(layer "In10.Cu")
	)
	(gr_circle
		(center 125.2347 -270.03629)
		(end 125.4887 -270.03629)
		(stroke
			(width 0.1016)
			(type default)
		)
		(fill no)
		(layer "In10.Cu")
	)
	(gr_line
		(start 126.10211 -9.780016)
		(end 126.10211 -5.780024)
		(stroke
			(width 1.016)
			(type default)
		)
		(layer "In10.Cu")
	)
	(gr_circle
		(center 126.174754 -278.13635)
		(end 126.428754 -278.13635)
		(stroke
			(width 0.1016)
			(type default)
		)
		(fill no)
		(layer "In10.Cu")
	)
	(gr_circle
		(center 126.174754 -276.516338)
		(end 126.428754 -276.516338)
		(stroke
			(width 0.1016)
			(type default)
		)
		(fill no)
		(layer "In10.Cu")
	)
	(gr_circle
		(center 126.174754 -274.896326)
		(end 126.428754 -274.896326)
		(stroke
			(width 0.1016)
			(type default)
		)
		(fill no)
		(layer "In10.Cu")
	)
	(gr_circle
		(center 126.174754 -273.276314)
		(end 126.428754 -273.276314)
		(stroke
			(width 0.1016)
			(type default)
		)
		(fill no)
		(layer "In10.Cu")
	)
	(gr_circle
		(center 126.174754 -271.656302)
		(end 126.428754 -271.656302)
		(stroke
			(width 0.1016)
			(type default)
		)
		(fill no)
		(layer "In10.Cu")
	)
	(gr_circle
		(center 126.174754 -270.03629)
		(end 126.428754 -270.03629)
		(stroke
			(width 0.1016)
			(type default)
		)
		(fill no)
		(layer "In10.Cu")
	)
	(gr_arc
		(start 126.601982 -5.279898)
		(mid 126.248489 -5.42646)
		(end 126.10211 -5.780024)
		(stroke
			(width 1.016)
			(type default)
		)
		(layer "In10.Cu")
	)
	(gr_line
		(start 126.601982 -5.279898)
		(end 194.20205 -5.279898)
		(stroke
			(width 1.016)
			(type default)
		)
		(layer "In10.Cu")
	)
	(gr_circle
		(center 128.71323 -154.465274)
		(end 129.60223 -154.465274)
		(stroke
			(width 0.2)
			(type default)
		)
		(fill no)
		(layer "In10.Cu")
	)
	(gr_circle
		(center 128.71323 -153.728674)
		(end 129.60223 -153.728674)
		(stroke
			(width 0.2)
			(type default)
		)
		(fill no)
		(layer "In10.Cu")
	)
	(gr_circle
		(center 128.71323 -152.992074)
		(end 129.60223 -152.992074)
		(stroke
			(width 0.2)
			(type default)
		)
		(fill no)
		(layer "In10.Cu")
	)
	(gr_circle
		(center 129.24663 -153.347674)
		(end 130.13563 -153.347674)
		(stroke
			(width 0.2)
			(type default)
		)
		(fill no)
		(layer "In10.Cu")
	)
	(gr_circle
		(center 129.27203 -154.109674)
		(end 130.16103 -154.109674)
		(stroke
			(width 0.2)
			(type default)
		)
		(fill no)
		(layer "In10.Cu")
	)
	(gr_circle
		(center 129.796794 -153.670254)
		(end 130.685794 -153.670254)
		(stroke
			(width 0.2)
			(type default)
		)
		(fill no)
		(layer "In10.Cu")
	)
	(gr_circle
		(center 129.796794 -152.933654)
		(end 130.685794 -152.933654)
		(stroke
			(width 0.2)
			(type default)
		)
		(fill no)
		(layer "In10.Cu")
	)
	(gr_circle
		(center 130.305048 -155.94076)
		(end 131.194048 -155.94076)
		(stroke
			(width 0.2)
			(type default)
		)
		(fill no)
		(layer "In10.Cu")
	)
	(gr_circle
		(center 130.305048 -155.20416)
		(end 131.194048 -155.20416)
		(stroke
			(width 0.2)
			(type default)
		)
		(fill no)
		(layer "In10.Cu")
	)
	(gr_circle
		(center 130.49885 -154.542744)
		(end 131.37896 -154.542744)
		(stroke
			(width 0.2)
			(type default)
		)
		(fill no)
		(layer "In10.Cu")
	)
	(gr_circle
		(center 131.11607 -154.542744)
		(end 131.99618 -154.542744)
		(stroke
			(width 0.2)
			(type default)
		)
		(fill no)
		(layer "In10.Cu")
	)
	(gr_circle
		(center 131.73329 -154.542744)
		(end 132.6134 -154.542744)
		(stroke
			(width 0.2)
			(type default)
		)
		(fill no)
		(layer "In10.Cu")
	)
	(gr_circle
		(center 176.332134 -26.634948)
		(end 177.221134 -26.634948)
		(stroke
			(width 0.2)
			(type default)
		)
		(fill no)
		(layer "In10.Cu")
	)
	(gr_circle
		(center 176.713134 -25.949148)
		(end 177.602134 -25.949148)
		(stroke
			(width 0.2)
			(type default)
		)
		(fill no)
		(layer "In10.Cu")
	)
	(gr_circle
		(center 176.878234 -19.942048)
		(end 177.767234 -19.942048)
		(stroke
			(width 0.2)
			(type default)
		)
		(fill no)
		(layer "In10.Cu")
	)
	(gr_circle
		(center 176.968912 -21.349208)
		(end 177.857912 -21.349208)
		(stroke
			(width 0.2)
			(type default)
		)
		(fill no)
		(layer "In10.Cu")
	)
	(gr_circle
		(center 176.968912 -20.714208)
		(end 177.857912 -20.714208)
		(stroke
			(width 0.2)
			(type default)
		)
		(fill no)
		(layer "In10.Cu")
	)
	(gr_circle
		(center 177.221134 -26.634948)
		(end 178.110134 -26.634948)
		(stroke
			(width 0.2)
			(type default)
		)
		(fill no)
		(layer "In10.Cu")
	)
	(gr_circle
		(center 177.472594 -21.85289)
		(end 178.361594 -21.85289)
		(stroke
			(width 0.2)
			(type default)
		)
		(fill no)
		(layer "In10.Cu")
	)
	(gr_circle
		(center 177.602134 -25.949148)
		(end 178.491134 -25.949148)
		(stroke
			(width 0.2)
			(type default)
		)
		(fill no)
		(layer "In10.Cu")
	)
	(gr_circle
		(center 178.110134 -26.634948)
		(end 178.999134 -26.634948)
		(stroke
			(width 0.2)
			(type default)
		)
		(fill no)
		(layer "In10.Cu")
	)
	(gr_circle
		(center 178.491134 -25.949148)
		(end 179.380134 -25.949148)
		(stroke
			(width 0.2)
			(type default)
		)
		(fill no)
		(layer "In10.Cu")
	)
	(gr_circle
		(center 179.507134 -25.517348)
		(end 180.396134 -25.517348)
		(stroke
			(width 0.2)
			(type default)
		)
		(fill no)
		(layer "In10.Cu")
	)
	(gr_circle
		(center 180.921914 -27.107388)
		(end 181.810914 -27.107388)
		(stroke
			(width 0.2)
			(type default)
		)
		(fill no)
		(layer "In10.Cu")
	)
	(gr_circle
		(center 183.610758 -353.283774)
		(end 184.490868 -353.283774)
		(stroke
			(width 0.2)
			(type default)
		)
		(fill no)
		(layer "In10.Cu")
	)
	(gr_circle
		(center 184.227978 -353.283774)
		(end 185.108088 -353.283774)
		(stroke
			(width 0.2)
			(type default)
		)
		(fill no)
		(layer "In10.Cu")
	)
	(gr_line
		(start 184.258458 -410.708348)
		(end 184.258458 -400.09572)
		(stroke
			(width 0.635)
			(type default)
		)
		(layer "In10.Cu")
	)
	(gr_line
		(start 184.258458 -400.09572)
		(end 184.463944 -399.890234)
		(stroke
			(width 0.635)
			(type default)
		)
		(layer "In10.Cu")
	)
	(gr_line
		(start 184.463944 -399.890234)
		(end 188.119004 -399.890234)
		(stroke
			(width 0.635)
			(type default)
		)
		(layer "In10.Cu")
	)
	(gr_line
		(start 184.8104 -411.26029)
		(end 184.258458 -410.708348)
		(stroke
			(width 0.635)
			(type default)
		)
		(layer "In10.Cu")
	)
	(gr_circle
		(center 184.845198 -353.283774)
		(end 185.725308 -353.283774)
		(stroke
			(width 0.2)
			(type default)
		)
		(fill no)
		(layer "In10.Cu")
	)
	(gr_circle
		(center 184.962292 -352.558604)
		(end 185.851292 -352.558604)
		(stroke
			(width 0.2)
			(type default)
		)
		(fill no)
		(layer "In10.Cu")
	)
	(gr_circle
		(center 184.962292 -351.822004)
		(end 185.851292 -351.822004)
		(stroke
			(width 0.2)
			(type default)
		)
		(fill no)
		(layer "In10.Cu")
	)
	(gr_circle
		(center 185.547254 -354.892864)
		(end 186.436254 -354.892864)
		(stroke
			(width 0.2)
			(type default)
		)
		(fill no)
		(layer "In10.Cu")
	)
	(gr_circle
		(center 185.547254 -354.156264)
		(end 186.436254 -354.156264)
		(stroke
			(width 0.2)
			(type default)
		)
		(fill no)
		(layer "In10.Cu")
	)
	(gr_circle
		(center 186.034172 -362.234988)
		(end 186.923172 -362.234988)
		(stroke
			(width 0.2)
			(type default)
		)
		(fill no)
		(layer "In10.Cu")
	)
	(gr_circle
		(center 186.034172 -361.472988)
		(end 186.923172 -361.472988)
		(stroke
			(width 0.2)
			(type default)
		)
		(fill no)
		(layer "In10.Cu")
	)
	(gr_circle
		(center 186.034172 -360.710988)
		(end 186.923172 -360.710988)
		(stroke
			(width 0.2)
			(type default)
		)
		(fill no)
		(layer "In10.Cu")
	)
	(gr_circle
		(center 186.072018 -353.716844)
		(end 186.961018 -353.716844)
		(stroke
			(width 0.2)
			(type default)
		)
		(fill no)
		(layer "In10.Cu")
	)
	(gr_circle
		(center 186.097418 -354.478844)
		(end 186.986418 -354.478844)
		(stroke
			(width 0.2)
			(type default)
		)
		(fill no)
		(layer "In10.Cu")
	)
	(gr_circle
		(center 186.630818 -354.834444)
		(end 187.519818 -354.834444)
		(stroke
			(width 0.2)
			(type default)
		)
		(fill no)
		(layer "In10.Cu")
	)
	(gr_circle
		(center 186.630818 -354.097844)
		(end 187.519818 -354.097844)
		(stroke
			(width 0.2)
			(type default)
		)
		(fill no)
		(layer "In10.Cu")
	)
	(gr_circle
		(center 186.630818 -353.361244)
		(end 187.519818 -353.361244)
		(stroke
			(width 0.2)
			(type default)
		)
		(fill no)
		(layer "In10.Cu")
	)
	(gr_circle
		(center 186.796172 -362.234988)
		(end 187.685172 -362.234988)
		(stroke
			(width 0.2)
			(type default)
		)
		(fill no)
		(layer "In10.Cu")
	)
	(gr_circle
		(center 186.796172 -361.472988)
		(end 187.685172 -361.472988)
		(stroke
			(width 0.2)
			(type default)
		)
		(fill no)
		(layer "In10.Cu")
	)
	(gr_circle
		(center 186.796172 -360.710988)
		(end 187.685172 -360.710988)
		(stroke
			(width 0.2)
			(type default)
		)
		(fill no)
		(layer "In10.Cu")
	)
	(gr_line
		(start 187.965334 -411.26029)
		(end 184.8104 -411.26029)
		(stroke
			(width 0.635)
			(type default)
		)
		(layer "In10.Cu")
	)
	(gr_line
		(start 188.119004 -399.890234)
		(end 188.303916 -400.075146)
		(stroke
			(width 0.635)
			(type default)
		)
		(layer "In10.Cu")
	)
	(gr_line
		(start 188.303916 -402.905976)
		(end 191.073786 -405.675846)
		(stroke
			(width 0.635)
			(type default)
		)
		(layer "In10.Cu")
	)
	(gr_line
		(start 188.303916 -400.075146)
		(end 188.303916 -402.905976)
		(stroke
			(width 0.635)
			(type default)
		)
		(layer "In10.Cu")
	)
	(gr_line
		(start 188.720222 -412.015178)
		(end 187.965334 -411.26029)
		(stroke
			(width 0.635)
			(type default)
		)
		(layer "In10.Cu")
	)
	(gr_circle
		(center 190.508636 -23.593552)
		(end 191.397636 -23.593552)
		(stroke
			(width 0.2)
			(type default)
		)
		(fill no)
		(layer "In10.Cu")
	)
	(gr_circle
		(center 190.508636 -22.856952)
		(end 191.397636 -22.856952)
		(stroke
			(width 0.2)
			(type default)
		)
		(fill no)
		(layer "In10.Cu")
	)
	(gr_line
		(start 191.073786 -405.675846)
		(end 195.418964 -405.675846)
		(stroke
			(width 0.635)
			(type default)
		)
		(layer "In10.Cu")
	)
	(gr_circle
		(center 191.67983 -362.430568)
		(end 193.07683 -362.430568)
		(stroke
			(width 0.2)
			(type default)
		)
		(fill no)
		(layer "In10.Cu")
	)
	(gr_circle
		(center 191.927734 -13.106908)
		(end 192.816734 -13.106908)
		(stroke
			(width 0.2)
			(type default)
		)
		(fill no)
		(layer "In10.Cu")
	)
	(gr_circle
		(center 191.937386 -353.309174)
		(end 192.817496 -353.309174)
		(stroke
			(width 0.2)
			(type default)
		)
		(fill no)
		(layer "In10.Cu")
	)
	(gr_circle
		(center 192.461134 -16.416528)
		(end 193.350134 -16.416528)
		(stroke
			(width 0.2)
			(type default)
		)
		(fill no)
		(layer "In10.Cu")
	)
	(gr_circle
		(center 192.461134 -15.781528)
		(end 193.350134 -15.781528)
		(stroke
			(width 0.2)
			(type default)
		)
		(fill no)
		(layer "In10.Cu")
	)
	(gr_circle
		(center 192.554606 -353.309174)
		(end 193.434716 -353.309174)
		(stroke
			(width 0.2)
			(type default)
		)
		(fill no)
		(layer "In10.Cu")
	)
	(gr_circle
		(center 192.689734 -13.106908)
		(end 193.578734 -13.106908)
		(stroke
			(width 0.2)
			(type default)
		)
		(fill no)
		(layer "In10.Cu")
	)
	(gr_circle
		(center 193.096134 -16.416528)
		(end 193.985134 -16.416528)
		(stroke
			(width 0.2)
			(type default)
		)
		(fill no)
		(layer "In10.Cu")
	)
	(gr_circle
		(center 193.096134 -15.781528)
		(end 193.985134 -15.781528)
		(stroke
			(width 0.2)
			(type default)
		)
		(fill no)
		(layer "In10.Cu")
	)
	(gr_circle
		(center 193.171826 -353.309174)
		(end 194.051936 -353.309174)
		(stroke
			(width 0.2)
			(type default)
		)
		(fill no)
		(layer "In10.Cu")
	)
	(gr_circle
		(center 193.28892 -352.563684)
		(end 194.17792 -352.563684)
		(stroke
			(width 0.2)
			(type default)
		)
		(fill no)
		(layer "In10.Cu")
	)
	(gr_circle
		(center 193.28892 -351.827084)
		(end 194.17792 -351.827084)
		(stroke
			(width 0.2)
			(type default)
		)
		(fill no)
		(layer "In10.Cu")
	)
	(gr_circle
		(center 193.731134 -15.781528)
		(end 194.620134 -15.781528)
		(stroke
			(width 0.2)
			(type default)
		)
		(fill no)
		(layer "In10.Cu")
	)
	(gr_circle
		(center 193.858134 -16.543528)
		(end 194.747134 -16.543528)
		(stroke
			(width 0.2)
			(type default)
		)
		(fill no)
		(layer "In10.Cu")
	)
	(gr_circle
		(center 193.873882 -354.918264)
		(end 194.762882 -354.918264)
		(stroke
			(width 0.2)
			(type default)
		)
		(fill no)
		(layer "In10.Cu")
	)
	(gr_circle
		(center 193.873882 -354.181664)
		(end 194.762882 -354.181664)
		(stroke
			(width 0.2)
			(type default)
		)
		(fill no)
		(layer "In10.Cu")
	)
	(gr_circle
		(center 194.398646 -353.742244)
		(end 195.287646 -353.742244)
		(stroke
			(width 0.2)
			(type default)
		)
		(fill no)
		(layer "In10.Cu")
	)
	(gr_circle
		(center 194.424046 -354.504244)
		(end 195.313046 -354.504244)
		(stroke
			(width 0.2)
			(type default)
		)
		(fill no)
		(layer "In10.Cu")
	)
	(gr_line
		(start 194.505072 -441.989972)
		(end 8.50011 -441.989972)
		(stroke
			(width 1.016)
			(type default)
		)
		(layer "In10.Cu")
	)
	(gr_arc
		(start 194.505072 -441.989972)
		(mid 194.858553 -441.843573)
		(end 195.004944 -441.4901)
		(stroke
			(width 1.016)
			(type default)
		)
		(layer "In10.Cu")
	)
	(gr_arc
		(start 194.701922 -9.780016)
		(mid 195.287707 -11.194227)
		(end 196.701918 -11.780012)
		(stroke
			(width 1.016)
			(type default)
		)
		(layer "In10.Cu")
	)
	(gr_arc
		(start 194.701922 -5.780024)
		(mid 194.555654 -5.42634)
		(end 194.20205 -5.279898)
		(stroke
			(width 1.016)
			(type default)
		)
		(layer "In10.Cu")
	)
	(gr_line
		(start 194.701922 -5.780024)
		(end 194.701922 -9.780016)
		(stroke
			(width 1.016)
			(type default)
		)
		(layer "In10.Cu")
	)
	(gr_circle
		(center 194.957446 -354.859844)
		(end 195.846446 -354.859844)
		(stroke
			(width 0.2)
			(type default)
		)
		(fill no)
		(layer "In10.Cu")
	)
	(gr_circle
		(center 194.957446 -354.123244)
		(end 195.846446 -354.123244)
		(stroke
			(width 0.2)
			(type default)
		)
		(fill no)
		(layer "In10.Cu")
	)
	(gr_circle
		(center 194.957446 -353.386644)
		(end 195.846446 -353.386644)
		(stroke
			(width 0.2)
			(type default)
		)
		(fill no)
		(layer "In10.Cu")
	)
	(gr_line
		(start 195.004944 -441.17006)
		(end 195.004944 -441.4901)
		(stroke
			(width 1.016)
			(type default)
		)
		(layer "In10.Cu")
	)
	(gr_line
		(start 195.270882 -412.015178)
		(end 188.720222 -412.015178)
		(stroke
			(width 0.635)
			(type default)
		)
		(layer "In10.Cu")
	)
	(gr_line
		(start 195.418964 -405.675846)
		(end 197.51167 -403.58314)
		(stroke
			(width 0.635)
			(type default)
		)
		(layer "In10.Cu")
	)
	(gr_arc
		(start 195.50507 -440.669934)
		(mid 195.151428 -440.816418)
		(end 195.004944 -441.17006)
		(stroke
			(width 1.016)
			(type default)
		)
		(layer "In10.Cu")
	)
	(gr_line
		(start 196.432424 -421.71112)
		(end 196.432424 -413.17672)
		(stroke
			(width 0.635)
			(type default)
		)
		(layer "In10.Cu")
	)
	(gr_line
		(start 196.432424 -421.71112)
		(end 205.73746 -431.016156)
		(stroke
			(width 0.635)
			(type default)
		)
		(layer "In10.Cu")
	)
	(gr_line
		(start 196.432424 -413.17672)
		(end 195.270882 -412.015178)
		(stroke
			(width 0.635)
			(type default)
		)
		(layer "In10.Cu")
	)
	(gr_line
		(start 196.701918 -11.780012)
		(end 221.30004 -11.780012)
		(stroke
			(width 1.016)
			(type default)
		)
		(layer "In10.Cu")
	)
	(gr_line
		(start 197.51167 -403.58314)
		(end 197.51167 -400.104356)
		(stroke
			(width 0.635)
			(type default)
		)
		(layer "In10.Cu")
	)
	(gr_line
		(start 197.51167 -400.104356)
		(end 197.764146 -399.85188)
		(stroke
			(width 0.635)
			(type default)
		)
		(layer "In10.Cu")
	)
	(gr_line
		(start 197.764146 -399.85188)
		(end 201.33818 -399.85188)
		(stroke
			(width 0.635)
			(type default)
		)
		(layer "In10.Cu")
	)
	(gr_circle
		(center 198.160386 -37.328094)
		(end 199.049386 -37.328094)
		(stroke
			(width 0.2)
			(type default)
		)
		(fill no)
		(layer "In10.Cu")
	)
	(gr_circle
		(center 198.486014 -30.133798)
		(end 199.375014 -30.133798)
		(stroke
			(width 0.2)
			(type default)
		)
		(fill no)
		(layer "In10.Cu")
	)
	(gr_circle
		(center 198.836026 -37.965634)
		(end 199.725026 -37.965634)
		(stroke
			(width 0.2)
			(type default)
		)
		(fill no)
		(layer "In10.Cu")
	)
	(gr_circle
		(center 199.121014 -30.133798)
		(end 200.010014 -30.133798)
		(stroke
			(width 0.2)
			(type default)
		)
		(fill no)
		(layer "In10.Cu")
	)
	(gr_circle
		(center 199.435974 -30.720538)
		(end 200.324974 -30.720538)
		(stroke
			(width 0.2)
			(type default)
		)
		(fill no)
		(layer "In10.Cu")
	)
	(gr_circle
		(center 199.756014 -30.133798)
		(end 200.645014 -30.133798)
		(stroke
			(width 0.2)
			(type default)
		)
		(fill no)
		(layer "In10.Cu")
	)
	(gr_circle
		(center 200.070974 -30.720538)
		(end 200.959974 -30.720538)
		(stroke
			(width 0.2)
			(type default)
		)
		(fill no)
		(layer "In10.Cu")
	)
	(gr_circle
		(center 200.33234 -378.160534)
		(end 201.22134 -378.160534)
		(stroke
			(width 0.2)
			(type default)
		)
		(fill no)
		(layer "In10.Cu")
	)
	(gr_circle
		(center 200.391014 -30.133798)
		(end 201.280014 -30.133798)
		(stroke
			(width 0.2)
			(type default)
		)
		(fill no)
		(layer "In10.Cu")
	)
	(gr_circle
		(center 200.705974 -30.720538)
		(end 201.594974 -30.720538)
		(stroke
			(width 0.2)
			(type default)
		)
		(fill no)
		(layer "In10.Cu")
	)
	(gr_line
		(start 201.33818 -399.85188)
		(end 201.59853 -400.11223)
		(stroke
			(width 0.635)
			(type default)
		)
		(layer "In10.Cu")
	)
	(gr_circle
		(center 201.340974 -30.720538)
		(end 202.229974 -30.720538)
		(stroke
			(width 0.2)
			(type default)
		)
		(fill no)
		(layer "In10.Cu")
	)
	(gr_line
		(start 201.59853 -403.575266)
		(end 201.811636 -403.788372)
		(stroke
			(width 0.635)
			(type default)
		)
		(layer "In10.Cu")
	)
	(gr_line
		(start 201.59853 -400.11223)
		(end 201.59853 -403.575266)
		(stroke
			(width 0.635)
			(type default)
		)
		(layer "In10.Cu")
	)
	(gr_circle
		(center 201.745342 -346.583)
		(end 202.634342 -346.583)
		(stroke
			(width 0.2)
			(type default)
		)
		(fill no)
		(layer "In10.Cu")
	)
	(gr_circle
		(center 201.745342 -345.821)
		(end 202.634342 -345.821)
		(stroke
			(width 0.2)
			(type default)
		)
		(fill no)
		(layer "In10.Cu")
	)
	(gr_circle
		(center 201.745342 -344.8304)
		(end 202.634342 -344.8304)
		(stroke
			(width 0.2)
			(type default)
		)
		(fill no)
		(layer "In10.Cu")
	)
	(gr_circle
		(center 201.745342 -344.0684)
		(end 202.634342 -344.0684)
		(stroke
			(width 0.2)
			(type default)
		)
		(fill no)
		(layer "In10.Cu")
	)
	(gr_line
		(start 201.811636 -406.668732)
		(end 203.461112 -408.318208)
		(stroke
			(width 0.635)
			(type default)
		)
		(layer "In10.Cu")
	)
	(gr_line
		(start 201.811636 -403.788372)
		(end 201.811636 -406.668732)
		(stroke
			(width 0.635)
			(type default)
		)
		(layer "In10.Cu")
	)
	(gr_line
		(start 203.461112 -408.318208)
		(end 205.948026 -408.318208)
		(stroke
			(width 0.635)
			(type default)
		)
		(layer "In10.Cu")
	)
	(gr_line
		(start 205.73746 -435.231032)
		(end 207.302608 -436.79618)
		(stroke
			(width 0.635)
			(type default)
		)
		(layer "In10.Cu")
	)
	(gr_line
		(start 205.73746 -431.016156)
		(end 205.73746 -435.231032)
		(stroke
			(width 0.635)
			(type default)
		)
		(layer "In10.Cu")
	)
	(gr_line
		(start 205.948026 -408.318208)
		(end 207.991202 -406.275032)
		(stroke
			(width 0.635)
			(type default)
		)
		(layer "In10.Cu")
	)
	(gr_line
		(start 207.302608 -436.79618)
		(end 229.074472 -436.79618)
		(stroke
			(width 0.635)
			(type default)
		)
		(layer "In10.Cu")
	)
	(gr_line
		(start 207.991202 -406.275032)
		(end 207.991202 -403.722586)
		(stroke
			(width 0.635)
			(type default)
		)
		(layer "In10.Cu")
	)
	(gr_line
		(start 207.991202 -403.722586)
		(end 208.17967 -403.534118)
		(stroke
			(width 0.635)
			(type default)
		)
		(layer "In10.Cu")
	)
	(gr_line
		(start 208.17967 -403.534118)
		(end 208.17967 -400.079464)
		(stroke
			(width 0.635)
			(type default)
		)
		(layer "In10.Cu")
	)
	(gr_line
		(start 208.17967 -400.079464)
		(end 208.42605 -399.833084)
		(stroke
			(width 0.635)
			(type default)
		)
		(layer "In10.Cu")
	)
	(gr_line
		(start 208.42605 -399.833084)
		(end 211.971128 -399.833084)
		(stroke
			(width 0.635)
			(type default)
		)
		(layer "In10.Cu")
	)
	(gr_circle
		(center 208.508854 -37.366448)
		(end 209.397854 -37.366448)
		(stroke
			(width 0.2)
			(type default)
		)
		(fill no)
		(layer "In10.Cu")
	)
	(gr_line
		(start 211.971128 -399.833084)
		(end 212.28304 -400.144996)
		(stroke
			(width 0.635)
			(type default)
		)
		(layer "In10.Cu")
	)
	(gr_line
		(start 212.28304 -403.63267)
		(end 212.414358 -403.763988)
		(stroke
			(width 0.635)
			(type default)
		)
		(layer "In10.Cu")
	)
	(gr_line
		(start 212.28304 -400.144996)
		(end 212.28304 -403.63267)
		(stroke
			(width 0.635)
			(type default)
		)
		(layer "In10.Cu")
	)
	(gr_line
		(start 212.414358 -406.410668)
		(end 214.347044 -408.343354)
		(stroke
			(width 0.635)
			(type default)
		)
		(layer "In10.Cu")
	)
	(gr_line
		(start 212.414358 -403.763988)
		(end 212.414358 -406.410668)
		(stroke
			(width 0.635)
			(type default)
		)
		(layer "In10.Cu")
	)
	(gr_line
		(start 214.347044 -408.343354)
		(end 216.541604 -408.343354)
		(stroke
			(width 0.635)
			(type default)
		)
		(layer "In10.Cu")
	)
	(gr_line
		(start 216.541604 -408.343354)
		(end 218.667584 -406.217374)
		(stroke
			(width 0.635)
			(type default)
		)
		(layer "In10.Cu")
	)
	(gr_line
		(start 218.667584 -406.217374)
		(end 218.667584 -403.755606)
		(stroke
			(width 0.635)
			(type default)
		)
		(layer "In10.Cu")
	)
	(gr_line
		(start 218.667584 -403.755606)
		(end 218.839796 -403.583394)
		(stroke
			(width 0.635)
			(type default)
		)
		(layer "In10.Cu")
	)
	(gr_line
		(start 218.839796 -403.583394)
		(end 218.839796 -400.095974)
		(stroke
			(width 0.635)
			(type default)
		)
		(layer "In10.Cu")
	)
	(gr_line
		(start 218.839796 -400.095974)
		(end 219.045282 -399.890488)
		(stroke
			(width 0.635)
			(type default)
		)
		(layer "In10.Cu")
	)
	(gr_line
		(start 219.045282 -399.890488)
		(end 222.709232 -399.890488)
		(stroke
			(width 0.635)
			(type default)
		)
		(layer "In10.Cu")
	)
	(gr_line
		(start 222.709232 -399.890488)
		(end 222.906082 -400.087338)
		(stroke
			(width 0.635)
			(type default)
		)
		(layer "In10.Cu")
	)
	(gr_line
		(start 222.906082 -403.607778)
		(end 223.099122 -403.800818)
		(stroke
			(width 0.635)
			(type default)
		)
		(layer "In10.Cu")
	)
	(gr_line
		(start 222.906082 -400.087338)
		(end 222.906082 -403.607778)
		(stroke
			(width 0.635)
			(type default)
		)
		(layer "In10.Cu")
	)
	(gr_line
		(start 223.099122 -406.414732)
		(end 224.990406 -408.306016)
		(stroke
			(width 0.635)
			(type default)
		)
		(layer "In10.Cu")
	)
	(gr_line
		(start 223.099122 -403.800818)
		(end 223.099122 -406.414732)
		(stroke
			(width 0.635)
			(type default)
		)
		(layer "In10.Cu")
	)
	(gr_arc
		(start 223.300036 -34.120074)
		(mid 223.885821 -35.534285)
		(end 225.300032 -36.12007)
		(stroke
			(width 1.016)
			(type default)
		)
		(layer "In10.Cu")
	)
	(gr_arc
		(start 223.300036 -13.780008)
		(mid 222.714256 -12.365778)
		(end 221.30004 -11.780012)
		(stroke
			(width 1.016)
			(type default)
		)
		(layer "In10.Cu")
	)
	(gr_line
		(start 223.300036 -13.780008)
		(end 223.300036 -34.120074)
		(stroke
			(width 1.016)
			(type default)
		)
		(layer "In10.Cu")
	)
	(gr_line
		(start 224.990406 -408.306016)
		(end 227.218748 -408.306016)
		(stroke
			(width 0.635)
			(type default)
		)
		(layer "In10.Cu")
	)
	(gr_line
		(start 225.300032 -36.12007)
		(end 256.800096 -36.12007)
		(stroke
			(width 1.016)
			(type default)
		)
		(layer "In10.Cu")
	)
	(gr_line
		(start 227.218748 -408.306016)
		(end 229.331774 -406.19299)
		(stroke
			(width 0.635)
			(type default)
		)
		(layer "In10.Cu")
	)
	(gr_line
		(start 229.074472 -436.79618)
		(end 229.997 -435.873652)
		(stroke
			(width 0.635)
			(type default)
		)
		(layer "In10.Cu")
	)
	(gr_line
		(start 229.331774 -406.19299)
		(end 229.331774 -403.768052)
		(stroke
			(width 0.635)
			(type default)
		)
		(layer "In10.Cu")
	)
	(gr_line
		(start 229.331774 -403.768052)
		(end 229.516178 -403.583648)
		(stroke
			(width 0.635)
			(type default)
		)
		(layer "In10.Cu")
	)
	(gr_line
		(start 229.516178 -403.583648)
		(end 229.516178 -400.11223)
		(stroke
			(width 0.635)
			(type default)
		)
		(layer "In10.Cu")
	)
	(gr_line
		(start 229.516178 -400.11223)
		(end 229.746302 -399.882106)
		(stroke
			(width 0.635)
			(type default)
		)
		(layer "In10.Cu")
	)
	(gr_line
		(start 229.746302 -399.882106)
		(end 233.352594 -399.882106)
		(stroke
			(width 0.635)
			(type default)
		)
		(layer "In10.Cu")
	)
	(gr_line
		(start 229.997 -435.873652)
		(end 229.997 -422.180766)
		(stroke
			(width 0.635)
			(type default)
		)
		(layer "In10.Cu")
	)
	(gr_line
		(start 233.352594 -399.882106)
		(end 233.574336 -400.103848)
		(stroke
			(width 0.635)
			(type default)
		)
		(layer "In10.Cu")
	)
	(gr_line
		(start 233.574336 -403.673564)
		(end 233.820462 -403.91969)
		(stroke
			(width 0.635)
			(type default)
		)
		(layer "In10.Cu")
	)
	(gr_line
		(start 233.574336 -400.103848)
		(end 233.574336 -403.673564)
		(stroke
			(width 0.635)
			(type default)
		)
		(layer "In10.Cu")
	)
	(gr_line
		(start 233.820462 -404.855172)
		(end 234.522264 -405.556974)
		(stroke
			(width 0.635)
			(type default)
		)
		(layer "In10.Cu")
	)
	(gr_line
		(start 233.820462 -403.91969)
		(end 233.820462 -404.855172)
		(stroke
			(width 0.635)
			(type default)
		)
		(layer "In10.Cu")
	)
	(gr_line
		(start 234.522264 -405.556974)
		(end 238.715804 -405.556974)
		(stroke
			(width 0.635)
			(type default)
		)
		(layer "In10.Cu")
	)
	(gr_line
		(start 234.897676 -417.28009)
		(end 229.997 -422.180766)
		(stroke
			(width 0.635)
			(type default)
		)
		(layer "In10.Cu")
	)
	(gr_circle
		(center 237.629954 -44.025566)
		(end 238.518954 -44.025566)
		(stroke
			(width 0.2)
			(type default)
		)
		(fill no)
		(layer "In10.Cu")
	)
	(gr_circle
		(center 237.640114 -44.716446)
		(end 238.529114 -44.716446)
		(stroke
			(width 0.2)
			(type default)
		)
		(fill no)
		(layer "In10.Cu")
	)
	(gr_circle
		(center 238.292894 -44.802806)
		(end 239.181894 -44.802806)
		(stroke
			(width 0.2)
			(type default)
		)
		(fill no)
		(layer "In10.Cu")
	)
	(gr_circle
		(center 238.292894 -44.040806)
		(end 239.181894 -44.040806)
		(stroke
			(width 0.2)
			(type default)
		)
		(fill no)
		(layer "In10.Cu")
	)
	(gr_arc
		(start 238.695992 -393.003532)
		(mid 238.724179 -393.144586)
		(end 238.804196 -393.264136)
		(stroke
			(width 0.635)
			(type default)
		)
		(layer "In10.Cu")
	)
	(gr_line
		(start 238.695992 -384.337306)
		(end 238.695992 -393.003532)
		(stroke
			(width 0.635)
			(type default)
		)
		(layer "In10.Cu")
	)
	(gr_line
		(start 238.715804 -405.556974)
		(end 238.882682 -405.390096)
		(stroke
			(width 0.635)
			(type default)
		)
		(layer "In10.Cu")
	)
	(gr_line
		(start 238.752126 -384.198876)
		(end 238.695992 -384.337306)
		(stroke
			(width 0.635)
			(type default)
		)
		(layer "In10.Cu")
	)
	(gr_line
		(start 238.804196 -393.264136)
		(end 239.027716 -393.487656)
		(stroke
			(width 0.635)
			(type default)
		)
		(layer "In10.Cu")
	)
	(gr_line
		(start 238.805974 -384.146806)
		(end 238.752126 -384.198876)
		(stroke
			(width 0.635)
			(type default)
		)
		(layer "In10.Cu")
	)
	(gr_line
		(start 238.882682 -405.390096)
		(end 238.882682 -394.210794)
		(stroke
			(width 0.635)
			(type default)
		)
		(layer "In10.Cu")
	)
	(gr_line
		(start 238.882682 -394.210794)
		(end 238.882682 -394.001498)
		(stroke
			(width 0.635)
			(type default)
		)
		(layer "In10.Cu")
	)
	(gr_line
		(start 238.882682 -394.210794)
		(end 279.615392 -394.210794)
		(stroke
			(width 0.635)
			(type default)
		)
		(layer "In10.Cu")
	)
	(gr_line
		(start 238.882682 -394.001498)
		(end 239.28832 -393.59586)
		(stroke
			(width 0.635)
			(type default)
		)
		(layer "In10.Cu")
	)
	(gr_circle
		(center 238.943134 -44.802806)
		(end 239.832134 -44.802806)
		(stroke
			(width 0.2)
			(type default)
		)
		(fill no)
		(layer "In10.Cu")
	)
	(gr_circle
		(center 238.943134 -44.040806)
		(end 239.832134 -44.040806)
		(stroke
			(width 0.2)
			(type default)
		)
		(fill no)
		(layer "In10.Cu")
	)
	(gr_arc
		(start 239.027716 -393.487656)
		(mid 239.147257 -393.567682)
		(end 239.28832 -393.59586)
		(stroke
			(width 0.635)
			(type default)
		)
		(layer "In10.Cu")
	)
	(gr_line
		(start 239.281716 -383.671064)
		(end 238.805974 -384.146806)
		(stroke
			(width 0.635)
			(type default)
		)
		(layer "In10.Cu")
	)
	(gr_line
		(start 239.28832 -393.59586)
		(end 273.155664 -393.59586)
		(stroke
			(width 0.635)
			(type default)
		)
		(layer "In10.Cu")
	)
	(gr_arc
		(start 239.54232 -383.56286)
		(mid 239.401266 -383.591047)
		(end 239.281716 -383.671064)
		(stroke
			(width 0.635)
			(type default)
		)
		(layer "In10.Cu")
	)
	(gr_circle
		(center 239.578134 -44.802806)
		(end 240.467134 -44.802806)
		(stroke
			(width 0.2)
			(type default)
		)
		(fill no)
		(layer "In10.Cu")
	)
	(gr_circle
		(center 239.578134 -44.040806)
		(end 240.467134 -44.040806)
		(stroke
			(width 0.2)
			(type default)
		)
		(fill no)
		(layer "In10.Cu")
	)
	(gr_circle
		(center 240.213134 -44.802806)
		(end 241.102134 -44.802806)
		(stroke
			(width 0.2)
			(type default)
		)
		(fill no)
		(layer "In10.Cu")
	)
	(gr_circle
		(center 240.213134 -44.040806)
		(end 241.102134 -44.040806)
		(stroke
			(width 0.2)
			(type default)
		)
		(fill no)
		(layer "In10.Cu")
	)
	(gr_circle
		(center 240.893854 -44.830746)
		(end 241.782854 -44.830746)
		(stroke
			(width 0.2)
			(type default)
		)
		(fill no)
		(layer "In10.Cu")
	)
	(gr_circle
		(center 244.518942 -43.246802)
		(end 245.407942 -43.246802)
		(stroke
			(width 0.2)
			(type default)
		)
		(fill no)
		(layer "In10.Cu")
	)
	(gr_circle
		(center 244.518942 -42.611802)
		(end 245.407942 -42.611802)
		(stroke
			(width 0.2)
			(type default)
		)
		(fill no)
		(layer "In10.Cu")
	)
	(gr_circle
		(center 245.857522 -52.022502)
		(end 246.746522 -52.022502)
		(stroke
			(width 0.2)
			(type default)
		)
		(fill no)
		(layer "In10.Cu")
	)
	(gr_circle
		(center 246.873522 -52.022502)
		(end 247.762522 -52.022502)
		(stroke
			(width 0.2)
			(type default)
		)
		(fill no)
		(layer "In10.Cu")
	)
	(gr_circle
		(center 247.825514 -40.94988)
		(end 248.714514 -40.94988)
		(stroke
			(width 0.2)
			(type default)
		)
		(fill no)
		(layer "In10.Cu")
	)
	(gr_circle
		(center 247.840246 -51.320446)
		(end 248.729246 -51.320446)
		(stroke
			(width 0.2)
			(type default)
		)
		(fill no)
		(layer "In10.Cu")
	)
	(gr_circle
		(center 248.214134 -52.171346)
		(end 249.103134 -52.171346)
		(stroke
			(width 0.2)
			(type default)
		)
		(fill no)
		(layer "In10.Cu")
	)
	(gr_circle
		(center 248.881646 -51.320446)
		(end 249.770646 -51.320446)
		(stroke
			(width 0.2)
			(type default)
		)
		(fill no)
		(layer "In10.Cu")
	)
	(gr_circle
		(center 249.202448 -40.945816)
		(end 250.091448 -40.945816)
		(stroke
			(width 0.2)
			(type default)
		)
		(fill no)
		(layer "In10.Cu")
	)
	(gr_circle
		(center 249.905266 -51.349148)
		(end 250.794266 -51.349148)
		(stroke
			(width 0.2)
			(type default)
		)
		(fill no)
		(layer "In10.Cu")
	)
	(gr_circle
		(center 250.449334 -49.555146)
		(end 251.338334 -49.555146)
		(stroke
			(width 0.2)
			(type default)
		)
		(fill no)
		(layer "In10.Cu")
	)
	(gr_circle
		(center 250.779534 -52.222146)
		(end 251.668534 -52.222146)
		(stroke
			(width 0.2)
			(type default)
		)
		(fill no)
		(layer "In10.Cu")
	)
	(gr_circle
		(center 250.779534 -51.333146)
		(end 251.668534 -51.333146)
		(stroke
			(width 0.2)
			(type default)
		)
		(fill no)
		(layer "In10.Cu")
	)
	(gr_circle
		(center 250.779534 -50.444146)
		(end 251.668534 -50.444146)
		(stroke
			(width 0.2)
			(type default)
		)
		(fill no)
		(layer "In10.Cu")
	)
	(gr_circle
		(center 251.516134 -52.501546)
		(end 252.405134 -52.501546)
		(stroke
			(width 0.2)
			(type default)
		)
		(fill no)
		(layer "In10.Cu")
	)
	(gr_circle
		(center 251.516134 -51.612546)
		(end 252.405134 -51.612546)
		(stroke
			(width 0.2)
			(type default)
		)
		(fill no)
		(layer "In10.Cu")
	)
	(gr_circle
		(center 251.516134 -50.723546)
		(end 252.405134 -50.723546)
		(stroke
			(width 0.2)
			(type default)
		)
		(fill no)
		(layer "In10.Cu")
	)
	(gr_circle
		(center 255.347978 -39.380922)
		(end 256.236978 -39.380922)
		(stroke
			(width 0.2)
			(type default)
		)
		(fill no)
		(layer "In10.Cu")
	)
	(gr_arc
		(start 256.800096 -36.12007)
		(mid 258.214307 -35.534285)
		(end 258.800092 -34.120074)
		(stroke
			(width 1.016)
			(type default)
		)
		(layer "In10.Cu")
	)
	(gr_line
		(start 258.800092 -34.120074)
		(end 258.800092 -13.780008)
		(stroke
			(width 1.016)
			(type default)
		)
		(layer "In10.Cu")
	)
	(gr_arc
		(start 260.800088 -11.780012)
		(mid 259.385888 -12.365802)
		(end 258.800092 -13.780008)
		(stroke
			(width 1.016)
			(type default)
		)
		(layer "In10.Cu")
	)
	(gr_line
		(start 260.800088 -11.780012)
		(end 385.601972 -11.780012)
		(stroke
			(width 1.016)
			(type default)
		)
		(layer "In10.Cu")
	)
	(gr_line
		(start 272.19021 -417.28009)
		(end 234.897676 -417.28009)
		(stroke
			(width 0.635)
			(type default)
		)
		(layer "In10.Cu")
	)
	(gr_arc
		(start 273.155664 -393.59586)
		(mid 273.296718 -393.567673)
		(end 273.416268 -393.487656)
		(stroke
			(width 0.635)
			(type default)
		)
		(layer "In10.Cu")
	)
	(gr_line
		(start 273.33067 -394.041884)
		(end 279.547066 -394.041884)
		(stroke
			(width 0.635)
			(type default)
		)
		(layer "In10.Cu")
	)
	(gr_line
		(start 273.416268 -393.487656)
		(end 273.893788 -393.010136)
		(stroke
			(width 0.635)
			(type default)
		)
		(layer "In10.Cu")
	)
	(gr_line
		(start 273.481546 -383.56286)
		(end 239.54232 -383.56286)
		(stroke
			(width 0.635)
			(type default)
		)
		(layer "In10.Cu")
	)
	(gr_line
		(start 273.619976 -383.618994)
		(end 273.481546 -383.56286)
		(stroke
			(width 0.635)
			(type default)
		)
		(layer "In10.Cu")
	)
	(gr_line
		(start 273.672046 -383.672842)
		(end 273.619976 -383.618994)
		(stroke
			(width 0.635)
			(type default)
		)
		(layer "In10.Cu")
	)
	(gr_arc
		(start 273.893788 -393.010136)
		(mid 273.97387 -392.890613)
		(end 274.001992 -392.749532)
		(stroke
			(width 0.635)
			(type default)
		)
		(layer "In10.Cu")
	)
	(gr_line
		(start 273.893788 -383.894584)
		(end 273.672046 -383.672842)
		(stroke
			(width 0.635)
			(type default)
		)
		(layer "In10.Cu")
	)
	(gr_line
		(start 274.001992 -392.749532)
		(end 274.001992 -384.155188)
		(stroke
			(width 0.635)
			(type default)
		)
		(layer "In10.Cu")
	)
	(gr_arc
		(start 274.001992 -384.155188)
		(mid 273.973805 -384.014134)
		(end 273.893788 -383.894584)
		(stroke
			(width 0.635)
			(type default)
		)
		(layer "In10.Cu")
	)
	(gr_line
		(start 274.123404 -393.697206)
		(end 279.133554 -393.697206)
		(stroke
			(width 0.635)
			(type default)
		)
		(layer "In10.Cu")
	)
	(gr_line
		(start 274.433792 -392.938762)
		(end 273.33067 -394.041884)
		(stroke
			(width 0.635)
			(type default)
		)
		(layer "In10.Cu")
	)
	(gr_line
		(start 274.433792 -392.938762)
		(end 274.50288 -392.869674)
		(stroke
			(width 0.635)
			(type default)
		)
		(layer "In10.Cu")
	)
	(gr_line
		(start 274.433792 -392.317732)
		(end 274.67052 -392.55446)
		(stroke
			(width 0.635)
			(type default)
		)
		(layer "In10.Cu")
	)
	(gr_line
		(start 274.433792 -384.002788)
		(end 274.433792 -392.938762)
		(stroke
			(width 0.635)
			(type default)
		)
		(layer "In10.Cu")
	)
	(gr_line
		(start 274.433792 -384.002788)
		(end 274.433792 -392.317732)
		(stroke
			(width 0.635)
			(type default)
		)
		(layer "In10.Cu")
	)
	(gr_line
		(start 274.50288 -392.869674)
		(end 279.110694 -392.869674)
		(stroke
			(width 0.635)
			(type default)
		)
		(layer "In10.Cu")
	)
	(gr_line
		(start 274.732496 -393.237466)
		(end 274.433792 -392.938762)
		(stroke
			(width 0.635)
			(type default)
		)
		(layer "In10.Cu")
	)
	(gr_line
		(start 274.778724 -392.605514)
		(end 274.192746 -392.019536)
		(stroke
			(width 0.635)
			(type default)
		)
		(layer "In10.Cu")
	)
	(gr_line
		(start 274.87372 -383.56286)
		(end 274.433792 -384.002788)
		(stroke
			(width 0.635)
			(type default)
		)
		(layer "In10.Cu")
	)
	(gr_circle
		(center 276.112986 -348.704662)
		(end 276.993096 -348.704662)
		(stroke
			(width 0.2)
			(type default)
		)
		(fill no)
		(layer "In10.Cu")
	)
	(gr_line
		(start 276.314916 -440.669934)
		(end 195.50507 -440.669934)
		(stroke
			(width 1.016)
			(type default)
		)
		(layer "In10.Cu")
	)
	(gr_circle
		(center 276.730206 -348.704662)
		(end 277.610316 -348.704662)
		(stroke
			(width 0.2)
			(type default)
		)
		(fill no)
		(layer "In10.Cu")
	)
	(gr_line
		(start 276.815042 -441.4901)
		(end 276.815042 -441.17006)
		(stroke
			(width 1.016)
			(type default)
		)
		(layer "In10.Cu")
	)
	(gr_arc
		(start 276.815042 -441.4901)
		(mid 276.961452 -441.843558)
		(end 277.314914 -441.989972)
		(stroke
			(width 1.016)
			(type default)
		)
		(layer "In10.Cu")
	)
	(gr_arc
		(start 276.815042 -441.17006)
		(mid 276.668558 -440.816418)
		(end 276.314916 -440.669934)
		(stroke
			(width 1.016)
			(type default)
		)
		(layer "In10.Cu")
	)
	(gr_circle
		(center 277.347426 -348.704662)
		(end 278.227536 -348.704662)
		(stroke
			(width 0.2)
			(type default)
		)
		(fill no)
		(layer "In10.Cu")
	)
	(gr_circle
		(center 277.593806 -348.025212)
		(end 278.482806 -348.025212)
		(stroke
			(width 0.2)
			(type default)
		)
		(fill no)
		(layer "In10.Cu")
	)
	(gr_circle
		(center 277.593806 -347.288612)
		(end 278.482806 -347.288612)
		(stroke
			(width 0.2)
			(type default)
		)
		(fill no)
		(layer "In10.Cu")
	)
	(gr_circle
		(center 278.049482 -350.313752)
		(end 278.938482 -350.313752)
		(stroke
			(width 0.2)
			(type default)
		)
		(fill no)
		(layer "In10.Cu")
	)
	(gr_circle
		(center 278.049482 -349.577152)
		(end 278.938482 -349.577152)
		(stroke
			(width 0.2)
			(type default)
		)
		(fill no)
		(layer "In10.Cu")
	)
	(gr_circle
		(center 278.574246 -349.137732)
		(end 279.463246 -349.137732)
		(stroke
			(width 0.2)
			(type default)
		)
		(fill no)
		(layer "In10.Cu")
	)
	(gr_circle
		(center 278.599646 -349.899732)
		(end 279.488646 -349.899732)
		(stroke
			(width 0.2)
			(type default)
		)
		(fill no)
		(layer "In10.Cu")
	)
	(gr_line
		(start 278.892508 -393.237466)
		(end 274.732496 -393.237466)
		(stroke
			(width 0.635)
			(type default)
		)
		(layer "In10.Cu")
	)
	(gr_line
		(start 279.110694 -392.869674)
		(end 279.351994 -392.628374)
		(stroke
			(width 0.635)
			(type default)
		)
		(layer "In10.Cu")
	)
	(gr_circle
		(center 279.133046 -350.255332)
		(end 280.022046 -350.255332)
		(stroke
			(width 0.2)
			(type default)
		)
		(fill no)
		(layer "In10.Cu")
	)
	(gr_circle
		(center 279.133046 -349.518732)
		(end 280.022046 -349.518732)
		(stroke
			(width 0.2)
			(type default)
		)
		(fill no)
		(layer "In10.Cu")
	)
	(gr_circle
		(center 279.133046 -348.782132)
		(end 280.022046 -348.782132)
		(stroke
			(width 0.2)
			(type default)
		)
		(fill no)
		(layer "In10.Cu")
	)
	(gr_line
		(start 279.133554 -393.697206)
		(end 279.983946 -392.846814)
		(stroke
			(width 0.635)
			(type default)
		)
		(layer "In10.Cu")
	)
	(gr_line
		(start 279.329134 -392.605514)
		(end 274.778724 -392.605514)
		(stroke
			(width 0.635)
			(type default)
		)
		(layer "In10.Cu")
	)
	(gr_line
		(start 279.351994 -392.628374)
		(end 279.329134 -392.605514)
		(stroke
			(width 0.635)
			(type default)
		)
		(layer "In10.Cu")
	)
	(gr_line
		(start 279.547066 -394.041884)
		(end 280.477976 -393.110974)
		(stroke
			(width 0.635)
			(type default)
		)
		(layer "In10.Cu")
	)
	(gr_line
		(start 279.616408 -392.513566)
		(end 278.892508 -393.237466)
		(stroke
			(width 0.635)
			(type default)
		)
		(layer "In10.Cu")
	)
	(gr_line
		(start 279.616408 -383.780538)
		(end 279.616408 -392.513566)
		(stroke
			(width 0.635)
			(type default)
		)
		(layer "In10.Cu")
	)
	(gr_line
		(start 279.834086 -383.56286)
		(end 279.616408 -383.780538)
		(stroke
			(width 0.635)
			(type default)
		)
		(layer "In10.Cu")
	)
	(gr_arc
		(start 279.875996 -394.318998)
		(mid 279.756473 -394.238916)
		(end 279.615392 -394.210794)
		(stroke
			(width 0.635)
			(type default)
		)
		(layer "In10.Cu")
	)
	(gr_line
		(start 279.983946 -392.846814)
		(end 279.983946 -383.781046)
		(stroke
			(width 0.635)
			(type default)
		)
		(layer "In10.Cu")
	)
	(gr_line
		(start 279.983946 -383.781046)
		(end 280.202132 -383.56286)
		(stroke
			(width 0.635)
			(type default)
		)
		(layer "In10.Cu")
	)
	(gr_line
		(start 280.202132 -383.56286)
		(end 274.87372 -383.56286)
		(stroke
			(width 0.635)
			(type default)
		)
		(layer "In10.Cu")
	)
	(gr_line
		(start 280.202132 -383.56286)
		(end 279.834086 -383.56286)
		(stroke
			(width 0.635)
			(type default)
		)
		(layer "In10.Cu")
	)
	(gr_line
		(start 280.259536 -394.702538)
		(end 279.875996 -394.318998)
		(stroke
			(width 0.635)
			(type default)
		)
		(layer "In10.Cu")
	)
	(gr_line
		(start 280.36774 -409.10256)
		(end 272.19021 -417.28009)
		(stroke
			(width 0.635)
			(type default)
		)
		(layer "In10.Cu")
	)
	(gr_arc
		(start 280.36774 -394.963142)
		(mid 280.339553 -394.822088)
		(end 280.259536 -394.702538)
		(stroke
			(width 0.635)
			(type default)
		)
		(layer "In10.Cu")
	)
	(gr_line
		(start 280.36774 -394.963142)
		(end 280.36774 -409.10256)
		(stroke
			(width 0.635)
			(type default)
		)
		(layer "In10.Cu")
	)
	(gr_line
		(start 280.477976 -393.110974)
		(end 280.477976 -383.838704)
		(stroke
			(width 0.635)
			(type default)
		)
		(layer "In10.Cu")
	)
	(gr_line
		(start 280.477976 -383.838704)
		(end 280.202132 -383.56286)
		(stroke
			(width 0.635)
			(type default)
		)
		(layer "In10.Cu")
	)
	(gr_line
		(start 280.537412 -392.55446)
		(end 274.67052 -392.55446)
		(stroke
			(width 0.635)
			(type default)
		)
		(layer "In10.Cu")
	)
	(gr_line
		(start 280.537412 -392.55446)
		(end 280.9113 -392.180572)
		(stroke
			(width 0.635)
			(type default)
		)
		(layer "In10.Cu")
	)
	(gr_line
		(start 280.9113 -392.180572)
		(end 280.9113 -384.272028)
		(stroke
			(width 0.635)
			(type default)
		)
		(layer "In10.Cu")
	)
	(gr_line
		(start 280.9113 -384.272028)
		(end 280.202132 -383.56286)
		(stroke
			(width 0.635)
			(type default)
		)
		(layer "In10.Cu")
	)
	(gr_circle
		(center 284.393386 -348.704662)
		(end 285.273496 -348.704662)
		(stroke
			(width 0.2)
			(type default)
		)
		(fill no)
		(layer "In10.Cu")
	)
	(gr_circle
		(center 285.010606 -348.704662)
		(end 285.890716 -348.704662)
		(stroke
			(width 0.2)
			(type default)
		)
		(fill no)
		(layer "In10.Cu")
	)
	(gr_circle
		(center 285.627826 -348.704662)
		(end 286.507936 -348.704662)
		(stroke
			(width 0.2)
			(type default)
		)
		(fill no)
		(layer "In10.Cu")
	)
	(gr_circle
		(center 285.869126 -347.982032)
		(end 286.758126 -347.982032)
		(stroke
			(width 0.2)
			(type default)
		)
		(fill no)
		(layer "In10.Cu")
	)
	(gr_circle
		(center 285.869126 -347.245432)
		(end 286.758126 -347.245432)
		(stroke
			(width 0.2)
			(type default)
		)
		(fill no)
		(layer "In10.Cu")
	)
	(gr_circle
		(center 286.329882 -350.313752)
		(end 287.218882 -350.313752)
		(stroke
			(width 0.2)
			(type default)
		)
		(fill no)
		(layer "In10.Cu")
	)
	(gr_circle
		(center 286.329882 -349.577152)
		(end 287.218882 -349.577152)
		(stroke
			(width 0.2)
			(type default)
		)
		(fill no)
		(layer "In10.Cu")
	)
	(gr_circle
		(center 286.36595 -355.279198)
		(end 287.25495 -355.279198)
		(stroke
			(width 0.2)
			(type default)
		)
		(fill no)
		(layer "In10.Cu")
	)
	(gr_circle
		(center 286.37611 -356.584758)
		(end 287.26511 -356.584758)
		(stroke
			(width 0.2)
			(type default)
		)
		(fill no)
		(layer "In10.Cu")
	)
	(gr_circle
		(center 286.37611 -355.949758)
		(end 287.26511 -355.949758)
		(stroke
			(width 0.2)
			(type default)
		)
		(fill no)
		(layer "In10.Cu")
	)
	(gr_circle
		(center 286.854646 -349.137732)
		(end 287.743646 -349.137732)
		(stroke
			(width 0.2)
			(type default)
		)
		(fill no)
		(layer "In10.Cu")
	)
	(gr_circle
		(center 286.880046 -349.899732)
		(end 287.769046 -349.899732)
		(stroke
			(width 0.2)
			(type default)
		)
		(fill no)
		(layer "In10.Cu")
	)
	(gr_circle
		(center 287.00095 -355.279198)
		(end 287.88995 -355.279198)
		(stroke
			(width 0.2)
			(type default)
		)
		(fill no)
		(layer "In10.Cu")
	)
	(gr_circle
		(center 287.01111 -356.584758)
		(end 287.90011 -356.584758)
		(stroke
			(width 0.2)
			(type default)
		)
		(fill no)
		(layer "In10.Cu")
	)
	(gr_circle
		(center 287.01111 -355.949758)
		(end 287.90011 -355.949758)
		(stroke
			(width 0.2)
			(type default)
		)
		(fill no)
		(layer "In10.Cu")
	)
	(gr_circle
		(center 287.413446 -350.255332)
		(end 288.302446 -350.255332)
		(stroke
			(width 0.2)
			(type default)
		)
		(fill no)
		(layer "In10.Cu")
	)
	(gr_circle
		(center 287.413446 -349.518732)
		(end 288.302446 -349.518732)
		(stroke
			(width 0.2)
			(type default)
		)
		(fill no)
		(layer "In10.Cu")
	)
	(gr_circle
		(center 287.413446 -348.782132)
		(end 288.302446 -348.782132)
		(stroke
			(width 0.2)
			(type default)
		)
		(fill no)
		(layer "In10.Cu")
	)
	(gr_circle
		(center 287.63595 -355.279198)
		(end 288.52495 -355.279198)
		(stroke
			(width 0.2)
			(type default)
		)
		(fill no)
		(layer "In10.Cu")
	)
	(gr_circle
		(center 287.64611 -356.584758)
		(end 288.53511 -356.584758)
		(stroke
			(width 0.2)
			(type default)
		)
		(fill no)
		(layer "In10.Cu")
	)
	(gr_circle
		(center 287.64611 -355.949758)
		(end 288.53511 -355.949758)
		(stroke
			(width 0.2)
			(type default)
		)
		(fill no)
		(layer "In10.Cu")
	)
	(gr_circle
		(center 288.27095 -355.279198)
		(end 289.15995 -355.279198)
		(stroke
			(width 0.2)
			(type default)
		)
		(fill no)
		(layer "In10.Cu")
	)
	(gr_circle
		(center 288.28111 -356.584758)
		(end 289.17011 -356.584758)
		(stroke
			(width 0.2)
			(type default)
		)
		(fill no)
		(layer "In10.Cu")
	)
	(gr_circle
		(center 288.28111 -355.949758)
		(end 289.17011 -355.949758)
		(stroke
			(width 0.2)
			(type default)
		)
		(fill no)
		(layer "In10.Cu")
	)
	(gr_circle
		(center 288.90595 -355.279198)
		(end 289.79495 -355.279198)
		(stroke
			(width 0.2)
			(type default)
		)
		(fill no)
		(layer "In10.Cu")
	)
	(gr_circle
		(center 288.91611 -356.584758)
		(end 289.80511 -356.584758)
		(stroke
			(width 0.2)
			(type default)
		)
		(fill no)
		(layer "In10.Cu")
	)
	(gr_circle
		(center 288.91611 -355.949758)
		(end 289.80511 -355.949758)
		(stroke
			(width 0.2)
			(type default)
		)
		(fill no)
		(layer "In10.Cu")
	)
	(gr_circle
		(center 292.699186 -348.704662)
		(end 293.579296 -348.704662)
		(stroke
			(width 0.2)
			(type default)
		)
		(fill no)
		(layer "In10.Cu")
	)
	(gr_circle
		(center 293.316406 -348.704662)
		(end 294.196516 -348.704662)
		(stroke
			(width 0.2)
			(type default)
		)
		(fill no)
		(layer "In10.Cu")
	)
	(gr_circle
		(center 293.933626 -348.704662)
		(end 294.813736 -348.704662)
		(stroke
			(width 0.2)
			(type default)
		)
		(fill no)
		(layer "In10.Cu")
	)
	(gr_circle
		(center 294.146986 -347.959172)
		(end 295.035986 -347.959172)
		(stroke
			(width 0.2)
			(type default)
		)
		(fill no)
		(layer "In10.Cu")
	)
	(gr_circle
		(center 294.146986 -347.222572)
		(end 295.035986 -347.222572)
		(stroke
			(width 0.2)
			(type default)
		)
		(fill no)
		(layer "In10.Cu")
	)
	(gr_circle
		(center 294.635682 -350.313752)
		(end 295.524682 -350.313752)
		(stroke
			(width 0.2)
			(type default)
		)
		(fill no)
		(layer "In10.Cu")
	)
	(gr_circle
		(center 294.635682 -349.577152)
		(end 295.524682 -349.577152)
		(stroke
			(width 0.2)
			(type default)
		)
		(fill no)
		(layer "In10.Cu")
	)
	(gr_circle
		(center 295.160446 -349.137732)
		(end 296.049446 -349.137732)
		(stroke
			(width 0.2)
			(type default)
		)
		(fill no)
		(layer "In10.Cu")
	)
	(gr_circle
		(center 295.185846 -349.899732)
		(end 296.074846 -349.899732)
		(stroke
			(width 0.2)
			(type default)
		)
		(fill no)
		(layer "In10.Cu")
	)
	(gr_circle
		(center 295.719246 -350.255332)
		(end 296.608246 -350.255332)
		(stroke
			(width 0.2)
			(type default)
		)
		(fill no)
		(layer "In10.Cu")
	)
	(gr_circle
		(center 295.719246 -349.518732)
		(end 296.608246 -349.518732)
		(stroke
			(width 0.2)
			(type default)
		)
		(fill no)
		(layer "In10.Cu")
	)
	(gr_circle
		(center 295.719246 -348.782132)
		(end 296.608246 -348.782132)
		(stroke
			(width 0.2)
			(type default)
		)
		(fill no)
		(layer "In10.Cu")
	)
	(gr_circle
		(center 296.29989 -358.769666)
		(end 297.69689 -358.769666)
		(stroke
			(width 0.2)
			(type default)
		)
		(fill no)
		(layer "In10.Cu")
	)
	(gr_circle
		(center 301.055786 -348.704662)
		(end 301.935896 -348.704662)
		(stroke
			(width 0.2)
			(type default)
		)
		(fill no)
		(layer "In10.Cu")
	)
	(gr_circle
		(center 301.673006 -348.704662)
		(end 302.553116 -348.704662)
		(stroke
			(width 0.2)
			(type default)
		)
		(fill no)
		(layer "In10.Cu")
	)
	(gr_circle
		(center 302.290226 -348.704662)
		(end 303.170336 -348.704662)
		(stroke
			(width 0.2)
			(type default)
		)
		(fill no)
		(layer "In10.Cu")
	)
	(gr_circle
		(center 302.526446 -348.002352)
		(end 303.415446 -348.002352)
		(stroke
			(width 0.2)
			(type default)
		)
		(fill no)
		(layer "In10.Cu")
	)
	(gr_circle
		(center 302.526446 -347.265752)
		(end 303.415446 -347.265752)
		(stroke
			(width 0.2)
			(type default)
		)
		(fill no)
		(layer "In10.Cu")
	)
	(gr_circle
		(center 302.992282 -350.313752)
		(end 303.881282 -350.313752)
		(stroke
			(width 0.2)
			(type default)
		)
		(fill no)
		(layer "In10.Cu")
	)
	(gr_circle
		(center 302.992282 -349.577152)
		(end 303.881282 -349.577152)
		(stroke
			(width 0.2)
			(type default)
		)
		(fill no)
		(layer "In10.Cu")
	)
	(gr_circle
		(center 303.517046 -349.137732)
		(end 304.406046 -349.137732)
		(stroke
			(width 0.2)
			(type default)
		)
		(fill no)
		(layer "In10.Cu")
	)
	(gr_circle
		(center 303.542446 -349.899732)
		(end 304.431446 -349.899732)
		(stroke
			(width 0.2)
			(type default)
		)
		(fill no)
		(layer "In10.Cu")
	)
	(gr_circle
		(center 304.075846 -350.255332)
		(end 304.964846 -350.255332)
		(stroke
			(width 0.2)
			(type default)
		)
		(fill no)
		(layer "In10.Cu")
	)
	(gr_circle
		(center 304.075846 -349.518732)
		(end 304.964846 -349.518732)
		(stroke
			(width 0.2)
			(type default)
		)
		(fill no)
		(layer "In10.Cu")
	)
	(gr_circle
		(center 304.075846 -348.782132)
		(end 304.964846 -348.782132)
		(stroke
			(width 0.2)
			(type default)
		)
		(fill no)
		(layer "In10.Cu")
	)
	(gr_circle
		(center 309.386986 -348.704662)
		(end 310.267096 -348.704662)
		(stroke
			(width 0.2)
			(type default)
		)
		(fill no)
		(layer "In10.Cu")
	)
	(gr_circle
		(center 310.004206 -348.704662)
		(end 310.884316 -348.704662)
		(stroke
			(width 0.2)
			(type default)
		)
		(fill no)
		(layer "In10.Cu")
	)
	(gr_circle
		(center 310.621426 -348.704662)
		(end 311.501536 -348.704662)
		(stroke
			(width 0.2)
			(type default)
		)
		(fill no)
		(layer "In10.Cu")
	)
	(gr_circle
		(center 310.867806 -348.002352)
		(end 311.756806 -348.002352)
		(stroke
			(width 0.2)
			(type default)
		)
		(fill no)
		(layer "In10.Cu")
	)
	(gr_circle
		(center 310.867806 -347.265752)
		(end 311.756806 -347.265752)
		(stroke
			(width 0.2)
			(type default)
		)
		(fill no)
		(layer "In10.Cu")
	)
	(gr_circle
		(center 311.323482 -350.313752)
		(end 312.212482 -350.313752)
		(stroke
			(width 0.2)
			(type default)
		)
		(fill no)
		(layer "In10.Cu")
	)
	(gr_circle
		(center 311.323482 -349.577152)
		(end 312.212482 -349.577152)
		(stroke
			(width 0.2)
			(type default)
		)
		(fill no)
		(layer "In10.Cu")
	)
	(gr_circle
		(center 311.848246 -349.137732)
		(end 312.737246 -349.137732)
		(stroke
			(width 0.2)
			(type default)
		)
		(fill no)
		(layer "In10.Cu")
	)
	(gr_circle
		(center 311.873646 -349.899732)
		(end 312.762646 -349.899732)
		(stroke
			(width 0.2)
			(type default)
		)
		(fill no)
		(layer "In10.Cu")
	)
	(gr_circle
		(center 312.407046 -350.255332)
		(end 313.296046 -350.255332)
		(stroke
			(width 0.2)
			(type default)
		)
		(fill no)
		(layer "In10.Cu")
	)
	(gr_circle
		(center 312.407046 -349.518732)
		(end 313.296046 -349.518732)
		(stroke
			(width 0.2)
			(type default)
		)
		(fill no)
		(layer "In10.Cu")
	)
	(gr_circle
		(center 312.407046 -348.782132)
		(end 313.296046 -348.782132)
		(stroke
			(width 0.2)
			(type default)
		)
		(fill no)
		(layer "In10.Cu")
	)
	(gr_circle
		(center 319.0367 -336.983578)
		(end 319.91681 -336.983578)
		(stroke
			(width 0.2)
			(type default)
		)
		(fill no)
		(layer "In10.Cu")
	)
	(gr_circle
		(center 319.65392 -336.983578)
		(end 320.53403 -336.983578)
		(stroke
			(width 0.2)
			(type default)
		)
		(fill no)
		(layer "In10.Cu")
	)
	(gr_circle
		(center 320.27114 -336.983578)
		(end 321.15125 -336.983578)
		(stroke
			(width 0.2)
			(type default)
		)
		(fill no)
		(layer "In10.Cu")
	)
	(gr_circle
		(center 320.5607 -336.239612)
		(end 321.4497 -336.239612)
		(stroke
			(width 0.2)
			(type default)
		)
		(fill no)
		(layer "In10.Cu")
	)
	(gr_circle
		(center 320.5607 -335.503012)
		(end 321.4497 -335.503012)
		(stroke
			(width 0.2)
			(type default)
		)
		(fill no)
		(layer "In10.Cu")
	)
	(gr_circle
		(center 320.973196 -338.592668)
		(end 321.862196 -338.592668)
		(stroke
			(width 0.2)
			(type default)
		)
		(fill no)
		(layer "In10.Cu")
	)
	(gr_circle
		(center 320.973196 -337.856068)
		(end 321.862196 -337.856068)
		(stroke
			(width 0.2)
			(type default)
		)
		(fill no)
		(layer "In10.Cu")
	)
	(gr_circle
		(center 321.49796 -337.416648)
		(end 322.38696 -337.416648)
		(stroke
			(width 0.2)
			(type default)
		)
		(fill no)
		(layer "In10.Cu")
	)
	(gr_circle
		(center 321.52336 -338.178648)
		(end 322.41236 -338.178648)
		(stroke
			(width 0.2)
			(type default)
		)
		(fill no)
		(layer "In10.Cu")
	)
	(gr_circle
		(center 322.05676 -338.534248)
		(end 322.94576 -338.534248)
		(stroke
			(width 0.2)
			(type default)
		)
		(fill no)
		(layer "In10.Cu")
	)
	(gr_circle
		(center 322.05676 -337.797648)
		(end 322.94576 -337.797648)
		(stroke
			(width 0.2)
			(type default)
		)
		(fill no)
		(layer "In10.Cu")
	)
	(gr_circle
		(center 322.05676 -337.061048)
		(end 322.94576 -337.061048)
		(stroke
			(width 0.2)
			(type default)
		)
		(fill no)
		(layer "In10.Cu")
	)
	(gr_circle
		(center 327.392284 -336.976466)
		(end 328.272394 -336.976466)
		(stroke
			(width 0.2)
			(type default)
		)
		(fill no)
		(layer "In10.Cu")
	)
	(gr_circle
		(center 327.692258 -104.30129)
		(end 328.581258 -104.30129)
		(stroke
			(width 0.2)
			(type default)
		)
		(fill no)
		(layer "In10.Cu")
	)
	(gr_circle
		(center 327.951084 -349.43161)
		(end 329.348084 -349.43161)
		(stroke
			(width 0.2)
			(type default)
		)
		(fill no)
		(layer "In10.Cu")
	)
	(gr_circle
		(center 328.009504 -336.976466)
		(end 328.889614 -336.976466)
		(stroke
			(width 0.2)
			(type default)
		)
		(fill no)
		(layer "In10.Cu")
	)
	(gr_circle
		(center 328.626724 -336.976466)
		(end 329.506834 -336.976466)
		(stroke
			(width 0.2)
			(type default)
		)
		(fill no)
		(layer "In10.Cu")
	)
	(gr_circle
		(center 328.918824 -336.253836)
		(end 329.807824 -336.253836)
		(stroke
			(width 0.2)
			(type default)
		)
		(fill no)
		(layer "In10.Cu")
	)
	(gr_circle
		(center 328.918824 -335.517236)
		(end 329.807824 -335.517236)
		(stroke
			(width 0.2)
			(type default)
		)
		(fill no)
		(layer "In10.Cu")
	)
	(gr_circle
		(center 329.32878 -338.585556)
		(end 330.21778 -338.585556)
		(stroke
			(width 0.2)
			(type default)
		)
		(fill no)
		(layer "In10.Cu")
	)
	(gr_circle
		(center 329.32878 -337.848956)
		(end 330.21778 -337.848956)
		(stroke
			(width 0.2)
			(type default)
		)
		(fill no)
		(layer "In10.Cu")
	)
	(gr_circle
		(center 329.853544 -337.409536)
		(end 330.742544 -337.409536)
		(stroke
			(width 0.2)
			(type default)
		)
		(fill no)
		(layer "In10.Cu")
	)
	(gr_circle
		(center 329.878944 -338.171536)
		(end 330.767944 -338.171536)
		(stroke
			(width 0.2)
			(type default)
		)
		(fill no)
		(layer "In10.Cu")
	)
	(gr_circle
		(center 330.412344 -338.527136)
		(end 331.301344 -338.527136)
		(stroke
			(width 0.2)
			(type default)
		)
		(fill no)
		(layer "In10.Cu")
	)
	(gr_circle
		(center 330.412344 -337.790536)
		(end 331.301344 -337.790536)
		(stroke
			(width 0.2)
			(type default)
		)
		(fill no)
		(layer "In10.Cu")
	)
	(gr_circle
		(center 330.412344 -337.053936)
		(end 331.301344 -337.053936)
		(stroke
			(width 0.2)
			(type default)
		)
		(fill no)
		(layer "In10.Cu")
	)
	(gr_circle
		(center 335.411064 -349.43161)
		(end 336.808064 -349.43161)
		(stroke
			(width 0.2)
			(type default)
		)
		(fill no)
		(layer "In10.Cu")
	)
	(gr_circle
		(center 335.7499 -336.961988)
		(end 336.63001 -336.961988)
		(stroke
			(width 0.2)
			(type default)
		)
		(fill no)
		(layer "In10.Cu")
	)
	(gr_circle
		(center 336.36712 -336.961988)
		(end 337.24723 -336.961988)
		(stroke
			(width 0.2)
			(type default)
		)
		(fill no)
		(layer "In10.Cu")
	)
	(gr_circle
		(center 336.98434 -336.961988)
		(end 337.86445 -336.961988)
		(stroke
			(width 0.2)
			(type default)
		)
		(fill no)
		(layer "In10.Cu")
	)
	(gr_circle
		(center 337.280504 -336.253836)
		(end 338.169504 -336.253836)
		(stroke
			(width 0.2)
			(type default)
		)
		(fill no)
		(layer "In10.Cu")
	)
	(gr_circle
		(center 337.280504 -335.517236)
		(end 338.169504 -335.517236)
		(stroke
			(width 0.2)
			(type default)
		)
		(fill no)
		(layer "In10.Cu")
	)
	(gr_circle
		(center 337.686396 -338.571078)
		(end 338.575396 -338.571078)
		(stroke
			(width 0.2)
			(type default)
		)
		(fill no)
		(layer "In10.Cu")
	)
	(gr_circle
		(center 337.686396 -337.834478)
		(end 338.575396 -337.834478)
		(stroke
			(width 0.2)
			(type default)
		)
		(fill no)
		(layer "In10.Cu")
	)
	(gr_circle
		(center 338.21116 -337.395058)
		(end 339.10016 -337.395058)
		(stroke
			(width 0.2)
			(type default)
		)
		(fill no)
		(layer "In10.Cu")
	)
	(gr_circle
		(center 338.23656 -338.157058)
		(end 339.12556 -338.157058)
		(stroke
			(width 0.2)
			(type default)
		)
		(fill no)
		(layer "In10.Cu")
	)
	(gr_circle
		(center 338.76996 -338.512658)
		(end 339.65896 -338.512658)
		(stroke
			(width 0.2)
			(type default)
		)
		(fill no)
		(layer "In10.Cu")
	)
	(gr_circle
		(center 338.76996 -337.776058)
		(end 339.65896 -337.776058)
		(stroke
			(width 0.2)
			(type default)
		)
		(fill no)
		(layer "In10.Cu")
	)
	(gr_circle
		(center 338.76996 -337.039458)
		(end 339.65896 -337.039458)
		(stroke
			(width 0.2)
			(type default)
		)
		(fill no)
		(layer "In10.Cu")
	)
	(gr_circle
		(center 339.73897 -352.973132)
		(end 340.62797 -352.973132)
		(stroke
			(width 0.2)
			(type default)
		)
		(fill no)
		(layer "In10.Cu")
	)
	(gr_circle
		(center 339.739224 -352.215196)
		(end 340.628224 -352.215196)
		(stroke
			(width 0.2)
			(type default)
		)
		(fill no)
		(layer "In10.Cu")
	)
	(gr_circle
		(center 339.739224 -351.453196)
		(end 340.628224 -351.453196)
		(stroke
			(width 0.2)
			(type default)
		)
		(fill no)
		(layer "In10.Cu")
	)
	(gr_circle
		(center 340.501224 -352.215196)
		(end 341.390224 -352.215196)
		(stroke
			(width 0.2)
			(type default)
		)
		(fill no)
		(layer "In10.Cu")
	)
	(gr_circle
		(center 340.501224 -351.453196)
		(end 341.390224 -351.453196)
		(stroke
			(width 0.2)
			(type default)
		)
		(fill no)
		(layer "In10.Cu")
	)
	(gr_circle
		(center 340.667848 -353.010216)
		(end 341.556848 -353.010216)
		(stroke
			(width 0.2)
			(type default)
		)
		(fill no)
		(layer "In10.Cu")
	)
	(gr_circle
		(center 341.263224 -352.215196)
		(end 342.152224 -352.215196)
		(stroke
			(width 0.2)
			(type default)
		)
		(fill no)
		(layer "In10.Cu")
	)
	(gr_circle
		(center 341.263224 -351.453196)
		(end 342.152224 -351.453196)
		(stroke
			(width 0.2)
			(type default)
		)
		(fill no)
		(layer "In10.Cu")
	)
	(gr_circle
		(center 341.302848 -353.010216)
		(end 342.191848 -353.010216)
		(stroke
			(width 0.2)
			(type default)
		)
		(fill no)
		(layer "In10.Cu")
	)
	(gr_circle
		(center 341.937848 -353.010216)
		(end 342.826848 -353.010216)
		(stroke
			(width 0.2)
			(type default)
		)
		(fill no)
		(layer "In10.Cu")
	)
	(gr_circle
		(center 342.025224 -352.215196)
		(end 342.914224 -352.215196)
		(stroke
			(width 0.2)
			(type default)
		)
		(fill no)
		(layer "In10.Cu")
	)
	(gr_circle
		(center 342.025224 -351.453196)
		(end 342.914224 -351.453196)
		(stroke
			(width 0.2)
			(type default)
		)
		(fill no)
		(layer "In10.Cu")
	)
	(gr_circle
		(center 342.572848 -353.010216)
		(end 343.461848 -353.010216)
		(stroke
			(width 0.2)
			(type default)
		)
		(fill no)
		(layer "In10.Cu")
	)
	(gr_circle
		(center 342.787224 -352.215196)
		(end 343.676224 -352.215196)
		(stroke
			(width 0.2)
			(type default)
		)
		(fill no)
		(layer "In10.Cu")
	)
	(gr_circle
		(center 342.787224 -351.453196)
		(end 343.676224 -351.453196)
		(stroke
			(width 0.2)
			(type default)
		)
		(fill no)
		(layer "In10.Cu")
	)
	(gr_circle
		(center 343.46515 -353.006152)
		(end 344.35415 -353.006152)
		(stroke
			(width 0.2)
			(type default)
		)
		(fill no)
		(layer "In10.Cu")
	)
	(gr_circle
		(center 343.465404 -352.248216)
		(end 344.354404 -352.248216)
		(stroke
			(width 0.2)
			(type default)
		)
		(fill no)
		(layer "In10.Cu")
	)
	(gr_circle
		(center 343.465404 -351.486216)
		(end 344.354404 -351.486216)
		(stroke
			(width 0.2)
			(type default)
		)
		(fill no)
		(layer "In10.Cu")
	)
	(gr_circle
		(center 344.016838 -159.073596)
		(end 344.905838 -159.073596)
		(stroke
			(width 0.2)
			(type default)
		)
		(fill no)
		(layer "In10.Cu")
	)
	(gr_circle
		(center 344.016838 -158.336996)
		(end 344.905838 -158.336996)
		(stroke
			(width 0.2)
			(type default)
		)
		(fill no)
		(layer "In10.Cu")
	)
	(gr_circle
		(center 344.016838 -157.600396)
		(end 344.905838 -157.600396)
		(stroke
			(width 0.2)
			(type default)
		)
		(fill no)
		(layer "In10.Cu")
	)
	(gr_circle
		(center 344.0811 -337.012788)
		(end 344.96121 -337.012788)
		(stroke
			(width 0.2)
			(type default)
		)
		(fill no)
		(layer "In10.Cu")
	)
	(gr_circle
		(center 344.550238 -157.955996)
		(end 345.439238 -157.955996)
		(stroke
			(width 0.2)
			(type default)
		)
		(fill no)
		(layer "In10.Cu")
	)
	(gr_circle
		(center 344.575638 -158.717996)
		(end 345.464638 -158.717996)
		(stroke
			(width 0.2)
			(type default)
		)
		(fill no)
		(layer "In10.Cu")
	)
	(gr_circle
		(center 344.69832 -337.012788)
		(end 345.57843 -337.012788)
		(stroke
			(width 0.2)
			(type default)
		)
		(fill no)
		(layer "In10.Cu")
	)
	(gr_circle
		(center 345.100402 -158.278576)
		(end 345.989402 -158.278576)
		(stroke
			(width 0.2)
			(type default)
		)
		(fill no)
		(layer "In10.Cu")
	)
	(gr_circle
		(center 345.100402 -157.541976)
		(end 345.989402 -157.541976)
		(stroke
			(width 0.2)
			(type default)
		)
		(fill no)
		(layer "In10.Cu")
	)
	(gr_circle
		(center 345.31554 -337.012788)
		(end 346.19565 -337.012788)
		(stroke
			(width 0.2)
			(type default)
		)
		(fill no)
		(layer "In10.Cu")
	)
	(gr_circle
		(center 345.623896 -336.317336)
		(end 346.512896 -336.317336)
		(stroke
			(width 0.2)
			(type default)
		)
		(fill no)
		(layer "In10.Cu")
	)
	(gr_circle
		(center 345.623896 -335.580736)
		(end 346.512896 -335.580736)
		(stroke
			(width 0.2)
			(type default)
		)
		(fill no)
		(layer "In10.Cu")
	)
	(gr_circle
		(center 345.684856 -160.633156)
		(end 346.573856 -160.633156)
		(stroke
			(width 0.2)
			(type default)
		)
		(fill no)
		(layer "In10.Cu")
	)
	(gr_circle
		(center 345.684856 -159.896556)
		(end 346.573856 -159.896556)
		(stroke
			(width 0.2)
			(type default)
		)
		(fill no)
		(layer "In10.Cu")
	)
	(gr_circle
		(center 345.802458 -159.151066)
		(end 346.682568 -159.151066)
		(stroke
			(width 0.2)
			(type default)
		)
		(fill no)
		(layer "In10.Cu")
	)
	(gr_circle
		(center 345.921076 -278.136096)
		(end 346.175076 -278.136096)
		(stroke
			(width 0.1016)
			(type default)
		)
		(fill no)
		(layer "In10.Cu")
	)
	(gr_circle
		(center 345.921076 -276.516084)
		(end 346.175076 -276.516084)
		(stroke
			(width 0.1016)
			(type default)
		)
		(fill no)
		(layer "In10.Cu")
	)
	(gr_circle
		(center 345.921076 -274.896072)
		(end 346.175076 -274.896072)
		(stroke
			(width 0.1016)
			(type default)
		)
		(fill no)
		(layer "In10.Cu")
	)
	(gr_circle
		(center 345.921076 -273.27606)
		(end 346.175076 -273.27606)
		(stroke
			(width 0.1016)
			(type default)
		)
		(fill no)
		(layer "In10.Cu")
	)
	(gr_circle
		(center 345.921076 -271.656048)
		(end 346.175076 -271.656048)
		(stroke
			(width 0.1016)
			(type default)
		)
		(fill no)
		(layer "In10.Cu")
	)
	(gr_circle
		(center 345.921076 -270.036036)
		(end 346.175076 -270.036036)
		(stroke
			(width 0.1016)
			(type default)
		)
		(fill no)
		(layer "In10.Cu")
	)
	(gr_circle
		(center 346.017596 -339.358478)
		(end 346.906596 -339.358478)
		(stroke
			(width 0.2)
			(type default)
		)
		(fill no)
		(layer "In10.Cu")
	)
	(gr_circle
		(center 346.017596 -338.621878)
		(end 346.906596 -338.621878)
		(stroke
			(width 0.2)
			(type default)
		)
		(fill no)
		(layer "In10.Cu")
	)
	(gr_circle
		(center 346.017596 -337.885278)
		(end 346.906596 -337.885278)
		(stroke
			(width 0.2)
			(type default)
		)
		(fill no)
		(layer "In10.Cu")
	)
	(gr_circle
		(center 346.419678 -159.151066)
		(end 347.299788 -159.151066)
		(stroke
			(width 0.2)
			(type default)
		)
		(fill no)
		(layer "In10.Cu")
	)
	(gr_circle
		(center 346.54236 -337.445858)
		(end 347.43136 -337.445858)
		(stroke
			(width 0.2)
			(type default)
		)
		(fill no)
		(layer "In10.Cu")
	)
	(gr_circle
		(center 346.56776 -339.731858)
		(end 347.45676 -339.731858)
		(stroke
			(width 0.2)
			(type default)
		)
		(fill no)
		(layer "In10.Cu")
	)
	(gr_circle
		(center 346.56776 -338.969858)
		(end 347.45676 -338.969858)
		(stroke
			(width 0.2)
			(type default)
		)
		(fill no)
		(layer "In10.Cu")
	)
	(gr_circle
		(center 346.56776 -338.207858)
		(end 347.45676 -338.207858)
		(stroke
			(width 0.2)
			(type default)
		)
		(fill no)
		(layer "In10.Cu")
	)
	(gr_circle
		(center 346.86113 -278.136096)
		(end 347.11513 -278.136096)
		(stroke
			(width 0.1016)
			(type default)
		)
		(fill no)
		(layer "In10.Cu")
	)
	(gr_circle
		(center 346.86113 -276.516084)
		(end 347.11513 -276.516084)
		(stroke
			(width 0.1016)
			(type default)
		)
		(fill no)
		(layer "In10.Cu")
	)
	(gr_circle
		(center 346.86113 -274.896072)
		(end 347.11513 -274.896072)
		(stroke
			(width 0.1016)
			(type default)
		)
		(fill no)
		(layer "In10.Cu")
	)
	(gr_circle
		(center 346.86113 -273.27606)
		(end 347.11513 -273.27606)
		(stroke
			(width 0.1016)
			(type default)
		)
		(fill no)
		(layer "In10.Cu")
	)
	(gr_circle
		(center 346.86113 -271.656048)
		(end 347.11513 -271.656048)
		(stroke
			(width 0.1016)
			(type default)
		)
		(fill no)
		(layer "In10.Cu")
	)
	(gr_circle
		(center 346.86113 -270.036036)
		(end 347.11513 -270.036036)
		(stroke
			(width 0.1016)
			(type default)
		)
		(fill no)
		(layer "In10.Cu")
	)
	(gr_circle
		(center 347.036898 -159.151066)
		(end 347.917008 -159.151066)
		(stroke
			(width 0.2)
			(type default)
		)
		(fill no)
		(layer "In10.Cu")
	)
	(gr_circle
		(center 348.740984 -278.136096)
		(end 348.994984 -278.136096)
		(stroke
			(width 0.1016)
			(type default)
		)
		(fill no)
		(layer "In10.Cu")
	)
	(gr_circle
		(center 348.740984 -276.516084)
		(end 348.994984 -276.516084)
		(stroke
			(width 0.1016)
			(type default)
		)
		(fill no)
		(layer "In10.Cu")
	)
	(gr_circle
		(center 348.740984 -274.896072)
		(end 348.994984 -274.896072)
		(stroke
			(width 0.1016)
			(type default)
		)
		(fill no)
		(layer "In10.Cu")
	)
	(gr_circle
		(center 348.740984 -273.27606)
		(end 348.994984 -273.27606)
		(stroke
			(width 0.1016)
			(type default)
		)
		(fill no)
		(layer "In10.Cu")
	)
	(gr_circle
		(center 348.740984 -271.656048)
		(end 348.994984 -271.656048)
		(stroke
			(width 0.1016)
			(type default)
		)
		(fill no)
		(layer "In10.Cu")
	)
	(gr_circle
		(center 348.740984 -270.036036)
		(end 348.994984 -270.036036)
		(stroke
			(width 0.1016)
			(type default)
		)
		(fill no)
		(layer "In10.Cu")
	)
	(gr_circle
		(center 349.681038 -278.136096)
		(end 349.935038 -278.136096)
		(stroke
			(width 0.1016)
			(type default)
		)
		(fill no)
		(layer "In10.Cu")
	)
	(gr_circle
		(center 349.681038 -276.516084)
		(end 349.935038 -276.516084)
		(stroke
			(width 0.1016)
			(type default)
		)
		(fill no)
		(layer "In10.Cu")
	)
	(gr_circle
		(center 349.681038 -274.896072)
		(end 349.935038 -274.896072)
		(stroke
			(width 0.1016)
			(type default)
		)
		(fill no)
		(layer "In10.Cu")
	)
	(gr_circle
		(center 349.681038 -273.27606)
		(end 349.935038 -273.27606)
		(stroke
			(width 0.1016)
			(type default)
		)
		(fill no)
		(layer "In10.Cu")
	)
	(gr_circle
		(center 349.681038 -271.656048)
		(end 349.935038 -271.656048)
		(stroke
			(width 0.1016)
			(type default)
		)
		(fill no)
		(layer "In10.Cu")
	)
	(gr_circle
		(center 349.681038 -270.036036)
		(end 349.935038 -270.036036)
		(stroke
			(width 0.1016)
			(type default)
		)
		(fill no)
		(layer "In10.Cu")
	)
	(gr_circle
		(center 351.561146 -278.136096)
		(end 351.815146 -278.136096)
		(stroke
			(width 0.1016)
			(type default)
		)
		(fill no)
		(layer "In10.Cu")
	)
	(gr_circle
		(center 351.561146 -276.516084)
		(end 351.815146 -276.516084)
		(stroke
			(width 0.1016)
			(type default)
		)
		(fill no)
		(layer "In10.Cu")
	)
	(gr_circle
		(center 351.561146 -274.896072)
		(end 351.815146 -274.896072)
		(stroke
			(width 0.1016)
			(type default)
		)
		(fill no)
		(layer "In10.Cu")
	)
	(gr_circle
		(center 351.561146 -273.27606)
		(end 351.815146 -273.27606)
		(stroke
			(width 0.1016)
			(type default)
		)
		(fill no)
		(layer "In10.Cu")
	)
	(gr_circle
		(center 351.561146 -271.656048)
		(end 351.815146 -271.656048)
		(stroke
			(width 0.1016)
			(type default)
		)
		(fill no)
		(layer "In10.Cu")
	)
	(gr_circle
		(center 351.561146 -270.036036)
		(end 351.815146 -270.036036)
		(stroke
			(width 0.1016)
			(type default)
		)
		(fill no)
		(layer "In10.Cu")
	)
	(gr_circle
		(center 352.322638 -167.430196)
		(end 353.211638 -167.430196)
		(stroke
			(width 0.2)
			(type default)
		)
		(fill no)
		(layer "In10.Cu")
	)
	(gr_circle
		(center 352.322638 -166.693596)
		(end 353.211638 -166.693596)
		(stroke
			(width 0.2)
			(type default)
		)
		(fill no)
		(layer "In10.Cu")
	)
	(gr_circle
		(center 352.322638 -165.956996)
		(end 353.211638 -165.956996)
		(stroke
			(width 0.2)
			(type default)
		)
		(fill no)
		(layer "In10.Cu")
	)
	(gr_circle
		(center 352.356928 -341.922862)
		(end 353.237038 -341.922862)
		(stroke
			(width 0.2)
			(type default)
		)
		(fill no)
		(layer "In10.Cu")
	)
	(gr_circle
		(center 352.5012 -278.136096)
		(end 352.7552 -278.136096)
		(stroke
			(width 0.1016)
			(type default)
		)
		(fill no)
		(layer "In10.Cu")
	)
	(gr_circle
		(center 352.5012 -276.516084)
		(end 352.7552 -276.516084)
		(stroke
			(width 0.1016)
			(type default)
		)
		(fill no)
		(layer "In10.Cu")
	)
	(gr_circle
		(center 352.5012 -274.896072)
		(end 352.7552 -274.896072)
		(stroke
			(width 0.1016)
			(type default)
		)
		(fill no)
		(layer "In10.Cu")
	)
	(gr_circle
		(center 352.5012 -273.27606)
		(end 352.7552 -273.27606)
		(stroke
			(width 0.1016)
			(type default)
		)
		(fill no)
		(layer "In10.Cu")
	)
	(gr_circle
		(center 352.5012 -271.656048)
		(end 352.7552 -271.656048)
		(stroke
			(width 0.1016)
			(type default)
		)
		(fill no)
		(layer "In10.Cu")
	)
	(gr_circle
		(center 352.5012 -270.036036)
		(end 352.7552 -270.036036)
		(stroke
			(width 0.1016)
			(type default)
		)
		(fill no)
		(layer "In10.Cu")
	)
	(gr_circle
		(center 352.856038 -166.312596)
		(end 353.745038 -166.312596)
		(stroke
			(width 0.2)
			(type default)
		)
		(fill no)
		(layer "In10.Cu")
	)
	(gr_circle
		(center 352.881438 -167.074596)
		(end 353.770438 -167.074596)
		(stroke
			(width 0.2)
			(type default)
		)
		(fill no)
		(layer "In10.Cu")
	)
	(gr_circle
		(center 352.974148 -341.922862)
		(end 353.854258 -341.922862)
		(stroke
			(width 0.2)
			(type default)
		)
		(fill no)
		(layer "In10.Cu")
	)
	(gr_circle
		(center 353.406202 -166.635176)
		(end 354.295202 -166.635176)
		(stroke
			(width 0.2)
			(type default)
		)
		(fill no)
		(layer "In10.Cu")
	)
	(gr_circle
		(center 353.406202 -165.898576)
		(end 354.295202 -165.898576)
		(stroke
			(width 0.2)
			(type default)
		)
		(fill no)
		(layer "In10.Cu")
	)
	(gr_circle
		(center 353.591368 -341.922862)
		(end 354.471478 -341.922862)
		(stroke
			(width 0.2)
			(type default)
		)
		(fill no)
		(layer "In10.Cu")
	)
	(gr_circle
		(center 353.899724 -341.22741)
		(end 354.788724 -341.22741)
		(stroke
			(width 0.2)
			(type default)
		)
		(fill no)
		(layer "In10.Cu")
	)
	(gr_circle
		(center 353.899724 -340.49081)
		(end 354.788724 -340.49081)
		(stroke
			(width 0.2)
			(type default)
		)
		(fill no)
		(layer "In10.Cu")
	)
	(gr_circle
		(center 353.990656 -168.982136)
		(end 354.879656 -168.982136)
		(stroke
			(width 0.2)
			(type default)
		)
		(fill no)
		(layer "In10.Cu")
	)
	(gr_circle
		(center 353.990656 -168.245536)
		(end 354.879656 -168.245536)
		(stroke
			(width 0.2)
			(type default)
		)
		(fill no)
		(layer "In10.Cu")
	)
	(gr_circle
		(center 354.108258 -167.507666)
		(end 354.988368 -167.507666)
		(stroke
			(width 0.2)
			(type default)
		)
		(fill no)
		(layer "In10.Cu")
	)
	(gr_circle
		(center 354.293424 -343.531952)
		(end 355.182424 -343.531952)
		(stroke
			(width 0.2)
			(type default)
		)
		(fill no)
		(layer "In10.Cu")
	)
	(gr_circle
		(center 354.293424 -342.795352)
		(end 355.182424 -342.795352)
		(stroke
			(width 0.2)
			(type default)
		)
		(fill no)
		(layer "In10.Cu")
	)
	(gr_circle
		(center 354.381054 -279.756108)
		(end 354.635054 -279.756108)
		(stroke
			(width 0.1016)
			(type default)
		)
		(fill no)
		(layer "In10.Cu")
	)
	(gr_circle
		(center 354.381054 -278.136096)
		(end 354.635054 -278.136096)
		(stroke
			(width 0.1016)
			(type default)
		)
		(fill no)
		(layer "In10.Cu")
	)
	(gr_circle
		(center 354.381054 -276.516084)
		(end 354.635054 -276.516084)
		(stroke
			(width 0.1016)
			(type default)
		)
		(fill no)
		(layer "In10.Cu")
	)
	(gr_circle
		(center 354.381054 -274.896072)
		(end 354.635054 -274.896072)
		(stroke
			(width 0.1016)
			(type default)
		)
		(fill no)
		(layer "In10.Cu")
	)
	(gr_circle
		(center 354.381054 -273.27606)
		(end 354.635054 -273.27606)
		(stroke
			(width 0.1016)
			(type default)
		)
		(fill no)
		(layer "In10.Cu")
	)
	(gr_circle
		(center 354.381054 -271.656048)
		(end 354.635054 -271.656048)
		(stroke
			(width 0.1016)
			(type default)
		)
		(fill no)
		(layer "In10.Cu")
	)
	(gr_circle
		(center 354.381054 -270.036036)
		(end 354.635054 -270.036036)
		(stroke
			(width 0.1016)
			(type default)
		)
		(fill no)
		(layer "In10.Cu")
	)
	(gr_circle
		(center 354.725478 -167.507666)
		(end 355.605588 -167.507666)
		(stroke
			(width 0.2)
			(type default)
		)
		(fill no)
		(layer "In10.Cu")
	)
	(gr_circle
		(center 354.818188 -342.355932)
		(end 355.707188 -342.355932)
		(stroke
			(width 0.2)
			(type default)
		)
		(fill no)
		(layer "In10.Cu")
	)
	(gr_circle
		(center 354.843588 -343.117932)
		(end 355.732588 -343.117932)
		(stroke
			(width 0.2)
			(type default)
		)
		(fill no)
		(layer "In10.Cu")
	)
	(gr_circle
		(center 355.321108 -279.756108)
		(end 355.575108 -279.756108)
		(stroke
			(width 0.1016)
			(type default)
		)
		(fill no)
		(layer "In10.Cu")
	)
	(gr_circle
		(center 355.321108 -278.136096)
		(end 355.575108 -278.136096)
		(stroke
			(width 0.1016)
			(type default)
		)
		(fill no)
		(layer "In10.Cu")
	)
	(gr_circle
		(center 355.321108 -276.516084)
		(end 355.575108 -276.516084)
		(stroke
			(width 0.1016)
			(type default)
		)
		(fill no)
		(layer "In10.Cu")
	)
	(gr_circle
		(center 355.321108 -274.896072)
		(end 355.575108 -274.896072)
		(stroke
			(width 0.1016)
			(type default)
		)
		(fill no)
		(layer "In10.Cu")
	)
	(gr_circle
		(center 355.321108 -273.27606)
		(end 355.575108 -273.27606)
		(stroke
			(width 0.1016)
			(type default)
		)
		(fill no)
		(layer "In10.Cu")
	)
	(gr_circle
		(center 355.321108 -271.656048)
		(end 355.575108 -271.656048)
		(stroke
			(width 0.1016)
			(type default)
		)
		(fill no)
		(layer "In10.Cu")
	)
	(gr_circle
		(center 355.321108 -270.036036)
		(end 355.575108 -270.036036)
		(stroke
			(width 0.1016)
			(type default)
		)
		(fill no)
		(layer "In10.Cu")
	)
	(gr_circle
		(center 355.342698 -167.507666)
		(end 356.222808 -167.507666)
		(stroke
			(width 0.2)
			(type default)
		)
		(fill no)
		(layer "In10.Cu")
	)
	(gr_circle
		(center 355.376988 -343.473532)
		(end 356.265988 -343.473532)
		(stroke
			(width 0.2)
			(type default)
		)
		(fill no)
		(layer "In10.Cu")
	)
	(gr_circle
		(center 355.376988 -342.736932)
		(end 356.265988 -342.736932)
		(stroke
			(width 0.2)
			(type default)
		)
		(fill no)
		(layer "In10.Cu")
	)
	(gr_circle
		(center 355.376988 -342.000332)
		(end 356.265988 -342.000332)
		(stroke
			(width 0.2)
			(type default)
		)
		(fill no)
		(layer "In10.Cu")
	)
	(gr_circle
		(center 356.731062 -278.946102)
		(end 356.985062 -278.946102)
		(stroke
			(width 0.1016)
			(type default)
		)
		(fill no)
		(layer "In10.Cu")
	)
	(gr_circle
		(center 356.731062 -277.32609)
		(end 356.985062 -277.32609)
		(stroke
			(width 0.1016)
			(type default)
		)
		(fill no)
		(layer "In10.Cu")
	)
	(gr_circle
		(center 356.731062 -275.706078)
		(end 356.985062 -275.706078)
		(stroke
			(width 0.1016)
			(type default)
		)
		(fill no)
		(layer "In10.Cu")
	)
	(gr_circle
		(center 356.731062 -274.086066)
		(end 356.985062 -274.086066)
		(stroke
			(width 0.1016)
			(type default)
		)
		(fill no)
		(layer "In10.Cu")
	)
	(gr_circle
		(center 356.731062 -272.466054)
		(end 356.985062 -272.466054)
		(stroke
			(width 0.1016)
			(type default)
		)
		(fill no)
		(layer "In10.Cu")
	)
	(gr_circle
		(center 356.731062 -270.846042)
		(end 356.985062 -270.846042)
		(stroke
			(width 0.1016)
			(type default)
		)
		(fill no)
		(layer "In10.Cu")
	)
	(gr_circle
		(center 356.731062 -269.22603)
		(end 356.985062 -269.22603)
		(stroke
			(width 0.1016)
			(type default)
		)
		(fill no)
		(layer "In10.Cu")
	)
	(gr_circle
		(center 357.671116 -278.946102)
		(end 357.925116 -278.946102)
		(stroke
			(width 0.1016)
			(type default)
		)
		(fill no)
		(layer "In10.Cu")
	)
	(gr_circle
		(center 357.671116 -277.32609)
		(end 357.925116 -277.32609)
		(stroke
			(width 0.1016)
			(type default)
		)
		(fill no)
		(layer "In10.Cu")
	)
	(gr_circle
		(center 357.671116 -275.706078)
		(end 357.925116 -275.706078)
		(stroke
			(width 0.1016)
			(type default)
		)
		(fill no)
		(layer "In10.Cu")
	)
	(gr_circle
		(center 357.671116 -274.086066)
		(end 357.925116 -274.086066)
		(stroke
			(width 0.1016)
			(type default)
		)
		(fill no)
		(layer "In10.Cu")
	)
	(gr_circle
		(center 357.671116 -272.466054)
		(end 357.925116 -272.466054)
		(stroke
			(width 0.1016)
			(type default)
		)
		(fill no)
		(layer "In10.Cu")
	)
	(gr_circle
		(center 357.671116 -270.846042)
		(end 357.925116 -270.846042)
		(stroke
			(width 0.1016)
			(type default)
		)
		(fill no)
		(layer "In10.Cu")
	)
	(gr_circle
		(center 357.671116 -269.22603)
		(end 357.925116 -269.22603)
		(stroke
			(width 0.1016)
			(type default)
		)
		(fill no)
		(layer "In10.Cu")
	)
	(gr_circle
		(center 359.58526 -152.71242)
		(end 360.98226 -152.71242)
		(stroke
			(width 0.2)
			(type default)
		)
		(fill no)
		(layer "In10.Cu")
	)
	(gr_circle
		(center 360.603038 -175.705516)
		(end 361.492038 -175.705516)
		(stroke
			(width 0.2)
			(type default)
		)
		(fill no)
		(layer "In10.Cu")
	)
	(gr_circle
		(center 360.603038 -174.968916)
		(end 361.492038 -174.968916)
		(stroke
			(width 0.2)
			(type default)
		)
		(fill no)
		(layer "In10.Cu")
	)
	(gr_circle
		(center 360.603038 -174.232316)
		(end 361.492038 -174.232316)
		(stroke
			(width 0.2)
			(type default)
		)
		(fill no)
		(layer "In10.Cu")
	)
	(gr_circle
		(center 361.136438 -174.587916)
		(end 362.025438 -174.587916)
		(stroke
			(width 0.2)
			(type default)
		)
		(fill no)
		(layer "In10.Cu")
	)
	(gr_circle
		(center 361.161838 -175.349916)
		(end 362.050838 -175.349916)
		(stroke
			(width 0.2)
			(type default)
		)
		(fill no)
		(layer "In10.Cu")
	)
	(gr_circle
		(center 361.686602 -174.910496)
		(end 362.575602 -174.910496)
		(stroke
			(width 0.2)
			(type default)
		)
		(fill no)
		(layer "In10.Cu")
	)
	(gr_circle
		(center 361.686602 -174.173896)
		(end 362.575602 -174.173896)
		(stroke
			(width 0.2)
			(type default)
		)
		(fill no)
		(layer "In10.Cu")
	)
	(gr_circle
		(center 362.271056 -177.254916)
		(end 363.160056 -177.254916)
		(stroke
			(width 0.2)
			(type default)
		)
		(fill no)
		(layer "In10.Cu")
	)
	(gr_circle
		(center 362.271056 -176.518316)
		(end 363.160056 -176.518316)
		(stroke
			(width 0.2)
			(type default)
		)
		(fill no)
		(layer "In10.Cu")
	)
	(gr_circle
		(center 362.364782 -278.946102)
		(end 362.618782 -278.946102)
		(stroke
			(width 0.1016)
			(type default)
		)
		(fill no)
		(layer "In10.Cu")
	)
	(gr_circle
		(center 362.364782 -277.32609)
		(end 362.618782 -277.32609)
		(stroke
			(width 0.1016)
			(type default)
		)
		(fill no)
		(layer "In10.Cu")
	)
	(gr_circle
		(center 362.364782 -275.706078)
		(end 362.618782 -275.706078)
		(stroke
			(width 0.1016)
			(type default)
		)
		(fill no)
		(layer "In10.Cu")
	)
	(gr_circle
		(center 362.364782 -274.086066)
		(end 362.618782 -274.086066)
		(stroke
			(width 0.1016)
			(type default)
		)
		(fill no)
		(layer "In10.Cu")
	)
	(gr_circle
		(center 362.364782 -272.466054)
		(end 362.618782 -272.466054)
		(stroke
			(width 0.1016)
			(type default)
		)
		(fill no)
		(layer "In10.Cu")
	)
	(gr_circle
		(center 362.364782 -270.846042)
		(end 362.618782 -270.846042)
		(stroke
			(width 0.1016)
			(type default)
		)
		(fill no)
		(layer "In10.Cu")
	)
	(gr_circle
		(center 362.364782 -269.22603)
		(end 362.618782 -269.22603)
		(stroke
			(width 0.1016)
			(type default)
		)
		(fill no)
		(layer "In10.Cu")
	)
	(gr_circle
		(center 362.396278 -175.859186)
		(end 363.276388 -175.859186)
		(stroke
			(width 0.2)
			(type default)
		)
		(fill no)
		(layer "In10.Cu")
	)
	(gr_circle
		(center 363.013498 -175.859186)
		(end 363.893608 -175.859186)
		(stroke
			(width 0.2)
			(type default)
		)
		(fill no)
		(layer "In10.Cu")
	)
	(gr_circle
		(center 363.304836 -278.946102)
		(end 363.558836 -278.946102)
		(stroke
			(width 0.1016)
			(type default)
		)
		(fill no)
		(layer "In10.Cu")
	)
	(gr_circle
		(center 363.304836 -277.32609)
		(end 363.558836 -277.32609)
		(stroke
			(width 0.1016)
			(type default)
		)
		(fill no)
		(layer "In10.Cu")
	)
	(gr_circle
		(center 363.304836 -275.706078)
		(end 363.558836 -275.706078)
		(stroke
			(width 0.1016)
			(type default)
		)
		(fill no)
		(layer "In10.Cu")
	)
	(gr_circle
		(center 363.304836 -274.086066)
		(end 363.558836 -274.086066)
		(stroke
			(width 0.1016)
			(type default)
		)
		(fill no)
		(layer "In10.Cu")
	)
	(gr_circle
		(center 363.304836 -272.466054)
		(end 363.558836 -272.466054)
		(stroke
			(width 0.1016)
			(type default)
		)
		(fill no)
		(layer "In10.Cu")
	)
	(gr_circle
		(center 363.304836 -270.846042)
		(end 363.558836 -270.846042)
		(stroke
			(width 0.1016)
			(type default)
		)
		(fill no)
		(layer "In10.Cu")
	)
	(gr_circle
		(center 363.304836 -269.22603)
		(end 363.558836 -269.22603)
		(stroke
			(width 0.1016)
			(type default)
		)
		(fill no)
		(layer "In10.Cu")
	)
	(gr_circle
		(center 363.630718 -175.859186)
		(end 364.510828 -175.859186)
		(stroke
			(width 0.2)
			(type default)
		)
		(fill no)
		(layer "In10.Cu")
	)
	(gr_circle
		(center 364.71479 -279.756108)
		(end 364.96879 -279.756108)
		(stroke
			(width 0.1016)
			(type default)
		)
		(fill no)
		(layer "In10.Cu")
	)
	(gr_circle
		(center 364.71479 -278.136096)
		(end 364.96879 -278.136096)
		(stroke
			(width 0.1016)
			(type default)
		)
		(fill no)
		(layer "In10.Cu")
	)
	(gr_circle
		(center 364.71479 -276.516084)
		(end 364.96879 -276.516084)
		(stroke
			(width 0.1016)
			(type default)
		)
		(fill no)
		(layer "In10.Cu")
	)
	(gr_circle
		(center 364.71479 -274.896072)
		(end 364.96879 -274.896072)
		(stroke
			(width 0.1016)
			(type default)
		)
		(fill no)
		(layer "In10.Cu")
	)
	(gr_circle
		(center 364.71479 -273.27606)
		(end 364.96879 -273.27606)
		(stroke
			(width 0.1016)
			(type default)
		)
		(fill no)
		(layer "In10.Cu")
	)
	(gr_circle
		(center 364.71479 -271.656048)
		(end 364.96879 -271.656048)
		(stroke
			(width 0.1016)
			(type default)
		)
		(fill no)
		(layer "In10.Cu")
	)
	(gr_circle
		(center 364.71479 -270.036036)
		(end 364.96879 -270.036036)
		(stroke
			(width 0.1016)
			(type default)
		)
		(fill no)
		(layer "In10.Cu")
	)
	(gr_circle
		(center 365.654844 -279.756108)
		(end 365.908844 -279.756108)
		(stroke
			(width 0.1016)
			(type default)
		)
		(fill no)
		(layer "In10.Cu")
	)
	(gr_circle
		(center 365.654844 -278.136096)
		(end 365.908844 -278.136096)
		(stroke
			(width 0.1016)
			(type default)
		)
		(fill no)
		(layer "In10.Cu")
	)
	(gr_circle
		(center 365.654844 -276.516084)
		(end 365.908844 -276.516084)
		(stroke
			(width 0.1016)
			(type default)
		)
		(fill no)
		(layer "In10.Cu")
	)
	(gr_circle
		(center 365.654844 -274.896072)
		(end 365.908844 -274.896072)
		(stroke
			(width 0.1016)
			(type default)
		)
		(fill no)
		(layer "In10.Cu")
	)
	(gr_circle
		(center 365.654844 -273.27606)
		(end 365.908844 -273.27606)
		(stroke
			(width 0.1016)
			(type default)
		)
		(fill no)
		(layer "In10.Cu")
	)
	(gr_circle
		(center 365.654844 -271.656048)
		(end 365.908844 -271.656048)
		(stroke
			(width 0.1016)
			(type default)
		)
		(fill no)
		(layer "In10.Cu")
	)
	(gr_circle
		(center 365.654844 -270.036036)
		(end 365.908844 -270.036036)
		(stroke
			(width 0.1016)
			(type default)
		)
		(fill no)
		(layer "In10.Cu")
	)
	(gr_circle
		(center 366.744504 -164.53358)
		(end 367.633504 -164.53358)
		(stroke
			(width 0.2)
			(type default)
		)
		(fill no)
		(layer "In10.Cu")
	)
	(gr_circle
		(center 366.744504 -163.89858)
		(end 367.633504 -163.89858)
		(stroke
			(width 0.2)
			(type default)
		)
		(fill no)
		(layer "In10.Cu")
	)
	(gr_circle
		(center 366.757204 -165.19398)
		(end 367.646204 -165.19398)
		(stroke
			(width 0.2)
			(type default)
		)
		(fill no)
		(layer "In10.Cu")
	)
	(gr_circle
		(center 367.379504 -164.53358)
		(end 368.268504 -164.53358)
		(stroke
			(width 0.2)
			(type default)
		)
		(fill no)
		(layer "In10.Cu")
	)
	(gr_circle
		(center 367.379504 -163.89858)
		(end 368.268504 -163.89858)
		(stroke
			(width 0.2)
			(type default)
		)
		(fill no)
		(layer "In10.Cu")
	)
	(gr_circle
		(center 367.392204 -165.19398)
		(end 368.281204 -165.19398)
		(stroke
			(width 0.2)
			(type default)
		)
		(fill no)
		(layer "In10.Cu")
	)
	(gr_circle
		(center 367.534698 -278.136096)
		(end 367.788698 -278.136096)
		(stroke
			(width 0.1016)
			(type default)
		)
		(fill no)
		(layer "In10.Cu")
	)
	(gr_circle
		(center 367.534698 -276.516084)
		(end 367.788698 -276.516084)
		(stroke
			(width 0.1016)
			(type default)
		)
		(fill no)
		(layer "In10.Cu")
	)
	(gr_circle
		(center 367.534698 -274.896072)
		(end 367.788698 -274.896072)
		(stroke
			(width 0.1016)
			(type default)
		)
		(fill no)
		(layer "In10.Cu")
	)
	(gr_circle
		(center 367.534698 -273.27606)
		(end 367.788698 -273.27606)
		(stroke
			(width 0.1016)
			(type default)
		)
		(fill no)
		(layer "In10.Cu")
	)
	(gr_circle
		(center 367.534698 -271.656048)
		(end 367.788698 -271.656048)
		(stroke
			(width 0.1016)
			(type default)
		)
		(fill no)
		(layer "In10.Cu")
	)
	(gr_circle
		(center 367.534698 -270.036036)
		(end 367.788698 -270.036036)
		(stroke
			(width 0.1016)
			(type default)
		)
		(fill no)
		(layer "In10.Cu")
	)
	(gr_circle
		(center 368.044984 -164.53358)
		(end 368.933984 -164.53358)
		(stroke
			(width 0.2)
			(type default)
		)
		(fill no)
		(layer "In10.Cu")
	)
	(gr_circle
		(center 368.044984 -163.89858)
		(end 368.933984 -163.89858)
		(stroke
			(width 0.2)
			(type default)
		)
		(fill no)
		(layer "In10.Cu")
	)
	(gr_circle
		(center 368.057684 -165.19398)
		(end 368.946684 -165.19398)
		(stroke
			(width 0.2)
			(type default)
		)
		(fill no)
		(layer "In10.Cu")
	)
	(gr_circle
		(center 368.474752 -278.136096)
		(end 368.728752 -278.136096)
		(stroke
			(width 0.1016)
			(type default)
		)
		(fill no)
		(layer "In10.Cu")
	)
	(gr_circle
		(center 368.474752 -276.516084)
		(end 368.728752 -276.516084)
		(stroke
			(width 0.1016)
			(type default)
		)
		(fill no)
		(layer "In10.Cu")
	)
	(gr_circle
		(center 368.474752 -274.896072)
		(end 368.728752 -274.896072)
		(stroke
			(width 0.1016)
			(type default)
		)
		(fill no)
		(layer "In10.Cu")
	)
	(gr_circle
		(center 368.474752 -273.27606)
		(end 368.728752 -273.27606)
		(stroke
			(width 0.1016)
			(type default)
		)
		(fill no)
		(layer "In10.Cu")
	)
	(gr_circle
		(center 368.474752 -271.656048)
		(end 368.728752 -271.656048)
		(stroke
			(width 0.1016)
			(type default)
		)
		(fill no)
		(layer "In10.Cu")
	)
	(gr_circle
		(center 368.474752 -270.036036)
		(end 368.728752 -270.036036)
		(stroke
			(width 0.1016)
			(type default)
		)
		(fill no)
		(layer "In10.Cu")
	)
	(gr_circle
		(center 368.679984 -164.53358)
		(end 369.568984 -164.53358)
		(stroke
			(width 0.2)
			(type default)
		)
		(fill no)
		(layer "In10.Cu")
	)
	(gr_circle
		(center 368.679984 -163.89858)
		(end 369.568984 -163.89858)
		(stroke
			(width 0.2)
			(type default)
		)
		(fill no)
		(layer "In10.Cu")
	)
	(gr_circle
		(center 368.692684 -165.19398)
		(end 369.581684 -165.19398)
		(stroke
			(width 0.2)
			(type default)
		)
		(fill no)
		(layer "In10.Cu")
	)
	(gr_circle
		(center 368.96421 -179.204874)
		(end 369.85321 -179.204874)
		(stroke
			(width 0.2)
			(type default)
		)
		(fill no)
		(layer "In10.Cu")
	)
	(gr_circle
		(center 369.314984 -164.53358)
		(end 370.203984 -164.53358)
		(stroke
			(width 0.2)
			(type default)
		)
		(fill no)
		(layer "In10.Cu")
	)
	(gr_circle
		(center 369.314984 -163.89858)
		(end 370.203984 -163.89858)
		(stroke
			(width 0.2)
			(type default)
		)
		(fill no)
		(layer "In10.Cu")
	)
	(gr_circle
		(center 369.327684 -165.19398)
		(end 370.216684 -165.19398)
		(stroke
			(width 0.2)
			(type default)
		)
		(fill no)
		(layer "In10.Cu")
	)
	(gr_circle
		(center 369.49761 -179.560474)
		(end 370.38661 -179.560474)
		(stroke
			(width 0.2)
			(type default)
		)
		(fill no)
		(layer "In10.Cu")
	)
	(gr_circle
		(center 369.49761 -178.798474)
		(end 370.38661 -178.798474)
		(stroke
			(width 0.2)
			(type default)
		)
		(fill no)
		(layer "In10.Cu")
	)
	(gr_circle
		(center 369.49761 -178.036474)
		(end 370.38661 -178.036474)
		(stroke
			(width 0.2)
			(type default)
		)
		(fill no)
		(layer "In10.Cu")
	)
	(gr_circle
		(center 369.52301 -180.322474)
		(end 370.41201 -180.322474)
		(stroke
			(width 0.2)
			(type default)
		)
		(fill no)
		(layer "In10.Cu")
	)
	(gr_circle
		(center 369.949984 -164.53358)
		(end 370.838984 -164.53358)
		(stroke
			(width 0.2)
			(type default)
		)
		(fill no)
		(layer "In10.Cu")
	)
	(gr_circle
		(center 369.949984 -163.89858)
		(end 370.838984 -163.89858)
		(stroke
			(width 0.2)
			(type default)
		)
		(fill no)
		(layer "In10.Cu")
	)
	(gr_circle
		(center 369.962684 -165.19398)
		(end 370.851684 -165.19398)
		(stroke
			(width 0.2)
			(type default)
		)
		(fill no)
		(layer "In10.Cu")
	)
	(gr_circle
		(center 370.047774 -179.883054)
		(end 370.936774 -179.883054)
		(stroke
			(width 0.2)
			(type default)
		)
		(fill no)
		(layer "In10.Cu")
	)
	(gr_circle
		(center 370.047774 -179.146454)
		(end 370.936774 -179.146454)
		(stroke
			(width 0.2)
			(type default)
		)
		(fill no)
		(layer "In10.Cu")
	)
	(gr_circle
		(center 370.35486 -278.136096)
		(end 370.60886 -278.136096)
		(stroke
			(width 0.1016)
			(type default)
		)
		(fill no)
		(layer "In10.Cu")
	)
	(gr_circle
		(center 370.35486 -276.516084)
		(end 370.60886 -276.516084)
		(stroke
			(width 0.1016)
			(type default)
		)
		(fill no)
		(layer "In10.Cu")
	)
	(gr_circle
		(center 370.35486 -274.896072)
		(end 370.60886 -274.896072)
		(stroke
			(width 0.1016)
			(type default)
		)
		(fill no)
		(layer "In10.Cu")
	)
	(gr_circle
		(center 370.35486 -273.27606)
		(end 370.60886 -273.27606)
		(stroke
			(width 0.1016)
			(type default)
		)
		(fill no)
		(layer "In10.Cu")
	)
	(gr_circle
		(center 370.35486 -271.656048)
		(end 370.60886 -271.656048)
		(stroke
			(width 0.1016)
			(type default)
		)
		(fill no)
		(layer "In10.Cu")
	)
	(gr_circle
		(center 370.35486 -270.036036)
		(end 370.60886 -270.036036)
		(stroke
			(width 0.1016)
			(type default)
		)
		(fill no)
		(layer "In10.Cu")
	)
	(gr_circle
		(center 370.529358 -182.141876)
		(end 371.418358 -182.141876)
		(stroke
			(width 0.2)
			(type default)
		)
		(fill no)
		(layer "In10.Cu")
	)
	(gr_circle
		(center 370.529358 -181.405276)
		(end 371.418358 -181.405276)
		(stroke
			(width 0.2)
			(type default)
		)
		(fill no)
		(layer "In10.Cu")
	)
	(gr_circle
		(center 370.686584 -164.53358)
		(end 371.575584 -164.53358)
		(stroke
			(width 0.2)
			(type default)
		)
		(fill no)
		(layer "In10.Cu")
	)
	(gr_circle
		(center 370.686584 -163.89858)
		(end 371.575584 -163.89858)
		(stroke
			(width 0.2)
			(type default)
		)
		(fill no)
		(layer "In10.Cu")
	)
	(gr_circle
		(center 370.699284 -165.19398)
		(end 371.588284 -165.19398)
		(stroke
			(width 0.2)
			(type default)
		)
		(fill no)
		(layer "In10.Cu")
	)
	(gr_circle
		(center 370.74221 -180.803804)
		(end 371.62232 -180.803804)
		(stroke
			(width 0.2)
			(type default)
		)
		(fill no)
		(layer "In10.Cu")
	)
	(gr_circle
		(center 371.294914 -278.136096)
		(end 371.548914 -278.136096)
		(stroke
			(width 0.1016)
			(type default)
		)
		(fill no)
		(layer "In10.Cu")
	)
	(gr_circle
		(center 371.294914 -276.516084)
		(end 371.548914 -276.516084)
		(stroke
			(width 0.1016)
			(type default)
		)
		(fill no)
		(layer "In10.Cu")
	)
	(gr_circle
		(center 371.294914 -274.896072)
		(end 371.548914 -274.896072)
		(stroke
			(width 0.1016)
			(type default)
		)
		(fill no)
		(layer "In10.Cu")
	)
	(gr_circle
		(center 371.294914 -273.27606)
		(end 371.548914 -273.27606)
		(stroke
			(width 0.1016)
			(type default)
		)
		(fill no)
		(layer "In10.Cu")
	)
	(gr_circle
		(center 371.294914 -271.656048)
		(end 371.548914 -271.656048)
		(stroke
			(width 0.1016)
			(type default)
		)
		(fill no)
		(layer "In10.Cu")
	)
	(gr_circle
		(center 371.294914 -270.036036)
		(end 371.548914 -270.036036)
		(stroke
			(width 0.1016)
			(type default)
		)
		(fill no)
		(layer "In10.Cu")
	)
	(gr_circle
		(center 371.35943 -180.803804)
		(end 372.23954 -180.803804)
		(stroke
			(width 0.2)
			(type default)
		)
		(fill no)
		(layer "In10.Cu")
	)
	(gr_circle
		(center 371.97665 -180.803804)
		(end 372.85676 -180.803804)
		(stroke
			(width 0.2)
			(type default)
		)
		(fill no)
		(layer "In10.Cu")
	)
	(gr_circle
		(center 373.174768 -278.136096)
		(end 373.428768 -278.136096)
		(stroke
			(width 0.1016)
			(type default)
		)
		(fill no)
		(layer "In10.Cu")
	)
	(gr_circle
		(center 373.174768 -276.516084)
		(end 373.428768 -276.516084)
		(stroke
			(width 0.1016)
			(type default)
		)
		(fill no)
		(layer "In10.Cu")
	)
	(gr_circle
		(center 373.174768 -274.896072)
		(end 373.428768 -274.896072)
		(stroke
			(width 0.1016)
			(type default)
		)
		(fill no)
		(layer "In10.Cu")
	)
	(gr_circle
		(center 373.174768 -273.27606)
		(end 373.428768 -273.27606)
		(stroke
			(width 0.1016)
			(type default)
		)
		(fill no)
		(layer "In10.Cu")
	)
	(gr_circle
		(center 373.174768 -271.656048)
		(end 373.428768 -271.656048)
		(stroke
			(width 0.1016)
			(type default)
		)
		(fill no)
		(layer "In10.Cu")
	)
	(gr_circle
		(center 373.174768 -270.036036)
		(end 373.428768 -270.036036)
		(stroke
			(width 0.1016)
			(type default)
		)
		(fill no)
		(layer "In10.Cu")
	)
	(gr_circle
		(center 374.114822 -278.136096)
		(end 374.368822 -278.136096)
		(stroke
			(width 0.1016)
			(type default)
		)
		(fill no)
		(layer "In10.Cu")
	)
	(gr_circle
		(center 374.114822 -276.516084)
		(end 374.368822 -276.516084)
		(stroke
			(width 0.1016)
			(type default)
		)
		(fill no)
		(layer "In10.Cu")
	)
	(gr_circle
		(center 374.114822 -274.896072)
		(end 374.368822 -274.896072)
		(stroke
			(width 0.1016)
			(type default)
		)
		(fill no)
		(layer "In10.Cu")
	)
	(gr_circle
		(center 374.114822 -273.27606)
		(end 374.368822 -273.27606)
		(stroke
			(width 0.1016)
			(type default)
		)
		(fill no)
		(layer "In10.Cu")
	)
	(gr_circle
		(center 374.114822 -271.656048)
		(end 374.368822 -271.656048)
		(stroke
			(width 0.1016)
			(type default)
		)
		(fill no)
		(layer "In10.Cu")
	)
	(gr_circle
		(center 374.114822 -270.036036)
		(end 374.368822 -270.036036)
		(stroke
			(width 0.1016)
			(type default)
		)
		(fill no)
		(layer "In10.Cu")
	)
	(gr_circle
		(center 377.367038 -180.678074)
		(end 378.256038 -180.678074)
		(stroke
			(width 0.2)
			(type default)
		)
		(fill no)
		(layer "In10.Cu")
	)
	(gr_circle
		(center 377.367038 -179.941474)
		(end 378.256038 -179.941474)
		(stroke
			(width 0.2)
			(type default)
		)
		(fill no)
		(layer "In10.Cu")
	)
	(gr_circle
		(center 377.367038 -179.204874)
		(end 378.256038 -179.204874)
		(stroke
			(width 0.2)
			(type default)
		)
		(fill no)
		(layer "In10.Cu")
	)
	(gr_circle
		(center 377.869958 -162.59683)
		(end 379.266958 -162.59683)
		(stroke
			(width 0.2)
			(type default)
		)
		(fill no)
		(layer "In10.Cu")
	)
	(gr_circle
		(center 377.900438 -179.560474)
		(end 378.789438 -179.560474)
		(stroke
			(width 0.2)
			(type default)
		)
		(fill no)
		(layer "In10.Cu")
	)
	(gr_circle
		(center 377.925838 -180.322474)
		(end 378.814838 -180.322474)
		(stroke
			(width 0.2)
			(type default)
		)
		(fill no)
		(layer "In10.Cu")
	)
	(gr_circle
		(center 378.450602 -179.883054)
		(end 379.339602 -179.883054)
		(stroke
			(width 0.2)
			(type default)
		)
		(fill no)
		(layer "In10.Cu")
	)
	(gr_circle
		(center 378.450602 -179.146454)
		(end 379.339602 -179.146454)
		(stroke
			(width 0.2)
			(type default)
		)
		(fill no)
		(layer "In10.Cu")
	)
	(gr_circle
		(center 379.035056 -182.230776)
		(end 379.924056 -182.230776)
		(stroke
			(width 0.2)
			(type default)
		)
		(fill no)
		(layer "In10.Cu")
	)
	(gr_circle
		(center 379.035056 -181.494176)
		(end 379.924056 -181.494176)
		(stroke
			(width 0.2)
			(type default)
		)
		(fill no)
		(layer "In10.Cu")
	)
	(gr_circle
		(center 379.152658 -180.755544)
		(end 380.032768 -180.755544)
		(stroke
			(width 0.2)
			(type default)
		)
		(fill no)
		(layer "In10.Cu")
	)
	(gr_circle
		(center 379.769878 -180.755544)
		(end 380.649988 -180.755544)
		(stroke
			(width 0.2)
			(type default)
		)
		(fill no)
		(layer "In10.Cu")
	)
	(gr_circle
		(center 380.387098 -180.755544)
		(end 381.267208 -180.755544)
		(stroke
			(width 0.2)
			(type default)
		)
		(fill no)
		(layer "In10.Cu")
	)
	(gr_arc
		(start 385.601972 -11.780012)
		(mid 387.016183 -11.194227)
		(end 387.601968 -9.780016)
		(stroke
			(width 1.016)
			(type default)
		)
		(layer "In10.Cu")
	)
	(gr_circle
		(center 385.698238 -180.678074)
		(end 386.587238 -180.678074)
		(stroke
			(width 0.2)
			(type default)
		)
		(fill no)
		(layer "In10.Cu")
	)
	(gr_circle
		(center 385.698238 -179.941474)
		(end 386.587238 -179.941474)
		(stroke
			(width 0.2)
			(type default)
		)
		(fill no)
		(layer "In10.Cu")
	)
	(gr_circle
		(center 385.698238 -179.204874)
		(end 386.587238 -179.204874)
		(stroke
			(width 0.2)
			(type default)
		)
		(fill no)
		(layer "In10.Cu")
	)
	(gr_circle
		(center 386.231638 -179.560474)
		(end 387.120638 -179.560474)
		(stroke
			(width 0.2)
			(type default)
		)
		(fill no)
		(layer "In10.Cu")
	)
	(gr_circle
		(center 386.257038 -180.322474)
		(end 387.146038 -180.322474)
		(stroke
			(width 0.2)
			(type default)
		)
		(fill no)
		(layer "In10.Cu")
	)
	(gr_circle
		(center 386.781802 -179.883054)
		(end 387.670802 -179.883054)
		(stroke
			(width 0.2)
			(type default)
		)
		(fill no)
		(layer "In10.Cu")
	)
	(gr_circle
		(center 386.781802 -179.146454)
		(end 387.670802 -179.146454)
		(stroke
			(width 0.2)
			(type default)
		)
		(fill no)
		(layer "In10.Cu")
	)
	(gr_circle
		(center 387.206998 -162.65271)
		(end 388.603998 -162.65271)
		(stroke
			(width 0.2)
			(type default)
		)
		(fill no)
		(layer "In10.Cu")
	)
	(gr_circle
		(center 387.293358 -157.001972)
		(end 388.182358 -157.001972)
		(stroke
			(width 0.2)
			(type default)
		)
		(fill no)
		(layer "In10.Cu")
	)
	(gr_circle
		(center 387.293358 -156.366972)
		(end 388.182358 -156.366972)
		(stroke
			(width 0.2)
			(type default)
		)
		(fill no)
		(layer "In10.Cu")
	)
	(gr_circle
		(center 387.293358 -155.724352)
		(end 388.182358 -155.724352)
		(stroke
			(width 0.2)
			(type default)
		)
		(fill no)
		(layer "In10.Cu")
	)
	(gr_circle
		(center 387.293358 -155.089352)
		(end 388.182358 -155.089352)
		(stroke
			(width 0.2)
			(type default)
		)
		(fill no)
		(layer "In10.Cu")
	)
	(gr_circle
		(center 387.293358 -154.428952)
		(end 388.182358 -154.428952)
		(stroke
			(width 0.2)
			(type default)
		)
		(fill no)
		(layer "In10.Cu")
	)
	(gr_circle
		(center 387.293358 -153.793952)
		(end 388.182358 -153.793952)
		(stroke
			(width 0.2)
			(type default)
		)
		(fill no)
		(layer "In10.Cu")
	)
	(gr_circle
		(center 387.366256 -182.230776)
		(end 388.255256 -182.230776)
		(stroke
			(width 0.2)
			(type default)
		)
		(fill no)
		(layer "In10.Cu")
	)
	(gr_circle
		(center 387.366256 -181.494176)
		(end 388.255256 -181.494176)
		(stroke
			(width 0.2)
			(type default)
		)
		(fill no)
		(layer "In10.Cu")
	)
	(gr_circle
		(center 387.483858 -180.755544)
		(end 388.363968 -180.755544)
		(stroke
			(width 0.2)
			(type default)
		)
		(fill no)
		(layer "In10.Cu")
	)
	(gr_line
		(start 387.601968 -9.780016)
		(end 387.601968 -0.500126)
		(stroke
			(width 1.016)
			(type default)
		)
		(layer "In10.Cu")
	)
	(gr_circle
		(center 387.928358 -157.001972)
		(end 388.817358 -157.001972)
		(stroke
			(width 0.2)
			(type default)
		)
		(fill no)
		(layer "In10.Cu")
	)
	(gr_circle
		(center 387.928358 -156.366972)
		(end 388.817358 -156.366972)
		(stroke
			(width 0.2)
			(type default)
		)
		(fill no)
		(layer "In10.Cu")
	)
	(gr_circle
		(center 387.928358 -155.724352)
		(end 388.817358 -155.724352)
		(stroke
			(width 0.2)
			(type default)
		)
		(fill no)
		(layer "In10.Cu")
	)
	(gr_circle
		(center 387.928358 -155.089352)
		(end 388.817358 -155.089352)
		(stroke
			(width 0.2)
			(type default)
		)
		(fill no)
		(layer "In10.Cu")
	)
	(gr_circle
		(center 387.928358 -154.428952)
		(end 388.817358 -154.428952)
		(stroke
			(width 0.2)
			(type default)
		)
		(fill no)
		(layer "In10.Cu")
	)
	(gr_circle
		(center 387.928358 -153.793952)
		(end 388.817358 -153.793952)
		(stroke
			(width 0.2)
			(type default)
		)
		(fill no)
		(layer "In10.Cu")
	)
	(gr_circle
		(center 388.101078 -180.755544)
		(end 388.981188 -180.755544)
		(stroke
			(width 0.2)
			(type default)
		)
		(fill no)
		(layer "In10.Cu")
	)
	(gr_arc
		(start 388.102094 0)
		(mid 387.748465 -0.146487)
		(end 387.601968 -0.500126)
		(stroke
			(width 1.016)
			(type default)
		)
		(layer "In10.Cu")
	)
	(gr_line
		(start 388.102094 0)
		(end 455.701908 0)
		(stroke
			(width 1.016)
			(type default)
		)
		(layer "In10.Cu")
	)
	(gr_circle
		(center 388.718298 -180.755544)
		(end 389.598408 -180.755544)
		(stroke
			(width 0.2)
			(type default)
		)
		(fill no)
		(layer "In10.Cu")
	)
	(gr_circle
		(center 394.628878 -173.21911)
		(end 395.517878 -173.21911)
		(stroke
			(width 0.2)
			(type default)
		)
		(fill no)
		(layer "In10.Cu")
	)
	(gr_circle
		(center 394.628878 -172.45711)
		(end 395.517878 -172.45711)
		(stroke
			(width 0.2)
			(type default)
		)
		(fill no)
		(layer "In10.Cu")
	)
	(gr_circle
		(center 394.646658 -173.987714)
		(end 395.535658 -173.987714)
		(stroke
			(width 0.2)
			(type default)
		)
		(fill no)
		(layer "In10.Cu")
	)
	(gr_circle
		(center 394.672058 -174.749714)
		(end 395.561058 -174.749714)
		(stroke
			(width 0.2)
			(type default)
		)
		(fill no)
		(layer "In10.Cu")
	)
	(gr_circle
		(center 395.196822 -174.310294)
		(end 396.085822 -174.310294)
		(stroke
			(width 0.2)
			(type default)
		)
		(fill no)
		(layer "In10.Cu")
	)
	(gr_circle
		(center 395.196822 -173.573694)
		(end 396.085822 -173.573694)
		(stroke
			(width 0.2)
			(type default)
		)
		(fill no)
		(layer "In10.Cu")
	)
	(gr_circle
		(center 395.230858 -172.819314)
		(end 396.119858 -172.819314)
		(stroke
			(width 0.2)
			(type default)
		)
		(fill no)
		(layer "In10.Cu")
	)
	(gr_circle
		(center 395.781276 -176.657254)
		(end 396.670276 -176.657254)
		(stroke
			(width 0.2)
			(type default)
		)
		(fill no)
		(layer "In10.Cu")
	)
	(gr_circle
		(center 395.781276 -175.895254)
		(end 396.670276 -175.895254)
		(stroke
			(width 0.2)
			(type default)
		)
		(fill no)
		(layer "In10.Cu")
	)
	(gr_circle
		(center 395.898878 -175.182784)
		(end 396.778988 -175.182784)
		(stroke
			(width 0.2)
			(type default)
		)
		(fill no)
		(layer "In10.Cu")
	)
	(gr_circle
		(center 396.516098 -175.182784)
		(end 397.396208 -175.182784)
		(stroke
			(width 0.2)
			(type default)
		)
		(fill no)
		(layer "In10.Cu")
	)
	(gr_circle
		(center 397.133318 -175.182784)
		(end 398.013428 -175.182784)
		(stroke
			(width 0.2)
			(type default)
		)
		(fill no)
		(layer "In10.Cu")
	)
	(gr_circle
		(center 399.165064 -81.051146)
		(end 400.054064 -81.051146)
		(stroke
			(width 0.2)
			(type default)
		)
		(fill no)
		(layer "In10.Cu")
	)
	(gr_circle
		(center 402.436838 -166.527988)
		(end 403.325838 -166.527988)
		(stroke
			(width 0.2)
			(type default)
		)
		(fill no)
		(layer "In10.Cu")
	)
	(gr_circle
		(center 402.436838 -165.791388)
		(end 403.325838 -165.791388)
		(stroke
			(width 0.2)
			(type default)
		)
		(fill no)
		(layer "In10.Cu")
	)
	(gr_circle
		(center 402.436838 -165.054788)
		(end 403.325838 -165.054788)
		(stroke
			(width 0.2)
			(type default)
		)
		(fill no)
		(layer "In10.Cu")
	)
	(gr_circle
		(center 402.970238 -165.410388)
		(end 403.859238 -165.410388)
		(stroke
			(width 0.2)
			(type default)
		)
		(fill no)
		(layer "In10.Cu")
	)
	(gr_circle
		(center 402.995638 -166.172388)
		(end 403.884638 -166.172388)
		(stroke
			(width 0.2)
			(type default)
		)
		(fill no)
		(layer "In10.Cu")
	)
	(gr_circle
		(center 403.520402 -165.732968)
		(end 404.409402 -165.732968)
		(stroke
			(width 0.2)
			(type default)
		)
		(fill no)
		(layer "In10.Cu")
	)
	(gr_circle
		(center 403.520402 -164.996368)
		(end 404.409402 -164.996368)
		(stroke
			(width 0.2)
			(type default)
		)
		(fill no)
		(layer "In10.Cu")
	)
	(gr_circle
		(center 404.104856 -168.082214)
		(end 404.993856 -168.082214)
		(stroke
			(width 0.2)
			(type default)
		)
		(fill no)
		(layer "In10.Cu")
	)
	(gr_circle
		(center 404.104856 -167.320214)
		(end 404.993856 -167.320214)
		(stroke
			(width 0.2)
			(type default)
		)
		(fill no)
		(layer "In10.Cu")
	)
	(gr_circle
		(center 404.222458 -166.605458)
		(end 405.102568 -166.605458)
		(stroke
			(width 0.2)
			(type default)
		)
		(fill no)
		(layer "In10.Cu")
	)
	(gr_circle
		(center 404.839678 -166.605458)
		(end 405.719788 -166.605458)
		(stroke
			(width 0.2)
			(type default)
		)
		(fill no)
		(layer "In10.Cu")
	)
	(gr_circle
		(center 405.456898 -166.605458)
		(end 406.337008 -166.605458)
		(stroke
			(width 0.2)
			(type default)
		)
		(fill no)
		(layer "In10.Cu")
	)
	(gr_circle
		(center 410.818838 -161.701988)
		(end 411.707838 -161.701988)
		(stroke
			(width 0.2)
			(type default)
		)
		(fill no)
		(layer "In10.Cu")
	)
	(gr_circle
		(center 410.818838 -160.965388)
		(end 411.707838 -160.965388)
		(stroke
			(width 0.2)
			(type default)
		)
		(fill no)
		(layer "In10.Cu")
	)
	(gr_circle
		(center 410.818838 -160.228788)
		(end 411.707838 -160.228788)
		(stroke
			(width 0.2)
			(type default)
		)
		(fill no)
		(layer "In10.Cu")
	)
	(gr_circle
		(center 411.352238 -160.584388)
		(end 412.241238 -160.584388)
		(stroke
			(width 0.2)
			(type default)
		)
		(fill no)
		(layer "In10.Cu")
	)
	(gr_circle
		(center 411.377638 -161.346388)
		(end 412.266638 -161.346388)
		(stroke
			(width 0.2)
			(type default)
		)
		(fill no)
		(layer "In10.Cu")
	)
	(gr_circle
		(center 411.902402 -160.906968)
		(end 412.791402 -160.906968)
		(stroke
			(width 0.2)
			(type default)
		)
		(fill no)
		(layer "In10.Cu")
	)
	(gr_circle
		(center 411.902402 -160.170368)
		(end 412.791402 -160.170368)
		(stroke
			(width 0.2)
			(type default)
		)
		(fill no)
		(layer "In10.Cu")
	)
	(gr_circle
		(center 412.486856 -163.256214)
		(end 413.375856 -163.256214)
		(stroke
			(width 0.2)
			(type default)
		)
		(fill no)
		(layer "In10.Cu")
	)
	(gr_circle
		(center 412.486856 -162.494214)
		(end 413.375856 -162.494214)
		(stroke
			(width 0.2)
			(type default)
		)
		(fill no)
		(layer "In10.Cu")
	)
	(gr_circle
		(center 412.604458 -161.779458)
		(end 413.484568 -161.779458)
		(stroke
			(width 0.2)
			(type default)
		)
		(fill no)
		(layer "In10.Cu")
	)
	(gr_circle
		(center 413.221678 -161.779458)
		(end 414.101788 -161.779458)
		(stroke
			(width 0.2)
			(type default)
		)
		(fill no)
		(layer "In10.Cu")
	)
	(gr_circle
		(center 413.838898 -161.779458)
		(end 414.719008 -161.779458)
		(stroke
			(width 0.2)
			(type default)
		)
		(fill no)
		(layer "In10.Cu")
	)
	(gr_circle
		(center 424.33494 -353.10318)
		(end 425.21505 -353.10318)
		(stroke
			(width 0.2)
			(type default)
		)
		(fill no)
		(layer "In10.Cu")
	)
	(gr_circle
		(center 424.95216 -353.10318)
		(end 425.83227 -353.10318)
		(stroke
			(width 0.2)
			(type default)
		)
		(fill no)
		(layer "In10.Cu")
	)
	(gr_circle
		(center 425.56938 -353.10318)
		(end 426.44949 -353.10318)
		(stroke
			(width 0.2)
			(type default)
		)
		(fill no)
		(layer "In10.Cu")
	)
	(gr_circle
		(center 425.686474 -352.35769)
		(end 426.575474 -352.35769)
		(stroke
			(width 0.2)
			(type default)
		)
		(fill no)
		(layer "In10.Cu")
	)
	(gr_circle
		(center 425.686474 -351.62109)
		(end 426.575474 -351.62109)
		(stroke
			(width 0.2)
			(type default)
		)
		(fill no)
		(layer "In10.Cu")
	)
	(gr_circle
		(center 426.271436 -354.71227)
		(end 427.160436 -354.71227)
		(stroke
			(width 0.2)
			(type default)
		)
		(fill no)
		(layer "In10.Cu")
	)
	(gr_circle
		(center 426.271436 -353.97567)
		(end 427.160436 -353.97567)
		(stroke
			(width 0.2)
			(type default)
		)
		(fill no)
		(layer "In10.Cu")
	)
	(gr_circle
		(center 426.7962 -353.53625)
		(end 427.6852 -353.53625)
		(stroke
			(width 0.2)
			(type default)
		)
		(fill no)
		(layer "In10.Cu")
	)
	(gr_circle
		(center 426.8216 -354.29825)
		(end 427.7106 -354.29825)
		(stroke
			(width 0.2)
			(type default)
		)
		(fill no)
		(layer "In10.Cu")
	)
	(gr_circle
		(center 427.355 -354.65385)
		(end 428.244 -354.65385)
		(stroke
			(width 0.2)
			(type default)
		)
		(fill no)
		(layer "In10.Cu")
	)
	(gr_circle
		(center 427.355 -353.91725)
		(end 428.244 -353.91725)
		(stroke
			(width 0.2)
			(type default)
		)
		(fill no)
		(layer "In10.Cu")
	)
	(gr_circle
		(center 427.355 -353.18065)
		(end 428.244 -353.18065)
		(stroke
			(width 0.2)
			(type default)
		)
		(fill no)
		(layer "In10.Cu")
	)
	(gr_circle
		(center 432.01336 -361.827826)
		(end 433.41036 -361.827826)
		(stroke
			(width 0.2)
			(type default)
		)
		(fill no)
		(layer "In10.Cu")
	)
	(gr_circle
		(center 432.661568 -353.12858)
		(end 433.541678 -353.12858)
		(stroke
			(width 0.2)
			(type default)
		)
		(fill no)
		(layer "In10.Cu")
	)
	(gr_circle
		(center 433.278788 -353.12858)
		(end 434.158898 -353.12858)
		(stroke
			(width 0.2)
			(type default)
		)
		(fill no)
		(layer "In10.Cu")
	)
	(gr_circle
		(center 433.896008 -353.12858)
		(end 434.776118 -353.12858)
		(stroke
			(width 0.2)
			(type default)
		)
		(fill no)
		(layer "In10.Cu")
	)
	(gr_circle
		(center 434.013102 -352.38309)
		(end 434.902102 -352.38309)
		(stroke
			(width 0.2)
			(type default)
		)
		(fill no)
		(layer "In10.Cu")
	)
	(gr_circle
		(center 434.013102 -351.64649)
		(end 434.902102 -351.64649)
		(stroke
			(width 0.2)
			(type default)
		)
		(fill no)
		(layer "In10.Cu")
	)
	(gr_circle
		(center 434.598064 -354.73767)
		(end 435.487064 -354.73767)
		(stroke
			(width 0.2)
			(type default)
		)
		(fill no)
		(layer "In10.Cu")
	)
	(gr_circle
		(center 434.598064 -354.00107)
		(end 435.487064 -354.00107)
		(stroke
			(width 0.2)
			(type default)
		)
		(fill no)
		(layer "In10.Cu")
	)
	(gr_circle
		(center 435.122828 -353.56165)
		(end 436.011828 -353.56165)
		(stroke
			(width 0.2)
			(type default)
		)
		(fill no)
		(layer "In10.Cu")
	)
	(gr_circle
		(center 435.148228 -354.32365)
		(end 436.037228 -354.32365)
		(stroke
			(width 0.2)
			(type default)
		)
		(fill no)
		(layer "In10.Cu")
	)
	(gr_circle
		(center 435.469538 -361.496102)
		(end 436.358538 -361.496102)
		(stroke
			(width 0.2)
			(type default)
		)
		(fill no)
		(layer "In10.Cu")
	)
	(gr_circle
		(center 435.469538 -360.734102)
		(end 436.358538 -360.734102)
		(stroke
			(width 0.2)
			(type default)
		)
		(fill no)
		(layer "In10.Cu")
	)
	(gr_circle
		(center 435.469538 -359.972102)
		(end 436.358538 -359.972102)
		(stroke
			(width 0.2)
			(type default)
		)
		(fill no)
		(layer "In10.Cu")
	)
	(gr_circle
		(center 435.681628 -354.67925)
		(end 436.570628 -354.67925)
		(stroke
			(width 0.2)
			(type default)
		)
		(fill no)
		(layer "In10.Cu")
	)
	(gr_circle
		(center 435.681628 -353.94265)
		(end 436.570628 -353.94265)
		(stroke
			(width 0.2)
			(type default)
		)
		(fill no)
		(layer "In10.Cu")
	)
	(gr_circle
		(center 435.681628 -353.20605)
		(end 436.570628 -353.20605)
		(stroke
			(width 0.2)
			(type default)
		)
		(fill no)
		(layer "In10.Cu")
	)
	(gr_circle
		(center 436.231538 -361.496102)
		(end 437.120538 -361.496102)
		(stroke
			(width 0.2)
			(type default)
		)
		(fill no)
		(layer "In10.Cu")
	)
	(gr_circle
		(center 436.231538 -360.734102)
		(end 437.120538 -360.734102)
		(stroke
			(width 0.2)
			(type default)
		)
		(fill no)
		(layer "In10.Cu")
	)
	(gr_circle
		(center 436.231538 -359.972102)
		(end 437.120538 -359.972102)
		(stroke
			(width 0.2)
			(type default)
		)
		(fill no)
		(layer "In10.Cu")
	)
	(gr_circle
		(center 437.703214 -12.400788)
		(end 438.592214 -12.400788)
		(stroke
			(width 0.2)
			(type default)
		)
		(fill no)
		(layer "In10.Cu")
	)
	(gr_circle
		(center 438.06999 -13.069316)
		(end 438.95899 -13.069316)
		(stroke
			(width 0.2)
			(type default)
		)
		(fill no)
		(layer "In10.Cu")
	)
	(gr_circle
		(center 438.592214 -12.400788)
		(end 439.481214 -12.400788)
		(stroke
			(width 0.2)
			(type default)
		)
		(fill no)
		(layer "In10.Cu")
	)
	(gr_circle
		(center 438.71515 -13.061696)
		(end 439.60415 -13.061696)
		(stroke
			(width 0.2)
			(type default)
		)
		(fill no)
		(layer "In10.Cu")
	)
	(gr_circle
		(center 439.39333 -13.043916)
		(end 440.28233 -13.043916)
		(stroke
			(width 0.2)
			(type default)
		)
		(fill no)
		(layer "In10.Cu")
	)
	(gr_circle
		(center 439.481214 -12.400788)
		(end 440.370214 -12.400788)
		(stroke
			(width 0.2)
			(type default)
		)
		(fill no)
		(layer "In10.Cu")
	)
	(gr_circle
		(center 440.945524 -11.261852)
		(end 441.834524 -11.261852)
		(stroke
			(width 0.2)
			(type default)
		)
		(fill no)
		(layer "In10.Cu")
	)
	(gr_circle
		(center 440.945524 -10.626852)
		(end 441.834524 -10.626852)
		(stroke
			(width 0.2)
			(type default)
		)
		(fill no)
		(layer "In10.Cu")
	)
	(gr_circle
		(center 441.129674 -25.982422)
		(end 442.018674 -25.982422)
		(stroke
			(width 0.2)
			(type default)
		)
		(fill no)
		(layer "In10.Cu")
	)
	(gr_circle
		(center 441.354718 -20.73656)
		(end 442.243718 -20.73656)
		(stroke
			(width 0.2)
			(type default)
		)
		(fill no)
		(layer "In10.Cu")
	)
	(gr_circle
		(center 441.354718 -20.10156)
		(end 442.243718 -20.10156)
		(stroke
			(width 0.2)
			(type default)
		)
		(fill no)
		(layer "In10.Cu")
	)
	(gr_circle
		(center 441.354718 -19.21256)
		(end 442.243718 -19.21256)
		(stroke
			(width 0.2)
			(type default)
		)
		(fill no)
		(layer "In10.Cu")
	)
	(gr_circle
		(center 441.354718 -18.57756)
		(end 442.243718 -18.57756)
		(stroke
			(width 0.2)
			(type default)
		)
		(fill no)
		(layer "In10.Cu")
	)
	(gr_circle
		(center 441.475622 -14.123162)
		(end 442.364622 -14.123162)
		(stroke
			(width 0.2)
			(type default)
		)
		(fill no)
		(layer "In10.Cu")
	)
	(gr_circle
		(center 441.475622 -13.488162)
		(end 442.364622 -13.488162)
		(stroke
			(width 0.2)
			(type default)
		)
		(fill no)
		(layer "In10.Cu")
	)
	(gr_circle
		(center 441.56249 -25.461976)
		(end 442.45149 -25.461976)
		(stroke
			(width 0.2)
			(type default)
		)
		(fill no)
		(layer "In10.Cu")
	)
	(gr_circle
		(center 442.018674 -25.982422)
		(end 442.907674 -25.982422)
		(stroke
			(width 0.2)
			(type default)
		)
		(fill no)
		(layer "In10.Cu")
	)
	(gr_circle
		(center 442.371734 -20.983702)
		(end 443.260734 -20.983702)
		(stroke
			(width 0.2)
			(type default)
		)
		(fill no)
		(layer "In10.Cu")
	)
	(gr_circle
		(center 442.371734 -20.348702)
		(end 443.260734 -20.348702)
		(stroke
			(width 0.2)
			(type default)
		)
		(fill no)
		(layer "In10.Cu")
	)
	(gr_circle
		(center 442.371734 -19.459702)
		(end 443.260734 -19.459702)
		(stroke
			(width 0.2)
			(type default)
		)
		(fill no)
		(layer "In10.Cu")
	)
	(gr_circle
		(center 442.371734 -18.824702)
		(end 443.260734 -18.824702)
		(stroke
			(width 0.2)
			(type default)
		)
		(fill no)
		(layer "In10.Cu")
	)
	(gr_circle
		(center 442.45149 -25.461976)
		(end 443.34049 -25.461976)
		(stroke
			(width 0.2)
			(type default)
		)
		(fill no)
		(layer "In10.Cu")
	)
	(gr_circle
		(center 442.907674 -25.982422)
		(end 443.796674 -25.982422)
		(stroke
			(width 0.2)
			(type default)
		)
		(fill no)
		(layer "In10.Cu")
	)
	(gr_circle
		(center 443.34049 -25.461976)
		(end 444.22949 -25.461976)
		(stroke
			(width 0.2)
			(type default)
		)
		(fill no)
		(layer "In10.Cu")
	)
	(gr_circle
		(center 444.166244 -24.741632)
		(end 445.055244 -24.741632)
		(stroke
			(width 0.2)
			(type default)
		)
		(fill no)
		(layer "In10.Cu")
	)
	(gr_circle
		(center 450.669914 -14.526514)
		(end 451.558914 -14.526514)
		(stroke
			(width 0.2)
			(type default)
		)
		(fill no)
		(layer "In10.Cu")
	)
	(gr_circle
		(center 450.670676 -16.010382)
		(end 451.559676 -16.010382)
		(stroke
			(width 0.2)
			(type default)
		)
		(fill no)
		(layer "In10.Cu")
	)
	(gr_circle
		(center 450.670676 -15.273782)
		(end 451.559676 -15.273782)
		(stroke
			(width 0.2)
			(type default)
		)
		(fill no)
		(layer "In10.Cu")
	)
	(gr_circle
		(center 452.054976 -18.535142)
		(end 452.943976 -18.535142)
		(stroke
			(width 0.2)
			(type default)
		)
		(fill no)
		(layer "In10.Cu")
	)
	(gr_circle
		(center 452.054976 -17.798542)
		(end 452.943976 -17.798542)
		(stroke
			(width 0.2)
			(type default)
		)
		(fill no)
		(layer "In10.Cu")
	)
	(gr_arc
		(start 456.202034 -9.780016)
		(mid 456.787819 -11.194227)
		(end 458.20203 -11.780012)
		(stroke
			(width 1.016)
			(type default)
		)
		(layer "In10.Cu")
	)
	(gr_arc
		(start 456.202034 -0.500126)
		(mid 456.05556 -0.146464)
		(end 455.701908 0)
		(stroke
			(width 1.016)
			(type default)
		)
		(layer "In10.Cu")
	)
	(gr_line
		(start 456.202034 -0.500126)
		(end 456.202034 -9.780016)
		(stroke
			(width 1.016)
			(type default)
		)
		(layer "In10.Cu")
	)
	(gr_line
		(start 458.20203 -11.780012)
		(end 469.799924 -11.780012)
		(stroke
			(width 1.016)
			(type default)
		)
		(layer "In10.Cu")
	)
	(gr_line
		(start 463.300064 -441.989972)
		(end 277.314914 -441.989972)
		(stroke
			(width 1.016)
			(type default)
		)
		(layer "In10.Cu")
	)
	(gr_arc
		(start 463.300064 -441.989972)
		(mid 464.71429 -441.404198)
		(end 465.30006 -439.989976)
		(stroke
			(width 1.016)
			(type default)
		)
		(layer "In10.Cu")
	)
	(gr_line
		(start 465.30006 -409.528518)
		(end 465.30006 -439.989976)
		(stroke
			(width 1.016)
			(type default)
		)
		(layer "In10.Cu")
	)
	(gr_arc
		(start 465.885784 -408.114246)
		(mid 465.452221 -408.76312)
		(end 465.30006 -409.528518)
		(stroke
			(width 1.016)
			(type default)
		)
		(layer "In10.Cu")
	)
	(gr_line
		(start 467.71433 -406.2857)
		(end 465.885784 -408.114246)
		(stroke
			(width 1.016)
			(type default)
		)
		(layer "In10.Cu")
	)
	(gr_arc
		(start 467.71433 -406.2857)
		(mid 468.147828 -405.636947)
		(end 468.300054 -404.871682)
		(stroke
			(width 1.016)
			(type default)
		)
		(layer "In10.Cu")
	)
	(gr_line
		(start 468.300054 -82.828384)
		(end 468.300054 -404.871682)
		(stroke
			(width 1.016)
			(type default)
		)
		(layer "In10.Cu")
	)
	(gr_arc
		(start 468.885778 -81.414112)
		(mid 468.452215 -82.062986)
		(end 468.300054 -82.828384)
		(stroke
			(width 1.016)
			(type default)
		)
		(layer "In10.Cu")
	)
	(gr_line
		(start 471.214196 -79.085694)
		(end 468.885778 -81.414112)
		(stroke
			(width 1.016)
			(type default)
		)
		(layer "In10.Cu")
	)
	(gr_arc
		(start 471.214196 -79.085694)
		(mid 471.6477 -78.436942)
		(end 471.79992 -77.671676)
		(stroke
			(width 1.016)
			(type default)
		)
		(layer "In10.Cu")
	)
	(gr_arc
		(start 471.79992 -13.780008)
		(mid 471.214139 -12.365784)
		(end 469.799924 -11.780012)
		(stroke
			(width 1.016)
			(type default)
		)
		(layer "In10.Cu")
	)
	(gr_line
		(start 471.79992 -13.780008)
		(end 471.79992 -77.671676)
		(stroke
			(width 1.016)
			(type default)
		)
		(layer "In10.Cu")
	)
	(gr_poly
		(pts
			(xy 77.493114 -223.772476) (xy 77.393292 -223.599248) (xy 77.35189 -223.623124) (xy 77.315314 -223.759522)
			(xy 77.451966 -223.796352)
		)
		(stroke
			(width 0)
			(type solid)
		)
		(fill yes)
		(layer "In11.Cu")
		(net "M_F_CPU1_SA_DQS_DP<5>")
	)
	(gr_poly
		(pts
			(xy 77.96784 -222.98152) (xy 77.868018 -222.808292) (xy 77.826616 -222.831914) (xy 77.79004 -222.968566)
			(xy 77.926692 -223.005142)
		)
		(stroke
			(width 0)
			(type solid)
		)
		(fill yes)
		(layer "In11.Cu")
		(net "M_F_CPU1_SA_DQS_DN<0>")
	)
	(gr_poly
		(pts
			(xy 78.034642 -247.116092) (xy 77.93482 -247.016016) (xy 77.834744 -247.116092) (xy 77.834744 -247.16359)
			(xy 78.034642 -247.16359)
		)
		(stroke
			(width 0)
			(type solid)
		)
		(fill yes)
		(layer "In11.Cu")
		(net "M_F_CPU1_SA_DQS_DN<9>")
	)
	(gr_poly
		(pts
			(xy 78.04658 -253.596394) (xy 77.946504 -253.496318) (xy 77.846682 -253.596394) (xy 77.846682 -253.640844)
			(xy 78.04658 -253.640844)
		)
		(stroke
			(width 0)
			(type solid)
		)
		(fill yes)
		(layer "In11.Cu")
		(net "M_F_CPU1_SA_CA<2>")
	)
	(gr_poly
		(pts
			(xy 78.060296 -224.035874) (xy 78.096872 -223.899476) (xy 77.96022 -223.8629) (xy 77.919072 -223.886522)
			(xy 78.018894 -224.05975)
		)
		(stroke
			(width 0)
			(type solid)
		)
		(fill yes)
		(layer "In11.Cu")
		(net "M_F_CPU1_SA_DQS_DN<5>")
	)
	(gr_poly
		(pts
			(xy 78.259432 -294.797988) (xy 78.220824 -294.775636) (xy 78.084426 -294.812466) (xy 78.121002 -294.948864)
			(xy 78.159356 -294.971216)
		)
		(stroke
			(width 0)
			(type solid)
		)
		(fill yes)
		(layer "In11.Cu")
		(net "M_F_CPU1_SB_DQ<28>")
	)
	(gr_poly
		(pts
			(xy 78.416658 -227.000308) (xy 78.33233 -226.819206) (xy 78.28915 -226.839272) (xy 78.240636 -226.972114)
			(xy 78.373732 -227.020628)
		)
		(stroke
			(width 0)
			(type solid)
		)
		(fill yes)
		(layer "In11.Cu")
		(net "M_F_CPU1_SA_DQS_DP<5>")
	)
	(gr_poly
		(pts
			(xy 78.429866 -224.696274) (xy 78.391258 -224.674176) (xy 78.254606 -224.710752) (xy 78.291436 -224.847404)
			(xy 78.32979 -224.869502)
		)
		(stroke
			(width 0)
			(type solid)
		)
		(fill yes)
		(layer "In11.Cu")
		(net "M_F_CPU1_SA_DQS_DN<0>")
	)
	(gr_poly
		(pts
			(xy 78.432914 -225.392488) (xy 78.333092 -225.21926) (xy 78.29169 -225.243136) (xy 78.255114 -225.379534)
			(xy 78.391766 -225.416364)
		)
		(stroke
			(width 0)
			(type solid)
		)
		(fill yes)
		(layer "In11.Cu")
		(net "M_F_CPU1_SA_DQS_DN<0>")
	)
	(gr_poly
		(pts
			(xy 78.43393 -223.773746) (xy 78.334108 -223.600518) (xy 78.292706 -223.624394) (xy 78.25613 -223.761046)
			(xy 78.392782 -223.797622)
		)
		(stroke
			(width 0)
			(type solid)
		)
		(fill yes)
		(layer "In11.Cu")
		(net "M_F_CPU1_SA_DQS_DN<0>")
	)
	(gr_poly
		(pts
			(xy 78.48854 -247.924066) (xy 78.388464 -247.82399) (xy 78.288388 -247.924066) (xy 78.288388 -247.968516)
			(xy 78.48854 -247.968516)
		)
		(stroke
			(width 0)
			(type solid)
		)
		(fill yes)
		(layer "In11.Cu")
		(net "M_F_CPU1_SA_CB<4>")
	)
	(gr_poly
		(pts
			(xy 78.500224 -247.522238) (xy 78.500224 -247.47474) (xy 78.300326 -247.47474) (xy 78.300326 -247.522238)
			(xy 78.400402 -247.622314)
		)
		(stroke
			(width 0)
			(type solid)
		)
		(fill yes)
		(layer "In11.Cu")
		(net "M_F_CPU1_SA_DQS_DP<9>")
	)
	(gr_poly
		(pts
			(xy 78.502256 -254.00254) (xy 78.502256 -253.95809) (xy 78.302358 -253.95809) (xy 78.302358 -254.00254)
			(xy 78.402434 -254.102616)
		)
		(stroke
			(width 0)
			(type solid)
		)
		(fill yes)
		(layer "In11.Cu")
		(net "M_F_CPU1_SA_CA<3>")
	)
	(gr_poly
		(pts
			(xy 78.502256 -252.382528) (xy 78.502256 -252.338078) (xy 78.302358 -252.338078) (xy 78.302358 -252.382528)
			(xy 78.402434 -252.482604)
		)
		(stroke
			(width 0)
			(type solid)
		)
		(fill yes)
		(layer "In11.Cu")
		(net "M_F_CPU1_SA_CS_N<1>")
	)
	(gr_poly
		(pts
			(xy 78.502256 -242.66271) (xy 78.502256 -242.615212) (xy 78.302358 -242.615212) (xy 78.302358 -242.66271)
			(xy 78.402434 -242.762786)
		)
		(stroke
			(width 0)
			(type solid)
		)
		(fill yes)
		(layer "In11.Cu")
		(net "M_F_CPU1_SA_DQS_DP<8>")
	)
	(gr_poly
		(pts
			(xy 78.502256 -236.182408) (xy 78.502256 -236.137958) (xy 78.302358 -236.137958) (xy 78.302358 -236.182408)
			(xy 78.402434 -236.282484)
		)
		(stroke
			(width 0)
			(type solid)
		)
		(fill yes)
		(layer "In11.Cu")
		(net "M_F_CPU1_SA_DQ<19>")
	)
	(gr_poly
		(pts
			(xy 78.502256 -234.562396) (xy 78.502256 -234.517946) (xy 78.302358 -234.517946) (xy 78.302358 -234.562396)
			(xy 78.402434 -234.662472)
		)
		(stroke
			(width 0)
			(type solid)
		)
		(fill yes)
		(layer "In11.Cu")
		(net "M_F_CPU1_SA_DQ<15>")
	)
	(gr_poly
		(pts
			(xy 78.502256 -232.942638) (xy 78.502256 -232.89514) (xy 78.302104 -232.89514) (xy 78.302104 -232.942638)
			(xy 78.40218 -233.042714)
		)
		(stroke
			(width 0)
			(type solid)
		)
		(fill yes)
		(layer "In11.Cu")
		(net "M_F_CPU1_SA_DQS_DP<6>")
	)
	(gr_poly
		(pts
			(xy 78.515972 -226.512628) (xy 78.564486 -226.379786) (xy 78.43139 -226.331272) (xy 78.38821 -226.351338)
			(xy 78.472792 -226.532694)
		)
		(stroke
			(width 0)
			(type solid)
		)
		(fill yes)
		(layer "In11.Cu")
		(net "M_F_CPU1_SA_DQS_DN<5>")
	)
	(gr_poly
		(pts
			(xy 78.516734 -237.802674) (xy 78.516734 -237.755176) (xy 78.316836 -237.755176) (xy 78.316836 -237.802674)
			(xy 78.416658 -237.90275)
		)
		(stroke
			(width 0)
			(type solid)
		)
		(fill yes)
		(layer "In11.Cu")
		(net "M_F_CPU1_SA_DQS_DP<7>")
	)
	(gr_poly
		(pts
			(xy 78.523846 -239.422432) (xy 78.523846 -239.377982) (xy 78.323694 -239.377982) (xy 78.323694 -239.422432)
			(xy 78.42377 -239.522508)
		)
		(stroke
			(width 0)
			(type solid)
		)
		(fill yes)
		(layer "In11.Cu")
		(net "M_F_CPU1_SA_DQ<23>")
	)
	(gr_poly
		(pts
			(xy 78.524354 -254.406146) (xy 78.424278 -254.306324) (xy 78.324202 -254.406146) (xy 78.324202 -254.450596)
			(xy 78.524354 -254.450596)
		)
		(stroke
			(width 0)
			(type solid)
		)
		(fill yes)
		(layer "In11.Cu")
		(net "M_F_CPU1_SA_CA<4>")
	)
	(gr_poly
		(pts
			(xy 78.524354 -252.786134) (xy 78.424278 -252.686312) (xy 78.324202 -252.786134) (xy 78.324202 -252.830584)
			(xy 78.524354 -252.830584)
		)
		(stroke
			(width 0)
			(type solid)
		)
		(fill yes)
		(layer "In11.Cu")
		(net "M_F_CPU1_SA_CA<0>")
	)
	(gr_poly
		(pts
			(xy 78.524354 -244.686074) (xy 78.424278 -244.586252) (xy 78.324202 -244.686074) (xy 78.324202 -244.730524)
			(xy 78.524354 -244.730524)
		)
		(stroke
			(width 0)
			(type solid)
		)
		(fill yes)
		(layer "In11.Cu")
		(net "M_F_CPU1_SA_CB<0>")
	)
	(gr_poly
		(pts
			(xy 78.526386 -256.025904) (xy 78.42631 -255.926082) (xy 78.326488 -256.025904) (xy 78.326488 -256.073656)
			(xy 78.526386 -256.073656)
		)
		(stroke
			(width 0)
			(type solid)
		)
		(fill yes)
		(layer "In11.Cu")
		(net "M_F_CPU1_CLK_DP<0>")
	)
	(gr_poly
		(pts
			(xy 78.528926 -223.223836) (xy 78.565502 -223.087184) (xy 78.42885 -223.050608) (xy 78.387702 -223.074484)
			(xy 78.487778 -223.247712)
		)
		(stroke
			(width 0)
			(type solid)
		)
		(fill yes)
		(layer "In11.Cu")
		(net "M_F_CPU1_SA_DQS_DP<0>")
	)
	(gr_poly
		(pts
			(xy 78.730348 -293.986712) (xy 78.691994 -293.96436) (xy 78.555342 -294.000936) (xy 78.591918 -294.137588)
			(xy 78.630526 -294.15994)
		)
		(stroke
			(width 0)
			(type solid)
		)
		(fill yes)
		(layer "In11.Cu")
		(net "M_F_CPU1_SB_DQ<28>")
	)
	(gr_poly
		(pts
			(xy 78.80223 -284.818328) (xy 78.702408 -284.718252) (xy 78.602332 -284.818328) (xy 78.602332 -284.862778)
			(xy 78.80223 -284.862778)
		)
		(stroke
			(width 0)
			(type solid)
		)
		(fill yes)
		(layer "In11.Cu")
		(net "M_F_CPU1_SB_DQ<17>")
	)
	(gr_poly
		(pts
			(xy 78.80223 -283.198316) (xy 78.702408 -283.09824) (xy 78.602332 -283.198316) (xy 78.602332 -283.242766)
			(xy 78.80223 -283.242766)
		)
		(stroke
			(width 0)
			(type solid)
		)
		(fill yes)
		(layer "In11.Cu")
		(net "M_F_CPU1_SB_DQ<13>")
	)
	(gr_poly
		(pts
			(xy 78.807564 -286.437832) (xy 78.707488 -286.33801) (xy 78.607412 -286.437832) (xy 78.607412 -286.485584)
			(xy 78.807564 -286.485584)
		)
		(stroke
			(width 0)
			(type solid)
		)
		(fill yes)
		(layer "In11.Cu")
		(net "M_F_CPU1_SB_DQS_DN<7>")
	)
	(gr_poly
		(pts
			(xy 78.824328 -279.554686) (xy 78.824328 -279.510236) (xy 78.624176 -279.510236) (xy 78.624176 -279.554686)
			(xy 78.724252 -279.654508)
		)
		(stroke
			(width 0)
			(type solid)
		)
		(fill yes)
		(layer "In11.Cu")
		(net "M_F_CPU1_SB_DQ<10>")
	)
	(gr_poly
		(pts
			(xy 78.824328 -274.69465) (xy 78.824328 -274.6502) (xy 78.624176 -274.6502) (xy 78.624176 -274.69465)
			(xy 78.724252 -274.794472)
		)
		(stroke
			(width 0)
			(type solid)
		)
		(fill yes)
		(layer "In11.Cu")
		(net "M_F_CPU1_SB_DQ<2>")
	)
	(gr_poly
		(pts
			(xy 78.824328 -273.074638) (xy 78.824328 -273.030188) (xy 78.624176 -273.030188) (xy 78.624176 -273.074638)
			(xy 78.724252 -273.17446)
		)
		(stroke
			(width 0)
			(type solid)
		)
		(fill yes)
		(layer "In11.Cu")
		(net "M_F_CPU1_SB_CB<2>")
	)
	(gr_poly
		(pts
			(xy 78.824328 -269.834614) (xy 78.824328 -269.790164) (xy 78.624176 -269.790164) (xy 78.624176 -269.834614)
			(xy 78.724252 -269.934436)
		)
		(stroke
			(width 0)
			(type solid)
		)
		(fill yes)
		(layer "In11.Cu")
		(net "M_F_CPU1_SB_CB<6>")
	)
	(gr_poly
		(pts
			(xy 78.824328 -264.974578) (xy 78.824328 -264.930128) (xy 78.624176 -264.930128) (xy 78.624176 -264.974578)
			(xy 78.724252 -265.0744)
		)
		(stroke
			(width 0)
			(type solid)
		)
		(fill yes)
		(layer "In11.Cu")
		(net "M_F_CPU1_SB_PAR")
	)
	(gr_poly
		(pts
			(xy 78.82636 -281.174952) (xy 78.82636 -281.1272) (xy 78.626462 -281.1272) (xy 78.626462 -281.174952)
			(xy 78.726284 -281.274774)
		)
		(stroke
			(width 0)
			(type solid)
		)
		(fill yes)
		(layer "In11.Cu")
		(net "M_F_CPU1_SB_DQS_DN<1>")
	)
	(gr_poly
		(pts
			(xy 78.889606 -232.143554) (xy 78.897734 -232.096564) (xy 78.700884 -232.061766) (xy 78.692502 -232.108756)
			(xy 78.773782 -232.22458)
		)
		(stroke
			(width 0)
			(type solid)
		)
		(fill yes)
		(layer "In11.Cu")
		(net "M_F_CPU1_SA_DQS_DN<1>")
	)
	(gr_poly
		(pts
			(xy 78.901798 -222.965264) (xy 78.801722 -222.792036) (xy 78.763368 -222.814388) (xy 78.726792 -222.95104)
			(xy 78.86319 -222.987616)
		)
		(stroke
			(width 0)
			(type solid)
		)
		(fill yes)
		(layer "In11.Cu")
		(net "M_F_CPU1_SA_DQ<3>")
	)
	(gr_poly
		(pts
			(xy 78.903322 -226.202494) (xy 78.8035 -226.029266) (xy 78.762098 -226.053142) (xy 78.725522 -226.18954)
			(xy 78.862174 -226.22637)
		)
		(stroke
			(width 0)
			(type solid)
		)
		(fill yes)
		(layer "In11.Cu")
		(net "M_F_CPU1_SA_DQS_DN<0>")
	)
	(gr_poly
		(pts
			(xy 78.966822 -256.433066) (xy 78.966822 -256.385314) (xy 78.766924 -256.385314) (xy 78.766924 -256.433066)
			(xy 78.867 -256.532888)
		)
		(stroke
			(width 0)
			(type solid)
		)
		(fill yes)
		(layer "In11.Cu")
		(net "M_F_CPU1_CLK_DN<0>")
	)
	(gr_poly
		(pts
			(xy 78.971394 -246.712994) (xy 78.971394 -246.665242) (xy 78.771496 -246.665242) (xy 78.771496 -246.712994)
			(xy 78.871572 -246.81307)
		)
		(stroke
			(width 0)
			(type solid)
		)
		(fill yes)
		(layer "In11.Cu")
		(net "M_F_CPU1_SA_DQS_DN<4>")
	)
	(gr_poly
		(pts
			(xy 78.971394 -241.852958) (xy 78.971394 -241.805206) (xy 78.771496 -241.805206) (xy 78.771496 -241.852958)
			(xy 78.871572 -241.953034)
		)
		(stroke
			(width 0)
			(type solid)
		)
		(fill yes)
		(layer "In11.Cu")
		(net "M_F_CPU1_SA_DQS_DN<3>")
	)
	(gr_poly
		(pts
			(xy 78.971394 -236.992922) (xy 78.971394 -236.94517) (xy 78.771496 -236.94517) (xy 78.771496 -236.992922)
			(xy 78.871572 -237.092744)
		)
		(stroke
			(width 0)
			(type solid)
		)
		(fill yes)
		(layer "In11.Cu")
		(net "M_F_CPU1_SA_DQS_DN<2>")
	)
	(gr_poly
		(pts
			(xy 78.981046 -250.35637) (xy 78.88097 -250.256294) (xy 78.780894 -250.35637) (xy 78.780894 -250.40082)
			(xy 78.981046 -250.40082)
		)
		(stroke
			(width 0)
			(type solid)
		)
		(fill yes)
		(layer "In11.Cu")
		(net "M_F_CPU1_ALERT_R_N")
	)
	(gr_poly
		(pts
			(xy 78.986634 -255.216406) (xy 78.886558 -255.11633) (xy 78.786482 -255.216406) (xy 78.786482 -255.260856)
			(xy 78.986634 -255.260856)
		)
		(stroke
			(width 0)
			(type solid)
		)
		(fill yes)
		(layer "In11.Cu")
		(net "M_F_CPU1_SA_CA<6>")
	)
	(gr_poly
		(pts
			(xy 78.986634 -253.596394) (xy 78.886558 -253.496318) (xy 78.786482 -253.596394) (xy 78.786482 -253.640844)
			(xy 78.986634 -253.640844)
		)
		(stroke
			(width 0)
			(type solid)
		)
		(fill yes)
		(layer "In11.Cu")
		(net "M_F_CPU1_SA_CA<2>")
	)
	(gr_poly
		(pts
			(xy 78.986634 -248.736358) (xy 78.886558 -248.636282) (xy 78.786482 -248.736358) (xy 78.786482 -248.780808)
			(xy 78.986634 -248.780808)
		)
		(stroke
			(width 0)
			(type solid)
		)
		(fill yes)
		(layer "In11.Cu")
		(net "M_F_CPU1_SA_CB<5>")
	)
	(gr_poly
		(pts
			(xy 78.986634 -247.116092) (xy 78.886558 -247.01627) (xy 78.786482 -247.116092) (xy 78.786482 -247.163844)
			(xy 78.986634 -247.163844)
		)
		(stroke
			(width 0)
			(type solid)
		)
		(fill yes)
		(layer "In11.Cu")
		(net "M_F_CPU1_SA_DQS_DN<9>")
	)
	(gr_poly
		(pts
			(xy 78.986634 -245.496334) (xy 78.886558 -245.396258) (xy 78.786482 -245.496334) (xy 78.786482 -245.540784)
			(xy 78.986634 -245.540784)
		)
		(stroke
			(width 0)
			(type solid)
		)
		(fill yes)
		(layer "In11.Cu")
		(net "M_F_CPU1_SA_CB<1>")
	)
	(gr_poly
		(pts
			(xy 78.986634 -243.876322) (xy 78.886558 -243.776246) (xy 78.786482 -243.876322) (xy 78.786482 -243.920772)
			(xy 78.986634 -243.920772)
		)
		(stroke
			(width 0)
			(type solid)
		)
		(fill yes)
		(layer "In11.Cu")
		(net "M_F_CPU1_SA_DQ<29>")
	)
	(gr_poly
		(pts
			(xy 78.986634 -242.256056) (xy 78.886558 -242.156234) (xy 78.786482 -242.256056) (xy 78.786482 -242.303808)
			(xy 78.986634 -242.303808)
		)
		(stroke
			(width 0)
			(type solid)
		)
		(fill yes)
		(layer "In11.Cu")
		(net "M_F_CPU1_SA_DQS_DN<8>")
	)
	(gr_poly
		(pts
			(xy 78.986634 -239.016286) (xy 78.886558 -238.91621) (xy 78.786482 -239.016286) (xy 78.786482 -239.060736)
			(xy 78.986634 -239.060736)
		)
		(stroke
			(width 0)
			(type solid)
		)
		(fill yes)
		(layer "In11.Cu")
		(net "M_F_CPU1_SA_DQ<21>")
	)
	(gr_poly
		(pts
			(xy 78.986634 -237.39602) (xy 78.886558 -237.296198) (xy 78.786482 -237.39602) (xy 78.786482 -237.443772)
			(xy 78.986634 -237.443772)
		)
		(stroke
			(width 0)
			(type solid)
		)
		(fill yes)
		(layer "In11.Cu")
		(net "M_F_CPU1_SA_DQS_DN<7>")
	)
	(gr_poly
		(pts
			(xy 78.986634 -235.776262) (xy 78.886558 -235.676186) (xy 78.786482 -235.776262) (xy 78.786482 -235.820712)
			(xy 78.986634 -235.820712)
		)
		(stroke
			(width 0)
			(type solid)
		)
		(fill yes)
		(layer "In11.Cu")
		(net "M_F_CPU1_SA_DQ<17>")
	)
	(gr_poly
		(pts
			(xy 78.986634 -234.15625) (xy 78.886558 -234.056174) (xy 78.786482 -234.15625) (xy 78.786482 -234.2007)
			(xy 78.986634 -234.2007)
		)
		(stroke
			(width 0)
			(type solid)
		)
		(fill yes)
		(layer "In11.Cu")
		(net "M_F_CPU1_SA_DQ<13>")
	)
	(gr_poly
		(pts
			(xy 78.986634 -232.535984) (xy 78.886558 -232.436162) (xy 78.786482 -232.535984) (xy 78.786482 -232.583736)
			(xy 78.986634 -232.583736)
		)
		(stroke
			(width 0)
			(type solid)
		)
		(fill yes)
		(layer "In11.Cu")
		(net "M_F_CPU1_SA_DQS_DN<6>")
	)
	(gr_poly
		(pts
			(xy 78.991968 -240.636552) (xy 78.891892 -240.536476) (xy 78.791816 -240.636552) (xy 78.791816 -240.681002)
			(xy 78.991968 -240.681002)
		)
		(stroke
			(width 0)
			(type solid)
		)
		(fill yes)
		(layer "In11.Cu")
		(net "M_F_CPU1_SA_DQ<25>")
	)
	(gr_poly
		(pts
			(xy 78.999588 -224.035366) (xy 79.036164 -223.898714) (xy 78.899512 -223.862138) (xy 78.860904 -223.884236)
			(xy 78.96098 -224.057464)
		)
		(stroke
			(width 0)
			(type solid)
		)
		(fill yes)
		(layer "In11.Cu")
		(net "M_F_CPU1_SA_DQS_DP<0>")
	)
	(gr_poly
		(pts
			(xy 79.00035 -225.655886) (xy 79.036926 -225.519488) (xy 78.900274 -225.482912) (xy 78.859126 -225.506534)
			(xy 78.958948 -225.679762)
		)
		(stroke
			(width 0)
			(type solid)
		)
		(fill yes)
		(layer "In11.Cu")
		(net "M_F_CPU1_SA_DQS_DP<0>")
	)
	(gr_poly
		(pts
			(xy 79.00035 -222.415862) (xy 79.036926 -222.27921) (xy 78.900274 -222.242634) (xy 78.86192 -222.264986)
			(xy 78.961742 -222.438214)
		)
		(stroke
			(width 0)
			(type solid)
		)
		(fill yes)
		(layer "In11.Cu")
		(net "M_F_CPU1_SA_DQ<1>")
	)
	(gr_poly
		(pts
			(xy 79.036418 -224.569782) (xy 78.999842 -224.43313) (xy 78.961234 -224.410778) (xy 78.861412 -224.584006)
			(xy 78.899766 -224.606358)
		)
		(stroke
			(width 0)
			(type solid)
		)
		(fill yes)
		(layer "In11.Cu")
		(net "M_F_CPU1_SA_DQS_DP<0>")
	)
	(gr_poly
		(pts
			(xy 79.200248 -293.177468) (xy 79.16164 -293.155116) (xy 79.025242 -293.191692) (xy 79.061818 -293.328344)
			(xy 79.100172 -293.350696)
		)
		(stroke
			(width 0)
			(type solid)
		)
		(fill yes)
		(layer "In11.Cu")
		(net "M_F_CPU1_SB_DQ<28>")
	)
	(gr_poly
		(pts
			(xy 79.269082 -269.42796) (xy 79.169006 -269.328138) (xy 79.06893 -269.42796) (xy 79.06893 -269.47241)
			(xy 79.269082 -269.47241)
		)
		(stroke
			(width 0)
			(type solid)
		)
		(fill yes)
		(layer "In11.Cu")
		(net "M_F_CPU1_SB_CB<4>")
	)
	(gr_poly
		(pts
			(xy 79.271368 -287.247838) (xy 79.171546 -287.147762) (xy 79.07147 -287.247838) (xy 79.07147 -287.292288)
			(xy 79.271368 -287.292288)
		)
		(stroke
			(width 0)
			(type solid)
		)
		(fill yes)
		(layer "In11.Cu")
		(net "M_F_CPU1_SB_DQ<20>")
	)
	(gr_poly
		(pts
			(xy 79.271368 -285.627826) (xy 79.171546 -285.528004) (xy 79.07147 -285.627826) (xy 79.07147 -285.675578)
			(xy 79.271368 -285.675578)
		)
		(stroke
			(width 0)
			(type solid)
		)
		(fill yes)
		(layer "In11.Cu")
		(net "M_F_CPU1_SB_DQS_DP<2>")
	)
	(gr_poly
		(pts
			(xy 79.271368 -280.76779) (xy 79.171546 -280.667968) (xy 79.07147 -280.76779) (xy 79.07147 -280.815542)
			(xy 79.271368 -280.815542)
		)
		(stroke
			(width 0)
			(type solid)
		)
		(fill yes)
		(layer "In11.Cu")
		(net "M_F_CPU1_SB_DQS_DP<1>")
	)
	(gr_poly
		(pts
			(xy 79.275686 -286.84474) (xy 79.275686 -286.796988) (xy 79.075788 -286.796988) (xy 79.075788 -286.84474)
			(xy 79.17561 -286.944562)
		)
		(stroke
			(width 0)
			(type solid)
		)
		(fill yes)
		(layer "In11.Cu")
		(net "M_F_CPU1_SB_DQS_DP<7>")
	)
	(gr_poly
		(pts
			(xy 79.281274 -267.808202) (xy 79.181198 -267.708126) (xy 79.081122 -267.808202) (xy 79.081122 -267.852652)
			(xy 79.281274 -267.852652)
		)
		(stroke
			(width 0)
			(type solid)
		)
		(fill yes)
		(layer "In11.Cu")
		(net "M_F_CPU1_SB_RSP<0>")
	)
	(gr_poly
		(pts
			(xy 79.286862 -285.224474) (xy 79.286862 -285.180024) (xy 79.08671 -285.180024) (xy 79.08671 -285.224474)
			(xy 79.186786 -285.32455)
		)
		(stroke
			(width 0)
			(type solid)
		)
		(fill yes)
		(layer "In11.Cu")
		(net "M_F_CPU1_SB_DQ<19>")
	)
	(gr_poly
		(pts
			(xy 79.286862 -283.604462) (xy 79.286862 -283.560012) (xy 79.08671 -283.560012) (xy 79.08671 -283.604462)
			(xy 79.186786 -283.704538)
		)
		(stroke
			(width 0)
			(type solid)
		)
		(fill yes)
		(layer "In11.Cu")
		(net "M_F_CPU1_SB_DQ<15>")
	)
	(gr_poly
		(pts
			(xy 79.36992 -225.392742) (xy 79.269844 -225.219514) (xy 79.23149 -225.241866) (xy 79.194914 -225.378264)
			(xy 79.331312 -225.41484)
		)
		(stroke
			(width 0)
			(type solid)
		)
		(fill yes)
		(layer "In11.Cu")
		(net "M_F_CPU1_SA_DQ<3>")
	)
	(gr_poly
		(pts
			(xy 79.36992 -224.696274) (xy 79.331312 -224.674176) (xy 79.194914 -224.710752) (xy 79.23149 -224.847404)
			(xy 79.269844 -224.869502)
		)
		(stroke
			(width 0)
			(type solid)
		)
		(fill yes)
		(layer "In11.Cu")
		(net "M_F_CPU1_SA_DQ<3>")
	)
	(gr_poly
		(pts
			(xy 79.36992 -222.152718) (xy 79.269844 -221.97949) (xy 79.23149 -222.001588) (xy 79.194914 -222.13824)
			(xy 79.331312 -222.17507)
		)
		(stroke
			(width 0)
			(type solid)
		)
		(fill yes)
		(layer "In11.Cu")
		(net "M_F_CPU1_SA_DQ<2>")
	)
	(gr_poly
		(pts
			(xy 79.370428 -223.773238) (xy 79.270352 -223.60001) (xy 79.231998 -223.622362) (xy 79.195422 -223.759014)
			(xy 79.33182 -223.79559)
		)
		(stroke
			(width 0)
			(type solid)
		)
		(fill yes)
		(layer "In11.Cu")
		(net "M_F_CPU1_SA_DQ<3>")
	)
	(gr_poly
		(pts
			(xy 79.37373 -227.013008) (xy 79.273654 -226.840034) (xy 79.232506 -226.863656) (xy 79.19593 -227.000308)
			(xy 79.332582 -227.036884)
		)
		(stroke
			(width 0)
			(type solid)
		)
		(fill yes)
		(layer "In11.Cu")
		(net "M_F_CPU1_SA_DQS_DN<0>")
	)
	(gr_poly
		(pts
			(xy 79.441294 -246.30634) (xy 79.341472 -246.206264) (xy 79.241396 -246.30634) (xy 79.241396 -246.353838)
			(xy 79.441294 -246.353838)
		)
		(stroke
			(width 0)
			(type solid)
		)
		(fill yes)
		(layer "In11.Cu")
		(net "M_F_CPU1_SA_DQS_DP<4>")
	)
	(gr_poly
		(pts
			(xy 79.441294 -241.446304) (xy 79.341472 -241.346228) (xy 79.241396 -241.446304) (xy 79.241396 -241.493802)
			(xy 79.441294 -241.493802)
		)
		(stroke
			(width 0)
			(type solid)
		)
		(fill yes)
		(layer "In11.Cu")
		(net "M_F_CPU1_SA_DQS_DP<3>")
	)
	(gr_poly
		(pts
			(xy 79.441294 -236.586268) (xy 79.341472 -236.486192) (xy 79.241396 -236.586268) (xy 79.241396 -236.633766)
			(xy 79.441294 -236.633766)
		)
		(stroke
			(width 0)
			(type solid)
		)
		(fill yes)
		(layer "In11.Cu")
		(net "M_F_CPU1_SA_DQS_DP<2>")
	)
	(gr_poly
		(pts
			(xy 79.441294 -231.726232) (xy 79.341472 -231.626156) (xy 79.241396 -231.726232) (xy 79.241396 -231.77373)
			(xy 79.441294 -231.77373)
		)
		(stroke
			(width 0)
			(type solid)
		)
		(fill yes)
		(layer "In11.Cu")
		(net "M_F_CPU1_SA_DQS_DP<1>")
	)
	(gr_poly
		(pts
			(xy 79.44485 -254.4064) (xy 79.344774 -254.306578) (xy 79.244952 -254.4064) (xy 79.244952 -254.45085)
			(xy 79.44485 -254.45085)
		)
		(stroke
			(width 0)
			(type solid)
		)
		(fill yes)
		(layer "In11.Cu")
		(net "M_F_CPU1_SA_CA<4>")
	)
	(gr_poly
		(pts
			(xy 79.44485 -252.786388) (xy 79.344774 -252.686566) (xy 79.244952 -252.786388) (xy 79.244952 -252.830838)
			(xy 79.44485 -252.830838)
		)
		(stroke
			(width 0)
			(type solid)
		)
		(fill yes)
		(layer "In11.Cu")
		(net "M_F_CPU1_SA_CA<0>")
	)
	(gr_poly
		(pts
			(xy 79.44485 -247.926352) (xy 79.344774 -247.82653) (xy 79.244952 -247.926352) (xy 79.244952 -247.970802)
			(xy 79.44485 -247.970802)
		)
		(stroke
			(width 0)
			(type solid)
		)
		(fill yes)
		(layer "In11.Cu")
		(net "M_F_CPU1_SA_CB<4>")
	)
	(gr_poly
		(pts
			(xy 79.44485 -244.686328) (xy 79.344774 -244.586506) (xy 79.244952 -244.686328) (xy 79.244952 -244.730778)
			(xy 79.44485 -244.730778)
		)
		(stroke
			(width 0)
			(type solid)
		)
		(fill yes)
		(layer "In11.Cu")
		(net "M_F_CPU1_SA_CB<0>")
	)
	(gr_poly
		(pts
			(xy 79.44485 -243.066316) (xy 79.344774 -242.966494) (xy 79.244952 -243.066316) (xy 79.244952 -243.110766)
			(xy 79.44485 -243.110766)
		)
		(stroke
			(width 0)
			(type solid)
		)
		(fill yes)
		(layer "In11.Cu")
		(net "M_F_CPU1_SA_DQ<28>")
	)
	(gr_poly
		(pts
			(xy 79.44485 -239.826292) (xy 79.344774 -239.72647) (xy 79.244952 -239.826292) (xy 79.244952 -239.870742)
			(xy 79.44485 -239.870742)
		)
		(stroke
			(width 0)
			(type solid)
		)
		(fill yes)
		(layer "In11.Cu")
		(net "M_F_CPU1_SA_DQ<24>")
	)
	(gr_poly
		(pts
			(xy 79.44485 -238.20628) (xy 79.344774 -238.106458) (xy 79.244952 -238.20628) (xy 79.244952 -238.25073)
			(xy 79.44485 -238.25073)
		)
		(stroke
			(width 0)
			(type solid)
		)
		(fill yes)
		(layer "In11.Cu")
		(net "M_F_CPU1_SA_DQ<20>")
	)
	(gr_poly
		(pts
			(xy 79.44485 -234.966256) (xy 79.344774 -234.866434) (xy 79.244952 -234.966256) (xy 79.244952 -235.010706)
			(xy 79.44485 -235.010706)
		)
		(stroke
			(width 0)
			(type solid)
		)
		(fill yes)
		(layer "In11.Cu")
		(net "M_F_CPU1_SA_DQ<16>")
	)
	(gr_poly
		(pts
			(xy 79.44485 -233.346244) (xy 79.344774 -233.246422) (xy 79.244952 -233.346244) (xy 79.244952 -233.390694)
			(xy 79.44485 -233.390694)
		)
		(stroke
			(width 0)
			(type solid)
		)
		(fill yes)
		(layer "In11.Cu")
		(net "M_F_CPU1_SA_DQ<12>")
	)
	(gr_poly
		(pts
			(xy 79.4512 -250.762516) (xy 79.4512 -250.718066) (xy 79.251048 -250.718066) (xy 79.251048 -250.762516)
			(xy 79.351124 -250.862592)
		)
		(stroke
			(width 0)
			(type solid)
		)
		(fill yes)
		(layer "In11.Cu")
		(net "M_F_CPU1_RESET_N")
	)
	(gr_poly
		(pts
			(xy 79.452216 -227.941632) (xy 79.472282 -227.898452) (xy 79.29118 -227.81387) (xy 79.271114 -227.85705)
			(xy 79.319374 -227.989892)
		)
		(stroke
			(width 0)
			(type solid)
		)
		(fill yes)
		(layer "In11.Cu")
		(net "M_F_CPU1_SA_DQS_DP<5>")
	)
	(gr_poly
		(pts
			(xy 79.456788 -255.622552) (xy 79.456788 -255.578102) (xy 79.25689 -255.578102) (xy 79.25689 -255.622552)
			(xy 79.356712 -255.722628)
		)
		(stroke
			(width 0)
			(type solid)
		)
		(fill yes)
		(layer "In11.Cu")
		(net "M_F_CPU1_SA_PAR")
	)
	(gr_poly
		(pts
			(xy 79.456788 -254.00254) (xy 79.456788 -253.95809) (xy 79.25689 -253.95809) (xy 79.25689 -254.00254)
			(xy 79.356712 -254.102616)
		)
		(stroke
			(width 0)
			(type solid)
		)
		(fill yes)
		(layer "In11.Cu")
		(net "M_F_CPU1_SA_CA<3>")
	)
	(gr_poly
		(pts
			(xy 79.456788 -252.382528) (xy 79.456788 -252.338078) (xy 79.25689 -252.338078) (xy 79.25689 -252.382528)
			(xy 79.356712 -252.482604)
		)
		(stroke
			(width 0)
			(type solid)
		)
		(fill yes)
		(layer "In11.Cu")
		(net "M_F_CPU1_SA_CS_N<1>")
	)
	(gr_poly
		(pts
			(xy 79.456788 -249.142504) (xy 79.456788 -249.098054) (xy 79.25689 -249.098054) (xy 79.25689 -249.142504)
			(xy 79.356712 -249.24258)
		)
		(stroke
			(width 0)
			(type solid)
		)
		(fill yes)
		(layer "In11.Cu")
		(net "M_F_CPU1_SA_CB<7>")
	)
	(gr_poly
		(pts
			(xy 79.456788 -247.522746) (xy 79.456788 -247.475248) (xy 79.25689 -247.475248) (xy 79.25689 -247.522746)
			(xy 79.356712 -247.622822)
		)
		(stroke
			(width 0)
			(type solid)
		)
		(fill yes)
		(layer "In11.Cu")
		(net "M_F_CPU1_SA_DQS_DP<9>")
	)
	(gr_poly
		(pts
			(xy 79.456788 -245.90248) (xy 79.456788 -245.85803) (xy 79.25689 -245.85803) (xy 79.25689 -245.90248)
			(xy 79.356712 -246.002556)
		)
		(stroke
			(width 0)
			(type solid)
		)
		(fill yes)
		(layer "In11.Cu")
		(net "M_F_CPU1_SA_CB<3>")
	)
	(gr_poly
		(pts
			(xy 79.456788 -244.282468) (xy 79.456788 -244.238018) (xy 79.25689 -244.238018) (xy 79.25689 -244.282468)
			(xy 79.356712 -244.382544)
		)
		(stroke
			(width 0)
			(type solid)
		)
		(fill yes)
		(layer "In11.Cu")
		(net "M_F_CPU1_SA_DQ<31>")
	)
	(gr_poly
		(pts
			(xy 79.456788 -242.66271) (xy 79.456788 -242.615212) (xy 79.25689 -242.615212) (xy 79.25689 -242.66271)
			(xy 79.356712 -242.762786)
		)
		(stroke
			(width 0)
			(type solid)
		)
		(fill yes)
		(layer "In11.Cu")
		(net "M_F_CPU1_SA_DQS_DP<8>")
	)
	(gr_poly
		(pts
			(xy 79.456788 -239.422432) (xy 79.456788 -239.377982) (xy 79.25689 -239.377982) (xy 79.25689 -239.422432)
			(xy 79.356712 -239.522508)
		)
		(stroke
			(width 0)
			(type solid)
		)
		(fill yes)
		(layer "In11.Cu")
		(net "M_F_CPU1_SA_DQ<23>")
	)
	(gr_poly
		(pts
			(xy 79.456788 -237.802674) (xy 79.456788 -237.755176) (xy 79.25689 -237.755176) (xy 79.25689 -237.802674)
			(xy 79.356712 -237.90275)
		)
		(stroke
			(width 0)
			(type solid)
		)
		(fill yes)
		(layer "In11.Cu")
		(net "M_F_CPU1_SA_DQS_DP<7>")
	)
	(gr_poly
		(pts
			(xy 79.456788 -236.182408) (xy 79.456788 -236.137958) (xy 79.25689 -236.137958) (xy 79.25689 -236.182408)
			(xy 79.356712 -236.282484)
		)
		(stroke
			(width 0)
			(type solid)
		)
		(fill yes)
		(layer "In11.Cu")
		(net "M_F_CPU1_SA_DQ<19>")
	)
	(gr_poly
		(pts
			(xy 79.456788 -234.562396) (xy 79.456788 -234.517946) (xy 79.25689 -234.517946) (xy 79.25689 -234.562396)
			(xy 79.356712 -234.662472)
		)
		(stroke
			(width 0)
			(type solid)
		)
		(fill yes)
		(layer "In11.Cu")
		(net "M_F_CPU1_SA_DQ<15>")
	)
	(gr_poly
		(pts
			(xy 79.456788 -232.942638) (xy 79.456788 -232.89514) (xy 79.25689 -232.89514) (xy 79.25689 -232.942638)
			(xy 79.356712 -233.042714)
		)
		(stroke
			(width 0)
			(type solid)
		)
		(fill yes)
		(layer "In11.Cu")
		(net "M_F_CPU1_SA_DQS_DP<6>")
	)
	(gr_poly
		(pts
			(xy 79.461868 -256.026412) (xy 79.361792 -255.926336) (xy 79.26197 -256.026412) (xy 79.26197 -256.07391)
			(xy 79.461868 -256.07391)
		)
		(stroke
			(width 0)
			(type solid)
		)
		(fill yes)
		(layer "In11.Cu")
		(net "M_F_CPU1_CLK_DP<0>")
	)
	(gr_poly
		(pts
			(xy 79.462884 -241.042952) (xy 79.462884 -240.998502) (xy 79.262986 -240.998502) (xy 79.262986 -241.042952)
			(xy 79.362808 -241.143028)
		)
		(stroke
			(width 0)
			(type solid)
		)
		(fill yes)
		(layer "In11.Cu")
		(net "M_F_CPU1_SA_DQ<27>")
	)
	(gr_poly
		(pts
			(xy 79.469488 -226.464622) (xy 79.506064 -226.32797) (xy 79.369412 -226.291394) (xy 79.328264 -226.31527)
			(xy 79.428086 -226.488498)
		)
		(stroke
			(width 0)
			(type solid)
		)
		(fill yes)
		(layer "In11.Cu")
		(net "M_F_CPU1_SA_DQS_DP<0>")
	)
	(gr_poly
		(pts
			(xy 79.469996 -223.225868) (xy 79.506572 -223.089216) (xy 79.36992 -223.05264) (xy 79.331566 -223.074992)
			(xy 79.431642 -223.24822)
		)
		(stroke
			(width 0)
			(type solid)
		)
		(fill yes)
		(layer "In11.Cu")
		(net "M_F_CPU1_SA_DQ<1>")
	)
	(gr_poly
		(pts
			(xy 79.670402 -295.607486) (xy 79.631794 -295.585134) (xy 79.495142 -295.62171) (xy 79.531972 -295.758362)
			(xy 79.570326 -295.780714)
		)
		(stroke
			(width 0)
			(type solid)
		)
		(fill yes)
		(layer "In11.Cu")
		(net "M_F_CPU1_SB_DQ<29>")
	)
	(gr_poly
		(pts
			(xy 79.680562 -292.349174) (xy 79.641954 -292.327076) (xy 79.505556 -292.363652) (xy 79.542132 -292.500304)
			(xy 79.580486 -292.522402)
		)
		(stroke
			(width 0)
			(type solid)
		)
		(fill yes)
		(layer "In11.Cu")
		(net "M_F_CPU1_SB_DQ<28>")
	)
	(gr_poly
		(pts
			(xy 79.741268 -287.654238) (xy 79.741268 -287.609788) (xy 79.54137 -287.609788) (xy 79.54137 -287.654238)
			(xy 79.641446 -287.754314)
		)
		(stroke
			(width 0)
			(type solid)
		)
		(fill yes)
		(layer "In11.Cu")
		(net "M_F_CPU1_SB_DQ<22>")
	)
	(gr_poly
		(pts
			(xy 79.741268 -286.03448) (xy 79.741268 -285.986982) (xy 79.54137 -285.986982) (xy 79.54137 -286.03448)
			(xy 79.641446 -286.134556)
		)
		(stroke
			(width 0)
			(type solid)
		)
		(fill yes)
		(layer "In11.Cu")
		(net "M_F_CPU1_SB_DQS_DN<2>")
	)
	(gr_poly
		(pts
			(xy 79.741268 -281.174444) (xy 79.741268 -281.126946) (xy 79.54137 -281.126946) (xy 79.54137 -281.174444)
			(xy 79.641446 -281.27452)
		)
		(stroke
			(width 0)
			(type solid)
		)
		(fill yes)
		(layer "In11.Cu")
		(net "M_F_CPU1_SB_DQS_DN<1>")
	)
	(gr_poly
		(pts
			(xy 79.744824 -289.27425) (xy 79.744824 -289.2298) (xy 79.544926 -289.2298) (xy 79.544926 -289.27425)
			(xy 79.644748 -289.374072)
		)
		(stroke
			(width 0)
			(type solid)
		)
		(fill yes)
		(layer "In11.Cu")
		(net "M_F_CPU1_SB_DQ<26>")
	)
	(gr_poly
		(pts
			(xy 79.744824 -284.414468) (xy 79.744824 -284.370018) (xy 79.544926 -284.370018) (xy 79.544926 -284.414468)
			(xy 79.644748 -284.51429)
		)
		(stroke
			(width 0)
			(type solid)
		)
		(fill yes)
		(layer "In11.Cu")
		(net "M_F_CPU1_SB_DQ<18>")
	)
	(gr_poly
		(pts
			(xy 79.744824 -282.794456) (xy 79.744824 -282.750006) (xy 79.544926 -282.750006) (xy 79.544926 -282.794456)
			(xy 79.644748 -282.894278)
		)
		(stroke
			(width 0)
			(type solid)
		)
		(fill yes)
		(layer "In11.Cu")
		(net "M_F_CPU1_SB_DQ<14>")
	)
	(gr_poly
		(pts
			(xy 79.744824 -279.554432) (xy 79.744824 -279.509982) (xy 79.544926 -279.509982) (xy 79.544926 -279.554432)
			(xy 79.644748 -279.654254)
		)
		(stroke
			(width 0)
			(type solid)
		)
		(fill yes)
		(layer "In11.Cu")
		(net "M_F_CPU1_SB_DQ<10>")
	)
	(gr_poly
		(pts
			(xy 79.744824 -277.93442) (xy 79.744824 -277.88997) (xy 79.544926 -277.88997) (xy 79.544926 -277.93442)
			(xy 79.644748 -278.034242)
		)
		(stroke
			(width 0)
			(type solid)
		)
		(fill yes)
		(layer "In11.Cu")
		(net "M_F_CPU1_SB_DQ<6>")
	)
	(gr_poly
		(pts
			(xy 79.744824 -274.694396) (xy 79.744824 -274.649946) (xy 79.544926 -274.649946) (xy 79.544926 -274.694396)
			(xy 79.644748 -274.794218)
		)
		(stroke
			(width 0)
			(type solid)
		)
		(fill yes)
		(layer "In11.Cu")
		(net "M_F_CPU1_SB_DQ<2>")
	)
	(gr_poly
		(pts
			(xy 79.744824 -273.074384) (xy 79.744824 -273.029934) (xy 79.544926 -273.029934) (xy 79.544926 -273.074384)
			(xy 79.644748 -273.174206)
		)
		(stroke
			(width 0)
			(type solid)
		)
		(fill yes)
		(layer "In11.Cu")
		(net "M_F_CPU1_SB_CB<2>")
	)
	(gr_poly
		(pts
			(xy 79.744824 -264.974324) (xy 79.744824 -264.929874) (xy 79.544926 -264.929874) (xy 79.544926 -264.974324)
			(xy 79.644748 -265.074146)
		)
		(stroke
			(width 0)
			(type solid)
		)
		(fill yes)
		(layer "In11.Cu")
		(net "M_F_CPU1_SB_PAR")
	)
	(gr_poly
		(pts
			(xy 79.746348 -290.894516) (xy 79.746348 -290.846764) (xy 79.546196 -290.846764) (xy 79.546196 -290.894516)
			(xy 79.646272 -290.994338)
		)
		(stroke
			(width 0)
			(type solid)
		)
		(fill yes)
		(layer "In11.Cu")
		(net "M_F_CPU1_SB_DQS_DN<3>")
	)
	(gr_poly
		(pts
			(xy 79.756762 -289.67811) (xy 79.656686 -289.578034) (xy 79.55661 -289.67811) (xy 79.55661 -289.72256)
			(xy 79.756762 -289.72256)
		)
		(stroke
			(width 0)
			(type solid)
		)
		(fill yes)
		(layer "In11.Cu")
		(net "M_F_CPU1_SB_DQ<25>")
	)
	(gr_poly
		(pts
			(xy 79.756762 -286.438086) (xy 79.656686 -286.33801) (xy 79.55661 -286.438086) (xy 79.55661 -286.485584)
			(xy 79.756762 -286.485584)
		)
		(stroke
			(width 0)
			(type solid)
		)
		(fill yes)
		(layer "In11.Cu")
		(net "M_F_CPU1_SB_DQS_DN<7>")
	)
	(gr_poly
		(pts
			(xy 79.756762 -284.818328) (xy 79.656686 -284.718252) (xy 79.55661 -284.818328) (xy 79.55661 -284.862778)
			(xy 79.756762 -284.862778)
		)
		(stroke
			(width 0)
			(type solid)
		)
		(fill yes)
		(layer "In11.Cu")
		(net "M_F_CPU1_SB_DQ<17>")
	)
	(gr_poly
		(pts
			(xy 79.756762 -283.198316) (xy 79.656686 -283.09824) (xy 79.55661 -283.198316) (xy 79.55661 -283.242766)
			(xy 79.756762 -283.242766)
		)
		(stroke
			(width 0)
			(type solid)
		)
		(fill yes)
		(layer "In11.Cu")
		(net "M_F_CPU1_SB_DQ<13>")
	)
	(gr_poly
		(pts
			(xy 79.758286 -269.83436) (xy 79.758286 -269.78991) (xy 79.558388 -269.78991) (xy 79.558388 -269.83436)
			(xy 79.658464 -269.934182)
		)
		(stroke
			(width 0)
			(type solid)
		)
		(fill yes)
		(layer "In11.Cu")
		(net "M_F_CPU1_SB_CB<6>")
	)
	(gr_poly
		(pts
			(xy 79.806546 -294.670734) (xy 79.76997 -294.534082) (xy 79.731616 -294.51173) (xy 79.63154 -294.684958)
			(xy 79.670148 -294.70731)
		)
		(stroke
			(width 0)
			(type solid)
		)
		(fill yes)
		(layer "In11.Cu")
		(net "M_F_CPU1_SB_DQ<30>")
	)
	(gr_poly
		(pts
			(xy 79.841344 -226.20478) (xy 79.741268 -226.031552) (xy 79.70266 -226.05365) (xy 79.666084 -226.190302)
			(xy 79.802736 -226.226878)
		)
		(stroke
			(width 0)
			(type solid)
		)
		(fill yes)
		(layer "In11.Cu")
		(net "M_F_CPU1_SA_DQ<3>")
	)
	(gr_poly
		(pts
			(xy 79.841344 -222.964756) (xy 79.741268 -222.791528) (xy 79.70266 -222.813626) (xy 79.666084 -222.950278)
			(xy 79.802736 -222.986854)
		)
		(stroke
			(width 0)
			(type solid)
		)
		(fill yes)
		(layer "In11.Cu")
		(net "M_F_CPU1_SA_DQ<2>")
	)
	(gr_poly
		(pts
			(xy 79.906876 -240.63579) (xy 79.807054 -240.535714) (xy 79.706978 -240.63579) (xy 79.706978 -240.68024)
			(xy 79.906876 -240.68024)
		)
		(stroke
			(width 0)
			(type solid)
		)
		(fill yes)
		(layer "In11.Cu")
		(net "M_F_CPU1_SA_DQ<25>")
	)
	(gr_poly
		(pts
			(xy 79.91475 -255.216406) (xy 79.814928 -255.11633) (xy 79.714852 -255.216406) (xy 79.714852 -255.260856)
			(xy 79.91475 -255.260856)
		)
		(stroke
			(width 0)
			(type solid)
		)
		(fill yes)
		(layer "In11.Cu")
		(net "M_F_CPU1_SA_CA<6>")
	)
	(gr_poly
		(pts
			(xy 79.91475 -253.596394) (xy 79.814928 -253.496318) (xy 79.714852 -253.596394) (xy 79.714852 -253.640844)
			(xy 79.91475 -253.640844)
		)
		(stroke
			(width 0)
			(type solid)
		)
		(fill yes)
		(layer "In11.Cu")
		(net "M_F_CPU1_SA_CA<2>")
	)
	(gr_poly
		(pts
			(xy 79.91475 -248.736358) (xy 79.814928 -248.636282) (xy 79.714852 -248.736358) (xy 79.714852 -248.780808)
			(xy 79.91475 -248.780808)
		)
		(stroke
			(width 0)
			(type solid)
		)
		(fill yes)
		(layer "In11.Cu")
		(net "M_F_CPU1_SA_CB<5>")
	)
	(gr_poly
		(pts
			(xy 79.91475 -247.116092) (xy 79.814928 -247.016016) (xy 79.714852 -247.116092) (xy 79.714852 -247.16359)
			(xy 79.91475 -247.16359)
		)
		(stroke
			(width 0)
			(type solid)
		)
		(fill yes)
		(layer "In11.Cu")
		(net "M_F_CPU1_SA_DQS_DN<9>")
	)
	(gr_poly
		(pts
			(xy 79.91475 -245.496334) (xy 79.814928 -245.396258) (xy 79.714852 -245.496334) (xy 79.714852 -245.540784)
			(xy 79.91475 -245.540784)
		)
		(stroke
			(width 0)
			(type solid)
		)
		(fill yes)
		(layer "In11.Cu")
		(net "M_F_CPU1_SA_CB<1>")
	)
	(gr_poly
		(pts
			(xy 79.91475 -243.876322) (xy 79.814928 -243.776246) (xy 79.714852 -243.876322) (xy 79.714852 -243.920772)
			(xy 79.91475 -243.920772)
		)
		(stroke
			(width 0)
			(type solid)
		)
		(fill yes)
		(layer "In11.Cu")
		(net "M_F_CPU1_SA_DQ<29>")
	)
	(gr_poly
		(pts
			(xy 79.91475 -242.256056) (xy 79.814928 -242.15598) (xy 79.714852 -242.256056) (xy 79.714852 -242.303554)
			(xy 79.91475 -242.303554)
		)
		(stroke
			(width 0)
			(type solid)
		)
		(fill yes)
		(layer "In11.Cu")
		(net "M_F_CPU1_SA_DQS_DN<8>")
	)
	(gr_poly
		(pts
			(xy 79.91475 -239.016286) (xy 79.814928 -238.91621) (xy 79.714852 -239.016286) (xy 79.714852 -239.060736)
			(xy 79.91475 -239.060736)
		)
		(stroke
			(width 0)
			(type solid)
		)
		(fill yes)
		(layer "In11.Cu")
		(net "M_F_CPU1_SA_DQ<21>")
	)
	(gr_poly
		(pts
			(xy 79.91475 -237.39602) (xy 79.814928 -237.295944) (xy 79.714852 -237.39602) (xy 79.714852 -237.443518)
			(xy 79.91475 -237.443518)
		)
		(stroke
			(width 0)
			(type solid)
		)
		(fill yes)
		(layer "In11.Cu")
		(net "M_F_CPU1_SA_DQS_DN<7>")
	)
	(gr_poly
		(pts
			(xy 79.91475 -235.776262) (xy 79.814928 -235.676186) (xy 79.714852 -235.776262) (xy 79.714852 -235.820712)
			(xy 79.91475 -235.820712)
		)
		(stroke
			(width 0)
			(type solid)
		)
		(fill yes)
		(layer "In11.Cu")
		(net "M_F_CPU1_SA_DQ<17>")
	)
	(gr_poly
		(pts
			(xy 79.91475 -234.15625) (xy 79.814928 -234.056174) (xy 79.714852 -234.15625) (xy 79.714852 -234.2007)
			(xy 79.91475 -234.2007)
		)
		(stroke
			(width 0)
			(type solid)
		)
		(fill yes)
		(layer "In11.Cu")
		(net "M_F_CPU1_SA_DQ<13>")
	)
	(gr_poly
		(pts
			(xy 79.91475 -232.535984) (xy 79.814928 -232.435908) (xy 79.714852 -232.535984) (xy 79.714852 -232.583482)
			(xy 79.91475 -232.583482)
		)
		(stroke
			(width 0)
			(type solid)
		)
		(fill yes)
		(layer "In11.Cu")
		(net "M_F_CPU1_SA_DQS_DN<6>")
	)
	(gr_poly
		(pts
			(xy 79.9211 -256.432812) (xy 79.9211 -256.38506) (xy 79.720948 -256.38506) (xy 79.720948 -256.432812)
			(xy 79.821024 -256.532634)
		)
		(stroke
			(width 0)
			(type solid)
		)
		(fill yes)
		(layer "In11.Cu")
		(net "M_F_CPU1_CLK_DN<0>")
	)
	(gr_poly
		(pts
			(xy 79.9211 -250.35637) (xy 79.821024 -250.256294) (xy 79.720948 -250.35637) (xy 79.720948 -250.40082)
			(xy 79.9211 -250.40082)
		)
		(stroke
			(width 0)
			(type solid)
		)
		(fill yes)
		(layer "In11.Cu")
		(net "M_F_CPU1_ALERT_R_N")
	)
	(gr_poly
		(pts
			(xy 79.928212 -254.812546) (xy 79.928212 -254.768096) (xy 79.728314 -254.768096) (xy 79.728314 -254.812546)
			(xy 79.82839 -254.912368)
		)
		(stroke
			(width 0)
			(type solid)
		)
		(fill yes)
		(layer "In11.Cu")
		(net "M_F_CPU1_SA_CA<5>")
	)
	(gr_poly
		(pts
			(xy 79.928212 -253.192534) (xy 79.928212 -253.148084) (xy 79.728314 -253.148084) (xy 79.728314 -253.192534)
			(xy 79.82839 -253.292356)
		)
		(stroke
			(width 0)
			(type solid)
		)
		(fill yes)
		(layer "In11.Cu")
		(net "M_F_CPU1_SA_CA<1>")
	)
	(gr_poly
		(pts
			(xy 79.928212 -251.572522) (xy 79.928212 -251.528072) (xy 79.728314 -251.528072) (xy 79.728314 -251.572522)
			(xy 79.82839 -251.672344)
		)
		(stroke
			(width 0)
			(type solid)
		)
		(fill yes)
		(layer "In11.Cu")
		(net "M_F_CPU1_SA_CS_N<0>")
	)
	(gr_poly
		(pts
			(xy 79.928212 -248.332498) (xy 79.928212 -248.288048) (xy 79.728314 -248.288048) (xy 79.728314 -248.332498)
			(xy 79.82839 -248.43232)
		)
		(stroke
			(width 0)
			(type solid)
		)
		(fill yes)
		(layer "In11.Cu")
		(net "M_F_CPU1_SA_CB<6>")
	)
	(gr_poly
		(pts
			(xy 79.928212 -245.092474) (xy 79.928212 -245.048024) (xy 79.728314 -245.048024) (xy 79.728314 -245.092474)
			(xy 79.82839 -245.192296)
		)
		(stroke
			(width 0)
			(type solid)
		)
		(fill yes)
		(layer "In11.Cu")
		(net "M_F_CPU1_SA_CB<2>")
	)
	(gr_poly
		(pts
			(xy 79.928212 -243.472462) (xy 79.928212 -243.428012) (xy 79.728314 -243.428012) (xy 79.728314 -243.472462)
			(xy 79.82839 -243.572284)
		)
		(stroke
			(width 0)
			(type solid)
		)
		(fill yes)
		(layer "In11.Cu")
		(net "M_F_CPU1_SA_DQ<30>")
	)
	(gr_poly
		(pts
			(xy 79.928212 -240.232438) (xy 79.928212 -240.187988) (xy 79.728314 -240.187988) (xy 79.728314 -240.232438)
			(xy 79.82839 -240.33226)
		)
		(stroke
			(width 0)
			(type solid)
		)
		(fill yes)
		(layer "In11.Cu")
		(net "M_F_CPU1_SA_DQ<26>")
	)
	(gr_poly
		(pts
			(xy 79.928212 -238.612426) (xy 79.928212 -238.567976) (xy 79.728314 -238.567976) (xy 79.728314 -238.612426)
			(xy 79.82839 -238.712248)
		)
		(stroke
			(width 0)
			(type solid)
		)
		(fill yes)
		(layer "In11.Cu")
		(net "M_F_CPU1_SA_DQ<22>")
	)
	(gr_poly
		(pts
			(xy 79.928212 -235.372402) (xy 79.928212 -235.327952) (xy 79.728314 -235.327952) (xy 79.728314 -235.372402)
			(xy 79.82839 -235.472224)
		)
		(stroke
			(width 0)
			(type solid)
		)
		(fill yes)
		(layer "In11.Cu")
		(net "M_F_CPU1_SA_DQ<18>")
	)
	(gr_poly
		(pts
			(xy 79.928212 -233.75239) (xy 79.928212 -233.70794) (xy 79.728314 -233.70794) (xy 79.728314 -233.75239)
			(xy 79.82839 -233.852212)
		)
		(stroke
			(width 0)
			(type solid)
		)
		(fill yes)
		(layer "In11.Cu")
		(net "M_F_CPU1_SA_DQ<14>")
	)
	(gr_poly
		(pts
			(xy 79.931768 -246.712486) (xy 79.931768 -246.664988) (xy 79.73187 -246.664988) (xy 79.73187 -246.712486)
			(xy 79.831692 -246.812562)
		)
		(stroke
			(width 0)
			(type solid)
		)
		(fill yes)
		(layer "In11.Cu")
		(net "M_F_CPU1_SA_DQS_DN<4>")
	)
	(gr_poly
		(pts
			(xy 79.931768 -241.85245) (xy 79.931768 -241.804952) (xy 79.73187 -241.804952) (xy 79.73187 -241.85245)
			(xy 79.831692 -241.952526)
		)
		(stroke
			(width 0)
			(type solid)
		)
		(fill yes)
		(layer "In11.Cu")
		(net "M_F_CPU1_SA_DQS_DN<3>")
	)
	(gr_poly
		(pts
			(xy 79.931768 -236.992414) (xy 79.931768 -236.944916) (xy 79.73187 -236.944916) (xy 79.73187 -236.992414)
			(xy 79.831692 -237.09249)
		)
		(stroke
			(width 0)
			(type solid)
		)
		(fill yes)
		(layer "In11.Cu")
		(net "M_F_CPU1_SA_DQS_DN<2>")
	)
	(gr_poly
		(pts
			(xy 79.931768 -232.132378) (xy 79.931768 -232.08488) (xy 79.73187 -232.08488) (xy 79.73187 -232.132378)
			(xy 79.831692 -232.232454)
		)
		(stroke
			(width 0)
			(type solid)
		)
		(fill yes)
		(layer "In11.Cu")
		(net "M_F_CPU1_SA_DQS_DN<1>")
	)
	(gr_poly
		(pts
			(xy 79.931768 -230.512366) (xy 79.931768 -230.467916) (xy 79.73187 -230.467916) (xy 79.73187 -230.512366)
			(xy 79.831692 -230.612442)
		)
		(stroke
			(width 0)
			(type solid)
		)
		(fill yes)
		(layer "In11.Cu")
		(net "M_F_CPU1_SA_DQ<10>")
	)
	(gr_poly
		(pts
			(xy 79.931768 -227.272596) (xy 79.931768 -227.225098) (xy 79.73187 -227.225098) (xy 79.73187 -227.272596)
			(xy 79.831692 -227.372672)
		)
		(stroke
			(width 0)
			(type solid)
		)
		(fill yes)
		(layer "In11.Cu")
		(net "M_F_CPU1_SA_DQS_DN<0>")
	)
	(gr_poly
		(pts
			(xy 79.939896 -224.035366) (xy 79.976472 -223.898714) (xy 79.83982 -223.862138) (xy 79.801212 -223.884236)
			(xy 79.901288 -224.057464)
		)
		(stroke
			(width 0)
			(type solid)
		)
		(fill yes)
		(layer "In11.Cu")
		(net "M_F_CPU1_SA_DQ<1>")
	)
	(gr_poly
		(pts
			(xy 79.94015 -225.655886) (xy 79.976726 -225.519234) (xy 79.840074 -225.482658) (xy 79.80172 -225.50501)
			(xy 79.901542 -225.678238)
		)
		(stroke
			(width 0)
			(type solid)
		)
		(fill yes)
		(layer "In11.Cu")
		(net "M_F_CPU1_SA_DQ<1>")
	)
	(gr_poly
		(pts
			(xy 79.94015 -222.415862) (xy 79.976726 -222.27921) (xy 79.840074 -222.242634) (xy 79.80172 -222.264986)
			(xy 79.901542 -222.438214)
		)
		(stroke
			(width 0)
			(type solid)
		)
		(fill yes)
		(layer "In11.Cu")
		(net "M_F_CPU1_SA_DQ<0>")
	)
	(gr_poly
		(pts
			(xy 79.976726 -224.569782) (xy 79.94015 -224.43313) (xy 79.901542 -224.410778) (xy 79.80172 -224.584006)
			(xy 79.840074 -224.606358)
		)
		(stroke
			(width 0)
			(type solid)
		)
		(fill yes)
		(layer "In11.Cu")
		(net "M_F_CPU1_SA_DQ<1>")
	)
	(gr_poly
		(pts
			(xy 80.132682 -281.99588) (xy 80.141064 -281.94889) (xy 79.94396 -281.914346) (xy 79.935832 -281.961082)
			(xy 80.016858 -282.076906)
		)
		(stroke
			(width 0)
			(type solid)
		)
		(fill yes)
		(layer "In11.Cu")
		(net "M_F_CPU1_SB_DQS_DP<6>")
	)
	(gr_poly
		(pts
			(xy 80.141318 -294.795956) (xy 80.10271 -294.773858) (xy 79.966058 -294.810434) (xy 80.002634 -294.947086)
			(xy 80.041242 -294.969184)
		)
		(stroke
			(width 0)
			(type solid)
		)
		(fill yes)
		(layer "In11.Cu")
		(net "M_F_CPU1_SB_DQ<29>")
	)
	(gr_poly
		(pts
			(xy 80.214978 -290.084256) (xy 80.214978 -290.039806) (xy 80.014826 -290.039806) (xy 80.014826 -290.084256)
			(xy 80.114902 -290.184332)
		)
		(stroke
			(width 0)
			(type solid)
		)
		(fill yes)
		(layer "In11.Cu")
		(net "M_F_CPU1_SB_DQ<27>")
	)
	(gr_poly
		(pts
			(xy 80.214978 -288.464498) (xy 80.214978 -288.420048) (xy 80.014826 -288.420048) (xy 80.014826 -288.464498)
			(xy 80.114902 -288.564574)
		)
		(stroke
			(width 0)
			(type solid)
		)
		(fill yes)
		(layer "In11.Cu")
		(net "M_F_CPU1_SB_DQ<23>")
	)
	(gr_poly
		(pts
			(xy 80.214978 -286.844486) (xy 80.214978 -286.796988) (xy 80.014826 -286.796988) (xy 80.014826 -286.844486)
			(xy 80.114902 -286.944562)
		)
		(stroke
			(width 0)
			(type solid)
		)
		(fill yes)
		(layer "In11.Cu")
		(net "M_F_CPU1_SB_DQS_DP<7>")
	)
	(gr_poly
		(pts
			(xy 80.214978 -285.224474) (xy 80.214978 -285.180024) (xy 80.014826 -285.180024) (xy 80.014826 -285.224474)
			(xy 80.114902 -285.32455)
		)
		(stroke
			(width 0)
			(type solid)
		)
		(fill yes)
		(layer "In11.Cu")
		(net "M_F_CPU1_SB_DQ<19>")
	)
	(gr_poly
		(pts
			(xy 80.214978 -283.604462) (xy 80.214978 -283.560012) (xy 80.014826 -283.560012) (xy 80.014826 -283.604462)
			(xy 80.114902 -283.704538)
		)
		(stroke
			(width 0)
			(type solid)
		)
		(fill yes)
		(layer "In11.Cu")
		(net "M_F_CPU1_SB_DQ<15>")
	)
	(gr_poly
		(pts
			(xy 80.214978 -280.364438) (xy 80.214978 -280.319988) (xy 80.014826 -280.319988) (xy 80.014826 -280.364438)
			(xy 80.114902 -280.464514)
		)
		(stroke
			(width 0)
			(type solid)
		)
		(fill yes)
		(layer "In11.Cu")
		(net "M_F_CPU1_SB_DQ<11>")
	)
	(gr_poly
		(pts
			(xy 80.214978 -278.744426) (xy 80.214978 -278.699976) (xy 80.014826 -278.699976) (xy 80.014826 -278.744426)
			(xy 80.114902 -278.844502)
		)
		(stroke
			(width 0)
			(type solid)
		)
		(fill yes)
		(layer "In11.Cu")
		(net "M_F_CPU1_SB_DQ<7>")
	)
	(gr_poly
		(pts
			(xy 80.214978 -275.504402) (xy 80.214978 -275.459952) (xy 80.014826 -275.459952) (xy 80.014826 -275.504402)
			(xy 80.114902 -275.604478)
		)
		(stroke
			(width 0)
			(type solid)
		)
		(fill yes)
		(layer "In11.Cu")
		(net "M_F_CPU1_SB_DQ<3>")
	)
	(gr_poly
		(pts
			(xy 80.214978 -273.88439) (xy 80.214978 -273.83994) (xy 80.014826 -273.83994) (xy 80.014826 -273.88439)
			(xy 80.114902 -273.984466)
		)
		(stroke
			(width 0)
			(type solid)
		)
		(fill yes)
		(layer "In11.Cu")
		(net "M_F_CPU1_SB_CB<3>")
	)
	(gr_poly
		(pts
			(xy 80.214978 -270.644366) (xy 80.214978 -270.599916) (xy 80.014826 -270.599916) (xy 80.014826 -270.644366)
			(xy 80.114902 -270.744442)
		)
		(stroke
			(width 0)
			(type solid)
		)
		(fill yes)
		(layer "In11.Cu")
		(net "M_F_CPU1_SB_CB<7>")
	)
	(gr_poly
		(pts
			(xy 80.214978 -265.78433) (xy 80.214978 -265.73988) (xy 80.014826 -265.73988) (xy 80.014826 -265.78433)
			(xy 80.114902 -265.884406)
		)
		(stroke
			(width 0)
			(type solid)
		)
		(fill yes)
		(layer "In11.Cu")
		(net "M_F_CPU1_SB_CS_N<0>")
	)
	(gr_poly
		(pts
			(xy 80.214978 -262.544306) (xy 80.214978 -262.499856) (xy 80.014826 -262.499856) (xy 80.014826 -262.544306)
			(xy 80.114902 -262.644382)
		)
		(stroke
			(width 0)
			(type solid)
		)
		(fill yes)
		(layer "In11.Cu")
		(net "M_F_CPU1_SB_CA<1>")
	)
	(gr_poly
		(pts
			(xy 80.221074 -292.108128) (xy 80.120998 -292.008052) (xy 80.020922 -292.108128) (xy 80.020922 -292.152578)
			(xy 80.221074 -292.152578)
		)
		(stroke
			(width 0)
			(type solid)
		)
		(fill yes)
		(layer "In11.Cu")
		(net "M_F_CPU1_SB_DQ<28>")
	)
	(gr_poly
		(pts
			(xy 80.221074 -277.12416) (xy 80.221074 -277.076662) (xy 80.020922 -277.076662) (xy 80.020922 -277.12416)
			(xy 80.120998 -277.224236)
		)
		(stroke
			(width 0)
			(type solid)
		)
		(fill yes)
		(layer "In11.Cu")
		(net "M_F_CPU1_SB_DQS_DP<5>")
	)
	(gr_poly
		(pts
			(xy 80.221074 -272.264124) (xy 80.221074 -272.216626) (xy 80.020922 -272.216626) (xy 80.020922 -272.264124)
			(xy 80.120998 -272.3642)
		)
		(stroke
			(width 0)
			(type solid)
		)
		(fill yes)
		(layer "In11.Cu")
		(net "M_F_CPU1_SB_DQS_DP<4>")
	)
	(gr_poly
		(pts
			(xy 80.221074 -269.428214) (xy 80.120998 -269.328138) (xy 80.020922 -269.428214) (xy 80.020922 -269.472664)
			(xy 80.221074 -269.472664)
		)
		(stroke
			(width 0)
			(type solid)
		)
		(fill yes)
		(layer "In11.Cu")
		(net "M_F_CPU1_SB_CB<4>")
	)
	(gr_poly
		(pts
			(xy 80.221328 -267.808202) (xy 80.121252 -267.708126) (xy 80.021176 -267.808202) (xy 80.021176 -267.852652)
			(xy 80.221328 -267.852652)
		)
		(stroke
			(width 0)
			(type solid)
		)
		(fill yes)
		(layer "In11.Cu")
		(net "M_F_CPU1_SB_RSP<0>")
	)
	(gr_poly
		(pts
			(xy 80.228186 -288.868104) (xy 80.128364 -288.768282) (xy 80.028288 -288.868104) (xy 80.028288 -288.912554)
			(xy 80.228186 -288.912554)
		)
		(stroke
			(width 0)
			(type solid)
		)
		(fill yes)
		(layer "In11.Cu")
		(net "M_F_CPU1_SB_DQ<24>")
	)
	(gr_poly
		(pts
			(xy 80.228186 -284.008322) (xy 80.128364 -283.9085) (xy 80.028288 -284.008322) (xy 80.028288 -284.052772)
			(xy 80.228186 -284.052772)
		)
		(stroke
			(width 0)
			(type solid)
		)
		(fill yes)
		(layer "In11.Cu")
		(net "M_F_CPU1_SB_DQ<16>")
	)
	(gr_poly
		(pts
			(xy 80.228186 -282.38831) (xy 80.128364 -282.288488) (xy 80.028288 -282.38831) (xy 80.028288 -282.43276)
			(xy 80.228186 -282.43276)
		)
		(stroke
			(width 0)
			(type solid)
		)
		(fill yes)
		(layer "In11.Cu")
		(net "M_F_CPU1_SB_DQ<12>")
	)
	(gr_poly
		(pts
			(xy 80.228186 -279.148286) (xy 80.128364 -279.048464) (xy 80.028288 -279.148286) (xy 80.028288 -279.192736)
			(xy 80.228186 -279.192736)
		)
		(stroke
			(width 0)
			(type solid)
		)
		(fill yes)
		(layer "In11.Cu")
		(net "M_F_CPU1_SB_DQ<8>")
	)
	(gr_poly
		(pts
			(xy 80.228186 -277.528274) (xy 80.128364 -277.428452) (xy 80.028288 -277.528274) (xy 80.028288 -277.572724)
			(xy 80.228186 -277.572724)
		)
		(stroke
			(width 0)
			(type solid)
		)
		(fill yes)
		(layer "In11.Cu")
		(net "M_F_CPU1_SB_DQ<4>")
	)
	(gr_poly
		(pts
			(xy 80.228186 -274.28825) (xy 80.128364 -274.188428) (xy 80.028288 -274.28825) (xy 80.028288 -274.3327)
			(xy 80.228186 -274.3327)
		)
		(stroke
			(width 0)
			(type solid)
		)
		(fill yes)
		(layer "In11.Cu")
		(net "M_F_CPU1_SB_DQ<0>")
	)
	(gr_poly
		(pts
			(xy 80.228186 -272.668238) (xy 80.128364 -272.568416) (xy 80.028288 -272.668238) (xy 80.028288 -272.712688)
			(xy 80.228186 -272.712688)
		)
		(stroke
			(width 0)
			(type solid)
		)
		(fill yes)
		(layer "In11.Cu")
		(net "M_F_CPU1_SB_CB<0>")
	)
	(gr_poly
		(pts
			(xy 80.228186 -264.568178) (xy 80.128364 -264.468356) (xy 80.028288 -264.568178) (xy 80.028288 -264.612628)
			(xy 80.228186 -264.612628)
		)
		(stroke
			(width 0)
			(type solid)
		)
		(fill yes)
		(layer "In11.Cu")
		(net "M_F_CPU1_SB_CA<6>")
	)
	(gr_poly
		(pts
			(xy 80.231742 -290.488116) (xy 80.131666 -290.38804) (xy 80.031844 -290.488116) (xy 80.031844 -290.535614)
			(xy 80.231742 -290.535614)
		)
		(stroke
			(width 0)
			(type solid)
		)
		(fill yes)
		(layer "In11.Cu")
		(net "M_F_CPU1_SB_DQS_DP<3>")
	)
	(gr_poly
		(pts
			(xy 80.231742 -287.248346) (xy 80.131666 -287.14827) (xy 80.031844 -287.248346) (xy 80.031844 -287.292796)
			(xy 80.231742 -287.292796)
		)
		(stroke
			(width 0)
			(type solid)
		)
		(fill yes)
		(layer "In11.Cu")
		(net "M_F_CPU1_SB_DQ<20>")
	)
	(gr_poly
		(pts
			(xy 80.231742 -285.628334) (xy 80.131666 -285.528258) (xy 80.031844 -285.628334) (xy 80.031844 -285.675832)
			(xy 80.231742 -285.675832)
		)
		(stroke
			(width 0)
			(type solid)
		)
		(fill yes)
		(layer "In11.Cu")
		(net "M_F_CPU1_SB_DQS_DP<2>")
	)
	(gr_poly
		(pts
			(xy 80.231742 -280.768298) (xy 80.131666 -280.668222) (xy 80.031844 -280.768298) (xy 80.031844 -280.815796)
			(xy 80.231742 -280.815796)
		)
		(stroke
			(width 0)
			(type solid)
		)
		(fill yes)
		(layer "In11.Cu")
		(net "M_F_CPU1_SB_DQS_DP<1>")
	)
	(gr_poly
		(pts
			(xy 80.231742 -275.908262) (xy 80.131666 -275.808186) (xy 80.031844 -275.908262) (xy 80.031844 -275.95576)
			(xy 80.231742 -275.95576)
		)
		(stroke
			(width 0)
			(type solid)
		)
		(fill yes)
		(layer "In11.Cu")
		(net "M_F_CPU1_SB_DQS_DP<0>")
	)
	(gr_poly
		(pts
			(xy 80.231742 -271.048226) (xy 80.131666 -270.94815) (xy 80.031844 -271.048226) (xy 80.031844 -271.095724)
			(xy 80.231742 -271.095724)
		)
		(stroke
			(width 0)
			(type solid)
		)
		(fill yes)
		(layer "In11.Cu")
		(net "M_F_CPU1_SB_DQS_DP<9>")
	)
	(gr_poly
		(pts
			(xy 80.23987 -264.164318) (xy 80.23987 -264.119868) (xy 80.039718 -264.119868) (xy 80.039718 -264.164318)
			(xy 80.139794 -264.26414)
		)
		(stroke
			(width 0)
			(type solid)
		)
		(fill yes)
		(layer "In11.Cu")
		(net "M_F_CPU1_SB_CA<5>")
	)
	(gr_poly
		(pts
			(xy 80.241902 -262.94842) (xy 80.141826 -262.848344) (xy 80.04175 -262.94842) (xy 80.04175 -262.99287)
			(xy 80.241902 -262.99287)
		)
		(stroke
			(width 0)
			(type solid)
		)
		(fill yes)
		(layer "In11.Cu")
		(net "M_F_CPU1_SB_CA<2>")
	)
	(gr_poly
		(pts
			(xy 80.276954 -293.860728) (xy 80.240378 -293.724076) (xy 80.202024 -293.701724) (xy 80.101948 -293.874952)
			(xy 80.140556 -293.897304)
		)
		(stroke
			(width 0)
			(type solid)
		)
		(fill yes)
		(layer "In11.Cu")
		(net "M_F_CPU1_SB_DQ<30>")
	)
	(gr_poly
		(pts
			(xy 80.309974 -225.392742) (xy 80.209898 -225.219514) (xy 80.171544 -225.241866) (xy 80.134714 -225.378264)
			(xy 80.271366 -225.41484)
		)
		(stroke
			(width 0)
			(type solid)
		)
		(fill yes)
		(layer "In11.Cu")
		(net "M_F_CPU1_SA_DQ<2>")
	)
	(gr_poly
		(pts
			(xy 80.309974 -224.696274) (xy 80.271366 -224.674176) (xy 80.134714 -224.710752) (xy 80.171544 -224.847404)
			(xy 80.209898 -224.869502)
		)
		(stroke
			(width 0)
			(type solid)
		)
		(fill yes)
		(layer "In11.Cu")
		(net "M_F_CPU1_SA_DQ<2>")
	)
	(gr_poly
		(pts
			(xy 80.311244 -223.774762) (xy 80.211168 -223.601534) (xy 80.17256 -223.623632) (xy 80.135984 -223.760284)
			(xy 80.272636 -223.79686)
		)
		(stroke
			(width 0)
			(type solid)
		)
		(fill yes)
		(layer "In11.Cu")
		(net "M_F_CPU1_SA_DQ<2>")
	)
	(gr_poly
		(pts
			(xy 80.391254 -256.026158) (xy 80.291178 -255.926336) (xy 80.191102 -256.026158) (xy 80.191102 -256.07391)
			(xy 80.391254 -256.07391)
		)
		(stroke
			(width 0)
			(type solid)
		)
		(fill yes)
		(layer "In11.Cu")
		(net "M_F_CPU1_CLK_DP<0>")
	)
	(gr_poly
		(pts
			(xy 80.391254 -255.622552) (xy 80.391254 -255.578102) (xy 80.191102 -255.578102) (xy 80.191102 -255.622552)
			(xy 80.291178 -255.722628)
		)
		(stroke
			(width 0)
			(type solid)
		)
		(fill yes)
		(layer "In11.Cu")
		(net "M_F_CPU1_SA_PAR")
	)
	(gr_poly
		(pts
			(xy 80.391254 -254.4064) (xy 80.291178 -254.306324) (xy 80.191102 -254.4064) (xy 80.191102 -254.45085)
			(xy 80.391254 -254.45085)
		)
		(stroke
			(width 0)
			(type solid)
		)
		(fill yes)
		(layer "In11.Cu")
		(net "M_F_CPU1_SA_CA<4>")
	)
	(gr_poly
		(pts
			(xy 80.391254 -254.00254) (xy 80.391254 -253.95809) (xy 80.191102 -253.95809) (xy 80.191102 -254.00254)
			(xy 80.291178 -254.102616)
		)
		(stroke
			(width 0)
			(type solid)
		)
		(fill yes)
		(layer "In11.Cu")
		(net "M_F_CPU1_SA_CA<3>")
	)
	(gr_poly
		(pts
			(xy 80.391254 -252.786388) (xy 80.291178 -252.686312) (xy 80.191102 -252.786388) (xy 80.191102 -252.830838)
			(xy 80.391254 -252.830838)
		)
		(stroke
			(width 0)
			(type solid)
		)
		(fill yes)
		(layer "In11.Cu")
		(net "M_F_CPU1_SA_CA<0>")
	)
	(gr_poly
		(pts
			(xy 80.391254 -252.382528) (xy 80.391254 -252.338078) (xy 80.191102 -252.338078) (xy 80.191102 -252.382528)
			(xy 80.291178 -252.482604)
		)
		(stroke
			(width 0)
			(type solid)
		)
		(fill yes)
		(layer "In11.Cu")
		(net "M_F_CPU1_SA_CS_N<1>")
	)
	(gr_poly
		(pts
			(xy 80.391254 -250.762516) (xy 80.391254 -250.718066) (xy 80.191102 -250.718066) (xy 80.191102 -250.762516)
			(xy 80.291178 -250.862592)
		)
		(stroke
			(width 0)
			(type solid)
		)
		(fill yes)
		(layer "In11.Cu")
		(net "M_F_CPU1_RESET_N")
	)
	(gr_poly
		(pts
			(xy 80.391254 -249.142504) (xy 80.391254 -249.098054) (xy 80.191102 -249.098054) (xy 80.191102 -249.142504)
			(xy 80.291178 -249.24258)
		)
		(stroke
			(width 0)
			(type solid)
		)
		(fill yes)
		(layer "In11.Cu")
		(net "M_F_CPU1_SA_CB<7>")
	)
	(gr_poly
		(pts
			(xy 80.391254 -247.926352) (xy 80.291178 -247.826276) (xy 80.191102 -247.926352) (xy 80.191102 -247.970802)
			(xy 80.391254 -247.970802)
		)
		(stroke
			(width 0)
			(type solid)
		)
		(fill yes)
		(layer "In11.Cu")
		(net "M_F_CPU1_SA_CB<4>")
	)
	(gr_poly
		(pts
			(xy 80.391254 -247.522746) (xy 80.391254 -247.474994) (xy 80.191102 -247.474994) (xy 80.191102 -247.522746)
			(xy 80.291178 -247.622568)
		)
		(stroke
			(width 0)
			(type solid)
		)
		(fill yes)
		(layer "In11.Cu")
		(net "M_F_CPU1_SA_DQS_DP<9>")
	)
	(gr_poly
		(pts
			(xy 80.391254 -246.306086) (xy 80.291178 -246.206264) (xy 80.191102 -246.306086) (xy 80.191102 -246.353838)
			(xy 80.391254 -246.353838)
		)
		(stroke
			(width 0)
			(type solid)
		)
		(fill yes)
		(layer "In11.Cu")
		(net "M_F_CPU1_SA_DQS_DP<4>")
	)
	(gr_poly
		(pts
			(xy 80.391254 -245.90248) (xy 80.391254 -245.85803) (xy 80.191102 -245.85803) (xy 80.191102 -245.90248)
			(xy 80.291178 -246.002556)
		)
		(stroke
			(width 0)
			(type solid)
		)
		(fill yes)
		(layer "In11.Cu")
		(net "M_F_CPU1_SA_CB<3>")
	)
	(gr_poly
		(pts
			(xy 80.391254 -244.686328) (xy 80.291178 -244.586252) (xy 80.191102 -244.686328) (xy 80.191102 -244.730778)
			(xy 80.391254 -244.730778)
		)
		(stroke
			(width 0)
			(type solid)
		)
		(fill yes)
		(layer "In11.Cu")
		(net "M_F_CPU1_SA_CB<0>")
	)
	(gr_poly
		(pts
			(xy 80.391254 -244.282468) (xy 80.391254 -244.238018) (xy 80.191102 -244.238018) (xy 80.191102 -244.282468)
			(xy 80.291178 -244.382544)
		)
		(stroke
			(width 0)
			(type solid)
		)
		(fill yes)
		(layer "In11.Cu")
		(net "M_F_CPU1_SA_DQ<31>")
	)
	(gr_poly
		(pts
			(xy 80.391254 -243.066316) (xy 80.291178 -242.96624) (xy 80.191102 -243.066316) (xy 80.191102 -243.110766)
			(xy 80.391254 -243.110766)
		)
		(stroke
			(width 0)
			(type solid)
		)
		(fill yes)
		(layer "In11.Cu")
		(net "M_F_CPU1_SA_DQ<28>")
	)
	(gr_poly
		(pts
			(xy 80.391254 -242.66271) (xy 80.391254 -242.614958) (xy 80.191102 -242.614958) (xy 80.191102 -242.66271)
			(xy 80.291178 -242.762532)
		)
		(stroke
			(width 0)
			(type solid)
		)
		(fill yes)
		(layer "In11.Cu")
		(net "M_F_CPU1_SA_DQS_DP<8>")
	)
	(gr_poly
		(pts
			(xy 80.391254 -241.44605) (xy 80.291178 -241.346228) (xy 80.191102 -241.44605) (xy 80.191102 -241.493802)
			(xy 80.391254 -241.493802)
		)
		(stroke
			(width 0)
			(type solid)
		)
		(fill yes)
		(layer "In11.Cu")
		(net "M_F_CPU1_SA_DQS_DP<3>")
	)
	(gr_poly
		(pts
			(xy 80.391254 -241.042444) (xy 80.391254 -240.997994) (xy 80.191102 -240.997994) (xy 80.191102 -241.042444)
			(xy 80.291178 -241.14252)
		)
		(stroke
			(width 0)
			(type solid)
		)
		(fill yes)
		(layer "In11.Cu")
		(net "M_F_CPU1_SA_DQ<27>")
	)
	(gr_poly
		(pts
			(xy 80.391254 -239.826292) (xy 80.291178 -239.726216) (xy 80.191102 -239.826292) (xy 80.191102 -239.870742)
			(xy 80.391254 -239.870742)
		)
		(stroke
			(width 0)
			(type solid)
		)
		(fill yes)
		(layer "In11.Cu")
		(net "M_F_CPU1_SA_DQ<24>")
	)
	(gr_poly
		(pts
			(xy 80.391254 -239.422432) (xy 80.391254 -239.377982) (xy 80.191102 -239.377982) (xy 80.191102 -239.422432)
			(xy 80.291178 -239.522508)
		)
		(stroke
			(width 0)
			(type solid)
		)
		(fill yes)
		(layer "In11.Cu")
		(net "M_F_CPU1_SA_DQ<23>")
	)
	(gr_poly
		(pts
			(xy 80.391254 -238.20628) (xy 80.291178 -238.106204) (xy 80.191102 -238.20628) (xy 80.191102 -238.25073)
			(xy 80.391254 -238.25073)
		)
		(stroke
			(width 0)
			(type solid)
		)
		(fill yes)
		(layer "In11.Cu")
		(net "M_F_CPU1_SA_DQ<20>")
	)
	(gr_poly
		(pts
			(xy 80.391254 -237.802674) (xy 80.391254 -237.754922) (xy 80.191102 -237.754922) (xy 80.191102 -237.802674)
			(xy 80.291178 -237.902496)
		)
		(stroke
			(width 0)
			(type solid)
		)
		(fill yes)
		(layer "In11.Cu")
		(net "M_F_CPU1_SA_DQS_DP<7>")
	)
	(gr_poly
		(pts
			(xy 80.391254 -236.586014) (xy 80.291178 -236.486192) (xy 80.191102 -236.586014) (xy 80.191102 -236.633766)
			(xy 80.391254 -236.633766)
		)
		(stroke
			(width 0)
			(type solid)
		)
		(fill yes)
		(layer "In11.Cu")
		(net "M_F_CPU1_SA_DQS_DP<2>")
	)
	(gr_poly
		(pts
			(xy 80.391254 -236.182408) (xy 80.391254 -236.137958) (xy 80.191102 -236.137958) (xy 80.191102 -236.182408)
			(xy 80.291178 -236.282484)
		)
		(stroke
			(width 0)
			(type solid)
		)
		(fill yes)
		(layer "In11.Cu")
		(net "M_F_CPU1_SA_DQ<19>")
	)
	(gr_poly
		(pts
			(xy 80.391254 -234.966256) (xy 80.291178 -234.86618) (xy 80.191102 -234.966256) (xy 80.191102 -235.010706)
			(xy 80.391254 -235.010706)
		)
		(stroke
			(width 0)
			(type solid)
		)
		(fill yes)
		(layer "In11.Cu")
		(net "M_F_CPU1_SA_DQ<16>")
	)
	(gr_poly
		(pts
			(xy 80.391254 -234.562396) (xy 80.391254 -234.517946) (xy 80.191102 -234.517946) (xy 80.191102 -234.562396)
			(xy 80.291178 -234.662472)
		)
		(stroke
			(width 0)
			(type solid)
		)
		(fill yes)
		(layer "In11.Cu")
		(net "M_F_CPU1_SA_DQ<15>")
	)
	(gr_poly
		(pts
			(xy 80.391254 -233.346244) (xy 80.291178 -233.246168) (xy 80.191102 -233.346244) (xy 80.191102 -233.390694)
			(xy 80.391254 -233.390694)
		)
		(stroke
			(width 0)
			(type solid)
		)
		(fill yes)
		(layer "In11.Cu")
		(net "M_F_CPU1_SA_DQ<12>")
	)
	(gr_poly
		(pts
			(xy 80.391254 -232.942638) (xy 80.391254 -232.894886) (xy 80.191102 -232.894886) (xy 80.191102 -232.942638)
			(xy 80.291178 -233.04246)
		)
		(stroke
			(width 0)
			(type solid)
		)
		(fill yes)
		(layer "In11.Cu")
		(net "M_F_CPU1_SA_DQS_DP<6>")
	)
	(gr_poly
		(pts
			(xy 80.391254 -231.725978) (xy 80.291178 -231.626156) (xy 80.191102 -231.725978) (xy 80.191102 -231.77373)
			(xy 80.391254 -231.77373)
		)
		(stroke
			(width 0)
			(type solid)
		)
		(fill yes)
		(layer "In11.Cu")
		(net "M_F_CPU1_SA_DQS_DP<1>")
	)
	(gr_poly
		(pts
			(xy 80.391254 -231.322626) (xy 80.391254 -231.278176) (xy 80.191102 -231.278176) (xy 80.191102 -231.322626)
			(xy 80.291178 -231.422702)
		)
		(stroke
			(width 0)
			(type solid)
		)
		(fill yes)
		(layer "In11.Cu")
		(net "M_F_CPU1_SA_DQ<11>")
	)
	(gr_poly
		(pts
			(xy 80.391254 -230.10622) (xy 80.291178 -230.006144) (xy 80.191102 -230.10622) (xy 80.191102 -230.15067)
			(xy 80.391254 -230.15067)
		)
		(stroke
			(width 0)
			(type solid)
		)
		(fill yes)
		(layer "In11.Cu")
		(net "M_F_CPU1_SA_DQ<8>")
	)
	(gr_poly
		(pts
			(xy 80.391254 -229.702614) (xy 80.391254 -229.658164) (xy 80.191102 -229.658164) (xy 80.191102 -229.702614)
			(xy 80.291178 -229.80269)
		)
		(stroke
			(width 0)
			(type solid)
		)
		(fill yes)
		(layer "In11.Cu")
		(net "M_F_CPU1_SA_DQ<7>")
	)
	(gr_poly
		(pts
			(xy 80.391254 -228.486462) (xy 80.291178 -228.386386) (xy 80.191102 -228.486462) (xy 80.191102 -228.530912)
			(xy 80.391254 -228.530912)
		)
		(stroke
			(width 0)
			(type solid)
		)
		(fill yes)
		(layer "In11.Cu")
		(net "M_F_CPU1_SA_DQ<4>")
	)
	(gr_poly
		(pts
			(xy 80.391254 -228.082856) (xy 80.391254 -228.035104) (xy 80.191102 -228.035104) (xy 80.191102 -228.082856)
			(xy 80.291178 -228.182678)
		)
		(stroke
			(width 0)
			(type solid)
		)
		(fill yes)
		(layer "In11.Cu")
		(net "M_F_CPU1_SA_DQS_DP<5>")
	)
	(gr_poly
		(pts
			(xy 80.391254 -226.866196) (xy 80.291178 -226.766374) (xy 80.191102 -226.866196) (xy 80.191102 -226.913948)
			(xy 80.391254 -226.913948)
		)
		(stroke
			(width 0)
			(type solid)
		)
		(fill yes)
		(layer "In11.Cu")
		(net "M_F_CPU1_SA_DQS_DP<0>")
	)
	(gr_poly
		(pts
			(xy 80.391254 -226.46259) (xy 80.391254 -226.41814) (xy 80.191102 -226.41814) (xy 80.191102 -226.46259)
			(xy 80.291178 -226.562666)
		)
		(stroke
			(width 0)
			(type solid)
		)
		(fill yes)
		(layer "In11.Cu")
		(net "M_F_CPU1_SA_DQ<3>")
	)
	(gr_poly
		(pts
			(xy 80.409796 -223.22536) (xy 80.446372 -223.088708) (xy 80.30972 -223.052132) (xy 80.271112 -223.07423)
			(xy 80.371188 -223.247458)
		)
		(stroke
			(width 0)
			(type solid)
		)
		(fill yes)
		(layer "In11.Cu")
		(net "M_F_CPU1_SA_DQ<0>")
	)
	(gr_poly
		(pts
			(xy 80.610202 -293.987474) (xy 80.571594 -293.965122) (xy 80.434942 -294.001698) (xy 80.471772 -294.13835)
			(xy 80.510126 -294.160702)
		)
		(stroke
			(width 0)
			(type solid)
		)
		(fill yes)
		(layer "In11.Cu")
		(net "M_F_CPU1_SB_DQ<29>")
	)
	(gr_poly
		(pts
			(xy 80.691228 -291.297868) (xy 80.591152 -291.198046) (xy 80.491076 -291.297868) (xy 80.491076 -291.34562)
			(xy 80.691228 -291.34562)
		)
		(stroke
			(width 0)
			(type solid)
		)
		(fill yes)
		(layer "In11.Cu")
		(net "M_F_CPU1_SB_DQS_DN<8>")
	)
	(gr_poly
		(pts
			(xy 80.691228 -290.894516) (xy 80.691228 -290.846764) (xy 80.491076 -290.846764) (xy 80.491076 -290.894516)
			(xy 80.591152 -290.994338)
		)
		(stroke
			(width 0)
			(type solid)
		)
		(fill yes)
		(layer "In11.Cu")
		(net "M_F_CPU1_SB_DQS_DN<3>")
	)
	(gr_poly
		(pts
			(xy 80.691228 -289.67811) (xy 80.591152 -289.578034) (xy 80.491076 -289.67811) (xy 80.491076 -289.72256)
			(xy 80.691228 -289.72256)
		)
		(stroke
			(width 0)
			(type solid)
		)
		(fill yes)
		(layer "In11.Cu")
		(net "M_F_CPU1_SB_DQ<25>")
	)
	(gr_poly
		(pts
			(xy 80.691228 -289.27425) (xy 80.691228 -289.2298) (xy 80.491076 -289.2298) (xy 80.491076 -289.27425)
			(xy 80.591152 -289.374326)
		)
		(stroke
			(width 0)
			(type solid)
		)
		(fill yes)
		(layer "In11.Cu")
		(net "M_F_CPU1_SB_DQ<26>")
	)
	(gr_poly
		(pts
			(xy 80.691228 -288.058098) (xy 80.591152 -287.958022) (xy 80.491076 -288.058098) (xy 80.491076 -288.102548)
			(xy 80.691228 -288.102548)
		)
		(stroke
			(width 0)
			(type solid)
		)
		(fill yes)
		(layer "In11.Cu")
		(net "M_F_CPU1_SB_DQ<21>")
	)
	(gr_poly
		(pts
			(xy 80.691228 -287.654492) (xy 80.691228 -287.610042) (xy 80.491076 -287.610042) (xy 80.491076 -287.654492)
			(xy 80.591152 -287.754568)
		)
		(stroke
			(width 0)
			(type solid)
		)
		(fill yes)
		(layer "In11.Cu")
		(net "M_F_CPU1_SB_DQ<22>")
	)
	(gr_poly
		(pts
			(xy 80.691228 -286.438086) (xy 80.591152 -286.33801) (xy 80.491076 -286.438086) (xy 80.491076 -286.485838)
			(xy 80.691228 -286.485838)
		)
		(stroke
			(width 0)
			(type solid)
		)
		(fill yes)
		(layer "In11.Cu")
		(net "M_F_CPU1_SB_DQS_DN<7>")
	)
	(gr_poly
		(pts
			(xy 80.691228 -286.034734) (xy 80.691228 -285.986982) (xy 80.491076 -285.986982) (xy 80.491076 -286.034734)
			(xy 80.591152 -286.134556)
		)
		(stroke
			(width 0)
			(type solid)
		)
		(fill yes)
		(layer "In11.Cu")
		(net "M_F_CPU1_SB_DQS_DN<2>")
	)
	(gr_poly
		(pts
			(xy 80.691228 -284.818328) (xy 80.591152 -284.718252) (xy 80.491076 -284.818328) (xy 80.491076 -284.862778)
			(xy 80.691228 -284.862778)
		)
		(stroke
			(width 0)
			(type solid)
		)
		(fill yes)
		(layer "In11.Cu")
		(net "M_F_CPU1_SB_DQ<17>")
	)
	(gr_poly
		(pts
			(xy 80.691228 -284.414468) (xy 80.691228 -284.370018) (xy 80.491076 -284.370018) (xy 80.491076 -284.414468)
			(xy 80.591152 -284.514544)
		)
		(stroke
			(width 0)
			(type solid)
		)
		(fill yes)
		(layer "In11.Cu")
		(net "M_F_CPU1_SB_DQ<18>")
	)
	(gr_poly
		(pts
			(xy 80.691228 -283.198316) (xy 80.591152 -283.09824) (xy 80.491076 -283.198316) (xy 80.491076 -283.242766)
			(xy 80.691228 -283.242766)
		)
		(stroke
			(width 0)
			(type solid)
		)
		(fill yes)
		(layer "In11.Cu")
		(net "M_F_CPU1_SB_DQ<13>")
	)
	(gr_poly
		(pts
			(xy 80.691228 -282.794456) (xy 80.691228 -282.750006) (xy 80.491076 -282.750006) (xy 80.491076 -282.794456)
			(xy 80.591152 -282.894532)
		)
		(stroke
			(width 0)
			(type solid)
		)
		(fill yes)
		(layer "In11.Cu")
		(net "M_F_CPU1_SB_DQ<14>")
	)
	(gr_poly
		(pts
			(xy 80.691228 -281.57805) (xy 80.591152 -281.478228) (xy 80.491076 -281.57805) (xy 80.491076 -281.625802)
			(xy 80.691228 -281.625802)
		)
		(stroke
			(width 0)
			(type solid)
		)
		(fill yes)
		(layer "In11.Cu")
		(net "M_F_CPU1_SB_DQS_DN<6>")
	)
	(gr_poly
		(pts
			(xy 80.691228 -281.174698) (xy 80.691228 -281.126946) (xy 80.491076 -281.126946) (xy 80.491076 -281.174698)
			(xy 80.591152 -281.27452)
		)
		(stroke
			(width 0)
			(type solid)
		)
		(fill yes)
		(layer "In11.Cu")
		(net "M_F_CPU1_SB_DQS_DN<1>")
	)
	(gr_poly
		(pts
			(xy 80.691228 -279.958292) (xy 80.591152 -279.858216) (xy 80.491076 -279.958292) (xy 80.491076 -280.002742)
			(xy 80.691228 -280.002742)
		)
		(stroke
			(width 0)
			(type solid)
		)
		(fill yes)
		(layer "In11.Cu")
		(net "M_F_CPU1_SB_DQ<9>")
	)
	(gr_poly
		(pts
			(xy 80.691228 -279.554432) (xy 80.691228 -279.509982) (xy 80.491076 -279.509982) (xy 80.491076 -279.554432)
			(xy 80.591152 -279.654508)
		)
		(stroke
			(width 0)
			(type solid)
		)
		(fill yes)
		(layer "In11.Cu")
		(net "M_F_CPU1_SB_DQ<10>")
	)
	(gr_poly
		(pts
			(xy 80.691228 -278.33828) (xy 80.591152 -278.238204) (xy 80.491076 -278.33828) (xy 80.491076 -278.38273)
			(xy 80.691228 -278.38273)
		)
		(stroke
			(width 0)
			(type solid)
		)
		(fill yes)
		(layer "In11.Cu")
		(net "M_F_CPU1_SB_DQ<5>")
	)
	(gr_poly
		(pts
			(xy 80.691228 -277.93442) (xy 80.691228 -277.88997) (xy 80.491076 -277.88997) (xy 80.491076 -277.93442)
			(xy 80.591152 -278.034496)
		)
		(stroke
			(width 0)
			(type solid)
		)
		(fill yes)
		(layer "In11.Cu")
		(net "M_F_CPU1_SB_DQ<6>")
	)
	(gr_poly
		(pts
			(xy 80.691228 -276.718014) (xy 80.591152 -276.618192) (xy 80.491076 -276.718014) (xy 80.491076 -276.765766)
			(xy 80.691228 -276.765766)
		)
		(stroke
			(width 0)
			(type solid)
		)
		(fill yes)
		(layer "In11.Cu")
		(net "M_F_CPU1_SB_DQS_DN<5>")
	)
	(gr_poly
		(pts
			(xy 80.691228 -276.314662) (xy 80.691228 -276.26691) (xy 80.491076 -276.26691) (xy 80.491076 -276.314662)
			(xy 80.591152 -276.414484)
		)
		(stroke
			(width 0)
			(type solid)
		)
		(fill yes)
		(layer "In11.Cu")
		(net "M_F_CPU1_SB_DQS_DN<0>")
	)
	(gr_poly
		(pts
			(xy 80.691228 -275.098256) (xy 80.591152 -274.99818) (xy 80.491076 -275.098256) (xy 80.491076 -275.142706)
			(xy 80.691228 -275.142706)
		)
		(stroke
			(width 0)
			(type solid)
		)
		(fill yes)
		(layer "In11.Cu")
		(net "M_F_CPU1_SB_DQ<1>")
	)
	(gr_poly
		(pts
			(xy 80.691228 -274.694396) (xy 80.691228 -274.649946) (xy 80.491076 -274.649946) (xy 80.491076 -274.694396)
			(xy 80.591152 -274.794472)
		)
		(stroke
			(width 0)
			(type solid)
		)
		(fill yes)
		(layer "In11.Cu")
		(net "M_F_CPU1_SB_DQ<2>")
	)
	(gr_poly
		(pts
			(xy 80.691228 -273.478244) (xy 80.591152 -273.378168) (xy 80.491076 -273.478244) (xy 80.491076 -273.522694)
			(xy 80.691228 -273.522694)
		)
		(stroke
			(width 0)
			(type solid)
		)
		(fill yes)
		(layer "In11.Cu")
		(net "M_F_CPU1_SB_CB<1>")
	)
	(gr_poly
		(pts
			(xy 80.691228 -273.074384) (xy 80.691228 -273.029934) (xy 80.491076 -273.029934) (xy 80.491076 -273.074384)
			(xy 80.591152 -273.17446)
		)
		(stroke
			(width 0)
			(type solid)
		)
		(fill yes)
		(layer "In11.Cu")
		(net "M_F_CPU1_SB_CB<2>")
	)
	(gr_poly
		(pts
			(xy 80.691228 -271.857978) (xy 80.591152 -271.758156) (xy 80.491076 -271.857978) (xy 80.491076 -271.90573)
			(xy 80.691228 -271.90573)
		)
		(stroke
			(width 0)
			(type solid)
		)
		(fill yes)
		(layer "In11.Cu")
		(net "M_F_CPU1_SB_DQS_DN<4>")
	)
	(gr_poly
		(pts
			(xy 80.691228 -271.454626) (xy 80.691228 -271.406874) (xy 80.491076 -271.406874) (xy 80.491076 -271.454626)
			(xy 80.591152 -271.554448)
		)
		(stroke
			(width 0)
			(type solid)
		)
		(fill yes)
		(layer "In11.Cu")
		(net "M_F_CPU1_SB_DQS_DN<9>")
	)
	(gr_poly
		(pts
			(xy 80.691228 -270.23822) (xy 80.591152 -270.138144) (xy 80.491076 -270.23822) (xy 80.491076 -270.28267)
			(xy 80.691228 -270.28267)
		)
		(stroke
			(width 0)
			(type solid)
		)
		(fill yes)
		(layer "In11.Cu")
		(net "M_F_CPU1_SB_CB<5>")
	)
	(gr_poly
		(pts
			(xy 80.691228 -269.83436) (xy 80.691228 -269.78991) (xy 80.491076 -269.78991) (xy 80.491076 -269.83436)
			(xy 80.591152 -269.934436)
		)
		(stroke
			(width 0)
			(type solid)
		)
		(fill yes)
		(layer "In11.Cu")
		(net "M_F_CPU1_SB_CB<6>")
	)
	(gr_poly
		(pts
			(xy 80.691228 -266.998196) (xy 80.591152 -266.89812) (xy 80.491076 -266.998196) (xy 80.491076 -267.042646)
			(xy 80.691228 -267.042646)
		)
		(stroke
			(width 0)
			(type solid)
		)
		(fill yes)
		(layer "In11.Cu")
		(net "M_F_CPU1_SA_RSP<0>")
	)
	(gr_poly
		(pts
			(xy 80.691228 -266.594336) (xy 80.691228 -266.549886) (xy 80.491076 -266.549886) (xy 80.491076 -266.594336)
			(xy 80.591152 -266.694412)
		)
		(stroke
			(width 0)
			(type solid)
		)
		(fill yes)
		(layer "In11.Cu")
		(net "M_F_CPU1_SB_CS_N<1>")
	)
	(gr_poly
		(pts
			(xy 80.691228 -264.974324) (xy 80.691228 -264.929874) (xy 80.491076 -264.929874) (xy 80.491076 -264.974324)
			(xy 80.591152 -265.0744)
		)
		(stroke
			(width 0)
			(type solid)
		)
		(fill yes)
		(layer "In11.Cu")
		(net "M_F_CPU1_SB_PAR")
	)
	(gr_poly
		(pts
			(xy 80.691228 -263.758172) (xy 80.591152 -263.658096) (xy 80.491076 -263.758172) (xy 80.491076 -263.802622)
			(xy 80.691228 -263.802622)
		)
		(stroke
			(width 0)
			(type solid)
		)
		(fill yes)
		(layer "In11.Cu")
		(net "M_F_CPU1_SB_CA<4>")
	)
	(gr_poly
		(pts
			(xy 80.691228 -263.354312) (xy 80.691228 -263.309862) (xy 80.491076 -263.309862) (xy 80.491076 -263.354312)
			(xy 80.591152 -263.454388)
		)
		(stroke
			(width 0)
			(type solid)
		)
		(fill yes)
		(layer "In11.Cu")
		(net "M_F_CPU1_SB_CA<3>")
	)
	(gr_poly
		(pts
			(xy 80.691228 -262.13816) (xy 80.591152 -262.038084) (xy 80.491076 -262.13816) (xy 80.491076 -262.18261)
			(xy 80.691228 -262.18261)
		)
		(stroke
			(width 0)
			(type solid)
		)
		(fill yes)
		(layer "In11.Cu")
		(net "M_F_CPU1_SB_CA<0>")
	)
	(gr_poly
		(pts
			(xy 80.736186 -296.30878) (xy 80.69961 -296.172128) (xy 80.661256 -296.15003) (xy 80.56118 -296.323258)
			(xy 80.599534 -296.345356)
		)
		(stroke
			(width 0)
			(type solid)
		)
		(fill yes)
		(layer "In11.Cu")
		(net "M_F_CPU1_SB_DQ<31>")
	)
	(gr_poly
		(pts
			(xy 80.73644 -293.068756) (xy 80.699864 -292.932104) (xy 80.66151 -292.909752) (xy 80.561434 -293.08298)
			(xy 80.599788 -293.105332)
		)
		(stroke
			(width 0)
			(type solid)
		)
		(fill yes)
		(layer "In11.Cu")
		(net "M_F_CPU1_SB_DQ<30>")
	)
	(gr_poly
		(pts
			(xy 80.861154 -256.432812) (xy 80.861154 -256.38506) (xy 80.661002 -256.38506) (xy 80.661002 -256.432812)
			(xy 80.761078 -256.532634)
		)
		(stroke
			(width 0)
			(type solid)
		)
		(fill yes)
		(layer "In11.Cu")
		(net "M_F_CPU1_CLK_DN<0>")
	)
	(gr_poly
		(pts
			(xy 80.861154 -255.216406) (xy 80.761078 -255.11633) (xy 80.661002 -255.216406) (xy 80.661002 -255.260856)
			(xy 80.861154 -255.260856)
		)
		(stroke
			(width 0)
			(type solid)
		)
		(fill yes)
		(layer "In11.Cu")
		(net "M_F_CPU1_SA_CA<6>")
	)
	(gr_poly
		(pts
			(xy 80.861154 -254.812546) (xy 80.861154 -254.768096) (xy 80.661002 -254.768096) (xy 80.661002 -254.812546)
			(xy 80.761078 -254.912622)
		)
		(stroke
			(width 0)
			(type solid)
		)
		(fill yes)
		(layer "In11.Cu")
		(net "M_F_CPU1_SA_CA<5>")
	)
	(gr_poly
		(pts
			(xy 80.861154 -253.596394) (xy 80.761078 -253.496318) (xy 80.661002 -253.596394) (xy 80.661002 -253.640844)
			(xy 80.861154 -253.640844)
		)
		(stroke
			(width 0)
			(type solid)
		)
		(fill yes)
		(layer "In11.Cu")
		(net "M_F_CPU1_SA_CA<2>")
	)
	(gr_poly
		(pts
			(xy 80.861154 -253.192534) (xy 80.861154 -253.148084) (xy 80.661002 -253.148084) (xy 80.661002 -253.192534)
			(xy 80.761078 -253.29261)
		)
		(stroke
			(width 0)
			(type solid)
		)
		(fill yes)
		(layer "In11.Cu")
		(net "M_F_CPU1_SA_CA<1>")
	)
	(gr_poly
		(pts
			(xy 80.861154 -251.572522) (xy 80.861154 -251.528072) (xy 80.661002 -251.528072) (xy 80.661002 -251.572522)
			(xy 80.761078 -251.672598)
		)
		(stroke
			(width 0)
			(type solid)
		)
		(fill yes)
		(layer "In11.Cu")
		(net "M_F_CPU1_SA_CS_N<0>")
	)
	(gr_poly
		(pts
			(xy 80.861154 -250.35637) (xy 80.761078 -250.256294) (xy 80.661002 -250.35637) (xy 80.661002 -250.40082)
			(xy 80.861154 -250.40082)
		)
		(stroke
			(width 0)
			(type solid)
		)
		(fill yes)
		(layer "In11.Cu")
		(net "M_F_CPU1_ALERT_R_N")
	)
	(gr_poly
		(pts
			(xy 80.861154 -248.736358) (xy 80.761078 -248.636282) (xy 80.661002 -248.736358) (xy 80.661002 -248.780808)
			(xy 80.861154 -248.780808)
		)
		(stroke
			(width 0)
			(type solid)
		)
		(fill yes)
		(layer "In11.Cu")
		(net "M_F_CPU1_SA_CB<5>")
	)
	(gr_poly
		(pts
			(xy 80.861154 -248.332498) (xy 80.861154 -248.288048) (xy 80.661002 -248.288048) (xy 80.661002 -248.332498)
			(xy 80.761078 -248.432574)
		)
		(stroke
			(width 0)
			(type solid)
		)
		(fill yes)
		(layer "In11.Cu")
		(net "M_F_CPU1_SA_CB<6>")
	)
	(gr_poly
		(pts
			(xy 80.861154 -247.116092) (xy 80.761078 -247.01627) (xy 80.661002 -247.116092) (xy 80.661002 -247.163844)
			(xy 80.861154 -247.163844)
		)
		(stroke
			(width 0)
			(type solid)
		)
		(fill yes)
		(layer "In11.Cu")
		(net "M_F_CPU1_SA_DQS_DN<9>")
	)
	(gr_poly
		(pts
			(xy 80.861154 -246.71274) (xy 80.861154 -246.664988) (xy 80.661002 -246.664988) (xy 80.661002 -246.71274)
			(xy 80.761078 -246.812562)
		)
		(stroke
			(width 0)
			(type solid)
		)
		(fill yes)
		(layer "In11.Cu")
		(net "M_F_CPU1_SA_DQS_DN<4>")
	)
	(gr_poly
		(pts
			(xy 80.861154 -245.496334) (xy 80.761078 -245.396258) (xy 80.661002 -245.496334) (xy 80.661002 -245.540784)
			(xy 80.861154 -245.540784)
		)
		(stroke
			(width 0)
			(type solid)
		)
		(fill yes)
		(layer "In11.Cu")
		(net "M_F_CPU1_SA_CB<1>")
	)
	(gr_poly
		(pts
			(xy 80.861154 -245.092474) (xy 80.861154 -245.048024) (xy 80.661002 -245.048024) (xy 80.661002 -245.092474)
			(xy 80.761078 -245.19255)
		)
		(stroke
			(width 0)
			(type solid)
		)
		(fill yes)
		(layer "In11.Cu")
		(net "M_F_CPU1_SA_CB<2>")
	)
	(gr_poly
		(pts
			(xy 80.861154 -243.876322) (xy 80.761078 -243.776246) (xy 80.661002 -243.876322) (xy 80.661002 -243.920772)
			(xy 80.861154 -243.920772)
		)
		(stroke
			(width 0)
			(type solid)
		)
		(fill yes)
		(layer "In11.Cu")
		(net "M_F_CPU1_SA_DQ<29>")
	)
	(gr_poly
		(pts
			(xy 80.861154 -243.472462) (xy 80.861154 -243.428012) (xy 80.661002 -243.428012) (xy 80.661002 -243.472462)
			(xy 80.761078 -243.572538)
		)
		(stroke
			(width 0)
			(type solid)
		)
		(fill yes)
		(layer "In11.Cu")
		(net "M_F_CPU1_SA_DQ<30>")
	)
	(gr_poly
		(pts
			(xy 80.861154 -242.256056) (xy 80.761078 -242.156234) (xy 80.661002 -242.256056) (xy 80.661002 -242.303808)
			(xy 80.861154 -242.303808)
		)
		(stroke
			(width 0)
			(type solid)
		)
		(fill yes)
		(layer "In11.Cu")
		(net "M_F_CPU1_SA_DQS_DN<8>")
	)
	(gr_poly
		(pts
			(xy 80.861154 -241.852704) (xy 80.861154 -241.804952) (xy 80.661002 -241.804952) (xy 80.661002 -241.852704)
			(xy 80.761078 -241.952526)
		)
		(stroke
			(width 0)
			(type solid)
		)
		(fill yes)
		(layer "In11.Cu")
		(net "M_F_CPU1_SA_DQS_DN<3>")
	)
	(gr_poly
		(pts
			(xy 80.861154 -240.636298) (xy 80.761078 -240.536222) (xy 80.661002 -240.636298) (xy 80.661002 -240.680748)
			(xy 80.861154 -240.680748)
		)
		(stroke
			(width 0)
			(type solid)
		)
		(fill yes)
		(layer "In11.Cu")
		(net "M_F_CPU1_SA_DQ<25>")
	)
	(gr_poly
		(pts
			(xy 80.861154 -240.232438) (xy 80.861154 -240.187988) (xy 80.661002 -240.187988) (xy 80.661002 -240.232438)
			(xy 80.761078 -240.332514)
		)
		(stroke
			(width 0)
			(type solid)
		)
		(fill yes)
		(layer "In11.Cu")
		(net "M_F_CPU1_SA_DQ<26>")
	)
	(gr_poly
		(pts
			(xy 80.861154 -239.016286) (xy 80.761078 -238.91621) (xy 80.661002 -239.016286) (xy 80.661002 -239.060736)
			(xy 80.861154 -239.060736)
		)
		(stroke
			(width 0)
			(type solid)
		)
		(fill yes)
		(layer "In11.Cu")
		(net "M_F_CPU1_SA_DQ<21>")
	)
	(gr_poly
		(pts
			(xy 80.861154 -238.612426) (xy 80.861154 -238.567976) (xy 80.661002 -238.567976) (xy 80.661002 -238.612426)
			(xy 80.761078 -238.712502)
		)
		(stroke
			(width 0)
			(type solid)
		)
		(fill yes)
		(layer "In11.Cu")
		(net "M_F_CPU1_SA_DQ<22>")
	)
	(gr_poly
		(pts
			(xy 80.861154 -237.39602) (xy 80.761078 -237.296198) (xy 80.661002 -237.39602) (xy 80.661002 -237.443772)
			(xy 80.861154 -237.443772)
		)
		(stroke
			(width 0)
			(type solid)
		)
		(fill yes)
		(layer "In11.Cu")
		(net "M_F_CPU1_SA_DQS_DN<7>")
	)
	(gr_poly
		(pts
			(xy 80.861154 -236.992668) (xy 80.861154 -236.944916) (xy 80.661002 -236.944916) (xy 80.661002 -236.992668)
			(xy 80.761078 -237.09249)
		)
		(stroke
			(width 0)
			(type solid)
		)
		(fill yes)
		(layer "In11.Cu")
		(net "M_F_CPU1_SA_DQS_DN<2>")
	)
	(gr_poly
		(pts
			(xy 80.861154 -235.776262) (xy 80.761078 -235.676186) (xy 80.661002 -235.776262) (xy 80.661002 -235.820712)
			(xy 80.861154 -235.820712)
		)
		(stroke
			(width 0)
			(type solid)
		)
		(fill yes)
		(layer "In11.Cu")
		(net "M_F_CPU1_SA_DQ<17>")
	)
	(gr_poly
		(pts
			(xy 80.861154 -235.372402) (xy 80.861154 -235.327952) (xy 80.661002 -235.327952) (xy 80.661002 -235.372402)
			(xy 80.761078 -235.472478)
		)
		(stroke
			(width 0)
			(type solid)
		)
		(fill yes)
		(layer "In11.Cu")
		(net "M_F_CPU1_SA_DQ<18>")
	)
	(gr_poly
		(pts
			(xy 80.861154 -234.15625) (xy 80.761078 -234.056174) (xy 80.661002 -234.15625) (xy 80.661002 -234.2007)
			(xy 80.861154 -234.2007)
		)
		(stroke
			(width 0)
			(type solid)
		)
		(fill yes)
		(layer "In11.Cu")
		(net "M_F_CPU1_SA_DQ<13>")
	)
	(gr_poly
		(pts
			(xy 80.861154 -233.75239) (xy 80.861154 -233.70794) (xy 80.661002 -233.70794) (xy 80.661002 -233.75239)
			(xy 80.761078 -233.852466)
		)
		(stroke
			(width 0)
			(type solid)
		)
		(fill yes)
		(layer "In11.Cu")
		(net "M_F_CPU1_SA_DQ<14>")
	)
	(gr_poly
		(pts
			(xy 80.861154 -232.535984) (xy 80.761078 -232.436162) (xy 80.661002 -232.535984) (xy 80.661002 -232.583736)
			(xy 80.861154 -232.583736)
		)
		(stroke
			(width 0)
			(type solid)
		)
		(fill yes)
		(layer "In11.Cu")
		(net "M_F_CPU1_SA_DQS_DN<6>")
	)
	(gr_poly
		(pts
			(xy 80.861154 -232.132632) (xy 80.861154 -232.08488) (xy 80.661002 -232.08488) (xy 80.661002 -232.132632)
			(xy 80.761078 -232.232454)
		)
		(stroke
			(width 0)
			(type solid)
		)
		(fill yes)
		(layer "In11.Cu")
		(net "M_F_CPU1_SA_DQS_DN<1>")
	)
	(gr_poly
		(pts
			(xy 80.861154 -230.916226) (xy 80.761078 -230.81615) (xy 80.661002 -230.916226) (xy 80.661002 -230.960676)
			(xy 80.861154 -230.960676)
		)
		(stroke
			(width 0)
			(type solid)
		)
		(fill yes)
		(layer "In11.Cu")
		(net "M_F_CPU1_SA_DQ<9>")
	)
	(gr_poly
		(pts
			(xy 80.861154 -230.51262) (xy 80.861154 -230.46817) (xy 80.661002 -230.46817) (xy 80.661002 -230.51262)
			(xy 80.761078 -230.612696)
		)
		(stroke
			(width 0)
			(type solid)
		)
		(fill yes)
		(layer "In11.Cu")
		(net "M_F_CPU1_SA_DQ<10>")
	)
	(gr_poly
		(pts
			(xy 80.861154 -229.296214) (xy 80.761078 -229.196138) (xy 80.661002 -229.296214) (xy 80.661002 -229.340664)
			(xy 80.861154 -229.340664)
		)
		(stroke
			(width 0)
			(type solid)
		)
		(fill yes)
		(layer "In11.Cu")
		(net "M_F_CPU1_SA_DQ<5>")
	)
	(gr_poly
		(pts
			(xy 80.861154 -228.892608) (xy 80.861154 -228.848158) (xy 80.661002 -228.848158) (xy 80.661002 -228.892608)
			(xy 80.761078 -228.992684)
		)
		(stroke
			(width 0)
			(type solid)
		)
		(fill yes)
		(layer "In11.Cu")
		(net "M_F_CPU1_SA_DQ<6>")
	)
	(gr_poly
		(pts
			(xy 80.861154 -227.676202) (xy 80.761078 -227.57638) (xy 80.661002 -227.676202) (xy 80.661002 -227.723954)
			(xy 80.861154 -227.723954)
		)
		(stroke
			(width 0)
			(type solid)
		)
		(fill yes)
		(layer "In11.Cu")
		(net "M_F_CPU1_SA_DQS_DN<5>")
	)
	(gr_poly
		(pts
			(xy 80.861154 -227.27285) (xy 80.861154 -227.225098) (xy 80.661002 -227.225098) (xy 80.661002 -227.27285)
			(xy 80.761078 -227.372672)
		)
		(stroke
			(width 0)
			(type solid)
		)
		(fill yes)
		(layer "In11.Cu")
		(net "M_F_CPU1_SA_DQS_DN<0>")
	)
	(gr_poly
		(pts
			(xy 80.861154 -226.056444) (xy 80.761078 -225.956368) (xy 80.661002 -226.056444) (xy 80.661002 -226.100894)
			(xy 80.861154 -226.100894)
		)
		(stroke
			(width 0)
			(type solid)
		)
		(fill yes)
		(layer "In11.Cu")
		(net "M_F_CPU1_SA_DQ<1>")
	)
	(gr_poly
		(pts
			(xy 80.861154 -225.652584) (xy 80.861154 -225.608134) (xy 80.661002 -225.608134) (xy 80.661002 -225.652584)
			(xy 80.761078 -225.75266)
		)
		(stroke
			(width 0)
			(type solid)
		)
		(fill yes)
		(layer "In11.Cu")
		(net "M_F_CPU1_SA_DQ<2>")
	)
	(gr_poly
		(pts
			(xy 80.879696 -224.035366) (xy 80.916272 -223.898714) (xy 80.77962 -223.862138) (xy 80.741012 -223.884236)
			(xy 80.841088 -224.057464)
		)
		(stroke
			(width 0)
			(type solid)
		)
		(fill yes)
		(layer "In11.Cu")
		(net "M_F_CPU1_SA_DQ<0>")
	)
	(gr_poly
		(pts
			(xy 80.916526 -224.569782) (xy 80.87995 -224.43313) (xy 80.841342 -224.410778) (xy 80.74152 -224.584006)
			(xy 80.779874 -224.606358)
		)
		(stroke
			(width 0)
			(type solid)
		)
		(fill yes)
		(layer "In11.Cu")
		(net "M_F_CPU1_SA_DQ<0>")
	)
	(gr_poly
		(pts
			(xy 81.09077 -293.15918) (xy 81.052162 -293.137082) (xy 80.915764 -293.173658) (xy 80.95234 -293.31031)
			(xy 80.990694 -293.332408)
		)
		(stroke
			(width 0)
			(type solid)
		)
		(fill yes)
		(layer "In11.Cu")
		(net "M_F_CPU1_SB_DQ<29>")
	)
	(gr_poly
		(pts
			(xy 81.161128 -292.108128) (xy 81.061052 -292.008052) (xy 80.960976 -292.108128) (xy 80.960976 -292.152578)
			(xy 81.161128 -292.152578)
		)
		(stroke
			(width 0)
			(type solid)
		)
		(fill yes)
		(layer "In11.Cu")
		(net "M_F_CPU1_SB_DQ<28>")
	)
	(gr_poly
		(pts
			(xy 81.161128 -291.704522) (xy 81.161128 -291.65677) (xy 80.960976 -291.65677) (xy 80.960976 -291.704522)
			(xy 81.061052 -291.804344)
		)
		(stroke
			(width 0)
			(type solid)
		)
		(fill yes)
		(layer "In11.Cu")
		(net "M_F_CPU1_SB_DQS_DP<8>")
	)
	(gr_poly
		(pts
			(xy 81.161128 -290.487862) (xy 81.061052 -290.38804) (xy 80.960976 -290.487862) (xy 80.960976 -290.535614)
			(xy 81.161128 -290.535614)
		)
		(stroke
			(width 0)
			(type solid)
		)
		(fill yes)
		(layer "In11.Cu")
		(net "M_F_CPU1_SB_DQS_DP<3>")
	)
	(gr_poly
		(pts
			(xy 81.161128 -290.084256) (xy 81.161128 -290.039806) (xy 80.960976 -290.039806) (xy 80.960976 -290.084256)
			(xy 81.061052 -290.184332)
		)
		(stroke
			(width 0)
			(type solid)
		)
		(fill yes)
		(layer "In11.Cu")
		(net "M_F_CPU1_SB_DQ<27>")
	)
	(gr_poly
		(pts
			(xy 81.161128 -288.868104) (xy 81.061052 -288.768028) (xy 80.960976 -288.868104) (xy 80.960976 -288.912554)
			(xy 81.161128 -288.912554)
		)
		(stroke
			(width 0)
			(type solid)
		)
		(fill yes)
		(layer "In11.Cu")
		(net "M_F_CPU1_SB_DQ<24>")
	)
	(gr_poly
		(pts
			(xy 81.161128 -288.464498) (xy 81.161128 -288.420048) (xy 80.960976 -288.420048) (xy 80.960976 -288.464498)
			(xy 81.061052 -288.564574)
		)
		(stroke
			(width 0)
			(type solid)
		)
		(fill yes)
		(layer "In11.Cu")
		(net "M_F_CPU1_SB_DQ<23>")
	)
	(gr_poly
		(pts
			(xy 81.161128 -287.248092) (xy 81.061052 -287.148016) (xy 80.960976 -287.248092) (xy 80.960976 -287.292542)
			(xy 81.161128 -287.292542)
		)
		(stroke
			(width 0)
			(type solid)
		)
		(fill yes)
		(layer "In11.Cu")
		(net "M_F_CPU1_SB_DQ<20>")
	)
	(gr_poly
		(pts
			(xy 81.161128 -286.844486) (xy 81.161128 -286.796734) (xy 80.960976 -286.796734) (xy 80.960976 -286.844486)
			(xy 81.061052 -286.944562)
		)
		(stroke
			(width 0)
			(type solid)
		)
		(fill yes)
		(layer "In11.Cu")
		(net "M_F_CPU1_SB_DQS_DP<7>")
	)
	(gr_poly
		(pts
			(xy 81.161128 -285.62808) (xy 81.061052 -285.528258) (xy 80.960976 -285.62808) (xy 80.960976 -285.675832)
			(xy 81.161128 -285.675832)
		)
		(stroke
			(width 0)
			(type solid)
		)
		(fill yes)
		(layer "In11.Cu")
		(net "M_F_CPU1_SB_DQS_DP<2>")
	)
	(gr_poly
		(pts
			(xy 81.161128 -285.224474) (xy 81.161128 -285.180024) (xy 80.960976 -285.180024) (xy 80.960976 -285.224474)
			(xy 81.061052 -285.32455)
		)
		(stroke
			(width 0)
			(type solid)
		)
		(fill yes)
		(layer "In11.Cu")
		(net "M_F_CPU1_SB_DQ<19>")
	)
	(gr_poly
		(pts
			(xy 81.161128 -284.008322) (xy 81.061052 -283.908246) (xy 80.960976 -284.008322) (xy 80.960976 -284.052772)
			(xy 81.161128 -284.052772)
		)
		(stroke
			(width 0)
			(type solid)
		)
		(fill yes)
		(layer "In11.Cu")
		(net "M_F_CPU1_SB_DQ<16>")
	)
	(gr_poly
		(pts
			(xy 81.161128 -283.604462) (xy 81.161128 -283.560012) (xy 80.960976 -283.560012) (xy 80.960976 -283.604462)
			(xy 81.061052 -283.704538)
		)
		(stroke
			(width 0)
			(type solid)
		)
		(fill yes)
		(layer "In11.Cu")
		(net "M_F_CPU1_SB_DQ<15>")
	)
	(gr_poly
		(pts
			(xy 81.161128 -282.38831) (xy 81.061052 -282.288234) (xy 80.960976 -282.38831) (xy 80.960976 -282.43276)
			(xy 81.161128 -282.43276)
		)
		(stroke
			(width 0)
			(type solid)
		)
		(fill yes)
		(layer "In11.Cu")
		(net "M_F_CPU1_SB_DQ<12>")
	)
	(gr_poly
		(pts
			(xy 81.161128 -281.984704) (xy 81.161128 -281.936952) (xy 80.960976 -281.936952) (xy 80.960976 -281.984704)
			(xy 81.061052 -282.084526)
		)
		(stroke
			(width 0)
			(type solid)
		)
		(fill yes)
		(layer "In11.Cu")
		(net "M_F_CPU1_SB_DQS_DP<6>")
	)
	(gr_poly
		(pts
			(xy 81.161128 -280.768044) (xy 81.061052 -280.668222) (xy 80.960976 -280.768044) (xy 80.960976 -280.815796)
			(xy 81.161128 -280.815796)
		)
		(stroke
			(width 0)
			(type solid)
		)
		(fill yes)
		(layer "In11.Cu")
		(net "M_F_CPU1_SB_DQS_DP<1>")
	)
	(gr_poly
		(pts
			(xy 81.161128 -280.364438) (xy 81.161128 -280.319988) (xy 80.960976 -280.319988) (xy 80.960976 -280.364438)
			(xy 81.061052 -280.464514)
		)
		(stroke
			(width 0)
			(type solid)
		)
		(fill yes)
		(layer "In11.Cu")
		(net "M_F_CPU1_SB_DQ<11>")
	)
	(gr_poly
		(pts
			(xy 81.161128 -279.148286) (xy 81.061052 -279.04821) (xy 80.960976 -279.148286) (xy 80.960976 -279.192736)
			(xy 81.161128 -279.192736)
		)
		(stroke
			(width 0)
			(type solid)
		)
		(fill yes)
		(layer "In11.Cu")
		(net "M_F_CPU1_SB_DQ<8>")
	)
	(gr_poly
		(pts
			(xy 81.161128 -278.744426) (xy 81.161128 -278.699976) (xy 80.960976 -278.699976) (xy 80.960976 -278.744426)
			(xy 81.061052 -278.844502)
		)
		(stroke
			(width 0)
			(type solid)
		)
		(fill yes)
		(layer "In11.Cu")
		(net "M_F_CPU1_SB_DQ<7>")
	)
	(gr_poly
		(pts
			(xy 81.161128 -277.528274) (xy 81.061052 -277.428198) (xy 80.960976 -277.528274) (xy 80.960976 -277.572724)
			(xy 81.161128 -277.572724)
		)
		(stroke
			(width 0)
			(type solid)
		)
		(fill yes)
		(layer "In11.Cu")
		(net "M_F_CPU1_SB_DQ<4>")
	)
	(gr_poly
		(pts
			(xy 81.161128 -277.124668) (xy 81.161128 -277.076916) (xy 80.960976 -277.076916) (xy 80.960976 -277.124668)
			(xy 81.061052 -277.22449)
		)
		(stroke
			(width 0)
			(type solid)
		)
		(fill yes)
		(layer "In11.Cu")
		(net "M_F_CPU1_SB_DQS_DP<5>")
	)
	(gr_poly
		(pts
			(xy 81.161128 -275.908008) (xy 81.061052 -275.808186) (xy 80.960976 -275.908008) (xy 80.960976 -275.95576)
			(xy 81.161128 -275.95576)
		)
		(stroke
			(width 0)
			(type solid)
		)
		(fill yes)
		(layer "In11.Cu")
		(net "M_F_CPU1_SB_DQS_DP<0>")
	)
	(gr_poly
		(pts
			(xy 81.161128 -275.504402) (xy 81.161128 -275.459952) (xy 80.960976 -275.459952) (xy 80.960976 -275.504402)
			(xy 81.061052 -275.604478)
		)
		(stroke
			(width 0)
			(type solid)
		)
		(fill yes)
		(layer "In11.Cu")
		(net "M_F_CPU1_SB_DQ<3>")
	)
	(gr_poly
		(pts
			(xy 81.161128 -274.28825) (xy 81.061052 -274.188174) (xy 80.960976 -274.28825) (xy 80.960976 -274.3327)
			(xy 81.161128 -274.3327)
		)
		(stroke
			(width 0)
			(type solid)
		)
		(fill yes)
		(layer "In11.Cu")
		(net "M_F_CPU1_SB_DQ<0>")
	)
	(gr_poly
		(pts
			(xy 81.161128 -273.88439) (xy 81.161128 -273.83994) (xy 80.960976 -273.83994) (xy 80.960976 -273.88439)
			(xy 81.061052 -273.984466)
		)
		(stroke
			(width 0)
			(type solid)
		)
		(fill yes)
		(layer "In11.Cu")
		(net "M_F_CPU1_SB_CB<3>")
	)
	(gr_poly
		(pts
			(xy 81.161128 -272.668238) (xy 81.061052 -272.568162) (xy 80.960976 -272.668238) (xy 80.960976 -272.712688)
			(xy 81.161128 -272.712688)
		)
		(stroke
			(width 0)
			(type solid)
		)
		(fill yes)
		(layer "In11.Cu")
		(net "M_F_CPU1_SB_CB<0>")
	)
	(gr_poly
		(pts
			(xy 81.161128 -272.264632) (xy 81.161128 -272.21688) (xy 80.960976 -272.21688) (xy 80.960976 -272.264632)
			(xy 81.061052 -272.364454)
		)
		(stroke
			(width 0)
			(type solid)
		)
		(fill yes)
		(layer "In11.Cu")
		(net "M_F_CPU1_SB_DQS_DP<4>")
	)
	(gr_poly
		(pts
			(xy 81.161128 -271.047972) (xy 81.061052 -270.94815) (xy 80.960976 -271.047972) (xy 80.960976 -271.095724)
			(xy 81.161128 -271.095724)
		)
		(stroke
			(width 0)
			(type solid)
		)
		(fill yes)
		(layer "In11.Cu")
		(net "M_F_CPU1_SB_DQS_DP<9>")
	)
	(gr_poly
		(pts
			(xy 81.161128 -270.644366) (xy 81.161128 -270.599916) (xy 80.960976 -270.599916) (xy 80.960976 -270.644366)
			(xy 81.061052 -270.744442)
		)
		(stroke
			(width 0)
			(type solid)
		)
		(fill yes)
		(layer "In11.Cu")
		(net "M_F_CPU1_SB_CB<7>")
	)
	(gr_poly
		(pts
			(xy 81.161128 -269.428214) (xy 81.061052 -269.328138) (xy 80.960976 -269.428214) (xy 80.960976 -269.472664)
			(xy 81.161128 -269.472664)
		)
		(stroke
			(width 0)
			(type solid)
		)
		(fill yes)
		(layer "In11.Cu")
		(net "M_F_CPU1_SB_CB<4>")
	)
	(gr_poly
		(pts
			(xy 81.161128 -267.808202) (xy 81.061052 -267.708126) (xy 80.960976 -267.808202) (xy 80.960976 -267.852652)
			(xy 81.161128 -267.852652)
		)
		(stroke
			(width 0)
			(type solid)
		)
		(fill yes)
		(layer "In11.Cu")
		(net "M_F_CPU1_SB_RSP<0>")
	)
	(gr_poly
		(pts
			(xy 81.161128 -265.78433) (xy 81.161128 -265.73988) (xy 80.960976 -265.73988) (xy 80.960976 -265.78433)
			(xy 81.061052 -265.884406)
		)
		(stroke
			(width 0)
			(type solid)
		)
		(fill yes)
		(layer "In11.Cu")
		(net "M_F_CPU1_SB_CS_N<0>")
	)
	(gr_poly
		(pts
			(xy 81.161128 -264.568178) (xy 81.061052 -264.468102) (xy 80.960976 -264.568178) (xy 80.960976 -264.612628)
			(xy 81.161128 -264.612628)
		)
		(stroke
			(width 0)
			(type solid)
		)
		(fill yes)
		(layer "In11.Cu")
		(net "M_F_CPU1_SB_CA<6>")
	)
	(gr_poly
		(pts
			(xy 81.161128 -264.164318) (xy 81.161128 -264.119868) (xy 80.960976 -264.119868) (xy 80.960976 -264.164318)
			(xy 81.061052 -264.264394)
		)
		(stroke
			(width 0)
			(type solid)
		)
		(fill yes)
		(layer "In11.Cu")
		(net "M_F_CPU1_SB_CA<5>")
	)
	(gr_poly
		(pts
			(xy 81.161128 -262.948166) (xy 81.061052 -262.84809) (xy 80.960976 -262.948166) (xy 80.960976 -262.992616)
			(xy 81.161128 -262.992616)
		)
		(stroke
			(width 0)
			(type solid)
		)
		(fill yes)
		(layer "In11.Cu")
		(net "M_F_CPU1_SB_CA<2>")
	)
	(gr_poly
		(pts
			(xy 81.161128 -262.544306) (xy 81.161128 -262.499856) (xy 80.960976 -262.499856) (xy 80.960976 -262.544306)
			(xy 81.061052 -262.644382)
		)
		(stroke
			(width 0)
			(type solid)
		)
		(fill yes)
		(layer "In11.Cu")
		(net "M_F_CPU1_SB_CA<1>")
	)
	(gr_poly
		(pts
			(xy 81.20634 -295.498774) (xy 81.169764 -295.362122) (xy 81.13141 -295.340024) (xy 81.031334 -295.513252)
			(xy 81.069942 -295.53535)
		)
		(stroke
			(width 0)
			(type solid)
		)
		(fill yes)
		(layer "In11.Cu")
		(net "M_F_CPU1_SB_DQ<31>")
	)
	(gr_poly
		(pts
			(xy 81.331054 -256.026158) (xy 81.230978 -255.926336) (xy 81.130902 -256.026158) (xy 81.130902 -256.07391)
			(xy 81.331054 -256.07391)
		)
		(stroke
			(width 0)
			(type solid)
		)
		(fill yes)
		(layer "In11.Cu")
		(net "M_F_CPU1_CLK_DP<0>")
	)
	(gr_poly
		(pts
			(xy 81.331054 -255.622552) (xy 81.331054 -255.578102) (xy 81.130902 -255.578102) (xy 81.130902 -255.622552)
			(xy 81.230978 -255.722628)
		)
		(stroke
			(width 0)
			(type solid)
		)
		(fill yes)
		(layer "In11.Cu")
		(net "M_F_CPU1_SA_PAR")
	)
	(gr_poly
		(pts
			(xy 81.331054 -254.4064) (xy 81.230978 -254.306324) (xy 81.130902 -254.4064) (xy 81.130902 -254.45085)
			(xy 81.331054 -254.45085)
		)
		(stroke
			(width 0)
			(type solid)
		)
		(fill yes)
		(layer "In11.Cu")
		(net "M_F_CPU1_SA_CA<4>")
	)
	(gr_poly
		(pts
			(xy 81.331054 -254.00254) (xy 81.331054 -253.95809) (xy 81.130902 -253.95809) (xy 81.130902 -254.00254)
			(xy 81.230978 -254.102616)
		)
		(stroke
			(width 0)
			(type solid)
		)
		(fill yes)
		(layer "In11.Cu")
		(net "M_F_CPU1_SA_CA<3>")
	)
	(gr_poly
		(pts
			(xy 81.331054 -252.786388) (xy 81.230978 -252.686312) (xy 81.130902 -252.786388) (xy 81.130902 -252.830838)
			(xy 81.331054 -252.830838)
		)
		(stroke
			(width 0)
			(type solid)
		)
		(fill yes)
		(layer "In11.Cu")
		(net "M_F_CPU1_SA_CA<0>")
	)
	(gr_poly
		(pts
			(xy 81.331054 -252.382528) (xy 81.331054 -252.338078) (xy 81.130902 -252.338078) (xy 81.130902 -252.382528)
			(xy 81.230978 -252.482604)
		)
		(stroke
			(width 0)
			(type solid)
		)
		(fill yes)
		(layer "In11.Cu")
		(net "M_F_CPU1_SA_CS_N<1>")
	)
	(gr_poly
		(pts
			(xy 81.331054 -250.762516) (xy 81.331054 -250.718066) (xy 81.130902 -250.718066) (xy 81.130902 -250.762516)
			(xy 81.230978 -250.862592)
		)
		(stroke
			(width 0)
			(type solid)
		)
		(fill yes)
		(layer "In11.Cu")
		(net "M_F_CPU1_RESET_N")
	)
	(gr_poly
		(pts
			(xy 81.331054 -249.142504) (xy 81.331054 -249.098054) (xy 81.130902 -249.098054) (xy 81.130902 -249.142504)
			(xy 81.230978 -249.24258)
		)
		(stroke
			(width 0)
			(type solid)
		)
		(fill yes)
		(layer "In11.Cu")
		(net "M_F_CPU1_SA_CB<7>")
	)
	(gr_poly
		(pts
			(xy 81.331054 -247.926352) (xy 81.230978 -247.826276) (xy 81.130902 -247.926352) (xy 81.130902 -247.970802)
			(xy 81.331054 -247.970802)
		)
		(stroke
			(width 0)
			(type solid)
		)
		(fill yes)
		(layer "In11.Cu")
		(net "M_F_CPU1_SA_CB<4>")
	)
	(gr_poly
		(pts
			(xy 81.331054 -247.522746) (xy 81.331054 -247.474994) (xy 81.130902 -247.474994) (xy 81.130902 -247.522746)
			(xy 81.230978 -247.622568)
		)
		(stroke
			(width 0)
			(type solid)
		)
		(fill yes)
		(layer "In11.Cu")
		(net "M_F_CPU1_SA_DQS_DP<9>")
	)
	(gr_poly
		(pts
			(xy 81.331054 -246.306086) (xy 81.230978 -246.206264) (xy 81.130902 -246.306086) (xy 81.130902 -246.353838)
			(xy 81.331054 -246.353838)
		)
		(stroke
			(width 0)
			(type solid)
		)
		(fill yes)
		(layer "In11.Cu")
		(net "M_F_CPU1_SA_DQS_DP<4>")
	)
	(gr_poly
		(pts
			(xy 81.331054 -245.90248) (xy 81.331054 -245.85803) (xy 81.130902 -245.85803) (xy 81.130902 -245.90248)
			(xy 81.230978 -246.002556)
		)
		(stroke
			(width 0)
			(type solid)
		)
		(fill yes)
		(layer "In11.Cu")
		(net "M_F_CPU1_SA_CB<3>")
	)
	(gr_poly
		(pts
			(xy 81.331054 -244.686328) (xy 81.230978 -244.586252) (xy 81.130902 -244.686328) (xy 81.130902 -244.730778)
			(xy 81.331054 -244.730778)
		)
		(stroke
			(width 0)
			(type solid)
		)
		(fill yes)
		(layer "In11.Cu")
		(net "M_F_CPU1_SA_CB<0>")
	)
	(gr_poly
		(pts
			(xy 81.331054 -244.282468) (xy 81.331054 -244.238018) (xy 81.130902 -244.238018) (xy 81.130902 -244.282468)
			(xy 81.230978 -244.382544)
		)
		(stroke
			(width 0)
			(type solid)
		)
		(fill yes)
		(layer "In11.Cu")
		(net "M_F_CPU1_SA_DQ<31>")
	)
	(gr_poly
		(pts
			(xy 81.331054 -243.066316) (xy 81.230978 -242.96624) (xy 81.130902 -243.066316) (xy 81.130902 -243.110766)
			(xy 81.331054 -243.110766)
		)
		(stroke
			(width 0)
			(type solid)
		)
		(fill yes)
		(layer "In11.Cu")
		(net "M_F_CPU1_SA_DQ<28>")
	)
	(gr_poly
		(pts
			(xy 81.331054 -242.66271) (xy 81.331054 -242.614958) (xy 81.130902 -242.614958) (xy 81.130902 -242.66271)
			(xy 81.230978 -242.762532)
		)
		(stroke
			(width 0)
			(type solid)
		)
		(fill yes)
		(layer "In11.Cu")
		(net "M_F_CPU1_SA_DQS_DP<8>")
	)
	(gr_poly
		(pts
			(xy 81.331054 -241.44605) (xy 81.230978 -241.346228) (xy 81.130902 -241.44605) (xy 81.130902 -241.493802)
			(xy 81.331054 -241.493802)
		)
		(stroke
			(width 0)
			(type solid)
		)
		(fill yes)
		(layer "In11.Cu")
		(net "M_F_CPU1_SA_DQS_DP<3>")
	)
	(gr_poly
		(pts
			(xy 81.331054 -241.042444) (xy 81.331054 -240.997994) (xy 81.130902 -240.997994) (xy 81.130902 -241.042444)
			(xy 81.230978 -241.14252)
		)
		(stroke
			(width 0)
			(type solid)
		)
		(fill yes)
		(layer "In11.Cu")
		(net "M_F_CPU1_SA_DQ<27>")
	)
	(gr_poly
		(pts
			(xy 81.331054 -239.826292) (xy 81.230978 -239.726216) (xy 81.130902 -239.826292) (xy 81.130902 -239.870742)
			(xy 81.331054 -239.870742)
		)
		(stroke
			(width 0)
			(type solid)
		)
		(fill yes)
		(layer "In11.Cu")
		(net "M_F_CPU1_SA_DQ<24>")
	)
	(gr_poly
		(pts
			(xy 81.331054 -239.422432) (xy 81.331054 -239.377982) (xy 81.130902 -239.377982) (xy 81.130902 -239.422432)
			(xy 81.230978 -239.522508)
		)
		(stroke
			(width 0)
			(type solid)
		)
		(fill yes)
		(layer "In11.Cu")
		(net "M_F_CPU1_SA_DQ<23>")
	)
	(gr_poly
		(pts
			(xy 81.331054 -238.20628) (xy 81.230978 -238.106204) (xy 81.130902 -238.20628) (xy 81.130902 -238.25073)
			(xy 81.331054 -238.25073)
		)
		(stroke
			(width 0)
			(type solid)
		)
		(fill yes)
		(layer "In11.Cu")
		(net "M_F_CPU1_SA_DQ<20>")
	)
	(gr_poly
		(pts
			(xy 81.331054 -237.802674) (xy 81.331054 -237.754922) (xy 81.130902 -237.754922) (xy 81.130902 -237.802674)
			(xy 81.230978 -237.902496)
		)
		(stroke
			(width 0)
			(type solid)
		)
		(fill yes)
		(layer "In11.Cu")
		(net "M_F_CPU1_SA_DQS_DP<7>")
	)
	(gr_poly
		(pts
			(xy 81.331054 -236.586014) (xy 81.230978 -236.486192) (xy 81.130902 -236.586014) (xy 81.130902 -236.633766)
			(xy 81.331054 -236.633766)
		)
		(stroke
			(width 0)
			(type solid)
		)
		(fill yes)
		(layer "In11.Cu")
		(net "M_F_CPU1_SA_DQS_DP<2>")
	)
	(gr_poly
		(pts
			(xy 81.331054 -236.182408) (xy 81.331054 -236.137958) (xy 81.130902 -236.137958) (xy 81.130902 -236.182408)
			(xy 81.230978 -236.282484)
		)
		(stroke
			(width 0)
			(type solid)
		)
		(fill yes)
		(layer "In11.Cu")
		(net "M_F_CPU1_SA_DQ<19>")
	)
	(gr_poly
		(pts
			(xy 81.331054 -234.966256) (xy 81.230978 -234.86618) (xy 81.130902 -234.966256) (xy 81.130902 -235.010706)
			(xy 81.331054 -235.010706)
		)
		(stroke
			(width 0)
			(type solid)
		)
		(fill yes)
		(layer "In11.Cu")
		(net "M_F_CPU1_SA_DQ<16>")
	)
	(gr_poly
		(pts
			(xy 81.331054 -234.562396) (xy 81.331054 -234.517946) (xy 81.130902 -234.517946) (xy 81.130902 -234.562396)
			(xy 81.230978 -234.662472)
		)
		(stroke
			(width 0)
			(type solid)
		)
		(fill yes)
		(layer "In11.Cu")
		(net "M_F_CPU1_SA_DQ<15>")
	)
	(gr_poly
		(pts
			(xy 81.331054 -233.346244) (xy 81.230978 -233.246168) (xy 81.130902 -233.346244) (xy 81.130902 -233.390694)
			(xy 81.331054 -233.390694)
		)
		(stroke
			(width 0)
			(type solid)
		)
		(fill yes)
		(layer "In11.Cu")
		(net "M_F_CPU1_SA_DQ<12>")
	)
	(gr_poly
		(pts
			(xy 81.331054 -232.942638) (xy 81.331054 -232.894886) (xy 81.130902 -232.894886) (xy 81.130902 -232.942638)
			(xy 81.230978 -233.04246)
		)
		(stroke
			(width 0)
			(type solid)
		)
		(fill yes)
		(layer "In11.Cu")
		(net "M_F_CPU1_SA_DQS_DP<6>")
	)
	(gr_poly
		(pts
			(xy 81.331054 -231.725978) (xy 81.230978 -231.626156) (xy 81.130902 -231.725978) (xy 81.130902 -231.77373)
			(xy 81.331054 -231.77373)
		)
		(stroke
			(width 0)
			(type solid)
		)
		(fill yes)
		(layer "In11.Cu")
		(net "M_F_CPU1_SA_DQS_DP<1>")
	)
	(gr_poly
		(pts
			(xy 81.331054 -231.322626) (xy 81.331054 -231.278176) (xy 81.130902 -231.278176) (xy 81.130902 -231.322626)
			(xy 81.230978 -231.422702)
		)
		(stroke
			(width 0)
			(type solid)
		)
		(fill yes)
		(layer "In11.Cu")
		(net "M_F_CPU1_SA_DQ<11>")
	)
	(gr_poly
		(pts
			(xy 81.331054 -230.10622) (xy 81.230978 -230.006144) (xy 81.130902 -230.10622) (xy 81.130902 -230.15067)
			(xy 81.331054 -230.15067)
		)
		(stroke
			(width 0)
			(type solid)
		)
		(fill yes)
		(layer "In11.Cu")
		(net "M_F_CPU1_SA_DQ<8>")
	)
	(gr_poly
		(pts
			(xy 81.331054 -229.702614) (xy 81.331054 -229.658164) (xy 81.130902 -229.658164) (xy 81.130902 -229.702614)
			(xy 81.230978 -229.80269)
		)
		(stroke
			(width 0)
			(type solid)
		)
		(fill yes)
		(layer "In11.Cu")
		(net "M_F_CPU1_SA_DQ<7>")
	)
	(gr_poly
		(pts
			(xy 81.331054 -228.486462) (xy 81.230978 -228.386386) (xy 81.130902 -228.486462) (xy 81.130902 -228.530912)
			(xy 81.331054 -228.530912)
		)
		(stroke
			(width 0)
			(type solid)
		)
		(fill yes)
		(layer "In11.Cu")
		(net "M_F_CPU1_SA_DQ<4>")
	)
	(gr_poly
		(pts
			(xy 81.331054 -228.082856) (xy 81.331054 -228.035104) (xy 81.130902 -228.035104) (xy 81.130902 -228.082856)
			(xy 81.230978 -228.182678)
		)
		(stroke
			(width 0)
			(type solid)
		)
		(fill yes)
		(layer "In11.Cu")
		(net "M_F_CPU1_SA_DQS_DP<5>")
	)
	(gr_poly
		(pts
			(xy 81.331054 -226.866196) (xy 81.230978 -226.766374) (xy 81.130902 -226.866196) (xy 81.130902 -226.913948)
			(xy 81.331054 -226.913948)
		)
		(stroke
			(width 0)
			(type solid)
		)
		(fill yes)
		(layer "In11.Cu")
		(net "M_F_CPU1_SA_DQS_DP<0>")
	)
	(gr_poly
		(pts
			(xy 81.331054 -226.46259) (xy 81.331054 -226.41814) (xy 81.130902 -226.41814) (xy 81.130902 -226.46259)
			(xy 81.230978 -226.562666)
		)
		(stroke
			(width 0)
			(type solid)
		)
		(fill yes)
		(layer "In11.Cu")
		(net "M_F_CPU1_SA_DQ<3>")
	)
	(gr_poly
		(pts
			(xy 81.331054 -225.246438) (xy 81.230978 -225.146362) (xy 81.130902 -225.246438) (xy 81.130902 -225.290888)
			(xy 81.331054 -225.290888)
		)
		(stroke
			(width 0)
			(type solid)
		)
		(fill yes)
		(layer "In11.Cu")
		(net "M_F_CPU1_SA_DQ<0>")
	)
	(gr_poly
		(pts
			(xy 81.631028 -292.514274) (xy 81.631028 -292.469824) (xy 81.430876 -292.469824) (xy 81.430876 -292.514274)
			(xy 81.530952 -292.61435)
		)
		(stroke
			(width 0)
			(type solid)
		)
		(fill yes)
		(layer "In11.Cu")
		(net "M_F_CPU1_SB_DQ<30>")
	)
	(gr_poly
		(pts
			(xy 81.631028 -291.297868) (xy 81.530952 -291.198046) (xy 81.430876 -291.297868) (xy 81.430876 -291.34562)
			(xy 81.631028 -291.34562)
		)
		(stroke
			(width 0)
			(type solid)
		)
		(fill yes)
		(layer "In11.Cu")
		(net "M_F_CPU1_SB_DQS_DN<8>")
	)
	(gr_poly
		(pts
			(xy 81.631028 -290.894516) (xy 81.631028 -290.846764) (xy 81.430876 -290.846764) (xy 81.430876 -290.894516)
			(xy 81.530952 -290.994338)
		)
		(stroke
			(width 0)
			(type solid)
		)
		(fill yes)
		(layer "In11.Cu")
		(net "M_F_CPU1_SB_DQS_DN<3>")
	)
	(gr_poly
		(pts
			(xy 81.631028 -289.67811) (xy 81.530952 -289.578034) (xy 81.430876 -289.67811) (xy 81.430876 -289.72256)
			(xy 81.631028 -289.72256)
		)
		(stroke
			(width 0)
			(type solid)
		)
		(fill yes)
		(layer "In11.Cu")
		(net "M_F_CPU1_SB_DQ<25>")
	)
	(gr_poly
		(pts
			(xy 81.631028 -289.27425) (xy 81.631028 -289.2298) (xy 81.430876 -289.2298) (xy 81.430876 -289.27425)
			(xy 81.530952 -289.374326)
		)
		(stroke
			(width 0)
			(type solid)
		)
		(fill yes)
		(layer "In11.Cu")
		(net "M_F_CPU1_SB_DQ<26>")
	)
	(gr_poly
		(pts
			(xy 81.631028 -288.058098) (xy 81.530952 -287.958022) (xy 81.430876 -288.058098) (xy 81.430876 -288.102548)
			(xy 81.631028 -288.102548)
		)
		(stroke
			(width 0)
			(type solid)
		)
		(fill yes)
		(layer "In11.Cu")
		(net "M_F_CPU1_SB_DQ<21>")
	)
	(gr_poly
		(pts
			(xy 81.631028 -287.654492) (xy 81.631028 -287.610042) (xy 81.430876 -287.610042) (xy 81.430876 -287.654492)
			(xy 81.530952 -287.754568)
		)
		(stroke
			(width 0)
			(type solid)
		)
		(fill yes)
		(layer "In11.Cu")
		(net "M_F_CPU1_SB_DQ<22>")
	)
	(gr_poly
		(pts
			(xy 81.631028 -286.438086) (xy 81.530952 -286.33801) (xy 81.430876 -286.438086) (xy 81.430876 -286.485838)
			(xy 81.631028 -286.485838)
		)
		(stroke
			(width 0)
			(type solid)
		)
		(fill yes)
		(layer "In11.Cu")
		(net "M_F_CPU1_SB_DQS_DN<7>")
	)
	(gr_poly
		(pts
			(xy 81.631028 -286.034734) (xy 81.631028 -285.986982) (xy 81.430876 -285.986982) (xy 81.430876 -286.034734)
			(xy 81.530952 -286.134556)
		)
		(stroke
			(width 0)
			(type solid)
		)
		(fill yes)
		(layer "In11.Cu")
		(net "M_F_CPU1_SB_DQS_DN<2>")
	)
	(gr_poly
		(pts
			(xy 81.631028 -284.818328) (xy 81.530952 -284.718252) (xy 81.430876 -284.818328) (xy 81.430876 -284.862778)
			(xy 81.631028 -284.862778)
		)
		(stroke
			(width 0)
			(type solid)
		)
		(fill yes)
		(layer "In11.Cu")
		(net "M_F_CPU1_SB_DQ<17>")
	)
	(gr_poly
		(pts
			(xy 81.631028 -284.414468) (xy 81.631028 -284.370018) (xy 81.430876 -284.370018) (xy 81.430876 -284.414468)
			(xy 81.530952 -284.514544)
		)
		(stroke
			(width 0)
			(type solid)
		)
		(fill yes)
		(layer "In11.Cu")
		(net "M_F_CPU1_SB_DQ<18>")
	)
	(gr_poly
		(pts
			(xy 81.631028 -283.198316) (xy 81.530952 -283.09824) (xy 81.430876 -283.198316) (xy 81.430876 -283.242766)
			(xy 81.631028 -283.242766)
		)
		(stroke
			(width 0)
			(type solid)
		)
		(fill yes)
		(layer "In11.Cu")
		(net "M_F_CPU1_SB_DQ<13>")
	)
	(gr_poly
		(pts
			(xy 81.631028 -282.794456) (xy 81.631028 -282.750006) (xy 81.430876 -282.750006) (xy 81.430876 -282.794456)
			(xy 81.530952 -282.894532)
		)
		(stroke
			(width 0)
			(type solid)
		)
		(fill yes)
		(layer "In11.Cu")
		(net "M_F_CPU1_SB_DQ<14>")
	)
	(gr_poly
		(pts
			(xy 81.631028 -281.57805) (xy 81.530952 -281.478228) (xy 81.430876 -281.57805) (xy 81.430876 -281.625802)
			(xy 81.631028 -281.625802)
		)
		(stroke
			(width 0)
			(type solid)
		)
		(fill yes)
		(layer "In11.Cu")
		(net "M_F_CPU1_SB_DQS_DN<6>")
	)
	(gr_poly
		(pts
			(xy 81.631028 -281.174698) (xy 81.631028 -281.126946) (xy 81.430876 -281.126946) (xy 81.430876 -281.174698)
			(xy 81.530952 -281.27452)
		)
		(stroke
			(width 0)
			(type solid)
		)
		(fill yes)
		(layer "In11.Cu")
		(net "M_F_CPU1_SB_DQS_DN<1>")
	)
	(gr_poly
		(pts
			(xy 81.631028 -279.958292) (xy 81.530952 -279.858216) (xy 81.430876 -279.958292) (xy 81.430876 -280.002742)
			(xy 81.631028 -280.002742)
		)
		(stroke
			(width 0)
			(type solid)
		)
		(fill yes)
		(layer "In11.Cu")
		(net "M_F_CPU1_SB_DQ<9>")
	)
	(gr_poly
		(pts
			(xy 81.631028 -279.554432) (xy 81.631028 -279.509982) (xy 81.430876 -279.509982) (xy 81.430876 -279.554432)
			(xy 81.530952 -279.654508)
		)
		(stroke
			(width 0)
			(type solid)
		)
		(fill yes)
		(layer "In11.Cu")
		(net "M_F_CPU1_SB_DQ<10>")
	)
	(gr_poly
		(pts
			(xy 81.631028 -278.33828) (xy 81.530952 -278.238204) (xy 81.430876 -278.33828) (xy 81.430876 -278.38273)
			(xy 81.631028 -278.38273)
		)
		(stroke
			(width 0)
			(type solid)
		)
		(fill yes)
		(layer "In11.Cu")
		(net "M_F_CPU1_SB_DQ<5>")
	)
	(gr_poly
		(pts
			(xy 81.631028 -277.93442) (xy 81.631028 -277.88997) (xy 81.430876 -277.88997) (xy 81.430876 -277.93442)
			(xy 81.530952 -278.034496)
		)
		(stroke
			(width 0)
			(type solid)
		)
		(fill yes)
		(layer "In11.Cu")
		(net "M_F_CPU1_SB_DQ<6>")
	)
	(gr_poly
		(pts
			(xy 81.631028 -276.718014) (xy 81.530952 -276.618192) (xy 81.430876 -276.718014) (xy 81.430876 -276.765766)
			(xy 81.631028 -276.765766)
		)
		(stroke
			(width 0)
			(type solid)
		)
		(fill yes)
		(layer "In11.Cu")
		(net "M_F_CPU1_SB_DQS_DN<5>")
	)
	(gr_poly
		(pts
			(xy 81.631028 -276.314662) (xy 81.631028 -276.26691) (xy 81.430876 -276.26691) (xy 81.430876 -276.314662)
			(xy 81.530952 -276.414484)
		)
		(stroke
			(width 0)
			(type solid)
		)
		(fill yes)
		(layer "In11.Cu")
		(net "M_F_CPU1_SB_DQS_DN<0>")
	)
	(gr_poly
		(pts
			(xy 81.631028 -275.098256) (xy 81.530952 -274.99818) (xy 81.430876 -275.098256) (xy 81.430876 -275.142706)
			(xy 81.631028 -275.142706)
		)
		(stroke
			(width 0)
			(type solid)
		)
		(fill yes)
		(layer "In11.Cu")
		(net "M_F_CPU1_SB_DQ<1>")
	)
	(gr_poly
		(pts
			(xy 81.631028 -274.694396) (xy 81.631028 -274.649946) (xy 81.430876 -274.649946) (xy 81.430876 -274.694396)
			(xy 81.530952 -274.794472)
		)
		(stroke
			(width 0)
			(type solid)
		)
		(fill yes)
		(layer "In11.Cu")
		(net "M_F_CPU1_SB_DQ<2>")
	)
	(gr_poly
		(pts
			(xy 81.631028 -273.478244) (xy 81.530952 -273.378168) (xy 81.430876 -273.478244) (xy 81.430876 -273.522694)
			(xy 81.631028 -273.522694)
		)
		(stroke
			(width 0)
			(type solid)
		)
		(fill yes)
		(layer "In11.Cu")
		(net "M_F_CPU1_SB_CB<1>")
	)
	(gr_poly
		(pts
			(xy 81.631028 -273.074384) (xy 81.631028 -273.029934) (xy 81.430876 -273.029934) (xy 81.430876 -273.074384)
			(xy 81.530952 -273.17446)
		)
		(stroke
			(width 0)
			(type solid)
		)
		(fill yes)
		(layer "In11.Cu")
		(net "M_F_CPU1_SB_CB<2>")
	)
	(gr_poly
		(pts
			(xy 81.631028 -271.857978) (xy 81.530952 -271.758156) (xy 81.430876 -271.857978) (xy 81.430876 -271.90573)
			(xy 81.631028 -271.90573)
		)
		(stroke
			(width 0)
			(type solid)
		)
		(fill yes)
		(layer "In11.Cu")
		(net "M_F_CPU1_SB_DQS_DN<4>")
	)
	(gr_poly
		(pts
			(xy 81.631028 -271.454626) (xy 81.631028 -271.406874) (xy 81.430876 -271.406874) (xy 81.430876 -271.454626)
			(xy 81.530952 -271.554448)
		)
		(stroke
			(width 0)
			(type solid)
		)
		(fill yes)
		(layer "In11.Cu")
		(net "M_F_CPU1_SB_DQS_DN<9>")
	)
	(gr_poly
		(pts
			(xy 81.631028 -270.23822) (xy 81.530952 -270.138144) (xy 81.430876 -270.23822) (xy 81.430876 -270.28267)
			(xy 81.631028 -270.28267)
		)
		(stroke
			(width 0)
			(type solid)
		)
		(fill yes)
		(layer "In11.Cu")
		(net "M_F_CPU1_SB_CB<5>")
	)
	(gr_poly
		(pts
			(xy 81.631028 -269.83436) (xy 81.631028 -269.78991) (xy 81.430876 -269.78991) (xy 81.430876 -269.83436)
			(xy 81.530952 -269.934436)
		)
		(stroke
			(width 0)
			(type solid)
		)
		(fill yes)
		(layer "In11.Cu")
		(net "M_F_CPU1_SB_CB<6>")
	)
	(gr_poly
		(pts
			(xy 81.631028 -266.594336) (xy 81.631028 -266.549886) (xy 81.430876 -266.549886) (xy 81.430876 -266.594336)
			(xy 81.530952 -266.694412)
		)
		(stroke
			(width 0)
			(type solid)
		)
		(fill yes)
		(layer "In11.Cu")
		(net "M_F_CPU1_SB_CS_N<1>")
	)
	(gr_poly
		(pts
			(xy 81.631028 -264.974324) (xy 81.631028 -264.929874) (xy 81.430876 -264.929874) (xy 81.430876 -264.974324)
			(xy 81.530952 -265.0744)
		)
		(stroke
			(width 0)
			(type solid)
		)
		(fill yes)
		(layer "In11.Cu")
		(net "M_F_CPU1_SB_PAR")
	)
	(gr_poly
		(pts
			(xy 81.631028 -263.758172) (xy 81.530952 -263.658096) (xy 81.430876 -263.758172) (xy 81.430876 -263.802622)
			(xy 81.631028 -263.802622)
		)
		(stroke
			(width 0)
			(type solid)
		)
		(fill yes)
		(layer "In11.Cu")
		(net "M_F_CPU1_SB_CA<4>")
	)
	(gr_poly
		(pts
			(xy 81.631028 -263.354312) (xy 81.631028 -263.309862) (xy 81.430876 -263.309862) (xy 81.430876 -263.354312)
			(xy 81.530952 -263.454388)
		)
		(stroke
			(width 0)
			(type solid)
		)
		(fill yes)
		(layer "In11.Cu")
		(net "M_F_CPU1_SB_CA<3>")
	)
	(gr_poly
		(pts
			(xy 81.631028 -262.13816) (xy 81.530952 -262.038084) (xy 81.430876 -262.13816) (xy 81.430876 -262.18261)
			(xy 81.631028 -262.18261)
		)
		(stroke
			(width 0)
			(type solid)
		)
		(fill yes)
		(layer "In11.Cu")
		(net "M_F_CPU1_SB_CA<0>")
	)
	(gr_poly
		(pts
			(xy 81.631282 -266.998196) (xy 81.531206 -266.89812) (xy 81.43113 -266.998196) (xy 81.43113 -267.042646)
			(xy 81.631282 -267.042646)
		)
		(stroke
			(width 0)
			(type solid)
		)
		(fill yes)
		(layer "In11.Cu")
		(net "M_F_CPU1_SA_RSP<0>")
	)
	(gr_poly
		(pts
			(xy 81.676494 -294.688768) (xy 81.639918 -294.552116) (xy 81.601564 -294.530018) (xy 81.501488 -294.703246)
			(xy 81.539842 -294.725344)
		)
		(stroke
			(width 0)
			(type solid)
		)
		(fill yes)
		(layer "In11.Cu")
		(net "M_F_CPU1_SB_DQ<31>")
	)
	(gr_poly
		(pts
			(xy 81.801208 -256.432812) (xy 81.801208 -256.38506) (xy 81.601056 -256.38506) (xy 81.601056 -256.432812)
			(xy 81.701132 -256.532634)
		)
		(stroke
			(width 0)
			(type solid)
		)
		(fill yes)
		(layer "In11.Cu")
		(net "M_F_CPU1_CLK_DN<0>")
	)
	(gr_poly
		(pts
			(xy 81.801208 -255.216406) (xy 81.701132 -255.11633) (xy 81.601056 -255.216406) (xy 81.601056 -255.260856)
			(xy 81.801208 -255.260856)
		)
		(stroke
			(width 0)
			(type solid)
		)
		(fill yes)
		(layer "In11.Cu")
		(net "M_F_CPU1_SA_CA<6>")
	)
	(gr_poly
		(pts
			(xy 81.801208 -254.812546) (xy 81.801208 -254.768096) (xy 81.601056 -254.768096) (xy 81.601056 -254.812546)
			(xy 81.701132 -254.912622)
		)
		(stroke
			(width 0)
			(type solid)
		)
		(fill yes)
		(layer "In11.Cu")
		(net "M_F_CPU1_SA_CA<5>")
	)
	(gr_poly
		(pts
			(xy 81.801208 -253.596394) (xy 81.701132 -253.496318) (xy 81.601056 -253.596394) (xy 81.601056 -253.640844)
			(xy 81.801208 -253.640844)
		)
		(stroke
			(width 0)
			(type solid)
		)
		(fill yes)
		(layer "In11.Cu")
		(net "M_F_CPU1_SA_CA<2>")
	)
	(gr_poly
		(pts
			(xy 81.801208 -253.192534) (xy 81.801208 -253.148084) (xy 81.601056 -253.148084) (xy 81.601056 -253.192534)
			(xy 81.701132 -253.29261)
		)
		(stroke
			(width 0)
			(type solid)
		)
		(fill yes)
		(layer "In11.Cu")
		(net "M_F_CPU1_SA_CA<1>")
	)
	(gr_poly
		(pts
			(xy 81.801208 -251.572522) (xy 81.801208 -251.528072) (xy 81.601056 -251.528072) (xy 81.601056 -251.572522)
			(xy 81.701132 -251.672598)
		)
		(stroke
			(width 0)
			(type solid)
		)
		(fill yes)
		(layer "In11.Cu")
		(net "M_F_CPU1_SA_CS_N<0>")
	)
	(gr_poly
		(pts
			(xy 81.801208 -250.35637) (xy 81.701132 -250.256294) (xy 81.601056 -250.35637) (xy 81.601056 -250.40082)
			(xy 81.801208 -250.40082)
		)
		(stroke
			(width 0)
			(type solid)
		)
		(fill yes)
		(layer "In11.Cu")
		(net "M_F_CPU1_ALERT_R_N")
	)
	(gr_poly
		(pts
			(xy 81.801208 -248.736358) (xy 81.701132 -248.636282) (xy 81.601056 -248.736358) (xy 81.601056 -248.780808)
			(xy 81.801208 -248.780808)
		)
		(stroke
			(width 0)
			(type solid)
		)
		(fill yes)
		(layer "In11.Cu")
		(net "M_F_CPU1_SA_CB<5>")
	)
	(gr_poly
		(pts
			(xy 81.801208 -248.332498) (xy 81.801208 -248.288048) (xy 81.601056 -248.288048) (xy 81.601056 -248.332498)
			(xy 81.701132 -248.432574)
		)
		(stroke
			(width 0)
			(type solid)
		)
		(fill yes)
		(layer "In11.Cu")
		(net "M_F_CPU1_SA_CB<6>")
	)
	(gr_poly
		(pts
			(xy 81.801208 -247.116092) (xy 81.701132 -247.01627) (xy 81.601056 -247.116092) (xy 81.601056 -247.163844)
			(xy 81.801208 -247.163844)
		)
		(stroke
			(width 0)
			(type solid)
		)
		(fill yes)
		(layer "In11.Cu")
		(net "M_F_CPU1_SA_DQS_DN<9>")
	)
	(gr_poly
		(pts
			(xy 81.801208 -246.71274) (xy 81.801208 -246.664988) (xy 81.601056 -246.664988) (xy 81.601056 -246.71274)
			(xy 81.701132 -246.812562)
		)
		(stroke
			(width 0)
			(type solid)
		)
		(fill yes)
		(layer "In11.Cu")
		(net "M_F_CPU1_SA_DQS_DN<4>")
	)
	(gr_poly
		(pts
			(xy 81.801208 -245.496334) (xy 81.701132 -245.396258) (xy 81.601056 -245.496334) (xy 81.601056 -245.540784)
			(xy 81.801208 -245.540784)
		)
		(stroke
			(width 0)
			(type solid)
		)
		(fill yes)
		(layer "In11.Cu")
		(net "M_F_CPU1_SA_CB<1>")
	)
	(gr_poly
		(pts
			(xy 81.801208 -245.092474) (xy 81.801208 -245.048024) (xy 81.601056 -245.048024) (xy 81.601056 -245.092474)
			(xy 81.701132 -245.19255)
		)
		(stroke
			(width 0)
			(type solid)
		)
		(fill yes)
		(layer "In11.Cu")
		(net "M_F_CPU1_SA_CB<2>")
	)
	(gr_poly
		(pts
			(xy 81.801208 -243.876322) (xy 81.701132 -243.776246) (xy 81.601056 -243.876322) (xy 81.601056 -243.920772)
			(xy 81.801208 -243.920772)
		)
		(stroke
			(width 0)
			(type solid)
		)
		(fill yes)
		(layer "In11.Cu")
		(net "M_F_CPU1_SA_DQ<29>")
	)
	(gr_poly
		(pts
			(xy 81.801208 -243.472462) (xy 81.801208 -243.428012) (xy 81.601056 -243.428012) (xy 81.601056 -243.472462)
			(xy 81.701132 -243.572538)
		)
		(stroke
			(width 0)
			(type solid)
		)
		(fill yes)
		(layer "In11.Cu")
		(net "M_F_CPU1_SA_DQ<30>")
	)
	(gr_poly
		(pts
			(xy 81.801208 -242.256056) (xy 81.701132 -242.156234) (xy 81.601056 -242.256056) (xy 81.601056 -242.303808)
			(xy 81.801208 -242.303808)
		)
		(stroke
			(width 0)
			(type solid)
		)
		(fill yes)
		(layer "In11.Cu")
		(net "M_F_CPU1_SA_DQS_DN<8>")
	)
	(gr_poly
		(pts
			(xy 81.801208 -241.852704) (xy 81.801208 -241.804952) (xy 81.601056 -241.804952) (xy 81.601056 -241.852704)
			(xy 81.701132 -241.952526)
		)
		(stroke
			(width 0)
			(type solid)
		)
		(fill yes)
		(layer "In11.Cu")
		(net "M_F_CPU1_SA_DQS_DN<3>")
	)
	(gr_poly
		(pts
			(xy 81.801208 -240.636298) (xy 81.701132 -240.536222) (xy 81.601056 -240.636298) (xy 81.601056 -240.680748)
			(xy 81.801208 -240.680748)
		)
		(stroke
			(width 0)
			(type solid)
		)
		(fill yes)
		(layer "In11.Cu")
		(net "M_F_CPU1_SA_DQ<25>")
	)
	(gr_poly
		(pts
			(xy 81.801208 -240.232438) (xy 81.801208 -240.187988) (xy 81.601056 -240.187988) (xy 81.601056 -240.232438)
			(xy 81.701132 -240.332514)
		)
		(stroke
			(width 0)
			(type solid)
		)
		(fill yes)
		(layer "In11.Cu")
		(net "M_F_CPU1_SA_DQ<26>")
	)
	(gr_poly
		(pts
			(xy 81.801208 -239.016286) (xy 81.701132 -238.91621) (xy 81.601056 -239.016286) (xy 81.601056 -239.060736)
			(xy 81.801208 -239.060736)
		)
		(stroke
			(width 0)
			(type solid)
		)
		(fill yes)
		(layer "In11.Cu")
		(net "M_F_CPU1_SA_DQ<21>")
	)
	(gr_poly
		(pts
			(xy 81.801208 -238.612426) (xy 81.801208 -238.567976) (xy 81.601056 -238.567976) (xy 81.601056 -238.612426)
			(xy 81.701132 -238.712502)
		)
		(stroke
			(width 0)
			(type solid)
		)
		(fill yes)
		(layer "In11.Cu")
		(net "M_F_CPU1_SA_DQ<22>")
	)
	(gr_poly
		(pts
			(xy 81.801208 -237.39602) (xy 81.701132 -237.296198) (xy 81.601056 -237.39602) (xy 81.601056 -237.443772)
			(xy 81.801208 -237.443772)
		)
		(stroke
			(width 0)
			(type solid)
		)
		(fill yes)
		(layer "In11.Cu")
		(net "M_F_CPU1_SA_DQS_DN<7>")
	)
	(gr_poly
		(pts
			(xy 81.801208 -236.992668) (xy 81.801208 -236.944916) (xy 81.601056 -236.944916) (xy 81.601056 -236.992668)
			(xy 81.701132 -237.09249)
		)
		(stroke
			(width 0)
			(type solid)
		)
		(fill yes)
		(layer "In11.Cu")
		(net "M_F_CPU1_SA_DQS_DN<2>")
	)
	(gr_poly
		(pts
			(xy 81.801208 -235.776262) (xy 81.701132 -235.676186) (xy 81.601056 -235.776262) (xy 81.601056 -235.820712)
			(xy 81.801208 -235.820712)
		)
		(stroke
			(width 0)
			(type solid)
		)
		(fill yes)
		(layer "In11.Cu")
		(net "M_F_CPU1_SA_DQ<17>")
	)
	(gr_poly
		(pts
			(xy 81.801208 -235.372402) (xy 81.801208 -235.327952) (xy 81.601056 -235.327952) (xy 81.601056 -235.372402)
			(xy 81.701132 -235.472478)
		)
		(stroke
			(width 0)
			(type solid)
		)
		(fill yes)
		(layer "In11.Cu")
		(net "M_F_CPU1_SA_DQ<18>")
	)
	(gr_poly
		(pts
			(xy 81.801208 -234.15625) (xy 81.701132 -234.056174) (xy 81.601056 -234.15625) (xy 81.601056 -234.2007)
			(xy 81.801208 -234.2007)
		)
		(stroke
			(width 0)
			(type solid)
		)
		(fill yes)
		(layer "In11.Cu")
		(net "M_F_CPU1_SA_DQ<13>")
	)
	(gr_poly
		(pts
			(xy 81.801208 -233.75239) (xy 81.801208 -233.70794) (xy 81.601056 -233.70794) (xy 81.601056 -233.75239)
			(xy 81.701132 -233.852466)
		)
		(stroke
			(width 0)
			(type solid)
		)
		(fill yes)
		(layer "In11.Cu")
		(net "M_F_CPU1_SA_DQ<14>")
	)
	(gr_poly
		(pts
			(xy 81.801208 -232.535984) (xy 81.701132 -232.436162) (xy 81.601056 -232.535984) (xy 81.601056 -232.583736)
			(xy 81.801208 -232.583736)
		)
		(stroke
			(width 0)
			(type solid)
		)
		(fill yes)
		(layer "In11.Cu")
		(net "M_F_CPU1_SA_DQS_DN<6>")
	)
	(gr_poly
		(pts
			(xy 81.801208 -232.132632) (xy 81.801208 -232.08488) (xy 81.601056 -232.08488) (xy 81.601056 -232.132632)
			(xy 81.701132 -232.232454)
		)
		(stroke
			(width 0)
			(type solid)
		)
		(fill yes)
		(layer "In11.Cu")
		(net "M_F_CPU1_SA_DQS_DN<1>")
	)
	(gr_poly
		(pts
			(xy 81.801208 -230.916226) (xy 81.701132 -230.81615) (xy 81.601056 -230.916226) (xy 81.601056 -230.960676)
			(xy 81.801208 -230.960676)
		)
		(stroke
			(width 0)
			(type solid)
		)
		(fill yes)
		(layer "In11.Cu")
		(net "M_F_CPU1_SA_DQ<9>")
	)
	(gr_poly
		(pts
			(xy 81.801208 -230.51262) (xy 81.801208 -230.46817) (xy 81.601056 -230.46817) (xy 81.601056 -230.51262)
			(xy 81.701132 -230.612696)
		)
		(stroke
			(width 0)
			(type solid)
		)
		(fill yes)
		(layer "In11.Cu")
		(net "M_F_CPU1_SA_DQ<10>")
	)
	(gr_poly
		(pts
			(xy 81.801208 -229.296214) (xy 81.701132 -229.196138) (xy 81.601056 -229.296214) (xy 81.601056 -229.340664)
			(xy 81.801208 -229.340664)
		)
		(stroke
			(width 0)
			(type solid)
		)
		(fill yes)
		(layer "In11.Cu")
		(net "M_F_CPU1_SA_DQ<5>")
	)
	(gr_poly
		(pts
			(xy 81.801208 -228.892608) (xy 81.801208 -228.848158) (xy 81.601056 -228.848158) (xy 81.601056 -228.892608)
			(xy 81.701132 -228.992684)
		)
		(stroke
			(width 0)
			(type solid)
		)
		(fill yes)
		(layer "In11.Cu")
		(net "M_F_CPU1_SA_DQ<6>")
	)
	(gr_poly
		(pts
			(xy 81.801208 -227.676202) (xy 81.701132 -227.57638) (xy 81.601056 -227.676202) (xy 81.601056 -227.723954)
			(xy 81.801208 -227.723954)
		)
		(stroke
			(width 0)
			(type solid)
		)
		(fill yes)
		(layer "In11.Cu")
		(net "M_F_CPU1_SA_DQS_DN<5>")
	)
	(gr_poly
		(pts
			(xy 81.801208 -227.27285) (xy 81.801208 -227.225098) (xy 81.601056 -227.225098) (xy 81.601056 -227.27285)
			(xy 81.701132 -227.372672)
		)
		(stroke
			(width 0)
			(type solid)
		)
		(fill yes)
		(layer "In11.Cu")
		(net "M_F_CPU1_SA_DQS_DN<0>")
	)
	(gr_poly
		(pts
			(xy 81.801208 -226.056444) (xy 81.701132 -225.956368) (xy 81.601056 -226.056444) (xy 81.601056 -226.100894)
			(xy 81.801208 -226.100894)
		)
		(stroke
			(width 0)
			(type solid)
		)
		(fill yes)
		(layer "In11.Cu")
		(net "M_F_CPU1_SA_DQ<1>")
	)
	(gr_poly
		(pts
			(xy 81.801208 -225.652584) (xy 81.801208 -225.608134) (xy 81.601056 -225.608134) (xy 81.601056 -225.652584)
			(xy 81.701132 -225.75266)
		)
		(stroke
			(width 0)
			(type solid)
		)
		(fill yes)
		(layer "In11.Cu")
		(net "M_F_CPU1_SA_DQ<2>")
	)
	(gr_poly
		(pts
			(xy 82.101182 -292.108128) (xy 82.001106 -292.008052) (xy 81.90103 -292.108128) (xy 81.90103 -292.152578)
			(xy 82.101182 -292.152578)
		)
		(stroke
			(width 0)
			(type solid)
		)
		(fill yes)
		(layer "In11.Cu")
		(net "M_F_CPU1_SB_DQ<28>")
	)
	(gr_poly
		(pts
			(xy 82.101182 -291.704522) (xy 82.101182 -291.65677) (xy 81.90103 -291.65677) (xy 81.90103 -291.704522)
			(xy 82.001106 -291.804344)
		)
		(stroke
			(width 0)
			(type solid)
		)
		(fill yes)
		(layer "In11.Cu")
		(net "M_F_CPU1_SB_DQS_DP<8>")
	)
	(gr_poly
		(pts
			(xy 82.101182 -290.487862) (xy 82.001106 -290.38804) (xy 81.90103 -290.487862) (xy 81.90103 -290.535614)
			(xy 82.101182 -290.535614)
		)
		(stroke
			(width 0)
			(type solid)
		)
		(fill yes)
		(layer "In11.Cu")
		(net "M_F_CPU1_SB_DQS_DP<3>")
	)
	(gr_poly
		(pts
			(xy 82.101182 -290.084256) (xy 82.101182 -290.039806) (xy 81.90103 -290.039806) (xy 81.90103 -290.084256)
			(xy 82.001106 -290.184332)
		)
		(stroke
			(width 0)
			(type solid)
		)
		(fill yes)
		(layer "In11.Cu")
		(net "M_F_CPU1_SB_DQ<27>")
	)
	(gr_poly
		(pts
			(xy 82.101182 -288.868104) (xy 82.001106 -288.768028) (xy 81.90103 -288.868104) (xy 81.90103 -288.912554)
			(xy 82.101182 -288.912554)
		)
		(stroke
			(width 0)
			(type solid)
		)
		(fill yes)
		(layer "In11.Cu")
		(net "M_F_CPU1_SB_DQ<24>")
	)
	(gr_poly
		(pts
			(xy 82.101182 -288.464498) (xy 82.101182 -288.420048) (xy 81.90103 -288.420048) (xy 81.90103 -288.464498)
			(xy 82.001106 -288.564574)
		)
		(stroke
			(width 0)
			(type solid)
		)
		(fill yes)
		(layer "In11.Cu")
		(net "M_F_CPU1_SB_DQ<23>")
	)
	(gr_poly
		(pts
			(xy 82.101182 -287.248092) (xy 82.001106 -287.148016) (xy 81.90103 -287.248092) (xy 81.90103 -287.292542)
			(xy 82.101182 -287.292542)
		)
		(stroke
			(width 0)
			(type solid)
		)
		(fill yes)
		(layer "In11.Cu")
		(net "M_F_CPU1_SB_DQ<20>")
	)
	(gr_poly
		(pts
			(xy 82.101182 -286.844486) (xy 82.101182 -286.796734) (xy 81.90103 -286.796734) (xy 81.90103 -286.844486)
			(xy 82.001106 -286.944562)
		)
		(stroke
			(width 0)
			(type solid)
		)
		(fill yes)
		(layer "In11.Cu")
		(net "M_F_CPU1_SB_DQS_DP<7>")
	)
	(gr_poly
		(pts
			(xy 82.101182 -285.62808) (xy 82.001106 -285.528258) (xy 81.90103 -285.62808) (xy 81.90103 -285.675832)
			(xy 82.101182 -285.675832)
		)
		(stroke
			(width 0)
			(type solid)
		)
		(fill yes)
		(layer "In11.Cu")
		(net "M_F_CPU1_SB_DQS_DP<2>")
	)
	(gr_poly
		(pts
			(xy 82.101182 -285.224474) (xy 82.101182 -285.180024) (xy 81.90103 -285.180024) (xy 81.90103 -285.224474)
			(xy 82.001106 -285.32455)
		)
		(stroke
			(width 0)
			(type solid)
		)
		(fill yes)
		(layer "In11.Cu")
		(net "M_F_CPU1_SB_DQ<19>")
	)
	(gr_poly
		(pts
			(xy 82.101182 -284.008322) (xy 82.001106 -283.908246) (xy 81.90103 -284.008322) (xy 81.90103 -284.052772)
			(xy 82.101182 -284.052772)
		)
		(stroke
			(width 0)
			(type solid)
		)
		(fill yes)
		(layer "In11.Cu")
		(net "M_F_CPU1_SB_DQ<16>")
	)
	(gr_poly
		(pts
			(xy 82.101182 -283.604462) (xy 82.101182 -283.560012) (xy 81.90103 -283.560012) (xy 81.90103 -283.604462)
			(xy 82.001106 -283.704538)
		)
		(stroke
			(width 0)
			(type solid)
		)
		(fill yes)
		(layer "In11.Cu")
		(net "M_F_CPU1_SB_DQ<15>")
	)
	(gr_poly
		(pts
			(xy 82.101182 -282.38831) (xy 82.001106 -282.288234) (xy 81.90103 -282.38831) (xy 81.90103 -282.43276)
			(xy 82.101182 -282.43276)
		)
		(stroke
			(width 0)
			(type solid)
		)
		(fill yes)
		(layer "In11.Cu")
		(net "M_F_CPU1_SB_DQ<12>")
	)
	(gr_poly
		(pts
			(xy 82.101182 -281.984704) (xy 82.101182 -281.936952) (xy 81.90103 -281.936952) (xy 81.90103 -281.984704)
			(xy 82.001106 -282.084526)
		)
		(stroke
			(width 0)
			(type solid)
		)
		(fill yes)
		(layer "In11.Cu")
		(net "M_F_CPU1_SB_DQS_DP<6>")
	)
	(gr_poly
		(pts
			(xy 82.101182 -280.768044) (xy 82.001106 -280.668222) (xy 81.90103 -280.768044) (xy 81.90103 -280.815796)
			(xy 82.101182 -280.815796)
		)
		(stroke
			(width 0)
			(type solid)
		)
		(fill yes)
		(layer "In11.Cu")
		(net "M_F_CPU1_SB_DQS_DP<1>")
	)
	(gr_poly
		(pts
			(xy 82.101182 -280.364438) (xy 82.101182 -280.319988) (xy 81.90103 -280.319988) (xy 81.90103 -280.364438)
			(xy 82.001106 -280.464514)
		)
		(stroke
			(width 0)
			(type solid)
		)
		(fill yes)
		(layer "In11.Cu")
		(net "M_F_CPU1_SB_DQ<11>")
	)
	(gr_poly
		(pts
			(xy 82.101182 -279.148286) (xy 82.001106 -279.04821) (xy 81.90103 -279.148286) (xy 81.90103 -279.192736)
			(xy 82.101182 -279.192736)
		)
		(stroke
			(width 0)
			(type solid)
		)
		(fill yes)
		(layer "In11.Cu")
		(net "M_F_CPU1_SB_DQ<8>")
	)
	(gr_poly
		(pts
			(xy 82.101182 -278.744426) (xy 82.101182 -278.699976) (xy 81.90103 -278.699976) (xy 81.90103 -278.744426)
			(xy 82.001106 -278.844502)
		)
		(stroke
			(width 0)
			(type solid)
		)
		(fill yes)
		(layer "In11.Cu")
		(net "M_F_CPU1_SB_DQ<7>")
	)
	(gr_poly
		(pts
			(xy 82.101182 -277.528274) (xy 82.001106 -277.428198) (xy 81.90103 -277.528274) (xy 81.90103 -277.572724)
			(xy 82.101182 -277.572724)
		)
		(stroke
			(width 0)
			(type solid)
		)
		(fill yes)
		(layer "In11.Cu")
		(net "M_F_CPU1_SB_DQ<4>")
	)
	(gr_poly
		(pts
			(xy 82.101182 -277.124668) (xy 82.101182 -277.076916) (xy 81.90103 -277.076916) (xy 81.90103 -277.124668)
			(xy 82.001106 -277.22449)
		)
		(stroke
			(width 0)
			(type solid)
		)
		(fill yes)
		(layer "In11.Cu")
		(net "M_F_CPU1_SB_DQS_DP<5>")
	)
	(gr_poly
		(pts
			(xy 82.101182 -275.908008) (xy 82.001106 -275.808186) (xy 81.90103 -275.908008) (xy 81.90103 -275.95576)
			(xy 82.101182 -275.95576)
		)
		(stroke
			(width 0)
			(type solid)
		)
		(fill yes)
		(layer "In11.Cu")
		(net "M_F_CPU1_SB_DQS_DP<0>")
	)
	(gr_poly
		(pts
			(xy 82.101182 -275.504402) (xy 82.101182 -275.459952) (xy 81.90103 -275.459952) (xy 81.90103 -275.504402)
			(xy 82.001106 -275.604478)
		)
		(stroke
			(width 0)
			(type solid)
		)
		(fill yes)
		(layer "In11.Cu")
		(net "M_F_CPU1_SB_DQ<3>")
	)
	(gr_poly
		(pts
			(xy 82.101182 -274.28825) (xy 82.001106 -274.188174) (xy 81.90103 -274.28825) (xy 81.90103 -274.3327)
			(xy 82.101182 -274.3327)
		)
		(stroke
			(width 0)
			(type solid)
		)
		(fill yes)
		(layer "In11.Cu")
		(net "M_F_CPU1_SB_DQ<0>")
	)
	(gr_poly
		(pts
			(xy 82.101182 -273.88439) (xy 82.101182 -273.83994) (xy 81.90103 -273.83994) (xy 81.90103 -273.88439)
			(xy 82.001106 -273.984466)
		)
		(stroke
			(width 0)
			(type solid)
		)
		(fill yes)
		(layer "In11.Cu")
		(net "M_F_CPU1_SB_CB<3>")
	)
	(gr_poly
		(pts
			(xy 82.101182 -272.668238) (xy 82.001106 -272.568162) (xy 81.90103 -272.668238) (xy 81.90103 -272.712688)
			(xy 82.101182 -272.712688)
		)
		(stroke
			(width 0)
			(type solid)
		)
		(fill yes)
		(layer "In11.Cu")
		(net "M_F_CPU1_SB_CB<0>")
	)
	(gr_poly
		(pts
			(xy 82.101182 -272.264632) (xy 82.101182 -272.21688) (xy 81.90103 -272.21688) (xy 81.90103 -272.264632)
			(xy 82.001106 -272.364454)
		)
		(stroke
			(width 0)
			(type solid)
		)
		(fill yes)
		(layer "In11.Cu")
		(net "M_F_CPU1_SB_DQS_DP<4>")
	)
	(gr_poly
		(pts
			(xy 82.101182 -271.047972) (xy 82.001106 -270.94815) (xy 81.90103 -271.047972) (xy 81.90103 -271.095724)
			(xy 82.101182 -271.095724)
		)
		(stroke
			(width 0)
			(type solid)
		)
		(fill yes)
		(layer "In11.Cu")
		(net "M_F_CPU1_SB_DQS_DP<9>")
	)
	(gr_poly
		(pts
			(xy 82.101182 -270.644366) (xy 82.101182 -270.599916) (xy 81.90103 -270.599916) (xy 81.90103 -270.644366)
			(xy 82.001106 -270.744442)
		)
		(stroke
			(width 0)
			(type solid)
		)
		(fill yes)
		(layer "In11.Cu")
		(net "M_F_CPU1_SB_CB<7>")
	)
	(gr_poly
		(pts
			(xy 82.101182 -269.428214) (xy 82.001106 -269.328138) (xy 81.90103 -269.428214) (xy 81.90103 -269.472664)
			(xy 82.101182 -269.472664)
		)
		(stroke
			(width 0)
			(type solid)
		)
		(fill yes)
		(layer "In11.Cu")
		(net "M_F_CPU1_SB_CB<4>")
	)
	(gr_poly
		(pts
			(xy 82.101182 -267.808202) (xy 82.001106 -267.708126) (xy 81.90103 -267.808202) (xy 81.90103 -267.852652)
			(xy 82.101182 -267.852652)
		)
		(stroke
			(width 0)
			(type solid)
		)
		(fill yes)
		(layer "In11.Cu")
		(net "M_F_CPU1_SB_RSP<0>")
	)
	(gr_poly
		(pts
			(xy 82.101182 -265.78433) (xy 82.101182 -265.73988) (xy 81.90103 -265.73988) (xy 81.90103 -265.78433)
			(xy 82.001106 -265.884406)
		)
		(stroke
			(width 0)
			(type solid)
		)
		(fill yes)
		(layer "In11.Cu")
		(net "M_F_CPU1_SB_CS_N<0>")
	)
	(gr_poly
		(pts
			(xy 82.101182 -264.568178) (xy 82.001106 -264.468102) (xy 81.90103 -264.568178) (xy 81.90103 -264.612628)
			(xy 82.101182 -264.612628)
		)
		(stroke
			(width 0)
			(type solid)
		)
		(fill yes)
		(layer "In11.Cu")
		(net "M_F_CPU1_SB_CA<6>")
	)
	(gr_poly
		(pts
			(xy 82.101182 -264.164318) (xy 82.101182 -264.119868) (xy 81.90103 -264.119868) (xy 81.90103 -264.164318)
			(xy 82.001106 -264.264394)
		)
		(stroke
			(width 0)
			(type solid)
		)
		(fill yes)
		(layer "In11.Cu")
		(net "M_F_CPU1_SB_CA<5>")
	)
	(gr_poly
		(pts
			(xy 82.101182 -262.948166) (xy 82.001106 -262.84809) (xy 81.90103 -262.948166) (xy 81.90103 -262.992616)
			(xy 82.101182 -262.992616)
		)
		(stroke
			(width 0)
			(type solid)
		)
		(fill yes)
		(layer "In11.Cu")
		(net "M_F_CPU1_SB_CA<2>")
	)
	(gr_poly
		(pts
			(xy 82.101182 -262.544306) (xy 82.101182 -262.499856) (xy 81.90103 -262.499856) (xy 81.90103 -262.544306)
			(xy 82.001106 -262.644382)
		)
		(stroke
			(width 0)
			(type solid)
		)
		(fill yes)
		(layer "In11.Cu")
		(net "M_F_CPU1_SB_CA<1>")
	)
	(gr_poly
		(pts
			(xy 82.157062 -293.860728) (xy 82.120232 -293.724076) (xy 82.081878 -293.701724) (xy 81.981802 -293.874952)
			(xy 82.02041 -293.897304)
		)
		(stroke
			(width 0)
			(type solid)
		)
		(fill yes)
		(layer "In11.Cu")
		(net "M_F_CPU1_SB_DQ<31>")
	)
	(gr_poly
		(pts
			(xy 82.271108 -256.026158) (xy 82.171032 -255.926336) (xy 82.070956 -256.026158) (xy 82.070956 -256.07391)
			(xy 82.271108 -256.07391)
		)
		(stroke
			(width 0)
			(type solid)
		)
		(fill yes)
		(layer "In11.Cu")
		(net "M_F_CPU1_CLK_DP<0>")
	)
	(gr_poly
		(pts
			(xy 82.271108 -255.622552) (xy 82.271108 -255.578102) (xy 82.070956 -255.578102) (xy 82.070956 -255.622552)
			(xy 82.171032 -255.722628)
		)
		(stroke
			(width 0)
			(type solid)
		)
		(fill yes)
		(layer "In11.Cu")
		(net "M_F_CPU1_SA_PAR")
	)
	(gr_poly
		(pts
			(xy 82.271108 -254.4064) (xy 82.171032 -254.306324) (xy 82.070956 -254.4064) (xy 82.070956 -254.45085)
			(xy 82.271108 -254.45085)
		)
		(stroke
			(width 0)
			(type solid)
		)
		(fill yes)
		(layer "In11.Cu")
		(net "M_F_CPU1_SA_CA<4>")
	)
	(gr_poly
		(pts
			(xy 82.271108 -254.00254) (xy 82.271108 -253.95809) (xy 82.070956 -253.95809) (xy 82.070956 -254.00254)
			(xy 82.171032 -254.102616)
		)
		(stroke
			(width 0)
			(type solid)
		)
		(fill yes)
		(layer "In11.Cu")
		(net "M_F_CPU1_SA_CA<3>")
	)
	(gr_poly
		(pts
			(xy 82.271108 -252.786388) (xy 82.171032 -252.686312) (xy 82.070956 -252.786388) (xy 82.070956 -252.830838)
			(xy 82.271108 -252.830838)
		)
		(stroke
			(width 0)
			(type solid)
		)
		(fill yes)
		(layer "In11.Cu")
		(net "M_F_CPU1_SA_CA<0>")
	)
	(gr_poly
		(pts
			(xy 82.271108 -252.382528) (xy 82.271108 -252.338078) (xy 82.070956 -252.338078) (xy 82.070956 -252.382528)
			(xy 82.171032 -252.482604)
		)
		(stroke
			(width 0)
			(type solid)
		)
		(fill yes)
		(layer "In11.Cu")
		(net "M_F_CPU1_SA_CS_N<1>")
	)
	(gr_poly
		(pts
			(xy 82.271108 -250.762516) (xy 82.271108 -250.718066) (xy 82.070956 -250.718066) (xy 82.070956 -250.762516)
			(xy 82.171032 -250.862592)
		)
		(stroke
			(width 0)
			(type solid)
		)
		(fill yes)
		(layer "In11.Cu")
		(net "M_F_CPU1_RESET_N")
	)
	(gr_poly
		(pts
			(xy 82.271108 -249.142504) (xy 82.271108 -249.098054) (xy 82.070956 -249.098054) (xy 82.070956 -249.142504)
			(xy 82.171032 -249.24258)
		)
		(stroke
			(width 0)
			(type solid)
		)
		(fill yes)
		(layer "In11.Cu")
		(net "M_F_CPU1_SA_CB<7>")
	)
	(gr_poly
		(pts
			(xy 82.271108 -247.926352) (xy 82.171032 -247.826276) (xy 82.070956 -247.926352) (xy 82.070956 -247.970802)
			(xy 82.271108 -247.970802)
		)
		(stroke
			(width 0)
			(type solid)
		)
		(fill yes)
		(layer "In11.Cu")
		(net "M_F_CPU1_SA_CB<4>")
	)
	(gr_poly
		(pts
			(xy 82.271108 -247.522746) (xy 82.271108 -247.474994) (xy 82.070956 -247.474994) (xy 82.070956 -247.522746)
			(xy 82.171032 -247.622568)
		)
		(stroke
			(width 0)
			(type solid)
		)
		(fill yes)
		(layer "In11.Cu")
		(net "M_F_CPU1_SA_DQS_DP<9>")
	)
	(gr_poly
		(pts
			(xy 82.271108 -246.306086) (xy 82.171032 -246.206264) (xy 82.070956 -246.306086) (xy 82.070956 -246.353838)
			(xy 82.271108 -246.353838)
		)
		(stroke
			(width 0)
			(type solid)
		)
		(fill yes)
		(layer "In11.Cu")
		(net "M_F_CPU1_SA_DQS_DP<4>")
	)
	(gr_poly
		(pts
			(xy 82.271108 -245.90248) (xy 82.271108 -245.85803) (xy 82.070956 -245.85803) (xy 82.070956 -245.90248)
			(xy 82.171032 -246.002556)
		)
		(stroke
			(width 0)
			(type solid)
		)
		(fill yes)
		(layer "In11.Cu")
		(net "M_F_CPU1_SA_CB<3>")
	)
	(gr_poly
		(pts
			(xy 82.271108 -244.686328) (xy 82.171032 -244.586252) (xy 82.070956 -244.686328) (xy 82.070956 -244.730778)
			(xy 82.271108 -244.730778)
		)
		(stroke
			(width 0)
			(type solid)
		)
		(fill yes)
		(layer "In11.Cu")
		(net "M_F_CPU1_SA_CB<0>")
	)
	(gr_poly
		(pts
			(xy 82.271108 -244.282468) (xy 82.271108 -244.238018) (xy 82.070956 -244.238018) (xy 82.070956 -244.282468)
			(xy 82.171032 -244.382544)
		)
		(stroke
			(width 0)
			(type solid)
		)
		(fill yes)
		(layer "In11.Cu")
		(net "M_F_CPU1_SA_DQ<31>")
	)
	(gr_poly
		(pts
			(xy 82.271108 -243.066316) (xy 82.171032 -242.96624) (xy 82.070956 -243.066316) (xy 82.070956 -243.110766)
			(xy 82.271108 -243.110766)
		)
		(stroke
			(width 0)
			(type solid)
		)
		(fill yes)
		(layer "In11.Cu")
		(net "M_F_CPU1_SA_DQ<28>")
	)
	(gr_poly
		(pts
			(xy 82.271108 -242.66271) (xy 82.271108 -242.614958) (xy 82.070956 -242.614958) (xy 82.070956 -242.66271)
			(xy 82.171032 -242.762532)
		)
		(stroke
			(width 0)
			(type solid)
		)
		(fill yes)
		(layer "In11.Cu")
		(net "M_F_CPU1_SA_DQS_DP<8>")
	)
	(gr_poly
		(pts
			(xy 82.271108 -241.44605) (xy 82.171032 -241.346228) (xy 82.070956 -241.44605) (xy 82.070956 -241.493802)
			(xy 82.271108 -241.493802)
		)
		(stroke
			(width 0)
			(type solid)
		)
		(fill yes)
		(layer "In11.Cu")
		(net "M_F_CPU1_SA_DQS_DP<3>")
	)
	(gr_poly
		(pts
			(xy 82.271108 -241.042444) (xy 82.271108 -240.997994) (xy 82.070956 -240.997994) (xy 82.070956 -241.042444)
			(xy 82.171032 -241.14252)
		)
		(stroke
			(width 0)
			(type solid)
		)
		(fill yes)
		(layer "In11.Cu")
		(net "M_F_CPU1_SA_DQ<27>")
	)
	(gr_poly
		(pts
			(xy 82.271108 -239.826292) (xy 82.171032 -239.726216) (xy 82.070956 -239.826292) (xy 82.070956 -239.870742)
			(xy 82.271108 -239.870742)
		)
		(stroke
			(width 0)
			(type solid)
		)
		(fill yes)
		(layer "In11.Cu")
		(net "M_F_CPU1_SA_DQ<24>")
	)
	(gr_poly
		(pts
			(xy 82.271108 -239.422432) (xy 82.271108 -239.377982) (xy 82.070956 -239.377982) (xy 82.070956 -239.422432)
			(xy 82.171032 -239.522508)
		)
		(stroke
			(width 0)
			(type solid)
		)
		(fill yes)
		(layer "In11.Cu")
		(net "M_F_CPU1_SA_DQ<23>")
	)
	(gr_poly
		(pts
			(xy 82.271108 -238.20628) (xy 82.171032 -238.106204) (xy 82.070956 -238.20628) (xy 82.070956 -238.25073)
			(xy 82.271108 -238.25073)
		)
		(stroke
			(width 0)
			(type solid)
		)
		(fill yes)
		(layer "In11.Cu")
		(net "M_F_CPU1_SA_DQ<20>")
	)
	(gr_poly
		(pts
			(xy 82.271108 -237.802674) (xy 82.271108 -237.754922) (xy 82.070956 -237.754922) (xy 82.070956 -237.802674)
			(xy 82.171032 -237.902496)
		)
		(stroke
			(width 0)
			(type solid)
		)
		(fill yes)
		(layer "In11.Cu")
		(net "M_F_CPU1_SA_DQS_DP<7>")
	)
	(gr_poly
		(pts
			(xy 82.271108 -236.586014) (xy 82.171032 -236.486192) (xy 82.070956 -236.586014) (xy 82.070956 -236.633766)
			(xy 82.271108 -236.633766)
		)
		(stroke
			(width 0)
			(type solid)
		)
		(fill yes)
		(layer "In11.Cu")
		(net "M_F_CPU1_SA_DQS_DP<2>")
	)
	(gr_poly
		(pts
			(xy 82.271108 -236.182408) (xy 82.271108 -236.137958) (xy 82.070956 -236.137958) (xy 82.070956 -236.182408)
			(xy 82.171032 -236.282484)
		)
		(stroke
			(width 0)
			(type solid)
		)
		(fill yes)
		(layer "In11.Cu")
		(net "M_F_CPU1_SA_DQ<19>")
	)
	(gr_poly
		(pts
			(xy 82.271108 -234.966256) (xy 82.171032 -234.86618) (xy 82.070956 -234.966256) (xy 82.070956 -235.010706)
			(xy 82.271108 -235.010706)
		)
		(stroke
			(width 0)
			(type solid)
		)
		(fill yes)
		(layer "In11.Cu")
		(net "M_F_CPU1_SA_DQ<16>")
	)
	(gr_poly
		(pts
			(xy 82.271108 -234.562396) (xy 82.271108 -234.517946) (xy 82.070956 -234.517946) (xy 82.070956 -234.562396)
			(xy 82.171032 -234.662472)
		)
		(stroke
			(width 0)
			(type solid)
		)
		(fill yes)
		(layer "In11.Cu")
		(net "M_F_CPU1_SA_DQ<15>")
	)
	(gr_poly
		(pts
			(xy 82.271108 -233.346244) (xy 82.171032 -233.246168) (xy 82.070956 -233.346244) (xy 82.070956 -233.390694)
			(xy 82.271108 -233.390694)
		)
		(stroke
			(width 0)
			(type solid)
		)
		(fill yes)
		(layer "In11.Cu")
		(net "M_F_CPU1_SA_DQ<12>")
	)
	(gr_poly
		(pts
			(xy 82.271108 -232.942638) (xy 82.271108 -232.894886) (xy 82.070956 -232.894886) (xy 82.070956 -232.942638)
			(xy 82.171032 -233.04246)
		)
		(stroke
			(width 0)
			(type solid)
		)
		(fill yes)
		(layer "In11.Cu")
		(net "M_F_CPU1_SA_DQS_DP<6>")
	)
	(gr_poly
		(pts
			(xy 82.271108 -231.725978) (xy 82.171032 -231.626156) (xy 82.070956 -231.725978) (xy 82.070956 -231.77373)
			(xy 82.271108 -231.77373)
		)
		(stroke
			(width 0)
			(type solid)
		)
		(fill yes)
		(layer "In11.Cu")
		(net "M_F_CPU1_SA_DQS_DP<1>")
	)
	(gr_poly
		(pts
			(xy 82.271108 -231.322626) (xy 82.271108 -231.278176) (xy 82.070956 -231.278176) (xy 82.070956 -231.322626)
			(xy 82.171032 -231.422702)
		)
		(stroke
			(width 0)
			(type solid)
		)
		(fill yes)
		(layer "In11.Cu")
		(net "M_F_CPU1_SA_DQ<11>")
	)
	(gr_poly
		(pts
			(xy 82.271108 -230.10622) (xy 82.171032 -230.006144) (xy 82.070956 -230.10622) (xy 82.070956 -230.15067)
			(xy 82.271108 -230.15067)
		)
		(stroke
			(width 0)
			(type solid)
		)
		(fill yes)
		(layer "In11.Cu")
		(net "M_F_CPU1_SA_DQ<8>")
	)
	(gr_poly
		(pts
			(xy 82.271108 -229.702614) (xy 82.271108 -229.658164) (xy 82.070956 -229.658164) (xy 82.070956 -229.702614)
			(xy 82.171032 -229.80269)
		)
		(stroke
			(width 0)
			(type solid)
		)
		(fill yes)
		(layer "In11.Cu")
		(net "M_F_CPU1_SA_DQ<7>")
	)
	(gr_poly
		(pts
			(xy 82.271108 -228.486462) (xy 82.171032 -228.386386) (xy 82.070956 -228.486462) (xy 82.070956 -228.530912)
			(xy 82.271108 -228.530912)
		)
		(stroke
			(width 0)
			(type solid)
		)
		(fill yes)
		(layer "In11.Cu")
		(net "M_F_CPU1_SA_DQ<4>")
	)
	(gr_poly
		(pts
			(xy 82.271108 -228.082856) (xy 82.271108 -228.035104) (xy 82.070956 -228.035104) (xy 82.070956 -228.082856)
			(xy 82.171032 -228.182678)
		)
		(stroke
			(width 0)
			(type solid)
		)
		(fill yes)
		(layer "In11.Cu")
		(net "M_F_CPU1_SA_DQS_DP<5>")
	)
	(gr_poly
		(pts
			(xy 82.271108 -226.866196) (xy 82.171032 -226.766374) (xy 82.070956 -226.866196) (xy 82.070956 -226.913948)
			(xy 82.271108 -226.913948)
		)
		(stroke
			(width 0)
			(type solid)
		)
		(fill yes)
		(layer "In11.Cu")
		(net "M_F_CPU1_SA_DQS_DP<0>")
	)
	(gr_poly
		(pts
			(xy 82.271108 -226.46259) (xy 82.271108 -226.41814) (xy 82.070956 -226.41814) (xy 82.070956 -226.46259)
			(xy 82.171032 -226.562666)
		)
		(stroke
			(width 0)
			(type solid)
		)
		(fill yes)
		(layer "In11.Cu")
		(net "M_F_CPU1_SA_DQ<3>")
	)
	(gr_poly
		(pts
			(xy 82.271108 -225.246438) (xy 82.171032 -225.146362) (xy 82.070956 -225.246438) (xy 82.070956 -225.290888)
			(xy 82.271108 -225.290888)
		)
		(stroke
			(width 0)
			(type solid)
		)
		(fill yes)
		(layer "In11.Cu")
		(net "M_F_CPU1_SA_DQ<0>")
	)
	(gr_poly
		(pts
			(xy 82.571082 -292.918134) (xy 82.471006 -292.818058) (xy 82.37093 -292.918134) (xy 82.37093 -292.962584)
			(xy 82.571082 -292.962584)
		)
		(stroke
			(width 0)
			(type solid)
		)
		(fill yes)
		(layer "In11.Cu")
		(net "M_F_CPU1_SB_DQ<29>")
	)
	(gr_poly
		(pts
			(xy 82.571082 -292.514274) (xy 82.571082 -292.469824) (xy 82.37093 -292.469824) (xy 82.37093 -292.514274)
			(xy 82.471006 -292.61435)
		)
		(stroke
			(width 0)
			(type solid)
		)
		(fill yes)
		(layer "In11.Cu")
		(net "M_F_CPU1_SB_DQ<30>")
	)
	(gr_poly
		(pts
			(xy 82.571082 -291.297868) (xy 82.471006 -291.198046) (xy 82.37093 -291.297868) (xy 82.37093 -291.34562)
			(xy 82.571082 -291.34562)
		)
		(stroke
			(width 0)
			(type solid)
		)
		(fill yes)
		(layer "In11.Cu")
		(net "M_F_CPU1_SB_DQS_DN<8>")
	)
	(gr_poly
		(pts
			(xy 82.571082 -290.894516) (xy 82.571082 -290.846764) (xy 82.37093 -290.846764) (xy 82.37093 -290.894516)
			(xy 82.471006 -290.994338)
		)
		(stroke
			(width 0)
			(type solid)
		)
		(fill yes)
		(layer "In11.Cu")
		(net "M_F_CPU1_SB_DQS_DN<3>")
	)
	(gr_poly
		(pts
			(xy 82.571082 -289.67811) (xy 82.471006 -289.578034) (xy 82.37093 -289.67811) (xy 82.37093 -289.72256)
			(xy 82.571082 -289.72256)
		)
		(stroke
			(width 0)
			(type solid)
		)
		(fill yes)
		(layer "In11.Cu")
		(net "M_F_CPU1_SB_DQ<25>")
	)
	(gr_poly
		(pts
			(xy 82.571082 -289.27425) (xy 82.571082 -289.2298) (xy 82.37093 -289.2298) (xy 82.37093 -289.27425)
			(xy 82.471006 -289.374326)
		)
		(stroke
			(width 0)
			(type solid)
		)
		(fill yes)
		(layer "In11.Cu")
		(net "M_F_CPU1_SB_DQ<26>")
	)
	(gr_poly
		(pts
			(xy 82.571082 -288.058098) (xy 82.471006 -287.958022) (xy 82.37093 -288.058098) (xy 82.37093 -288.102548)
			(xy 82.571082 -288.102548)
		)
		(stroke
			(width 0)
			(type solid)
		)
		(fill yes)
		(layer "In11.Cu")
		(net "M_F_CPU1_SB_DQ<21>")
	)
	(gr_poly
		(pts
			(xy 82.571082 -287.654492) (xy 82.571082 -287.610042) (xy 82.37093 -287.610042) (xy 82.37093 -287.654492)
			(xy 82.471006 -287.754568)
		)
		(stroke
			(width 0)
			(type solid)
		)
		(fill yes)
		(layer "In11.Cu")
		(net "M_F_CPU1_SB_DQ<22>")
	)
	(gr_poly
		(pts
			(xy 82.571082 -286.438086) (xy 82.471006 -286.33801) (xy 82.37093 -286.438086) (xy 82.37093 -286.485838)
			(xy 82.571082 -286.485838)
		)
		(stroke
			(width 0)
			(type solid)
		)
		(fill yes)
		(layer "In11.Cu")
		(net "M_F_CPU1_SB_DQS_DN<7>")
	)
	(gr_poly
		(pts
			(xy 82.571082 -286.034734) (xy 82.571082 -285.986982) (xy 82.37093 -285.986982) (xy 82.37093 -286.034734)
			(xy 82.471006 -286.134556)
		)
		(stroke
			(width 0)
			(type solid)
		)
		(fill yes)
		(layer "In11.Cu")
		(net "M_F_CPU1_SB_DQS_DN<2>")
	)
	(gr_poly
		(pts
			(xy 82.571082 -284.818328) (xy 82.471006 -284.718252) (xy 82.37093 -284.818328) (xy 82.37093 -284.862778)
			(xy 82.571082 -284.862778)
		)
		(stroke
			(width 0)
			(type solid)
		)
		(fill yes)
		(layer "In11.Cu")
		(net "M_F_CPU1_SB_DQ<17>")
	)
	(gr_poly
		(pts
			(xy 82.571082 -284.414468) (xy 82.571082 -284.370018) (xy 82.37093 -284.370018) (xy 82.37093 -284.414468)
			(xy 82.471006 -284.514544)
		)
		(stroke
			(width 0)
			(type solid)
		)
		(fill yes)
		(layer "In11.Cu")
		(net "M_F_CPU1_SB_DQ<18>")
	)
	(gr_poly
		(pts
			(xy 82.571082 -283.198316) (xy 82.471006 -283.09824) (xy 82.37093 -283.198316) (xy 82.37093 -283.242766)
			(xy 82.571082 -283.242766)
		)
		(stroke
			(width 0)
			(type solid)
		)
		(fill yes)
		(layer "In11.Cu")
		(net "M_F_CPU1_SB_DQ<13>")
	)
	(gr_poly
		(pts
			(xy 82.571082 -282.794456) (xy 82.571082 -282.750006) (xy 82.37093 -282.750006) (xy 82.37093 -282.794456)
			(xy 82.471006 -282.894532)
		)
		(stroke
			(width 0)
			(type solid)
		)
		(fill yes)
		(layer "In11.Cu")
		(net "M_F_CPU1_SB_DQ<14>")
	)
	(gr_poly
		(pts
			(xy 82.571082 -281.57805) (xy 82.471006 -281.478228) (xy 82.37093 -281.57805) (xy 82.37093 -281.625802)
			(xy 82.571082 -281.625802)
		)
		(stroke
			(width 0)
			(type solid)
		)
		(fill yes)
		(layer "In11.Cu")
		(net "M_F_CPU1_SB_DQS_DN<6>")
	)
	(gr_poly
		(pts
			(xy 82.571082 -281.174698) (xy 82.571082 -281.126946) (xy 82.37093 -281.126946) (xy 82.37093 -281.174698)
			(xy 82.471006 -281.27452)
		)
		(stroke
			(width 0)
			(type solid)
		)
		(fill yes)
		(layer "In11.Cu")
		(net "M_F_CPU1_SB_DQS_DN<1>")
	)
	(gr_poly
		(pts
			(xy 82.571082 -279.958292) (xy 82.471006 -279.858216) (xy 82.37093 -279.958292) (xy 82.37093 -280.002742)
			(xy 82.571082 -280.002742)
		)
		(stroke
			(width 0)
			(type solid)
		)
		(fill yes)
		(layer "In11.Cu")
		(net "M_F_CPU1_SB_DQ<9>")
	)
	(gr_poly
		(pts
			(xy 82.571082 -279.554432) (xy 82.571082 -279.509982) (xy 82.37093 -279.509982) (xy 82.37093 -279.554432)
			(xy 82.471006 -279.654508)
		)
		(stroke
			(width 0)
			(type solid)
		)
		(fill yes)
		(layer "In11.Cu")
		(net "M_F_CPU1_SB_DQ<10>")
	)
	(gr_poly
		(pts
			(xy 82.571082 -278.33828) (xy 82.471006 -278.238204) (xy 82.37093 -278.33828) (xy 82.37093 -278.38273)
			(xy 82.571082 -278.38273)
		)
		(stroke
			(width 0)
			(type solid)
		)
		(fill yes)
		(layer "In11.Cu")
		(net "M_F_CPU1_SB_DQ<5>")
	)
	(gr_poly
		(pts
			(xy 82.571082 -277.93442) (xy 82.571082 -277.88997) (xy 82.37093 -277.88997) (xy 82.37093 -277.93442)
			(xy 82.471006 -278.034496)
		)
		(stroke
			(width 0)
			(type solid)
		)
		(fill yes)
		(layer "In11.Cu")
		(net "M_F_CPU1_SB_DQ<6>")
	)
	(gr_poly
		(pts
			(xy 82.571082 -276.718014) (xy 82.471006 -276.618192) (xy 82.37093 -276.718014) (xy 82.37093 -276.765766)
			(xy 82.571082 -276.765766)
		)
		(stroke
			(width 0)
			(type solid)
		)
		(fill yes)
		(layer "In11.Cu")
		(net "M_F_CPU1_SB_DQS_DN<5>")
	)
	(gr_poly
		(pts
			(xy 82.571082 -276.314662) (xy 82.571082 -276.26691) (xy 82.37093 -276.26691) (xy 82.37093 -276.314662)
			(xy 82.471006 -276.414484)
		)
		(stroke
			(width 0)
			(type solid)
		)
		(fill yes)
		(layer "In11.Cu")
		(net "M_F_CPU1_SB_DQS_DN<0>")
	)
	(gr_poly
		(pts
			(xy 82.571082 -275.098256) (xy 82.471006 -274.99818) (xy 82.37093 -275.098256) (xy 82.37093 -275.142706)
			(xy 82.571082 -275.142706)
		)
		(stroke
			(width 0)
			(type solid)
		)
		(fill yes)
		(layer "In11.Cu")
		(net "M_F_CPU1_SB_DQ<1>")
	)
	(gr_poly
		(pts
			(xy 82.571082 -274.694396) (xy 82.571082 -274.649946) (xy 82.37093 -274.649946) (xy 82.37093 -274.694396)
			(xy 82.471006 -274.794472)
		)
		(stroke
			(width 0)
			(type solid)
		)
		(fill yes)
		(layer "In11.Cu")
		(net "M_F_CPU1_SB_DQ<2>")
	)
	(gr_poly
		(pts
			(xy 82.571082 -273.478244) (xy 82.471006 -273.378168) (xy 82.37093 -273.478244) (xy 82.37093 -273.522694)
			(xy 82.571082 -273.522694)
		)
		(stroke
			(width 0)
			(type solid)
		)
		(fill yes)
		(layer "In11.Cu")
		(net "M_F_CPU1_SB_CB<1>")
	)
	(gr_poly
		(pts
			(xy 82.571082 -273.074384) (xy 82.571082 -273.029934) (xy 82.37093 -273.029934) (xy 82.37093 -273.074384)
			(xy 82.471006 -273.17446)
		)
		(stroke
			(width 0)
			(type solid)
		)
		(fill yes)
		(layer "In11.Cu")
		(net "M_F_CPU1_SB_CB<2>")
	)
	(gr_poly
		(pts
			(xy 82.571082 -271.857978) (xy 82.471006 -271.758156) (xy 82.37093 -271.857978) (xy 82.37093 -271.90573)
			(xy 82.571082 -271.90573)
		)
		(stroke
			(width 0)
			(type solid)
		)
		(fill yes)
		(layer "In11.Cu")
		(net "M_F_CPU1_SB_DQS_DN<4>")
	)
	(gr_poly
		(pts
			(xy 82.571082 -271.454626) (xy 82.571082 -271.406874) (xy 82.37093 -271.406874) (xy 82.37093 -271.454626)
			(xy 82.471006 -271.554448)
		)
		(stroke
			(width 0)
			(type solid)
		)
		(fill yes)
		(layer "In11.Cu")
		(net "M_F_CPU1_SB_DQS_DN<9>")
	)
	(gr_poly
		(pts
			(xy 82.571082 -270.23822) (xy 82.471006 -270.138144) (xy 82.37093 -270.23822) (xy 82.37093 -270.28267)
			(xy 82.571082 -270.28267)
		)
		(stroke
			(width 0)
			(type solid)
		)
		(fill yes)
		(layer "In11.Cu")
		(net "M_F_CPU1_SB_CB<5>")
	)
	(gr_poly
		(pts
			(xy 82.571082 -269.83436) (xy 82.571082 -269.78991) (xy 82.37093 -269.78991) (xy 82.37093 -269.83436)
			(xy 82.471006 -269.934436)
		)
		(stroke
			(width 0)
			(type solid)
		)
		(fill yes)
		(layer "In11.Cu")
		(net "M_F_CPU1_SB_CB<6>")
	)
	(gr_poly
		(pts
			(xy 82.571082 -266.998196) (xy 82.471006 -266.89812) (xy 82.37093 -266.998196) (xy 82.37093 -267.042646)
			(xy 82.571082 -267.042646)
		)
		(stroke
			(width 0)
			(type solid)
		)
		(fill yes)
		(layer "In11.Cu")
		(net "M_F_CPU1_SA_RSP<0>")
	)
	(gr_poly
		(pts
			(xy 82.571082 -266.594336) (xy 82.571082 -266.549886) (xy 82.37093 -266.549886) (xy 82.37093 -266.594336)
			(xy 82.471006 -266.694412)
		)
		(stroke
			(width 0)
			(type solid)
		)
		(fill yes)
		(layer "In11.Cu")
		(net "M_F_CPU1_SB_CS_N<1>")
	)
	(gr_poly
		(pts
			(xy 82.571082 -264.974324) (xy 82.571082 -264.929874) (xy 82.37093 -264.929874) (xy 82.37093 -264.974324)
			(xy 82.471006 -265.0744)
		)
		(stroke
			(width 0)
			(type solid)
		)
		(fill yes)
		(layer "In11.Cu")
		(net "M_F_CPU1_SB_PAR")
	)
	(gr_poly
		(pts
			(xy 82.571082 -263.758172) (xy 82.471006 -263.658096) (xy 82.37093 -263.758172) (xy 82.37093 -263.802622)
			(xy 82.571082 -263.802622)
		)
		(stroke
			(width 0)
			(type solid)
		)
		(fill yes)
		(layer "In11.Cu")
		(net "M_F_CPU1_SB_CA<4>")
	)
	(gr_poly
		(pts
			(xy 82.571082 -263.354312) (xy 82.571082 -263.309862) (xy 82.37093 -263.309862) (xy 82.37093 -263.354312)
			(xy 82.471006 -263.454388)
		)
		(stroke
			(width 0)
			(type solid)
		)
		(fill yes)
		(layer "In11.Cu")
		(net "M_F_CPU1_SB_CA<3>")
	)
	(gr_poly
		(pts
			(xy 82.571082 -262.13816) (xy 82.471006 -262.038084) (xy 82.37093 -262.13816) (xy 82.37093 -262.18261)
			(xy 82.571082 -262.18261)
		)
		(stroke
			(width 0)
			(type solid)
		)
		(fill yes)
		(layer "In11.Cu")
		(net "M_F_CPU1_SB_CA<0>")
	)
	(gr_poly
		(pts
			(xy 82.741008 -256.432812) (xy 82.741008 -256.38506) (xy 82.540856 -256.38506) (xy 82.540856 -256.432812)
			(xy 82.640932 -256.532634)
		)
		(stroke
			(width 0)
			(type solid)
		)
		(fill yes)
		(layer "In11.Cu")
		(net "M_F_CPU1_CLK_DN<0>")
	)
	(gr_poly
		(pts
			(xy 82.741008 -255.216406) (xy 82.640932 -255.11633) (xy 82.540856 -255.216406) (xy 82.540856 -255.260856)
			(xy 82.741008 -255.260856)
		)
		(stroke
			(width 0)
			(type solid)
		)
		(fill yes)
		(layer "In11.Cu")
		(net "M_F_CPU1_SA_CA<6>")
	)
	(gr_poly
		(pts
			(xy 82.741008 -254.812546) (xy 82.741008 -254.768096) (xy 82.540856 -254.768096) (xy 82.540856 -254.812546)
			(xy 82.640932 -254.912622)
		)
		(stroke
			(width 0)
			(type solid)
		)
		(fill yes)
		(layer "In11.Cu")
		(net "M_F_CPU1_SA_CA<5>")
	)
	(gr_poly
		(pts
			(xy 82.741008 -253.596394) (xy 82.640932 -253.496318) (xy 82.540856 -253.596394) (xy 82.540856 -253.640844)
			(xy 82.741008 -253.640844)
		)
		(stroke
			(width 0)
			(type solid)
		)
		(fill yes)
		(layer "In11.Cu")
		(net "M_F_CPU1_SA_CA<2>")
	)
	(gr_poly
		(pts
			(xy 82.741008 -253.192534) (xy 82.741008 -253.148084) (xy 82.540856 -253.148084) (xy 82.540856 -253.192534)
			(xy 82.640932 -253.29261)
		)
		(stroke
			(width 0)
			(type solid)
		)
		(fill yes)
		(layer "In11.Cu")
		(net "M_F_CPU1_SA_CA<1>")
	)
	(gr_poly
		(pts
			(xy 82.741008 -251.572522) (xy 82.741008 -251.528072) (xy 82.540856 -251.528072) (xy 82.540856 -251.572522)
			(xy 82.640932 -251.672598)
		)
		(stroke
			(width 0)
			(type solid)
		)
		(fill yes)
		(layer "In11.Cu")
		(net "M_F_CPU1_SA_CS_N<0>")
	)
	(gr_poly
		(pts
			(xy 82.741008 -250.35637) (xy 82.640932 -250.256294) (xy 82.540856 -250.35637) (xy 82.540856 -250.40082)
			(xy 82.741008 -250.40082)
		)
		(stroke
			(width 0)
			(type solid)
		)
		(fill yes)
		(layer "In11.Cu")
		(net "M_F_CPU1_ALERT_R_N")
	)
	(gr_poly
		(pts
			(xy 82.741008 -248.736358) (xy 82.640932 -248.636282) (xy 82.540856 -248.736358) (xy 82.540856 -248.780808)
			(xy 82.741008 -248.780808)
		)
		(stroke
			(width 0)
			(type solid)
		)
		(fill yes)
		(layer "In11.Cu")
		(net "M_F_CPU1_SA_CB<5>")
	)
	(gr_poly
		(pts
			(xy 82.741008 -248.332498) (xy 82.741008 -248.288048) (xy 82.540856 -248.288048) (xy 82.540856 -248.332498)
			(xy 82.640932 -248.432574)
		)
		(stroke
			(width 0)
			(type solid)
		)
		(fill yes)
		(layer "In11.Cu")
		(net "M_F_CPU1_SA_CB<6>")
	)
	(gr_poly
		(pts
			(xy 82.741008 -247.116092) (xy 82.640932 -247.01627) (xy 82.540856 -247.116092) (xy 82.540856 -247.163844)
			(xy 82.741008 -247.163844)
		)
		(stroke
			(width 0)
			(type solid)
		)
		(fill yes)
		(layer "In11.Cu")
		(net "M_F_CPU1_SA_DQS_DN<9>")
	)
	(gr_poly
		(pts
			(xy 82.741008 -246.71274) (xy 82.741008 -246.664988) (xy 82.540856 -246.664988) (xy 82.540856 -246.71274)
			(xy 82.640932 -246.812562)
		)
		(stroke
			(width 0)
			(type solid)
		)
		(fill yes)
		(layer "In11.Cu")
		(net "M_F_CPU1_SA_DQS_DN<4>")
	)
	(gr_poly
		(pts
			(xy 82.741008 -245.496334) (xy 82.640932 -245.396258) (xy 82.540856 -245.496334) (xy 82.540856 -245.540784)
			(xy 82.741008 -245.540784)
		)
		(stroke
			(width 0)
			(type solid)
		)
		(fill yes)
		(layer "In11.Cu")
		(net "M_F_CPU1_SA_CB<1>")
	)
	(gr_poly
		(pts
			(xy 82.741008 -245.092474) (xy 82.741008 -245.048024) (xy 82.540856 -245.048024) (xy 82.540856 -245.092474)
			(xy 82.640932 -245.19255)
		)
		(stroke
			(width 0)
			(type solid)
		)
		(fill yes)
		(layer "In11.Cu")
		(net "M_F_CPU1_SA_CB<2>")
	)
	(gr_poly
		(pts
			(xy 82.741008 -243.876322) (xy 82.640932 -243.776246) (xy 82.540856 -243.876322) (xy 82.540856 -243.920772)
			(xy 82.741008 -243.920772)
		)
		(stroke
			(width 0)
			(type solid)
		)
		(fill yes)
		(layer "In11.Cu")
		(net "M_F_CPU1_SA_DQ<29>")
	)
	(gr_poly
		(pts
			(xy 82.741008 -243.472462) (xy 82.741008 -243.428012) (xy 82.540856 -243.428012) (xy 82.540856 -243.472462)
			(xy 82.640932 -243.572538)
		)
		(stroke
			(width 0)
			(type solid)
		)
		(fill yes)
		(layer "In11.Cu")
		(net "M_F_CPU1_SA_DQ<30>")
	)
	(gr_poly
		(pts
			(xy 82.741008 -242.256056) (xy 82.640932 -242.156234) (xy 82.540856 -242.256056) (xy 82.540856 -242.303808)
			(xy 82.741008 -242.303808)
		)
		(stroke
			(width 0)
			(type solid)
		)
		(fill yes)
		(layer "In11.Cu")
		(net "M_F_CPU1_SA_DQS_DN<8>")
	)
	(gr_poly
		(pts
			(xy 82.741008 -241.852704) (xy 82.741008 -241.804952) (xy 82.540856 -241.804952) (xy 82.540856 -241.852704)
			(xy 82.640932 -241.952526)
		)
		(stroke
			(width 0)
			(type solid)
		)
		(fill yes)
		(layer "In11.Cu")
		(net "M_F_CPU1_SA_DQS_DN<3>")
	)
	(gr_poly
		(pts
			(xy 82.741008 -240.636298) (xy 82.640932 -240.536222) (xy 82.540856 -240.636298) (xy 82.540856 -240.680748)
			(xy 82.741008 -240.680748)
		)
		(stroke
			(width 0)
			(type solid)
		)
		(fill yes)
		(layer "In11.Cu")
		(net "M_F_CPU1_SA_DQ<25>")
	)
	(gr_poly
		(pts
			(xy 82.741008 -240.232438) (xy 82.741008 -240.187988) (xy 82.540856 -240.187988) (xy 82.540856 -240.232438)
			(xy 82.640932 -240.332514)
		)
		(stroke
			(width 0)
			(type solid)
		)
		(fill yes)
		(layer "In11.Cu")
		(net "M_F_CPU1_SA_DQ<26>")
	)
	(gr_poly
		(pts
			(xy 82.741008 -239.016286) (xy 82.640932 -238.91621) (xy 82.540856 -239.016286) (xy 82.540856 -239.060736)
			(xy 82.741008 -239.060736)
		)
		(stroke
			(width 0)
			(type solid)
		)
		(fill yes)
		(layer "In11.Cu")
		(net "M_F_CPU1_SA_DQ<21>")
	)
	(gr_poly
		(pts
			(xy 82.741008 -238.612426) (xy 82.741008 -238.567976) (xy 82.540856 -238.567976) (xy 82.540856 -238.612426)
			(xy 82.640932 -238.712502)
		)
		(stroke
			(width 0)
			(type solid)
		)
		(fill yes)
		(layer "In11.Cu")
		(net "M_F_CPU1_SA_DQ<22>")
	)
	(gr_poly
		(pts
			(xy 82.741008 -237.39602) (xy 82.640932 -237.296198) (xy 82.540856 -237.39602) (xy 82.540856 -237.443772)
			(xy 82.741008 -237.443772)
		)
		(stroke
			(width 0)
			(type solid)
		)
		(fill yes)
		(layer "In11.Cu")
		(net "M_F_CPU1_SA_DQS_DN<7>")
	)
	(gr_poly
		(pts
			(xy 82.741008 -236.992668) (xy 82.741008 -236.944916) (xy 82.540856 -236.944916) (xy 82.540856 -236.992668)
			(xy 82.640932 -237.09249)
		)
		(stroke
			(width 0)
			(type solid)
		)
		(fill yes)
		(layer "In11.Cu")
		(net "M_F_CPU1_SA_DQS_DN<2>")
	)
	(gr_poly
		(pts
			(xy 82.741008 -235.776262) (xy 82.640932 -235.676186) (xy 82.540856 -235.776262) (xy 82.540856 -235.820712)
			(xy 82.741008 -235.820712)
		)
		(stroke
			(width 0)
			(type solid)
		)
		(fill yes)
		(layer "In11.Cu")
		(net "M_F_CPU1_SA_DQ<17>")
	)
	(gr_poly
		(pts
			(xy 82.741008 -235.372402) (xy 82.741008 -235.327952) (xy 82.540856 -235.327952) (xy 82.540856 -235.372402)
			(xy 82.640932 -235.472478)
		)
		(stroke
			(width 0)
			(type solid)
		)
		(fill yes)
		(layer "In11.Cu")
		(net "M_F_CPU1_SA_DQ<18>")
	)
	(gr_poly
		(pts
			(xy 82.741008 -234.15625) (xy 82.640932 -234.056174) (xy 82.540856 -234.15625) (xy 82.540856 -234.2007)
			(xy 82.741008 -234.2007)
		)
		(stroke
			(width 0)
			(type solid)
		)
		(fill yes)
		(layer "In11.Cu")
		(net "M_F_CPU1_SA_DQ<13>")
	)
	(gr_poly
		(pts
			(xy 82.741008 -233.75239) (xy 82.741008 -233.70794) (xy 82.540856 -233.70794) (xy 82.540856 -233.75239)
			(xy 82.640932 -233.852466)
		)
		(stroke
			(width 0)
			(type solid)
		)
		(fill yes)
		(layer "In11.Cu")
		(net "M_F_CPU1_SA_DQ<14>")
	)
	(gr_poly
		(pts
			(xy 82.741008 -232.535984) (xy 82.640932 -232.436162) (xy 82.540856 -232.535984) (xy 82.540856 -232.583736)
			(xy 82.741008 -232.583736)
		)
		(stroke
			(width 0)
			(type solid)
		)
		(fill yes)
		(layer "In11.Cu")
		(net "M_F_CPU1_SA_DQS_DN<6>")
	)
	(gr_poly
		(pts
			(xy 82.741008 -232.132632) (xy 82.741008 -232.08488) (xy 82.540856 -232.08488) (xy 82.540856 -232.132632)
			(xy 82.640932 -232.232454)
		)
		(stroke
			(width 0)
			(type solid)
		)
		(fill yes)
		(layer "In11.Cu")
		(net "M_F_CPU1_SA_DQS_DN<1>")
	)
	(gr_poly
		(pts
			(xy 82.741008 -230.916226) (xy 82.640932 -230.81615) (xy 82.540856 -230.916226) (xy 82.540856 -230.960676)
			(xy 82.741008 -230.960676)
		)
		(stroke
			(width 0)
			(type solid)
		)
		(fill yes)
		(layer "In11.Cu")
		(net "M_F_CPU1_SA_DQ<9>")
	)
	(gr_poly
		(pts
			(xy 82.741008 -230.51262) (xy 82.741008 -230.46817) (xy 82.540856 -230.46817) (xy 82.540856 -230.51262)
			(xy 82.640932 -230.612696)
		)
		(stroke
			(width 0)
			(type solid)
		)
		(fill yes)
		(layer "In11.Cu")
		(net "M_F_CPU1_SA_DQ<10>")
	)
	(gr_poly
		(pts
			(xy 82.741008 -229.296214) (xy 82.640932 -229.196138) (xy 82.540856 -229.296214) (xy 82.540856 -229.340664)
			(xy 82.741008 -229.340664)
		)
		(stroke
			(width 0)
			(type solid)
		)
		(fill yes)
		(layer "In11.Cu")
		(net "M_F_CPU1_SA_DQ<5>")
	)
	(gr_poly
		(pts
			(xy 82.741008 -228.892608) (xy 82.741008 -228.848158) (xy 82.540856 -228.848158) (xy 82.540856 -228.892608)
			(xy 82.640932 -228.992684)
		)
		(stroke
			(width 0)
			(type solid)
		)
		(fill yes)
		(layer "In11.Cu")
		(net "M_F_CPU1_SA_DQ<6>")
	)
	(gr_poly
		(pts
			(xy 82.741008 -227.676202) (xy 82.640932 -227.57638) (xy 82.540856 -227.676202) (xy 82.540856 -227.723954)
			(xy 82.741008 -227.723954)
		)
		(stroke
			(width 0)
			(type solid)
		)
		(fill yes)
		(layer "In11.Cu")
		(net "M_F_CPU1_SA_DQS_DN<5>")
	)
	(gr_poly
		(pts
			(xy 82.741008 -227.27285) (xy 82.741008 -227.225098) (xy 82.540856 -227.225098) (xy 82.540856 -227.27285)
			(xy 82.640932 -227.372672)
		)
		(stroke
			(width 0)
			(type solid)
		)
		(fill yes)
		(layer "In11.Cu")
		(net "M_F_CPU1_SA_DQS_DN<0>")
	)
	(gr_poly
		(pts
			(xy 82.741008 -226.056444) (xy 82.640932 -225.956368) (xy 82.540856 -226.056444) (xy 82.540856 -226.100894)
			(xy 82.741008 -226.100894)
		)
		(stroke
			(width 0)
			(type solid)
		)
		(fill yes)
		(layer "In11.Cu")
		(net "M_F_CPU1_SA_DQ<1>")
	)
	(gr_poly
		(pts
			(xy 82.741008 -225.652584) (xy 82.741008 -225.608134) (xy 82.540856 -225.608134) (xy 82.540856 -225.652584)
			(xy 82.640932 -225.75266)
		)
		(stroke
			(width 0)
			(type solid)
		)
		(fill yes)
		(layer "In11.Cu")
		(net "M_F_CPU1_SA_DQ<2>")
	)
	(gr_poly
		(pts
			(xy 83.040982 -293.32428) (xy 83.040982 -293.27983) (xy 82.84083 -293.27983) (xy 82.84083 -293.32428)
			(xy 82.940906 -293.424356)
		)
		(stroke
			(width 0)
			(type solid)
		)
		(fill yes)
		(layer "In11.Cu")
		(net "M_F_CPU1_SB_DQ<31>")
	)
	(gr_poly
		(pts
			(xy 83.040982 -292.108128) (xy 82.940906 -292.008052) (xy 82.84083 -292.108128) (xy 82.84083 -292.152578)
			(xy 83.040982 -292.152578)
		)
		(stroke
			(width 0)
			(type solid)
		)
		(fill yes)
		(layer "In11.Cu")
		(net "M_F_CPU1_SB_DQ<28>")
	)
	(gr_poly
		(pts
			(xy 83.040982 -291.704522) (xy 83.040982 -291.65677) (xy 82.84083 -291.65677) (xy 82.84083 -291.704522)
			(xy 82.940906 -291.804344)
		)
		(stroke
			(width 0)
			(type solid)
		)
		(fill yes)
		(layer "In11.Cu")
		(net "M_F_CPU1_SB_DQS_DP<8>")
	)
	(gr_poly
		(pts
			(xy 83.040982 -290.487862) (xy 82.940906 -290.38804) (xy 82.84083 -290.487862) (xy 82.84083 -290.535614)
			(xy 83.040982 -290.535614)
		)
		(stroke
			(width 0)
			(type solid)
		)
		(fill yes)
		(layer "In11.Cu")
		(net "M_F_CPU1_SB_DQS_DP<3>")
	)
	(gr_poly
		(pts
			(xy 83.040982 -290.084256) (xy 83.040982 -290.039806) (xy 82.84083 -290.039806) (xy 82.84083 -290.084256)
			(xy 82.940906 -290.184332)
		)
		(stroke
			(width 0)
			(type solid)
		)
		(fill yes)
		(layer "In11.Cu")
		(net "M_F_CPU1_SB_DQ<27>")
	)
	(gr_poly
		(pts
			(xy 83.040982 -288.868104) (xy 82.940906 -288.768028) (xy 82.84083 -288.868104) (xy 82.84083 -288.912554)
			(xy 83.040982 -288.912554)
		)
		(stroke
			(width 0)
			(type solid)
		)
		(fill yes)
		(layer "In11.Cu")
		(net "M_F_CPU1_SB_DQ<24>")
	)
	(gr_poly
		(pts
			(xy 83.040982 -288.464498) (xy 83.040982 -288.420048) (xy 82.84083 -288.420048) (xy 82.84083 -288.464498)
			(xy 82.940906 -288.564574)
		)
		(stroke
			(width 0)
			(type solid)
		)
		(fill yes)
		(layer "In11.Cu")
		(net "M_F_CPU1_SB_DQ<23>")
	)
	(gr_poly
		(pts
			(xy 83.040982 -287.248092) (xy 82.940906 -287.148016) (xy 82.84083 -287.248092) (xy 82.84083 -287.292542)
			(xy 83.040982 -287.292542)
		)
		(stroke
			(width 0)
			(type solid)
		)
		(fill yes)
		(layer "In11.Cu")
		(net "M_F_CPU1_SB_DQ<20>")
	)
	(gr_poly
		(pts
			(xy 83.040982 -286.844486) (xy 83.040982 -286.796734) (xy 82.84083 -286.796734) (xy 82.84083 -286.844486)
			(xy 82.940906 -286.944562)
		)
		(stroke
			(width 0)
			(type solid)
		)
		(fill yes)
		(layer "In11.Cu")
		(net "M_F_CPU1_SB_DQS_DP<7>")
	)
	(gr_poly
		(pts
			(xy 83.040982 -285.62808) (xy 82.940906 -285.528258) (xy 82.84083 -285.62808) (xy 82.84083 -285.675832)
			(xy 83.040982 -285.675832)
		)
		(stroke
			(width 0)
			(type solid)
		)
		(fill yes)
		(layer "In11.Cu")
		(net "M_F_CPU1_SB_DQS_DP<2>")
	)
	(gr_poly
		(pts
			(xy 83.040982 -285.224474) (xy 83.040982 -285.180024) (xy 82.84083 -285.180024) (xy 82.84083 -285.224474)
			(xy 82.940906 -285.32455)
		)
		(stroke
			(width 0)
			(type solid)
		)
		(fill yes)
		(layer "In11.Cu")
		(net "M_F_CPU1_SB_DQ<19>")
	)
	(gr_poly
		(pts
			(xy 83.040982 -284.008322) (xy 82.940906 -283.908246) (xy 82.84083 -284.008322) (xy 82.84083 -284.052772)
			(xy 83.040982 -284.052772)
		)
		(stroke
			(width 0)
			(type solid)
		)
		(fill yes)
		(layer "In11.Cu")
		(net "M_F_CPU1_SB_DQ<16>")
	)
	(gr_poly
		(pts
			(xy 83.040982 -283.604462) (xy 83.040982 -283.560012) (xy 82.84083 -283.560012) (xy 82.84083 -283.604462)
			(xy 82.940906 -283.704538)
		)
		(stroke
			(width 0)
			(type solid)
		)
		(fill yes)
		(layer "In11.Cu")
		(net "M_F_CPU1_SB_DQ<15>")
	)
	(gr_poly
		(pts
			(xy 83.040982 -282.38831) (xy 82.940906 -282.288234) (xy 82.84083 -282.38831) (xy 82.84083 -282.43276)
			(xy 83.040982 -282.43276)
		)
		(stroke
			(width 0)
			(type solid)
		)
		(fill yes)
		(layer "In11.Cu")
		(net "M_F_CPU1_SB_DQ<12>")
	)
	(gr_poly
		(pts
			(xy 83.040982 -281.984704) (xy 83.040982 -281.936952) (xy 82.84083 -281.936952) (xy 82.84083 -281.984704)
			(xy 82.940906 -282.084526)
		)
		(stroke
			(width 0)
			(type solid)
		)
		(fill yes)
		(layer "In11.Cu")
		(net "M_F_CPU1_SB_DQS_DP<6>")
	)
	(gr_poly
		(pts
			(xy 83.040982 -280.768044) (xy 82.940906 -280.668222) (xy 82.84083 -280.768044) (xy 82.84083 -280.815796)
			(xy 83.040982 -280.815796)
		)
		(stroke
			(width 0)
			(type solid)
		)
		(fill yes)
		(layer "In11.Cu")
		(net "M_F_CPU1_SB_DQS_DP<1>")
	)
	(gr_poly
		(pts
			(xy 83.040982 -280.364438) (xy 83.040982 -280.319988) (xy 82.84083 -280.319988) (xy 82.84083 -280.364438)
			(xy 82.940906 -280.464514)
		)
		(stroke
			(width 0)
			(type solid)
		)
		(fill yes)
		(layer "In11.Cu")
		(net "M_F_CPU1_SB_DQ<11>")
	)
	(gr_poly
		(pts
			(xy 83.040982 -279.148286) (xy 82.940906 -279.04821) (xy 82.84083 -279.148286) (xy 82.84083 -279.192736)
			(xy 83.040982 -279.192736)
		)
		(stroke
			(width 0)
			(type solid)
		)
		(fill yes)
		(layer "In11.Cu")
		(net "M_F_CPU1_SB_DQ<8>")
	)
	(gr_poly
		(pts
			(xy 83.040982 -278.744426) (xy 83.040982 -278.699976) (xy 82.84083 -278.699976) (xy 82.84083 -278.744426)
			(xy 82.940906 -278.844502)
		)
		(stroke
			(width 0)
			(type solid)
		)
		(fill yes)
		(layer "In11.Cu")
		(net "M_F_CPU1_SB_DQ<7>")
	)
	(gr_poly
		(pts
			(xy 83.040982 -277.528274) (xy 82.940906 -277.428198) (xy 82.84083 -277.528274) (xy 82.84083 -277.572724)
			(xy 83.040982 -277.572724)
		)
		(stroke
			(width 0)
			(type solid)
		)
		(fill yes)
		(layer "In11.Cu")
		(net "M_F_CPU1_SB_DQ<4>")
	)
	(gr_poly
		(pts
			(xy 83.040982 -277.124668) (xy 83.040982 -277.076916) (xy 82.84083 -277.076916) (xy 82.84083 -277.124668)
			(xy 82.940906 -277.22449)
		)
		(stroke
			(width 0)
			(type solid)
		)
		(fill yes)
		(layer "In11.Cu")
		(net "M_F_CPU1_SB_DQS_DP<5>")
	)
	(gr_poly
		(pts
			(xy 83.040982 -275.908008) (xy 82.940906 -275.808186) (xy 82.84083 -275.908008) (xy 82.84083 -275.95576)
			(xy 83.040982 -275.95576)
		)
		(stroke
			(width 0)
			(type solid)
		)
		(fill yes)
		(layer "In11.Cu")
		(net "M_F_CPU1_SB_DQS_DP<0>")
	)
	(gr_poly
		(pts
			(xy 83.040982 -275.504402) (xy 83.040982 -275.459952) (xy 82.84083 -275.459952) (xy 82.84083 -275.504402)
			(xy 82.940906 -275.604478)
		)
		(stroke
			(width 0)
			(type solid)
		)
		(fill yes)
		(layer "In11.Cu")
		(net "M_F_CPU1_SB_DQ<3>")
	)
	(gr_poly
		(pts
			(xy 83.040982 -274.28825) (xy 82.940906 -274.188174) (xy 82.84083 -274.28825) (xy 82.84083 -274.3327)
			(xy 83.040982 -274.3327)
		)
		(stroke
			(width 0)
			(type solid)
		)
		(fill yes)
		(layer "In11.Cu")
		(net "M_F_CPU1_SB_DQ<0>")
	)
	(gr_poly
		(pts
			(xy 83.040982 -273.88439) (xy 83.040982 -273.83994) (xy 82.84083 -273.83994) (xy 82.84083 -273.88439)
			(xy 82.940906 -273.984466)
		)
		(stroke
			(width 0)
			(type solid)
		)
		(fill yes)
		(layer "In11.Cu")
		(net "M_F_CPU1_SB_CB<3>")
	)
	(gr_poly
		(pts
			(xy 83.040982 -272.668238) (xy 82.940906 -272.568162) (xy 82.84083 -272.668238) (xy 82.84083 -272.712688)
			(xy 83.040982 -272.712688)
		)
		(stroke
			(width 0)
			(type solid)
		)
		(fill yes)
		(layer "In11.Cu")
		(net "M_F_CPU1_SB_CB<0>")
	)
	(gr_poly
		(pts
			(xy 83.040982 -272.264632) (xy 83.040982 -272.21688) (xy 82.84083 -272.21688) (xy 82.84083 -272.264632)
			(xy 82.940906 -272.364454)
		)
		(stroke
			(width 0)
			(type solid)
		)
		(fill yes)
		(layer "In11.Cu")
		(net "M_F_CPU1_SB_DQS_DP<4>")
	)
	(gr_poly
		(pts
			(xy 83.040982 -271.047972) (xy 82.940906 -270.94815) (xy 82.84083 -271.047972) (xy 82.84083 -271.095724)
			(xy 83.040982 -271.095724)
		)
		(stroke
			(width 0)
			(type solid)
		)
		(fill yes)
		(layer "In11.Cu")
		(net "M_F_CPU1_SB_DQS_DP<9>")
	)
	(gr_poly
		(pts
			(xy 83.040982 -270.644366) (xy 83.040982 -270.599916) (xy 82.84083 -270.599916) (xy 82.84083 -270.644366)
			(xy 82.940906 -270.744442)
		)
		(stroke
			(width 0)
			(type solid)
		)
		(fill yes)
		(layer "In11.Cu")
		(net "M_F_CPU1_SB_CB<7>")
	)
	(gr_poly
		(pts
			(xy 83.040982 -269.428214) (xy 82.940906 -269.328138) (xy 82.84083 -269.428214) (xy 82.84083 -269.472664)
			(xy 83.040982 -269.472664)
		)
		(stroke
			(width 0)
			(type solid)
		)
		(fill yes)
		(layer "In11.Cu")
		(net "M_F_CPU1_SB_CB<4>")
	)
	(gr_poly
		(pts
			(xy 83.040982 -264.164318) (xy 83.040982 -264.119868) (xy 82.84083 -264.119868) (xy 82.84083 -264.164318)
			(xy 82.940906 -264.264394)
		)
		(stroke
			(width 0)
			(type solid)
		)
		(fill yes)
		(layer "In11.Cu")
		(net "M_F_CPU1_SB_CA<5>")
	)
	(gr_poly
		(pts
			(xy 83.040982 -262.948166) (xy 82.940906 -262.84809) (xy 82.84083 -262.948166) (xy 82.84083 -262.992616)
			(xy 83.040982 -262.992616)
		)
		(stroke
			(width 0)
			(type solid)
		)
		(fill yes)
		(layer "In11.Cu")
		(net "M_F_CPU1_SB_CA<2>")
	)
	(gr_poly
		(pts
			(xy 83.040982 -262.544306) (xy 83.040982 -262.499856) (xy 82.84083 -262.499856) (xy 82.84083 -262.544306)
			(xy 82.940906 -262.644382)
		)
		(stroke
			(width 0)
			(type solid)
		)
		(fill yes)
		(layer "In11.Cu")
		(net "M_F_CPU1_SB_CA<1>")
	)
	(gr_poly
		(pts
			(xy 83.041236 -267.808202) (xy 82.94116 -267.708126) (xy 82.841084 -267.808202) (xy 82.841084 -267.852652)
			(xy 83.041236 -267.852652)
		)
		(stroke
			(width 0)
			(type solid)
		)
		(fill yes)
		(layer "In11.Cu")
		(net "M_F_CPU1_SB_RSP<0>")
	)
	(gr_poly
		(pts
			(xy 83.041236 -265.78433) (xy 83.041236 -265.73988) (xy 82.841084 -265.73988) (xy 82.841084 -265.78433)
			(xy 82.94116 -265.884406)
		)
		(stroke
			(width 0)
			(type solid)
		)
		(fill yes)
		(layer "In11.Cu")
		(net "M_F_CPU1_SB_CS_N<0>")
	)
	(gr_poly
		(pts
			(xy 83.041236 -264.568178) (xy 82.94116 -264.468102) (xy 82.841084 -264.568178) (xy 82.841084 -264.612628)
			(xy 83.041236 -264.612628)
		)
		(stroke
			(width 0)
			(type solid)
		)
		(fill yes)
		(layer "In11.Cu")
		(net "M_F_CPU1_SB_CA<6>")
	)
	(gr_poly
		(pts
			(xy 83.211162 -256.026158) (xy 83.111086 -255.926336) (xy 83.01101 -256.026158) (xy 83.01101 -256.07391)
			(xy 83.211162 -256.07391)
		)
		(stroke
			(width 0)
			(type solid)
		)
		(fill yes)
		(layer "In11.Cu")
		(net "M_F_CPU1_CLK_DP<0>")
	)
	(gr_poly
		(pts
			(xy 83.211162 -255.622552) (xy 83.211162 -255.578102) (xy 83.01101 -255.578102) (xy 83.01101 -255.622552)
			(xy 83.111086 -255.722628)
		)
		(stroke
			(width 0)
			(type solid)
		)
		(fill yes)
		(layer "In11.Cu")
		(net "M_F_CPU1_SA_PAR")
	)
	(gr_poly
		(pts
			(xy 83.211162 -254.4064) (xy 83.111086 -254.306324) (xy 83.01101 -254.4064) (xy 83.01101 -254.45085)
			(xy 83.211162 -254.45085)
		)
		(stroke
			(width 0)
			(type solid)
		)
		(fill yes)
		(layer "In11.Cu")
		(net "M_F_CPU1_SA_CA<4>")
	)
	(gr_poly
		(pts
			(xy 83.211162 -254.00254) (xy 83.211162 -253.95809) (xy 83.01101 -253.95809) (xy 83.01101 -254.00254)
			(xy 83.111086 -254.102616)
		)
		(stroke
			(width 0)
			(type solid)
		)
		(fill yes)
		(layer "In11.Cu")
		(net "M_F_CPU1_SA_CA<3>")
	)
	(gr_poly
		(pts
			(xy 83.211162 -252.786388) (xy 83.111086 -252.686312) (xy 83.01101 -252.786388) (xy 83.01101 -252.830838)
			(xy 83.211162 -252.830838)
		)
		(stroke
			(width 0)
			(type solid)
		)
		(fill yes)
		(layer "In11.Cu")
		(net "M_F_CPU1_SA_CA<0>")
	)
	(gr_poly
		(pts
			(xy 83.211162 -252.382528) (xy 83.211162 -252.338078) (xy 83.01101 -252.338078) (xy 83.01101 -252.382528)
			(xy 83.111086 -252.482604)
		)
		(stroke
			(width 0)
			(type solid)
		)
		(fill yes)
		(layer "In11.Cu")
		(net "M_F_CPU1_SA_CS_N<1>")
	)
	(gr_poly
		(pts
			(xy 83.211162 -250.762516) (xy 83.211162 -250.718066) (xy 83.01101 -250.718066) (xy 83.01101 -250.762516)
			(xy 83.111086 -250.862592)
		)
		(stroke
			(width 0)
			(type solid)
		)
		(fill yes)
		(layer "In11.Cu")
		(net "M_F_CPU1_RESET_N")
	)
	(gr_poly
		(pts
			(xy 83.211162 -249.142504) (xy 83.211162 -249.098054) (xy 83.01101 -249.098054) (xy 83.01101 -249.142504)
			(xy 83.111086 -249.24258)
		)
		(stroke
			(width 0)
			(type solid)
		)
		(fill yes)
		(layer "In11.Cu")
		(net "M_F_CPU1_SA_CB<7>")
	)
	(gr_poly
		(pts
			(xy 83.211162 -247.926352) (xy 83.111086 -247.826276) (xy 83.01101 -247.926352) (xy 83.01101 -247.970802)
			(xy 83.211162 -247.970802)
		)
		(stroke
			(width 0)
			(type solid)
		)
		(fill yes)
		(layer "In11.Cu")
		(net "M_F_CPU1_SA_CB<4>")
	)
	(gr_poly
		(pts
			(xy 83.211162 -247.522746) (xy 83.211162 -247.474994) (xy 83.01101 -247.474994) (xy 83.01101 -247.522746)
			(xy 83.111086 -247.622568)
		)
		(stroke
			(width 0)
			(type solid)
		)
		(fill yes)
		(layer "In11.Cu")
		(net "M_F_CPU1_SA_DQS_DP<9>")
	)
	(gr_poly
		(pts
			(xy 83.211162 -246.306086) (xy 83.111086 -246.206264) (xy 83.01101 -246.306086) (xy 83.01101 -246.353838)
			(xy 83.211162 -246.353838)
		)
		(stroke
			(width 0)
			(type solid)
		)
		(fill yes)
		(layer "In11.Cu")
		(net "M_F_CPU1_SA_DQS_DP<4>")
	)
	(gr_poly
		(pts
			(xy 83.211162 -245.90248) (xy 83.211162 -245.85803) (xy 83.01101 -245.85803) (xy 83.01101 -245.90248)
			(xy 83.111086 -246.002556)
		)
		(stroke
			(width 0)
			(type solid)
		)
		(fill yes)
		(layer "In11.Cu")
		(net "M_F_CPU1_SA_CB<3>")
	)
	(gr_poly
		(pts
			(xy 83.211162 -244.686328) (xy 83.111086 -244.586252) (xy 83.01101 -244.686328) (xy 83.01101 -244.730778)
			(xy 83.211162 -244.730778)
		)
		(stroke
			(width 0)
			(type solid)
		)
		(fill yes)
		(layer "In11.Cu")
		(net "M_F_CPU1_SA_CB<0>")
	)
	(gr_poly
		(pts
			(xy 83.211162 -244.282468) (xy 83.211162 -244.238018) (xy 83.01101 -244.238018) (xy 83.01101 -244.282468)
			(xy 83.111086 -244.382544)
		)
		(stroke
			(width 0)
			(type solid)
		)
		(fill yes)
		(layer "In11.Cu")
		(net "M_F_CPU1_SA_DQ<31>")
	)
	(gr_poly
		(pts
			(xy 83.211162 -243.066316) (xy 83.111086 -242.96624) (xy 83.01101 -243.066316) (xy 83.01101 -243.110766)
			(xy 83.211162 -243.110766)
		)
		(stroke
			(width 0)
			(type solid)
		)
		(fill yes)
		(layer "In11.Cu")
		(net "M_F_CPU1_SA_DQ<28>")
	)
	(gr_poly
		(pts
			(xy 83.211162 -242.66271) (xy 83.211162 -242.614958) (xy 83.01101 -242.614958) (xy 83.01101 -242.66271)
			(xy 83.111086 -242.762532)
		)
		(stroke
			(width 0)
			(type solid)
		)
		(fill yes)
		(layer "In11.Cu")
		(net "M_F_CPU1_SA_DQS_DP<8>")
	)
	(gr_poly
		(pts
			(xy 83.211162 -241.44605) (xy 83.111086 -241.346228) (xy 83.01101 -241.44605) (xy 83.01101 -241.493802)
			(xy 83.211162 -241.493802)
		)
		(stroke
			(width 0)
			(type solid)
		)
		(fill yes)
		(layer "In11.Cu")
		(net "M_F_CPU1_SA_DQS_DP<3>")
	)
	(gr_poly
		(pts
			(xy 83.211162 -241.042444) (xy 83.211162 -240.997994) (xy 83.01101 -240.997994) (xy 83.01101 -241.042444)
			(xy 83.111086 -241.14252)
		)
		(stroke
			(width 0)
			(type solid)
		)
		(fill yes)
		(layer "In11.Cu")
		(net "M_F_CPU1_SA_DQ<27>")
	)
	(gr_poly
		(pts
			(xy 83.211162 -239.826292) (xy 83.111086 -239.726216) (xy 83.01101 -239.826292) (xy 83.01101 -239.870742)
			(xy 83.211162 -239.870742)
		)
		(stroke
			(width 0)
			(type solid)
		)
		(fill yes)
		(layer "In11.Cu")
		(net "M_F_CPU1_SA_DQ<24>")
	)
	(gr_poly
		(pts
			(xy 83.211162 -239.422432) (xy 83.211162 -239.377982) (xy 83.01101 -239.377982) (xy 83.01101 -239.422432)
			(xy 83.111086 -239.522508)
		)
		(stroke
			(width 0)
			(type solid)
		)
		(fill yes)
		(layer "In11.Cu")
		(net "M_F_CPU1_SA_DQ<23>")
	)
	(gr_poly
		(pts
			(xy 83.211162 -238.20628) (xy 83.111086 -238.106204) (xy 83.01101 -238.20628) (xy 83.01101 -238.25073)
			(xy 83.211162 -238.25073)
		)
		(stroke
			(width 0)
			(type solid)
		)
		(fill yes)
		(layer "In11.Cu")
		(net "M_F_CPU1_SA_DQ<20>")
	)
	(gr_poly
		(pts
			(xy 83.211162 -237.802674) (xy 83.211162 -237.754922) (xy 83.01101 -237.754922) (xy 83.01101 -237.802674)
			(xy 83.111086 -237.902496)
		)
		(stroke
			(width 0)
			(type solid)
		)
		(fill yes)
		(layer "In11.Cu")
		(net "M_F_CPU1_SA_DQS_DP<7>")
	)
	(gr_poly
		(pts
			(xy 83.211162 -236.586014) (xy 83.111086 -236.486192) (xy 83.01101 -236.586014) (xy 83.01101 -236.633766)
			(xy 83.211162 -236.633766)
		)
		(stroke
			(width 0)
			(type solid)
		)
		(fill yes)
		(layer "In11.Cu")
		(net "M_F_CPU1_SA_DQS_DP<2>")
	)
	(gr_poly
		(pts
			(xy 83.211162 -236.182408) (xy 83.211162 -236.137958) (xy 83.01101 -236.137958) (xy 83.01101 -236.182408)
			(xy 83.111086 -236.282484)
		)
		(stroke
			(width 0)
			(type solid)
		)
		(fill yes)
		(layer "In11.Cu")
		(net "M_F_CPU1_SA_DQ<19>")
	)
	(gr_poly
		(pts
			(xy 83.211162 -234.966256) (xy 83.111086 -234.86618) (xy 83.01101 -234.966256) (xy 83.01101 -235.010706)
			(xy 83.211162 -235.010706)
		)
		(stroke
			(width 0)
			(type solid)
		)
		(fill yes)
		(layer "In11.Cu")
		(net "M_F_CPU1_SA_DQ<16>")
	)
	(gr_poly
		(pts
			(xy 83.211162 -234.562396) (xy 83.211162 -234.517946) (xy 83.01101 -234.517946) (xy 83.01101 -234.562396)
			(xy 83.111086 -234.662472)
		)
		(stroke
			(width 0)
			(type solid)
		)
		(fill yes)
		(layer "In11.Cu")
		(net "M_F_CPU1_SA_DQ<15>")
	)
	(gr_poly
		(pts
			(xy 83.211162 -233.346244) (xy 83.111086 -233.246168) (xy 83.01101 -233.346244) (xy 83.01101 -233.390694)
			(xy 83.211162 -233.390694)
		)
		(stroke
			(width 0)
			(type solid)
		)
		(fill yes)
		(layer "In11.Cu")
		(net "M_F_CPU1_SA_DQ<12>")
	)
	(gr_poly
		(pts
			(xy 83.211162 -232.942638) (xy 83.211162 -232.894886) (xy 83.01101 -232.894886) (xy 83.01101 -232.942638)
			(xy 83.111086 -233.04246)
		)
		(stroke
			(width 0)
			(type solid)
		)
		(fill yes)
		(layer "In11.Cu")
		(net "M_F_CPU1_SA_DQS_DP<6>")
	)
	(gr_poly
		(pts
			(xy 83.211162 -231.725978) (xy 83.111086 -231.626156) (xy 83.01101 -231.725978) (xy 83.01101 -231.77373)
			(xy 83.211162 -231.77373)
		)
		(stroke
			(width 0)
			(type solid)
		)
		(fill yes)
		(layer "In11.Cu")
		(net "M_F_CPU1_SA_DQS_DP<1>")
	)
	(gr_poly
		(pts
			(xy 83.211162 -231.322626) (xy 83.211162 -231.278176) (xy 83.01101 -231.278176) (xy 83.01101 -231.322626)
			(xy 83.111086 -231.422702)
		)
		(stroke
			(width 0)
			(type solid)
		)
		(fill yes)
		(layer "In11.Cu")
		(net "M_F_CPU1_SA_DQ<11>")
	)
	(gr_poly
		(pts
			(xy 83.211162 -230.10622) (xy 83.111086 -230.006144) (xy 83.01101 -230.10622) (xy 83.01101 -230.15067)
			(xy 83.211162 -230.15067)
		)
		(stroke
			(width 0)
			(type solid)
		)
		(fill yes)
		(layer "In11.Cu")
		(net "M_F_CPU1_SA_DQ<8>")
	)
	(gr_poly
		(pts
			(xy 83.211162 -229.702614) (xy 83.211162 -229.658164) (xy 83.01101 -229.658164) (xy 83.01101 -229.702614)
			(xy 83.111086 -229.80269)
		)
		(stroke
			(width 0)
			(type solid)
		)
		(fill yes)
		(layer "In11.Cu")
		(net "M_F_CPU1_SA_DQ<7>")
	)
	(gr_poly
		(pts
			(xy 83.211162 -228.486462) (xy 83.111086 -228.386386) (xy 83.01101 -228.486462) (xy 83.01101 -228.530912)
			(xy 83.211162 -228.530912)
		)
		(stroke
			(width 0)
			(type solid)
		)
		(fill yes)
		(layer "In11.Cu")
		(net "M_F_CPU1_SA_DQ<4>")
	)
	(gr_poly
		(pts
			(xy 83.211162 -228.082856) (xy 83.211162 -228.035104) (xy 83.01101 -228.035104) (xy 83.01101 -228.082856)
			(xy 83.111086 -228.182678)
		)
		(stroke
			(width 0)
			(type solid)
		)
		(fill yes)
		(layer "In11.Cu")
		(net "M_F_CPU1_SA_DQS_DP<5>")
	)
	(gr_poly
		(pts
			(xy 83.211162 -226.866196) (xy 83.111086 -226.766374) (xy 83.01101 -226.866196) (xy 83.01101 -226.913948)
			(xy 83.211162 -226.913948)
		)
		(stroke
			(width 0)
			(type solid)
		)
		(fill yes)
		(layer "In11.Cu")
		(net "M_F_CPU1_SA_DQS_DP<0>")
	)
	(gr_poly
		(pts
			(xy 83.211162 -226.46259) (xy 83.211162 -226.41814) (xy 83.01101 -226.41814) (xy 83.01101 -226.46259)
			(xy 83.111086 -226.562666)
		)
		(stroke
			(width 0)
			(type solid)
		)
		(fill yes)
		(layer "In11.Cu")
		(net "M_F_CPU1_SA_DQ<3>")
	)
	(gr_poly
		(pts
			(xy 83.211162 -225.246438) (xy 83.111086 -225.146362) (xy 83.01101 -225.246438) (xy 83.01101 -225.290888)
			(xy 83.211162 -225.290888)
		)
		(stroke
			(width 0)
			(type solid)
		)
		(fill yes)
		(layer "In11.Cu")
		(net "M_F_CPU1_SA_DQ<0>")
	)
	(gr_poly
		(pts
			(xy 83.511136 -292.918134) (xy 83.41106 -292.818058) (xy 83.310984 -292.918134) (xy 83.310984 -292.962584)
			(xy 83.511136 -292.962584)
		)
		(stroke
			(width 0)
			(type solid)
		)
		(fill yes)
		(layer "In11.Cu")
		(net "M_F_CPU1_SB_DQ<29>")
	)
	(gr_poly
		(pts
			(xy 83.511136 -292.514274) (xy 83.511136 -292.469824) (xy 83.310984 -292.469824) (xy 83.310984 -292.514274)
			(xy 83.41106 -292.61435)
		)
		(stroke
			(width 0)
			(type solid)
		)
		(fill yes)
		(layer "In11.Cu")
		(net "M_F_CPU1_SB_DQ<30>")
	)
	(gr_poly
		(pts
			(xy 83.511136 -291.297868) (xy 83.41106 -291.198046) (xy 83.310984 -291.297868) (xy 83.310984 -291.34562)
			(xy 83.511136 -291.34562)
		)
		(stroke
			(width 0)
			(type solid)
		)
		(fill yes)
		(layer "In11.Cu")
		(net "M_F_CPU1_SB_DQS_DN<8>")
	)
	(gr_poly
		(pts
			(xy 83.511136 -290.894516) (xy 83.511136 -290.846764) (xy 83.310984 -290.846764) (xy 83.310984 -290.894516)
			(xy 83.41106 -290.994338)
		)
		(stroke
			(width 0)
			(type solid)
		)
		(fill yes)
		(layer "In11.Cu")
		(net "M_F_CPU1_SB_DQS_DN<3>")
	)
	(gr_poly
		(pts
			(xy 83.511136 -289.67811) (xy 83.41106 -289.578034) (xy 83.310984 -289.67811) (xy 83.310984 -289.72256)
			(xy 83.511136 -289.72256)
		)
		(stroke
			(width 0)
			(type solid)
		)
		(fill yes)
		(layer "In11.Cu")
		(net "M_F_CPU1_SB_DQ<25>")
	)
	(gr_poly
		(pts
			(xy 83.511136 -289.27425) (xy 83.511136 -289.2298) (xy 83.310984 -289.2298) (xy 83.310984 -289.27425)
			(xy 83.41106 -289.374326)
		)
		(stroke
			(width 0)
			(type solid)
		)
		(fill yes)
		(layer "In11.Cu")
		(net "M_F_CPU1_SB_DQ<26>")
	)
	(gr_poly
		(pts
			(xy 83.511136 -288.058098) (xy 83.41106 -287.958022) (xy 83.310984 -288.058098) (xy 83.310984 -288.102548)
			(xy 83.511136 -288.102548)
		)
		(stroke
			(width 0)
			(type solid)
		)
		(fill yes)
		(layer "In11.Cu")
		(net "M_F_CPU1_SB_DQ<21>")
	)
	(gr_poly
		(pts
			(xy 83.511136 -287.654492) (xy 83.511136 -287.610042) (xy 83.310984 -287.610042) (xy 83.310984 -287.654492)
			(xy 83.41106 -287.754568)
		)
		(stroke
			(width 0)
			(type solid)
		)
		(fill yes)
		(layer "In11.Cu")
		(net "M_F_CPU1_SB_DQ<22>")
	)
	(gr_poly
		(pts
			(xy 83.511136 -286.438086) (xy 83.41106 -286.33801) (xy 83.310984 -286.438086) (xy 83.310984 -286.485838)
			(xy 83.511136 -286.485838)
		)
		(stroke
			(width 0)
			(type solid)
		)
		(fill yes)
		(layer "In11.Cu")
		(net "M_F_CPU1_SB_DQS_DN<7>")
	)
	(gr_poly
		(pts
			(xy 83.511136 -286.034734) (xy 83.511136 -285.986982) (xy 83.310984 -285.986982) (xy 83.310984 -286.034734)
			(xy 83.41106 -286.134556)
		)
		(stroke
			(width 0)
			(type solid)
		)
		(fill yes)
		(layer "In11.Cu")
		(net "M_F_CPU1_SB_DQS_DN<2>")
	)
	(gr_poly
		(pts
			(xy 83.511136 -284.818328) (xy 83.41106 -284.718252) (xy 83.310984 -284.818328) (xy 83.310984 -284.862778)
			(xy 83.511136 -284.862778)
		)
		(stroke
			(width 0)
			(type solid)
		)
		(fill yes)
		(layer "In11.Cu")
		(net "M_F_CPU1_SB_DQ<17>")
	)
	(gr_poly
		(pts
			(xy 83.511136 -284.414468) (xy 83.511136 -284.370018) (xy 83.310984 -284.370018) (xy 83.310984 -284.414468)
			(xy 83.41106 -284.514544)
		)
		(stroke
			(width 0)
			(type solid)
		)
		(fill yes)
		(layer "In11.Cu")
		(net "M_F_CPU1_SB_DQ<18>")
	)
	(gr_poly
		(pts
			(xy 83.511136 -283.198316) (xy 83.41106 -283.09824) (xy 83.310984 -283.198316) (xy 83.310984 -283.242766)
			(xy 83.511136 -283.242766)
		)
		(stroke
			(width 0)
			(type solid)
		)
		(fill yes)
		(layer "In11.Cu")
		(net "M_F_CPU1_SB_DQ<13>")
	)
	(gr_poly
		(pts
			(xy 83.511136 -282.794456) (xy 83.511136 -282.750006) (xy 83.310984 -282.750006) (xy 83.310984 -282.794456)
			(xy 83.41106 -282.894532)
		)
		(stroke
			(width 0)
			(type solid)
		)
		(fill yes)
		(layer "In11.Cu")
		(net "M_F_CPU1_SB_DQ<14>")
	)
	(gr_poly
		(pts
			(xy 83.511136 -281.57805) (xy 83.41106 -281.478228) (xy 83.310984 -281.57805) (xy 83.310984 -281.625802)
			(xy 83.511136 -281.625802)
		)
		(stroke
			(width 0)
			(type solid)
		)
		(fill yes)
		(layer "In11.Cu")
		(net "M_F_CPU1_SB_DQS_DN<6>")
	)
	(gr_poly
		(pts
			(xy 83.511136 -281.174698) (xy 83.511136 -281.126946) (xy 83.310984 -281.126946) (xy 83.310984 -281.174698)
			(xy 83.41106 -281.27452)
		)
		(stroke
			(width 0)
			(type solid)
		)
		(fill yes)
		(layer "In11.Cu")
		(net "M_F_CPU1_SB_DQS_DN<1>")
	)
	(gr_poly
		(pts
			(xy 83.511136 -279.958292) (xy 83.41106 -279.858216) (xy 83.310984 -279.958292) (xy 83.310984 -280.002742)
			(xy 83.511136 -280.002742)
		)
		(stroke
			(width 0)
			(type solid)
		)
		(fill yes)
		(layer "In11.Cu")
		(net "M_F_CPU1_SB_DQ<9>")
	)
	(gr_poly
		(pts
			(xy 83.511136 -279.554432) (xy 83.511136 -279.509982) (xy 83.310984 -279.509982) (xy 83.310984 -279.554432)
			(xy 83.41106 -279.654508)
		)
		(stroke
			(width 0)
			(type solid)
		)
		(fill yes)
		(layer "In11.Cu")
		(net "M_F_CPU1_SB_DQ<10>")
	)
	(gr_poly
		(pts
			(xy 83.511136 -278.33828) (xy 83.41106 -278.238204) (xy 83.310984 -278.33828) (xy 83.310984 -278.38273)
			(xy 83.511136 -278.38273)
		)
		(stroke
			(width 0)
			(type solid)
		)
		(fill yes)
		(layer "In11.Cu")
		(net "M_F_CPU1_SB_DQ<5>")
	)
	(gr_poly
		(pts
			(xy 83.511136 -277.93442) (xy 83.511136 -277.88997) (xy 83.310984 -277.88997) (xy 83.310984 -277.93442)
			(xy 83.41106 -278.034496)
		)
		(stroke
			(width 0)
			(type solid)
		)
		(fill yes)
		(layer "In11.Cu")
		(net "M_F_CPU1_SB_DQ<6>")
	)
	(gr_poly
		(pts
			(xy 83.511136 -276.718014) (xy 83.41106 -276.618192) (xy 83.310984 -276.718014) (xy 83.310984 -276.765766)
			(xy 83.511136 -276.765766)
		)
		(stroke
			(width 0)
			(type solid)
		)
		(fill yes)
		(layer "In11.Cu")
		(net "M_F_CPU1_SB_DQS_DN<5>")
	)
	(gr_poly
		(pts
			(xy 83.511136 -276.314662) (xy 83.511136 -276.26691) (xy 83.310984 -276.26691) (xy 83.310984 -276.314662)
			(xy 83.41106 -276.414484)
		)
		(stroke
			(width 0)
			(type solid)
		)
		(fill yes)
		(layer "In11.Cu")
		(net "M_F_CPU1_SB_DQS_DN<0>")
	)
	(gr_poly
		(pts
			(xy 83.511136 -275.098256) (xy 83.41106 -274.99818) (xy 83.310984 -275.098256) (xy 83.310984 -275.142706)
			(xy 83.511136 -275.142706)
		)
		(stroke
			(width 0)
			(type solid)
		)
		(fill yes)
		(layer "In11.Cu")
		(net "M_F_CPU1_SB_DQ<1>")
	)
	(gr_poly
		(pts
			(xy 83.511136 -274.694396) (xy 83.511136 -274.649946) (xy 83.310984 -274.649946) (xy 83.310984 -274.694396)
			(xy 83.41106 -274.794472)
		)
		(stroke
			(width 0)
			(type solid)
		)
		(fill yes)
		(layer "In11.Cu")
		(net "M_F_CPU1_SB_DQ<2>")
	)
	(gr_poly
		(pts
			(xy 83.511136 -273.478244) (xy 83.41106 -273.378168) (xy 83.310984 -273.478244) (xy 83.310984 -273.522694)
			(xy 83.511136 -273.522694)
		)
		(stroke
			(width 0)
			(type solid)
		)
		(fill yes)
		(layer "In11.Cu")
		(net "M_F_CPU1_SB_CB<1>")
	)
	(gr_poly
		(pts
			(xy 83.511136 -273.074384) (xy 83.511136 -273.029934) (xy 83.310984 -273.029934) (xy 83.310984 -273.074384)
			(xy 83.41106 -273.17446)
		)
		(stroke
			(width 0)
			(type solid)
		)
		(fill yes)
		(layer "In11.Cu")
		(net "M_F_CPU1_SB_CB<2>")
	)
	(gr_poly
		(pts
			(xy 83.511136 -271.857978) (xy 83.41106 -271.758156) (xy 83.310984 -271.857978) (xy 83.310984 -271.90573)
			(xy 83.511136 -271.90573)
		)
		(stroke
			(width 0)
			(type solid)
		)
		(fill yes)
		(layer "In11.Cu")
		(net "M_F_CPU1_SB_DQS_DN<4>")
	)
	(gr_poly
		(pts
			(xy 83.511136 -271.454626) (xy 83.511136 -271.406874) (xy 83.310984 -271.406874) (xy 83.310984 -271.454626)
			(xy 83.41106 -271.554448)
		)
		(stroke
			(width 0)
			(type solid)
		)
		(fill yes)
		(layer "In11.Cu")
		(net "M_F_CPU1_SB_DQS_DN<9>")
	)
	(gr_poly
		(pts
			(xy 83.511136 -270.23822) (xy 83.41106 -270.138144) (xy 83.310984 -270.23822) (xy 83.310984 -270.28267)
			(xy 83.511136 -270.28267)
		)
		(stroke
			(width 0)
			(type solid)
		)
		(fill yes)
		(layer "In11.Cu")
		(net "M_F_CPU1_SB_CB<5>")
	)
	(gr_poly
		(pts
			(xy 83.511136 -269.83436) (xy 83.511136 -269.78991) (xy 83.310984 -269.78991) (xy 83.310984 -269.83436)
			(xy 83.41106 -269.934436)
		)
		(stroke
			(width 0)
			(type solid)
		)
		(fill yes)
		(layer "In11.Cu")
		(net "M_F_CPU1_SB_CB<6>")
	)
	(gr_poly
		(pts
			(xy 83.511136 -266.998196) (xy 83.41106 -266.89812) (xy 83.310984 -266.998196) (xy 83.310984 -267.042646)
			(xy 83.511136 -267.042646)
		)
		(stroke
			(width 0)
			(type solid)
		)
		(fill yes)
		(layer "In11.Cu")
		(net "M_F_CPU1_SA_RSP<0>")
	)
	(gr_poly
		(pts
			(xy 83.511136 -266.594336) (xy 83.511136 -266.549886) (xy 83.310984 -266.549886) (xy 83.310984 -266.594336)
			(xy 83.41106 -266.694412)
		)
		(stroke
			(width 0)
			(type solid)
		)
		(fill yes)
		(layer "In11.Cu")
		(net "M_F_CPU1_SB_CS_N<1>")
	)
	(gr_poly
		(pts
			(xy 83.511136 -264.974324) (xy 83.511136 -264.929874) (xy 83.310984 -264.929874) (xy 83.310984 -264.974324)
			(xy 83.41106 -265.0744)
		)
		(stroke
			(width 0)
			(type solid)
		)
		(fill yes)
		(layer "In11.Cu")
		(net "M_F_CPU1_SB_PAR")
	)
	(gr_poly
		(pts
			(xy 83.511136 -263.758172) (xy 83.41106 -263.658096) (xy 83.310984 -263.758172) (xy 83.310984 -263.802622)
			(xy 83.511136 -263.802622)
		)
		(stroke
			(width 0)
			(type solid)
		)
		(fill yes)
		(layer "In11.Cu")
		(net "M_F_CPU1_SB_CA<4>")
	)
	(gr_poly
		(pts
			(xy 83.511136 -263.354312) (xy 83.511136 -263.309862) (xy 83.310984 -263.309862) (xy 83.310984 -263.354312)
			(xy 83.41106 -263.454388)
		)
		(stroke
			(width 0)
			(type solid)
		)
		(fill yes)
		(layer "In11.Cu")
		(net "M_F_CPU1_SB_CA<3>")
	)
	(gr_poly
		(pts
			(xy 83.511136 -262.13816) (xy 83.41106 -262.038084) (xy 83.310984 -262.13816) (xy 83.310984 -262.18261)
			(xy 83.511136 -262.18261)
		)
		(stroke
			(width 0)
			(type solid)
		)
		(fill yes)
		(layer "In11.Cu")
		(net "M_F_CPU1_SB_CA<0>")
	)
	(gr_poly
		(pts
			(xy 83.681062 -256.432812) (xy 83.681062 -256.38506) (xy 83.48091 -256.38506) (xy 83.48091 -256.432812)
			(xy 83.580986 -256.532634)
		)
		(stroke
			(width 0)
			(type solid)
		)
		(fill yes)
		(layer "In11.Cu")
		(net "M_F_CPU1_CLK_DN<0>")
	)
	(gr_poly
		(pts
			(xy 83.681062 -255.216406) (xy 83.580986 -255.11633) (xy 83.48091 -255.216406) (xy 83.48091 -255.260856)
			(xy 83.681062 -255.260856)
		)
		(stroke
			(width 0)
			(type solid)
		)
		(fill yes)
		(layer "In11.Cu")
		(net "M_F_CPU1_SA_CA<6>")
	)
	(gr_poly
		(pts
			(xy 83.681062 -254.812546) (xy 83.681062 -254.768096) (xy 83.48091 -254.768096) (xy 83.48091 -254.812546)
			(xy 83.580986 -254.912622)
		)
		(stroke
			(width 0)
			(type solid)
		)
		(fill yes)
		(layer "In11.Cu")
		(net "M_F_CPU1_SA_CA<5>")
	)
	(gr_poly
		(pts
			(xy 83.681062 -253.596394) (xy 83.580986 -253.496318) (xy 83.48091 -253.596394) (xy 83.48091 -253.640844)
			(xy 83.681062 -253.640844)
		)
		(stroke
			(width 0)
			(type solid)
		)
		(fill yes)
		(layer "In11.Cu")
		(net "M_F_CPU1_SA_CA<2>")
	)
	(gr_poly
		(pts
			(xy 83.681062 -253.192534) (xy 83.681062 -253.148084) (xy 83.48091 -253.148084) (xy 83.48091 -253.192534)
			(xy 83.580986 -253.29261)
		)
		(stroke
			(width 0)
			(type solid)
		)
		(fill yes)
		(layer "In11.Cu")
		(net "M_F_CPU1_SA_CA<1>")
	)
	(gr_poly
		(pts
			(xy 83.681062 -251.572522) (xy 83.681062 -251.528072) (xy 83.48091 -251.528072) (xy 83.48091 -251.572522)
			(xy 83.580986 -251.672598)
		)
		(stroke
			(width 0)
			(type solid)
		)
		(fill yes)
		(layer "In11.Cu")
		(net "M_F_CPU1_SA_CS_N<0>")
	)
	(gr_poly
		(pts
			(xy 83.681062 -250.35637) (xy 83.580986 -250.256294) (xy 83.48091 -250.35637) (xy 83.48091 -250.40082)
			(xy 83.681062 -250.40082)
		)
		(stroke
			(width 0)
			(type solid)
		)
		(fill yes)
		(layer "In11.Cu")
		(net "M_F_CPU1_ALERT_R_N")
	)
	(gr_poly
		(pts
			(xy 83.681062 -248.736358) (xy 83.580986 -248.636282) (xy 83.48091 -248.736358) (xy 83.48091 -248.780808)
			(xy 83.681062 -248.780808)
		)
		(stroke
			(width 0)
			(type solid)
		)
		(fill yes)
		(layer "In11.Cu")
		(net "M_F_CPU1_SA_CB<5>")
	)
	(gr_poly
		(pts
			(xy 83.681062 -248.332498) (xy 83.681062 -248.288048) (xy 83.48091 -248.288048) (xy 83.48091 -248.332498)
			(xy 83.580986 -248.432574)
		)
		(stroke
			(width 0)
			(type solid)
		)
		(fill yes)
		(layer "In11.Cu")
		(net "M_F_CPU1_SA_CB<6>")
	)
	(gr_poly
		(pts
			(xy 83.681062 -247.116092) (xy 83.580986 -247.01627) (xy 83.48091 -247.116092) (xy 83.48091 -247.163844)
			(xy 83.681062 -247.163844)
		)
		(stroke
			(width 0)
			(type solid)
		)
		(fill yes)
		(layer "In11.Cu")
		(net "M_F_CPU1_SA_DQS_DN<9>")
	)
	(gr_poly
		(pts
			(xy 83.681062 -246.71274) (xy 83.681062 -246.664988) (xy 83.48091 -246.664988) (xy 83.48091 -246.71274)
			(xy 83.580986 -246.812562)
		)
		(stroke
			(width 0)
			(type solid)
		)
		(fill yes)
		(layer "In11.Cu")
		(net "M_F_CPU1_SA_DQS_DN<4>")
	)
	(gr_poly
		(pts
			(xy 83.681062 -245.496334) (xy 83.580986 -245.396258) (xy 83.48091 -245.496334) (xy 83.48091 -245.540784)
			(xy 83.681062 -245.540784)
		)
		(stroke
			(width 0)
			(type solid)
		)
		(fill yes)
		(layer "In11.Cu")
		(net "M_F_CPU1_SA_CB<1>")
	)
	(gr_poly
		(pts
			(xy 83.681062 -245.092474) (xy 83.681062 -245.048024) (xy 83.48091 -245.048024) (xy 83.48091 -245.092474)
			(xy 83.580986 -245.19255)
		)
		(stroke
			(width 0)
			(type solid)
		)
		(fill yes)
		(layer "In11.Cu")
		(net "M_F_CPU1_SA_CB<2>")
	)
	(gr_poly
		(pts
			(xy 83.681062 -243.876322) (xy 83.580986 -243.776246) (xy 83.48091 -243.876322) (xy 83.48091 -243.920772)
			(xy 83.681062 -243.920772)
		)
		(stroke
			(width 0)
			(type solid)
		)
		(fill yes)
		(layer "In11.Cu")
		(net "M_F_CPU1_SA_DQ<29>")
	)
	(gr_poly
		(pts
			(xy 83.681062 -243.472462) (xy 83.681062 -243.428012) (xy 83.48091 -243.428012) (xy 83.48091 -243.472462)
			(xy 83.580986 -243.572538)
		)
		(stroke
			(width 0)
			(type solid)
		)
		(fill yes)
		(layer "In11.Cu")
		(net "M_F_CPU1_SA_DQ<30>")
	)
	(gr_poly
		(pts
			(xy 83.681062 -242.256056) (xy 83.580986 -242.156234) (xy 83.48091 -242.256056) (xy 83.48091 -242.303808)
			(xy 83.681062 -242.303808)
		)
		(stroke
			(width 0)
			(type solid)
		)
		(fill yes)
		(layer "In11.Cu")
		(net "M_F_CPU1_SA_DQS_DN<8>")
	)
	(gr_poly
		(pts
			(xy 83.681062 -241.852704) (xy 83.681062 -241.804952) (xy 83.48091 -241.804952) (xy 83.48091 -241.852704)
			(xy 83.580986 -241.952526)
		)
		(stroke
			(width 0)
			(type solid)
		)
		(fill yes)
		(layer "In11.Cu")
		(net "M_F_CPU1_SA_DQS_DN<3>")
	)
	(gr_poly
		(pts
			(xy 83.681062 -240.636298) (xy 83.580986 -240.536222) (xy 83.48091 -240.636298) (xy 83.48091 -240.680748)
			(xy 83.681062 -240.680748)
		)
		(stroke
			(width 0)
			(type solid)
		)
		(fill yes)
		(layer "In11.Cu")
		(net "M_F_CPU1_SA_DQ<25>")
	)
	(gr_poly
		(pts
			(xy 83.681062 -240.232438) (xy 83.681062 -240.187988) (xy 83.48091 -240.187988) (xy 83.48091 -240.232438)
			(xy 83.580986 -240.332514)
		)
		(stroke
			(width 0)
			(type solid)
		)
		(fill yes)
		(layer "In11.Cu")
		(net "M_F_CPU1_SA_DQ<26>")
	)
	(gr_poly
		(pts
			(xy 83.681062 -239.016286) (xy 83.580986 -238.91621) (xy 83.48091 -239.016286) (xy 83.48091 -239.060736)
			(xy 83.681062 -239.060736)
		)
		(stroke
			(width 0)
			(type solid)
		)
		(fill yes)
		(layer "In11.Cu")
		(net "M_F_CPU1_SA_DQ<21>")
	)
	(gr_poly
		(pts
			(xy 83.681062 -238.612426) (xy 83.681062 -238.567976) (xy 83.48091 -238.567976) (xy 83.48091 -238.612426)
			(xy 83.580986 -238.712502)
		)
		(stroke
			(width 0)
			(type solid)
		)
		(fill yes)
		(layer "In11.Cu")
		(net "M_F_CPU1_SA_DQ<22>")
	)
	(gr_poly
		(pts
			(xy 83.681062 -237.39602) (xy 83.580986 -237.296198) (xy 83.48091 -237.39602) (xy 83.48091 -237.443772)
			(xy 83.681062 -237.443772)
		)
		(stroke
			(width 0)
			(type solid)
		)
		(fill yes)
		(layer "In11.Cu")
		(net "M_F_CPU1_SA_DQS_DN<7>")
	)
	(gr_poly
		(pts
			(xy 83.681062 -236.992668) (xy 83.681062 -236.944916) (xy 83.48091 -236.944916) (xy 83.48091 -236.992668)
			(xy 83.580986 -237.09249)
		)
		(stroke
			(width 0)
			(type solid)
		)
		(fill yes)
		(layer "In11.Cu")
		(net "M_F_CPU1_SA_DQS_DN<2>")
	)
	(gr_poly
		(pts
			(xy 83.681062 -235.776262) (xy 83.580986 -235.676186) (xy 83.48091 -235.776262) (xy 83.48091 -235.820712)
			(xy 83.681062 -235.820712)
		)
		(stroke
			(width 0)
			(type solid)
		)
		(fill yes)
		(layer "In11.Cu")
		(net "M_F_CPU1_SA_DQ<17>")
	)
	(gr_poly
		(pts
			(xy 83.681062 -235.372402) (xy 83.681062 -235.327952) (xy 83.48091 -235.327952) (xy 83.48091 -235.372402)
			(xy 83.580986 -235.472478)
		)
		(stroke
			(width 0)
			(type solid)
		)
		(fill yes)
		(layer "In11.Cu")
		(net "M_F_CPU1_SA_DQ<18>")
	)
	(gr_poly
		(pts
			(xy 83.681062 -234.15625) (xy 83.580986 -234.056174) (xy 83.48091 -234.15625) (xy 83.48091 -234.2007)
			(xy 83.681062 -234.2007)
		)
		(stroke
			(width 0)
			(type solid)
		)
		(fill yes)
		(layer "In11.Cu")
		(net "M_F_CPU1_SA_DQ<13>")
	)
	(gr_poly
		(pts
			(xy 83.681062 -233.75239) (xy 83.681062 -233.70794) (xy 83.48091 -233.70794) (xy 83.48091 -233.75239)
			(xy 83.580986 -233.852466)
		)
		(stroke
			(width 0)
			(type solid)
		)
		(fill yes)
		(layer "In11.Cu")
		(net "M_F_CPU1_SA_DQ<14>")
	)
	(gr_poly
		(pts
			(xy 83.681062 -232.535984) (xy 83.580986 -232.436162) (xy 83.48091 -232.535984) (xy 83.48091 -232.583736)
			(xy 83.681062 -232.583736)
		)
		(stroke
			(width 0)
			(type solid)
		)
		(fill yes)
		(layer "In11.Cu")
		(net "M_F_CPU1_SA_DQS_DN<6>")
	)
	(gr_poly
		(pts
			(xy 83.681062 -232.132632) (xy 83.681062 -232.08488) (xy 83.48091 -232.08488) (xy 83.48091 -232.132632)
			(xy 83.580986 -232.232454)
		)
		(stroke
			(width 0)
			(type solid)
		)
		(fill yes)
		(layer "In11.Cu")
		(net "M_F_CPU1_SA_DQS_DN<1>")
	)
	(gr_poly
		(pts
			(xy 83.681062 -230.916226) (xy 83.580986 -230.81615) (xy 83.48091 -230.916226) (xy 83.48091 -230.960676)
			(xy 83.681062 -230.960676)
		)
		(stroke
			(width 0)
			(type solid)
		)
		(fill yes)
		(layer "In11.Cu")
		(net "M_F_CPU1_SA_DQ<9>")
	)
	(gr_poly
		(pts
			(xy 83.681062 -230.51262) (xy 83.681062 -230.46817) (xy 83.48091 -230.46817) (xy 83.48091 -230.51262)
			(xy 83.580986 -230.612696)
		)
		(stroke
			(width 0)
			(type solid)
		)
		(fill yes)
		(layer "In11.Cu")
		(net "M_F_CPU1_SA_DQ<10>")
	)
	(gr_poly
		(pts
			(xy 83.681062 -229.296214) (xy 83.580986 -229.196138) (xy 83.48091 -229.296214) (xy 83.48091 -229.340664)
			(xy 83.681062 -229.340664)
		)
		(stroke
			(width 0)
			(type solid)
		)
		(fill yes)
		(layer "In11.Cu")
		(net "M_F_CPU1_SA_DQ<5>")
	)
	(gr_poly
		(pts
			(xy 83.681062 -228.892608) (xy 83.681062 -228.848158) (xy 83.48091 -228.848158) (xy 83.48091 -228.892608)
			(xy 83.580986 -228.992684)
		)
		(stroke
			(width 0)
			(type solid)
		)
		(fill yes)
		(layer "In11.Cu")
		(net "M_F_CPU1_SA_DQ<6>")
	)
	(gr_poly
		(pts
			(xy 83.681062 -227.676202) (xy 83.580986 -227.57638) (xy 83.48091 -227.676202) (xy 83.48091 -227.723954)
			(xy 83.681062 -227.723954)
		)
		(stroke
			(width 0)
			(type solid)
		)
		(fill yes)
		(layer "In11.Cu")
		(net "M_F_CPU1_SA_DQS_DN<5>")
	)
	(gr_poly
		(pts
			(xy 83.681062 -227.27285) (xy 83.681062 -227.225098) (xy 83.48091 -227.225098) (xy 83.48091 -227.27285)
			(xy 83.580986 -227.372672)
		)
		(stroke
			(width 0)
			(type solid)
		)
		(fill yes)
		(layer "In11.Cu")
		(net "M_F_CPU1_SA_DQS_DN<0>")
	)
	(gr_poly
		(pts
			(xy 83.681062 -226.056444) (xy 83.580986 -225.956368) (xy 83.48091 -226.056444) (xy 83.48091 -226.100894)
			(xy 83.681062 -226.100894)
		)
		(stroke
			(width 0)
			(type solid)
		)
		(fill yes)
		(layer "In11.Cu")
		(net "M_F_CPU1_SA_DQ<1>")
	)
	(gr_poly
		(pts
			(xy 83.681062 -225.652584) (xy 83.681062 -225.608134) (xy 83.48091 -225.608134) (xy 83.48091 -225.652584)
			(xy 83.580986 -225.75266)
		)
		(stroke
			(width 0)
			(type solid)
		)
		(fill yes)
		(layer "In11.Cu")
		(net "M_F_CPU1_SA_DQ<2>")
	)
	(gr_poly
		(pts
			(xy 83.941412 -293.3319) (xy 83.945222 -293.28745) (xy 83.746086 -293.270178) (xy 83.742022 -293.314374)
			(xy 83.832954 -293.422578)
		)
		(stroke
			(width 0)
			(type solid)
		)
		(fill yes)
		(layer "In11.Cu")
		(net "M_F_CPU1_SB_DQ<31>")
	)
	(gr_poly
		(pts
			(xy 83.981036 -292.108128) (xy 83.88096 -292.008052) (xy 83.780884 -292.108128) (xy 83.780884 -292.152578)
			(xy 83.981036 -292.152578)
		)
		(stroke
			(width 0)
			(type solid)
		)
		(fill yes)
		(layer "In11.Cu")
		(net "M_F_CPU1_SB_DQ<28>")
	)
	(gr_poly
		(pts
			(xy 83.981036 -291.704522) (xy 83.981036 -291.65677) (xy 83.780884 -291.65677) (xy 83.780884 -291.704522)
			(xy 83.88096 -291.804344)
		)
		(stroke
			(width 0)
			(type solid)
		)
		(fill yes)
		(layer "In11.Cu")
		(net "M_F_CPU1_SB_DQS_DP<8>")
	)
	(gr_poly
		(pts
			(xy 83.981036 -290.487862) (xy 83.88096 -290.38804) (xy 83.780884 -290.487862) (xy 83.780884 -290.535614)
			(xy 83.981036 -290.535614)
		)
		(stroke
			(width 0)
			(type solid)
		)
		(fill yes)
		(layer "In11.Cu")
		(net "M_F_CPU1_SB_DQS_DP<3>")
	)
	(gr_poly
		(pts
			(xy 83.981036 -290.084256) (xy 83.981036 -290.039806) (xy 83.780884 -290.039806) (xy 83.780884 -290.084256)
			(xy 83.88096 -290.184332)
		)
		(stroke
			(width 0)
			(type solid)
		)
		(fill yes)
		(layer "In11.Cu")
		(net "M_F_CPU1_SB_DQ<27>")
	)
	(gr_poly
		(pts
			(xy 83.981036 -288.868104) (xy 83.88096 -288.768028) (xy 83.780884 -288.868104) (xy 83.780884 -288.912554)
			(xy 83.981036 -288.912554)
		)
		(stroke
			(width 0)
			(type solid)
		)
		(fill yes)
		(layer "In11.Cu")
		(net "M_F_CPU1_SB_DQ<24>")
	)
	(gr_poly
		(pts
			(xy 83.981036 -288.464498) (xy 83.981036 -288.420048) (xy 83.780884 -288.420048) (xy 83.780884 -288.464498)
			(xy 83.88096 -288.564574)
		)
		(stroke
			(width 0)
			(type solid)
		)
		(fill yes)
		(layer "In11.Cu")
		(net "M_F_CPU1_SB_DQ<23>")
	)
	(gr_poly
		(pts
			(xy 83.981036 -287.248092) (xy 83.88096 -287.148016) (xy 83.780884 -287.248092) (xy 83.780884 -287.292542)
			(xy 83.981036 -287.292542)
		)
		(stroke
			(width 0)
			(type solid)
		)
		(fill yes)
		(layer "In11.Cu")
		(net "M_F_CPU1_SB_DQ<20>")
	)
	(gr_poly
		(pts
			(xy 83.981036 -286.844486) (xy 83.981036 -286.796734) (xy 83.780884 -286.796734) (xy 83.780884 -286.844486)
			(xy 83.88096 -286.944562)
		)
		(stroke
			(width 0)
			(type solid)
		)
		(fill yes)
		(layer "In11.Cu")
		(net "M_F_CPU1_SB_DQS_DP<7>")
	)
	(gr_poly
		(pts
			(xy 83.981036 -285.62808) (xy 83.88096 -285.528258) (xy 83.780884 -285.62808) (xy 83.780884 -285.675832)
			(xy 83.981036 -285.675832)
		)
		(stroke
			(width 0)
			(type solid)
		)
		(fill yes)
		(layer "In11.Cu")
		(net "M_F_CPU1_SB_DQS_DP<2>")
	)
	(gr_poly
		(pts
			(xy 83.981036 -285.224474) (xy 83.981036 -285.180024) (xy 83.780884 -285.180024) (xy 83.780884 -285.224474)
			(xy 83.88096 -285.32455)
		)
		(stroke
			(width 0)
			(type solid)
		)
		(fill yes)
		(layer "In11.Cu")
		(net "M_F_CPU1_SB_DQ<19>")
	)
	(gr_poly
		(pts
			(xy 83.981036 -284.008322) (xy 83.88096 -283.908246) (xy 83.780884 -284.008322) (xy 83.780884 -284.052772)
			(xy 83.981036 -284.052772)
		)
		(stroke
			(width 0)
			(type solid)
		)
		(fill yes)
		(layer "In11.Cu")
		(net "M_F_CPU1_SB_DQ<16>")
	)
	(gr_poly
		(pts
			(xy 83.981036 -283.604462) (xy 83.981036 -283.560012) (xy 83.780884 -283.560012) (xy 83.780884 -283.604462)
			(xy 83.88096 -283.704538)
		)
		(stroke
			(width 0)
			(type solid)
		)
		(fill yes)
		(layer "In11.Cu")
		(net "M_F_CPU1_SB_DQ<15>")
	)
	(gr_poly
		(pts
			(xy 83.981036 -282.38831) (xy 83.88096 -282.288234) (xy 83.780884 -282.38831) (xy 83.780884 -282.43276)
			(xy 83.981036 -282.43276)
		)
		(stroke
			(width 0)
			(type solid)
		)
		(fill yes)
		(layer "In11.Cu")
		(net "M_F_CPU1_SB_DQ<12>")
	)
	(gr_poly
		(pts
			(xy 83.981036 -281.984704) (xy 83.981036 -281.936952) (xy 83.780884 -281.936952) (xy 83.780884 -281.984704)
			(xy 83.88096 -282.084526)
		)
		(stroke
			(width 0)
			(type solid)
		)
		(fill yes)
		(layer "In11.Cu")
		(net "M_F_CPU1_SB_DQS_DP<6>")
	)
	(gr_poly
		(pts
			(xy 83.981036 -280.768044) (xy 83.88096 -280.668222) (xy 83.780884 -280.768044) (xy 83.780884 -280.815796)
			(xy 83.981036 -280.815796)
		)
		(stroke
			(width 0)
			(type solid)
		)
		(fill yes)
		(layer "In11.Cu")
		(net "M_F_CPU1_SB_DQS_DP<1>")
	)
	(gr_poly
		(pts
			(xy 83.981036 -280.364438) (xy 83.981036 -280.319988) (xy 83.780884 -280.319988) (xy 83.780884 -280.364438)
			(xy 83.88096 -280.464514)
		)
		(stroke
			(width 0)
			(type solid)
		)
		(fill yes)
		(layer "In11.Cu")
		(net "M_F_CPU1_SB_DQ<11>")
	)
	(gr_poly
		(pts
			(xy 83.981036 -279.148286) (xy 83.88096 -279.04821) (xy 83.780884 -279.148286) (xy 83.780884 -279.192736)
			(xy 83.981036 -279.192736)
		)
		(stroke
			(width 0)
			(type solid)
		)
		(fill yes)
		(layer "In11.Cu")
		(net "M_F_CPU1_SB_DQ<8>")
	)
	(gr_poly
		(pts
			(xy 83.981036 -278.744426) (xy 83.981036 -278.699976) (xy 83.780884 -278.699976) (xy 83.780884 -278.744426)
			(xy 83.88096 -278.844502)
		)
		(stroke
			(width 0)
			(type solid)
		)
		(fill yes)
		(layer "In11.Cu")
		(net "M_F_CPU1_SB_DQ<7>")
	)
	(gr_poly
		(pts
			(xy 83.981036 -277.528274) (xy 83.88096 -277.428198) (xy 83.780884 -277.528274) (xy 83.780884 -277.572724)
			(xy 83.981036 -277.572724)
		)
		(stroke
			(width 0)
			(type solid)
		)
		(fill yes)
		(layer "In11.Cu")
		(net "M_F_CPU1_SB_DQ<4>")
	)
	(gr_poly
		(pts
			(xy 83.981036 -277.124668) (xy 83.981036 -277.076916) (xy 83.780884 -277.076916) (xy 83.780884 -277.124668)
			(xy 83.88096 -277.22449)
		)
		(stroke
			(width 0)
			(type solid)
		)
		(fill yes)
		(layer "In11.Cu")
		(net "M_F_CPU1_SB_DQS_DP<5>")
	)
	(gr_poly
		(pts
			(xy 83.981036 -275.908008) (xy 83.88096 -275.808186) (xy 83.780884 -275.908008) (xy 83.780884 -275.95576)
			(xy 83.981036 -275.95576)
		)
		(stroke
			(width 0)
			(type solid)
		)
		(fill yes)
		(layer "In11.Cu")
		(net "M_F_CPU1_SB_DQS_DP<0>")
	)
	(gr_poly
		(pts
			(xy 83.981036 -275.504402) (xy 83.981036 -275.459952) (xy 83.780884 -275.459952) (xy 83.780884 -275.504402)
			(xy 83.88096 -275.604478)
		)
		(stroke
			(width 0)
			(type solid)
		)
		(fill yes)
		(layer "In11.Cu")
		(net "M_F_CPU1_SB_DQ<3>")
	)
	(gr_poly
		(pts
			(xy 83.981036 -274.28825) (xy 83.88096 -274.188174) (xy 83.780884 -274.28825) (xy 83.780884 -274.3327)
			(xy 83.981036 -274.3327)
		)
		(stroke
			(width 0)
			(type solid)
		)
		(fill yes)
		(layer "In11.Cu")
		(net "M_F_CPU1_SB_DQ<0>")
	)
	(gr_poly
		(pts
			(xy 83.981036 -273.88439) (xy 83.981036 -273.83994) (xy 83.780884 -273.83994) (xy 83.780884 -273.88439)
			(xy 83.88096 -273.984466)
		)
		(stroke
			(width 0)
			(type solid)
		)
		(fill yes)
		(layer "In11.Cu")
		(net "M_F_CPU1_SB_CB<3>")
	)
	(gr_poly
		(pts
			(xy 83.981036 -272.668238) (xy 83.88096 -272.568162) (xy 83.780884 -272.668238) (xy 83.780884 -272.712688)
			(xy 83.981036 -272.712688)
		)
		(stroke
			(width 0)
			(type solid)
		)
		(fill yes)
		(layer "In11.Cu")
		(net "M_F_CPU1_SB_CB<0>")
	)
	(gr_poly
		(pts
			(xy 83.981036 -272.264632) (xy 83.981036 -272.21688) (xy 83.780884 -272.21688) (xy 83.780884 -272.264632)
			(xy 83.88096 -272.364454)
		)
		(stroke
			(width 0)
			(type solid)
		)
		(fill yes)
		(layer "In11.Cu")
		(net "M_F_CPU1_SB_DQS_DP<4>")
	)
	(gr_poly
		(pts
			(xy 83.981036 -271.047972) (xy 83.88096 -270.94815) (xy 83.780884 -271.047972) (xy 83.780884 -271.095724)
			(xy 83.981036 -271.095724)
		)
		(stroke
			(width 0)
			(type solid)
		)
		(fill yes)
		(layer "In11.Cu")
		(net "M_F_CPU1_SB_DQS_DP<9>")
	)
	(gr_poly
		(pts
			(xy 83.981036 -270.644366) (xy 83.981036 -270.599916) (xy 83.780884 -270.599916) (xy 83.780884 -270.644366)
			(xy 83.88096 -270.744442)
		)
		(stroke
			(width 0)
			(type solid)
		)
		(fill yes)
		(layer "In11.Cu")
		(net "M_F_CPU1_SB_CB<7>")
	)
	(gr_poly
		(pts
			(xy 83.981036 -269.428214) (xy 83.88096 -269.328138) (xy 83.780884 -269.428214) (xy 83.780884 -269.472664)
			(xy 83.981036 -269.472664)
		)
		(stroke
			(width 0)
			(type solid)
		)
		(fill yes)
		(layer "In11.Cu")
		(net "M_F_CPU1_SB_CB<4>")
	)
	(gr_poly
		(pts
			(xy 83.981036 -265.78433) (xy 83.981036 -265.73988) (xy 83.780884 -265.73988) (xy 83.780884 -265.78433)
			(xy 83.88096 -265.884406)
		)
		(stroke
			(width 0)
			(type solid)
		)
		(fill yes)
		(layer "In11.Cu")
		(net "M_F_CPU1_SB_CS_N<0>")
	)
	(gr_poly
		(pts
			(xy 83.981036 -264.568178) (xy 83.88096 -264.468102) (xy 83.780884 -264.568178) (xy 83.780884 -264.612628)
			(xy 83.981036 -264.612628)
		)
		(stroke
			(width 0)
			(type solid)
		)
		(fill yes)
		(layer "In11.Cu")
		(net "M_F_CPU1_SB_CA<6>")
	)
	(gr_poly
		(pts
			(xy 83.981036 -264.164318) (xy 83.981036 -264.119868) (xy 83.780884 -264.119868) (xy 83.780884 -264.164318)
			(xy 83.88096 -264.264394)
		)
		(stroke
			(width 0)
			(type solid)
		)
		(fill yes)
		(layer "In11.Cu")
		(net "M_F_CPU1_SB_CA<5>")
	)
	(gr_poly
		(pts
			(xy 83.981036 -262.948166) (xy 83.88096 -262.84809) (xy 83.780884 -262.948166) (xy 83.780884 -262.992616)
			(xy 83.981036 -262.992616)
		)
		(stroke
			(width 0)
			(type solid)
		)
		(fill yes)
		(layer "In11.Cu")
		(net "M_F_CPU1_SB_CA<2>")
	)
	(gr_poly
		(pts
			(xy 83.981036 -262.544306) (xy 83.981036 -262.499856) (xy 83.780884 -262.499856) (xy 83.780884 -262.544306)
			(xy 83.88096 -262.644382)
		)
		(stroke
			(width 0)
			(type solid)
		)
		(fill yes)
		(layer "In11.Cu")
		(net "M_F_CPU1_SB_CA<1>")
	)
	(gr_poly
		(pts
			(xy 83.98129 -267.808202) (xy 83.881214 -267.708126) (xy 83.781138 -267.808202) (xy 83.781138 -267.852652)
			(xy 83.98129 -267.852652)
		)
		(stroke
			(width 0)
			(type solid)
		)
		(fill yes)
		(layer "In11.Cu")
		(net "M_F_CPU1_SB_RSP<0>")
	)
	(gr_poly
		(pts
			(xy 84.102956 -246.34698) (xy 84.098638 -246.299736) (xy 83.990434 -246.208804) (xy 83.899502 -246.317008)
			(xy 83.903566 -246.364506)
		)
		(stroke
			(width 0)
			(type solid)
		)
		(fill yes)
		(layer "In11.Cu")
		(net "M_F_CPU1_SA_DQS_DP<4>")
	)
	(gr_poly
		(pts
			(xy 84.102956 -236.626908) (xy 84.098638 -236.579664) (xy 83.990434 -236.488732) (xy 83.899502 -236.596936)
			(xy 83.903566 -236.644434)
		)
		(stroke
			(width 0)
			(type solid)
		)
		(fill yes)
		(layer "In11.Cu")
		(net "M_F_CPU1_SA_DQS_DP<2>")
	)
	(gr_poly
		(pts
			(xy 84.102956 -231.766872) (xy 84.098638 -231.719628) (xy 83.990434 -231.628696) (xy 83.899502 -231.7369)
			(xy 83.903566 -231.784398)
		)
		(stroke
			(width 0)
			(type solid)
		)
		(fill yes)
		(layer "In11.Cu")
		(net "M_F_CPU1_SA_DQS_DP<1>")
	)
	(gr_poly
		(pts
			(xy 84.102956 -226.90709) (xy 84.098638 -226.859592) (xy 83.990434 -226.768914) (xy 83.899502 -226.877118)
			(xy 83.903566 -226.924616)
		)
		(stroke
			(width 0)
			(type solid)
		)
		(fill yes)
		(layer "In11.Cu")
		(net "M_F_CPU1_SA_DQS_DP<0>")
	)
	(gr_poly
		(pts
			(xy 84.113878 -256.06629) (xy 84.10956 -256.018792) (xy 84.001356 -255.92786) (xy 83.910424 -256.036318)
			(xy 83.914488 -256.083816)
		)
		(stroke
			(width 0)
			(type solid)
		)
		(fill yes)
		(layer "In11.Cu")
		(net "M_F_CPU1_CLK_DP<0>")
	)
	(gr_poly
		(pts
			(xy 84.115402 -254.44323) (xy 84.111592 -254.39878) (xy 84.003388 -254.307848) (xy 83.912456 -254.416306)
			(xy 83.916266 -254.460502)
		)
		(stroke
			(width 0)
			(type solid)
		)
		(fill yes)
		(layer "In11.Cu")
		(net "M_F_CPU1_SA_CA<4>")
	)
	(gr_poly
		(pts
			(xy 84.115402 -252.823218) (xy 84.111592 -252.778768) (xy 84.003388 -252.687836) (xy 83.912456 -252.796294)
			(xy 83.916266 -252.84049)
		)
		(stroke
			(width 0)
			(type solid)
		)
		(fill yes)
		(layer "In11.Cu")
		(net "M_F_CPU1_SA_CA<0>")
	)
	(gr_poly
		(pts
			(xy 84.115402 -247.963182) (xy 84.111592 -247.918732) (xy 84.003388 -247.8278) (xy 83.912456 -247.936258)
			(xy 83.916266 -247.980454)
		)
		(stroke
			(width 0)
			(type solid)
		)
		(fill yes)
		(layer "In11.Cu")
		(net "M_F_CPU1_SA_CB<4>")
	)
	(gr_poly
		(pts
			(xy 84.115402 -244.723158) (xy 84.111592 -244.678708) (xy 84.003388 -244.587776) (xy 83.912456 -244.696234)
			(xy 83.916266 -244.74043)
		)
		(stroke
			(width 0)
			(type solid)
		)
		(fill yes)
		(layer "In11.Cu")
		(net "M_F_CPU1_SA_CB<0>")
	)
	(gr_poly
		(pts
			(xy 84.115402 -243.103146) (xy 84.111592 -243.058696) (xy 84.003388 -242.967764) (xy 83.912456 -243.076222)
			(xy 83.916266 -243.120418)
		)
		(stroke
			(width 0)
			(type solid)
		)
		(fill yes)
		(layer "In11.Cu")
		(net "M_F_CPU1_SA_DQ<28>")
	)
	(gr_poly
		(pts
			(xy 84.115402 -239.863122) (xy 84.111592 -239.818672) (xy 84.003388 -239.72774) (xy 83.912456 -239.836198)
			(xy 83.916266 -239.880394)
		)
		(stroke
			(width 0)
			(type solid)
		)
		(fill yes)
		(layer "In11.Cu")
		(net "M_F_CPU1_SA_DQ<24>")
	)
	(gr_poly
		(pts
			(xy 84.115402 -238.24311) (xy 84.111592 -238.19866) (xy 84.003388 -238.107728) (xy 83.912456 -238.216186)
			(xy 83.916266 -238.260382)
		)
		(stroke
			(width 0)
			(type solid)
		)
		(fill yes)
		(layer "In11.Cu")
		(net "M_F_CPU1_SA_DQ<20>")
	)
	(gr_poly
		(pts
			(xy 84.115402 -235.003086) (xy 84.111592 -234.958636) (xy 84.003388 -234.867704) (xy 83.912456 -234.976162)
			(xy 83.916266 -235.020358)
		)
		(stroke
			(width 0)
			(type solid)
		)
		(fill yes)
		(layer "In11.Cu")
		(net "M_F_CPU1_SA_DQ<16>")
	)
	(gr_poly
		(pts
			(xy 84.115402 -233.383074) (xy 84.111592 -233.338624) (xy 84.003388 -233.247692) (xy 83.912456 -233.35615)
			(xy 83.916266 -233.400346)
		)
		(stroke
			(width 0)
			(type solid)
		)
		(fill yes)
		(layer "In11.Cu")
		(net "M_F_CPU1_SA_DQ<12>")
	)
	(gr_poly
		(pts
			(xy 84.115402 -230.14305) (xy 84.111592 -230.0986) (xy 84.003388 -230.007668) (xy 83.912456 -230.116126)
			(xy 83.916266 -230.160322)
		)
		(stroke
			(width 0)
			(type solid)
		)
		(fill yes)
		(layer "In11.Cu")
		(net "M_F_CPU1_SA_DQ<8>")
	)
	(gr_poly
		(pts
			(xy 84.115402 -228.523292) (xy 84.111592 -228.478842) (xy 84.003388 -228.38791) (xy 83.912456 -228.496368)
			(xy 83.916266 -228.540564)
		)
		(stroke
			(width 0)
			(type solid)
		)
		(fill yes)
		(layer "In11.Cu")
		(net "M_F_CPU1_SA_DQ<4>")
	)
	(gr_poly
		(pts
			(xy 84.115402 -225.283268) (xy 84.111592 -225.238818) (xy 84.003388 -225.147886) (xy 83.912456 -225.256344)
			(xy 83.916266 -225.30054)
		)
		(stroke
			(width 0)
			(type solid)
		)
		(fill yes)
		(layer "In11.Cu")
		(net "M_F_CPU1_SA_DQ<0>")
	)
	(gr_poly
		(pts
			(xy 84.151216 -255.622552) (xy 84.151216 -255.578102) (xy 83.951064 -255.578102) (xy 83.951064 -255.622552)
			(xy 84.05114 -255.722628)
		)
		(stroke
			(width 0)
			(type solid)
		)
		(fill yes)
		(layer "In11.Cu")
		(net "M_F_CPU1_SA_PAR")
	)
	(gr_poly
		(pts
			(xy 84.151216 -254.00254) (xy 84.151216 -253.95809) (xy 83.951064 -253.95809) (xy 83.951064 -254.00254)
			(xy 84.05114 -254.102616)
		)
		(stroke
			(width 0)
			(type solid)
		)
		(fill yes)
		(layer "In11.Cu")
		(net "M_F_CPU1_SA_CA<3>")
	)
	(gr_poly
		(pts
			(xy 84.151216 -252.382528) (xy 84.151216 -252.338078) (xy 83.951064 -252.338078) (xy 83.951064 -252.382528)
			(xy 84.05114 -252.482604)
		)
		(stroke
			(width 0)
			(type solid)
		)
		(fill yes)
		(layer "In11.Cu")
		(net "M_F_CPU1_SA_CS_N<1>")
	)
	(gr_poly
		(pts
			(xy 84.151216 -250.762516) (xy 84.151216 -250.718066) (xy 83.951064 -250.718066) (xy 83.951064 -250.762516)
			(xy 84.05114 -250.862592)
		)
		(stroke
			(width 0)
			(type solid)
		)
		(fill yes)
		(layer "In11.Cu")
		(net "M_F_CPU1_RESET_N")
	)
	(gr_poly
		(pts
			(xy 84.151216 -249.142504) (xy 84.151216 -249.098054) (xy 83.951064 -249.098054) (xy 83.951064 -249.142504)
			(xy 84.05114 -249.24258)
		)
		(stroke
			(width 0)
			(type solid)
		)
		(fill yes)
		(layer "In11.Cu")
		(net "M_F_CPU1_SA_CB<7>")
	)
	(gr_poly
		(pts
			(xy 84.151216 -247.522746) (xy 84.151216 -247.474994) (xy 83.951064 -247.474994) (xy 83.951064 -247.522746)
			(xy 84.05114 -247.622568)
		)
		(stroke
			(width 0)
			(type solid)
		)
		(fill yes)
		(layer "In11.Cu")
		(net "M_F_CPU1_SA_DQS_DP<9>")
	)
	(gr_poly
		(pts
			(xy 84.151216 -245.90248) (xy 84.151216 -245.85803) (xy 83.951064 -245.85803) (xy 83.951064 -245.90248)
			(xy 84.05114 -246.002556)
		)
		(stroke
			(width 0)
			(type solid)
		)
		(fill yes)
		(layer "In11.Cu")
		(net "M_F_CPU1_SA_CB<3>")
	)
	(gr_poly
		(pts
			(xy 84.151216 -244.282468) (xy 84.151216 -244.238018) (xy 83.951064 -244.238018) (xy 83.951064 -244.282468)
			(xy 84.05114 -244.382544)
		)
		(stroke
			(width 0)
			(type solid)
		)
		(fill yes)
		(layer "In11.Cu")
		(net "M_F_CPU1_SA_DQ<31>")
	)
	(gr_poly
		(pts
			(xy 84.151216 -242.66271) (xy 84.151216 -242.614958) (xy 83.951064 -242.614958) (xy 83.951064 -242.66271)
			(xy 84.05114 -242.762532)
		)
		(stroke
			(width 0)
			(type solid)
		)
		(fill yes)
		(layer "In11.Cu")
		(net "M_F_CPU1_SA_DQS_DP<8>")
	)
	(gr_poly
		(pts
			(xy 84.151216 -241.042444) (xy 84.151216 -240.997994) (xy 83.951064 -240.997994) (xy 83.951064 -241.042444)
			(xy 84.05114 -241.14252)
		)
		(stroke
			(width 0)
			(type solid)
		)
		(fill yes)
		(layer "In11.Cu")
		(net "M_F_CPU1_SA_DQ<27>")
	)
	(gr_poly
		(pts
			(xy 84.151216 -239.422432) (xy 84.151216 -239.377982) (xy 83.951064 -239.377982) (xy 83.951064 -239.422432)
			(xy 84.05114 -239.522508)
		)
		(stroke
			(width 0)
			(type solid)
		)
		(fill yes)
		(layer "In11.Cu")
		(net "M_F_CPU1_SA_DQ<23>")
	)
	(gr_poly
		(pts
			(xy 84.151216 -237.802674) (xy 84.151216 -237.754922) (xy 83.951064 -237.754922) (xy 83.951064 -237.802674)
			(xy 84.05114 -237.902496)
		)
		(stroke
			(width 0)
			(type solid)
		)
		(fill yes)
		(layer "In11.Cu")
		(net "M_F_CPU1_SA_DQS_DP<7>")
	)
	(gr_poly
		(pts
			(xy 84.151216 -236.182408) (xy 84.151216 -236.137958) (xy 83.951064 -236.137958) (xy 83.951064 -236.182408)
			(xy 84.05114 -236.282484)
		)
		(stroke
			(width 0)
			(type solid)
		)
		(fill yes)
		(layer "In11.Cu")
		(net "M_F_CPU1_SA_DQ<19>")
	)
	(gr_poly
		(pts
			(xy 84.151216 -234.562396) (xy 84.151216 -234.517946) (xy 83.951064 -234.517946) (xy 83.951064 -234.562396)
			(xy 84.05114 -234.662472)
		)
		(stroke
			(width 0)
			(type solid)
		)
		(fill yes)
		(layer "In11.Cu")
		(net "M_F_CPU1_SA_DQ<15>")
	)
	(gr_poly
		(pts
			(xy 84.151216 -232.942638) (xy 84.151216 -232.894886) (xy 83.951064 -232.894886) (xy 83.951064 -232.942638)
			(xy 84.05114 -233.04246)
		)
		(stroke
			(width 0)
			(type solid)
		)
		(fill yes)
		(layer "In11.Cu")
		(net "M_F_CPU1_SA_DQS_DP<6>")
	)
	(gr_poly
		(pts
			(xy 84.151216 -231.322626) (xy 84.151216 -231.278176) (xy 83.951064 -231.278176) (xy 83.951064 -231.322626)
			(xy 84.05114 -231.422702)
		)
		(stroke
			(width 0)
			(type solid)
		)
		(fill yes)
		(layer "In11.Cu")
		(net "M_F_CPU1_SA_DQ<11>")
	)
	(gr_poly
		(pts
			(xy 84.151216 -229.702614) (xy 84.151216 -229.658164) (xy 83.951064 -229.658164) (xy 83.951064 -229.702614)
			(xy 84.05114 -229.80269)
		)
		(stroke
			(width 0)
			(type solid)
		)
		(fill yes)
		(layer "In11.Cu")
		(net "M_F_CPU1_SA_DQ<7>")
	)
	(gr_poly
		(pts
			(xy 84.151216 -228.082856) (xy 84.151216 -228.035104) (xy 83.951064 -228.035104) (xy 83.951064 -228.082856)
			(xy 84.05114 -228.182678)
		)
		(stroke
			(width 0)
			(type solid)
		)
		(fill yes)
		(layer "In11.Cu")
		(net "M_F_CPU1_SA_DQS_DP<5>")
	)
	(gr_poly
		(pts
			(xy 84.151216 -226.46259) (xy 84.151216 -226.41814) (xy 83.951064 -226.41814) (xy 83.951064 -226.46259)
			(xy 84.05114 -226.562666)
		)
		(stroke
			(width 0)
			(type solid)
		)
		(fill yes)
		(layer "In11.Cu")
		(net "M_F_CPU1_SA_DQ<3>")
	)
	(gr_poly
		(pts
			(xy 84.398612 -290.91382) (xy 84.40293 -290.866322) (xy 84.20354 -290.848796) (xy 84.199476 -290.896294)
			(xy 84.290408 -291.004498)
		)
		(stroke
			(width 0)
			(type solid)
		)
		(fill yes)
		(layer "In11.Cu")
		(net "M_F_CPU1_SB_DQS_DN<3>")
	)
	(gr_poly
		(pts
			(xy 84.398612 -281.181048) (xy 84.40293 -281.133804) (xy 84.20354 -281.116278) (xy 84.199476 -281.163776)
			(xy 84.290408 -281.27198)
		)
		(stroke
			(width 0)
			(type solid)
		)
		(fill yes)
		(layer "In11.Cu")
		(net "M_F_CPU1_SB_DQS_DN<1>")
	)
	(gr_poly
		(pts
			(xy 84.398612 -276.321012) (xy 84.40293 -276.273768) (xy 84.20354 -276.256242) (xy 84.199476 -276.30374)
			(xy 84.290408 -276.411944)
		)
		(stroke
			(width 0)
			(type solid)
		)
		(fill yes)
		(layer "In11.Cu")
		(net "M_F_CPU1_SB_DQS_DN<0>")
	)
	(gr_poly
		(pts
			(xy 84.398612 -271.460976) (xy 84.40293 -271.413732) (xy 84.20354 -271.396206) (xy 84.199476 -271.443704)
			(xy 84.290408 -271.551908)
		)
		(stroke
			(width 0)
			(type solid)
		)
		(fill yes)
		(layer "In11.Cu")
		(net "M_F_CPU1_SB_DQS_DN<9>")
	)
	(gr_poly
		(pts
			(xy 84.401914 -286.04972) (xy 84.401914 -286.001968) (xy 84.201762 -286.001968) (xy 84.201762 -286.04972)
			(xy 84.301838 -286.149542)
		)
		(stroke
			(width 0)
			(type solid)
		)
		(fill yes)
		(layer "In11.Cu")
		(net "M_F_CPU1_SB_DQS_DN<2>")
	)
	(gr_poly
		(pts
			(xy 84.411566 -292.521894) (xy 84.41563 -292.477444) (xy 84.21624 -292.460172) (xy 84.21243 -292.504368)
			(xy 84.303362 -292.612826)
		)
		(stroke
			(width 0)
			(type solid)
		)
		(fill yes)
		(layer "In11.Cu")
		(net "M_F_CPU1_SB_DQ<30>")
	)
	(gr_poly
		(pts
			(xy 84.411566 -289.28187) (xy 84.41563 -289.23742) (xy 84.21624 -289.220148) (xy 84.21243 -289.264344)
			(xy 84.303362 -289.372802)
		)
		(stroke
			(width 0)
			(type solid)
		)
		(fill yes)
		(layer "In11.Cu")
		(net "M_F_CPU1_SB_DQ<26>")
	)
	(gr_poly
		(pts
			(xy 84.411566 -287.662112) (xy 84.41563 -287.617662) (xy 84.21624 -287.60039) (xy 84.21243 -287.644586)
			(xy 84.303362 -287.753044)
		)
		(stroke
			(width 0)
			(type solid)
		)
		(fill yes)
		(layer "In11.Cu")
		(net "M_F_CPU1_SB_DQ<22>")
	)
	(gr_poly
		(pts
			(xy 84.411566 -284.422088) (xy 84.41563 -284.377638) (xy 84.21624 -284.360366) (xy 84.21243 -284.404562)
			(xy 84.303362 -284.51302)
		)
		(stroke
			(width 0)
			(type solid)
		)
		(fill yes)
		(layer "In11.Cu")
		(net "M_F_CPU1_SB_DQ<18>")
	)
	(gr_poly
		(pts
			(xy 84.411566 -282.802076) (xy 84.41563 -282.757626) (xy 84.21624 -282.740354) (xy 84.21243 -282.78455)
			(xy 84.303362 -282.893008)
		)
		(stroke
			(width 0)
			(type solid)
		)
		(fill yes)
		(layer "In11.Cu")
		(net "M_F_CPU1_SB_DQ<14>")
	)
	(gr_poly
		(pts
			(xy 84.411566 -279.562052) (xy 84.41563 -279.517602) (xy 84.21624 -279.50033) (xy 84.21243 -279.544526)
			(xy 84.303362 -279.652984)
		)
		(stroke
			(width 0)
			(type solid)
		)
		(fill yes)
		(layer "In11.Cu")
		(net "M_F_CPU1_SB_DQ<10>")
	)
	(gr_poly
		(pts
			(xy 84.411566 -277.94204) (xy 84.41563 -277.89759) (xy 84.21624 -277.880318) (xy 84.21243 -277.924514)
			(xy 84.303362 -278.032972)
		)
		(stroke
			(width 0)
			(type solid)
		)
		(fill yes)
		(layer "In11.Cu")
		(net "M_F_CPU1_SB_DQ<6>")
	)
	(gr_poly
		(pts
			(xy 84.411566 -274.702016) (xy 84.41563 -274.657566) (xy 84.21624 -274.640294) (xy 84.21243 -274.68449)
			(xy 84.303362 -274.792948)
		)
		(stroke
			(width 0)
			(type solid)
		)
		(fill yes)
		(layer "In11.Cu")
		(net "M_F_CPU1_SB_DQ<2>")
	)
	(gr_poly
		(pts
			(xy 84.411566 -273.082004) (xy 84.41563 -273.037554) (xy 84.21624 -273.020282) (xy 84.21243 -273.064478)
			(xy 84.303362 -273.172936)
		)
		(stroke
			(width 0)
			(type solid)
		)
		(fill yes)
		(layer "In11.Cu")
		(net "M_F_CPU1_SB_CB<2>")
	)
	(gr_poly
		(pts
			(xy 84.411566 -269.84198) (xy 84.41563 -269.79753) (xy 84.21624 -269.780258) (xy 84.21243 -269.824454)
			(xy 84.303362 -269.932912)
		)
		(stroke
			(width 0)
			(type solid)
		)
		(fill yes)
		(layer "In11.Cu")
		(net "M_F_CPU1_SB_CB<6>")
	)
	(gr_poly
		(pts
			(xy 84.411566 -266.601956) (xy 84.41563 -266.557506) (xy 84.21624 -266.540234) (xy 84.21243 -266.58443)
			(xy 84.303362 -266.692888)
		)
		(stroke
			(width 0)
			(type solid)
		)
		(fill yes)
		(layer "In11.Cu")
		(net "M_F_CPU1_SB_CS_N<1>")
	)
	(gr_poly
		(pts
			(xy 84.411566 -264.981944) (xy 84.41563 -264.937494) (xy 84.21624 -264.920222) (xy 84.21243 -264.964418)
			(xy 84.303362 -265.072876)
		)
		(stroke
			(width 0)
			(type solid)
		)
		(fill yes)
		(layer "In11.Cu")
		(net "M_F_CPU1_SB_PAR")
	)
	(gr_poly
		(pts
			(xy 84.411566 -263.361932) (xy 84.41563 -263.317482) (xy 84.21624 -263.30021) (xy 84.21243 -263.344406)
			(xy 84.303362 -263.452864)
		)
		(stroke
			(width 0)
			(type solid)
		)
		(fill yes)
		(layer "In11.Cu")
		(net "M_F_CPU1_SB_CA<3>")
	)
	(gr_poly
		(pts
			(xy 84.450936 -292.918134) (xy 84.35086 -292.818058) (xy 84.250784 -292.918134) (xy 84.250784 -292.962584)
			(xy 84.450936 -292.962584)
		)
		(stroke
			(width 0)
			(type solid)
		)
		(fill yes)
		(layer "In11.Cu")
		(net "M_F_CPU1_SB_DQ<29>")
	)
	(gr_poly
		(pts
			(xy 84.45119 -291.297868) (xy 84.351114 -291.198046) (xy 84.251038 -291.297868) (xy 84.251038 -291.34562)
			(xy 84.45119 -291.34562)
		)
		(stroke
			(width 0)
			(type solid)
		)
		(fill yes)
		(layer "In11.Cu")
		(net "M_F_CPU1_SB_DQS_DN<8>")
	)
	(gr_poly
		(pts
			(xy 84.45119 -289.67811) (xy 84.351114 -289.578034) (xy 84.251038 -289.67811) (xy 84.251038 -289.72256)
			(xy 84.45119 -289.72256)
		)
		(stroke
			(width 0)
			(type solid)
		)
		(fill yes)
		(layer "In11.Cu")
		(net "M_F_CPU1_SB_DQ<25>")
	)
	(gr_poly
		(pts
			(xy 84.45119 -288.058098) (xy 84.351114 -287.958022) (xy 84.251038 -288.058098) (xy 84.251038 -288.102548)
			(xy 84.45119 -288.102548)
		)
		(stroke
			(width 0)
			(type solid)
		)
		(fill yes)
		(layer "In11.Cu")
		(net "M_F_CPU1_SB_DQ<21>")
	)
	(gr_poly
		(pts
			(xy 84.45119 -286.438086) (xy 84.351114 -286.33801) (xy 84.251038 -286.438086) (xy 84.251038 -286.485838)
			(xy 84.45119 -286.485838)
		)
		(stroke
			(width 0)
			(type solid)
		)
		(fill yes)
		(layer "In11.Cu")
		(net "M_F_CPU1_SB_DQS_DN<7>")
	)
	(gr_poly
		(pts
			(xy 84.45119 -284.818328) (xy 84.351114 -284.718252) (xy 84.251038 -284.818328) (xy 84.251038 -284.862778)
			(xy 84.45119 -284.862778)
		)
		(stroke
			(width 0)
			(type solid)
		)
		(fill yes)
		(layer "In11.Cu")
		(net "M_F_CPU1_SB_DQ<17>")
	)
	(gr_poly
		(pts
			(xy 84.45119 -283.198316) (xy 84.351114 -283.09824) (xy 84.251038 -283.198316) (xy 84.251038 -283.242766)
			(xy 84.45119 -283.242766)
		)
		(stroke
			(width 0)
			(type solid)
		)
		(fill yes)
		(layer "In11.Cu")
		(net "M_F_CPU1_SB_DQ<13>")
	)
	(gr_poly
		(pts
			(xy 84.45119 -281.57805) (xy 84.351114 -281.478228) (xy 84.251038 -281.57805) (xy 84.251038 -281.625802)
			(xy 84.45119 -281.625802)
		)
		(stroke
			(width 0)
			(type solid)
		)
		(fill yes)
		(layer "In11.Cu")
		(net "M_F_CPU1_SB_DQS_DN<6>")
	)
	(gr_poly
		(pts
			(xy 84.45119 -279.958292) (xy 84.351114 -279.858216) (xy 84.251038 -279.958292) (xy 84.251038 -280.002742)
			(xy 84.45119 -280.002742)
		)
		(stroke
			(width 0)
			(type solid)
		)
		(fill yes)
		(layer "In11.Cu")
		(net "M_F_CPU1_SB_DQ<9>")
	)
	(gr_poly
		(pts
			(xy 84.45119 -278.33828) (xy 84.351114 -278.238204) (xy 84.251038 -278.33828) (xy 84.251038 -278.38273)
			(xy 84.45119 -278.38273)
		)
		(stroke
			(width 0)
			(type solid)
		)
		(fill yes)
		(layer "In11.Cu")
		(net "M_F_CPU1_SB_DQ<5>")
	)
	(gr_poly
		(pts
			(xy 84.45119 -276.718014) (xy 84.351114 -276.618192) (xy 84.251038 -276.718014) (xy 84.251038 -276.765766)
			(xy 84.45119 -276.765766)
		)
		(stroke
			(width 0)
			(type solid)
		)
		(fill yes)
		(layer "In11.Cu")
		(net "M_F_CPU1_SB_DQS_DN<5>")
	)
	(gr_poly
		(pts
			(xy 84.45119 -275.098256) (xy 84.351114 -274.99818) (xy 84.251038 -275.098256) (xy 84.251038 -275.142706)
			(xy 84.45119 -275.142706)
		)
		(stroke
			(width 0)
			(type solid)
		)
		(fill yes)
		(layer "In11.Cu")
		(net "M_F_CPU1_SB_DQ<1>")
	)
	(gr_poly
		(pts
			(xy 84.45119 -273.478244) (xy 84.351114 -273.378168) (xy 84.251038 -273.478244) (xy 84.251038 -273.522694)
			(xy 84.45119 -273.522694)
		)
		(stroke
			(width 0)
			(type solid)
		)
		(fill yes)
		(layer "In11.Cu")
		(net "M_F_CPU1_SB_CB<1>")
	)
	(gr_poly
		(pts
			(xy 84.45119 -271.857978) (xy 84.351114 -271.758156) (xy 84.251038 -271.857978) (xy 84.251038 -271.90573)
			(xy 84.45119 -271.90573)
		)
		(stroke
			(width 0)
			(type solid)
		)
		(fill yes)
		(layer "In11.Cu")
		(net "M_F_CPU1_SB_DQS_DN<4>")
	)
	(gr_poly
		(pts
			(xy 84.45119 -270.23822) (xy 84.351114 -270.138144) (xy 84.251038 -270.23822) (xy 84.251038 -270.28267)
			(xy 84.45119 -270.28267)
		)
		(stroke
			(width 0)
			(type solid)
		)
		(fill yes)
		(layer "In11.Cu")
		(net "M_F_CPU1_SB_CB<5>")
	)
	(gr_poly
		(pts
			(xy 84.45119 -266.998196) (xy 84.351114 -266.89812) (xy 84.251038 -266.998196) (xy 84.251038 -267.042646)
			(xy 84.45119 -267.042646)
		)
		(stroke
			(width 0)
			(type solid)
		)
		(fill yes)
		(layer "In11.Cu")
		(net "M_F_CPU1_SA_RSP<0>")
	)
	(gr_poly
		(pts
			(xy 84.45119 -263.758172) (xy 84.351114 -263.658096) (xy 84.251038 -263.758172) (xy 84.251038 -263.802622)
			(xy 84.45119 -263.802622)
		)
		(stroke
			(width 0)
			(type solid)
		)
		(fill yes)
		(layer "In11.Cu")
		(net "M_F_CPU1_SB_CA<4>")
	)
	(gr_poly
		(pts
			(xy 84.45119 -262.13816) (xy 84.351114 -262.038084) (xy 84.251038 -262.13816) (xy 84.251038 -262.18261)
			(xy 84.45119 -262.18261)
		)
		(stroke
			(width 0)
			(type solid)
		)
		(fill yes)
		(layer "In11.Cu")
		(net "M_F_CPU1_SB_CA<0>")
	)
	(gr_poly
		(pts
			(xy 84.621116 -255.216406) (xy 84.52104 -255.11633) (xy 84.420964 -255.216406) (xy 84.420964 -255.260856)
			(xy 84.621116 -255.260856)
		)
		(stroke
			(width 0)
			(type solid)
		)
		(fill yes)
		(layer "In11.Cu")
		(net "M_F_CPU1_SA_CA<6>")
	)
	(gr_poly
		(pts
			(xy 84.621116 -253.596394) (xy 84.52104 -253.496318) (xy 84.420964 -253.596394) (xy 84.420964 -253.640844)
			(xy 84.621116 -253.640844)
		)
		(stroke
			(width 0)
			(type solid)
		)
		(fill yes)
		(layer "In11.Cu")
		(net "M_F_CPU1_SA_CA<2>")
	)
	(gr_poly
		(pts
			(xy 84.621116 -250.35637) (xy 84.52104 -250.256294) (xy 84.420964 -250.35637) (xy 84.420964 -250.40082)
			(xy 84.621116 -250.40082)
		)
		(stroke
			(width 0)
			(type solid)
		)
		(fill yes)
		(layer "In11.Cu")
		(net "M_F_CPU1_ALERT_R_N")
	)
	(gr_poly
		(pts
			(xy 84.621116 -248.736358) (xy 84.52104 -248.636282) (xy 84.420964 -248.736358) (xy 84.420964 -248.780808)
			(xy 84.621116 -248.780808)
		)
		(stroke
			(width 0)
			(type solid)
		)
		(fill yes)
		(layer "In11.Cu")
		(net "M_F_CPU1_SA_CB<5>")
	)
	(gr_poly
		(pts
			(xy 84.621116 -247.116092) (xy 84.52104 -247.01627) (xy 84.420964 -247.116092) (xy 84.420964 -247.163844)
			(xy 84.621116 -247.163844)
		)
		(stroke
			(width 0)
			(type solid)
		)
		(fill yes)
		(layer "In11.Cu")
		(net "M_F_CPU1_SA_DQS_DN<9>")
	)
	(gr_poly
		(pts
			(xy 84.621116 -245.496334) (xy 84.52104 -245.396258) (xy 84.420964 -245.496334) (xy 84.420964 -245.540784)
			(xy 84.621116 -245.540784)
		)
		(stroke
			(width 0)
			(type solid)
		)
		(fill yes)
		(layer "In11.Cu")
		(net "M_F_CPU1_SA_CB<1>")
	)
	(gr_poly
		(pts
			(xy 84.621116 -243.876322) (xy 84.52104 -243.776246) (xy 84.420964 -243.876322) (xy 84.420964 -243.920772)
			(xy 84.621116 -243.920772)
		)
		(stroke
			(width 0)
			(type solid)
		)
		(fill yes)
		(layer "In11.Cu")
		(net "M_F_CPU1_SA_DQ<29>")
	)
	(gr_poly
		(pts
			(xy 84.621116 -242.256056) (xy 84.52104 -242.156234) (xy 84.420964 -242.256056) (xy 84.420964 -242.303808)
			(xy 84.621116 -242.303808)
		)
		(stroke
			(width 0)
			(type solid)
		)
		(fill yes)
		(layer "In11.Cu")
		(net "M_F_CPU1_SA_DQS_DN<8>")
	)
	(gr_poly
		(pts
			(xy 84.621116 -240.636298) (xy 84.52104 -240.536222) (xy 84.420964 -240.636298) (xy 84.420964 -240.680748)
			(xy 84.621116 -240.680748)
		)
		(stroke
			(width 0)
			(type solid)
		)
		(fill yes)
		(layer "In11.Cu")
		(net "M_F_CPU1_SA_DQ<25>")
	)
	(gr_poly
		(pts
			(xy 84.621116 -239.016286) (xy 84.52104 -238.91621) (xy 84.420964 -239.016286) (xy 84.420964 -239.060736)
			(xy 84.621116 -239.060736)
		)
		(stroke
			(width 0)
			(type solid)
		)
		(fill yes)
		(layer "In11.Cu")
		(net "M_F_CPU1_SA_DQ<21>")
	)
	(gr_poly
		(pts
			(xy 84.621116 -237.39602) (xy 84.52104 -237.296198) (xy 84.420964 -237.39602) (xy 84.420964 -237.443772)
			(xy 84.621116 -237.443772)
		)
		(stroke
			(width 0)
			(type solid)
		)
		(fill yes)
		(layer "In11.Cu")
		(net "M_F_CPU1_SA_DQS_DN<7>")
	)
	(gr_poly
		(pts
			(xy 84.621116 -235.776262) (xy 84.52104 -235.676186) (xy 84.420964 -235.776262) (xy 84.420964 -235.820712)
			(xy 84.621116 -235.820712)
		)
		(stroke
			(width 0)
			(type solid)
		)
		(fill yes)
		(layer "In11.Cu")
		(net "M_F_CPU1_SA_DQ<17>")
	)
	(gr_poly
		(pts
			(xy 84.621116 -234.15625) (xy 84.52104 -234.056174) (xy 84.420964 -234.15625) (xy 84.420964 -234.2007)
			(xy 84.621116 -234.2007)
		)
		(stroke
			(width 0)
			(type solid)
		)
		(fill yes)
		(layer "In11.Cu")
		(net "M_F_CPU1_SA_DQ<13>")
	)
	(gr_poly
		(pts
			(xy 84.621116 -232.535984) (xy 84.52104 -232.436162) (xy 84.420964 -232.535984) (xy 84.420964 -232.583736)
			(xy 84.621116 -232.583736)
		)
		(stroke
			(width 0)
			(type solid)
		)
		(fill yes)
		(layer "In11.Cu")
		(net "M_F_CPU1_SA_DQS_DN<6>")
	)
	(gr_poly
		(pts
			(xy 84.621116 -230.916226) (xy 84.52104 -230.81615) (xy 84.420964 -230.916226) (xy 84.420964 -230.960676)
			(xy 84.621116 -230.960676)
		)
		(stroke
			(width 0)
			(type solid)
		)
		(fill yes)
		(layer "In11.Cu")
		(net "M_F_CPU1_SA_DQ<9>")
	)
	(gr_poly
		(pts
			(xy 84.621116 -229.296214) (xy 84.52104 -229.196138) (xy 84.420964 -229.296214) (xy 84.420964 -229.340664)
			(xy 84.621116 -229.340664)
		)
		(stroke
			(width 0)
			(type solid)
		)
		(fill yes)
		(layer "In11.Cu")
		(net "M_F_CPU1_SA_DQ<5>")
	)
	(gr_poly
		(pts
			(xy 84.621116 -227.676202) (xy 84.52104 -227.57638) (xy 84.420964 -227.676202) (xy 84.420964 -227.723954)
			(xy 84.621116 -227.723954)
		)
		(stroke
			(width 0)
			(type solid)
		)
		(fill yes)
		(layer "In11.Cu")
		(net "M_F_CPU1_SA_DQS_DN<5>")
	)
	(gr_poly
		(pts
			(xy 84.621116 -226.056444) (xy 84.52104 -225.956368) (xy 84.420964 -226.056444) (xy 84.420964 -226.100894)
			(xy 84.621116 -226.100894)
		)
		(stroke
			(width 0)
			(type solid)
		)
		(fill yes)
		(layer "In11.Cu")
		(net "M_F_CPU1_SA_DQ<1>")
	)
	(gr_poly
		(pts
			(xy 84.92109 -291.704522) (xy 84.92109 -291.65677) (xy 84.720938 -291.65677) (xy 84.720938 -291.704522)
			(xy 84.821014 -291.804344)
		)
		(stroke
			(width 0)
			(type solid)
		)
		(fill yes)
		(layer "In11.Cu")
		(net "M_F_CPU1_SB_DQS_DP<8>")
	)
	(gr_poly
		(pts
			(xy 84.92109 -290.084256) (xy 84.92109 -290.039806) (xy 84.720938 -290.039806) (xy 84.720938 -290.084256)
			(xy 84.821014 -290.184332)
		)
		(stroke
			(width 0)
			(type solid)
		)
		(fill yes)
		(layer "In11.Cu")
		(net "M_F_CPU1_SB_DQ<27>")
	)
	(gr_poly
		(pts
			(xy 84.92109 -288.464498) (xy 84.92109 -288.420048) (xy 84.720938 -288.420048) (xy 84.720938 -288.464498)
			(xy 84.821014 -288.564574)
		)
		(stroke
			(width 0)
			(type solid)
		)
		(fill yes)
		(layer "In11.Cu")
		(net "M_F_CPU1_SB_DQ<23>")
	)
	(gr_poly
		(pts
			(xy 84.92109 -286.844486) (xy 84.92109 -286.796734) (xy 84.720938 -286.796734) (xy 84.720938 -286.844486)
			(xy 84.821014 -286.944562)
		)
		(stroke
			(width 0)
			(type solid)
		)
		(fill yes)
		(layer "In11.Cu")
		(net "M_F_CPU1_SB_DQS_DP<7>")
	)
	(gr_poly
		(pts
			(xy 84.92109 -285.224474) (xy 84.92109 -285.180024) (xy 84.720938 -285.180024) (xy 84.720938 -285.224474)
			(xy 84.821014 -285.32455)
		)
		(stroke
			(width 0)
			(type solid)
		)
		(fill yes)
		(layer "In11.Cu")
		(net "M_F_CPU1_SB_DQ<19>")
	)
	(gr_poly
		(pts
			(xy 84.92109 -283.604462) (xy 84.92109 -283.560012) (xy 84.720938 -283.560012) (xy 84.720938 -283.604462)
			(xy 84.821014 -283.704538)
		)
		(stroke
			(width 0)
			(type solid)
		)
		(fill yes)
		(layer "In11.Cu")
		(net "M_F_CPU1_SB_DQ<15>")
	)
	(gr_poly
		(pts
			(xy 84.92109 -281.984704) (xy 84.92109 -281.936952) (xy 84.720938 -281.936952) (xy 84.720938 -281.984704)
			(xy 84.821014 -282.084526)
		)
		(stroke
			(width 0)
			(type solid)
		)
		(fill yes)
		(layer "In11.Cu")
		(net "M_F_CPU1_SB_DQS_DP<6>")
	)
	(gr_poly
		(pts
			(xy 84.92109 -280.364438) (xy 84.92109 -280.319988) (xy 84.720938 -280.319988) (xy 84.720938 -280.364438)
			(xy 84.821014 -280.464514)
		)
		(stroke
			(width 0)
			(type solid)
		)
		(fill yes)
		(layer "In11.Cu")
		(net "M_F_CPU1_SB_DQ<11>")
	)
	(gr_poly
		(pts
			(xy 84.92109 -278.744426) (xy 84.92109 -278.699976) (xy 84.720938 -278.699976) (xy 84.720938 -278.744426)
			(xy 84.821014 -278.844502)
		)
		(stroke
			(width 0)
			(type solid)
		)
		(fill yes)
		(layer "In11.Cu")
		(net "M_F_CPU1_SB_DQ<7>")
	)
	(gr_poly
		(pts
			(xy 84.92109 -277.124668) (xy 84.92109 -277.076916) (xy 84.720938 -277.076916) (xy 84.720938 -277.124668)
			(xy 84.821014 -277.22449)
		)
		(stroke
			(width 0)
			(type solid)
		)
		(fill yes)
		(layer "In11.Cu")
		(net "M_F_CPU1_SB_DQS_DP<5>")
	)
	(gr_poly
		(pts
			(xy 84.92109 -275.504402) (xy 84.92109 -275.459952) (xy 84.720938 -275.459952) (xy 84.720938 -275.504402)
			(xy 84.821014 -275.604478)
		)
		(stroke
			(width 0)
			(type solid)
		)
		(fill yes)
		(layer "In11.Cu")
		(net "M_F_CPU1_SB_DQ<3>")
	)
	(gr_poly
		(pts
			(xy 84.92109 -273.88439) (xy 84.92109 -273.83994) (xy 84.720938 -273.83994) (xy 84.720938 -273.88439)
			(xy 84.821014 -273.984466)
		)
		(stroke
			(width 0)
			(type solid)
		)
		(fill yes)
		(layer "In11.Cu")
		(net "M_F_CPU1_SB_CB<3>")
	)
	(gr_poly
		(pts
			(xy 84.92109 -272.264632) (xy 84.92109 -272.21688) (xy 84.720938 -272.21688) (xy 84.720938 -272.264632)
			(xy 84.821014 -272.364454)
		)
		(stroke
			(width 0)
			(type solid)
		)
		(fill yes)
		(layer "In11.Cu")
		(net "M_F_CPU1_SB_DQS_DP<4>")
	)
	(gr_poly
		(pts
			(xy 84.92109 -270.644366) (xy 84.92109 -270.599916) (xy 84.720938 -270.599916) (xy 84.720938 -270.644366)
			(xy 84.821014 -270.744442)
		)
		(stroke
			(width 0)
			(type solid)
		)
		(fill yes)
		(layer "In11.Cu")
		(net "M_F_CPU1_SB_CB<7>")
	)
	(gr_poly
		(pts
			(xy 84.92109 -265.78433) (xy 84.92109 -265.73988) (xy 84.720938 -265.73988) (xy 84.720938 -265.78433)
			(xy 84.821014 -265.884406)
		)
		(stroke
			(width 0)
			(type solid)
		)
		(fill yes)
		(layer "In11.Cu")
		(net "M_F_CPU1_SB_CS_N<0>")
	)
	(gr_poly
		(pts
			(xy 84.92109 -264.164318) (xy 84.92109 -264.119868) (xy 84.720938 -264.119868) (xy 84.720938 -264.164318)
			(xy 84.821014 -264.264394)
		)
		(stroke
			(width 0)
			(type solid)
		)
		(fill yes)
		(layer "In11.Cu")
		(net "M_F_CPU1_SB_CA<5>")
	)
	(gr_poly
		(pts
			(xy 84.92109 -262.544306) (xy 84.92109 -262.499856) (xy 84.720938 -262.499856) (xy 84.720938 -262.544306)
			(xy 84.821014 -262.644382)
		)
		(stroke
			(width 0)
			(type solid)
		)
		(fill yes)
		(layer "In11.Cu")
		(net "M_F_CPU1_SB_CA<1>")
	)
	(gr_poly
		(pts
			(xy 85.091016 -255.622552) (xy 85.091016 -255.578102) (xy 84.890864 -255.578102) (xy 84.890864 -255.622552)
			(xy 84.99094 -255.722628)
		)
		(stroke
			(width 0)
			(type solid)
		)
		(fill yes)
		(layer "In11.Cu")
		(net "M_F_CPU1_SA_PAR")
	)
	(gr_poly
		(pts
			(xy 85.091016 -254.00254) (xy 85.091016 -253.95809) (xy 84.890864 -253.95809) (xy 84.890864 -254.00254)
			(xy 84.99094 -254.102616)
		)
		(stroke
			(width 0)
			(type solid)
		)
		(fill yes)
		(layer "In11.Cu")
		(net "M_F_CPU1_SA_CA<3>")
	)
	(gr_poly
		(pts
			(xy 85.091016 -252.382528) (xy 85.091016 -252.338078) (xy 84.890864 -252.338078) (xy 84.890864 -252.382528)
			(xy 84.99094 -252.482604)
		)
		(stroke
			(width 0)
			(type solid)
		)
		(fill yes)
		(layer "In11.Cu")
		(net "M_F_CPU1_SA_CS_N<1>")
	)
	(gr_poly
		(pts
			(xy 85.091016 -250.762516) (xy 85.091016 -250.718066) (xy 84.890864 -250.718066) (xy 84.890864 -250.762516)
			(xy 84.99094 -250.862592)
		)
		(stroke
			(width 0)
			(type solid)
		)
		(fill yes)
		(layer "In11.Cu")
		(net "M_F_CPU1_RESET_N")
	)
	(gr_poly
		(pts
			(xy 85.091016 -249.142504) (xy 85.091016 -249.098054) (xy 84.890864 -249.098054) (xy 84.890864 -249.142504)
			(xy 84.99094 -249.24258)
		)
		(stroke
			(width 0)
			(type solid)
		)
		(fill yes)
		(layer "In11.Cu")
		(net "M_F_CPU1_SA_CB<7>")
	)
	(gr_poly
		(pts
			(xy 85.091016 -247.522746) (xy 85.091016 -247.474994) (xy 84.890864 -247.474994) (xy 84.890864 -247.522746)
			(xy 84.99094 -247.622568)
		)
		(stroke
			(width 0)
			(type solid)
		)
		(fill yes)
		(layer "In11.Cu")
		(net "M_F_CPU1_SA_DQS_DP<9>")
	)
	(gr_poly
		(pts
			(xy 85.091016 -245.90248) (xy 85.091016 -245.85803) (xy 84.890864 -245.85803) (xy 84.890864 -245.90248)
			(xy 84.99094 -246.002556)
		)
		(stroke
			(width 0)
			(type solid)
		)
		(fill yes)
		(layer "In11.Cu")
		(net "M_F_CPU1_SA_CB<3>")
	)
	(gr_poly
		(pts
			(xy 85.091016 -244.282468) (xy 85.091016 -244.238018) (xy 84.890864 -244.238018) (xy 84.890864 -244.282468)
			(xy 84.99094 -244.382544)
		)
		(stroke
			(width 0)
			(type solid)
		)
		(fill yes)
		(layer "In11.Cu")
		(net "M_F_CPU1_SA_DQ<31>")
	)
	(gr_poly
		(pts
			(xy 85.091016 -242.66271) (xy 85.091016 -242.614958) (xy 84.890864 -242.614958) (xy 84.890864 -242.66271)
			(xy 84.99094 -242.762532)
		)
		(stroke
			(width 0)
			(type solid)
		)
		(fill yes)
		(layer "In11.Cu")
		(net "M_F_CPU1_SA_DQS_DP<8>")
	)
	(gr_poly
		(pts
			(xy 85.091016 -241.042444) (xy 85.091016 -240.997994) (xy 84.890864 -240.997994) (xy 84.890864 -241.042444)
			(xy 84.99094 -241.14252)
		)
		(stroke
			(width 0)
			(type solid)
		)
		(fill yes)
		(layer "In11.Cu")
		(net "M_F_CPU1_SA_DQ<27>")
	)
	(gr_poly
		(pts
			(xy 85.091016 -239.422432) (xy 85.091016 -239.377982) (xy 84.890864 -239.377982) (xy 84.890864 -239.422432)
			(xy 84.99094 -239.522508)
		)
		(stroke
			(width 0)
			(type solid)
		)
		(fill yes)
		(layer "In11.Cu")
		(net "M_F_CPU1_SA_DQ<23>")
	)
	(gr_poly
		(pts
			(xy 85.091016 -237.802674) (xy 85.091016 -237.754922) (xy 84.890864 -237.754922) (xy 84.890864 -237.802674)
			(xy 84.99094 -237.902496)
		)
		(stroke
			(width 0)
			(type solid)
		)
		(fill yes)
		(layer "In11.Cu")
		(net "M_F_CPU1_SA_DQS_DP<7>")
	)
	(gr_poly
		(pts
			(xy 85.091016 -236.182408) (xy 85.091016 -236.137958) (xy 84.890864 -236.137958) (xy 84.890864 -236.182408)
			(xy 84.99094 -236.282484)
		)
		(stroke
			(width 0)
			(type solid)
		)
		(fill yes)
		(layer "In11.Cu")
		(net "M_F_CPU1_SA_DQ<19>")
	)
	(gr_poly
		(pts
			(xy 85.091016 -234.562396) (xy 85.091016 -234.517946) (xy 84.890864 -234.517946) (xy 84.890864 -234.562396)
			(xy 84.99094 -234.662472)
		)
		(stroke
			(width 0)
			(type solid)
		)
		(fill yes)
		(layer "In11.Cu")
		(net "M_F_CPU1_SA_DQ<15>")
	)
	(gr_poly
		(pts
			(xy 85.091016 -232.942638) (xy 85.091016 -232.894886) (xy 84.890864 -232.894886) (xy 84.890864 -232.942638)
			(xy 84.99094 -233.04246)
		)
		(stroke
			(width 0)
			(type solid)
		)
		(fill yes)
		(layer "In11.Cu")
		(net "M_F_CPU1_SA_DQS_DP<6>")
	)
	(gr_poly
		(pts
			(xy 85.091016 -231.322626) (xy 85.091016 -231.278176) (xy 84.890864 -231.278176) (xy 84.890864 -231.322626)
			(xy 84.99094 -231.422702)
		)
		(stroke
			(width 0)
			(type solid)
		)
		(fill yes)
		(layer "In11.Cu")
		(net "M_F_CPU1_SA_DQ<11>")
	)
	(gr_poly
		(pts
			(xy 85.091016 -229.702614) (xy 85.091016 -229.658164) (xy 84.890864 -229.658164) (xy 84.890864 -229.702614)
			(xy 84.99094 -229.80269)
		)
		(stroke
			(width 0)
			(type solid)
		)
		(fill yes)
		(layer "In11.Cu")
		(net "M_F_CPU1_SA_DQ<7>")
	)
	(gr_poly
		(pts
			(xy 85.091016 -228.082856) (xy 85.091016 -228.035104) (xy 84.890864 -228.035104) (xy 84.890864 -228.082856)
			(xy 84.99094 -228.182678)
		)
		(stroke
			(width 0)
			(type solid)
		)
		(fill yes)
		(layer "In11.Cu")
		(net "M_F_CPU1_SA_DQS_DP<5>")
	)
	(gr_poly
		(pts
			(xy 85.091016 -226.46259) (xy 85.091016 -226.41814) (xy 84.890864 -226.41814) (xy 84.890864 -226.46259)
			(xy 84.99094 -226.562666)
		)
		(stroke
			(width 0)
			(type solid)
		)
		(fill yes)
		(layer "In11.Cu")
		(net "M_F_CPU1_SA_DQ<3>")
	)
	(gr_poly
		(pts
			(xy 85.39099 -292.918134) (xy 85.290914 -292.818058) (xy 85.190838 -292.918134) (xy 85.190838 -292.962584)
			(xy 85.39099 -292.962584)
		)
		(stroke
			(width 0)
			(type solid)
		)
		(fill yes)
		(layer "In11.Cu")
		(net "M_F_CPU1_SB_DQ<29>")
	)
	(gr_poly
		(pts
			(xy 85.39099 -291.297868) (xy 85.290914 -291.198046) (xy 85.190838 -291.297868) (xy 85.190838 -291.34562)
			(xy 85.39099 -291.34562)
		)
		(stroke
			(width 0)
			(type solid)
		)
		(fill yes)
		(layer "In11.Cu")
		(net "M_F_CPU1_SB_DQS_DN<8>")
	)
	(gr_poly
		(pts
			(xy 85.39099 -289.67811) (xy 85.290914 -289.578034) (xy 85.190838 -289.67811) (xy 85.190838 -289.72256)
			(xy 85.39099 -289.72256)
		)
		(stroke
			(width 0)
			(type solid)
		)
		(fill yes)
		(layer "In11.Cu")
		(net "M_F_CPU1_SB_DQ<25>")
	)
	(gr_poly
		(pts
			(xy 85.39099 -288.058098) (xy 85.290914 -287.958022) (xy 85.190838 -288.058098) (xy 85.190838 -288.102548)
			(xy 85.39099 -288.102548)
		)
		(stroke
			(width 0)
			(type solid)
		)
		(fill yes)
		(layer "In11.Cu")
		(net "M_F_CPU1_SB_DQ<21>")
	)
	(gr_poly
		(pts
			(xy 85.39099 -286.438086) (xy 85.290914 -286.33801) (xy 85.190838 -286.438086) (xy 85.190838 -286.485838)
			(xy 85.39099 -286.485838)
		)
		(stroke
			(width 0)
			(type solid)
		)
		(fill yes)
		(layer "In11.Cu")
		(net "M_F_CPU1_SB_DQS_DN<7>")
	)
	(gr_poly
		(pts
			(xy 85.39099 -284.818328) (xy 85.290914 -284.718252) (xy 85.190838 -284.818328) (xy 85.190838 -284.862778)
			(xy 85.39099 -284.862778)
		)
		(stroke
			(width 0)
			(type solid)
		)
		(fill yes)
		(layer "In11.Cu")
		(net "M_F_CPU1_SB_DQ<17>")
	)
	(gr_poly
		(pts
			(xy 85.39099 -283.198316) (xy 85.290914 -283.09824) (xy 85.190838 -283.198316) (xy 85.190838 -283.242766)
			(xy 85.39099 -283.242766)
		)
		(stroke
			(width 0)
			(type solid)
		)
		(fill yes)
		(layer "In11.Cu")
		(net "M_F_CPU1_SB_DQ<13>")
	)
	(gr_poly
		(pts
			(xy 85.39099 -281.57805) (xy 85.290914 -281.478228) (xy 85.190838 -281.57805) (xy 85.190838 -281.625802)
			(xy 85.39099 -281.625802)
		)
		(stroke
			(width 0)
			(type solid)
		)
		(fill yes)
		(layer "In11.Cu")
		(net "M_F_CPU1_SB_DQS_DN<6>")
	)
	(gr_poly
		(pts
			(xy 85.39099 -279.958292) (xy 85.290914 -279.858216) (xy 85.190838 -279.958292) (xy 85.190838 -280.002742)
			(xy 85.39099 -280.002742)
		)
		(stroke
			(width 0)
			(type solid)
		)
		(fill yes)
		(layer "In11.Cu")
		(net "M_F_CPU1_SB_DQ<9>")
	)
	(gr_poly
		(pts
			(xy 85.39099 -278.33828) (xy 85.290914 -278.238204) (xy 85.190838 -278.33828) (xy 85.190838 -278.38273)
			(xy 85.39099 -278.38273)
		)
		(stroke
			(width 0)
			(type solid)
		)
		(fill yes)
		(layer "In11.Cu")
		(net "M_F_CPU1_SB_DQ<5>")
	)
	(gr_poly
		(pts
			(xy 85.39099 -276.718014) (xy 85.290914 -276.618192) (xy 85.190838 -276.718014) (xy 85.190838 -276.765766)
			(xy 85.39099 -276.765766)
		)
		(stroke
			(width 0)
			(type solid)
		)
		(fill yes)
		(layer "In11.Cu")
		(net "M_F_CPU1_SB_DQS_DN<5>")
	)
	(gr_poly
		(pts
			(xy 85.39099 -275.098256) (xy 85.290914 -274.99818) (xy 85.190838 -275.098256) (xy 85.190838 -275.142706)
			(xy 85.39099 -275.142706)
		)
		(stroke
			(width 0)
			(type solid)
		)
		(fill yes)
		(layer "In11.Cu")
		(net "M_F_CPU1_SB_DQ<1>")
	)
	(gr_poly
		(pts
			(xy 85.39099 -273.478244) (xy 85.290914 -273.378168) (xy 85.190838 -273.478244) (xy 85.190838 -273.522694)
			(xy 85.39099 -273.522694)
		)
		(stroke
			(width 0)
			(type solid)
		)
		(fill yes)
		(layer "In11.Cu")
		(net "M_F_CPU1_SB_CB<1>")
	)
	(gr_poly
		(pts
			(xy 85.39099 -271.857978) (xy 85.290914 -271.758156) (xy 85.190838 -271.857978) (xy 85.190838 -271.90573)
			(xy 85.39099 -271.90573)
		)
		(stroke
			(width 0)
			(type solid)
		)
		(fill yes)
		(layer "In11.Cu")
		(net "M_F_CPU1_SB_DQS_DN<4>")
	)
	(gr_poly
		(pts
			(xy 85.39099 -270.23822) (xy 85.290914 -270.138144) (xy 85.190838 -270.23822) (xy 85.190838 -270.28267)
			(xy 85.39099 -270.28267)
		)
		(stroke
			(width 0)
			(type solid)
		)
		(fill yes)
		(layer "In11.Cu")
		(net "M_F_CPU1_SB_CB<5>")
	)
	(gr_poly
		(pts
			(xy 85.39099 -263.758172) (xy 85.290914 -263.658096) (xy 85.190838 -263.758172) (xy 85.190838 -263.802622)
			(xy 85.39099 -263.802622)
		)
		(stroke
			(width 0)
			(type solid)
		)
		(fill yes)
		(layer "In11.Cu")
		(net "M_F_CPU1_SB_CA<4>")
	)
	(gr_poly
		(pts
			(xy 85.39099 -262.13816) (xy 85.290914 -262.038084) (xy 85.190838 -262.13816) (xy 85.190838 -262.18261)
			(xy 85.39099 -262.18261)
		)
		(stroke
			(width 0)
			(type solid)
		)
		(fill yes)
		(layer "In11.Cu")
		(net "M_F_CPU1_SB_CA<0>")
	)
	(gr_poly
		(pts
			(xy 85.391244 -266.998196) (xy 85.291168 -266.89812) (xy 85.191092 -266.998196) (xy 85.191092 -267.042646)
			(xy 85.391244 -267.042646)
		)
		(stroke
			(width 0)
			(type solid)
		)
		(fill yes)
		(layer "In11.Cu")
		(net "M_F_CPU1_SA_RSP<0>")
	)
	(gr_poly
		(pts
			(xy 85.51291 -247.156986) (xy 85.508592 -247.109488) (xy 85.400388 -247.01881) (xy 85.309456 -247.127014)
			(xy 85.31352 -247.174512)
		)
		(stroke
			(width 0)
			(type solid)
		)
		(fill yes)
		(layer "In11.Cu")
		(net "M_F_CPU1_SA_DQS_DN<9>")
	)
	(gr_poly
		(pts
			(xy 85.51291 -242.29695) (xy 85.508592 -242.249452) (xy 85.400388 -242.158774) (xy 85.309456 -242.266978)
			(xy 85.31352 -242.314476)
		)
		(stroke
			(width 0)
			(type solid)
		)
		(fill yes)
		(layer "In11.Cu")
		(net "M_F_CPU1_SA_DQS_DN<8>")
	)
	(gr_poly
		(pts
			(xy 85.51291 -237.436914) (xy 85.508592 -237.38967) (xy 85.400388 -237.298738) (xy 85.309456 -237.406942)
			(xy 85.31352 -237.45444)
		)
		(stroke
			(width 0)
			(type solid)
		)
		(fill yes)
		(layer "In11.Cu")
		(net "M_F_CPU1_SA_DQS_DN<7>")
	)
	(gr_poly
		(pts
			(xy 85.51291 -232.576878) (xy 85.508592 -232.529634) (xy 85.400388 -232.438702) (xy 85.309456 -232.546906)
			(xy 85.31352 -232.594404)
		)
		(stroke
			(width 0)
			(type solid)
		)
		(fill yes)
		(layer "In11.Cu")
		(net "M_F_CPU1_SA_DQS_DN<6>")
	)
	(gr_poly
		(pts
			(xy 85.51291 -227.717096) (xy 85.508592 -227.669852) (xy 85.400388 -227.57892) (xy 85.309456 -227.687124)
			(xy 85.31352 -227.734622)
		)
		(stroke
			(width 0)
			(type solid)
		)
		(fill yes)
		(layer "In11.Cu")
		(net "M_F_CPU1_SA_DQS_DN<5>")
	)
	(gr_poly
		(pts
			(xy 85.52561 -255.253236) (xy 85.521546 -255.208786) (xy 85.413342 -255.117854) (xy 85.32241 -255.226312)
			(xy 85.32622 -255.270508)
		)
		(stroke
			(width 0)
			(type solid)
		)
		(fill yes)
		(layer "In11.Cu")
		(net "M_F_CPU1_SA_CA<6>")
	)
	(gr_poly
		(pts
			(xy 85.52561 -253.633224) (xy 85.521546 -253.588774) (xy 85.413342 -253.497842) (xy 85.32241 -253.6063)
			(xy 85.32622 -253.650496)
		)
		(stroke
			(width 0)
			(type solid)
		)
		(fill yes)
		(layer "In11.Cu")
		(net "M_F_CPU1_SA_CA<2>")
	)
	(gr_poly
		(pts
			(xy 85.52561 -250.3932) (xy 85.521546 -250.34875) (xy 85.413342 -250.257818) (xy 85.32241 -250.366276)
			(xy 85.32622 -250.410472)
		)
		(stroke
			(width 0)
			(type solid)
		)
		(fill yes)
		(layer "In11.Cu")
		(net "M_F_CPU1_ALERT_R_N")
	)
	(gr_poly
		(pts
			(xy 85.52561 -248.773188) (xy 85.521546 -248.728738) (xy 85.413342 -248.637806) (xy 85.32241 -248.746264)
			(xy 85.32622 -248.79046)
		)
		(stroke
			(width 0)
			(type solid)
		)
		(fill yes)
		(layer "In11.Cu")
		(net "M_F_CPU1_SA_CB<5>")
	)
	(gr_poly
		(pts
			(xy 85.52561 -245.533164) (xy 85.521546 -245.488714) (xy 85.413342 -245.397782) (xy 85.32241 -245.50624)
			(xy 85.32622 -245.550436)
		)
		(stroke
			(width 0)
			(type solid)
		)
		(fill yes)
		(layer "In11.Cu")
		(net "M_F_CPU1_SA_CB<1>")
	)
	(gr_poly
		(pts
			(xy 85.52561 -243.913152) (xy 85.521546 -243.868702) (xy 85.413342 -243.77777) (xy 85.32241 -243.886228)
			(xy 85.32622 -243.930424)
		)
		(stroke
			(width 0)
			(type solid)
		)
		(fill yes)
		(layer "In11.Cu")
		(net "M_F_CPU1_SA_DQ<29>")
	)
	(gr_poly
		(pts
			(xy 85.52561 -240.673128) (xy 85.521546 -240.628678) (xy 85.413342 -240.537746) (xy 85.32241 -240.646204)
			(xy 85.32622 -240.6904)
		)
		(stroke
			(width 0)
			(type solid)
		)
		(fill yes)
		(layer "In11.Cu")
		(net "M_F_CPU1_SA_DQ<25>")
	)
	(gr_poly
		(pts
			(xy 85.52561 -239.053116) (xy 85.521546 -239.008666) (xy 85.413342 -238.917734) (xy 85.32241 -239.026192)
			(xy 85.32622 -239.070388)
		)
		(stroke
			(width 0)
			(type solid)
		)
		(fill yes)
		(layer "In11.Cu")
		(net "M_F_CPU1_SA_DQ<21>")
	)
	(gr_poly
		(pts
			(xy 85.52561 -235.813092) (xy 85.521546 -235.768642) (xy 85.413342 -235.67771) (xy 85.32241 -235.786168)
			(xy 85.32622 -235.830364)
		)
		(stroke
			(width 0)
			(type solid)
		)
		(fill yes)
		(layer "In11.Cu")
		(net "M_F_CPU1_SA_DQ<17>")
	)
	(gr_poly
		(pts
			(xy 85.52561 -234.19308) (xy 85.521546 -234.14863) (xy 85.413342 -234.057698) (xy 85.32241 -234.166156)
			(xy 85.32622 -234.210352)
		)
		(stroke
			(width 0)
			(type solid)
		)
		(fill yes)
		(layer "In11.Cu")
		(net "M_F_CPU1_SA_DQ<13>")
	)
	(gr_poly
		(pts
			(xy 85.52561 -230.953056) (xy 85.5218 -230.90886) (xy 85.413342 -230.817928) (xy 85.32241 -230.926132)
			(xy 85.326474 -230.970328)
		)
		(stroke
			(width 0)
			(type solid)
		)
		(fill yes)
		(layer "In11.Cu")
		(net "M_F_CPU1_SA_DQ<9>")
	)
	(gr_poly
		(pts
			(xy 85.52561 -229.333044) (xy 85.5218 -229.288848) (xy 85.413342 -229.197916) (xy 85.32241 -229.30612)
			(xy 85.326474 -229.350316)
		)
		(stroke
			(width 0)
			(type solid)
		)
		(fill yes)
		(layer "In11.Cu")
		(net "M_F_CPU1_SA_DQ<5>")
	)
	(gr_poly
		(pts
			(xy 85.52561 -226.093274) (xy 85.521546 -226.048824) (xy 85.413342 -225.957892) (xy 85.32241 -226.06635)
			(xy 85.32622 -226.110546)
		)
		(stroke
			(width 0)
			(type solid)
		)
		(fill yes)
		(layer "In11.Cu")
		(net "M_F_CPU1_SA_DQ<1>")
	)
	(gr_poly
		(pts
			(xy 85.808566 -286.872426) (xy 85.812884 -286.824928) (xy 85.613494 -286.807656) (xy 85.60943 -286.8549)
			(xy 85.700362 -286.963358)
		)
		(stroke
			(width 0)
			(type solid)
		)
		(fill yes)
		(layer "In11.Cu")
		(net "M_F_CPU1_SB_DQS_DP<7>")
	)
	(gr_poly
		(pts
			(xy 85.808566 -281.991308) (xy 85.812884 -281.94381) (xy 85.613494 -281.926284) (xy 85.60943 -281.973782)
			(xy 85.700362 -282.081986)
		)
		(stroke
			(width 0)
			(type solid)
		)
		(fill yes)
		(layer "In11.Cu")
		(net "M_F_CPU1_SB_DQS_DP<6>")
	)
	(gr_poly
		(pts
			(xy 85.808566 -277.131272) (xy 85.812884 -277.083774) (xy 85.613494 -277.066248) (xy 85.60943 -277.113746)
			(xy 85.700362 -277.22195)
		)
		(stroke
			(width 0)
			(type solid)
		)
		(fill yes)
		(layer "In11.Cu")
		(net "M_F_CPU1_SB_DQS_DP<5>")
	)
	(gr_poly
		(pts
			(xy 85.808566 -272.271236) (xy 85.812884 -272.223738) (xy 85.613494 -272.206212) (xy 85.60943 -272.25371)
			(xy 85.700362 -272.361914)
		)
		(stroke
			(width 0)
			(type solid)
		)
		(fill yes)
		(layer "In11.Cu")
		(net "M_F_CPU1_SB_DQS_DP<4>")
	)
	(gr_poly
		(pts
			(xy 85.814916 -291.738558) (xy 85.819234 -291.691314) (xy 85.619844 -291.673788) (xy 85.61578 -291.721286)
			(xy 85.706712 -291.82949)
		)
		(stroke
			(width 0)
			(type solid)
		)
		(fill yes)
		(layer "In11.Cu")
		(net "M_F_CPU1_SB_DQS_DP<8>")
	)
	(gr_poly
		(pts
			(xy 85.82152 -290.091876) (xy 85.82533 -290.047426) (xy 85.626194 -290.030154) (xy 85.622384 -290.07435)
			(xy 85.713316 -290.182808)
		)
		(stroke
			(width 0)
			(type solid)
		)
		(fill yes)
		(layer "In11.Cu")
		(net "M_F_CPU1_SB_DQ<27>")
	)
	(gr_poly
		(pts
			(xy 85.82152 -285.232094) (xy 85.82533 -285.187644) (xy 85.626194 -285.170372) (xy 85.622384 -285.214568)
			(xy 85.713316 -285.323026)
		)
		(stroke
			(width 0)
			(type solid)
		)
		(fill yes)
		(layer "In11.Cu")
		(net "M_F_CPU1_SB_DQ<19>")
	)
	(gr_poly
		(pts
			(xy 85.82152 -283.612082) (xy 85.82533 -283.567632) (xy 85.626194 -283.55036) (xy 85.622384 -283.594556)
			(xy 85.713316 -283.703014)
		)
		(stroke
			(width 0)
			(type solid)
		)
		(fill yes)
		(layer "In11.Cu")
		(net "M_F_CPU1_SB_DQ<15>")
	)
	(gr_poly
		(pts
			(xy 85.82152 -280.372058) (xy 85.82533 -280.327608) (xy 85.626194 -280.310336) (xy 85.622384 -280.354532)
			(xy 85.713316 -280.46299)
		)
		(stroke
			(width 0)
			(type solid)
		)
		(fill yes)
		(layer "In11.Cu")
		(net "M_F_CPU1_SB_DQ<11>")
	)
	(gr_poly
		(pts
			(xy 85.82152 -278.752046) (xy 85.82533 -278.707596) (xy 85.626194 -278.690324) (xy 85.622384 -278.73452)
			(xy 85.713316 -278.842978)
		)
		(stroke
			(width 0)
			(type solid)
		)
		(fill yes)
		(layer "In11.Cu")
		(net "M_F_CPU1_SB_DQ<7>")
	)
	(gr_poly
		(pts
			(xy 85.82152 -275.512022) (xy 85.82533 -275.467572) (xy 85.626194 -275.4503) (xy 85.622384 -275.494496)
			(xy 85.713316 -275.602954)
		)
		(stroke
			(width 0)
			(type solid)
		)
		(fill yes)
		(layer "In11.Cu")
		(net "M_F_CPU1_SB_DQ<3>")
	)
	(gr_poly
		(pts
			(xy 85.82152 -273.89201) (xy 85.82533 -273.84756) (xy 85.626194 -273.830288) (xy 85.622384 -273.874484)
			(xy 85.713316 -273.982942)
		)
		(stroke
			(width 0)
			(type solid)
		)
		(fill yes)
		(layer "In11.Cu")
		(net "M_F_CPU1_SB_CB<3>")
	)
	(gr_poly
		(pts
			(xy 85.82152 -270.651986) (xy 85.82533 -270.607536) (xy 85.626194 -270.590264) (xy 85.622384 -270.63446)
			(xy 85.713316 -270.742918)
		)
		(stroke
			(width 0)
			(type solid)
		)
		(fill yes)
		(layer "In11.Cu")
		(net "M_F_CPU1_SB_CB<7>")
	)
	(gr_poly
		(pts
			(xy 85.82152 -265.79195) (xy 85.82533 -265.7475) (xy 85.626194 -265.730228) (xy 85.622384 -265.774424)
			(xy 85.713316 -265.882882)
		)
		(stroke
			(width 0)
			(type solid)
		)
		(fill yes)
		(layer "In11.Cu")
		(net "M_F_CPU1_SB_CS_N<0>")
	)
	(gr_poly
		(pts
			(xy 85.82152 -264.171938) (xy 85.82533 -264.127488) (xy 85.626194 -264.110216) (xy 85.622384 -264.154412)
			(xy 85.713316 -264.26287)
		)
		(stroke
			(width 0)
			(type solid)
		)
		(fill yes)
		(layer "In11.Cu")
		(net "M_F_CPU1_SB_CA<5>")
	)
	(gr_poly
		(pts
			(xy 85.82152 -262.551926) (xy 85.82533 -262.507476) (xy 85.626194 -262.490204) (xy 85.622384 -262.5344)
			(xy 85.713316 -262.642858)
		)
		(stroke
			(width 0)
			(type solid)
		)
		(fill yes)
		(layer "In11.Cu")
		(net "M_F_CPU1_SB_CA<1>")
	)
	(gr_poly
		(pts
			(xy 85.821774 -288.471864) (xy 85.825584 -288.427668) (xy 85.626448 -288.410396) (xy 85.622384 -288.454592)
			(xy 85.713316 -288.562796)
		)
		(stroke
			(width 0)
			(type solid)
		)
		(fill yes)
		(layer "In11.Cu")
		(net "M_F_CPU1_SB_DQ<23>")
	)
	(gr_poly
		(pts
			(xy 138.233404 -255.226312) (xy 138.142472 -255.117854) (xy 138.034268 -255.208786) (xy 138.030458 -255.253236)
			(xy 138.229594 -255.270508)
		)
		(stroke
			(width 0)
			(type solid)
		)
		(fill yes)
		(layer "In11.Cu")
		(net "M_L_CPU1_SA_CA<6>")
	)
	(gr_poly
		(pts
			(xy 138.233404 -253.6063) (xy 138.142472 -253.497842) (xy 138.034268 -253.588774) (xy 138.030458 -253.633224)
			(xy 138.229594 -253.650496)
		)
		(stroke
			(width 0)
			(type solid)
		)
		(fill yes)
		(layer "In11.Cu")
		(net "M_L_CPU1_SA_CA<2>")
	)
	(gr_poly
		(pts
			(xy 138.233404 -250.366276) (xy 138.142472 -250.257818) (xy 138.034268 -250.34875) (xy 138.030458 -250.3932)
			(xy 138.229594 -250.410472)
		)
		(stroke
			(width 0)
			(type solid)
		)
		(fill yes)
		(layer "In11.Cu")
		(net "M_L_CPU1_ALERT_R_N")
	)
	(gr_poly
		(pts
			(xy 138.233404 -248.746264) (xy 138.142472 -248.637806) (xy 138.034268 -248.728738) (xy 138.030458 -248.773188)
			(xy 138.229594 -248.79046)
		)
		(stroke
			(width 0)
			(type solid)
		)
		(fill yes)
		(layer "In11.Cu")
		(net "M_L_CPU1_SA_CB<5>")
	)
	(gr_poly
		(pts
			(xy 138.233404 -245.50624) (xy 138.142472 -245.397782) (xy 138.034268 -245.488714) (xy 138.030458 -245.533164)
			(xy 138.229594 -245.550436)
		)
		(stroke
			(width 0)
			(type solid)
		)
		(fill yes)
		(layer "In11.Cu")
		(net "M_L_CPU1_SA_CB<1>")
	)
	(gr_poly
		(pts
			(xy 138.233404 -243.886228) (xy 138.142472 -243.77777) (xy 138.034268 -243.868702) (xy 138.030458 -243.913152)
			(xy 138.229594 -243.930424)
		)
		(stroke
			(width 0)
			(type solid)
		)
		(fill yes)
		(layer "In11.Cu")
		(net "M_L_CPU1_SA_DQ<29>")
	)
	(gr_poly
		(pts
			(xy 138.233404 -240.646204) (xy 138.142472 -240.537746) (xy 138.034268 -240.628678) (xy 138.030458 -240.673128)
			(xy 138.229594 -240.6904)
		)
		(stroke
			(width 0)
			(type solid)
		)
		(fill yes)
		(layer "In11.Cu")
		(net "M_L_CPU1_SA_DQ<25>")
	)
	(gr_poly
		(pts
			(xy 138.233404 -239.026192) (xy 138.142472 -238.917734) (xy 138.034268 -239.008666) (xy 138.030458 -239.053116)
			(xy 138.229594 -239.070388)
		)
		(stroke
			(width 0)
			(type solid)
		)
		(fill yes)
		(layer "In11.Cu")
		(net "M_L_CPU1_SA_DQ<21>")
	)
	(gr_poly
		(pts
			(xy 138.233404 -235.786168) (xy 138.142472 -235.67771) (xy 138.034268 -235.768642) (xy 138.030458 -235.813092)
			(xy 138.229594 -235.830364)
		)
		(stroke
			(width 0)
			(type solid)
		)
		(fill yes)
		(layer "In11.Cu")
		(net "M_L_CPU1_SA_DQ<17>")
	)
	(gr_poly
		(pts
			(xy 138.233404 -234.166156) (xy 138.142472 -234.057698) (xy 138.034268 -234.14863) (xy 138.030458 -234.19308)
			(xy 138.229594 -234.210352)
		)
		(stroke
			(width 0)
			(type solid)
		)
		(fill yes)
		(layer "In11.Cu")
		(net "M_L_CPU1_SA_DQ<13>")
	)
	(gr_poly
		(pts
			(xy 138.233404 -230.926132) (xy 138.142472 -230.817928) (xy 138.034014 -230.90886) (xy 138.030204 -230.953056)
			(xy 138.22934 -230.970328)
		)
		(stroke
			(width 0)
			(type solid)
		)
		(fill yes)
		(layer "In11.Cu")
		(net "M_L_CPU1_SA_DQ<9>")
	)
	(gr_poly
		(pts
			(xy 138.233404 -229.30612) (xy 138.142472 -229.197916) (xy 138.034014 -229.288848) (xy 138.030204 -229.333044)
			(xy 138.22934 -229.350316)
		)
		(stroke
			(width 0)
			(type solid)
		)
		(fill yes)
		(layer "In11.Cu")
		(net "M_L_CPU1_SA_DQ<5>")
	)
	(gr_poly
		(pts
			(xy 138.233404 -226.06635) (xy 138.142472 -225.957892) (xy 138.034268 -226.048824) (xy 138.030458 -226.093274)
			(xy 138.229594 -226.110546)
		)
		(stroke
			(width 0)
			(type solid)
		)
		(fill yes)
		(layer "In11.Cu")
		(net "M_L_CPU1_SA_DQ<1>")
	)
	(gr_poly
		(pts
			(xy 138.235436 -247.126252) (xy 138.144504 -247.017794) (xy 138.0363 -247.108726) (xy 138.031982 -247.156224)
			(xy 138.231372 -247.173496)
		)
		(stroke
			(width 0)
			(type solid)
		)
		(fill yes)
		(layer "In11.Cu")
		(net "M_L_CPU1_SA_DQS_DN<9>")
	)
	(gr_poly
		(pts
			(xy 138.235436 -242.266216) (xy 138.144504 -242.157758) (xy 138.0363 -242.24869) (xy 138.031982 -242.296188)
			(xy 138.231372 -242.31346)
		)
		(stroke
			(width 0)
			(type solid)
		)
		(fill yes)
		(layer "In11.Cu")
		(net "M_L_CPU1_SA_DQS_DN<8>")
	)
	(gr_poly
		(pts
			(xy 138.235436 -237.40618) (xy 138.144504 -237.297722) (xy 138.0363 -237.388654) (xy 138.031982 -237.436152)
			(xy 138.231372 -237.453424)
		)
		(stroke
			(width 0)
			(type solid)
		)
		(fill yes)
		(layer "In11.Cu")
		(net "M_L_CPU1_SA_DQS_DN<7>")
	)
	(gr_poly
		(pts
			(xy 138.235436 -232.546144) (xy 138.144504 -232.437686) (xy 138.0363 -232.528618) (xy 138.031982 -232.576116)
			(xy 138.231372 -232.593388)
		)
		(stroke
			(width 0)
			(type solid)
		)
		(fill yes)
		(layer "In11.Cu")
		(net "M_L_CPU1_SA_DQS_DN<6>")
	)
	(gr_poly
		(pts
			(xy 138.235436 -227.686362) (xy 138.144504 -227.577904) (xy 138.0363 -227.668836) (xy 138.031982 -227.716334)
			(xy 138.231372 -227.73386)
		)
		(stroke
			(width 0)
			(type solid)
		)
		(fill yes)
		(layer "In11.Cu")
		(net "M_L_CPU1_SA_DQS_DN<5>")
	)
	(gr_poly
		(pts
			(xy 138.235944 -251.979938) (xy 138.145012 -251.871734) (xy 138.036554 -251.962666) (xy 138.032744 -252.006862)
			(xy 138.232134 -252.024388)
		)
		(stroke
			(width 0)
			(type solid)
		)
		(fill yes)
		(layer "In11.Cu")
		(net "M_L_CPU1_SA_CS_N<1>")
	)
	(gr_poly
		(pts
			(xy 138.533378 -290.07435) (xy 138.529568 -290.030154) (xy 138.330178 -290.047426) (xy 138.334242 -290.091876)
			(xy 138.442446 -290.182808)
		)
		(stroke
			(width 0)
			(type solid)
		)
		(fill yes)
		(layer "In11.Cu")
		(net "M_L_CPU1_SB_DQ<27>")
	)
	(gr_poly
		(pts
			(xy 138.533378 -288.454592) (xy 138.529314 -288.410396) (xy 138.330178 -288.427668) (xy 138.333988 -288.471864)
			(xy 138.442446 -288.562796)
		)
		(stroke
			(width 0)
			(type solid)
		)
		(fill yes)
		(layer "In11.Cu")
		(net "M_L_CPU1_SB_DQ<23>")
	)
	(gr_poly
		(pts
			(xy 138.533378 -285.214568) (xy 138.529568 -285.170372) (xy 138.330178 -285.187644) (xy 138.334242 -285.232094)
			(xy 138.442446 -285.323026)
		)
		(stroke
			(width 0)
			(type solid)
		)
		(fill yes)
		(layer "In11.Cu")
		(net "M_L_CPU1_SB_DQ<19>")
	)
	(gr_poly
		(pts
			(xy 138.533378 -283.594556) (xy 138.529568 -283.55036) (xy 138.330178 -283.567632) (xy 138.334242 -283.612082)
			(xy 138.442446 -283.703014)
		)
		(stroke
			(width 0)
			(type solid)
		)
		(fill yes)
		(layer "In11.Cu")
		(net "M_L_CPU1_SB_DQ<15>")
	)
	(gr_poly
		(pts
			(xy 138.533378 -280.354532) (xy 138.529568 -280.310336) (xy 138.330178 -280.327608) (xy 138.334242 -280.372058)
			(xy 138.442446 -280.46299)
		)
		(stroke
			(width 0)
			(type solid)
		)
		(fill yes)
		(layer "In11.Cu")
		(net "M_L_CPU1_SB_DQ<11>")
	)
	(gr_poly
		(pts
			(xy 138.533378 -278.73452) (xy 138.529568 -278.690324) (xy 138.330178 -278.707596) (xy 138.334242 -278.752046)
			(xy 138.442446 -278.842978)
		)
		(stroke
			(width 0)
			(type solid)
		)
		(fill yes)
		(layer "In11.Cu")
		(net "M_L_CPU1_SB_DQ<7>")
	)
	(gr_poly
		(pts
			(xy 138.533378 -275.494496) (xy 138.529568 -275.4503) (xy 138.330178 -275.467572) (xy 138.334242 -275.512022)
			(xy 138.442446 -275.602954)
		)
		(stroke
			(width 0)
			(type solid)
		)
		(fill yes)
		(layer "In11.Cu")
		(net "M_L_CPU1_SB_DQ<3>")
	)
	(gr_poly
		(pts
			(xy 138.533378 -273.874484) (xy 138.529568 -273.830288) (xy 138.330178 -273.84756) (xy 138.334242 -273.89201)
			(xy 138.442446 -273.982942)
		)
		(stroke
			(width 0)
			(type solid)
		)
		(fill yes)
		(layer "In11.Cu")
		(net "M_L_CPU1_SB_CB<3>")
	)
	(gr_poly
		(pts
			(xy 138.533378 -270.63446) (xy 138.529568 -270.590264) (xy 138.330178 -270.607536) (xy 138.334242 -270.651986)
			(xy 138.442446 -270.742918)
		)
		(stroke
			(width 0)
			(type solid)
		)
		(fill yes)
		(layer "In11.Cu")
		(net "M_L_CPU1_SB_CB<7>")
	)
	(gr_poly
		(pts
			(xy 138.533378 -265.774424) (xy 138.529568 -265.730228) (xy 138.330178 -265.7475) (xy 138.334242 -265.79195)
			(xy 138.442446 -265.882882)
		)
		(stroke
			(width 0)
			(type solid)
		)
		(fill yes)
		(layer "In11.Cu")
		(net "M_L_CPU1_SB_CS_N<0>")
	)
	(gr_poly
		(pts
			(xy 138.533378 -264.154412) (xy 138.529568 -264.110216) (xy 138.330178 -264.127488) (xy 138.334242 -264.171938)
			(xy 138.442446 -264.26287)
		)
		(stroke
			(width 0)
			(type solid)
		)
		(fill yes)
		(layer "In11.Cu")
		(net "M_L_CPU1_SB_CA<5>")
	)
	(gr_poly
		(pts
			(xy 138.533378 -262.5344) (xy 138.529568 -262.490204) (xy 138.330178 -262.507476) (xy 138.334242 -262.551926)
			(xy 138.442446 -262.642858)
		)
		(stroke
			(width 0)
			(type solid)
		)
		(fill yes)
		(layer "In11.Cu")
		(net "M_L_CPU1_SB_CA<1>")
	)
	(gr_poly
		(pts
			(xy 138.546332 -291.6936) (xy 138.542268 -291.646102) (xy 138.342878 -291.663628) (xy 138.347196 -291.710872)
			(xy 138.4554 -291.801804)
		)
		(stroke
			(width 0)
			(type solid)
		)
		(fill yes)
		(layer "In11.Cu")
		(net "M_L_CPU1_SB_DQS_DP<8>")
	)
	(gr_poly
		(pts
			(xy 138.546332 -286.833564) (xy 138.542268 -286.78632) (xy 138.342878 -286.803592) (xy 138.347196 -286.85109)
			(xy 138.4554 -286.942022)
		)
		(stroke
			(width 0)
			(type solid)
		)
		(fill yes)
		(layer "In11.Cu")
		(net "M_L_CPU1_SB_DQS_DP<7>")
	)
	(gr_poly
		(pts
			(xy 138.546332 -281.973782) (xy 138.542268 -281.926284) (xy 138.342878 -281.94381) (xy 138.347196 -281.991308)
			(xy 138.4554 -282.081986)
		)
		(stroke
			(width 0)
			(type solid)
		)
		(fill yes)
		(layer "In11.Cu")
		(net "M_L_CPU1_SB_DQS_DP<6>")
	)
	(gr_poly
		(pts
			(xy 138.546332 -277.113746) (xy 138.542268 -277.066248) (xy 138.342878 -277.083774) (xy 138.347196 -277.131272)
			(xy 138.4554 -277.22195)
		)
		(stroke
			(width 0)
			(type solid)
		)
		(fill yes)
		(layer "In11.Cu")
		(net "M_L_CPU1_SB_DQS_DP<5>")
	)
	(gr_poly
		(pts
			(xy 138.546332 -272.25371) (xy 138.542268 -272.206212) (xy 138.342878 -272.223738) (xy 138.347196 -272.271236)
			(xy 138.4554 -272.361914)
		)
		(stroke
			(width 0)
			(type solid)
		)
		(fill yes)
		(layer "In11.Cu")
		(net "M_L_CPU1_SB_DQS_DP<4>")
	)
	(gr_poly
		(pts
			(xy 138.66495 -255.622552) (xy 138.66495 -255.578102) (xy 138.464798 -255.578102) (xy 138.464798 -255.622552)
			(xy 138.564874 -255.722628)
		)
		(stroke
			(width 0)
			(type solid)
		)
		(fill yes)
		(layer "In11.Cu")
		(net "M_L_CPU1_SA_PAR")
	)
	(gr_poly
		(pts
			(xy 138.66495 -254.00254) (xy 138.66495 -253.95809) (xy 138.464798 -253.95809) (xy 138.464798 -254.00254)
			(xy 138.564874 -254.102616)
		)
		(stroke
			(width 0)
			(type solid)
		)
		(fill yes)
		(layer "In11.Cu")
		(net "M_L_CPU1_SA_CA<3>")
	)
	(gr_poly
		(pts
			(xy 138.66495 -250.762516) (xy 138.66495 -250.718066) (xy 138.464798 -250.718066) (xy 138.464798 -250.762516)
			(xy 138.564874 -250.862592)
		)
		(stroke
			(width 0)
			(type solid)
		)
		(fill yes)
		(layer "In11.Cu")
		(net "M_L_CPU1_RESET_N")
	)
	(gr_poly
		(pts
			(xy 138.66495 -249.142504) (xy 138.66495 -249.098054) (xy 138.464798 -249.098054) (xy 138.464798 -249.142504)
			(xy 138.564874 -249.24258)
		)
		(stroke
			(width 0)
			(type solid)
		)
		(fill yes)
		(layer "In11.Cu")
		(net "M_L_CPU1_SA_CB<7>")
	)
	(gr_poly
		(pts
			(xy 138.66495 -247.522746) (xy 138.66495 -247.474994) (xy 138.464798 -247.474994) (xy 138.464798 -247.522746)
			(xy 138.564874 -247.622568)
		)
		(stroke
			(width 0)
			(type solid)
		)
		(fill yes)
		(layer "In11.Cu")
		(net "M_L_CPU1_SA_DQS_DP<9>")
	)
	(gr_poly
		(pts
			(xy 138.66495 -245.90248) (xy 138.66495 -245.85803) (xy 138.464798 -245.85803) (xy 138.464798 -245.90248)
			(xy 138.564874 -246.002556)
		)
		(stroke
			(width 0)
			(type solid)
		)
		(fill yes)
		(layer "In11.Cu")
		(net "M_L_CPU1_SA_CB<3>")
	)
	(gr_poly
		(pts
			(xy 138.66495 -244.282468) (xy 138.66495 -244.238018) (xy 138.464798 -244.238018) (xy 138.464798 -244.282468)
			(xy 138.564874 -244.382544)
		)
		(stroke
			(width 0)
			(type solid)
		)
		(fill yes)
		(layer "In11.Cu")
		(net "M_L_CPU1_SA_DQ<31>")
	)
	(gr_poly
		(pts
			(xy 138.66495 -242.66271) (xy 138.66495 -242.614958) (xy 138.464798 -242.614958) (xy 138.464798 -242.66271)
			(xy 138.564874 -242.762532)
		)
		(stroke
			(width 0)
			(type solid)
		)
		(fill yes)
		(layer "In11.Cu")
		(net "M_L_CPU1_SA_DQS_DP<8>")
	)
	(gr_poly
		(pts
			(xy 138.66495 -241.042444) (xy 138.66495 -240.997994) (xy 138.464798 -240.997994) (xy 138.464798 -241.042444)
			(xy 138.564874 -241.14252)
		)
		(stroke
			(width 0)
			(type solid)
		)
		(fill yes)
		(layer "In11.Cu")
		(net "M_L_CPU1_SA_DQ<27>")
	)
	(gr_poly
		(pts
			(xy 138.66495 -239.422432) (xy 138.66495 -239.377982) (xy 138.464798 -239.377982) (xy 138.464798 -239.422432)
			(xy 138.564874 -239.522508)
		)
		(stroke
			(width 0)
			(type solid)
		)
		(fill yes)
		(layer "In11.Cu")
		(net "M_L_CPU1_SA_DQ<23>")
	)
	(gr_poly
		(pts
			(xy 138.66495 -237.802674) (xy 138.66495 -237.754922) (xy 138.464798 -237.754922) (xy 138.464798 -237.802674)
			(xy 138.564874 -237.902496)
		)
		(stroke
			(width 0)
			(type solid)
		)
		(fill yes)
		(layer "In11.Cu")
		(net "M_L_CPU1_SA_DQS_DP<7>")
	)
	(gr_poly
		(pts
			(xy 138.66495 -236.182408) (xy 138.66495 -236.137958) (xy 138.464798 -236.137958) (xy 138.464798 -236.182408)
			(xy 138.564874 -236.282484)
		)
		(stroke
			(width 0)
			(type solid)
		)
		(fill yes)
		(layer "In11.Cu")
		(net "M_L_CPU1_SA_DQ<19>")
	)
	(gr_poly
		(pts
			(xy 138.66495 -234.562396) (xy 138.66495 -234.517946) (xy 138.464798 -234.517946) (xy 138.464798 -234.562396)
			(xy 138.564874 -234.662472)
		)
		(stroke
			(width 0)
			(type solid)
		)
		(fill yes)
		(layer "In11.Cu")
		(net "M_L_CPU1_SA_DQ<15>")
	)
	(gr_poly
		(pts
			(xy 138.66495 -232.942638) (xy 138.66495 -232.894886) (xy 138.464798 -232.894886) (xy 138.464798 -232.942638)
			(xy 138.564874 -233.04246)
		)
		(stroke
			(width 0)
			(type solid)
		)
		(fill yes)
		(layer "In11.Cu")
		(net "M_L_CPU1_SA_DQS_DP<6>")
	)
	(gr_poly
		(pts
			(xy 138.66495 -231.322626) (xy 138.66495 -231.278176) (xy 138.464798 -231.278176) (xy 138.464798 -231.322626)
			(xy 138.564874 -231.422702)
		)
		(stroke
			(width 0)
			(type solid)
		)
		(fill yes)
		(layer "In11.Cu")
		(net "M_L_CPU1_SA_DQ<11>")
	)
	(gr_poly
		(pts
			(xy 138.66495 -229.702614) (xy 138.66495 -229.658164) (xy 138.464798 -229.658164) (xy 138.464798 -229.702614)
			(xy 138.564874 -229.80269)
		)
		(stroke
			(width 0)
			(type solid)
		)
		(fill yes)
		(layer "In11.Cu")
		(net "M_L_CPU1_SA_DQ<7>")
	)
	(gr_poly
		(pts
			(xy 138.66495 -228.082856) (xy 138.66495 -228.035104) (xy 138.464798 -228.035104) (xy 138.464798 -228.082856)
			(xy 138.564874 -228.182678)
		)
		(stroke
			(width 0)
			(type solid)
		)
		(fill yes)
		(layer "In11.Cu")
		(net "M_L_CPU1_SA_DQS_DP<5>")
	)
	(gr_poly
		(pts
			(xy 138.66495 -226.46259) (xy 138.66495 -226.41814) (xy 138.464798 -226.41814) (xy 138.464798 -226.46259)
			(xy 138.564874 -226.562666)
		)
		(stroke
			(width 0)
			(type solid)
		)
		(fill yes)
		(layer "In11.Cu")
		(net "M_L_CPU1_SA_DQ<3>")
	)
	(gr_poly
		(pts
			(xy 138.964924 -291.297868) (xy 138.864848 -291.198046) (xy 138.764772 -291.297868) (xy 138.764772 -291.34562)
			(xy 138.964924 -291.34562)
		)
		(stroke
			(width 0)
			(type solid)
		)
		(fill yes)
		(layer "In11.Cu")
		(net "M_L_CPU1_SB_DQS_DN<8>")
	)
	(gr_poly
		(pts
			(xy 138.964924 -289.67811) (xy 138.864848 -289.578034) (xy 138.764772 -289.67811) (xy 138.764772 -289.72256)
			(xy 138.964924 -289.72256)
		)
		(stroke
			(width 0)
			(type solid)
		)
		(fill yes)
		(layer "In11.Cu")
		(net "M_L_CPU1_SB_DQ<25>")
	)
	(gr_poly
		(pts
			(xy 138.964924 -288.058098) (xy 138.864848 -287.958022) (xy 138.764772 -288.058098) (xy 138.764772 -288.102548)
			(xy 138.964924 -288.102548)
		)
		(stroke
			(width 0)
			(type solid)
		)
		(fill yes)
		(layer "In11.Cu")
		(net "M_L_CPU1_SB_DQ<21>")
	)
	(gr_poly
		(pts
			(xy 138.964924 -286.438086) (xy 138.864848 -286.33801) (xy 138.764772 -286.438086) (xy 138.764772 -286.485838)
			(xy 138.964924 -286.485838)
		)
		(stroke
			(width 0)
			(type solid)
		)
		(fill yes)
		(layer "In11.Cu")
		(net "M_L_CPU1_SB_DQS_DN<7>")
	)
	(gr_poly
		(pts
			(xy 138.964924 -284.818328) (xy 138.864848 -284.718252) (xy 138.764772 -284.818328) (xy 138.764772 -284.862778)
			(xy 138.964924 -284.862778)
		)
		(stroke
			(width 0)
			(type solid)
		)
		(fill yes)
		(layer "In11.Cu")
		(net "M_L_CPU1_SB_DQ<17>")
	)
	(gr_poly
		(pts
			(xy 138.964924 -283.198316) (xy 138.864848 -283.09824) (xy 138.764772 -283.198316) (xy 138.764772 -283.242766)
			(xy 138.964924 -283.242766)
		)
		(stroke
			(width 0)
			(type solid)
		)
		(fill yes)
		(layer "In11.Cu")
		(net "M_L_CPU1_SB_DQ<13>")
	)
	(gr_poly
		(pts
			(xy 138.964924 -281.57805) (xy 138.864848 -281.478228) (xy 138.764772 -281.57805) (xy 138.764772 -281.625802)
			(xy 138.964924 -281.625802)
		)
		(stroke
			(width 0)
			(type solid)
		)
		(fill yes)
		(layer "In11.Cu")
		(net "M_L_CPU1_SB_DQS_DN<6>")
	)
	(gr_poly
		(pts
			(xy 138.964924 -279.958292) (xy 138.864848 -279.858216) (xy 138.764772 -279.958292) (xy 138.764772 -280.002742)
			(xy 138.964924 -280.002742)
		)
		(stroke
			(width 0)
			(type solid)
		)
		(fill yes)
		(layer "In11.Cu")
		(net "M_L_CPU1_SB_DQ<9>")
	)
	(gr_poly
		(pts
			(xy 138.964924 -278.33828) (xy 138.864848 -278.238204) (xy 138.764772 -278.33828) (xy 138.764772 -278.38273)
			(xy 138.964924 -278.38273)
		)
		(stroke
			(width 0)
			(type solid)
		)
		(fill yes)
		(layer "In11.Cu")
		(net "M_L_CPU1_SB_DQ<5>")
	)
	(gr_poly
		(pts
			(xy 138.964924 -276.718014) (xy 138.864848 -276.618192) (xy 138.764772 -276.718014) (xy 138.764772 -276.765766)
			(xy 138.964924 -276.765766)
		)
		(stroke
			(width 0)
			(type solid)
		)
		(fill yes)
		(layer "In11.Cu")
		(net "M_L_CPU1_SB_DQS_DN<5>")
	)
	(gr_poly
		(pts
			(xy 138.964924 -275.098256) (xy 138.864848 -274.99818) (xy 138.764772 -275.098256) (xy 138.764772 -275.142706)
			(xy 138.964924 -275.142706)
		)
		(stroke
			(width 0)
			(type solid)
		)
		(fill yes)
		(layer "In11.Cu")
		(net "M_L_CPU1_SB_DQ<1>")
	)
	(gr_poly
		(pts
			(xy 138.964924 -273.478244) (xy 138.864848 -273.378168) (xy 138.764772 -273.478244) (xy 138.764772 -273.522694)
			(xy 138.964924 -273.522694)
		)
		(stroke
			(width 0)
			(type solid)
		)
		(fill yes)
		(layer "In11.Cu")
		(net "M_L_CPU1_SB_CB<1>")
	)
	(gr_poly
		(pts
			(xy 138.964924 -271.857978) (xy 138.864848 -271.758156) (xy 138.764772 -271.857978) (xy 138.764772 -271.90573)
			(xy 138.964924 -271.90573)
		)
		(stroke
			(width 0)
			(type solid)
		)
		(fill yes)
		(layer "In11.Cu")
		(net "M_L_CPU1_SB_DQS_DN<4>")
	)
	(gr_poly
		(pts
			(xy 138.964924 -270.23822) (xy 138.864848 -270.138144) (xy 138.764772 -270.23822) (xy 138.764772 -270.28267)
			(xy 138.964924 -270.28267)
		)
		(stroke
			(width 0)
			(type solid)
		)
		(fill yes)
		(layer "In11.Cu")
		(net "M_L_CPU1_SB_CB<5>")
	)
	(gr_poly
		(pts
			(xy 138.964924 -266.998196) (xy 138.864848 -266.89812) (xy 138.764772 -266.998196) (xy 138.764772 -267.042646)
			(xy 138.964924 -267.042646)
		)
		(stroke
			(width 0)
			(type solid)
		)
		(fill yes)
		(layer "In11.Cu")
		(net "M_L_CPU1_SA_RSP<0>")
	)
	(gr_poly
		(pts
			(xy 138.964924 -265.378184) (xy 138.864848 -265.278108) (xy 138.764772 -265.378184) (xy 138.764772 -265.422634)
			(xy 138.964924 -265.422634)
		)
		(stroke
			(width 0)
			(type solid)
		)
		(fill yes)
		(layer "In11.Cu")
		(net "M_L_CPU1_SB_PAR")
	)
	(gr_poly
		(pts
			(xy 138.964924 -263.758172) (xy 138.864848 -263.658096) (xy 138.764772 -263.758172) (xy 138.764772 -263.802622)
			(xy 138.964924 -263.802622)
		)
		(stroke
			(width 0)
			(type solid)
		)
		(fill yes)
		(layer "In11.Cu")
		(net "M_L_CPU1_SB_CA<4>")
	)
	(gr_poly
		(pts
			(xy 138.964924 -262.13816) (xy 138.864848 -262.038084) (xy 138.764772 -262.13816) (xy 138.764772 -262.18261)
			(xy 138.964924 -262.18261)
		)
		(stroke
			(width 0)
			(type solid)
		)
		(fill yes)
		(layer "In11.Cu")
		(net "M_L_CPU1_SB_CA<0>")
	)
	(gr_poly
		(pts
			(xy 139.13485 -255.216406) (xy 139.034774 -255.11633) (xy 138.934698 -255.216406) (xy 138.934698 -255.260856)
			(xy 139.13485 -255.260856)
		)
		(stroke
			(width 0)
			(type solid)
		)
		(fill yes)
		(layer "In11.Cu")
		(net "M_L_CPU1_SA_CA<6>")
	)
	(gr_poly
		(pts
			(xy 139.13485 -253.596394) (xy 139.034774 -253.496318) (xy 138.934698 -253.596394) (xy 138.934698 -253.640844)
			(xy 139.13485 -253.640844)
		)
		(stroke
			(width 0)
			(type solid)
		)
		(fill yes)
		(layer "In11.Cu")
		(net "M_L_CPU1_SA_CA<2>")
	)
	(gr_poly
		(pts
			(xy 139.13485 -251.970032) (xy 139.034774 -251.869956) (xy 138.934698 -251.970032) (xy 138.934698 -252.014482)
			(xy 139.13485 -252.014482)
		)
		(stroke
			(width 0)
			(type solid)
		)
		(fill yes)
		(layer "In11.Cu")
		(net "M_L_CPU1_SA_CS_N<1>")
	)
	(gr_poly
		(pts
			(xy 139.13485 -250.35637) (xy 139.034774 -250.256294) (xy 138.934698 -250.35637) (xy 138.934698 -250.40082)
			(xy 139.13485 -250.40082)
		)
		(stroke
			(width 0)
			(type solid)
		)
		(fill yes)
		(layer "In11.Cu")
		(net "M_L_CPU1_ALERT_R_N")
	)
	(gr_poly
		(pts
			(xy 139.13485 -248.736358) (xy 139.034774 -248.636282) (xy 138.934698 -248.736358) (xy 138.934698 -248.780808)
			(xy 139.13485 -248.780808)
		)
		(stroke
			(width 0)
			(type solid)
		)
		(fill yes)
		(layer "In11.Cu")
		(net "M_L_CPU1_SA_CB<5>")
	)
	(gr_poly
		(pts
			(xy 139.13485 -247.116092) (xy 139.034774 -247.01627) (xy 138.934698 -247.116092) (xy 138.934698 -247.163844)
			(xy 139.13485 -247.163844)
		)
		(stroke
			(width 0)
			(type solid)
		)
		(fill yes)
		(layer "In11.Cu")
		(net "M_L_CPU1_SA_DQS_DN<9>")
	)
	(gr_poly
		(pts
			(xy 139.13485 -245.496334) (xy 139.034774 -245.396258) (xy 138.934698 -245.496334) (xy 138.934698 -245.540784)
			(xy 139.13485 -245.540784)
		)
		(stroke
			(width 0)
			(type solid)
		)
		(fill yes)
		(layer "In11.Cu")
		(net "M_L_CPU1_SA_CB<1>")
	)
	(gr_poly
		(pts
			(xy 139.13485 -243.876322) (xy 139.034774 -243.776246) (xy 138.934698 -243.876322) (xy 138.934698 -243.920772)
			(xy 139.13485 -243.920772)
		)
		(stroke
			(width 0)
			(type solid)
		)
		(fill yes)
		(layer "In11.Cu")
		(net "M_L_CPU1_SA_DQ<29>")
	)
	(gr_poly
		(pts
			(xy 139.13485 -242.256056) (xy 139.034774 -242.156234) (xy 138.934698 -242.256056) (xy 138.934698 -242.303808)
			(xy 139.13485 -242.303808)
		)
		(stroke
			(width 0)
			(type solid)
		)
		(fill yes)
		(layer "In11.Cu")
		(net "M_L_CPU1_SA_DQS_DN<8>")
	)
	(gr_poly
		(pts
			(xy 139.13485 -240.636298) (xy 139.034774 -240.536222) (xy 138.934698 -240.636298) (xy 138.934698 -240.680748)
			(xy 139.13485 -240.680748)
		)
		(stroke
			(width 0)
			(type solid)
		)
		(fill yes)
		(layer "In11.Cu")
		(net "M_L_CPU1_SA_DQ<25>")
	)
	(gr_poly
		(pts
			(xy 139.13485 -239.016286) (xy 139.034774 -238.91621) (xy 138.934698 -239.016286) (xy 138.934698 -239.060736)
			(xy 139.13485 -239.060736)
		)
		(stroke
			(width 0)
			(type solid)
		)
		(fill yes)
		(layer "In11.Cu")
		(net "M_L_CPU1_SA_DQ<21>")
	)
	(gr_poly
		(pts
			(xy 139.13485 -237.39602) (xy 139.034774 -237.296198) (xy 138.934698 -237.39602) (xy 138.934698 -237.443772)
			(xy 139.13485 -237.443772)
		)
		(stroke
			(width 0)
			(type solid)
		)
		(fill yes)
		(layer "In11.Cu")
		(net "M_L_CPU1_SA_DQS_DN<7>")
	)
	(gr_poly
		(pts
			(xy 139.13485 -235.776262) (xy 139.034774 -235.676186) (xy 138.934698 -235.776262) (xy 138.934698 -235.820712)
			(xy 139.13485 -235.820712)
		)
		(stroke
			(width 0)
			(type solid)
		)
		(fill yes)
		(layer "In11.Cu")
		(net "M_L_CPU1_SA_DQ<17>")
	)
	(gr_poly
		(pts
			(xy 139.13485 -234.15625) (xy 139.034774 -234.056174) (xy 138.934698 -234.15625) (xy 138.934698 -234.2007)
			(xy 139.13485 -234.2007)
		)
		(stroke
			(width 0)
			(type solid)
		)
		(fill yes)
		(layer "In11.Cu")
		(net "M_L_CPU1_SA_DQ<13>")
	)
	(gr_poly
		(pts
			(xy 139.13485 -232.535984) (xy 139.034774 -232.436162) (xy 138.934698 -232.535984) (xy 138.934698 -232.583736)
			(xy 139.13485 -232.583736)
		)
		(stroke
			(width 0)
			(type solid)
		)
		(fill yes)
		(layer "In11.Cu")
		(net "M_L_CPU1_SA_DQS_DN<6>")
	)
	(gr_poly
		(pts
			(xy 139.13485 -230.916226) (xy 139.034774 -230.81615) (xy 138.934698 -230.916226) (xy 138.934698 -230.960676)
			(xy 139.13485 -230.960676)
		)
		(stroke
			(width 0)
			(type solid)
		)
		(fill yes)
		(layer "In11.Cu")
		(net "M_L_CPU1_SA_DQ<9>")
	)
	(gr_poly
		(pts
			(xy 139.13485 -229.296214) (xy 139.034774 -229.196138) (xy 138.934698 -229.296214) (xy 138.934698 -229.340664)
			(xy 139.13485 -229.340664)
		)
		(stroke
			(width 0)
			(type solid)
		)
		(fill yes)
		(layer "In11.Cu")
		(net "M_L_CPU1_SA_DQ<5>")
	)
	(gr_poly
		(pts
			(xy 139.13485 -227.676202) (xy 139.034774 -227.57638) (xy 138.934698 -227.676202) (xy 138.934698 -227.723954)
			(xy 139.13485 -227.723954)
		)
		(stroke
			(width 0)
			(type solid)
		)
		(fill yes)
		(layer "In11.Cu")
		(net "M_L_CPU1_SA_DQS_DN<5>")
	)
	(gr_poly
		(pts
			(xy 139.13485 -226.056444) (xy 139.034774 -225.956368) (xy 138.934698 -226.056444) (xy 138.934698 -226.100894)
			(xy 139.13485 -226.100894)
		)
		(stroke
			(width 0)
			(type solid)
		)
		(fill yes)
		(layer "In11.Cu")
		(net "M_L_CPU1_SA_DQ<1>")
	)
	(gr_poly
		(pts
			(xy 139.434824 -291.704522) (xy 139.434824 -291.65677) (xy 139.234672 -291.65677) (xy 139.234672 -291.704522)
			(xy 139.334748 -291.804344)
		)
		(stroke
			(width 0)
			(type solid)
		)
		(fill yes)
		(layer "In11.Cu")
		(net "M_L_CPU1_SB_DQS_DP<8>")
	)
	(gr_poly
		(pts
			(xy 139.434824 -290.084256) (xy 139.434824 -290.039806) (xy 139.234672 -290.039806) (xy 139.234672 -290.084256)
			(xy 139.334748 -290.184332)
		)
		(stroke
			(width 0)
			(type solid)
		)
		(fill yes)
		(layer "In11.Cu")
		(net "M_L_CPU1_SB_DQ<27>")
	)
	(gr_poly
		(pts
			(xy 139.434824 -288.464498) (xy 139.434824 -288.420048) (xy 139.234672 -288.420048) (xy 139.234672 -288.464498)
			(xy 139.334748 -288.564574)
		)
		(stroke
			(width 0)
			(type solid)
		)
		(fill yes)
		(layer "In11.Cu")
		(net "M_L_CPU1_SB_DQ<23>")
	)
	(gr_poly
		(pts
			(xy 139.434824 -286.844486) (xy 139.434824 -286.796734) (xy 139.234672 -286.796734) (xy 139.234672 -286.844486)
			(xy 139.334748 -286.944562)
		)
		(stroke
			(width 0)
			(type solid)
		)
		(fill yes)
		(layer "In11.Cu")
		(net "M_L_CPU1_SB_DQS_DP<7>")
	)
	(gr_poly
		(pts
			(xy 139.434824 -285.224474) (xy 139.434824 -285.180024) (xy 139.234672 -285.180024) (xy 139.234672 -285.224474)
			(xy 139.334748 -285.32455)
		)
		(stroke
			(width 0)
			(type solid)
		)
		(fill yes)
		(layer "In11.Cu")
		(net "M_L_CPU1_SB_DQ<19>")
	)
	(gr_poly
		(pts
			(xy 139.434824 -283.604462) (xy 139.434824 -283.560012) (xy 139.234672 -283.560012) (xy 139.234672 -283.604462)
			(xy 139.334748 -283.704538)
		)
		(stroke
			(width 0)
			(type solid)
		)
		(fill yes)
		(layer "In11.Cu")
		(net "M_L_CPU1_SB_DQ<15>")
	)
	(gr_poly
		(pts
			(xy 139.434824 -281.984704) (xy 139.434824 -281.936952) (xy 139.234672 -281.936952) (xy 139.234672 -281.984704)
			(xy 139.334748 -282.084526)
		)
		(stroke
			(width 0)
			(type solid)
		)
		(fill yes)
		(layer "In11.Cu")
		(net "M_L_CPU1_SB_DQS_DP<6>")
	)
	(gr_poly
		(pts
			(xy 139.434824 -280.364438) (xy 139.434824 -280.319988) (xy 139.234672 -280.319988) (xy 139.234672 -280.364438)
			(xy 139.334748 -280.464514)
		)
		(stroke
			(width 0)
			(type solid)
		)
		(fill yes)
		(layer "In11.Cu")
		(net "M_L_CPU1_SB_DQ<11>")
	)
	(gr_poly
		(pts
			(xy 139.434824 -278.744426) (xy 139.434824 -278.699976) (xy 139.234672 -278.699976) (xy 139.234672 -278.744426)
			(xy 139.334748 -278.844502)
		)
		(stroke
			(width 0)
			(type solid)
		)
		(fill yes)
		(layer "In11.Cu")
		(net "M_L_CPU1_SB_DQ<7>")
	)
	(gr_poly
		(pts
			(xy 139.434824 -277.124668) (xy 139.434824 -277.076916) (xy 139.234672 -277.076916) (xy 139.234672 -277.124668)
			(xy 139.334748 -277.22449)
		)
		(stroke
			(width 0)
			(type solid)
		)
		(fill yes)
		(layer "In11.Cu")
		(net "M_L_CPU1_SB_DQS_DP<5>")
	)
	(gr_poly
		(pts
			(xy 139.434824 -275.504402) (xy 139.434824 -275.459952) (xy 139.234672 -275.459952) (xy 139.234672 -275.504402)
			(xy 139.334748 -275.604478)
		)
		(stroke
			(width 0)
			(type solid)
		)
		(fill yes)
		(layer "In11.Cu")
		(net "M_L_CPU1_SB_DQ<3>")
	)
	(gr_poly
		(pts
			(xy 139.434824 -273.88439) (xy 139.434824 -273.83994) (xy 139.234672 -273.83994) (xy 139.234672 -273.88439)
			(xy 139.334748 -273.984466)
		)
		(stroke
			(width 0)
			(type solid)
		)
		(fill yes)
		(layer "In11.Cu")
		(net "M_L_CPU1_SB_CB<3>")
	)
	(gr_poly
		(pts
			(xy 139.434824 -272.264632) (xy 139.434824 -272.21688) (xy 139.234672 -272.21688) (xy 139.234672 -272.264632)
			(xy 139.334748 -272.364454)
		)
		(stroke
			(width 0)
			(type solid)
		)
		(fill yes)
		(layer "In11.Cu")
		(net "M_L_CPU1_SB_DQS_DP<4>")
	)
	(gr_poly
		(pts
			(xy 139.434824 -270.644366) (xy 139.434824 -270.599916) (xy 139.234672 -270.599916) (xy 139.234672 -270.644366)
			(xy 139.334748 -270.744442)
		)
		(stroke
			(width 0)
			(type solid)
		)
		(fill yes)
		(layer "In11.Cu")
		(net "M_L_CPU1_SB_CB<7>")
	)
	(gr_poly
		(pts
			(xy 139.434824 -265.78433) (xy 139.434824 -265.73988) (xy 139.234672 -265.73988) (xy 139.234672 -265.78433)
			(xy 139.334748 -265.884406)
		)
		(stroke
			(width 0)
			(type solid)
		)
		(fill yes)
		(layer "In11.Cu")
		(net "M_L_CPU1_SB_CS_N<0>")
	)
	(gr_poly
		(pts
			(xy 139.434824 -264.164318) (xy 139.434824 -264.119868) (xy 139.234672 -264.119868) (xy 139.234672 -264.164318)
			(xy 139.334748 -264.264394)
		)
		(stroke
			(width 0)
			(type solid)
		)
		(fill yes)
		(layer "In11.Cu")
		(net "M_L_CPU1_SB_CA<5>")
	)
	(gr_poly
		(pts
			(xy 139.434824 -262.544306) (xy 139.434824 -262.499856) (xy 139.234672 -262.499856) (xy 139.234672 -262.544306)
			(xy 139.334748 -262.644382)
		)
		(stroke
			(width 0)
			(type solid)
		)
		(fill yes)
		(layer "In11.Cu")
		(net "M_L_CPU1_SB_CA<1>")
	)
	(gr_poly
		(pts
			(xy 139.60475 -255.622552) (xy 139.60475 -255.578102) (xy 139.404598 -255.578102) (xy 139.404598 -255.622552)
			(xy 139.504674 -255.722628)
		)
		(stroke
			(width 0)
			(type solid)
		)
		(fill yes)
		(layer "In11.Cu")
		(net "M_L_CPU1_SA_PAR")
	)
	(gr_poly
		(pts
			(xy 139.60475 -254.00254) (xy 139.60475 -253.95809) (xy 139.404598 -253.95809) (xy 139.404598 -254.00254)
			(xy 139.504674 -254.102616)
		)
		(stroke
			(width 0)
			(type solid)
		)
		(fill yes)
		(layer "In11.Cu")
		(net "M_L_CPU1_SA_CA<3>")
	)
	(gr_poly
		(pts
			(xy 139.60475 -250.762516) (xy 139.60475 -250.718066) (xy 139.404598 -250.718066) (xy 139.404598 -250.762516)
			(xy 139.504674 -250.862592)
		)
		(stroke
			(width 0)
			(type solid)
		)
		(fill yes)
		(layer "In11.Cu")
		(net "M_L_CPU1_RESET_N")
	)
	(gr_poly
		(pts
			(xy 139.60475 -249.142504) (xy 139.60475 -249.098054) (xy 139.404598 -249.098054) (xy 139.404598 -249.142504)
			(xy 139.504674 -249.24258)
		)
		(stroke
			(width 0)
			(type solid)
		)
		(fill yes)
		(layer "In11.Cu")
		(net "M_L_CPU1_SA_CB<7>")
	)
	(gr_poly
		(pts
			(xy 139.60475 -247.522746) (xy 139.60475 -247.474994) (xy 139.404598 -247.474994) (xy 139.404598 -247.522746)
			(xy 139.504674 -247.622568)
		)
		(stroke
			(width 0)
			(type solid)
		)
		(fill yes)
		(layer "In11.Cu")
		(net "M_L_CPU1_SA_DQS_DP<9>")
	)
	(gr_poly
		(pts
			(xy 139.60475 -245.90248) (xy 139.60475 -245.85803) (xy 139.404598 -245.85803) (xy 139.404598 -245.90248)
			(xy 139.504674 -246.002556)
		)
		(stroke
			(width 0)
			(type solid)
		)
		(fill yes)
		(layer "In11.Cu")
		(net "M_L_CPU1_SA_CB<3>")
	)
	(gr_poly
		(pts
			(xy 139.60475 -244.282468) (xy 139.60475 -244.238018) (xy 139.404598 -244.238018) (xy 139.404598 -244.282468)
			(xy 139.504674 -244.382544)
		)
		(stroke
			(width 0)
			(type solid)
		)
		(fill yes)
		(layer "In11.Cu")
		(net "M_L_CPU1_SA_DQ<31>")
	)
	(gr_poly
		(pts
			(xy 139.60475 -242.66271) (xy 139.60475 -242.614958) (xy 139.404598 -242.614958) (xy 139.404598 -242.66271)
			(xy 139.504674 -242.762532)
		)
		(stroke
			(width 0)
			(type solid)
		)
		(fill yes)
		(layer "In11.Cu")
		(net "M_L_CPU1_SA_DQS_DP<8>")
	)
	(gr_poly
		(pts
			(xy 139.60475 -241.042444) (xy 139.60475 -240.997994) (xy 139.404598 -240.997994) (xy 139.404598 -241.042444)
			(xy 139.504674 -241.14252)
		)
		(stroke
			(width 0)
			(type solid)
		)
		(fill yes)
		(layer "In11.Cu")
		(net "M_L_CPU1_SA_DQ<27>")
	)
	(gr_poly
		(pts
			(xy 139.60475 -239.422432) (xy 139.60475 -239.377982) (xy 139.404598 -239.377982) (xy 139.404598 -239.422432)
			(xy 139.504674 -239.522508)
		)
		(stroke
			(width 0)
			(type solid)
		)
		(fill yes)
		(layer "In11.Cu")
		(net "M_L_CPU1_SA_DQ<23>")
	)
	(gr_poly
		(pts
			(xy 139.60475 -237.802674) (xy 139.60475 -237.754922) (xy 139.404598 -237.754922) (xy 139.404598 -237.802674)
			(xy 139.504674 -237.902496)
		)
		(stroke
			(width 0)
			(type solid)
		)
		(fill yes)
		(layer "In11.Cu")
		(net "M_L_CPU1_SA_DQS_DP<7>")
	)
	(gr_poly
		(pts
			(xy 139.60475 -236.182408) (xy 139.60475 -236.137958) (xy 139.404598 -236.137958) (xy 139.404598 -236.182408)
			(xy 139.504674 -236.282484)
		)
		(stroke
			(width 0)
			(type solid)
		)
		(fill yes)
		(layer "In11.Cu")
		(net "M_L_CPU1_SA_DQ<19>")
	)
	(gr_poly
		(pts
			(xy 139.60475 -234.562396) (xy 139.60475 -234.517946) (xy 139.404598 -234.517946) (xy 139.404598 -234.562396)
			(xy 139.504674 -234.662472)
		)
		(stroke
			(width 0)
			(type solid)
		)
		(fill yes)
		(layer "In11.Cu")
		(net "M_L_CPU1_SA_DQ<15>")
	)
	(gr_poly
		(pts
			(xy 139.60475 -232.942638) (xy 139.60475 -232.894886) (xy 139.404598 -232.894886) (xy 139.404598 -232.942638)
			(xy 139.504674 -233.04246)
		)
		(stroke
			(width 0)
			(type solid)
		)
		(fill yes)
		(layer "In11.Cu")
		(net "M_L_CPU1_SA_DQS_DP<6>")
	)
	(gr_poly
		(pts
			(xy 139.60475 -231.322626) (xy 139.60475 -231.278176) (xy 139.404598 -231.278176) (xy 139.404598 -231.322626)
			(xy 139.504674 -231.422702)
		)
		(stroke
			(width 0)
			(type solid)
		)
		(fill yes)
		(layer "In11.Cu")
		(net "M_L_CPU1_SA_DQ<11>")
	)
	(gr_poly
		(pts
			(xy 139.60475 -229.702614) (xy 139.60475 -229.658164) (xy 139.404598 -229.658164) (xy 139.404598 -229.702614)
			(xy 139.504674 -229.80269)
		)
		(stroke
			(width 0)
			(type solid)
		)
		(fill yes)
		(layer "In11.Cu")
		(net "M_L_CPU1_SA_DQ<7>")
	)
	(gr_poly
		(pts
			(xy 139.60475 -228.082856) (xy 139.60475 -228.035104) (xy 139.404598 -228.035104) (xy 139.404598 -228.082856)
			(xy 139.504674 -228.182678)
		)
		(stroke
			(width 0)
			(type solid)
		)
		(fill yes)
		(layer "In11.Cu")
		(net "M_L_CPU1_SA_DQS_DP<5>")
	)
	(gr_poly
		(pts
			(xy 139.60475 -226.46259) (xy 139.60475 -226.41814) (xy 139.404598 -226.41814) (xy 139.404598 -226.46259)
			(xy 139.504674 -226.562666)
		)
		(stroke
			(width 0)
			(type solid)
		)
		(fill yes)
		(layer "In11.Cu")
		(net "M_L_CPU1_SA_DQ<3>")
	)
	(gr_poly
		(pts
			(xy 139.643358 -254.416306) (xy 139.552426 -254.307848) (xy 139.444222 -254.39878) (xy 139.440158 -254.44323)
			(xy 139.639548 -254.460502)
		)
		(stroke
			(width 0)
			(type solid)
		)
		(fill yes)
		(layer "In11.Cu")
		(net "M_L_CPU1_SA_CA<4>")
	)
	(gr_poly
		(pts
			(xy 139.643358 -252.796294) (xy 139.552426 -252.687836) (xy 139.444222 -252.778768) (xy 139.440158 -252.823218)
			(xy 139.639548 -252.84049)
		)
		(stroke
			(width 0)
			(type solid)
		)
		(fill yes)
		(layer "In11.Cu")
		(net "M_L_CPU1_SA_CA<0>")
	)
	(gr_poly
		(pts
			(xy 139.643358 -247.936258) (xy 139.552426 -247.8278) (xy 139.444222 -247.918732) (xy 139.440158 -247.963182)
			(xy 139.639548 -247.980454)
		)
		(stroke
			(width 0)
			(type solid)
		)
		(fill yes)
		(layer "In11.Cu")
		(net "M_L_CPU1_SA_CB<4>")
	)
	(gr_poly
		(pts
			(xy 139.643358 -244.696234) (xy 139.552426 -244.587776) (xy 139.444222 -244.678708) (xy 139.440158 -244.723158)
			(xy 139.639548 -244.74043)
		)
		(stroke
			(width 0)
			(type solid)
		)
		(fill yes)
		(layer "In11.Cu")
		(net "M_L_CPU1_SA_CB<0>")
	)
	(gr_poly
		(pts
			(xy 139.643358 -243.076222) (xy 139.552426 -242.967764) (xy 139.444222 -243.058696) (xy 139.440158 -243.103146)
			(xy 139.639548 -243.120418)
		)
		(stroke
			(width 0)
			(type solid)
		)
		(fill yes)
		(layer "In11.Cu")
		(net "M_L_CPU1_SA_DQ<28>")
	)
	(gr_poly
		(pts
			(xy 139.643358 -239.836198) (xy 139.552426 -239.72774) (xy 139.444222 -239.818672) (xy 139.440158 -239.863122)
			(xy 139.639548 -239.880394)
		)
		(stroke
			(width 0)
			(type solid)
		)
		(fill yes)
		(layer "In11.Cu")
		(net "M_L_CPU1_SA_DQ<24>")
	)
	(gr_poly
		(pts
			(xy 139.643358 -238.216186) (xy 139.552426 -238.107728) (xy 139.444222 -238.19866) (xy 139.440158 -238.24311)
			(xy 139.639548 -238.260382)
		)
		(stroke
			(width 0)
			(type solid)
		)
		(fill yes)
		(layer "In11.Cu")
		(net "M_L_CPU1_SA_DQ<20>")
	)
	(gr_poly
		(pts
			(xy 139.643358 -234.976162) (xy 139.552426 -234.867704) (xy 139.444222 -234.958636) (xy 139.440158 -235.003086)
			(xy 139.639548 -235.020358)
		)
		(stroke
			(width 0)
			(type solid)
		)
		(fill yes)
		(layer "In11.Cu")
		(net "M_L_CPU1_SA_DQ<16>")
	)
	(gr_poly
		(pts
			(xy 139.643358 -233.35615) (xy 139.552426 -233.247692) (xy 139.444222 -233.338624) (xy 139.440158 -233.383074)
			(xy 139.639548 -233.400346)
		)
		(stroke
			(width 0)
			(type solid)
		)
		(fill yes)
		(layer "In11.Cu")
		(net "M_L_CPU1_SA_DQ<12>")
	)
	(gr_poly
		(pts
			(xy 139.643358 -230.116126) (xy 139.552426 -230.007668) (xy 139.444222 -230.0986) (xy 139.440158 -230.14305)
			(xy 139.639548 -230.160322)
		)
		(stroke
			(width 0)
			(type solid)
		)
		(fill yes)
		(layer "In11.Cu")
		(net "M_L_CPU1_SA_DQ<8>")
	)
	(gr_poly
		(pts
			(xy 139.643358 -228.496368) (xy 139.552426 -228.38791) (xy 139.444222 -228.478842) (xy 139.440158 -228.523292)
			(xy 139.639548 -228.540564)
		)
		(stroke
			(width 0)
			(type solid)
		)
		(fill yes)
		(layer "In11.Cu")
		(net "M_L_CPU1_SA_DQ<4>")
	)
	(gr_poly
		(pts
			(xy 139.643358 -225.256344) (xy 139.552426 -225.147886) (xy 139.444222 -225.238818) (xy 139.440158 -225.283268)
			(xy 139.639548 -225.30054)
		)
		(stroke
			(width 0)
			(type solid)
		)
		(fill yes)
		(layer "In11.Cu")
		(net "M_L_CPU1_SA_DQ<0>")
	)
	(gr_poly
		(pts
			(xy 139.64539 -246.316246) (xy 139.554458 -246.207788) (xy 139.446254 -246.29872) (xy 139.44219 -246.346218)
			(xy 139.641326 -246.363744)
		)
		(stroke
			(width 0)
			(type solid)
		)
		(fill yes)
		(layer "In11.Cu")
		(net "M_L_CPU1_SA_DQS_DP<4>")
	)
	(gr_poly
		(pts
			(xy 139.64539 -241.45621) (xy 139.554458 -241.347752) (xy 139.446254 -241.438684) (xy 139.44219 -241.486182)
			(xy 139.641326 -241.503708)
		)
		(stroke
			(width 0)
			(type solid)
		)
		(fill yes)
		(layer "In11.Cu")
		(net "M_L_CPU1_SA_DQS_DP<3>")
	)
	(gr_poly
		(pts
			(xy 139.64539 -236.596174) (xy 139.554458 -236.487716) (xy 139.446254 -236.578648) (xy 139.44219 -236.626146)
			(xy 139.641326 -236.643672)
		)
		(stroke
			(width 0)
			(type solid)
		)
		(fill yes)
		(layer "In11.Cu")
		(net "M_L_CPU1_SA_DQS_DP<2>")
	)
	(gr_poly
		(pts
			(xy 139.64539 -231.736138) (xy 139.554458 -231.62768) (xy 139.446254 -231.718612) (xy 139.44219 -231.76611)
			(xy 139.641326 -231.783636)
		)
		(stroke
			(width 0)
			(type solid)
		)
		(fill yes)
		(layer "In11.Cu")
		(net "M_L_CPU1_SA_DQS_DP<1>")
	)
	(gr_poly
		(pts
			(xy 139.64539 -226.876356) (xy 139.554458 -226.767898) (xy 139.446254 -226.85883) (xy 139.44219 -226.906328)
			(xy 139.641326 -226.9236)
		)
		(stroke
			(width 0)
			(type solid)
		)
		(fill yes)
		(layer "In11.Cu")
		(net "M_L_CPU1_SA_DQS_DP<0>")
	)
	(gr_poly
		(pts
			(xy 139.645898 -251.169932) (xy 139.554966 -251.061728) (xy 139.446762 -251.15266) (xy 139.442698 -251.196856)
			(xy 139.642088 -251.214382)
		)
		(stroke
			(width 0)
			(type solid)
		)
		(fill yes)
		(layer "In11.Cu")
		(net "M_L_CPU1_SA_CS_N<0>")
	)
	(gr_poly
		(pts
			(xy 139.656312 -256.03708) (xy 139.56538 -255.928876) (xy 139.457176 -256.019808) (xy 139.452858 -256.067052)
			(xy 139.652248 -256.084578)
		)
		(stroke
			(width 0)
			(type solid)
		)
		(fill yes)
		(layer "In11.Cu")
		(net "M_L_CPU1_CLK_DP<0>")
	)
	(gr_poly
		(pts
			(xy 139.904724 -292.918134) (xy 139.804648 -292.818058) (xy 139.704572 -292.918134) (xy 139.704572 -292.962584)
			(xy 139.904724 -292.962584)
		)
		(stroke
			(width 0)
			(type solid)
		)
		(fill yes)
		(layer "In11.Cu")
		(net "M_L_CPU1_SB_DQ<29>")
	)
	(gr_poly
		(pts
			(xy 139.904724 -291.297868) (xy 139.804648 -291.198046) (xy 139.704572 -291.297868) (xy 139.704572 -291.34562)
			(xy 139.904724 -291.34562)
		)
		(stroke
			(width 0)
			(type solid)
		)
		(fill yes)
		(layer "In11.Cu")
		(net "M_L_CPU1_SB_DQS_DN<8>")
	)
	(gr_poly
		(pts
			(xy 139.904724 -289.67811) (xy 139.804648 -289.578034) (xy 139.704572 -289.67811) (xy 139.704572 -289.72256)
			(xy 139.904724 -289.72256)
		)
		(stroke
			(width 0)
			(type solid)
		)
		(fill yes)
		(layer "In11.Cu")
		(net "M_L_CPU1_SB_DQ<25>")
	)
	(gr_poly
		(pts
			(xy 139.904724 -288.058098) (xy 139.804648 -287.958022) (xy 139.704572 -288.058098) (xy 139.704572 -288.102548)
			(xy 139.904724 -288.102548)
		)
		(stroke
			(width 0)
			(type solid)
		)
		(fill yes)
		(layer "In11.Cu")
		(net "M_L_CPU1_SB_DQ<21>")
	)
	(gr_poly
		(pts
			(xy 139.904724 -286.438086) (xy 139.804648 -286.33801) (xy 139.704572 -286.438086) (xy 139.704572 -286.485838)
			(xy 139.904724 -286.485838)
		)
		(stroke
			(width 0)
			(type solid)
		)
		(fill yes)
		(layer "In11.Cu")
		(net "M_L_CPU1_SB_DQS_DN<7>")
	)
	(gr_poly
		(pts
			(xy 139.904724 -284.818328) (xy 139.804648 -284.718252) (xy 139.704572 -284.818328) (xy 139.704572 -284.862778)
			(xy 139.904724 -284.862778)
		)
		(stroke
			(width 0)
			(type solid)
		)
		(fill yes)
		(layer "In11.Cu")
		(net "M_L_CPU1_SB_DQ<17>")
	)
	(gr_poly
		(pts
			(xy 139.904724 -283.198316) (xy 139.804648 -283.09824) (xy 139.704572 -283.198316) (xy 139.704572 -283.242766)
			(xy 139.904724 -283.242766)
		)
		(stroke
			(width 0)
			(type solid)
		)
		(fill yes)
		(layer "In11.Cu")
		(net "M_L_CPU1_SB_DQ<13>")
	)
	(gr_poly
		(pts
			(xy 139.904724 -281.57805) (xy 139.804648 -281.478228) (xy 139.704572 -281.57805) (xy 139.704572 -281.625802)
			(xy 139.904724 -281.625802)
		)
		(stroke
			(width 0)
			(type solid)
		)
		(fill yes)
		(layer "In11.Cu")
		(net "M_L_CPU1_SB_DQS_DN<6>")
	)
	(gr_poly
		(pts
			(xy 139.904724 -279.958292) (xy 139.804648 -279.858216) (xy 139.704572 -279.958292) (xy 139.704572 -280.002742)
			(xy 139.904724 -280.002742)
		)
		(stroke
			(width 0)
			(type solid)
		)
		(fill yes)
		(layer "In11.Cu")
		(net "M_L_CPU1_SB_DQ<9>")
	)
	(gr_poly
		(pts
			(xy 139.904724 -278.33828) (xy 139.804648 -278.238204) (xy 139.704572 -278.33828) (xy 139.704572 -278.38273)
			(xy 139.904724 -278.38273)
		)
		(stroke
			(width 0)
			(type solid)
		)
		(fill yes)
		(layer "In11.Cu")
		(net "M_L_CPU1_SB_DQ<5>")
	)
	(gr_poly
		(pts
			(xy 139.904724 -276.718014) (xy 139.804648 -276.618192) (xy 139.704572 -276.718014) (xy 139.704572 -276.765766)
			(xy 139.904724 -276.765766)
		)
		(stroke
			(width 0)
			(type solid)
		)
		(fill yes)
		(layer "In11.Cu")
		(net "M_L_CPU1_SB_DQS_DN<5>")
	)
	(gr_poly
		(pts
			(xy 139.904724 -275.098256) (xy 139.804648 -274.99818) (xy 139.704572 -275.098256) (xy 139.704572 -275.142706)
			(xy 139.904724 -275.142706)
		)
		(stroke
			(width 0)
			(type solid)
		)
		(fill yes)
		(layer "In11.Cu")
		(net "M_L_CPU1_SB_DQ<1>")
	)
	(gr_poly
		(pts
			(xy 139.904724 -273.478244) (xy 139.804648 -273.378168) (xy 139.704572 -273.478244) (xy 139.704572 -273.522694)
			(xy 139.904724 -273.522694)
		)
		(stroke
			(width 0)
			(type solid)
		)
		(fill yes)
		(layer "In11.Cu")
		(net "M_L_CPU1_SB_CB<1>")
	)
	(gr_poly
		(pts
			(xy 139.904724 -271.857978) (xy 139.804648 -271.758156) (xy 139.704572 -271.857978) (xy 139.704572 -271.90573)
			(xy 139.904724 -271.90573)
		)
		(stroke
			(width 0)
			(type solid)
		)
		(fill yes)
		(layer "In11.Cu")
		(net "M_L_CPU1_SB_DQS_DN<4>")
	)
	(gr_poly
		(pts
			(xy 139.904724 -270.23822) (xy 139.804648 -270.138144) (xy 139.704572 -270.23822) (xy 139.704572 -270.28267)
			(xy 139.904724 -270.28267)
		)
		(stroke
			(width 0)
			(type solid)
		)
		(fill yes)
		(layer "In11.Cu")
		(net "M_L_CPU1_SB_CB<5>")
	)
	(gr_poly
		(pts
			(xy 139.904724 -266.998196) (xy 139.804648 -266.89812) (xy 139.704572 -266.998196) (xy 139.704572 -267.042646)
			(xy 139.904724 -267.042646)
		)
		(stroke
			(width 0)
			(type solid)
		)
		(fill yes)
		(layer "In11.Cu")
		(net "M_L_CPU1_SA_RSP<0>")
	)
	(gr_poly
		(pts
			(xy 139.904724 -265.378184) (xy 139.804648 -265.278108) (xy 139.704572 -265.378184) (xy 139.704572 -265.422634)
			(xy 139.904724 -265.422634)
		)
		(stroke
			(width 0)
			(type solid)
		)
		(fill yes)
		(layer "In11.Cu")
		(net "M_L_CPU1_SB_PAR")
	)
	(gr_poly
		(pts
			(xy 139.904724 -263.758172) (xy 139.804648 -263.658096) (xy 139.704572 -263.758172) (xy 139.704572 -263.802622)
			(xy 139.904724 -263.802622)
		)
		(stroke
			(width 0)
			(type solid)
		)
		(fill yes)
		(layer "In11.Cu")
		(net "M_L_CPU1_SB_CA<4>")
	)
	(gr_poly
		(pts
			(xy 139.904724 -262.13816) (xy 139.804648 -262.038084) (xy 139.704572 -262.13816) (xy 139.704572 -262.18261)
			(xy 139.904724 -262.18261)
		)
		(stroke
			(width 0)
			(type solid)
		)
		(fill yes)
		(layer "In11.Cu")
		(net "M_L_CPU1_SB_CA<0>")
	)
	(gr_poly
		(pts
			(xy 139.943332 -292.504368) (xy 139.939522 -292.460172) (xy 139.740386 -292.477444) (xy 139.744196 -292.521894)
			(xy 139.8524 -292.612826)
		)
		(stroke
			(width 0)
			(type solid)
		)
		(fill yes)
		(layer "In11.Cu")
		(net "M_L_CPU1_SB_DQ<30>")
	)
	(gr_poly
		(pts
			(xy 139.943332 -289.264344) (xy 139.939522 -289.220148) (xy 139.740386 -289.23742) (xy 139.744196 -289.28187)
			(xy 139.8524 -289.372802)
		)
		(stroke
			(width 0)
			(type solid)
		)
		(fill yes)
		(layer "In11.Cu")
		(net "M_L_CPU1_SB_DQ<26>")
	)
	(gr_poly
		(pts
			(xy 139.943332 -287.644586) (xy 139.939522 -287.60039) (xy 139.740386 -287.617662) (xy 139.744196 -287.662112)
			(xy 139.8524 -287.753044)
		)
		(stroke
			(width 0)
			(type solid)
		)
		(fill yes)
		(layer "In11.Cu")
		(net "M_L_CPU1_SB_DQ<22>")
	)
	(gr_poly
		(pts
			(xy 139.943332 -284.404562) (xy 139.939522 -284.360366) (xy 139.740386 -284.377638) (xy 139.744196 -284.422088)
			(xy 139.8524 -284.51302)
		)
		(stroke
			(width 0)
			(type solid)
		)
		(fill yes)
		(layer "In11.Cu")
		(net "M_L_CPU1_SB_DQ<18>")
	)
	(gr_poly
		(pts
			(xy 139.943332 -282.78455) (xy 139.939522 -282.740354) (xy 139.740386 -282.757626) (xy 139.744196 -282.802076)
			(xy 139.8524 -282.893008)
		)
		(stroke
			(width 0)
			(type solid)
		)
		(fill yes)
		(layer "In11.Cu")
		(net "M_L_CPU1_SB_DQ<14>")
	)
	(gr_poly
		(pts
			(xy 139.943332 -279.544526) (xy 139.939522 -279.50033) (xy 139.740386 -279.517602) (xy 139.744196 -279.562052)
			(xy 139.8524 -279.652984)
		)
		(stroke
			(width 0)
			(type solid)
		)
		(fill yes)
		(layer "In11.Cu")
		(net "M_L_CPU1_SB_DQ<10>")
	)
	(gr_poly
		(pts
			(xy 139.943332 -277.924514) (xy 139.939522 -277.880318) (xy 139.740386 -277.89759) (xy 139.744196 -277.94204)
			(xy 139.8524 -278.032972)
		)
		(stroke
			(width 0)
			(type solid)
		)
		(fill yes)
		(layer "In11.Cu")
		(net "M_L_CPU1_SB_DQ<6>")
	)
	(gr_poly
		(pts
			(xy 139.943332 -274.68449) (xy 139.939522 -274.640294) (xy 139.740386 -274.657566) (xy 139.744196 -274.702016)
			(xy 139.8524 -274.792948)
		)
		(stroke
			(width 0)
			(type solid)
		)
		(fill yes)
		(layer "In11.Cu")
		(net "M_L_CPU1_SB_DQ<2>")
	)
	(gr_poly
		(pts
			(xy 139.943332 -273.064478) (xy 139.939522 -273.020282) (xy 139.740386 -273.037554) (xy 139.744196 -273.082004)
			(xy 139.8524 -273.172936)
		)
		(stroke
			(width 0)
			(type solid)
		)
		(fill yes)
		(layer "In11.Cu")
		(net "M_L_CPU1_SB_CB<2>")
	)
	(gr_poly
		(pts
			(xy 139.943332 -269.824454) (xy 139.939522 -269.780258) (xy 139.740386 -269.79753) (xy 139.744196 -269.84198)
			(xy 139.8524 -269.932912)
		)
		(stroke
			(width 0)
			(type solid)
		)
		(fill yes)
		(layer "In11.Cu")
		(net "M_L_CPU1_SB_CB<6>")
	)
	(gr_poly
		(pts
			(xy 139.943332 -266.58443) (xy 139.939522 -266.540234) (xy 139.740386 -266.557506) (xy 139.744196 -266.601956)
			(xy 139.8524 -266.692888)
		)
		(stroke
			(width 0)
			(type solid)
		)
		(fill yes)
		(layer "In11.Cu")
		(net "M_L_CPU1_SB_CS_N<1>")
	)
	(gr_poly
		(pts
			(xy 139.943332 -263.344406) (xy 139.939522 -263.30021) (xy 139.740386 -263.317482) (xy 139.744196 -263.361932)
			(xy 139.8524 -263.452864)
		)
		(stroke
			(width 0)
			(type solid)
		)
		(fill yes)
		(layer "In11.Cu")
		(net "M_L_CPU1_SB_CA<3>")
	)
	(gr_poly
		(pts
			(xy 139.956286 -290.883594) (xy 139.952222 -290.836096) (xy 139.752832 -290.853622) (xy 139.75715 -290.90112)
			(xy 139.865354 -290.991798)
		)
		(stroke
			(width 0)
			(type solid)
		)
		(fill yes)
		(layer "In11.Cu")
		(net "M_L_CPU1_SB_DQS_DN<3>")
	)
	(gr_poly
		(pts
			(xy 139.956286 -286.023812) (xy 139.952222 -285.976314) (xy 139.752832 -285.99384) (xy 139.75715 -286.041084)
			(xy 139.865354 -286.132016)
		)
		(stroke
			(width 0)
			(type solid)
		)
		(fill yes)
		(layer "In11.Cu")
		(net "M_L_CPU1_SB_DQS_DN<2>")
	)
	(gr_poly
		(pts
			(xy 139.956286 -281.163776) (xy 139.952222 -281.116278) (xy 139.752832 -281.133804) (xy 139.75715 -281.181048)
			(xy 139.865354 -281.27198)
		)
		(stroke
			(width 0)
			(type solid)
		)
		(fill yes)
		(layer "In11.Cu")
		(net "M_L_CPU1_SB_DQS_DN<1>")
	)
	(gr_poly
		(pts
			(xy 139.956286 -276.30374) (xy 139.952222 -276.256242) (xy 139.752832 -276.273768) (xy 139.75715 -276.321012)
			(xy 139.865354 -276.411944)
		)
		(stroke
			(width 0)
			(type solid)
		)
		(fill yes)
		(layer "In11.Cu")
		(net "M_L_CPU1_SB_DQS_DN<0>")
	)
	(gr_poly
		(pts
			(xy 139.956286 -271.443704) (xy 139.952222 -271.396206) (xy 139.752832 -271.413732) (xy 139.75715 -271.460976)
			(xy 139.865354 -271.551908)
		)
		(stroke
			(width 0)
			(type solid)
		)
		(fill yes)
		(layer "In11.Cu")
		(net "M_L_CPU1_SB_DQS_DN<9>")
	)
	(gr_poly
		(pts
			(xy 140.068554 -251.970032) (xy 139.968478 -251.869956) (xy 139.868656 -251.970032) (xy 139.868656 -252.014482)
			(xy 140.068554 -252.014482)
		)
		(stroke
			(width 0)
			(type solid)
		)
		(fill yes)
		(layer "In11.Cu")
		(net "M_L_CPU1_SA_CS_N<1>")
	)
	(gr_poly
		(pts
			(xy 140.074904 -256.432812) (xy 140.074904 -256.38506) (xy 139.874752 -256.38506) (xy 139.874752 -256.432812)
			(xy 139.974828 -256.532634)
		)
		(stroke
			(width 0)
			(type solid)
		)
		(fill yes)
		(layer "In11.Cu")
		(net "M_L_CPU1_CLK_DN<0>")
	)
	(gr_poly
		(pts
			(xy 140.074904 -255.216406) (xy 139.974828 -255.11633) (xy 139.874752 -255.216406) (xy 139.874752 -255.260856)
			(xy 140.074904 -255.260856)
		)
		(stroke
			(width 0)
			(type solid)
		)
		(fill yes)
		(layer "In11.Cu")
		(net "M_L_CPU1_SA_CA<6>")
	)
	(gr_poly
		(pts
			(xy 140.074904 -254.812546) (xy 140.074904 -254.768096) (xy 139.874752 -254.768096) (xy 139.874752 -254.812546)
			(xy 139.974828 -254.912622)
		)
		(stroke
			(width 0)
			(type solid)
		)
		(fill yes)
		(layer "In11.Cu")
		(net "M_L_CPU1_SA_CA<5>")
	)
	(gr_poly
		(pts
			(xy 140.074904 -253.596394) (xy 139.974828 -253.496318) (xy 139.874752 -253.596394) (xy 139.874752 -253.640844)
			(xy 140.074904 -253.640844)
		)
		(stroke
			(width 0)
			(type solid)
		)
		(fill yes)
		(layer "In11.Cu")
		(net "M_L_CPU1_SA_CA<2>")
	)
	(gr_poly
		(pts
			(xy 140.074904 -253.192534) (xy 140.074904 -253.148084) (xy 139.874752 -253.148084) (xy 139.874752 -253.192534)
			(xy 139.974828 -253.29261)
		)
		(stroke
			(width 0)
			(type solid)
		)
		(fill yes)
		(layer "In11.Cu")
		(net "M_L_CPU1_SA_CA<1>")
	)
	(gr_poly
		(pts
			(xy 140.074904 -250.35637) (xy 139.974828 -250.256294) (xy 139.874752 -250.35637) (xy 139.874752 -250.40082)
			(xy 140.074904 -250.40082)
		)
		(stroke
			(width 0)
			(type solid)
		)
		(fill yes)
		(layer "In11.Cu")
		(net "M_L_CPU1_ALERT_R_N")
	)
	(gr_poly
		(pts
			(xy 140.074904 -248.736358) (xy 139.974828 -248.636282) (xy 139.874752 -248.736358) (xy 139.874752 -248.780808)
			(xy 140.074904 -248.780808)
		)
		(stroke
			(width 0)
			(type solid)
		)
		(fill yes)
		(layer "In11.Cu")
		(net "M_L_CPU1_SA_CB<5>")
	)
	(gr_poly
		(pts
			(xy 140.074904 -248.332498) (xy 140.074904 -248.288048) (xy 139.874752 -248.288048) (xy 139.874752 -248.332498)
			(xy 139.974828 -248.432574)
		)
		(stroke
			(width 0)
			(type solid)
		)
		(fill yes)
		(layer "In11.Cu")
		(net "M_L_CPU1_SA_CB<6>")
	)
	(gr_poly
		(pts
			(xy 140.074904 -247.116092) (xy 139.974828 -247.01627) (xy 139.874752 -247.116092) (xy 139.874752 -247.163844)
			(xy 140.074904 -247.163844)
		)
		(stroke
			(width 0)
			(type solid)
		)
		(fill yes)
		(layer "In11.Cu")
		(net "M_L_CPU1_SA_DQS_DN<9>")
	)
	(gr_poly
		(pts
			(xy 140.074904 -246.71274) (xy 140.074904 -246.664988) (xy 139.874752 -246.664988) (xy 139.874752 -246.71274)
			(xy 139.974828 -246.812562)
		)
		(stroke
			(width 0)
			(type solid)
		)
		(fill yes)
		(layer "In11.Cu")
		(net "M_L_CPU1_SA_DQS_DN<4>")
	)
	(gr_poly
		(pts
			(xy 140.074904 -245.496334) (xy 139.974828 -245.396258) (xy 139.874752 -245.496334) (xy 139.874752 -245.540784)
			(xy 140.074904 -245.540784)
		)
		(stroke
			(width 0)
			(type solid)
		)
		(fill yes)
		(layer "In11.Cu")
		(net "M_L_CPU1_SA_CB<1>")
	)
	(gr_poly
		(pts
			(xy 140.074904 -245.092474) (xy 140.074904 -245.048024) (xy 139.874752 -245.048024) (xy 139.874752 -245.092474)
			(xy 139.974828 -245.19255)
		)
		(stroke
			(width 0)
			(type solid)
		)
		(fill yes)
		(layer "In11.Cu")
		(net "M_L_CPU1_SA_CB<2>")
	)
	(gr_poly
		(pts
			(xy 140.074904 -243.876322) (xy 139.974828 -243.776246) (xy 139.874752 -243.876322) (xy 139.874752 -243.920772)
			(xy 140.074904 -243.920772)
		)
		(stroke
			(width 0)
			(type solid)
		)
		(fill yes)
		(layer "In11.Cu")
		(net "M_L_CPU1_SA_DQ<29>")
	)
	(gr_poly
		(pts
			(xy 140.074904 -243.472462) (xy 140.074904 -243.428012) (xy 139.874752 -243.428012) (xy 139.874752 -243.472462)
			(xy 139.974828 -243.572538)
		)
		(stroke
			(width 0)
			(type solid)
		)
		(fill yes)
		(layer "In11.Cu")
		(net "M_L_CPU1_SA_DQ<30>")
	)
	(gr_poly
		(pts
			(xy 140.074904 -242.256056) (xy 139.974828 -242.156234) (xy 139.874752 -242.256056) (xy 139.874752 -242.303808)
			(xy 140.074904 -242.303808)
		)
		(stroke
			(width 0)
			(type solid)
		)
		(fill yes)
		(layer "In11.Cu")
		(net "M_L_CPU1_SA_DQS_DN<8>")
	)
	(gr_poly
		(pts
			(xy 140.074904 -241.852704) (xy 140.074904 -241.804952) (xy 139.874752 -241.804952) (xy 139.874752 -241.852704)
			(xy 139.974828 -241.952526)
		)
		(stroke
			(width 0)
			(type solid)
		)
		(fill yes)
		(layer "In11.Cu")
		(net "M_L_CPU1_SA_DQS_DN<3>")
	)
	(gr_poly
		(pts
			(xy 140.074904 -240.636298) (xy 139.974828 -240.536222) (xy 139.874752 -240.636298) (xy 139.874752 -240.680748)
			(xy 140.074904 -240.680748)
		)
		(stroke
			(width 0)
			(type solid)
		)
		(fill yes)
		(layer "In11.Cu")
		(net "M_L_CPU1_SA_DQ<25>")
	)
	(gr_poly
		(pts
			(xy 140.074904 -240.232438) (xy 140.074904 -240.187988) (xy 139.874752 -240.187988) (xy 139.874752 -240.232438)
			(xy 139.974828 -240.332514)
		)
		(stroke
			(width 0)
			(type solid)
		)
		(fill yes)
		(layer "In11.Cu")
		(net "M_L_CPU1_SA_DQ<26>")
	)
	(gr_poly
		(pts
			(xy 140.074904 -239.016286) (xy 139.974828 -238.91621) (xy 139.874752 -239.016286) (xy 139.874752 -239.060736)
			(xy 140.074904 -239.060736)
		)
		(stroke
			(width 0)
			(type solid)
		)
		(fill yes)
		(layer "In11.Cu")
		(net "M_L_CPU1_SA_DQ<21>")
	)
	(gr_poly
		(pts
			(xy 140.074904 -238.612426) (xy 140.074904 -238.567976) (xy 139.874752 -238.567976) (xy 139.874752 -238.612426)
			(xy 139.974828 -238.712502)
		)
		(stroke
			(width 0)
			(type solid)
		)
		(fill yes)
		(layer "In11.Cu")
		(net "M_L_CPU1_SA_DQ<22>")
	)
	(gr_poly
		(pts
			(xy 140.074904 -237.39602) (xy 139.974828 -237.296198) (xy 139.874752 -237.39602) (xy 139.874752 -237.443772)
			(xy 140.074904 -237.443772)
		)
		(stroke
			(width 0)
			(type solid)
		)
		(fill yes)
		(layer "In11.Cu")
		(net "M_L_CPU1_SA_DQS_DN<7>")
	)
	(gr_poly
		(pts
			(xy 140.074904 -236.992668) (xy 140.074904 -236.944916) (xy 139.874752 -236.944916) (xy 139.874752 -236.992668)
			(xy 139.974828 -237.09249)
		)
		(stroke
			(width 0)
			(type solid)
		)
		(fill yes)
		(layer "In11.Cu")
		(net "M_L_CPU1_SA_DQS_DN<2>")
	)
	(gr_poly
		(pts
			(xy 140.074904 -235.776262) (xy 139.974828 -235.676186) (xy 139.874752 -235.776262) (xy 139.874752 -235.820712)
			(xy 140.074904 -235.820712)
		)
		(stroke
			(width 0)
			(type solid)
		)
		(fill yes)
		(layer "In11.Cu")
		(net "M_L_CPU1_SA_DQ<17>")
	)
	(gr_poly
		(pts
			(xy 140.074904 -235.372402) (xy 140.074904 -235.327952) (xy 139.874752 -235.327952) (xy 139.874752 -235.372402)
			(xy 139.974828 -235.472478)
		)
		(stroke
			(width 0)
			(type solid)
		)
		(fill yes)
		(layer "In11.Cu")
		(net "M_L_CPU1_SA_DQ<18>")
	)
	(gr_poly
		(pts
			(xy 140.074904 -234.15625) (xy 139.974828 -234.056174) (xy 139.874752 -234.15625) (xy 139.874752 -234.2007)
			(xy 140.074904 -234.2007)
		)
		(stroke
			(width 0)
			(type solid)
		)
		(fill yes)
		(layer "In11.Cu")
		(net "M_L_CPU1_SA_DQ<13>")
	)
	(gr_poly
		(pts
			(xy 140.074904 -233.75239) (xy 140.074904 -233.70794) (xy 139.874752 -233.70794) (xy 139.874752 -233.75239)
			(xy 139.974828 -233.852466)
		)
		(stroke
			(width 0)
			(type solid)
		)
		(fill yes)
		(layer "In11.Cu")
		(net "M_L_CPU1_SA_DQ<14>")
	)
	(gr_poly
		(pts
			(xy 140.074904 -232.535984) (xy 139.974828 -232.436162) (xy 139.874752 -232.535984) (xy 139.874752 -232.583736)
			(xy 140.074904 -232.583736)
		)
		(stroke
			(width 0)
			(type solid)
		)
		(fill yes)
		(layer "In11.Cu")
		(net "M_L_CPU1_SA_DQS_DN<6>")
	)
	(gr_poly
		(pts
			(xy 140.074904 -232.132632) (xy 140.074904 -232.08488) (xy 139.874752 -232.08488) (xy 139.874752 -232.132632)
			(xy 139.974828 -232.232454)
		)
		(stroke
			(width 0)
			(type solid)
		)
		(fill yes)
		(layer "In11.Cu")
		(net "M_L_CPU1_SA_DQS_DN<1>")
	)
	(gr_poly
		(pts
			(xy 140.074904 -230.916226) (xy 139.974828 -230.81615) (xy 139.874752 -230.916226) (xy 139.874752 -230.960676)
			(xy 140.074904 -230.960676)
		)
		(stroke
			(width 0)
			(type solid)
		)
		(fill yes)
		(layer "In11.Cu")
		(net "M_L_CPU1_SA_DQ<9>")
	)
	(gr_poly
		(pts
			(xy 140.074904 -230.51262) (xy 140.074904 -230.46817) (xy 139.874752 -230.46817) (xy 139.874752 -230.51262)
			(xy 139.974828 -230.612696)
		)
		(stroke
			(width 0)
			(type solid)
		)
		(fill yes)
		(layer "In11.Cu")
		(net "M_L_CPU1_SA_DQ<10>")
	)
	(gr_poly
		(pts
			(xy 140.074904 -229.296214) (xy 139.974828 -229.196138) (xy 139.874752 -229.296214) (xy 139.874752 -229.340664)
			(xy 140.074904 -229.340664)
		)
		(stroke
			(width 0)
			(type solid)
		)
		(fill yes)
		(layer "In11.Cu")
		(net "M_L_CPU1_SA_DQ<5>")
	)
	(gr_poly
		(pts
			(xy 140.074904 -228.892608) (xy 140.074904 -228.848158) (xy 139.874752 -228.848158) (xy 139.874752 -228.892608)
			(xy 139.974828 -228.992684)
		)
		(stroke
			(width 0)
			(type solid)
		)
		(fill yes)
		(layer "In11.Cu")
		(net "M_L_CPU1_SA_DQ<6>")
	)
	(gr_poly
		(pts
			(xy 140.074904 -227.676202) (xy 139.974828 -227.57638) (xy 139.874752 -227.676202) (xy 139.874752 -227.723954)
			(xy 140.074904 -227.723954)
		)
		(stroke
			(width 0)
			(type solid)
		)
		(fill yes)
		(layer "In11.Cu")
		(net "M_L_CPU1_SA_DQS_DN<5>")
	)
	(gr_poly
		(pts
			(xy 140.074904 -227.27285) (xy 140.074904 -227.225098) (xy 139.874752 -227.225098) (xy 139.874752 -227.27285)
			(xy 139.974828 -227.372672)
		)
		(stroke
			(width 0)
			(type solid)
		)
		(fill yes)
		(layer "In11.Cu")
		(net "M_L_CPU1_SA_DQS_DN<0>")
	)
	(gr_poly
		(pts
			(xy 140.074904 -226.056444) (xy 139.974828 -225.956368) (xy 139.874752 -226.056444) (xy 139.874752 -226.100894)
			(xy 140.074904 -226.100894)
		)
		(stroke
			(width 0)
			(type solid)
		)
		(fill yes)
		(layer "In11.Cu")
		(net "M_L_CPU1_SA_DQ<1>")
	)
	(gr_poly
		(pts
			(xy 140.074904 -225.652584) (xy 140.074904 -225.608134) (xy 139.874752 -225.608134) (xy 139.874752 -225.652584)
			(xy 139.974828 -225.75266)
		)
		(stroke
			(width 0)
			(type solid)
		)
		(fill yes)
		(layer "In11.Cu")
		(net "M_L_CPU1_SA_DQ<2>")
	)
	(gr_poly
		(pts
			(xy 140.368528 -264.561828) (xy 140.268452 -264.461752) (xy 140.16863 -264.561828) (xy 140.16863 -264.606278)
			(xy 140.368528 -264.606278)
		)
		(stroke
			(width 0)
			(type solid)
		)
		(fill yes)
		(layer "In11.Cu")
		(net "M_L_CPU1_SB_CA<6>")
	)
	(gr_poly
		(pts
			(xy 140.374878 -292.108128) (xy 140.274802 -292.008052) (xy 140.174726 -292.108128) (xy 140.174726 -292.152578)
			(xy 140.374878 -292.152578)
		)
		(stroke
			(width 0)
			(type solid)
		)
		(fill yes)
		(layer "In11.Cu")
		(net "M_L_CPU1_SB_DQ<28>")
	)
	(gr_poly
		(pts
			(xy 140.374878 -291.704522) (xy 140.374878 -291.65677) (xy 140.174726 -291.65677) (xy 140.174726 -291.704522)
			(xy 140.274802 -291.804344)
		)
		(stroke
			(width 0)
			(type solid)
		)
		(fill yes)
		(layer "In11.Cu")
		(net "M_L_CPU1_SB_DQS_DP<8>")
	)
	(gr_poly
		(pts
			(xy 140.374878 -290.487862) (xy 140.274802 -290.38804) (xy 140.174726 -290.487862) (xy 140.174726 -290.535614)
			(xy 140.374878 -290.535614)
		)
		(stroke
			(width 0)
			(type solid)
		)
		(fill yes)
		(layer "In11.Cu")
		(net "M_L_CPU1_SB_DQS_DP<3>")
	)
	(gr_poly
		(pts
			(xy 140.374878 -290.084256) (xy 140.374878 -290.039806) (xy 140.174726 -290.039806) (xy 140.174726 -290.084256)
			(xy 140.274802 -290.184332)
		)
		(stroke
			(width 0)
			(type solid)
		)
		(fill yes)
		(layer "In11.Cu")
		(net "M_L_CPU1_SB_DQ<27>")
	)
	(gr_poly
		(pts
			(xy 140.374878 -288.868104) (xy 140.274802 -288.768028) (xy 140.174726 -288.868104) (xy 140.174726 -288.912554)
			(xy 140.374878 -288.912554)
		)
		(stroke
			(width 0)
			(type solid)
		)
		(fill yes)
		(layer "In11.Cu")
		(net "M_L_CPU1_SB_DQ<24>")
	)
	(gr_poly
		(pts
			(xy 140.374878 -288.464498) (xy 140.374878 -288.420048) (xy 140.174726 -288.420048) (xy 140.174726 -288.464498)
			(xy 140.274802 -288.564574)
		)
		(stroke
			(width 0)
			(type solid)
		)
		(fill yes)
		(layer "In11.Cu")
		(net "M_L_CPU1_SB_DQ<23>")
	)
	(gr_poly
		(pts
			(xy 140.374878 -287.248092) (xy 140.274802 -287.148016) (xy 140.174726 -287.248092) (xy 140.174726 -287.292542)
			(xy 140.374878 -287.292542)
		)
		(stroke
			(width 0)
			(type solid)
		)
		(fill yes)
		(layer "In11.Cu")
		(net "M_L_CPU1_SB_DQ<20>")
	)
	(gr_poly
		(pts
			(xy 140.374878 -286.844486) (xy 140.374878 -286.796734) (xy 140.174726 -286.796734) (xy 140.174726 -286.844486)
			(xy 140.274802 -286.944562)
		)
		(stroke
			(width 0)
			(type solid)
		)
		(fill yes)
		(layer "In11.Cu")
		(net "M_L_CPU1_SB_DQS_DP<7>")
	)
	(gr_poly
		(pts
			(xy 140.374878 -285.62808) (xy 140.274802 -285.528258) (xy 140.174726 -285.62808) (xy 140.174726 -285.675832)
			(xy 140.374878 -285.675832)
		)
		(stroke
			(width 0)
			(type solid)
		)
		(fill yes)
		(layer "In11.Cu")
		(net "M_L_CPU1_SB_DQS_DP<2>")
	)
	(gr_poly
		(pts
			(xy 140.374878 -285.224474) (xy 140.374878 -285.180024) (xy 140.174726 -285.180024) (xy 140.174726 -285.224474)
			(xy 140.274802 -285.32455)
		)
		(stroke
			(width 0)
			(type solid)
		)
		(fill yes)
		(layer "In11.Cu")
		(net "M_L_CPU1_SB_DQ<19>")
	)
	(gr_poly
		(pts
			(xy 140.374878 -284.008322) (xy 140.274802 -283.908246) (xy 140.174726 -284.008322) (xy 140.174726 -284.052772)
			(xy 140.374878 -284.052772)
		)
		(stroke
			(width 0)
			(type solid)
		)
		(fill yes)
		(layer "In11.Cu")
		(net "M_L_CPU1_SB_DQ<16>")
	)
	(gr_poly
		(pts
			(xy 140.374878 -283.604462) (xy 140.374878 -283.560012) (xy 140.174726 -283.560012) (xy 140.174726 -283.604462)
			(xy 140.274802 -283.704538)
		)
		(stroke
			(width 0)
			(type solid)
		)
		(fill yes)
		(layer "In11.Cu")
		(net "M_L_CPU1_SB_DQ<15>")
	)
	(gr_poly
		(pts
			(xy 140.374878 -282.38831) (xy 140.274802 -282.288234) (xy 140.174726 -282.38831) (xy 140.174726 -282.43276)
			(xy 140.374878 -282.43276)
		)
		(stroke
			(width 0)
			(type solid)
		)
		(fill yes)
		(layer "In11.Cu")
		(net "M_L_CPU1_SB_DQ<12>")
	)
	(gr_poly
		(pts
			(xy 140.374878 -281.984704) (xy 140.374878 -281.936952) (xy 140.174726 -281.936952) (xy 140.174726 -281.984704)
			(xy 140.274802 -282.084526)
		)
		(stroke
			(width 0)
			(type solid)
		)
		(fill yes)
		(layer "In11.Cu")
		(net "M_L_CPU1_SB_DQS_DP<6>")
	)
	(gr_poly
		(pts
			(xy 140.374878 -280.768044) (xy 140.274802 -280.668222) (xy 140.174726 -280.768044) (xy 140.174726 -280.815796)
			(xy 140.374878 -280.815796)
		)
		(stroke
			(width 0)
			(type solid)
		)
		(fill yes)
		(layer "In11.Cu")
		(net "M_L_CPU1_SB_DQS_DP<1>")
	)
	(gr_poly
		(pts
			(xy 140.374878 -280.364438) (xy 140.374878 -280.319988) (xy 140.174726 -280.319988) (xy 140.174726 -280.364438)
			(xy 140.274802 -280.464514)
		)
		(stroke
			(width 0)
			(type solid)
		)
		(fill yes)
		(layer "In11.Cu")
		(net "M_L_CPU1_SB_DQ<11>")
	)
	(gr_poly
		(pts
			(xy 140.374878 -279.148286) (xy 140.274802 -279.04821) (xy 140.174726 -279.148286) (xy 140.174726 -279.192736)
			(xy 140.374878 -279.192736)
		)
		(stroke
			(width 0)
			(type solid)
		)
		(fill yes)
		(layer "In11.Cu")
		(net "M_L_CPU1_SB_DQ<8>")
	)
	(gr_poly
		(pts
			(xy 140.374878 -278.744426) (xy 140.374878 -278.699976) (xy 140.174726 -278.699976) (xy 140.174726 -278.744426)
			(xy 140.274802 -278.844502)
		)
		(stroke
			(width 0)
			(type solid)
		)
		(fill yes)
		(layer "In11.Cu")
		(net "M_L_CPU1_SB_DQ<7>")
	)
	(gr_poly
		(pts
			(xy 140.374878 -277.528274) (xy 140.274802 -277.428198) (xy 140.174726 -277.528274) (xy 140.174726 -277.572724)
			(xy 140.374878 -277.572724)
		)
		(stroke
			(width 0)
			(type solid)
		)
		(fill yes)
		(layer "In11.Cu")
		(net "M_L_CPU1_SB_DQ<4>")
	)
	(gr_poly
		(pts
			(xy 140.374878 -277.124668) (xy 140.374878 -277.076916) (xy 140.174726 -277.076916) (xy 140.174726 -277.124668)
			(xy 140.274802 -277.22449)
		)
		(stroke
			(width 0)
			(type solid)
		)
		(fill yes)
		(layer "In11.Cu")
		(net "M_L_CPU1_SB_DQS_DP<5>")
	)
	(gr_poly
		(pts
			(xy 140.374878 -275.908008) (xy 140.274802 -275.808186) (xy 140.174726 -275.908008) (xy 140.174726 -275.95576)
			(xy 140.374878 -275.95576)
		)
		(stroke
			(width 0)
			(type solid)
		)
		(fill yes)
		(layer "In11.Cu")
		(net "M_L_CPU1_SB_DQS_DP<0>")
	)
	(gr_poly
		(pts
			(xy 140.374878 -275.504402) (xy 140.374878 -275.459952) (xy 140.174726 -275.459952) (xy 140.174726 -275.504402)
			(xy 140.274802 -275.604478)
		)
		(stroke
			(width 0)
			(type solid)
		)
		(fill yes)
		(layer "In11.Cu")
		(net "M_L_CPU1_SB_DQ<3>")
	)
	(gr_poly
		(pts
			(xy 140.374878 -274.28825) (xy 140.274802 -274.188174) (xy 140.174726 -274.28825) (xy 140.174726 -274.3327)
			(xy 140.374878 -274.3327)
		)
		(stroke
			(width 0)
			(type solid)
		)
		(fill yes)
		(layer "In11.Cu")
		(net "M_L_CPU1_SB_DQ<0>")
	)
	(gr_poly
		(pts
			(xy 140.374878 -273.88439) (xy 140.374878 -273.83994) (xy 140.174726 -273.83994) (xy 140.174726 -273.88439)
			(xy 140.274802 -273.984466)
		)
		(stroke
			(width 0)
			(type solid)
		)
		(fill yes)
		(layer "In11.Cu")
		(net "M_L_CPU1_SB_CB<3>")
	)
	(gr_poly
		(pts
			(xy 140.374878 -272.668238) (xy 140.274802 -272.568162) (xy 140.174726 -272.668238) (xy 140.174726 -272.712688)
			(xy 140.374878 -272.712688)
		)
		(stroke
			(width 0)
			(type solid)
		)
		(fill yes)
		(layer "In11.Cu")
		(net "M_L_CPU1_SB_CB<0>")
	)
	(gr_poly
		(pts
			(xy 140.374878 -272.264632) (xy 140.374878 -272.21688) (xy 140.174726 -272.21688) (xy 140.174726 -272.264632)
			(xy 140.274802 -272.364454)
		)
		(stroke
			(width 0)
			(type solid)
		)
		(fill yes)
		(layer "In11.Cu")
		(net "M_L_CPU1_SB_DQS_DP<4>")
	)
	(gr_poly
		(pts
			(xy 140.374878 -271.047972) (xy 140.274802 -270.94815) (xy 140.174726 -271.047972) (xy 140.174726 -271.095724)
			(xy 140.374878 -271.095724)
		)
		(stroke
			(width 0)
			(type solid)
		)
		(fill yes)
		(layer "In11.Cu")
		(net "M_L_CPU1_SB_DQS_DP<9>")
	)
	(gr_poly
		(pts
			(xy 140.374878 -270.644366) (xy 140.374878 -270.599916) (xy 140.174726 -270.599916) (xy 140.174726 -270.644366)
			(xy 140.274802 -270.744442)
		)
		(stroke
			(width 0)
			(type solid)
		)
		(fill yes)
		(layer "In11.Cu")
		(net "M_L_CPU1_SB_CB<7>")
	)
	(gr_poly
		(pts
			(xy 140.374878 -269.428214) (xy 140.274802 -269.328138) (xy 140.174726 -269.428214) (xy 140.174726 -269.472664)
			(xy 140.374878 -269.472664)
		)
		(stroke
			(width 0)
			(type solid)
		)
		(fill yes)
		(layer "In11.Cu")
		(net "M_L_CPU1_SB_CB<4>")
	)
	(gr_poly
		(pts
			(xy 140.374878 -267.808202) (xy 140.274802 -267.708126) (xy 140.174726 -267.808202) (xy 140.174726 -267.852652)
			(xy 140.374878 -267.852652)
		)
		(stroke
			(width 0)
			(type solid)
		)
		(fill yes)
		(layer "In11.Cu")
		(net "M_L_CPU1_SB_RSP<0>")
	)
	(gr_poly
		(pts
			(xy 140.374878 -265.78433) (xy 140.374878 -265.73988) (xy 140.174726 -265.73988) (xy 140.174726 -265.78433)
			(xy 140.274802 -265.884406)
		)
		(stroke
			(width 0)
			(type solid)
		)
		(fill yes)
		(layer "In11.Cu")
		(net "M_L_CPU1_SB_CS_N<0>")
	)
	(gr_poly
		(pts
			(xy 140.374878 -264.164318) (xy 140.374878 -264.119868) (xy 140.174726 -264.119868) (xy 140.174726 -264.164318)
			(xy 140.274802 -264.264394)
		)
		(stroke
			(width 0)
			(type solid)
		)
		(fill yes)
		(layer "In11.Cu")
		(net "M_L_CPU1_SB_CA<5>")
	)
	(gr_poly
		(pts
			(xy 140.374878 -262.948166) (xy 140.274802 -262.84809) (xy 140.174726 -262.948166) (xy 140.174726 -262.992616)
			(xy 140.374878 -262.992616)
		)
		(stroke
			(width 0)
			(type solid)
		)
		(fill yes)
		(layer "In11.Cu")
		(net "M_L_CPU1_SB_CA<2>")
	)
	(gr_poly
		(pts
			(xy 140.374878 -262.544306) (xy 140.374878 -262.499856) (xy 140.174726 -262.499856) (xy 140.174726 -262.544306)
			(xy 140.274802 -262.644382)
		)
		(stroke
			(width 0)
			(type solid)
		)
		(fill yes)
		(layer "In11.Cu")
		(net "M_L_CPU1_SB_CA<1>")
	)
	(gr_poly
		(pts
			(xy 140.544804 -256.026158) (xy 140.444728 -255.926336) (xy 140.344652 -256.026158) (xy 140.344652 -256.07391)
			(xy 140.544804 -256.07391)
		)
		(stroke
			(width 0)
			(type solid)
		)
		(fill yes)
		(layer "In11.Cu")
		(net "M_L_CPU1_CLK_DP<0>")
	)
	(gr_poly
		(pts
			(xy 140.544804 -255.622552) (xy 140.544804 -255.578102) (xy 140.344652 -255.578102) (xy 140.344652 -255.622552)
			(xy 140.444728 -255.722628)
		)
		(stroke
			(width 0)
			(type solid)
		)
		(fill yes)
		(layer "In11.Cu")
		(net "M_L_CPU1_SA_PAR")
	)
	(gr_poly
		(pts
			(xy 140.544804 -254.4064) (xy 140.444728 -254.306324) (xy 140.344652 -254.4064) (xy 140.344652 -254.45085)
			(xy 140.544804 -254.45085)
		)
		(stroke
			(width 0)
			(type solid)
		)
		(fill yes)
		(layer "In11.Cu")
		(net "M_L_CPU1_SA_CA<4>")
	)
	(gr_poly
		(pts
			(xy 140.544804 -254.00254) (xy 140.544804 -253.95809) (xy 140.344652 -253.95809) (xy 140.344652 -254.00254)
			(xy 140.444728 -254.102616)
		)
		(stroke
			(width 0)
			(type solid)
		)
		(fill yes)
		(layer "In11.Cu")
		(net "M_L_CPU1_SA_CA<3>")
	)
	(gr_poly
		(pts
			(xy 140.544804 -252.786388) (xy 140.444728 -252.686312) (xy 140.344652 -252.786388) (xy 140.344652 -252.830838)
			(xy 140.544804 -252.830838)
		)
		(stroke
			(width 0)
			(type solid)
		)
		(fill yes)
		(layer "In11.Cu")
		(net "M_L_CPU1_SA_CA<0>")
	)
	(gr_poly
		(pts
			(xy 140.544804 -250.762516) (xy 140.544804 -250.718066) (xy 140.344652 -250.718066) (xy 140.344652 -250.762516)
			(xy 140.444728 -250.862592)
		)
		(stroke
			(width 0)
			(type solid)
		)
		(fill yes)
		(layer "In11.Cu")
		(net "M_L_CPU1_RESET_N")
	)
	(gr_poly
		(pts
			(xy 140.544804 -249.142504) (xy 140.544804 -249.098054) (xy 140.344652 -249.098054) (xy 140.344652 -249.142504)
			(xy 140.444728 -249.24258)
		)
		(stroke
			(width 0)
			(type solid)
		)
		(fill yes)
		(layer "In11.Cu")
		(net "M_L_CPU1_SA_CB<7>")
	)
	(gr_poly
		(pts
			(xy 140.544804 -247.926352) (xy 140.444728 -247.826276) (xy 140.344652 -247.926352) (xy 140.344652 -247.970802)
			(xy 140.544804 -247.970802)
		)
		(stroke
			(width 0)
			(type solid)
		)
		(fill yes)
		(layer "In11.Cu")
		(net "M_L_CPU1_SA_CB<4>")
	)
	(gr_poly
		(pts
			(xy 140.544804 -247.522746) (xy 140.544804 -247.474994) (xy 140.344652 -247.474994) (xy 140.344652 -247.522746)
			(xy 140.444728 -247.622568)
		)
		(stroke
			(width 0)
			(type solid)
		)
		(fill yes)
		(layer "In11.Cu")
		(net "M_L_CPU1_SA_DQS_DP<9>")
	)
	(gr_poly
		(pts
			(xy 140.544804 -246.306086) (xy 140.444728 -246.206264) (xy 140.344652 -246.306086) (xy 140.344652 -246.353838)
			(xy 140.544804 -246.353838)
		)
		(stroke
			(width 0)
			(type solid)
		)
		(fill yes)
		(layer "In11.Cu")
		(net "M_L_CPU1_SA_DQS_DP<4>")
	)
	(gr_poly
		(pts
			(xy 140.544804 -245.90248) (xy 140.544804 -245.85803) (xy 140.344652 -245.85803) (xy 140.344652 -245.90248)
			(xy 140.444728 -246.002556)
		)
		(stroke
			(width 0)
			(type solid)
		)
		(fill yes)
		(layer "In11.Cu")
		(net "M_L_CPU1_SA_CB<3>")
	)
	(gr_poly
		(pts
			(xy 140.544804 -244.686328) (xy 140.444728 -244.586252) (xy 140.344652 -244.686328) (xy 140.344652 -244.730778)
			(xy 140.544804 -244.730778)
		)
		(stroke
			(width 0)
			(type solid)
		)
		(fill yes)
		(layer "In11.Cu")
		(net "M_L_CPU1_SA_CB<0>")
	)
	(gr_poly
		(pts
			(xy 140.544804 -244.282468) (xy 140.544804 -244.238018) (xy 140.344652 -244.238018) (xy 140.344652 -244.282468)
			(xy 140.444728 -244.382544)
		)
		(stroke
			(width 0)
			(type solid)
		)
		(fill yes)
		(layer "In11.Cu")
		(net "M_L_CPU1_SA_DQ<31>")
	)
	(gr_poly
		(pts
			(xy 140.544804 -243.066316) (xy 140.444728 -242.96624) (xy 140.344652 -243.066316) (xy 140.344652 -243.110766)
			(xy 140.544804 -243.110766)
		)
		(stroke
			(width 0)
			(type solid)
		)
		(fill yes)
		(layer "In11.Cu")
		(net "M_L_CPU1_SA_DQ<28>")
	)
	(gr_poly
		(pts
			(xy 140.544804 -242.66271) (xy 140.544804 -242.614958) (xy 140.344652 -242.614958) (xy 140.344652 -242.66271)
			(xy 140.444728 -242.762532)
		)
		(stroke
			(width 0)
			(type solid)
		)
		(fill yes)
		(layer "In11.Cu")
		(net "M_L_CPU1_SA_DQS_DP<8>")
	)
	(gr_poly
		(pts
			(xy 140.544804 -241.44605) (xy 140.444728 -241.346228) (xy 140.344652 -241.44605) (xy 140.344652 -241.493802)
			(xy 140.544804 -241.493802)
		)
		(stroke
			(width 0)
			(type solid)
		)
		(fill yes)
		(layer "In11.Cu")
		(net "M_L_CPU1_SA_DQS_DP<3>")
	)
	(gr_poly
		(pts
			(xy 140.544804 -241.042444) (xy 140.544804 -240.997994) (xy 140.344652 -240.997994) (xy 140.344652 -241.042444)
			(xy 140.444728 -241.14252)
		)
		(stroke
			(width 0)
			(type solid)
		)
		(fill yes)
		(layer "In11.Cu")
		(net "M_L_CPU1_SA_DQ<27>")
	)
	(gr_poly
		(pts
			(xy 140.544804 -239.826292) (xy 140.444728 -239.726216) (xy 140.344652 -239.826292) (xy 140.344652 -239.870742)
			(xy 140.544804 -239.870742)
		)
		(stroke
			(width 0)
			(type solid)
		)
		(fill yes)
		(layer "In11.Cu")
		(net "M_L_CPU1_SA_DQ<24>")
	)
	(gr_poly
		(pts
			(xy 140.544804 -239.422432) (xy 140.544804 -239.377982) (xy 140.344652 -239.377982) (xy 140.344652 -239.422432)
			(xy 140.444728 -239.522508)
		)
		(stroke
			(width 0)
			(type solid)
		)
		(fill yes)
		(layer "In11.Cu")
		(net "M_L_CPU1_SA_DQ<23>")
	)
	(gr_poly
		(pts
			(xy 140.544804 -238.20628) (xy 140.444728 -238.106204) (xy 140.344652 -238.20628) (xy 140.344652 -238.25073)
			(xy 140.544804 -238.25073)
		)
		(stroke
			(width 0)
			(type solid)
		)
		(fill yes)
		(layer "In11.Cu")
		(net "M_L_CPU1_SA_DQ<20>")
	)
	(gr_poly
		(pts
			(xy 140.544804 -237.802674) (xy 140.544804 -237.754922) (xy 140.344652 -237.754922) (xy 140.344652 -237.802674)
			(xy 140.444728 -237.902496)
		)
		(stroke
			(width 0)
			(type solid)
		)
		(fill yes)
		(layer "In11.Cu")
		(net "M_L_CPU1_SA_DQS_DP<7>")
	)
	(gr_poly
		(pts
			(xy 140.544804 -236.586014) (xy 140.444728 -236.486192) (xy 140.344652 -236.586014) (xy 140.344652 -236.633766)
			(xy 140.544804 -236.633766)
		)
		(stroke
			(width 0)
			(type solid)
		)
		(fill yes)
		(layer "In11.Cu")
		(net "M_L_CPU1_SA_DQS_DP<2>")
	)
	(gr_poly
		(pts
			(xy 140.544804 -236.182408) (xy 140.544804 -236.137958) (xy 140.344652 -236.137958) (xy 140.344652 -236.182408)
			(xy 140.444728 -236.282484)
		)
		(stroke
			(width 0)
			(type solid)
		)
		(fill yes)
		(layer "In11.Cu")
		(net "M_L_CPU1_SA_DQ<19>")
	)
	(gr_poly
		(pts
			(xy 140.544804 -234.966256) (xy 140.444728 -234.86618) (xy 140.344652 -234.966256) (xy 140.344652 -235.010706)
			(xy 140.544804 -235.010706)
		)
		(stroke
			(width 0)
			(type solid)
		)
		(fill yes)
		(layer "In11.Cu")
		(net "M_L_CPU1_SA_DQ<16>")
	)
	(gr_poly
		(pts
			(xy 140.544804 -234.562396) (xy 140.544804 -234.517946) (xy 140.344652 -234.517946) (xy 140.344652 -234.562396)
			(xy 140.444728 -234.662472)
		)
		(stroke
			(width 0)
			(type solid)
		)
		(fill yes)
		(layer "In11.Cu")
		(net "M_L_CPU1_SA_DQ<15>")
	)
	(gr_poly
		(pts
			(xy 140.544804 -233.346244) (xy 140.444728 -233.246168) (xy 140.344652 -233.346244) (xy 140.344652 -233.390694)
			(xy 140.544804 -233.390694)
		)
		(stroke
			(width 0)
			(type solid)
		)
		(fill yes)
		(layer "In11.Cu")
		(net "M_L_CPU1_SA_DQ<12>")
	)
	(gr_poly
		(pts
			(xy 140.544804 -232.942638) (xy 140.544804 -232.894886) (xy 140.344652 -232.894886) (xy 140.344652 -232.942638)
			(xy 140.444728 -233.04246)
		)
		(stroke
			(width 0)
			(type solid)
		)
		(fill yes)
		(layer "In11.Cu")
		(net "M_L_CPU1_SA_DQS_DP<6>")
	)
	(gr_poly
		(pts
			(xy 140.544804 -231.725978) (xy 140.444728 -231.626156) (xy 140.344652 -231.725978) (xy 140.344652 -231.77373)
			(xy 140.544804 -231.77373)
		)
		(stroke
			(width 0)
			(type solid)
		)
		(fill yes)
		(layer "In11.Cu")
		(net "M_L_CPU1_SA_DQS_DP<1>")
	)
	(gr_poly
		(pts
			(xy 140.544804 -231.322626) (xy 140.544804 -231.278176) (xy 140.344652 -231.278176) (xy 140.344652 -231.322626)
			(xy 140.444728 -231.422702)
		)
		(stroke
			(width 0)
			(type solid)
		)
		(fill yes)
		(layer "In11.Cu")
		(net "M_L_CPU1_SA_DQ<11>")
	)
	(gr_poly
		(pts
			(xy 140.544804 -230.10622) (xy 140.444728 -230.006144) (xy 140.344652 -230.10622) (xy 140.344652 -230.15067)
			(xy 140.544804 -230.15067)
		)
		(stroke
			(width 0)
			(type solid)
		)
		(fill yes)
		(layer "In11.Cu")
		(net "M_L_CPU1_SA_DQ<8>")
	)
	(gr_poly
		(pts
			(xy 140.544804 -229.702614) (xy 140.544804 -229.658164) (xy 140.344652 -229.658164) (xy 140.344652 -229.702614)
			(xy 140.444728 -229.80269)
		)
		(stroke
			(width 0)
			(type solid)
		)
		(fill yes)
		(layer "In11.Cu")
		(net "M_L_CPU1_SA_DQ<7>")
	)
	(gr_poly
		(pts
			(xy 140.544804 -228.486462) (xy 140.444728 -228.386386) (xy 140.344652 -228.486462) (xy 140.344652 -228.530912)
			(xy 140.544804 -228.530912)
		)
		(stroke
			(width 0)
			(type solid)
		)
		(fill yes)
		(layer "In11.Cu")
		(net "M_L_CPU1_SA_DQ<4>")
	)
	(gr_poly
		(pts
			(xy 140.544804 -228.082856) (xy 140.544804 -228.035104) (xy 140.344652 -228.035104) (xy 140.344652 -228.082856)
			(xy 140.444728 -228.182678)
		)
		(stroke
			(width 0)
			(type solid)
		)
		(fill yes)
		(layer "In11.Cu")
		(net "M_L_CPU1_SA_DQS_DP<5>")
	)
	(gr_poly
		(pts
			(xy 140.544804 -226.866196) (xy 140.444728 -226.766374) (xy 140.344652 -226.866196) (xy 140.344652 -226.913948)
			(xy 140.544804 -226.913948)
		)
		(stroke
			(width 0)
			(type solid)
		)
		(fill yes)
		(layer "In11.Cu")
		(net "M_L_CPU1_SA_DQS_DP<0>")
	)
	(gr_poly
		(pts
			(xy 140.544804 -226.46259) (xy 140.544804 -226.41814) (xy 140.344652 -226.41814) (xy 140.344652 -226.46259)
			(xy 140.444728 -226.562666)
		)
		(stroke
			(width 0)
			(type solid)
		)
		(fill yes)
		(layer "In11.Cu")
		(net "M_L_CPU1_SA_DQ<3>")
	)
	(gr_poly
		(pts
			(xy 140.544804 -225.246438) (xy 140.444728 -225.146362) (xy 140.344652 -225.246438) (xy 140.344652 -225.290888)
			(xy 140.544804 -225.290888)
		)
		(stroke
			(width 0)
			(type solid)
		)
		(fill yes)
		(layer "In11.Cu")
		(net "M_L_CPU1_SA_DQ<0>")
	)
	(gr_poly
		(pts
			(xy 140.5509 -251.160026) (xy 140.451078 -251.05995) (xy 140.351002 -251.160026) (xy 140.351002 -251.204476)
			(xy 140.5509 -251.204476)
		)
		(stroke
			(width 0)
			(type solid)
		)
		(fill yes)
		(layer "In11.Cu")
		(net "M_L_CPU1_SA_CS_N<0>")
	)
	(gr_poly
		(pts
			(xy 140.844778 -292.918134) (xy 140.744702 -292.818058) (xy 140.644626 -292.918134) (xy 140.644626 -292.962584)
			(xy 140.844778 -292.962584)
		)
		(stroke
			(width 0)
			(type solid)
		)
		(fill yes)
		(layer "In11.Cu")
		(net "M_L_CPU1_SB_DQ<29>")
	)
	(gr_poly
		(pts
			(xy 140.844778 -292.514274) (xy 140.844778 -292.469824) (xy 140.644626 -292.469824) (xy 140.644626 -292.514274)
			(xy 140.744702 -292.61435)
		)
		(stroke
			(width 0)
			(type solid)
		)
		(fill yes)
		(layer "In11.Cu")
		(net "M_L_CPU1_SB_DQ<30>")
	)
	(gr_poly
		(pts
			(xy 140.844778 -291.297868) (xy 140.744702 -291.198046) (xy 140.644626 -291.297868) (xy 140.644626 -291.34562)
			(xy 140.844778 -291.34562)
		)
		(stroke
			(width 0)
			(type solid)
		)
		(fill yes)
		(layer "In11.Cu")
		(net "M_L_CPU1_SB_DQS_DN<8>")
	)
	(gr_poly
		(pts
			(xy 140.844778 -290.894516) (xy 140.844778 -290.846764) (xy 140.644626 -290.846764) (xy 140.644626 -290.894516)
			(xy 140.744702 -290.994338)
		)
		(stroke
			(width 0)
			(type solid)
		)
		(fill yes)
		(layer "In11.Cu")
		(net "M_L_CPU1_SB_DQS_DN<3>")
	)
	(gr_poly
		(pts
			(xy 140.844778 -289.67811) (xy 140.744702 -289.578034) (xy 140.644626 -289.67811) (xy 140.644626 -289.72256)
			(xy 140.844778 -289.72256)
		)
		(stroke
			(width 0)
			(type solid)
		)
		(fill yes)
		(layer "In11.Cu")
		(net "M_L_CPU1_SB_DQ<25>")
	)
	(gr_poly
		(pts
			(xy 140.844778 -289.27425) (xy 140.844778 -289.2298) (xy 140.644626 -289.2298) (xy 140.644626 -289.27425)
			(xy 140.744702 -289.374326)
		)
		(stroke
			(width 0)
			(type solid)
		)
		(fill yes)
		(layer "In11.Cu")
		(net "M_L_CPU1_SB_DQ<26>")
	)
	(gr_poly
		(pts
			(xy 140.844778 -288.058098) (xy 140.744702 -287.958022) (xy 140.644626 -288.058098) (xy 140.644626 -288.102548)
			(xy 140.844778 -288.102548)
		)
		(stroke
			(width 0)
			(type solid)
		)
		(fill yes)
		(layer "In11.Cu")
		(net "M_L_CPU1_SB_DQ<21>")
	)
	(gr_poly
		(pts
			(xy 140.844778 -287.654492) (xy 140.844778 -287.610042) (xy 140.644626 -287.610042) (xy 140.644626 -287.654492)
			(xy 140.744702 -287.754568)
		)
		(stroke
			(width 0)
			(type solid)
		)
		(fill yes)
		(layer "In11.Cu")
		(net "M_L_CPU1_SB_DQ<22>")
	)
	(gr_poly
		(pts
			(xy 140.844778 -286.438086) (xy 140.744702 -286.33801) (xy 140.644626 -286.438086) (xy 140.644626 -286.485838)
			(xy 140.844778 -286.485838)
		)
		(stroke
			(width 0)
			(type solid)
		)
		(fill yes)
		(layer "In11.Cu")
		(net "M_L_CPU1_SB_DQS_DN<7>")
	)
	(gr_poly
		(pts
			(xy 140.844778 -286.034734) (xy 140.844778 -285.986982) (xy 140.644626 -285.986982) (xy 140.644626 -286.034734)
			(xy 140.744702 -286.134556)
		)
		(stroke
			(width 0)
			(type solid)
		)
		(fill yes)
		(layer "In11.Cu")
		(net "M_L_CPU1_SB_DQS_DN<2>")
	)
	(gr_poly
		(pts
			(xy 140.844778 -284.818328) (xy 140.744702 -284.718252) (xy 140.644626 -284.818328) (xy 140.644626 -284.862778)
			(xy 140.844778 -284.862778)
		)
		(stroke
			(width 0)
			(type solid)
		)
		(fill yes)
		(layer "In11.Cu")
		(net "M_L_CPU1_SB_DQ<17>")
	)
	(gr_poly
		(pts
			(xy 140.844778 -284.414468) (xy 140.844778 -284.370018) (xy 140.644626 -284.370018) (xy 140.644626 -284.414468)
			(xy 140.744702 -284.514544)
		)
		(stroke
			(width 0)
			(type solid)
		)
		(fill yes)
		(layer "In11.Cu")
		(net "M_L_CPU1_SB_DQ<18>")
	)
	(gr_poly
		(pts
			(xy 140.844778 -283.198316) (xy 140.744702 -283.09824) (xy 140.644626 -283.198316) (xy 140.644626 -283.242766)
			(xy 140.844778 -283.242766)
		)
		(stroke
			(width 0)
			(type solid)
		)
		(fill yes)
		(layer "In11.Cu")
		(net "M_L_CPU1_SB_DQ<13>")
	)
	(gr_poly
		(pts
			(xy 140.844778 -282.794456) (xy 140.844778 -282.750006) (xy 140.644626 -282.750006) (xy 140.644626 -282.794456)
			(xy 140.744702 -282.894532)
		)
		(stroke
			(width 0)
			(type solid)
		)
		(fill yes)
		(layer "In11.Cu")
		(net "M_L_CPU1_SB_DQ<14>")
	)
	(gr_poly
		(pts
			(xy 140.844778 -281.57805) (xy 140.744702 -281.478228) (xy 140.644626 -281.57805) (xy 140.644626 -281.625802)
			(xy 140.844778 -281.625802)
		)
		(stroke
			(width 0)
			(type solid)
		)
		(fill yes)
		(layer "In11.Cu")
		(net "M_L_CPU1_SB_DQS_DN<6>")
	)
	(gr_poly
		(pts
			(xy 140.844778 -281.174698) (xy 140.844778 -281.126946) (xy 140.644626 -281.126946) (xy 140.644626 -281.174698)
			(xy 140.744702 -281.27452)
		)
		(stroke
			(width 0)
			(type solid)
		)
		(fill yes)
		(layer "In11.Cu")
		(net "M_L_CPU1_SB_DQS_DN<1>")
	)
	(gr_poly
		(pts
			(xy 140.844778 -279.958292) (xy 140.744702 -279.858216) (xy 140.644626 -279.958292) (xy 140.644626 -280.002742)
			(xy 140.844778 -280.002742)
		)
		(stroke
			(width 0)
			(type solid)
		)
		(fill yes)
		(layer "In11.Cu")
		(net "M_L_CPU1_SB_DQ<9>")
	)
	(gr_poly
		(pts
			(xy 140.844778 -279.554432) (xy 140.844778 -279.509982) (xy 140.644626 -279.509982) (xy 140.644626 -279.554432)
			(xy 140.744702 -279.654508)
		)
		(stroke
			(width 0)
			(type solid)
		)
		(fill yes)
		(layer "In11.Cu")
		(net "M_L_CPU1_SB_DQ<10>")
	)
	(gr_poly
		(pts
			(xy 140.844778 -278.33828) (xy 140.744702 -278.238204) (xy 140.644626 -278.33828) (xy 140.644626 -278.38273)
			(xy 140.844778 -278.38273)
		)
		(stroke
			(width 0)
			(type solid)
		)
		(fill yes)
		(layer "In11.Cu")
		(net "M_L_CPU1_SB_DQ<5>")
	)
	(gr_poly
		(pts
			(xy 140.844778 -277.93442) (xy 140.844778 -277.88997) (xy 140.644626 -277.88997) (xy 140.644626 -277.93442)
			(xy 140.744702 -278.034496)
		)
		(stroke
			(width 0)
			(type solid)
		)
		(fill yes)
		(layer "In11.Cu")
		(net "M_L_CPU1_SB_DQ<6>")
	)
	(gr_poly
		(pts
			(xy 140.844778 -276.718014) (xy 140.744702 -276.618192) (xy 140.644626 -276.718014) (xy 140.644626 -276.765766)
			(xy 140.844778 -276.765766)
		)
		(stroke
			(width 0)
			(type solid)
		)
		(fill yes)
		(layer "In11.Cu")
		(net "M_L_CPU1_SB_DQS_DN<5>")
	)
	(gr_poly
		(pts
			(xy 140.844778 -276.314662) (xy 140.844778 -276.26691) (xy 140.644626 -276.26691) (xy 140.644626 -276.314662)
			(xy 140.744702 -276.414484)
		)
		(stroke
			(width 0)
			(type solid)
		)
		(fill yes)
		(layer "In11.Cu")
		(net "M_L_CPU1_SB_DQS_DN<0>")
	)
	(gr_poly
		(pts
			(xy 140.844778 -275.098256) (xy 140.744702 -274.99818) (xy 140.644626 -275.098256) (xy 140.644626 -275.142706)
			(xy 140.844778 -275.142706)
		)
		(stroke
			(width 0)
			(type solid)
		)
		(fill yes)
		(layer "In11.Cu")
		(net "M_L_CPU1_SB_DQ<1>")
	)
	(gr_poly
		(pts
			(xy 140.844778 -274.694396) (xy 140.844778 -274.649946) (xy 140.644626 -274.649946) (xy 140.644626 -274.694396)
			(xy 140.744702 -274.794472)
		)
		(stroke
			(width 0)
			(type solid)
		)
		(fill yes)
		(layer "In11.Cu")
		(net "M_L_CPU1_SB_DQ<2>")
	)
	(gr_poly
		(pts
			(xy 140.844778 -273.478244) (xy 140.744702 -273.378168) (xy 140.644626 -273.478244) (xy 140.644626 -273.522694)
			(xy 140.844778 -273.522694)
		)
		(stroke
			(width 0)
			(type solid)
		)
		(fill yes)
		(layer "In11.Cu")
		(net "M_L_CPU1_SB_CB<1>")
	)
	(gr_poly
		(pts
			(xy 140.844778 -273.074384) (xy 140.844778 -273.029934) (xy 140.644626 -273.029934) (xy 140.644626 -273.074384)
			(xy 140.744702 -273.17446)
		)
		(stroke
			(width 0)
			(type solid)
		)
		(fill yes)
		(layer "In11.Cu")
		(net "M_L_CPU1_SB_CB<2>")
	)
	(gr_poly
		(pts
			(xy 140.844778 -271.857978) (xy 140.744702 -271.758156) (xy 140.644626 -271.857978) (xy 140.644626 -271.90573)
			(xy 140.844778 -271.90573)
		)
		(stroke
			(width 0)
			(type solid)
		)
		(fill yes)
		(layer "In11.Cu")
		(net "M_L_CPU1_SB_DQS_DN<4>")
	)
	(gr_poly
		(pts
			(xy 140.844778 -271.454626) (xy 140.844778 -271.406874) (xy 140.644626 -271.406874) (xy 140.644626 -271.454626)
			(xy 140.744702 -271.554448)
		)
		(stroke
			(width 0)
			(type solid)
		)
		(fill yes)
		(layer "In11.Cu")
		(net "M_L_CPU1_SB_DQS_DN<9>")
	)
	(gr_poly
		(pts
			(xy 140.844778 -270.23822) (xy 140.744702 -270.138144) (xy 140.644626 -270.23822) (xy 140.644626 -270.28267)
			(xy 140.844778 -270.28267)
		)
		(stroke
			(width 0)
			(type solid)
		)
		(fill yes)
		(layer "In11.Cu")
		(net "M_L_CPU1_SB_CB<5>")
	)
	(gr_poly
		(pts
			(xy 140.844778 -269.83436) (xy 140.844778 -269.78991) (xy 140.644626 -269.78991) (xy 140.644626 -269.83436)
			(xy 140.744702 -269.934436)
		)
		(stroke
			(width 0)
			(type solid)
		)
		(fill yes)
		(layer "In11.Cu")
		(net "M_L_CPU1_SB_CB<6>")
	)
	(gr_poly
		(pts
			(xy 140.844778 -266.998196) (xy 140.744702 -266.89812) (xy 140.644626 -266.998196) (xy 140.644626 -267.042646)
			(xy 140.844778 -267.042646)
		)
		(stroke
			(width 0)
			(type solid)
		)
		(fill yes)
		(layer "In11.Cu")
		(net "M_L_CPU1_SA_RSP<0>")
	)
	(gr_poly
		(pts
			(xy 140.844778 -266.594336) (xy 140.844778 -266.549886) (xy 140.644626 -266.549886) (xy 140.644626 -266.594336)
			(xy 140.744702 -266.694412)
		)
		(stroke
			(width 0)
			(type solid)
		)
		(fill yes)
		(layer "In11.Cu")
		(net "M_L_CPU1_SB_CS_N<1>")
	)
	(gr_poly
		(pts
			(xy 140.844778 -265.378184) (xy 140.744702 -265.278108) (xy 140.644626 -265.378184) (xy 140.644626 -265.422634)
			(xy 140.844778 -265.422634)
		)
		(stroke
			(width 0)
			(type solid)
		)
		(fill yes)
		(layer "In11.Cu")
		(net "M_L_CPU1_SB_PAR")
	)
	(gr_poly
		(pts
			(xy 140.844778 -263.758172) (xy 140.744702 -263.658096) (xy 140.644626 -263.758172) (xy 140.644626 -263.802622)
			(xy 140.844778 -263.802622)
		)
		(stroke
			(width 0)
			(type solid)
		)
		(fill yes)
		(layer "In11.Cu")
		(net "M_L_CPU1_SB_CA<4>")
	)
	(gr_poly
		(pts
			(xy 140.844778 -263.354312) (xy 140.844778 -263.309862) (xy 140.644626 -263.309862) (xy 140.644626 -263.354312)
			(xy 140.744702 -263.454388)
		)
		(stroke
			(width 0)
			(type solid)
		)
		(fill yes)
		(layer "In11.Cu")
		(net "M_L_CPU1_SB_CA<3>")
	)
	(gr_poly
		(pts
			(xy 140.844778 -262.13816) (xy 140.744702 -262.038084) (xy 140.644626 -262.13816) (xy 140.644626 -262.18261)
			(xy 140.844778 -262.18261)
		)
		(stroke
			(width 0)
			(type solid)
		)
		(fill yes)
		(layer "In11.Cu")
		(net "M_L_CPU1_SB_CA<0>")
	)
	(gr_poly
		(pts
			(xy 141.014704 -253.192534) (xy 141.014704 -253.148084) (xy 140.814552 -253.148084) (xy 140.814552 -253.192534)
			(xy 140.914628 -253.29261)
		)
		(stroke
			(width 0)
			(type solid)
		)
		(fill yes)
		(layer "In11.Cu")
		(net "M_L_CPU1_SA_CA<1>")
	)
	(gr_poly
		(pts
			(xy 141.014958 -256.432812) (xy 141.014958 -256.38506) (xy 140.814806 -256.38506) (xy 140.814806 -256.432812)
			(xy 140.914882 -256.532634)
		)
		(stroke
			(width 0)
			(type solid)
		)
		(fill yes)
		(layer "In11.Cu")
		(net "M_L_CPU1_CLK_DN<0>")
	)
	(gr_poly
		(pts
			(xy 141.014958 -255.216406) (xy 140.914882 -255.11633) (xy 140.814806 -255.216406) (xy 140.814806 -255.260856)
			(xy 141.014958 -255.260856)
		)
		(stroke
			(width 0)
			(type solid)
		)
		(fill yes)
		(layer "In11.Cu")
		(net "M_L_CPU1_SA_CA<6>")
	)
	(gr_poly
		(pts
			(xy 141.014958 -254.812546) (xy 141.014958 -254.768096) (xy 140.814806 -254.768096) (xy 140.814806 -254.812546)
			(xy 140.914882 -254.912622)
		)
		(stroke
			(width 0)
			(type solid)
		)
		(fill yes)
		(layer "In11.Cu")
		(net "M_L_CPU1_SA_CA<5>")
	)
	(gr_poly
		(pts
			(xy 141.014958 -253.596394) (xy 140.914882 -253.496318) (xy 140.814806 -253.596394) (xy 140.814806 -253.640844)
			(xy 141.014958 -253.640844)
		)
		(stroke
			(width 0)
			(type solid)
		)
		(fill yes)
		(layer "In11.Cu")
		(net "M_L_CPU1_SA_CA<2>")
	)
	(gr_poly
		(pts
			(xy 141.014958 -250.35637) (xy 140.914882 -250.256294) (xy 140.814806 -250.35637) (xy 140.814806 -250.40082)
			(xy 141.014958 -250.40082)
		)
		(stroke
			(width 0)
			(type solid)
		)
		(fill yes)
		(layer "In11.Cu")
		(net "M_L_CPU1_ALERT_R_N")
	)
	(gr_poly
		(pts
			(xy 141.014958 -248.736358) (xy 140.914882 -248.636282) (xy 140.814806 -248.736358) (xy 140.814806 -248.780808)
			(xy 141.014958 -248.780808)
		)
		(stroke
			(width 0)
			(type solid)
		)
		(fill yes)
		(layer "In11.Cu")
		(net "M_L_CPU1_SA_CB<5>")
	)
	(gr_poly
		(pts
			(xy 141.014958 -248.332498) (xy 141.014958 -248.288048) (xy 140.814806 -248.288048) (xy 140.814806 -248.332498)
			(xy 140.914882 -248.432574)
		)
		(stroke
			(width 0)
			(type solid)
		)
		(fill yes)
		(layer "In11.Cu")
		(net "M_L_CPU1_SA_CB<6>")
	)
	(gr_poly
		(pts
			(xy 141.014958 -247.116092) (xy 140.914882 -247.01627) (xy 140.814806 -247.116092) (xy 140.814806 -247.163844)
			(xy 141.014958 -247.163844)
		)
		(stroke
			(width 0)
			(type solid)
		)
		(fill yes)
		(layer "In11.Cu")
		(net "M_L_CPU1_SA_DQS_DN<9>")
	)
	(gr_poly
		(pts
			(xy 141.014958 -246.71274) (xy 141.014958 -246.664988) (xy 140.814806 -246.664988) (xy 140.814806 -246.71274)
			(xy 140.914882 -246.812562)
		)
		(stroke
			(width 0)
			(type solid)
		)
		(fill yes)
		(layer "In11.Cu")
		(net "M_L_CPU1_SA_DQS_DN<4>")
	)
	(gr_poly
		(pts
			(xy 141.014958 -245.496334) (xy 140.914882 -245.396258) (xy 140.814806 -245.496334) (xy 140.814806 -245.540784)
			(xy 141.014958 -245.540784)
		)
		(stroke
			(width 0)
			(type solid)
		)
		(fill yes)
		(layer "In11.Cu")
		(net "M_L_CPU1_SA_CB<1>")
	)
	(gr_poly
		(pts
			(xy 141.014958 -245.092474) (xy 141.014958 -245.048024) (xy 140.814806 -245.048024) (xy 140.814806 -245.092474)
			(xy 140.914882 -245.19255)
		)
		(stroke
			(width 0)
			(type solid)
		)
		(fill yes)
		(layer "In11.Cu")
		(net "M_L_CPU1_SA_CB<2>")
	)
	(gr_poly
		(pts
			(xy 141.014958 -243.876322) (xy 140.914882 -243.776246) (xy 140.814806 -243.876322) (xy 140.814806 -243.920772)
			(xy 141.014958 -243.920772)
		)
		(stroke
			(width 0)
			(type solid)
		)
		(fill yes)
		(layer "In11.Cu")
		(net "M_L_CPU1_SA_DQ<29>")
	)
	(gr_poly
		(pts
			(xy 141.014958 -243.472462) (xy 141.014958 -243.428012) (xy 140.814806 -243.428012) (xy 140.814806 -243.472462)
			(xy 140.914882 -243.572538)
		)
		(stroke
			(width 0)
			(type solid)
		)
		(fill yes)
		(layer "In11.Cu")
		(net "M_L_CPU1_SA_DQ<30>")
	)
	(gr_poly
		(pts
			(xy 141.014958 -242.256056) (xy 140.914882 -242.156234) (xy 140.814806 -242.256056) (xy 140.814806 -242.303808)
			(xy 141.014958 -242.303808)
		)
		(stroke
			(width 0)
			(type solid)
		)
		(fill yes)
		(layer "In11.Cu")
		(net "M_L_CPU1_SA_DQS_DN<8>")
	)
	(gr_poly
		(pts
			(xy 141.014958 -241.852704) (xy 141.014958 -241.804952) (xy 140.814806 -241.804952) (xy 140.814806 -241.852704)
			(xy 140.914882 -241.952526)
		)
		(stroke
			(width 0)
			(type solid)
		)
		(fill yes)
		(layer "In11.Cu")
		(net "M_L_CPU1_SA_DQS_DN<3>")
	)
	(gr_poly
		(pts
			(xy 141.014958 -240.636298) (xy 140.914882 -240.536222) (xy 140.814806 -240.636298) (xy 140.814806 -240.680748)
			(xy 141.014958 -240.680748)
		)
		(stroke
			(width 0)
			(type solid)
		)
		(fill yes)
		(layer "In11.Cu")
		(net "M_L_CPU1_SA_DQ<25>")
	)
	(gr_poly
		(pts
			(xy 141.014958 -240.232438) (xy 141.014958 -240.187988) (xy 140.814806 -240.187988) (xy 140.814806 -240.232438)
			(xy 140.914882 -240.332514)
		)
		(stroke
			(width 0)
			(type solid)
		)
		(fill yes)
		(layer "In11.Cu")
		(net "M_L_CPU1_SA_DQ<26>")
	)
	(gr_poly
		(pts
			(xy 141.014958 -239.016286) (xy 140.914882 -238.91621) (xy 140.814806 -239.016286) (xy 140.814806 -239.060736)
			(xy 141.014958 -239.060736)
		)
		(stroke
			(width 0)
			(type solid)
		)
		(fill yes)
		(layer "In11.Cu")
		(net "M_L_CPU1_SA_DQ<21>")
	)
	(gr_poly
		(pts
			(xy 141.014958 -238.612426) (xy 141.014958 -238.567976) (xy 140.814806 -238.567976) (xy 140.814806 -238.612426)
			(xy 140.914882 -238.712502)
		)
		(stroke
			(width 0)
			(type solid)
		)
		(fill yes)
		(layer "In11.Cu")
		(net "M_L_CPU1_SA_DQ<22>")
	)
	(gr_poly
		(pts
			(xy 141.014958 -237.39602) (xy 140.914882 -237.296198) (xy 140.814806 -237.39602) (xy 140.814806 -237.443772)
			(xy 141.014958 -237.443772)
		)
		(stroke
			(width 0)
			(type solid)
		)
		(fill yes)
		(layer "In11.Cu")
		(net "M_L_CPU1_SA_DQS_DN<7>")
	)
	(gr_poly
		(pts
			(xy 141.014958 -236.992668) (xy 141.014958 -236.944916) (xy 140.814806 -236.944916) (xy 140.814806 -236.992668)
			(xy 140.914882 -237.09249)
		)
		(stroke
			(width 0)
			(type solid)
		)
		(fill yes)
		(layer "In11.Cu")
		(net "M_L_CPU1_SA_DQS_DN<2>")
	)
	(gr_poly
		(pts
			(xy 141.014958 -235.776262) (xy 140.914882 -235.676186) (xy 140.814806 -235.776262) (xy 140.814806 -235.820712)
			(xy 141.014958 -235.820712)
		)
		(stroke
			(width 0)
			(type solid)
		)
		(fill yes)
		(layer "In11.Cu")
		(net "M_L_CPU1_SA_DQ<17>")
	)
	(gr_poly
		(pts
			(xy 141.014958 -235.372402) (xy 141.014958 -235.327952) (xy 140.814806 -235.327952) (xy 140.814806 -235.372402)
			(xy 140.914882 -235.472478)
		)
		(stroke
			(width 0)
			(type solid)
		)
		(fill yes)
		(layer "In11.Cu")
		(net "M_L_CPU1_SA_DQ<18>")
	)
	(gr_poly
		(pts
			(xy 141.014958 -234.15625) (xy 140.914882 -234.056174) (xy 140.814806 -234.15625) (xy 140.814806 -234.2007)
			(xy 141.014958 -234.2007)
		)
		(stroke
			(width 0)
			(type solid)
		)
		(fill yes)
		(layer "In11.Cu")
		(net "M_L_CPU1_SA_DQ<13>")
	)
	(gr_poly
		(pts
			(xy 141.014958 -233.75239) (xy 141.014958 -233.70794) (xy 140.814806 -233.70794) (xy 140.814806 -233.75239)
			(xy 140.914882 -233.852466)
		)
		(stroke
			(width 0)
			(type solid)
		)
		(fill yes)
		(layer "In11.Cu")
		(net "M_L_CPU1_SA_DQ<14>")
	)
	(gr_poly
		(pts
			(xy 141.014958 -232.535984) (xy 140.914882 -232.436162) (xy 140.814806 -232.535984) (xy 140.814806 -232.583736)
			(xy 141.014958 -232.583736)
		)
		(stroke
			(width 0)
			(type solid)
		)
		(fill yes)
		(layer "In11.Cu")
		(net "M_L_CPU1_SA_DQS_DN<6>")
	)
	(gr_poly
		(pts
			(xy 141.014958 -232.132632) (xy 141.014958 -232.08488) (xy 140.814806 -232.08488) (xy 140.814806 -232.132632)
			(xy 140.914882 -232.232454)
		)
		(stroke
			(width 0)
			(type solid)
		)
		(fill yes)
		(layer "In11.Cu")
		(net "M_L_CPU1_SA_DQS_DN<1>")
	)
	(gr_poly
		(pts
			(xy 141.014958 -230.916226) (xy 140.914882 -230.81615) (xy 140.814806 -230.916226) (xy 140.814806 -230.960676)
			(xy 141.014958 -230.960676)
		)
		(stroke
			(width 0)
			(type solid)
		)
		(fill yes)
		(layer "In11.Cu")
		(net "M_L_CPU1_SA_DQ<9>")
	)
	(gr_poly
		(pts
			(xy 141.014958 -230.51262) (xy 141.014958 -230.46817) (xy 140.814806 -230.46817) (xy 140.814806 -230.51262)
			(xy 140.914882 -230.612696)
		)
		(stroke
			(width 0)
			(type solid)
		)
		(fill yes)
		(layer "In11.Cu")
		(net "M_L_CPU1_SA_DQ<10>")
	)
	(gr_poly
		(pts
			(xy 141.014958 -229.296214) (xy 140.914882 -229.196138) (xy 140.814806 -229.296214) (xy 140.814806 -229.340664)
			(xy 141.014958 -229.340664)
		)
		(stroke
			(width 0)
			(type solid)
		)
		(fill yes)
		(layer "In11.Cu")
		(net "M_L_CPU1_SA_DQ<5>")
	)
	(gr_poly
		(pts
			(xy 141.014958 -228.892608) (xy 141.014958 -228.848158) (xy 140.814806 -228.848158) (xy 140.814806 -228.892608)
			(xy 140.914882 -228.992684)
		)
		(stroke
			(width 0)
			(type solid)
		)
		(fill yes)
		(layer "In11.Cu")
		(net "M_L_CPU1_SA_DQ<6>")
	)
	(gr_poly
		(pts
			(xy 141.014958 -227.676202) (xy 140.914882 -227.57638) (xy 140.814806 -227.676202) (xy 140.814806 -227.723954)
			(xy 141.014958 -227.723954)
		)
		(stroke
			(width 0)
			(type solid)
		)
		(fill yes)
		(layer "In11.Cu")
		(net "M_L_CPU1_SA_DQS_DN<5>")
	)
	(gr_poly
		(pts
			(xy 141.014958 -227.27285) (xy 141.014958 -227.225098) (xy 140.814806 -227.225098) (xy 140.814806 -227.27285)
			(xy 140.914882 -227.372672)
		)
		(stroke
			(width 0)
			(type solid)
		)
		(fill yes)
		(layer "In11.Cu")
		(net "M_L_CPU1_SA_DQS_DN<0>")
	)
	(gr_poly
		(pts
			(xy 141.014958 -226.056444) (xy 140.914882 -225.956368) (xy 140.814806 -226.056444) (xy 140.814806 -226.100894)
			(xy 141.014958 -226.100894)
		)
		(stroke
			(width 0)
			(type solid)
		)
		(fill yes)
		(layer "In11.Cu")
		(net "M_L_CPU1_SA_DQ<1>")
	)
	(gr_poly
		(pts
			(xy 141.014958 -225.652584) (xy 141.014958 -225.608134) (xy 140.814806 -225.608134) (xy 140.814806 -225.652584)
			(xy 140.914882 -225.75266)
		)
		(stroke
			(width 0)
			(type solid)
		)
		(fill yes)
		(layer "In11.Cu")
		(net "M_L_CPU1_SA_DQ<2>")
	)
	(gr_poly
		(pts
			(xy 141.0208 -251.970032) (xy 140.920978 -251.869956) (xy 140.820902 -251.970032) (xy 140.820902 -252.014482)
			(xy 141.0208 -252.014482)
		)
		(stroke
			(width 0)
			(type solid)
		)
		(fill yes)
		(layer "In11.Cu")
		(net "M_L_CPU1_SA_CS_N<1>")
	)
	(gr_poly
		(pts
			(xy 141.308582 -264.561828) (xy 141.208506 -264.461752) (xy 141.108684 -264.561828) (xy 141.108684 -264.606278)
			(xy 141.308582 -264.606278)
		)
		(stroke
			(width 0)
			(type solid)
		)
		(fill yes)
		(layer "In11.Cu")
		(net "M_L_CPU1_SB_CA<6>")
	)
	(gr_poly
		(pts
			(xy 141.314932 -293.32428) (xy 141.314932 -293.27983) (xy 141.11478 -293.27983) (xy 141.11478 -293.32428)
			(xy 141.214856 -293.424356)
		)
		(stroke
			(width 0)
			(type solid)
		)
		(fill yes)
		(layer "In11.Cu")
		(net "M_L_CPU1_SB_DQ<31>")
	)
	(gr_poly
		(pts
			(xy 141.314932 -292.108128) (xy 141.214856 -292.008052) (xy 141.11478 -292.108128) (xy 141.11478 -292.152578)
			(xy 141.314932 -292.152578)
		)
		(stroke
			(width 0)
			(type solid)
		)
		(fill yes)
		(layer "In11.Cu")
		(net "M_L_CPU1_SB_DQ<28>")
	)
	(gr_poly
		(pts
			(xy 141.314932 -291.704522) (xy 141.314932 -291.65677) (xy 141.11478 -291.65677) (xy 141.11478 -291.704522)
			(xy 141.214856 -291.804344)
		)
		(stroke
			(width 0)
			(type solid)
		)
		(fill yes)
		(layer "In11.Cu")
		(net "M_L_CPU1_SB_DQS_DP<8>")
	)
	(gr_poly
		(pts
			(xy 141.314932 -290.487862) (xy 141.214856 -290.38804) (xy 141.11478 -290.487862) (xy 141.11478 -290.535614)
			(xy 141.314932 -290.535614)
		)
		(stroke
			(width 0)
			(type solid)
		)
		(fill yes)
		(layer "In11.Cu")
		(net "M_L_CPU1_SB_DQS_DP<3>")
	)
	(gr_poly
		(pts
			(xy 141.314932 -290.084256) (xy 141.314932 -290.039806) (xy 141.11478 -290.039806) (xy 141.11478 -290.084256)
			(xy 141.214856 -290.184332)
		)
		(stroke
			(width 0)
			(type solid)
		)
		(fill yes)
		(layer "In11.Cu")
		(net "M_L_CPU1_SB_DQ<27>")
	)
	(gr_poly
		(pts
			(xy 141.314932 -288.868104) (xy 141.214856 -288.768028) (xy 141.11478 -288.868104) (xy 141.11478 -288.912554)
			(xy 141.314932 -288.912554)
		)
		(stroke
			(width 0)
			(type solid)
		)
		(fill yes)
		(layer "In11.Cu")
		(net "M_L_CPU1_SB_DQ<24>")
	)
	(gr_poly
		(pts
			(xy 141.314932 -288.464498) (xy 141.314932 -288.420048) (xy 141.11478 -288.420048) (xy 141.11478 -288.464498)
			(xy 141.214856 -288.564574)
		)
		(stroke
			(width 0)
			(type solid)
		)
		(fill yes)
		(layer "In11.Cu")
		(net "M_L_CPU1_SB_DQ<23>")
	)
	(gr_poly
		(pts
			(xy 141.314932 -287.248092) (xy 141.214856 -287.148016) (xy 141.11478 -287.248092) (xy 141.11478 -287.292542)
			(xy 141.314932 -287.292542)
		)
		(stroke
			(width 0)
			(type solid)
		)
		(fill yes)
		(layer "In11.Cu")
		(net "M_L_CPU1_SB_DQ<20>")
	)
	(gr_poly
		(pts
			(xy 141.314932 -286.844486) (xy 141.314932 -286.796734) (xy 141.11478 -286.796734) (xy 141.11478 -286.844486)
			(xy 141.214856 -286.944562)
		)
		(stroke
			(width 0)
			(type solid)
		)
		(fill yes)
		(layer "In11.Cu")
		(net "M_L_CPU1_SB_DQS_DP<7>")
	)
	(gr_poly
		(pts
			(xy 141.314932 -285.62808) (xy 141.214856 -285.528258) (xy 141.11478 -285.62808) (xy 141.11478 -285.675832)
			(xy 141.314932 -285.675832)
		)
		(stroke
			(width 0)
			(type solid)
		)
		(fill yes)
		(layer "In11.Cu")
		(net "M_L_CPU1_SB_DQS_DP<2>")
	)
	(gr_poly
		(pts
			(xy 141.314932 -285.224474) (xy 141.314932 -285.180024) (xy 141.11478 -285.180024) (xy 141.11478 -285.224474)
			(xy 141.214856 -285.32455)
		)
		(stroke
			(width 0)
			(type solid)
		)
		(fill yes)
		(layer "In11.Cu")
		(net "M_L_CPU1_SB_DQ<19>")
	)
	(gr_poly
		(pts
			(xy 141.314932 -284.008322) (xy 141.214856 -283.908246) (xy 141.11478 -284.008322) (xy 141.11478 -284.052772)
			(xy 141.314932 -284.052772)
		)
		(stroke
			(width 0)
			(type solid)
		)
		(fill yes)
		(layer "In11.Cu")
		(net "M_L_CPU1_SB_DQ<16>")
	)
	(gr_poly
		(pts
			(xy 141.314932 -283.604462) (xy 141.314932 -283.560012) (xy 141.11478 -283.560012) (xy 141.11478 -283.604462)
			(xy 141.214856 -283.704538)
		)
		(stroke
			(width 0)
			(type solid)
		)
		(fill yes)
		(layer "In11.Cu")
		(net "M_L_CPU1_SB_DQ<15>")
	)
	(gr_poly
		(pts
			(xy 141.314932 -282.38831) (xy 141.214856 -282.288234) (xy 141.11478 -282.38831) (xy 141.11478 -282.43276)
			(xy 141.314932 -282.43276)
		)
		(stroke
			(width 0)
			(type solid)
		)
		(fill yes)
		(layer "In11.Cu")
		(net "M_L_CPU1_SB_DQ<12>")
	)
	(gr_poly
		(pts
			(xy 141.314932 -281.984704) (xy 141.314932 -281.936952) (xy 141.11478 -281.936952) (xy 141.11478 -281.984704)
			(xy 141.214856 -282.084526)
		)
		(stroke
			(width 0)
			(type solid)
		)
		(fill yes)
		(layer "In11.Cu")
		(net "M_L_CPU1_SB_DQS_DP<6>")
	)
	(gr_poly
		(pts
			(xy 141.314932 -280.768044) (xy 141.214856 -280.668222) (xy 141.11478 -280.768044) (xy 141.11478 -280.815796)
			(xy 141.314932 -280.815796)
		)
		(stroke
			(width 0)
			(type solid)
		)
		(fill yes)
		(layer "In11.Cu")
		(net "M_L_CPU1_SB_DQS_DP<1>")
	)
	(gr_poly
		(pts
			(xy 141.314932 -280.364438) (xy 141.314932 -280.319988) (xy 141.11478 -280.319988) (xy 141.11478 -280.364438)
			(xy 141.214856 -280.464514)
		)
		(stroke
			(width 0)
			(type solid)
		)
		(fill yes)
		(layer "In11.Cu")
		(net "M_L_CPU1_SB_DQ<11>")
	)
	(gr_poly
		(pts
			(xy 141.314932 -279.148286) (xy 141.214856 -279.04821) (xy 141.11478 -279.148286) (xy 141.11478 -279.192736)
			(xy 141.314932 -279.192736)
		)
		(stroke
			(width 0)
			(type solid)
		)
		(fill yes)
		(layer "In11.Cu")
		(net "M_L_CPU1_SB_DQ<8>")
	)
	(gr_poly
		(pts
			(xy 141.314932 -278.744426) (xy 141.314932 -278.699976) (xy 141.11478 -278.699976) (xy 141.11478 -278.744426)
			(xy 141.214856 -278.844502)
		)
		(stroke
			(width 0)
			(type solid)
		)
		(fill yes)
		(layer "In11.Cu")
		(net "M_L_CPU1_SB_DQ<7>")
	)
	(gr_poly
		(pts
			(xy 141.314932 -277.528274) (xy 141.214856 -277.428198) (xy 141.11478 -277.528274) (xy 141.11478 -277.572724)
			(xy 141.314932 -277.572724)
		)
		(stroke
			(width 0)
			(type solid)
		)
		(fill yes)
		(layer "In11.Cu")
		(net "M_L_CPU1_SB_DQ<4>")
	)
	(gr_poly
		(pts
			(xy 141.314932 -277.124668) (xy 141.314932 -277.076916) (xy 141.11478 -277.076916) (xy 141.11478 -277.124668)
			(xy 141.214856 -277.22449)
		)
		(stroke
			(width 0)
			(type solid)
		)
		(fill yes)
		(layer "In11.Cu")
		(net "M_L_CPU1_SB_DQS_DP<5>")
	)
	(gr_poly
		(pts
			(xy 141.314932 -275.908008) (xy 141.214856 -275.808186) (xy 141.11478 -275.908008) (xy 141.11478 -275.95576)
			(xy 141.314932 -275.95576)
		)
		(stroke
			(width 0)
			(type solid)
		)
		(fill yes)
		(layer "In11.Cu")
		(net "M_L_CPU1_SB_DQS_DP<0>")
	)
	(gr_poly
		(pts
			(xy 141.314932 -275.504402) (xy 141.314932 -275.459952) (xy 141.11478 -275.459952) (xy 141.11478 -275.504402)
			(xy 141.214856 -275.604478)
		)
		(stroke
			(width 0)
			(type solid)
		)
		(fill yes)
		(layer "In11.Cu")
		(net "M_L_CPU1_SB_DQ<3>")
	)
	(gr_poly
		(pts
			(xy 141.314932 -274.28825) (xy 141.214856 -274.188174) (xy 141.11478 -274.28825) (xy 141.11478 -274.3327)
			(xy 141.314932 -274.3327)
		)
		(stroke
			(width 0)
			(type solid)
		)
		(fill yes)
		(layer "In11.Cu")
		(net "M_L_CPU1_SB_DQ<0>")
	)
	(gr_poly
		(pts
			(xy 141.314932 -273.88439) (xy 141.314932 -273.83994) (xy 141.11478 -273.83994) (xy 141.11478 -273.88439)
			(xy 141.214856 -273.984466)
		)
		(stroke
			(width 0)
			(type solid)
		)
		(fill yes)
		(layer "In11.Cu")
		(net "M_L_CPU1_SB_CB<3>")
	)
	(gr_poly
		(pts
			(xy 141.314932 -272.668238) (xy 141.214856 -272.568162) (xy 141.11478 -272.668238) (xy 141.11478 -272.712688)
			(xy 141.314932 -272.712688)
		)
		(stroke
			(width 0)
			(type solid)
		)
		(fill yes)
		(layer "In11.Cu")
		(net "M_L_CPU1_SB_CB<0>")
	)
	(gr_poly
		(pts
			(xy 141.314932 -272.264632) (xy 141.314932 -272.21688) (xy 141.11478 -272.21688) (xy 141.11478 -272.264632)
			(xy 141.214856 -272.364454)
		)
		(stroke
			(width 0)
			(type solid)
		)
		(fill yes)
		(layer "In11.Cu")
		(net "M_L_CPU1_SB_DQS_DP<4>")
	)
	(gr_poly
		(pts
			(xy 141.314932 -271.047972) (xy 141.214856 -270.94815) (xy 141.11478 -271.047972) (xy 141.11478 -271.095724)
			(xy 141.314932 -271.095724)
		)
		(stroke
			(width 0)
			(type solid)
		)
		(fill yes)
		(layer "In11.Cu")
		(net "M_L_CPU1_SB_DQS_DP<9>")
	)
	(gr_poly
		(pts
			(xy 141.314932 -270.644366) (xy 141.314932 -270.599916) (xy 141.11478 -270.599916) (xy 141.11478 -270.644366)
			(xy 141.214856 -270.744442)
		)
		(stroke
			(width 0)
			(type solid)
		)
		(fill yes)
		(layer "In11.Cu")
		(net "M_L_CPU1_SB_CB<7>")
	)
	(gr_poly
		(pts
			(xy 141.314932 -269.428214) (xy 141.214856 -269.328138) (xy 141.11478 -269.428214) (xy 141.11478 -269.472664)
			(xy 141.314932 -269.472664)
		)
		(stroke
			(width 0)
			(type solid)
		)
		(fill yes)
		(layer "In11.Cu")
		(net "M_L_CPU1_SB_CB<4>")
	)
	(gr_poly
		(pts
			(xy 141.314932 -267.808202) (xy 141.214856 -267.708126) (xy 141.11478 -267.808202) (xy 141.11478 -267.852652)
			(xy 141.314932 -267.852652)
		)
		(stroke
			(width 0)
			(type solid)
		)
		(fill yes)
		(layer "In11.Cu")
		(net "M_L_CPU1_SB_RSP<0>")
	)
	(gr_poly
		(pts
			(xy 141.314932 -265.78433) (xy 141.314932 -265.73988) (xy 141.11478 -265.73988) (xy 141.11478 -265.78433)
			(xy 141.214856 -265.884406)
		)
		(stroke
			(width 0)
			(type solid)
		)
		(fill yes)
		(layer "In11.Cu")
		(net "M_L_CPU1_SB_CS_N<0>")
	)
	(gr_poly
		(pts
			(xy 141.314932 -264.164318) (xy 141.314932 -264.119868) (xy 141.11478 -264.119868) (xy 141.11478 -264.164318)
			(xy 141.214856 -264.264394)
		)
		(stroke
			(width 0)
			(type solid)
		)
		(fill yes)
		(layer "In11.Cu")
		(net "M_L_CPU1_SB_CA<5>")
	)
	(gr_poly
		(pts
			(xy 141.314932 -262.948166) (xy 141.214856 -262.84809) (xy 141.11478 -262.948166) (xy 141.11478 -262.992616)
			(xy 141.314932 -262.992616)
		)
		(stroke
			(width 0)
			(type solid)
		)
		(fill yes)
		(layer "In11.Cu")
		(net "M_L_CPU1_SB_CA<2>")
	)
	(gr_poly
		(pts
			(xy 141.314932 -262.544306) (xy 141.314932 -262.499856) (xy 141.11478 -262.499856) (xy 141.11478 -262.544306)
			(xy 141.214856 -262.644382)
		)
		(stroke
			(width 0)
			(type solid)
		)
		(fill yes)
		(layer "In11.Cu")
		(net "M_L_CPU1_SB_CA<1>")
	)
	(gr_poly
		(pts
			(xy 141.484858 -256.026158) (xy 141.384782 -255.926336) (xy 141.284706 -256.026158) (xy 141.284706 -256.07391)
			(xy 141.484858 -256.07391)
		)
		(stroke
			(width 0)
			(type solid)
		)
		(fill yes)
		(layer "In11.Cu")
		(net "M_L_CPU1_CLK_DP<0>")
	)
	(gr_poly
		(pts
			(xy 141.484858 -255.622552) (xy 141.484858 -255.578102) (xy 141.284706 -255.578102) (xy 141.284706 -255.622552)
			(xy 141.384782 -255.722628)
		)
		(stroke
			(width 0)
			(type solid)
		)
		(fill yes)
		(layer "In11.Cu")
		(net "M_L_CPU1_SA_PAR")
	)
	(gr_poly
		(pts
			(xy 141.484858 -254.4064) (xy 141.384782 -254.306324) (xy 141.284706 -254.4064) (xy 141.284706 -254.45085)
			(xy 141.484858 -254.45085)
		)
		(stroke
			(width 0)
			(type solid)
		)
		(fill yes)
		(layer "In11.Cu")
		(net "M_L_CPU1_SA_CA<4>")
	)
	(gr_poly
		(pts
			(xy 141.484858 -254.00254) (xy 141.484858 -253.95809) (xy 141.284706 -253.95809) (xy 141.284706 -254.00254)
			(xy 141.384782 -254.102616)
		)
		(stroke
			(width 0)
			(type solid)
		)
		(fill yes)
		(layer "In11.Cu")
		(net "M_L_CPU1_SA_CA<3>")
	)
	(gr_poly
		(pts
			(xy 141.484858 -252.786388) (xy 141.384782 -252.686312) (xy 141.284706 -252.786388) (xy 141.284706 -252.830838)
			(xy 141.484858 -252.830838)
		)
		(stroke
			(width 0)
			(type solid)
		)
		(fill yes)
		(layer "In11.Cu")
		(net "M_L_CPU1_SA_CA<0>")
	)
	(gr_poly
		(pts
			(xy 141.484858 -251.160026) (xy 141.384782 -251.05995) (xy 141.284706 -251.160026) (xy 141.284706 -251.204476)
			(xy 141.484858 -251.204476)
		)
		(stroke
			(width 0)
			(type solid)
		)
		(fill yes)
		(layer "In11.Cu")
		(net "M_L_CPU1_SA_CS_N<0>")
	)
	(gr_poly
		(pts
			(xy 141.484858 -250.762516) (xy 141.484858 -250.718066) (xy 141.284706 -250.718066) (xy 141.284706 -250.762516)
			(xy 141.384782 -250.862592)
		)
		(stroke
			(width 0)
			(type solid)
		)
		(fill yes)
		(layer "In11.Cu")
		(net "M_L_CPU1_RESET_N")
	)
	(gr_poly
		(pts
			(xy 141.484858 -249.142504) (xy 141.484858 -249.098054) (xy 141.284706 -249.098054) (xy 141.284706 -249.142504)
			(xy 141.384782 -249.24258)
		)
		(stroke
			(width 0)
			(type solid)
		)
		(fill yes)
		(layer "In11.Cu")
		(net "M_L_CPU1_SA_CB<7>")
	)
	(gr_poly
		(pts
			(xy 141.484858 -247.926352) (xy 141.384782 -247.826276) (xy 141.284706 -247.926352) (xy 141.284706 -247.970802)
			(xy 141.484858 -247.970802)
		)
		(stroke
			(width 0)
			(type solid)
		)
		(fill yes)
		(layer "In11.Cu")
		(net "M_L_CPU1_SA_CB<4>")
	)
	(gr_poly
		(pts
			(xy 141.484858 -247.522746) (xy 141.484858 -247.474994) (xy 141.284706 -247.474994) (xy 141.284706 -247.522746)
			(xy 141.384782 -247.622568)
		)
		(stroke
			(width 0)
			(type solid)
		)
		(fill yes)
		(layer "In11.Cu")
		(net "M_L_CPU1_SA_DQS_DP<9>")
	)
	(gr_poly
		(pts
			(xy 141.484858 -246.306086) (xy 141.384782 -246.206264) (xy 141.284706 -246.306086) (xy 141.284706 -246.353838)
			(xy 141.484858 -246.353838)
		)
		(stroke
			(width 0)
			(type solid)
		)
		(fill yes)
		(layer "In11.Cu")
		(net "M_L_CPU1_SA_DQS_DP<4>")
	)
	(gr_poly
		(pts
			(xy 141.484858 -245.90248) (xy 141.484858 -245.85803) (xy 141.284706 -245.85803) (xy 141.284706 -245.90248)
			(xy 141.384782 -246.002556)
		)
		(stroke
			(width 0)
			(type solid)
		)
		(fill yes)
		(layer "In11.Cu")
		(net "M_L_CPU1_SA_CB<3>")
	)
	(gr_poly
		(pts
			(xy 141.484858 -244.686328) (xy 141.384782 -244.586252) (xy 141.284706 -244.686328) (xy 141.284706 -244.730778)
			(xy 141.484858 -244.730778)
		)
		(stroke
			(width 0)
			(type solid)
		)
		(fill yes)
		(layer "In11.Cu")
		(net "M_L_CPU1_SA_CB<0>")
	)
	(gr_poly
		(pts
			(xy 141.484858 -244.282468) (xy 141.484858 -244.238018) (xy 141.284706 -244.238018) (xy 141.284706 -244.282468)
			(xy 141.384782 -244.382544)
		)
		(stroke
			(width 0)
			(type solid)
		)
		(fill yes)
		(layer "In11.Cu")
		(net "M_L_CPU1_SA_DQ<31>")
	)
	(gr_poly
		(pts
			(xy 141.484858 -243.066316) (xy 141.384782 -242.96624) (xy 141.284706 -243.066316) (xy 141.284706 -243.110766)
			(xy 141.484858 -243.110766)
		)
		(stroke
			(width 0)
			(type solid)
		)
		(fill yes)
		(layer "In11.Cu")
		(net "M_L_CPU1_SA_DQ<28>")
	)
	(gr_poly
		(pts
			(xy 141.484858 -242.66271) (xy 141.484858 -242.614958) (xy 141.284706 -242.614958) (xy 141.284706 -242.66271)
			(xy 141.384782 -242.762532)
		)
		(stroke
			(width 0)
			(type solid)
		)
		(fill yes)
		(layer "In11.Cu")
		(net "M_L_CPU1_SA_DQS_DP<8>")
	)
	(gr_poly
		(pts
			(xy 141.484858 -241.44605) (xy 141.384782 -241.346228) (xy 141.284706 -241.44605) (xy 141.284706 -241.493802)
			(xy 141.484858 -241.493802)
		)
		(stroke
			(width 0)
			(type solid)
		)
		(fill yes)
		(layer "In11.Cu")
		(net "M_L_CPU1_SA_DQS_DP<3>")
	)
	(gr_poly
		(pts
			(xy 141.484858 -241.042444) (xy 141.484858 -240.997994) (xy 141.284706 -240.997994) (xy 141.284706 -241.042444)
			(xy 141.384782 -241.14252)
		)
		(stroke
			(width 0)
			(type solid)
		)
		(fill yes)
		(layer "In11.Cu")
		(net "M_L_CPU1_SA_DQ<27>")
	)
	(gr_poly
		(pts
			(xy 141.484858 -239.826292) (xy 141.384782 -239.726216) (xy 141.284706 -239.826292) (xy 141.284706 -239.870742)
			(xy 141.484858 -239.870742)
		)
		(stroke
			(width 0)
			(type solid)
		)
		(fill yes)
		(layer "In11.Cu")
		(net "M_L_CPU1_SA_DQ<24>")
	)
	(gr_poly
		(pts
			(xy 141.484858 -239.422432) (xy 141.484858 -239.377982) (xy 141.284706 -239.377982) (xy 141.284706 -239.422432)
			(xy 141.384782 -239.522508)
		)
		(stroke
			(width 0)
			(type solid)
		)
		(fill yes)
		(layer "In11.Cu")
		(net "M_L_CPU1_SA_DQ<23>")
	)
	(gr_poly
		(pts
			(xy 141.484858 -238.20628) (xy 141.384782 -238.106204) (xy 141.284706 -238.20628) (xy 141.284706 -238.25073)
			(xy 141.484858 -238.25073)
		)
		(stroke
			(width 0)
			(type solid)
		)
		(fill yes)
		(layer "In11.Cu")
		(net "M_L_CPU1_SA_DQ<20>")
	)
	(gr_poly
		(pts
			(xy 141.484858 -237.802674) (xy 141.484858 -237.754922) (xy 141.284706 -237.754922) (xy 141.284706 -237.802674)
			(xy 141.384782 -237.902496)
		)
		(stroke
			(width 0)
			(type solid)
		)
		(fill yes)
		(layer "In11.Cu")
		(net "M_L_CPU1_SA_DQS_DP<7>")
	)
	(gr_poly
		(pts
			(xy 141.484858 -236.586014) (xy 141.384782 -236.486192) (xy 141.284706 -236.586014) (xy 141.284706 -236.633766)
			(xy 141.484858 -236.633766)
		)
		(stroke
			(width 0)
			(type solid)
		)
		(fill yes)
		(layer "In11.Cu")
		(net "M_L_CPU1_SA_DQS_DP<2>")
	)
	(gr_poly
		(pts
			(xy 141.484858 -236.182408) (xy 141.484858 -236.137958) (xy 141.284706 -236.137958) (xy 141.284706 -236.182408)
			(xy 141.384782 -236.282484)
		)
		(stroke
			(width 0)
			(type solid)
		)
		(fill yes)
		(layer "In11.Cu")
		(net "M_L_CPU1_SA_DQ<19>")
	)
	(gr_poly
		(pts
			(xy 141.484858 -234.966256) (xy 141.384782 -234.86618) (xy 141.284706 -234.966256) (xy 141.284706 -235.010706)
			(xy 141.484858 -235.010706)
		)
		(stroke
			(width 0)
			(type solid)
		)
		(fill yes)
		(layer "In11.Cu")
		(net "M_L_CPU1_SA_DQ<16>")
	)
	(gr_poly
		(pts
			(xy 141.484858 -234.562396) (xy 141.484858 -234.517946) (xy 141.284706 -234.517946) (xy 141.284706 -234.562396)
			(xy 141.384782 -234.662472)
		)
		(stroke
			(width 0)
			(type solid)
		)
		(fill yes)
		(layer "In11.Cu")
		(net "M_L_CPU1_SA_DQ<15>")
	)
	(gr_poly
		(pts
			(xy 141.484858 -233.346244) (xy 141.384782 -233.246168) (xy 141.284706 -233.346244) (xy 141.284706 -233.390694)
			(xy 141.484858 -233.390694)
		)
		(stroke
			(width 0)
			(type solid)
		)
		(fill yes)
		(layer "In11.Cu")
		(net "M_L_CPU1_SA_DQ<12>")
	)
	(gr_poly
		(pts
			(xy 141.484858 -232.942638) (xy 141.484858 -232.894886) (xy 141.284706 -232.894886) (xy 141.284706 -232.942638)
			(xy 141.384782 -233.04246)
		)
		(stroke
			(width 0)
			(type solid)
		)
		(fill yes)
		(layer "In11.Cu")
		(net "M_L_CPU1_SA_DQS_DP<6>")
	)
	(gr_poly
		(pts
			(xy 141.484858 -231.725978) (xy 141.384782 -231.626156) (xy 141.284706 -231.725978) (xy 141.284706 -231.77373)
			(xy 141.484858 -231.77373)
		)
		(stroke
			(width 0)
			(type solid)
		)
		(fill yes)
		(layer "In11.Cu")
		(net "M_L_CPU1_SA_DQS_DP<1>")
	)
	(gr_poly
		(pts
			(xy 141.484858 -231.322626) (xy 141.484858 -231.278176) (xy 141.284706 -231.278176) (xy 141.284706 -231.322626)
			(xy 141.384782 -231.422702)
		)
		(stroke
			(width 0)
			(type solid)
		)
		(fill yes)
		(layer "In11.Cu")
		(net "M_L_CPU1_SA_DQ<11>")
	)
	(gr_poly
		(pts
			(xy 141.484858 -230.10622) (xy 141.384782 -230.006144) (xy 141.284706 -230.10622) (xy 141.284706 -230.15067)
			(xy 141.484858 -230.15067)
		)
		(stroke
			(width 0)
			(type solid)
		)
		(fill yes)
		(layer "In11.Cu")
		(net "M_L_CPU1_SA_DQ<8>")
	)
	(gr_poly
		(pts
			(xy 141.484858 -229.702614) (xy 141.484858 -229.658164) (xy 141.284706 -229.658164) (xy 141.284706 -229.702614)
			(xy 141.384782 -229.80269)
		)
		(stroke
			(width 0)
			(type solid)
		)
		(fill yes)
		(layer "In11.Cu")
		(net "M_L_CPU1_SA_DQ<7>")
	)
	(gr_poly
		(pts
			(xy 141.484858 -228.486462) (xy 141.384782 -228.386386) (xy 141.284706 -228.486462) (xy 141.284706 -228.530912)
			(xy 141.484858 -228.530912)
		)
		(stroke
			(width 0)
			(type solid)
		)
		(fill yes)
		(layer "In11.Cu")
		(net "M_L_CPU1_SA_DQ<4>")
	)
	(gr_poly
		(pts
			(xy 141.484858 -228.082856) (xy 141.484858 -228.035104) (xy 141.284706 -228.035104) (xy 141.284706 -228.082856)
			(xy 141.384782 -228.182678)
		)
		(stroke
			(width 0)
			(type solid)
		)
		(fill yes)
		(layer "In11.Cu")
		(net "M_L_CPU1_SA_DQS_DP<5>")
	)
	(gr_poly
		(pts
			(xy 141.484858 -226.866196) (xy 141.384782 -226.766374) (xy 141.284706 -226.866196) (xy 141.284706 -226.913948)
			(xy 141.484858 -226.913948)
		)
		(stroke
			(width 0)
			(type solid)
		)
		(fill yes)
		(layer "In11.Cu")
		(net "M_L_CPU1_SA_DQS_DP<0>")
	)
	(gr_poly
		(pts
			(xy 141.484858 -226.46259) (xy 141.484858 -226.41814) (xy 141.284706 -226.41814) (xy 141.284706 -226.46259)
			(xy 141.384782 -226.562666)
		)
		(stroke
			(width 0)
			(type solid)
		)
		(fill yes)
		(layer "In11.Cu")
		(net "M_L_CPU1_SA_DQ<3>")
	)
	(gr_poly
		(pts
			(xy 141.484858 -225.246438) (xy 141.384782 -225.146362) (xy 141.284706 -225.246438) (xy 141.284706 -225.290888)
			(xy 141.484858 -225.290888)
		)
		(stroke
			(width 0)
			(type solid)
		)
		(fill yes)
		(layer "In11.Cu")
		(net "M_L_CPU1_SA_DQ<0>")
	)
	(gr_poly
		(pts
			(xy 141.784832 -292.918134) (xy 141.684756 -292.818058) (xy 141.58468 -292.918134) (xy 141.58468 -292.962584)
			(xy 141.784832 -292.962584)
		)
		(stroke
			(width 0)
			(type solid)
		)
		(fill yes)
		(layer "In11.Cu")
		(net "M_L_CPU1_SB_DQ<29>")
	)
	(gr_poly
		(pts
			(xy 141.784832 -292.514274) (xy 141.784832 -292.469824) (xy 141.58468 -292.469824) (xy 141.58468 -292.514274)
			(xy 141.684756 -292.61435)
		)
		(stroke
			(width 0)
			(type solid)
		)
		(fill yes)
		(layer "In11.Cu")
		(net "M_L_CPU1_SB_DQ<30>")
	)
	(gr_poly
		(pts
			(xy 141.784832 -291.297868) (xy 141.684756 -291.198046) (xy 141.58468 -291.297868) (xy 141.58468 -291.34562)
			(xy 141.784832 -291.34562)
		)
		(stroke
			(width 0)
			(type solid)
		)
		(fill yes)
		(layer "In11.Cu")
		(net "M_L_CPU1_SB_DQS_DN<8>")
	)
	(gr_poly
		(pts
			(xy 141.784832 -290.894516) (xy 141.784832 -290.846764) (xy 141.58468 -290.846764) (xy 141.58468 -290.894516)
			(xy 141.684756 -290.994338)
		)
		(stroke
			(width 0)
			(type solid)
		)
		(fill yes)
		(layer "In11.Cu")
		(net "M_L_CPU1_SB_DQS_DN<3>")
	)
	(gr_poly
		(pts
			(xy 141.784832 -289.67811) (xy 141.684756 -289.578034) (xy 141.58468 -289.67811) (xy 141.58468 -289.72256)
			(xy 141.784832 -289.72256)
		)
		(stroke
			(width 0)
			(type solid)
		)
		(fill yes)
		(layer "In11.Cu")
		(net "M_L_CPU1_SB_DQ<25>")
	)
	(gr_poly
		(pts
			(xy 141.784832 -289.27425) (xy 141.784832 -289.2298) (xy 141.58468 -289.2298) (xy 141.58468 -289.27425)
			(xy 141.684756 -289.374326)
		)
		(stroke
			(width 0)
			(type solid)
		)
		(fill yes)
		(layer "In11.Cu")
		(net "M_L_CPU1_SB_DQ<26>")
	)
	(gr_poly
		(pts
			(xy 141.784832 -288.058098) (xy 141.684756 -287.958022) (xy 141.58468 -288.058098) (xy 141.58468 -288.102548)
			(xy 141.784832 -288.102548)
		)
		(stroke
			(width 0)
			(type solid)
		)
		(fill yes)
		(layer "In11.Cu")
		(net "M_L_CPU1_SB_DQ<21>")
	)
	(gr_poly
		(pts
			(xy 141.784832 -287.654492) (xy 141.784832 -287.610042) (xy 141.58468 -287.610042) (xy 141.58468 -287.654492)
			(xy 141.684756 -287.754568)
		)
		(stroke
			(width 0)
			(type solid)
		)
		(fill yes)
		(layer "In11.Cu")
		(net "M_L_CPU1_SB_DQ<22>")
	)
	(gr_poly
		(pts
			(xy 141.784832 -286.438086) (xy 141.684756 -286.33801) (xy 141.58468 -286.438086) (xy 141.58468 -286.485838)
			(xy 141.784832 -286.485838)
		)
		(stroke
			(width 0)
			(type solid)
		)
		(fill yes)
		(layer "In11.Cu")
		(net "M_L_CPU1_SB_DQS_DN<7>")
	)
	(gr_poly
		(pts
			(xy 141.784832 -286.034734) (xy 141.784832 -285.986982) (xy 141.58468 -285.986982) (xy 141.58468 -286.034734)
			(xy 141.684756 -286.134556)
		)
		(stroke
			(width 0)
			(type solid)
		)
		(fill yes)
		(layer "In11.Cu")
		(net "M_L_CPU1_SB_DQS_DN<2>")
	)
	(gr_poly
		(pts
			(xy 141.784832 -284.818328) (xy 141.684756 -284.718252) (xy 141.58468 -284.818328) (xy 141.58468 -284.862778)
			(xy 141.784832 -284.862778)
		)
		(stroke
			(width 0)
			(type solid)
		)
		(fill yes)
		(layer "In11.Cu")
		(net "M_L_CPU1_SB_DQ<17>")
	)
	(gr_poly
		(pts
			(xy 141.784832 -284.414468) (xy 141.784832 -284.370018) (xy 141.58468 -284.370018) (xy 141.58468 -284.414468)
			(xy 141.684756 -284.514544)
		)
		(stroke
			(width 0)
			(type solid)
		)
		(fill yes)
		(layer "In11.Cu")
		(net "M_L_CPU1_SB_DQ<18>")
	)
	(gr_poly
		(pts
			(xy 141.784832 -283.198316) (xy 141.684756 -283.09824) (xy 141.58468 -283.198316) (xy 141.58468 -283.242766)
			(xy 141.784832 -283.242766)
		)
		(stroke
			(width 0)
			(type solid)
		)
		(fill yes)
		(layer "In11.Cu")
		(net "M_L_CPU1_SB_DQ<13>")
	)
	(gr_poly
		(pts
			(xy 141.784832 -282.794456) (xy 141.784832 -282.750006) (xy 141.58468 -282.750006) (xy 141.58468 -282.794456)
			(xy 141.684756 -282.894532)
		)
		(stroke
			(width 0)
			(type solid)
		)
		(fill yes)
		(layer "In11.Cu")
		(net "M_L_CPU1_SB_DQ<14>")
	)
	(gr_poly
		(pts
			(xy 141.784832 -281.57805) (xy 141.684756 -281.478228) (xy 141.58468 -281.57805) (xy 141.58468 -281.625802)
			(xy 141.784832 -281.625802)
		)
		(stroke
			(width 0)
			(type solid)
		)
		(fill yes)
		(layer "In11.Cu")
		(net "M_L_CPU1_SB_DQS_DN<6>")
	)
	(gr_poly
		(pts
			(xy 141.784832 -281.174698) (xy 141.784832 -281.126946) (xy 141.58468 -281.126946) (xy 141.58468 -281.174698)
			(xy 141.684756 -281.27452)
		)
		(stroke
			(width 0)
			(type solid)
		)
		(fill yes)
		(layer "In11.Cu")
		(net "M_L_CPU1_SB_DQS_DN<1>")
	)
	(gr_poly
		(pts
			(xy 141.784832 -279.958292) (xy 141.684756 -279.858216) (xy 141.58468 -279.958292) (xy 141.58468 -280.002742)
			(xy 141.784832 -280.002742)
		)
		(stroke
			(width 0)
			(type solid)
		)
		(fill yes)
		(layer "In11.Cu")
		(net "M_L_CPU1_SB_DQ<9>")
	)
	(gr_poly
		(pts
			(xy 141.784832 -279.554432) (xy 141.784832 -279.509982) (xy 141.58468 -279.509982) (xy 141.58468 -279.554432)
			(xy 141.684756 -279.654508)
		)
		(stroke
			(width 0)
			(type solid)
		)
		(fill yes)
		(layer "In11.Cu")
		(net "M_L_CPU1_SB_DQ<10>")
	)
	(gr_poly
		(pts
			(xy 141.784832 -278.33828) (xy 141.684756 -278.238204) (xy 141.58468 -278.33828) (xy 141.58468 -278.38273)
			(xy 141.784832 -278.38273)
		)
		(stroke
			(width 0)
			(type solid)
		)
		(fill yes)
		(layer "In11.Cu")
		(net "M_L_CPU1_SB_DQ<5>")
	)
	(gr_poly
		(pts
			(xy 141.784832 -277.93442) (xy 141.784832 -277.88997) (xy 141.58468 -277.88997) (xy 141.58468 -277.93442)
			(xy 141.684756 -278.034496)
		)
		(stroke
			(width 0)
			(type solid)
		)
		(fill yes)
		(layer "In11.Cu")
		(net "M_L_CPU1_SB_DQ<6>")
	)
	(gr_poly
		(pts
			(xy 141.784832 -276.718014) (xy 141.684756 -276.618192) (xy 141.58468 -276.718014) (xy 141.58468 -276.765766)
			(xy 141.784832 -276.765766)
		)
		(stroke
			(width 0)
			(type solid)
		)
		(fill yes)
		(layer "In11.Cu")
		(net "M_L_CPU1_SB_DQS_DN<5>")
	)
	(gr_poly
		(pts
			(xy 141.784832 -276.314662) (xy 141.784832 -276.26691) (xy 141.58468 -276.26691) (xy 141.58468 -276.314662)
			(xy 141.684756 -276.414484)
		)
		(stroke
			(width 0)
			(type solid)
		)
		(fill yes)
		(layer "In11.Cu")
		(net "M_L_CPU1_SB_DQS_DN<0>")
	)
	(gr_poly
		(pts
			(xy 141.784832 -275.098256) (xy 141.684756 -274.99818) (xy 141.58468 -275.098256) (xy 141.58468 -275.142706)
			(xy 141.784832 -275.142706)
		)
		(stroke
			(width 0)
			(type solid)
		)
		(fill yes)
		(layer "In11.Cu")
		(net "M_L_CPU1_SB_DQ<1>")
	)
	(gr_poly
		(pts
			(xy 141.784832 -274.694396) (xy 141.784832 -274.649946) (xy 141.58468 -274.649946) (xy 141.58468 -274.694396)
			(xy 141.684756 -274.794472)
		)
		(stroke
			(width 0)
			(type solid)
		)
		(fill yes)
		(layer "In11.Cu")
		(net "M_L_CPU1_SB_DQ<2>")
	)
	(gr_poly
		(pts
			(xy 141.784832 -273.478244) (xy 141.684756 -273.378168) (xy 141.58468 -273.478244) (xy 141.58468 -273.522694)
			(xy 141.784832 -273.522694)
		)
		(stroke
			(width 0)
			(type solid)
		)
		(fill yes)
		(layer "In11.Cu")
		(net "M_L_CPU1_SB_CB<1>")
	)
	(gr_poly
		(pts
			(xy 141.784832 -273.074384) (xy 141.784832 -273.029934) (xy 141.58468 -273.029934) (xy 141.58468 -273.074384)
			(xy 141.684756 -273.17446)
		)
		(stroke
			(width 0)
			(type solid)
		)
		(fill yes)
		(layer "In11.Cu")
		(net "M_L_CPU1_SB_CB<2>")
	)
	(gr_poly
		(pts
			(xy 141.784832 -271.857978) (xy 141.684756 -271.758156) (xy 141.58468 -271.857978) (xy 141.58468 -271.90573)
			(xy 141.784832 -271.90573)
		)
		(stroke
			(width 0)
			(type solid)
		)
		(fill yes)
		(layer "In11.Cu")
		(net "M_L_CPU1_SB_DQS_DN<4>")
	)
	(gr_poly
		(pts
			(xy 141.784832 -271.454626) (xy 141.784832 -271.406874) (xy 141.58468 -271.406874) (xy 141.58468 -271.454626)
			(xy 141.684756 -271.554448)
		)
		(stroke
			(width 0)
			(type solid)
		)
		(fill yes)
		(layer "In11.Cu")
		(net "M_L_CPU1_SB_DQS_DN<9>")
	)
	(gr_poly
		(pts
			(xy 141.784832 -270.23822) (xy 141.684756 -270.138144) (xy 141.58468 -270.23822) (xy 141.58468 -270.28267)
			(xy 141.784832 -270.28267)
		)
		(stroke
			(width 0)
			(type solid)
		)
		(fill yes)
		(layer "In11.Cu")
		(net "M_L_CPU1_SB_CB<5>")
	)
	(gr_poly
		(pts
			(xy 141.784832 -269.83436) (xy 141.784832 -269.78991) (xy 141.58468 -269.78991) (xy 141.58468 -269.83436)
			(xy 141.684756 -269.934436)
		)
		(stroke
			(width 0)
			(type solid)
		)
		(fill yes)
		(layer "In11.Cu")
		(net "M_L_CPU1_SB_CB<6>")
	)
	(gr_poly
		(pts
			(xy 141.784832 -266.998196) (xy 141.684756 -266.89812) (xy 141.58468 -266.998196) (xy 141.58468 -267.042646)
			(xy 141.784832 -267.042646)
		)
		(stroke
			(width 0)
			(type solid)
		)
		(fill yes)
		(layer "In11.Cu")
		(net "M_L_CPU1_SA_RSP<0>")
	)
	(gr_poly
		(pts
			(xy 141.784832 -266.594336) (xy 141.784832 -266.549886) (xy 141.58468 -266.549886) (xy 141.58468 -266.594336)
			(xy 141.684756 -266.694412)
		)
		(stroke
			(width 0)
			(type solid)
		)
		(fill yes)
		(layer "In11.Cu")
		(net "M_L_CPU1_SB_CS_N<1>")
	)
	(gr_poly
		(pts
			(xy 141.784832 -265.378184) (xy 141.684756 -265.278108) (xy 141.58468 -265.378184) (xy 141.58468 -265.422634)
			(xy 141.784832 -265.422634)
		)
		(stroke
			(width 0)
			(type solid)
		)
		(fill yes)
		(layer "In11.Cu")
		(net "M_L_CPU1_SB_PAR")
	)
	(gr_poly
		(pts
			(xy 141.784832 -263.758172) (xy 141.684756 -263.658096) (xy 141.58468 -263.758172) (xy 141.58468 -263.802622)
			(xy 141.784832 -263.802622)
		)
		(stroke
			(width 0)
			(type solid)
		)
		(fill yes)
		(layer "In11.Cu")
		(net "M_L_CPU1_SB_CA<4>")
	)
	(gr_poly
		(pts
			(xy 141.784832 -263.354312) (xy 141.784832 -263.309862) (xy 141.58468 -263.309862) (xy 141.58468 -263.354312)
			(xy 141.684756 -263.454388)
		)
		(stroke
			(width 0)
			(type solid)
		)
		(fill yes)
		(layer "In11.Cu")
		(net "M_L_CPU1_SB_CA<3>")
	)
	(gr_poly
		(pts
			(xy 141.784832 -262.13816) (xy 141.684756 -262.038084) (xy 141.58468 -262.13816) (xy 141.58468 -262.18261)
			(xy 141.784832 -262.18261)
		)
		(stroke
			(width 0)
			(type solid)
		)
		(fill yes)
		(layer "In11.Cu")
		(net "M_L_CPU1_SB_CA<0>")
	)
	(gr_poly
		(pts
			(xy 141.954758 -256.432812) (xy 141.954758 -256.38506) (xy 141.754606 -256.38506) (xy 141.754606 -256.432812)
			(xy 141.854682 -256.532634)
		)
		(stroke
			(width 0)
			(type solid)
		)
		(fill yes)
		(layer "In11.Cu")
		(net "M_L_CPU1_CLK_DN<0>")
	)
	(gr_poly
		(pts
			(xy 141.954758 -255.216406) (xy 141.854682 -255.11633) (xy 141.754606 -255.216406) (xy 141.754606 -255.260856)
			(xy 141.954758 -255.260856)
		)
		(stroke
			(width 0)
			(type solid)
		)
		(fill yes)
		(layer "In11.Cu")
		(net "M_L_CPU1_SA_CA<6>")
	)
	(gr_poly
		(pts
			(xy 141.954758 -254.812546) (xy 141.954758 -254.768096) (xy 141.754606 -254.768096) (xy 141.754606 -254.812546)
			(xy 141.854682 -254.912622)
		)
		(stroke
			(width 0)
			(type solid)
		)
		(fill yes)
		(layer "In11.Cu")
		(net "M_L_CPU1_SA_CA<5>")
	)
	(gr_poly
		(pts
			(xy 141.954758 -253.596394) (xy 141.854682 -253.496318) (xy 141.754606 -253.596394) (xy 141.754606 -253.640844)
			(xy 141.954758 -253.640844)
		)
		(stroke
			(width 0)
			(type solid)
		)
		(fill yes)
		(layer "In11.Cu")
		(net "M_L_CPU1_SA_CA<2>")
	)
	(gr_poly
		(pts
			(xy 141.954758 -253.192534) (xy 141.954758 -253.148084) (xy 141.754606 -253.148084) (xy 141.754606 -253.192534)
			(xy 141.854682 -253.29261)
		)
		(stroke
			(width 0)
			(type solid)
		)
		(fill yes)
		(layer "In11.Cu")
		(net "M_L_CPU1_SA_CA<1>")
	)
	(gr_poly
		(pts
			(xy 141.954758 -250.35637) (xy 141.854682 -250.256294) (xy 141.754606 -250.35637) (xy 141.754606 -250.40082)
			(xy 141.954758 -250.40082)
		)
		(stroke
			(width 0)
			(type solid)
		)
		(fill yes)
		(layer "In11.Cu")
		(net "M_L_CPU1_ALERT_R_N")
	)
	(gr_poly
		(pts
			(xy 141.954758 -248.736358) (xy 141.854682 -248.636282) (xy 141.754606 -248.736358) (xy 141.754606 -248.780808)
			(xy 141.954758 -248.780808)
		)
		(stroke
			(width 0)
			(type solid)
		)
		(fill yes)
		(layer "In11.Cu")
		(net "M_L_CPU1_SA_CB<5>")
	)
	(gr_poly
		(pts
			(xy 141.954758 -248.332498) (xy 141.954758 -248.288048) (xy 141.754606 -248.288048) (xy 141.754606 -248.332498)
			(xy 141.854682 -248.432574)
		)
		(stroke
			(width 0)
			(type solid)
		)
		(fill yes)
		(layer "In11.Cu")
		(net "M_L_CPU1_SA_CB<6>")
	)
	(gr_poly
		(pts
			(xy 141.954758 -247.116092) (xy 141.854682 -247.01627) (xy 141.754606 -247.116092) (xy 141.754606 -247.163844)
			(xy 141.954758 -247.163844)
		)
		(stroke
			(width 0)
			(type solid)
		)
		(fill yes)
		(layer "In11.Cu")
		(net "M_L_CPU1_SA_DQS_DN<9>")
	)
	(gr_poly
		(pts
			(xy 141.954758 -246.71274) (xy 141.954758 -246.664988) (xy 141.754606 -246.664988) (xy 141.754606 -246.71274)
			(xy 141.854682 -246.812562)
		)
		(stroke
			(width 0)
			(type solid)
		)
		(fill yes)
		(layer "In11.Cu")
		(net "M_L_CPU1_SA_DQS_DN<4>")
	)
	(gr_poly
		(pts
			(xy 141.954758 -245.496334) (xy 141.854682 -245.396258) (xy 141.754606 -245.496334) (xy 141.754606 -245.540784)
			(xy 141.954758 -245.540784)
		)
		(stroke
			(width 0)
			(type solid)
		)
		(fill yes)
		(layer "In11.Cu")
		(net "M_L_CPU1_SA_CB<1>")
	)
	(gr_poly
		(pts
			(xy 141.954758 -245.092474) (xy 141.954758 -245.048024) (xy 141.754606 -245.048024) (xy 141.754606 -245.092474)
			(xy 141.854682 -245.19255)
		)
		(stroke
			(width 0)
			(type solid)
		)
		(fill yes)
		(layer "In11.Cu")
		(net "M_L_CPU1_SA_CB<2>")
	)
	(gr_poly
		(pts
			(xy 141.954758 -243.876322) (xy 141.854682 -243.776246) (xy 141.754606 -243.876322) (xy 141.754606 -243.920772)
			(xy 141.954758 -243.920772)
		)
		(stroke
			(width 0)
			(type solid)
		)
		(fill yes)
		(layer "In11.Cu")
		(net "M_L_CPU1_SA_DQ<29>")
	)
	(gr_poly
		(pts
			(xy 141.954758 -243.472462) (xy 141.954758 -243.428012) (xy 141.754606 -243.428012) (xy 141.754606 -243.472462)
			(xy 141.854682 -243.572538)
		)
		(stroke
			(width 0)
			(type solid)
		)
		(fill yes)
		(layer "In11.Cu")
		(net "M_L_CPU1_SA_DQ<30>")
	)
	(gr_poly
		(pts
			(xy 141.954758 -242.256056) (xy 141.854682 -242.156234) (xy 141.754606 -242.256056) (xy 141.754606 -242.303808)
			(xy 141.954758 -242.303808)
		)
		(stroke
			(width 0)
			(type solid)
		)
		(fill yes)
		(layer "In11.Cu")
		(net "M_L_CPU1_SA_DQS_DN<8>")
	)
	(gr_poly
		(pts
			(xy 141.954758 -241.852704) (xy 141.954758 -241.804952) (xy 141.754606 -241.804952) (xy 141.754606 -241.852704)
			(xy 141.854682 -241.952526)
		)
		(stroke
			(width 0)
			(type solid)
		)
		(fill yes)
		(layer "In11.Cu")
		(net "M_L_CPU1_SA_DQS_DN<3>")
	)
	(gr_poly
		(pts
			(xy 141.954758 -240.636298) (xy 141.854682 -240.536222) (xy 141.754606 -240.636298) (xy 141.754606 -240.680748)
			(xy 141.954758 -240.680748)
		)
		(stroke
			(width 0)
			(type solid)
		)
		(fill yes)
		(layer "In11.Cu")
		(net "M_L_CPU1_SA_DQ<25>")
	)
	(gr_poly
		(pts
			(xy 141.954758 -240.232438) (xy 141.954758 -240.187988) (xy 141.754606 -240.187988) (xy 141.754606 -240.232438)
			(xy 141.854682 -240.332514)
		)
		(stroke
			(width 0)
			(type solid)
		)
		(fill yes)
		(layer "In11.Cu")
		(net "M_L_CPU1_SA_DQ<26>")
	)
	(gr_poly
		(pts
			(xy 141.954758 -239.016286) (xy 141.854682 -238.91621) (xy 141.754606 -239.016286) (xy 141.754606 -239.060736)
			(xy 141.954758 -239.060736)
		)
		(stroke
			(width 0)
			(type solid)
		)
		(fill yes)
		(layer "In11.Cu")
		(net "M_L_CPU1_SA_DQ<21>")
	)
	(gr_poly
		(pts
			(xy 141.954758 -238.612426) (xy 141.954758 -238.567976) (xy 141.754606 -238.567976) (xy 141.754606 -238.612426)
			(xy 141.854682 -238.712502)
		)
		(stroke
			(width 0)
			(type solid)
		)
		(fill yes)
		(layer "In11.Cu")
		(net "M_L_CPU1_SA_DQ<22>")
	)
	(gr_poly
		(pts
			(xy 141.954758 -237.39602) (xy 141.854682 -237.296198) (xy 141.754606 -237.39602) (xy 141.754606 -237.443772)
			(xy 141.954758 -237.443772)
		)
		(stroke
			(width 0)
			(type solid)
		)
		(fill yes)
		(layer "In11.Cu")
		(net "M_L_CPU1_SA_DQS_DN<7>")
	)
	(gr_poly
		(pts
			(xy 141.954758 -236.992668) (xy 141.954758 -236.944916) (xy 141.754606 -236.944916) (xy 141.754606 -236.992668)
			(xy 141.854682 -237.09249)
		)
		(stroke
			(width 0)
			(type solid)
		)
		(fill yes)
		(layer "In11.Cu")
		(net "M_L_CPU1_SA_DQS_DN<2>")
	)
	(gr_poly
		(pts
			(xy 141.954758 -235.776262) (xy 141.854682 -235.676186) (xy 141.754606 -235.776262) (xy 141.754606 -235.820712)
			(xy 141.954758 -235.820712)
		)
		(stroke
			(width 0)
			(type solid)
		)
		(fill yes)
		(layer "In11.Cu")
		(net "M_L_CPU1_SA_DQ<17>")
	)
	(gr_poly
		(pts
			(xy 141.954758 -235.372402) (xy 141.954758 -235.327952) (xy 141.754606 -235.327952) (xy 141.754606 -235.372402)
			(xy 141.854682 -235.472478)
		)
		(stroke
			(width 0)
			(type solid)
		)
		(fill yes)
		(layer "In11.Cu")
		(net "M_L_CPU1_SA_DQ<18>")
	)
	(gr_poly
		(pts
			(xy 141.954758 -234.15625) (xy 141.854682 -234.056174) (xy 141.754606 -234.15625) (xy 141.754606 -234.2007)
			(xy 141.954758 -234.2007)
		)
		(stroke
			(width 0)
			(type solid)
		)
		(fill yes)
		(layer "In11.Cu")
		(net "M_L_CPU1_SA_DQ<13>")
	)
	(gr_poly
		(pts
			(xy 141.954758 -233.75239) (xy 141.954758 -233.70794) (xy 141.754606 -233.70794) (xy 141.754606 -233.75239)
			(xy 141.854682 -233.852466)
		)
		(stroke
			(width 0)
			(type solid)
		)
		(fill yes)
		(layer "In11.Cu")
		(net "M_L_CPU1_SA_DQ<14>")
	)
	(gr_poly
		(pts
			(xy 141.954758 -232.535984) (xy 141.854682 -232.436162) (xy 141.754606 -232.535984) (xy 141.754606 -232.583736)
			(xy 141.954758 -232.583736)
		)
		(stroke
			(width 0)
			(type solid)
		)
		(fill yes)
		(layer "In11.Cu")
		(net "M_L_CPU1_SA_DQS_DN<6>")
	)
	(gr_poly
		(pts
			(xy 141.954758 -232.132632) (xy 141.954758 -232.08488) (xy 141.754606 -232.08488) (xy 141.754606 -232.132632)
			(xy 141.854682 -232.232454)
		)
		(stroke
			(width 0)
			(type solid)
		)
		(fill yes)
		(layer "In11.Cu")
		(net "M_L_CPU1_SA_DQS_DN<1>")
	)
	(gr_poly
		(pts
			(xy 141.954758 -230.916226) (xy 141.854682 -230.81615) (xy 141.754606 -230.916226) (xy 141.754606 -230.960676)
			(xy 141.954758 -230.960676)
		)
		(stroke
			(width 0)
			(type solid)
		)
		(fill yes)
		(layer "In11.Cu")
		(net "M_L_CPU1_SA_DQ<9>")
	)
	(gr_poly
		(pts
			(xy 141.954758 -230.51262) (xy 141.954758 -230.46817) (xy 141.754606 -230.46817) (xy 141.754606 -230.51262)
			(xy 141.854682 -230.612696)
		)
		(stroke
			(width 0)
			(type solid)
		)
		(fill yes)
		(layer "In11.Cu")
		(net "M_L_CPU1_SA_DQ<10>")
	)
	(gr_poly
		(pts
			(xy 141.954758 -229.296214) (xy 141.854682 -229.196138) (xy 141.754606 -229.296214) (xy 141.754606 -229.340664)
			(xy 141.954758 -229.340664)
		)
		(stroke
			(width 0)
			(type solid)
		)
		(fill yes)
		(layer "In11.Cu")
		(net "M_L_CPU1_SA_DQ<5>")
	)
	(gr_poly
		(pts
			(xy 141.954758 -228.892608) (xy 141.954758 -228.848158) (xy 141.754606 -228.848158) (xy 141.754606 -228.892608)
			(xy 141.854682 -228.992684)
		)
		(stroke
			(width 0)
			(type solid)
		)
		(fill yes)
		(layer "In11.Cu")
		(net "M_L_CPU1_SA_DQ<6>")
	)
	(gr_poly
		(pts
			(xy 141.954758 -227.676202) (xy 141.854682 -227.57638) (xy 141.754606 -227.676202) (xy 141.754606 -227.723954)
			(xy 141.954758 -227.723954)
		)
		(stroke
			(width 0)
			(type solid)
		)
		(fill yes)
		(layer "In11.Cu")
		(net "M_L_CPU1_SA_DQS_DN<5>")
	)
	(gr_poly
		(pts
			(xy 141.954758 -227.27285) (xy 141.954758 -227.225098) (xy 141.754606 -227.225098) (xy 141.754606 -227.27285)
			(xy 141.854682 -227.372672)
		)
		(stroke
			(width 0)
			(type solid)
		)
		(fill yes)
		(layer "In11.Cu")
		(net "M_L_CPU1_SA_DQS_DN<0>")
	)
	(gr_poly
		(pts
			(xy 141.954758 -226.056444) (xy 141.854682 -225.956368) (xy 141.754606 -226.056444) (xy 141.754606 -226.100894)
			(xy 141.954758 -226.100894)
		)
		(stroke
			(width 0)
			(type solid)
		)
		(fill yes)
		(layer "In11.Cu")
		(net "M_L_CPU1_SA_DQ<1>")
	)
	(gr_poly
		(pts
			(xy 141.954758 -225.652584) (xy 141.954758 -225.608134) (xy 141.754606 -225.608134) (xy 141.754606 -225.652584)
			(xy 141.854682 -225.75266)
		)
		(stroke
			(width 0)
			(type solid)
		)
		(fill yes)
		(layer "In11.Cu")
		(net "M_L_CPU1_SA_DQ<2>")
	)
	(gr_poly
		(pts
			(xy 141.960854 -251.970032) (xy 141.861032 -251.869956) (xy 141.760956 -251.970032) (xy 141.760956 -252.014482)
			(xy 141.960854 -252.014482)
		)
		(stroke
			(width 0)
			(type solid)
		)
		(fill yes)
		(layer "In11.Cu")
		(net "M_L_CPU1_SA_CS_N<1>")
	)
	(gr_poly
		(pts
			(xy 142.254732 -293.32428) (xy 142.254732 -293.27983) (xy 142.05458 -293.27983) (xy 142.05458 -293.32428)
			(xy 142.154656 -293.424356)
		)
		(stroke
			(width 0)
			(type solid)
		)
		(fill yes)
		(layer "In11.Cu")
		(net "M_L_CPU1_SB_DQ<31>")
	)
	(gr_poly
		(pts
			(xy 142.254732 -292.108128) (xy 142.154656 -292.008052) (xy 142.05458 -292.108128) (xy 142.05458 -292.152578)
			(xy 142.254732 -292.152578)
		)
		(stroke
			(width 0)
			(type solid)
		)
		(fill yes)
		(layer "In11.Cu")
		(net "M_L_CPU1_SB_DQ<28>")
	)
	(gr_poly
		(pts
			(xy 142.254732 -291.704522) (xy 142.254732 -291.65677) (xy 142.05458 -291.65677) (xy 142.05458 -291.704522)
			(xy 142.154656 -291.804344)
		)
		(stroke
			(width 0)
			(type solid)
		)
		(fill yes)
		(layer "In11.Cu")
		(net "M_L_CPU1_SB_DQS_DP<8>")
	)
	(gr_poly
		(pts
			(xy 142.254732 -290.487862) (xy 142.154656 -290.38804) (xy 142.05458 -290.487862) (xy 142.05458 -290.535614)
			(xy 142.254732 -290.535614)
		)
		(stroke
			(width 0)
			(type solid)
		)
		(fill yes)
		(layer "In11.Cu")
		(net "M_L_CPU1_SB_DQS_DP<3>")
	)
	(gr_poly
		(pts
			(xy 142.254732 -290.084256) (xy 142.254732 -290.039806) (xy 142.05458 -290.039806) (xy 142.05458 -290.084256)
			(xy 142.154656 -290.184332)
		)
		(stroke
			(width 0)
			(type solid)
		)
		(fill yes)
		(layer "In11.Cu")
		(net "M_L_CPU1_SB_DQ<27>")
	)
	(gr_poly
		(pts
			(xy 142.254732 -288.868104) (xy 142.154656 -288.768028) (xy 142.05458 -288.868104) (xy 142.05458 -288.912554)
			(xy 142.254732 -288.912554)
		)
		(stroke
			(width 0)
			(type solid)
		)
		(fill yes)
		(layer "In11.Cu")
		(net "M_L_CPU1_SB_DQ<24>")
	)
	(gr_poly
		(pts
			(xy 142.254732 -288.464498) (xy 142.254732 -288.420048) (xy 142.05458 -288.420048) (xy 142.05458 -288.464498)
			(xy 142.154656 -288.564574)
		)
		(stroke
			(width 0)
			(type solid)
		)
		(fill yes)
		(layer "In11.Cu")
		(net "M_L_CPU1_SB_DQ<23>")
	)
	(gr_poly
		(pts
			(xy 142.254732 -287.248092) (xy 142.154656 -287.148016) (xy 142.05458 -287.248092) (xy 142.05458 -287.292542)
			(xy 142.254732 -287.292542)
		)
		(stroke
			(width 0)
			(type solid)
		)
		(fill yes)
		(layer "In11.Cu")
		(net "M_L_CPU1_SB_DQ<20>")
	)
	(gr_poly
		(pts
			(xy 142.254732 -286.844486) (xy 142.254732 -286.796734) (xy 142.05458 -286.796734) (xy 142.05458 -286.844486)
			(xy 142.154656 -286.944562)
		)
		(stroke
			(width 0)
			(type solid)
		)
		(fill yes)
		(layer "In11.Cu")
		(net "M_L_CPU1_SB_DQS_DP<7>")
	)
	(gr_poly
		(pts
			(xy 142.254732 -285.62808) (xy 142.154656 -285.528258) (xy 142.05458 -285.62808) (xy 142.05458 -285.675832)
			(xy 142.254732 -285.675832)
		)
		(stroke
			(width 0)
			(type solid)
		)
		(fill yes)
		(layer "In11.Cu")
		(net "M_L_CPU1_SB_DQS_DP<2>")
	)
	(gr_poly
		(pts
			(xy 142.254732 -285.224474) (xy 142.254732 -285.180024) (xy 142.05458 -285.180024) (xy 142.05458 -285.224474)
			(xy 142.154656 -285.32455)
		)
		(stroke
			(width 0)
			(type solid)
		)
		(fill yes)
		(layer "In11.Cu")
		(net "M_L_CPU1_SB_DQ<19>")
	)
	(gr_poly
		(pts
			(xy 142.254732 -284.008322) (xy 142.154656 -283.908246) (xy 142.05458 -284.008322) (xy 142.05458 -284.052772)
			(xy 142.254732 -284.052772)
		)
		(stroke
			(width 0)
			(type solid)
		)
		(fill yes)
		(layer "In11.Cu")
		(net "M_L_CPU1_SB_DQ<16>")
	)
	(gr_poly
		(pts
			(xy 142.254732 -283.604462) (xy 142.254732 -283.560012) (xy 142.05458 -283.560012) (xy 142.05458 -283.604462)
			(xy 142.154656 -283.704538)
		)
		(stroke
			(width 0)
			(type solid)
		)
		(fill yes)
		(layer "In11.Cu")
		(net "M_L_CPU1_SB_DQ<15>")
	)
	(gr_poly
		(pts
			(xy 142.254732 -282.38831) (xy 142.154656 -282.288234) (xy 142.05458 -282.38831) (xy 142.05458 -282.43276)
			(xy 142.254732 -282.43276)
		)
		(stroke
			(width 0)
			(type solid)
		)
		(fill yes)
		(layer "In11.Cu")
		(net "M_L_CPU1_SB_DQ<12>")
	)
	(gr_poly
		(pts
			(xy 142.254732 -281.984704) (xy 142.254732 -281.936952) (xy 142.05458 -281.936952) (xy 142.05458 -281.984704)
			(xy 142.154656 -282.084526)
		)
		(stroke
			(width 0)
			(type solid)
		)
		(fill yes)
		(layer "In11.Cu")
		(net "M_L_CPU1_SB_DQS_DP<6>")
	)
	(gr_poly
		(pts
			(xy 142.254732 -280.768044) (xy 142.154656 -280.668222) (xy 142.05458 -280.768044) (xy 142.05458 -280.815796)
			(xy 142.254732 -280.815796)
		)
		(stroke
			(width 0)
			(type solid)
		)
		(fill yes)
		(layer "In11.Cu")
		(net "M_L_CPU1_SB_DQS_DP<1>")
	)
	(gr_poly
		(pts
			(xy 142.254732 -280.364438) (xy 142.254732 -280.319988) (xy 142.05458 -280.319988) (xy 142.05458 -280.364438)
			(xy 142.154656 -280.464514)
		)
		(stroke
			(width 0)
			(type solid)
		)
		(fill yes)
		(layer "In11.Cu")
		(net "M_L_CPU1_SB_DQ<11>")
	)
	(gr_poly
		(pts
			(xy 142.254732 -279.148286) (xy 142.154656 -279.04821) (xy 142.05458 -279.148286) (xy 142.05458 -279.192736)
			(xy 142.254732 -279.192736)
		)
		(stroke
			(width 0)
			(type solid)
		)
		(fill yes)
		(layer "In11.Cu")
		(net "M_L_CPU1_SB_DQ<8>")
	)
	(gr_poly
		(pts
			(xy 142.254732 -278.744426) (xy 142.254732 -278.699976) (xy 142.05458 -278.699976) (xy 142.05458 -278.744426)
			(xy 142.154656 -278.844502)
		)
		(stroke
			(width 0)
			(type solid)
		)
		(fill yes)
		(layer "In11.Cu")
		(net "M_L_CPU1_SB_DQ<7>")
	)
	(gr_poly
		(pts
			(xy 142.254732 -277.528274) (xy 142.154656 -277.428198) (xy 142.05458 -277.528274) (xy 142.05458 -277.572724)
			(xy 142.254732 -277.572724)
		)
		(stroke
			(width 0)
			(type solid)
		)
		(fill yes)
		(layer "In11.Cu")
		(net "M_L_CPU1_SB_DQ<4>")
	)
	(gr_poly
		(pts
			(xy 142.254732 -277.124668) (xy 142.254732 -277.076916) (xy 142.05458 -277.076916) (xy 142.05458 -277.124668)
			(xy 142.154656 -277.22449)
		)
		(stroke
			(width 0)
			(type solid)
		)
		(fill yes)
		(layer "In11.Cu")
		(net "M_L_CPU1_SB_DQS_DP<5>")
	)
	(gr_poly
		(pts
			(xy 142.254732 -275.908008) (xy 142.154656 -275.808186) (xy 142.05458 -275.908008) (xy 142.05458 -275.95576)
			(xy 142.254732 -275.95576)
		)
		(stroke
			(width 0)
			(type solid)
		)
		(fill yes)
		(layer "In11.Cu")
		(net "M_L_CPU1_SB_DQS_DP<0>")
	)
	(gr_poly
		(pts
			(xy 142.254732 -275.504402) (xy 142.254732 -275.459952) (xy 142.05458 -275.459952) (xy 142.05458 -275.504402)
			(xy 142.154656 -275.604478)
		)
		(stroke
			(width 0)
			(type solid)
		)
		(fill yes)
		(layer "In11.Cu")
		(net "M_L_CPU1_SB_DQ<3>")
	)
	(gr_poly
		(pts
			(xy 142.254732 -274.28825) (xy 142.154656 -274.188174) (xy 142.05458 -274.28825) (xy 142.05458 -274.3327)
			(xy 142.254732 -274.3327)
		)
		(stroke
			(width 0)
			(type solid)
		)
		(fill yes)
		(layer "In11.Cu")
		(net "M_L_CPU1_SB_DQ<0>")
	)
	(gr_poly
		(pts
			(xy 142.254732 -273.88439) (xy 142.254732 -273.83994) (xy 142.05458 -273.83994) (xy 142.05458 -273.88439)
			(xy 142.154656 -273.984466)
		)
		(stroke
			(width 0)
			(type solid)
		)
		(fill yes)
		(layer "In11.Cu")
		(net "M_L_CPU1_SB_CB<3>")
	)
	(gr_poly
		(pts
			(xy 142.254732 -272.668238) (xy 142.154656 -272.568162) (xy 142.05458 -272.668238) (xy 142.05458 -272.712688)
			(xy 142.254732 -272.712688)
		)
		(stroke
			(width 0)
			(type solid)
		)
		(fill yes)
		(layer "In11.Cu")
		(net "M_L_CPU1_SB_CB<0>")
	)
	(gr_poly
		(pts
			(xy 142.254732 -272.264632) (xy 142.254732 -272.21688) (xy 142.05458 -272.21688) (xy 142.05458 -272.264632)
			(xy 142.154656 -272.364454)
		)
		(stroke
			(width 0)
			(type solid)
		)
		(fill yes)
		(layer "In11.Cu")
		(net "M_L_CPU1_SB_DQS_DP<4>")
	)
	(gr_poly
		(pts
			(xy 142.254732 -271.047972) (xy 142.154656 -270.94815) (xy 142.05458 -271.047972) (xy 142.05458 -271.095724)
			(xy 142.254732 -271.095724)
		)
		(stroke
			(width 0)
			(type solid)
		)
		(fill yes)
		(layer "In11.Cu")
		(net "M_L_CPU1_SB_DQS_DP<9>")
	)
	(gr_poly
		(pts
			(xy 142.254732 -270.644366) (xy 142.254732 -270.599916) (xy 142.05458 -270.599916) (xy 142.05458 -270.644366)
			(xy 142.154656 -270.744442)
		)
		(stroke
			(width 0)
			(type solid)
		)
		(fill yes)
		(layer "In11.Cu")
		(net "M_L_CPU1_SB_CB<7>")
	)
	(gr_poly
		(pts
			(xy 142.254732 -269.428214) (xy 142.154656 -269.328138) (xy 142.05458 -269.428214) (xy 142.05458 -269.472664)
			(xy 142.254732 -269.472664)
		)
		(stroke
			(width 0)
			(type solid)
		)
		(fill yes)
		(layer "In11.Cu")
		(net "M_L_CPU1_SB_CB<4>")
	)
	(gr_poly
		(pts
			(xy 142.254732 -267.808202) (xy 142.154656 -267.708126) (xy 142.05458 -267.808202) (xy 142.05458 -267.852652)
			(xy 142.254732 -267.852652)
		)
		(stroke
			(width 0)
			(type solid)
		)
		(fill yes)
		(layer "In11.Cu")
		(net "M_L_CPU1_SB_RSP<0>")
	)
	(gr_poly
		(pts
			(xy 142.254732 -265.78433) (xy 142.254732 -265.73988) (xy 142.05458 -265.73988) (xy 142.05458 -265.78433)
			(xy 142.154656 -265.884406)
		)
		(stroke
			(width 0)
			(type solid)
		)
		(fill yes)
		(layer "In11.Cu")
		(net "M_L_CPU1_SB_CS_N<0>")
	)
	(gr_poly
		(pts
			(xy 142.254732 -264.164318) (xy 142.254732 -264.119868) (xy 142.05458 -264.119868) (xy 142.05458 -264.164318)
			(xy 142.154656 -264.264394)
		)
		(stroke
			(width 0)
			(type solid)
		)
		(fill yes)
		(layer "In11.Cu")
		(net "M_L_CPU1_SB_CA<5>")
	)
	(gr_poly
		(pts
			(xy 142.254732 -262.948166) (xy 142.154656 -262.84809) (xy 142.05458 -262.948166) (xy 142.05458 -262.992616)
			(xy 142.254732 -262.992616)
		)
		(stroke
			(width 0)
			(type solid)
		)
		(fill yes)
		(layer "In11.Cu")
		(net "M_L_CPU1_SB_CA<2>")
	)
	(gr_poly
		(pts
			(xy 142.254732 -262.544306) (xy 142.254732 -262.499856) (xy 142.05458 -262.499856) (xy 142.05458 -262.544306)
			(xy 142.154656 -262.644382)
		)
		(stroke
			(width 0)
			(type solid)
		)
		(fill yes)
		(layer "In11.Cu")
		(net "M_L_CPU1_SB_CA<1>")
	)
	(gr_poly
		(pts
			(xy 142.260828 -264.561828) (xy 142.161006 -264.461752) (xy 142.06093 -264.561828) (xy 142.06093 -264.606278)
			(xy 142.260828 -264.606278)
		)
		(stroke
			(width 0)
			(type solid)
		)
		(fill yes)
		(layer "In11.Cu")
		(net "M_L_CPU1_SB_CA<6>")
	)
	(gr_poly
		(pts
			(xy 142.343886 -224.695766) (xy 142.305278 -224.673414) (xy 142.168626 -224.70999) (xy 142.205456 -224.846642)
			(xy 142.24381 -224.868994)
		)
		(stroke
			(width 0)
			(type solid)
		)
		(fill yes)
		(layer "In11.Cu")
		(net "M_L_CPU1_SA_DQ<0>")
	)
	(gr_poly
		(pts
			(xy 142.418562 -251.160026) (xy 142.318486 -251.05995) (xy 142.218664 -251.160026) (xy 142.218664 -251.204476)
			(xy 142.418562 -251.204476)
		)
		(stroke
			(width 0)
			(type solid)
		)
		(fill yes)
		(layer "In11.Cu")
		(net "M_L_CPU1_SA_CS_N<0>")
	)
	(gr_poly
		(pts
			(xy 142.424912 -256.026158) (xy 142.324836 -255.926336) (xy 142.22476 -256.026158) (xy 142.22476 -256.07391)
			(xy 142.424912 -256.07391)
		)
		(stroke
			(width 0)
			(type solid)
		)
		(fill yes)
		(layer "In11.Cu")
		(net "M_L_CPU1_CLK_DP<0>")
	)
	(gr_poly
		(pts
			(xy 142.424912 -255.622552) (xy 142.424912 -255.578102) (xy 142.22476 -255.578102) (xy 142.22476 -255.622552)
			(xy 142.324836 -255.722628)
		)
		(stroke
			(width 0)
			(type solid)
		)
		(fill yes)
		(layer "In11.Cu")
		(net "M_L_CPU1_SA_PAR")
	)
	(gr_poly
		(pts
			(xy 142.424912 -254.4064) (xy 142.324836 -254.306324) (xy 142.22476 -254.4064) (xy 142.22476 -254.45085)
			(xy 142.424912 -254.45085)
		)
		(stroke
			(width 0)
			(type solid)
		)
		(fill yes)
		(layer "In11.Cu")
		(net "M_L_CPU1_SA_CA<4>")
	)
	(gr_poly
		(pts
			(xy 142.424912 -254.00254) (xy 142.424912 -253.95809) (xy 142.22476 -253.95809) (xy 142.22476 -254.00254)
			(xy 142.324836 -254.102616)
		)
		(stroke
			(width 0)
			(type solid)
		)
		(fill yes)
		(layer "In11.Cu")
		(net "M_L_CPU1_SA_CA<3>")
	)
	(gr_poly
		(pts
			(xy 142.424912 -252.786388) (xy 142.324836 -252.686312) (xy 142.22476 -252.786388) (xy 142.22476 -252.830838)
			(xy 142.424912 -252.830838)
		)
		(stroke
			(width 0)
			(type solid)
		)
		(fill yes)
		(layer "In11.Cu")
		(net "M_L_CPU1_SA_CA<0>")
	)
	(gr_poly
		(pts
			(xy 142.424912 -250.762516) (xy 142.424912 -250.718066) (xy 142.22476 -250.718066) (xy 142.22476 -250.762516)
			(xy 142.324836 -250.862592)
		)
		(stroke
			(width 0)
			(type solid)
		)
		(fill yes)
		(layer "In11.Cu")
		(net "M_L_CPU1_RESET_N")
	)
	(gr_poly
		(pts
			(xy 142.424912 -249.142504) (xy 142.424912 -249.098054) (xy 142.22476 -249.098054) (xy 142.22476 -249.142504)
			(xy 142.324836 -249.24258)
		)
		(stroke
			(width 0)
			(type solid)
		)
		(fill yes)
		(layer "In11.Cu")
		(net "M_L_CPU1_SA_CB<7>")
	)
	(gr_poly
		(pts
			(xy 142.424912 -247.926352) (xy 142.324836 -247.826276) (xy 142.22476 -247.926352) (xy 142.22476 -247.970802)
			(xy 142.424912 -247.970802)
		)
		(stroke
			(width 0)
			(type solid)
		)
		(fill yes)
		(layer "In11.Cu")
		(net "M_L_CPU1_SA_CB<4>")
	)
	(gr_poly
		(pts
			(xy 142.424912 -247.522746) (xy 142.424912 -247.474994) (xy 142.22476 -247.474994) (xy 142.22476 -247.522746)
			(xy 142.324836 -247.622568)
		)
		(stroke
			(width 0)
			(type solid)
		)
		(fill yes)
		(layer "In11.Cu")
		(net "M_L_CPU1_SA_DQS_DP<9>")
	)
	(gr_poly
		(pts
			(xy 142.424912 -246.306086) (xy 142.324836 -246.206264) (xy 142.22476 -246.306086) (xy 142.22476 -246.353838)
			(xy 142.424912 -246.353838)
		)
		(stroke
			(width 0)
			(type solid)
		)
		(fill yes)
		(layer "In11.Cu")
		(net "M_L_CPU1_SA_DQS_DP<4>")
	)
	(gr_poly
		(pts
			(xy 142.424912 -245.90248) (xy 142.424912 -245.85803) (xy 142.22476 -245.85803) (xy 142.22476 -245.90248)
			(xy 142.324836 -246.002556)
		)
		(stroke
			(width 0)
			(type solid)
		)
		(fill yes)
		(layer "In11.Cu")
		(net "M_L_CPU1_SA_CB<3>")
	)
	(gr_poly
		(pts
			(xy 142.424912 -244.686328) (xy 142.324836 -244.586252) (xy 142.22476 -244.686328) (xy 142.22476 -244.730778)
			(xy 142.424912 -244.730778)
		)
		(stroke
			(width 0)
			(type solid)
		)
		(fill yes)
		(layer "In11.Cu")
		(net "M_L_CPU1_SA_CB<0>")
	)
	(gr_poly
		(pts
			(xy 142.424912 -244.282468) (xy 142.424912 -244.238018) (xy 142.22476 -244.238018) (xy 142.22476 -244.282468)
			(xy 142.324836 -244.382544)
		)
		(stroke
			(width 0)
			(type solid)
		)
		(fill yes)
		(layer "In11.Cu")
		(net "M_L_CPU1_SA_DQ<31>")
	)
	(gr_poly
		(pts
			(xy 142.424912 -243.066316) (xy 142.324836 -242.96624) (xy 142.22476 -243.066316) (xy 142.22476 -243.110766)
			(xy 142.424912 -243.110766)
		)
		(stroke
			(width 0)
			(type solid)
		)
		(fill yes)
		(layer "In11.Cu")
		(net "M_L_CPU1_SA_DQ<28>")
	)
	(gr_poly
		(pts
			(xy 142.424912 -242.66271) (xy 142.424912 -242.614958) (xy 142.22476 -242.614958) (xy 142.22476 -242.66271)
			(xy 142.324836 -242.762532)
		)
		(stroke
			(width 0)
			(type solid)
		)
		(fill yes)
		(layer "In11.Cu")
		(net "M_L_CPU1_SA_DQS_DP<8>")
	)
	(gr_poly
		(pts
			(xy 142.424912 -241.44605) (xy 142.324836 -241.346228) (xy 142.22476 -241.44605) (xy 142.22476 -241.493802)
			(xy 142.424912 -241.493802)
		)
		(stroke
			(width 0)
			(type solid)
		)
		(fill yes)
		(layer "In11.Cu")
		(net "M_L_CPU1_SA_DQS_DP<3>")
	)
	(gr_poly
		(pts
			(xy 142.424912 -241.042444) (xy 142.424912 -240.997994) (xy 142.22476 -240.997994) (xy 142.22476 -241.042444)
			(xy 142.324836 -241.14252)
		)
		(stroke
			(width 0)
			(type solid)
		)
		(fill yes)
		(layer "In11.Cu")
		(net "M_L_CPU1_SA_DQ<27>")
	)
	(gr_poly
		(pts
			(xy 142.424912 -239.826292) (xy 142.324836 -239.726216) (xy 142.22476 -239.826292) (xy 142.22476 -239.870742)
			(xy 142.424912 -239.870742)
		)
		(stroke
			(width 0)
			(type solid)
		)
		(fill yes)
		(layer "In11.Cu")
		(net "M_L_CPU1_SA_DQ<24>")
	)
	(gr_poly
		(pts
			(xy 142.424912 -239.422432) (xy 142.424912 -239.377982) (xy 142.22476 -239.377982) (xy 142.22476 -239.422432)
			(xy 142.324836 -239.522508)
		)
		(stroke
			(width 0)
			(type solid)
		)
		(fill yes)
		(layer "In11.Cu")
		(net "M_L_CPU1_SA_DQ<23>")
	)
	(gr_poly
		(pts
			(xy 142.424912 -238.20628) (xy 142.324836 -238.106204) (xy 142.22476 -238.20628) (xy 142.22476 -238.25073)
			(xy 142.424912 -238.25073)
		)
		(stroke
			(width 0)
			(type solid)
		)
		(fill yes)
		(layer "In11.Cu")
		(net "M_L_CPU1_SA_DQ<20>")
	)
	(gr_poly
		(pts
			(xy 142.424912 -237.802674) (xy 142.424912 -237.754922) (xy 142.22476 -237.754922) (xy 142.22476 -237.802674)
			(xy 142.324836 -237.902496)
		)
		(stroke
			(width 0)
			(type solid)
		)
		(fill yes)
		(layer "In11.Cu")
		(net "M_L_CPU1_SA_DQS_DP<7>")
	)
	(gr_poly
		(pts
			(xy 142.424912 -236.586014) (xy 142.324836 -236.486192) (xy 142.22476 -236.586014) (xy 142.22476 -236.633766)
			(xy 142.424912 -236.633766)
		)
		(stroke
			(width 0)
			(type solid)
		)
		(fill yes)
		(layer "In11.Cu")
		(net "M_L_CPU1_SA_DQS_DP<2>")
	)
	(gr_poly
		(pts
			(xy 142.424912 -236.182408) (xy 142.424912 -236.137958) (xy 142.22476 -236.137958) (xy 142.22476 -236.182408)
			(xy 142.324836 -236.282484)
		)
		(stroke
			(width 0)
			(type solid)
		)
		(fill yes)
		(layer "In11.Cu")
		(net "M_L_CPU1_SA_DQ<19>")
	)
	(gr_poly
		(pts
			(xy 142.424912 -234.966256) (xy 142.324836 -234.86618) (xy 142.22476 -234.966256) (xy 142.22476 -235.010706)
			(xy 142.424912 -235.010706)
		)
		(stroke
			(width 0)
			(type solid)
		)
		(fill yes)
		(layer "In11.Cu")
		(net "M_L_CPU1_SA_DQ<16>")
	)
	(gr_poly
		(pts
			(xy 142.424912 -234.562396) (xy 142.424912 -234.517946) (xy 142.22476 -234.517946) (xy 142.22476 -234.562396)
			(xy 142.324836 -234.662472)
		)
		(stroke
			(width 0)
			(type solid)
		)
		(fill yes)
		(layer "In11.Cu")
		(net "M_L_CPU1_SA_DQ<15>")
	)
	(gr_poly
		(pts
			(xy 142.424912 -233.346244) (xy 142.324836 -233.246168) (xy 142.22476 -233.346244) (xy 142.22476 -233.390694)
			(xy 142.424912 -233.390694)
		)
		(stroke
			(width 0)
			(type solid)
		)
		(fill yes)
		(layer "In11.Cu")
		(net "M_L_CPU1_SA_DQ<12>")
	)
	(gr_poly
		(pts
			(xy 142.424912 -232.942638) (xy 142.424912 -232.894886) (xy 142.22476 -232.894886) (xy 142.22476 -232.942638)
			(xy 142.324836 -233.04246)
		)
		(stroke
			(width 0)
			(type solid)
		)
		(fill yes)
		(layer "In11.Cu")
		(net "M_L_CPU1_SA_DQS_DP<6>")
	)
	(gr_poly
		(pts
			(xy 142.424912 -231.725978) (xy 142.324836 -231.626156) (xy 142.22476 -231.725978) (xy 142.22476 -231.77373)
			(xy 142.424912 -231.77373)
		)
		(stroke
			(width 0)
			(type solid)
		)
		(fill yes)
		(layer "In11.Cu")
		(net "M_L_CPU1_SA_DQS_DP<1>")
	)
	(gr_poly
		(pts
			(xy 142.424912 -231.322626) (xy 142.424912 -231.278176) (xy 142.22476 -231.278176) (xy 142.22476 -231.322626)
			(xy 142.324836 -231.422702)
		)
		(stroke
			(width 0)
			(type solid)
		)
		(fill yes)
		(layer "In11.Cu")
		(net "M_L_CPU1_SA_DQ<11>")
	)
	(gr_poly
		(pts
			(xy 142.424912 -230.10622) (xy 142.324836 -230.006144) (xy 142.22476 -230.10622) (xy 142.22476 -230.15067)
			(xy 142.424912 -230.15067)
		)
		(stroke
			(width 0)
			(type solid)
		)
		(fill yes)
		(layer "In11.Cu")
		(net "M_L_CPU1_SA_DQ<8>")
	)
	(gr_poly
		(pts
			(xy 142.424912 -229.702614) (xy 142.424912 -229.658164) (xy 142.22476 -229.658164) (xy 142.22476 -229.702614)
			(xy 142.324836 -229.80269)
		)
		(stroke
			(width 0)
			(type solid)
		)
		(fill yes)
		(layer "In11.Cu")
		(net "M_L_CPU1_SA_DQ<7>")
	)
	(gr_poly
		(pts
			(xy 142.424912 -228.486462) (xy 142.324836 -228.386386) (xy 142.22476 -228.486462) (xy 142.22476 -228.530912)
			(xy 142.424912 -228.530912)
		)
		(stroke
			(width 0)
			(type solid)
		)
		(fill yes)
		(layer "In11.Cu")
		(net "M_L_CPU1_SA_DQ<4>")
	)
	(gr_poly
		(pts
			(xy 142.424912 -228.082856) (xy 142.424912 -228.035104) (xy 142.22476 -228.035104) (xy 142.22476 -228.082856)
			(xy 142.324836 -228.182678)
		)
		(stroke
			(width 0)
			(type solid)
		)
		(fill yes)
		(layer "In11.Cu")
		(net "M_L_CPU1_SA_DQS_DP<5>")
	)
	(gr_poly
		(pts
			(xy 142.424912 -226.866196) (xy 142.324836 -226.766374) (xy 142.22476 -226.866196) (xy 142.22476 -226.913948)
			(xy 142.424912 -226.913948)
		)
		(stroke
			(width 0)
			(type solid)
		)
		(fill yes)
		(layer "In11.Cu")
		(net "M_L_CPU1_SA_DQS_DP<0>")
	)
	(gr_poly
		(pts
			(xy 142.424912 -226.46259) (xy 142.424912 -226.41814) (xy 142.22476 -226.41814) (xy 142.22476 -226.46259)
			(xy 142.324836 -226.562666)
		)
		(stroke
			(width 0)
			(type solid)
		)
		(fill yes)
		(layer "In11.Cu")
		(net "M_L_CPU1_SA_DQ<3>")
	)
	(gr_poly
		(pts
			(xy 142.480538 -225.379026) (xy 142.443962 -225.242374) (xy 142.405608 -225.220022) (xy 142.305532 -225.39325)
			(xy 142.34414 -225.415602)
		)
		(stroke
			(width 0)
			(type solid)
		)
		(fill yes)
		(layer "In11.Cu")
		(net "M_L_CPU1_SA_DQ<2>")
	)
	(gr_poly
		(pts
			(xy 142.724886 -292.918134) (xy 142.62481 -292.818058) (xy 142.524734 -292.918134) (xy 142.524734 -292.962584)
			(xy 142.724886 -292.962584)
		)
		(stroke
			(width 0)
			(type solid)
		)
		(fill yes)
		(layer "In11.Cu")
		(net "M_L_CPU1_SB_DQ<29>")
	)
	(gr_poly
		(pts
			(xy 142.724886 -292.514274) (xy 142.724886 -292.469824) (xy 142.524734 -292.469824) (xy 142.524734 -292.514274)
			(xy 142.62481 -292.61435)
		)
		(stroke
			(width 0)
			(type solid)
		)
		(fill yes)
		(layer "In11.Cu")
		(net "M_L_CPU1_SB_DQ<30>")
	)
	(gr_poly
		(pts
			(xy 142.724886 -291.297868) (xy 142.62481 -291.198046) (xy 142.524734 -291.297868) (xy 142.524734 -291.34562)
			(xy 142.724886 -291.34562)
		)
		(stroke
			(width 0)
			(type solid)
		)
		(fill yes)
		(layer "In11.Cu")
		(net "M_L_CPU1_SB_DQS_DN<8>")
	)
	(gr_poly
		(pts
			(xy 142.724886 -290.894516) (xy 142.724886 -290.846764) (xy 142.524734 -290.846764) (xy 142.524734 -290.894516)
			(xy 142.62481 -290.994338)
		)
		(stroke
			(width 0)
			(type solid)
		)
		(fill yes)
		(layer "In11.Cu")
		(net "M_L_CPU1_SB_DQS_DN<3>")
	)
	(gr_poly
		(pts
			(xy 142.724886 -289.67811) (xy 142.62481 -289.578034) (xy 142.524734 -289.67811) (xy 142.524734 -289.72256)
			(xy 142.724886 -289.72256)
		)
		(stroke
			(width 0)
			(type solid)
		)
		(fill yes)
		(layer "In11.Cu")
		(net "M_L_CPU1_SB_DQ<25>")
	)
	(gr_poly
		(pts
			(xy 142.724886 -289.27425) (xy 142.724886 -289.2298) (xy 142.524734 -289.2298) (xy 142.524734 -289.27425)
			(xy 142.62481 -289.374326)
		)
		(stroke
			(width 0)
			(type solid)
		)
		(fill yes)
		(layer "In11.Cu")
		(net "M_L_CPU1_SB_DQ<26>")
	)
	(gr_poly
		(pts
			(xy 142.724886 -288.058098) (xy 142.62481 -287.958022) (xy 142.524734 -288.058098) (xy 142.524734 -288.102548)
			(xy 142.724886 -288.102548)
		)
		(stroke
			(width 0)
			(type solid)
		)
		(fill yes)
		(layer "In11.Cu")
		(net "M_L_CPU1_SB_DQ<21>")
	)
	(gr_poly
		(pts
			(xy 142.724886 -287.654492) (xy 142.724886 -287.610042) (xy 142.524734 -287.610042) (xy 142.524734 -287.654492)
			(xy 142.62481 -287.754568)
		)
		(stroke
			(width 0)
			(type solid)
		)
		(fill yes)
		(layer "In11.Cu")
		(net "M_L_CPU1_SB_DQ<22>")
	)
	(gr_poly
		(pts
			(xy 142.724886 -286.438086) (xy 142.62481 -286.33801) (xy 142.524734 -286.438086) (xy 142.524734 -286.485838)
			(xy 142.724886 -286.485838)
		)
		(stroke
			(width 0)
			(type solid)
		)
		(fill yes)
		(layer "In11.Cu")
		(net "M_L_CPU1_SB_DQS_DN<7>")
	)
	(gr_poly
		(pts
			(xy 142.724886 -286.034734) (xy 142.724886 -285.986982) (xy 142.524734 -285.986982) (xy 142.524734 -286.034734)
			(xy 142.62481 -286.134556)
		)
		(stroke
			(width 0)
			(type solid)
		)
		(fill yes)
		(layer "In11.Cu")
		(net "M_L_CPU1_SB_DQS_DN<2>")
	)
	(gr_poly
		(pts
			(xy 142.724886 -284.818328) (xy 142.62481 -284.718252) (xy 142.524734 -284.818328) (xy 142.524734 -284.862778)
			(xy 142.724886 -284.862778)
		)
		(stroke
			(width 0)
			(type solid)
		)
		(fill yes)
		(layer "In11.Cu")
		(net "M_L_CPU1_SB_DQ<17>")
	)
	(gr_poly
		(pts
			(xy 142.724886 -284.414468) (xy 142.724886 -284.370018) (xy 142.524734 -284.370018) (xy 142.524734 -284.414468)
			(xy 142.62481 -284.514544)
		)
		(stroke
			(width 0)
			(type solid)
		)
		(fill yes)
		(layer "In11.Cu")
		(net "M_L_CPU1_SB_DQ<18>")
	)
	(gr_poly
		(pts
			(xy 142.724886 -283.198316) (xy 142.62481 -283.09824) (xy 142.524734 -283.198316) (xy 142.524734 -283.242766)
			(xy 142.724886 -283.242766)
		)
		(stroke
			(width 0)
			(type solid)
		)
		(fill yes)
		(layer "In11.Cu")
		(net "M_L_CPU1_SB_DQ<13>")
	)
	(gr_poly
		(pts
			(xy 142.724886 -282.794456) (xy 142.724886 -282.750006) (xy 142.524734 -282.750006) (xy 142.524734 -282.794456)
			(xy 142.62481 -282.894532)
		)
		(stroke
			(width 0)
			(type solid)
		)
		(fill yes)
		(layer "In11.Cu")
		(net "M_L_CPU1_SB_DQ<14>")
	)
	(gr_poly
		(pts
			(xy 142.724886 -281.57805) (xy 142.62481 -281.478228) (xy 142.524734 -281.57805) (xy 142.524734 -281.625802)
			(xy 142.724886 -281.625802)
		)
		(stroke
			(width 0)
			(type solid)
		)
		(fill yes)
		(layer "In11.Cu")
		(net "M_L_CPU1_SB_DQS_DN<6>")
	)
	(gr_poly
		(pts
			(xy 142.724886 -281.174698) (xy 142.724886 -281.126946) (xy 142.524734 -281.126946) (xy 142.524734 -281.174698)
			(xy 142.62481 -281.27452)
		)
		(stroke
			(width 0)
			(type solid)
		)
		(fill yes)
		(layer "In11.Cu")
		(net "M_L_CPU1_SB_DQS_DN<1>")
	)
	(gr_poly
		(pts
			(xy 142.724886 -279.958292) (xy 142.62481 -279.858216) (xy 142.524734 -279.958292) (xy 142.524734 -280.002742)
			(xy 142.724886 -280.002742)
		)
		(stroke
			(width 0)
			(type solid)
		)
		(fill yes)
		(layer "In11.Cu")
		(net "M_L_CPU1_SB_DQ<9>")
	)
	(gr_poly
		(pts
			(xy 142.724886 -279.554432) (xy 142.724886 -279.509982) (xy 142.524734 -279.509982) (xy 142.524734 -279.554432)
			(xy 142.62481 -279.654508)
		)
		(stroke
			(width 0)
			(type solid)
		)
		(fill yes)
		(layer "In11.Cu")
		(net "M_L_CPU1_SB_DQ<10>")
	)
	(gr_poly
		(pts
			(xy 142.724886 -278.33828) (xy 142.62481 -278.238204) (xy 142.524734 -278.33828) (xy 142.524734 -278.38273)
			(xy 142.724886 -278.38273)
		)
		(stroke
			(width 0)
			(type solid)
		)
		(fill yes)
		(layer "In11.Cu")
		(net "M_L_CPU1_SB_DQ<5>")
	)
	(gr_poly
		(pts
			(xy 142.724886 -277.93442) (xy 142.724886 -277.88997) (xy 142.524734 -277.88997) (xy 142.524734 -277.93442)
			(xy 142.62481 -278.034496)
		)
		(stroke
			(width 0)
			(type solid)
		)
		(fill yes)
		(layer "In11.Cu")
		(net "M_L_CPU1_SB_DQ<6>")
	)
	(gr_poly
		(pts
			(xy 142.724886 -276.718014) (xy 142.62481 -276.618192) (xy 142.524734 -276.718014) (xy 142.524734 -276.765766)
			(xy 142.724886 -276.765766)
		)
		(stroke
			(width 0)
			(type solid)
		)
		(fill yes)
		(layer "In11.Cu")
		(net "M_L_CPU1_SB_DQS_DN<5>")
	)
	(gr_poly
		(pts
			(xy 142.724886 -276.314662) (xy 142.724886 -276.26691) (xy 142.524734 -276.26691) (xy 142.524734 -276.314662)
			(xy 142.62481 -276.414484)
		)
		(stroke
			(width 0)
			(type solid)
		)
		(fill yes)
		(layer "In11.Cu")
		(net "M_L_CPU1_SB_DQS_DN<0>")
	)
	(gr_poly
		(pts
			(xy 142.724886 -275.098256) (xy 142.62481 -274.99818) (xy 142.524734 -275.098256) (xy 142.524734 -275.142706)
			(xy 142.724886 -275.142706)
		)
		(stroke
			(width 0)
			(type solid)
		)
		(fill yes)
		(layer "In11.Cu")
		(net "M_L_CPU1_SB_DQ<1>")
	)
	(gr_poly
		(pts
			(xy 142.724886 -274.694396) (xy 142.724886 -274.649946) (xy 142.524734 -274.649946) (xy 142.524734 -274.694396)
			(xy 142.62481 -274.794472)
		)
		(stroke
			(width 0)
			(type solid)
		)
		(fill yes)
		(layer "In11.Cu")
		(net "M_L_CPU1_SB_DQ<2>")
	)
	(gr_poly
		(pts
			(xy 142.724886 -273.478244) (xy 142.62481 -273.378168) (xy 142.524734 -273.478244) (xy 142.524734 -273.522694)
			(xy 142.724886 -273.522694)
		)
		(stroke
			(width 0)
			(type solid)
		)
		(fill yes)
		(layer "In11.Cu")
		(net "M_L_CPU1_SB_CB<1>")
	)
	(gr_poly
		(pts
			(xy 142.724886 -273.074384) (xy 142.724886 -273.029934) (xy 142.524734 -273.029934) (xy 142.524734 -273.074384)
			(xy 142.62481 -273.17446)
		)
		(stroke
			(width 0)
			(type solid)
		)
		(fill yes)
		(layer "In11.Cu")
		(net "M_L_CPU1_SB_CB<2>")
	)
	(gr_poly
		(pts
			(xy 142.724886 -271.857978) (xy 142.62481 -271.758156) (xy 142.524734 -271.857978) (xy 142.524734 -271.90573)
			(xy 142.724886 -271.90573)
		)
		(stroke
			(width 0)
			(type solid)
		)
		(fill yes)
		(layer "In11.Cu")
		(net "M_L_CPU1_SB_DQS_DN<4>")
	)
	(gr_poly
		(pts
			(xy 142.724886 -271.454626) (xy 142.724886 -271.406874) (xy 142.524734 -271.406874) (xy 142.524734 -271.454626)
			(xy 142.62481 -271.554448)
		)
		(stroke
			(width 0)
			(type solid)
		)
		(fill yes)
		(layer "In11.Cu")
		(net "M_L_CPU1_SB_DQS_DN<9>")
	)
	(gr_poly
		(pts
			(xy 142.724886 -270.23822) (xy 142.62481 -270.138144) (xy 142.524734 -270.23822) (xy 142.524734 -270.28267)
			(xy 142.724886 -270.28267)
		)
		(stroke
			(width 0)
			(type solid)
		)
		(fill yes)
		(layer "In11.Cu")
		(net "M_L_CPU1_SB_CB<5>")
	)
	(gr_poly
		(pts
			(xy 142.724886 -269.83436) (xy 142.724886 -269.78991) (xy 142.524734 -269.78991) (xy 142.524734 -269.83436)
			(xy 142.62481 -269.934436)
		)
		(stroke
			(width 0)
			(type solid)
		)
		(fill yes)
		(layer "In11.Cu")
		(net "M_L_CPU1_SB_CB<6>")
	)
	(gr_poly
		(pts
			(xy 142.724886 -266.998196) (xy 142.62481 -266.89812) (xy 142.524734 -266.998196) (xy 142.524734 -267.042646)
			(xy 142.724886 -267.042646)
		)
		(stroke
			(width 0)
			(type solid)
		)
		(fill yes)
		(layer "In11.Cu")
		(net "M_L_CPU1_SA_RSP<0>")
	)
	(gr_poly
		(pts
			(xy 142.724886 -266.594336) (xy 142.724886 -266.549886) (xy 142.524734 -266.549886) (xy 142.524734 -266.594336)
			(xy 142.62481 -266.694412)
		)
		(stroke
			(width 0)
			(type solid)
		)
		(fill yes)
		(layer "In11.Cu")
		(net "M_L_CPU1_SB_CS_N<1>")
	)
	(gr_poly
		(pts
			(xy 142.724886 -265.378184) (xy 142.62481 -265.278108) (xy 142.524734 -265.378184) (xy 142.524734 -265.422634)
			(xy 142.724886 -265.422634)
		)
		(stroke
			(width 0)
			(type solid)
		)
		(fill yes)
		(layer "In11.Cu")
		(net "M_L_CPU1_SB_PAR")
	)
	(gr_poly
		(pts
			(xy 142.724886 -263.758172) (xy 142.62481 -263.658096) (xy 142.524734 -263.758172) (xy 142.524734 -263.802622)
			(xy 142.724886 -263.802622)
		)
		(stroke
			(width 0)
			(type solid)
		)
		(fill yes)
		(layer "In11.Cu")
		(net "M_L_CPU1_SB_CA<4>")
	)
	(gr_poly
		(pts
			(xy 142.724886 -263.354312) (xy 142.724886 -263.309862) (xy 142.524734 -263.309862) (xy 142.524734 -263.354312)
			(xy 142.62481 -263.454388)
		)
		(stroke
			(width 0)
			(type solid)
		)
		(fill yes)
		(layer "In11.Cu")
		(net "M_L_CPU1_SB_CA<3>")
	)
	(gr_poly
		(pts
			(xy 142.724886 -262.13816) (xy 142.62481 -262.038084) (xy 142.524734 -262.13816) (xy 142.524734 -262.18261)
			(xy 142.724886 -262.18261)
		)
		(stroke
			(width 0)
			(type solid)
		)
		(fill yes)
		(layer "In11.Cu")
		(net "M_L_CPU1_SB_CA<0>")
	)
	(gr_poly
		(pts
			(xy 142.814802 -225.504248) (xy 142.776194 -225.48215) (xy 142.639542 -225.518726) (xy 142.676118 -225.655378)
			(xy 142.714726 -225.677476)
		)
		(stroke
			(width 0)
			(type solid)
		)
		(fill yes)
		(layer "In11.Cu")
		(net "M_L_CPU1_SA_DQ<1>")
	)
	(gr_poly
		(pts
			(xy 142.814802 -223.884236) (xy 142.776194 -223.862138) (xy 142.639542 -223.898714) (xy 142.676118 -224.035366)
			(xy 142.714726 -224.057464)
		)
		(stroke
			(width 0)
			(type solid)
		)
		(fill yes)
		(layer "In11.Cu")
		(net "M_L_CPU1_SA_DQ<0>")
	)
	(gr_poly
		(pts
			(xy 142.894812 -256.432812) (xy 142.894812 -256.38506) (xy 142.69466 -256.38506) (xy 142.69466 -256.432812)
			(xy 142.794736 -256.532634)
		)
		(stroke
			(width 0)
			(type solid)
		)
		(fill yes)
		(layer "In11.Cu")
		(net "M_L_CPU1_CLK_DN<0>")
	)
	(gr_poly
		(pts
			(xy 142.894812 -255.216406) (xy 142.794736 -255.11633) (xy 142.69466 -255.216406) (xy 142.69466 -255.260856)
			(xy 142.894812 -255.260856)
		)
		(stroke
			(width 0)
			(type solid)
		)
		(fill yes)
		(layer "In11.Cu")
		(net "M_L_CPU1_SA_CA<6>")
	)
	(gr_poly
		(pts
			(xy 142.894812 -254.812546) (xy 142.894812 -254.768096) (xy 142.69466 -254.768096) (xy 142.69466 -254.812546)
			(xy 142.794736 -254.912622)
		)
		(stroke
			(width 0)
			(type solid)
		)
		(fill yes)
		(layer "In11.Cu")
		(net "M_L_CPU1_SA_CA<5>")
	)
	(gr_poly
		(pts
			(xy 142.894812 -253.596394) (xy 142.794736 -253.496318) (xy 142.69466 -253.596394) (xy 142.69466 -253.640844)
			(xy 142.894812 -253.640844)
		)
		(stroke
			(width 0)
			(type solid)
		)
		(fill yes)
		(layer "In11.Cu")
		(net "M_L_CPU1_SA_CA<2>")
	)
	(gr_poly
		(pts
			(xy 142.894812 -253.192534) (xy 142.894812 -253.148084) (xy 142.69466 -253.148084) (xy 142.69466 -253.192534)
			(xy 142.794736 -253.29261)
		)
		(stroke
			(width 0)
			(type solid)
		)
		(fill yes)
		(layer "In11.Cu")
		(net "M_L_CPU1_SA_CA<1>")
	)
	(gr_poly
		(pts
			(xy 142.894812 -251.970032) (xy 142.794736 -251.869956) (xy 142.69466 -251.970032) (xy 142.69466 -252.014482)
			(xy 142.894812 -252.014482)
		)
		(stroke
			(width 0)
			(type solid)
		)
		(fill yes)
		(layer "In11.Cu")
		(net "M_L_CPU1_SA_CS_N<1>")
	)
	(gr_poly
		(pts
			(xy 142.894812 -250.35637) (xy 142.794736 -250.256294) (xy 142.69466 -250.35637) (xy 142.69466 -250.40082)
			(xy 142.894812 -250.40082)
		)
		(stroke
			(width 0)
			(type solid)
		)
		(fill yes)
		(layer "In11.Cu")
		(net "M_L_CPU1_ALERT_R_N")
	)
	(gr_poly
		(pts
			(xy 142.894812 -248.736358) (xy 142.794736 -248.636282) (xy 142.69466 -248.736358) (xy 142.69466 -248.780808)
			(xy 142.894812 -248.780808)
		)
		(stroke
			(width 0)
			(type solid)
		)
		(fill yes)
		(layer "In11.Cu")
		(net "M_L_CPU1_SA_CB<5>")
	)
	(gr_poly
		(pts
			(xy 142.894812 -248.332498) (xy 142.894812 -248.288048) (xy 142.69466 -248.288048) (xy 142.69466 -248.332498)
			(xy 142.794736 -248.432574)
		)
		(stroke
			(width 0)
			(type solid)
		)
		(fill yes)
		(layer "In11.Cu")
		(net "M_L_CPU1_SA_CB<6>")
	)
	(gr_poly
		(pts
			(xy 142.894812 -247.116092) (xy 142.794736 -247.01627) (xy 142.69466 -247.116092) (xy 142.69466 -247.163844)
			(xy 142.894812 -247.163844)
		)
		(stroke
			(width 0)
			(type solid)
		)
		(fill yes)
		(layer "In11.Cu")
		(net "M_L_CPU1_SA_DQS_DN<9>")
	)
	(gr_poly
		(pts
			(xy 142.894812 -246.71274) (xy 142.894812 -246.664988) (xy 142.69466 -246.664988) (xy 142.69466 -246.71274)
			(xy 142.794736 -246.812562)
		)
		(stroke
			(width 0)
			(type solid)
		)
		(fill yes)
		(layer "In11.Cu")
		(net "M_L_CPU1_SA_DQS_DN<4>")
	)
	(gr_poly
		(pts
			(xy 142.894812 -245.496334) (xy 142.794736 -245.396258) (xy 142.69466 -245.496334) (xy 142.69466 -245.540784)
			(xy 142.894812 -245.540784)
		)
		(stroke
			(width 0)
			(type solid)
		)
		(fill yes)
		(layer "In11.Cu")
		(net "M_L_CPU1_SA_CB<1>")
	)
	(gr_poly
		(pts
			(xy 142.894812 -245.092474) (xy 142.894812 -245.048024) (xy 142.69466 -245.048024) (xy 142.69466 -245.092474)
			(xy 142.794736 -245.19255)
		)
		(stroke
			(width 0)
			(type solid)
		)
		(fill yes)
		(layer "In11.Cu")
		(net "M_L_CPU1_SA_CB<2>")
	)
	(gr_poly
		(pts
			(xy 142.894812 -243.876322) (xy 142.794736 -243.776246) (xy 142.69466 -243.876322) (xy 142.69466 -243.920772)
			(xy 142.894812 -243.920772)
		)
		(stroke
			(width 0)
			(type solid)
		)
		(fill yes)
		(layer "In11.Cu")
		(net "M_L_CPU1_SA_DQ<29>")
	)
	(gr_poly
		(pts
			(xy 142.894812 -243.472462) (xy 142.894812 -243.428012) (xy 142.69466 -243.428012) (xy 142.69466 -243.472462)
			(xy 142.794736 -243.572538)
		)
		(stroke
			(width 0)
			(type solid)
		)
		(fill yes)
		(layer "In11.Cu")
		(net "M_L_CPU1_SA_DQ<30>")
	)
	(gr_poly
		(pts
			(xy 142.894812 -242.256056) (xy 142.794736 -242.156234) (xy 142.69466 -242.256056) (xy 142.69466 -242.303808)
			(xy 142.894812 -242.303808)
		)
		(stroke
			(width 0)
			(type solid)
		)
		(fill yes)
		(layer "In11.Cu")
		(net "M_L_CPU1_SA_DQS_DN<8>")
	)
	(gr_poly
		(pts
			(xy 142.894812 -241.852704) (xy 142.894812 -241.804952) (xy 142.69466 -241.804952) (xy 142.69466 -241.852704)
			(xy 142.794736 -241.952526)
		)
		(stroke
			(width 0)
			(type solid)
		)
		(fill yes)
		(layer "In11.Cu")
		(net "M_L_CPU1_SA_DQS_DN<3>")
	)
	(gr_poly
		(pts
			(xy 142.894812 -240.636298) (xy 142.794736 -240.536222) (xy 142.69466 -240.636298) (xy 142.69466 -240.680748)
			(xy 142.894812 -240.680748)
		)
		(stroke
			(width 0)
			(type solid)
		)
		(fill yes)
		(layer "In11.Cu")
		(net "M_L_CPU1_SA_DQ<25>")
	)
	(gr_poly
		(pts
			(xy 142.894812 -240.232438) (xy 142.894812 -240.187988) (xy 142.69466 -240.187988) (xy 142.69466 -240.232438)
			(xy 142.794736 -240.332514)
		)
		(stroke
			(width 0)
			(type solid)
		)
		(fill yes)
		(layer "In11.Cu")
		(net "M_L_CPU1_SA_DQ<26>")
	)
	(gr_poly
		(pts
			(xy 142.894812 -239.016286) (xy 142.794736 -238.91621) (xy 142.69466 -239.016286) (xy 142.69466 -239.060736)
			(xy 142.894812 -239.060736)
		)
		(stroke
			(width 0)
			(type solid)
		)
		(fill yes)
		(layer "In11.Cu")
		(net "M_L_CPU1_SA_DQ<21>")
	)
	(gr_poly
		(pts
			(xy 142.894812 -238.612426) (xy 142.894812 -238.567976) (xy 142.69466 -238.567976) (xy 142.69466 -238.612426)
			(xy 142.794736 -238.712502)
		)
		(stroke
			(width 0)
			(type solid)
		)
		(fill yes)
		(layer "In11.Cu")
		(net "M_L_CPU1_SA_DQ<22>")
	)
	(gr_poly
		(pts
			(xy 142.894812 -237.39602) (xy 142.794736 -237.296198) (xy 142.69466 -237.39602) (xy 142.69466 -237.443772)
			(xy 142.894812 -237.443772)
		)
		(stroke
			(width 0)
			(type solid)
		)
		(fill yes)
		(layer "In11.Cu")
		(net "M_L_CPU1_SA_DQS_DN<7>")
	)
	(gr_poly
		(pts
			(xy 142.894812 -236.992668) (xy 142.894812 -236.944916) (xy 142.69466 -236.944916) (xy 142.69466 -236.992668)
			(xy 142.794736 -237.09249)
		)
		(stroke
			(width 0)
			(type solid)
		)
		(fill yes)
		(layer "In11.Cu")
		(net "M_L_CPU1_SA_DQS_DN<2>")
	)
	(gr_poly
		(pts
			(xy 142.894812 -235.776262) (xy 142.794736 -235.676186) (xy 142.69466 -235.776262) (xy 142.69466 -235.820712)
			(xy 142.894812 -235.820712)
		)
		(stroke
			(width 0)
			(type solid)
		)
		(fill yes)
		(layer "In11.Cu")
		(net "M_L_CPU1_SA_DQ<17>")
	)
	(gr_poly
		(pts
			(xy 142.894812 -235.372402) (xy 142.894812 -235.327952) (xy 142.69466 -235.327952) (xy 142.69466 -235.372402)
			(xy 142.794736 -235.472478)
		)
		(stroke
			(width 0)
			(type solid)
		)
		(fill yes)
		(layer "In11.Cu")
		(net "M_L_CPU1_SA_DQ<18>")
	)
	(gr_poly
		(pts
			(xy 142.894812 -234.15625) (xy 142.794736 -234.056174) (xy 142.69466 -234.15625) (xy 142.69466 -234.2007)
			(xy 142.894812 -234.2007)
		)
		(stroke
			(width 0)
			(type solid)
		)
		(fill yes)
		(layer "In11.Cu")
		(net "M_L_CPU1_SA_DQ<13>")
	)
	(gr_poly
		(pts
			(xy 142.894812 -233.75239) (xy 142.894812 -233.70794) (xy 142.69466 -233.70794) (xy 142.69466 -233.75239)
			(xy 142.794736 -233.852466)
		)
		(stroke
			(width 0)
			(type solid)
		)
		(fill yes)
		(layer "In11.Cu")
		(net "M_L_CPU1_SA_DQ<14>")
	)
	(gr_poly
		(pts
			(xy 142.894812 -232.535984) (xy 142.794736 -232.436162) (xy 142.69466 -232.535984) (xy 142.69466 -232.583736)
			(xy 142.894812 -232.583736)
		)
		(stroke
			(width 0)
			(type solid)
		)
		(fill yes)
		(layer "In11.Cu")
		(net "M_L_CPU1_SA_DQS_DN<6>")
	)
	(gr_poly
		(pts
			(xy 142.894812 -232.132632) (xy 142.894812 -232.08488) (xy 142.69466 -232.08488) (xy 142.69466 -232.132632)
			(xy 142.794736 -232.232454)
		)
		(stroke
			(width 0)
			(type solid)
		)
		(fill yes)
		(layer "In11.Cu")
		(net "M_L_CPU1_SA_DQS_DN<1>")
	)
	(gr_poly
		(pts
			(xy 142.894812 -230.916226) (xy 142.794736 -230.81615) (xy 142.69466 -230.916226) (xy 142.69466 -230.960676)
			(xy 142.894812 -230.960676)
		)
		(stroke
			(width 0)
			(type solid)
		)
		(fill yes)
		(layer "In11.Cu")
		(net "M_L_CPU1_SA_DQ<9>")
	)
	(gr_poly
		(pts
			(xy 142.894812 -230.51262) (xy 142.894812 -230.46817) (xy 142.69466 -230.46817) (xy 142.69466 -230.51262)
			(xy 142.794736 -230.612696)
		)
		(stroke
			(width 0)
			(type solid)
		)
		(fill yes)
		(layer "In11.Cu")
		(net "M_L_CPU1_SA_DQ<10>")
	)
	(gr_poly
		(pts
			(xy 142.894812 -229.296214) (xy 142.794736 -229.196138) (xy 142.69466 -229.296214) (xy 142.69466 -229.340664)
			(xy 142.894812 -229.340664)
		)
		(stroke
			(width 0)
			(type solid)
		)
		(fill yes)
		(layer "In11.Cu")
		(net "M_L_CPU1_SA_DQ<5>")
	)
	(gr_poly
		(pts
			(xy 142.894812 -228.892608) (xy 142.894812 -228.848158) (xy 142.69466 -228.848158) (xy 142.69466 -228.892608)
			(xy 142.794736 -228.992684)
		)
		(stroke
			(width 0)
			(type solid)
		)
		(fill yes)
		(layer "In11.Cu")
		(net "M_L_CPU1_SA_DQ<6>")
	)
	(gr_poly
		(pts
			(xy 142.894812 -227.676202) (xy 142.794736 -227.57638) (xy 142.69466 -227.676202) (xy 142.69466 -227.723954)
			(xy 142.894812 -227.723954)
		)
		(stroke
			(width 0)
			(type solid)
		)
		(fill yes)
		(layer "In11.Cu")
		(net "M_L_CPU1_SA_DQS_DN<5>")
	)
	(gr_poly
		(pts
			(xy 142.894812 -227.27285) (xy 142.894812 -227.225098) (xy 142.69466 -227.225098) (xy 142.69466 -227.27285)
			(xy 142.794736 -227.372672)
		)
		(stroke
			(width 0)
			(type solid)
		)
		(fill yes)
		(layer "In11.Cu")
		(net "M_L_CPU1_SA_DQS_DN<0>")
	)
	(gr_poly
		(pts
			(xy 142.94993 -226.190302) (xy 142.913354 -226.05365) (xy 142.874746 -226.031552) (xy 142.77467 -226.20478)
			(xy 142.813278 -226.226878)
		)
		(stroke
			(width 0)
			(type solid)
		)
		(fill yes)
		(layer "In11.Cu")
		(net "M_L_CPU1_SA_DQ<3>")
	)
	(gr_poly
		(pts
			(xy 142.94993 -224.57029) (xy 142.913354 -224.433638) (xy 142.874746 -224.41154) (xy 142.77467 -224.584768)
			(xy 142.813278 -224.606866)
		)
		(stroke
			(width 0)
			(type solid)
		)
		(fill yes)
		(layer "In11.Cu")
		(net "M_L_CPU1_SA_DQ<2>")
	)
	(gr_poly
		(pts
			(xy 143.194786 -293.32428) (xy 143.194786 -293.27983) (xy 142.994634 -293.27983) (xy 142.994634 -293.32428)
			(xy 143.09471 -293.424356)
		)
		(stroke
			(width 0)
			(type solid)
		)
		(fill yes)
		(layer "In11.Cu")
		(net "M_L_CPU1_SB_DQ<31>")
	)
	(gr_poly
		(pts
			(xy 143.194786 -292.108128) (xy 143.09471 -292.008052) (xy 142.994634 -292.108128) (xy 142.994634 -292.152578)
			(xy 143.194786 -292.152578)
		)
		(stroke
			(width 0)
			(type solid)
		)
		(fill yes)
		(layer "In11.Cu")
		(net "M_L_CPU1_SB_DQ<28>")
	)
	(gr_poly
		(pts
			(xy 143.194786 -291.704522) (xy 143.194786 -291.65677) (xy 142.994634 -291.65677) (xy 142.994634 -291.704522)
			(xy 143.09471 -291.804344)
		)
		(stroke
			(width 0)
			(type solid)
		)
		(fill yes)
		(layer "In11.Cu")
		(net "M_L_CPU1_SB_DQS_DP<8>")
	)
	(gr_poly
		(pts
			(xy 143.194786 -290.487862) (xy 143.09471 -290.38804) (xy 142.994634 -290.487862) (xy 142.994634 -290.535614)
			(xy 143.194786 -290.535614)
		)
		(stroke
			(width 0)
			(type solid)
		)
		(fill yes)
		(layer "In11.Cu")
		(net "M_L_CPU1_SB_DQS_DP<3>")
	)
	(gr_poly
		(pts
			(xy 143.194786 -290.084256) (xy 143.194786 -290.039806) (xy 142.994634 -290.039806) (xy 142.994634 -290.084256)
			(xy 143.09471 -290.184332)
		)
		(stroke
			(width 0)
			(type solid)
		)
		(fill yes)
		(layer "In11.Cu")
		(net "M_L_CPU1_SB_DQ<27>")
	)
	(gr_poly
		(pts
			(xy 143.194786 -288.868104) (xy 143.09471 -288.768028) (xy 142.994634 -288.868104) (xy 142.994634 -288.912554)
			(xy 143.194786 -288.912554)
		)
		(stroke
			(width 0)
			(type solid)
		)
		(fill yes)
		(layer "In11.Cu")
		(net "M_L_CPU1_SB_DQ<24>")
	)
	(gr_poly
		(pts
			(xy 143.194786 -288.464498) (xy 143.194786 -288.420048) (xy 142.994634 -288.420048) (xy 142.994634 -288.464498)
			(xy 143.09471 -288.564574)
		)
		(stroke
			(width 0)
			(type solid)
		)
		(fill yes)
		(layer "In11.Cu")
		(net "M_L_CPU1_SB_DQ<23>")
	)
	(gr_poly
		(pts
			(xy 143.194786 -287.248092) (xy 143.09471 -287.148016) (xy 142.994634 -287.248092) (xy 142.994634 -287.292542)
			(xy 143.194786 -287.292542)
		)
		(stroke
			(width 0)
			(type solid)
		)
		(fill yes)
		(layer "In11.Cu")
		(net "M_L_CPU1_SB_DQ<20>")
	)
	(gr_poly
		(pts
			(xy 143.194786 -286.844486) (xy 143.194786 -286.796734) (xy 142.994634 -286.796734) (xy 142.994634 -286.844486)
			(xy 143.09471 -286.944562)
		)
		(stroke
			(width 0)
			(type solid)
		)
		(fill yes)
		(layer "In11.Cu")
		(net "M_L_CPU1_SB_DQS_DP<7>")
	)
	(gr_poly
		(pts
			(xy 143.194786 -285.62808) (xy 143.09471 -285.528258) (xy 142.994634 -285.62808) (xy 142.994634 -285.675832)
			(xy 143.194786 -285.675832)
		)
		(stroke
			(width 0)
			(type solid)
		)
		(fill yes)
		(layer "In11.Cu")
		(net "M_L_CPU1_SB_DQS_DP<2>")
	)
	(gr_poly
		(pts
			(xy 143.194786 -285.224474) (xy 143.194786 -285.180024) (xy 142.994634 -285.180024) (xy 142.994634 -285.224474)
			(xy 143.09471 -285.32455)
		)
		(stroke
			(width 0)
			(type solid)
		)
		(fill yes)
		(layer "In11.Cu")
		(net "M_L_CPU1_SB_DQ<19>")
	)
	(gr_poly
		(pts
			(xy 143.194786 -284.008322) (xy 143.09471 -283.908246) (xy 142.994634 -284.008322) (xy 142.994634 -284.052772)
			(xy 143.194786 -284.052772)
		)
		(stroke
			(width 0)
			(type solid)
		)
		(fill yes)
		(layer "In11.Cu")
		(net "M_L_CPU1_SB_DQ<16>")
	)
	(gr_poly
		(pts
			(xy 143.194786 -283.604462) (xy 143.194786 -283.560012) (xy 142.994634 -283.560012) (xy 142.994634 -283.604462)
			(xy 143.09471 -283.704538)
		)
		(stroke
			(width 0)
			(type solid)
		)
		(fill yes)
		(layer "In11.Cu")
		(net "M_L_CPU1_SB_DQ<15>")
	)
	(gr_poly
		(pts
			(xy 143.194786 -282.38831) (xy 143.09471 -282.288234) (xy 142.994634 -282.38831) (xy 142.994634 -282.43276)
			(xy 143.194786 -282.43276)
		)
		(stroke
			(width 0)
			(type solid)
		)
		(fill yes)
		(layer "In11.Cu")
		(net "M_L_CPU1_SB_DQ<12>")
	)
	(gr_poly
		(pts
			(xy 143.194786 -281.984704) (xy 143.194786 -281.936952) (xy 142.994634 -281.936952) (xy 142.994634 -281.984704)
			(xy 143.09471 -282.084526)
		)
		(stroke
			(width 0)
			(type solid)
		)
		(fill yes)
		(layer "In11.Cu")
		(net "M_L_CPU1_SB_DQS_DP<6>")
	)
	(gr_poly
		(pts
			(xy 143.194786 -280.768044) (xy 143.09471 -280.668222) (xy 142.994634 -280.768044) (xy 142.994634 -280.815796)
			(xy 143.194786 -280.815796)
		)
		(stroke
			(width 0)
			(type solid)
		)
		(fill yes)
		(layer "In11.Cu")
		(net "M_L_CPU1_SB_DQS_DP<1>")
	)
	(gr_poly
		(pts
			(xy 143.194786 -280.364438) (xy 143.194786 -280.319988) (xy 142.994634 -280.319988) (xy 142.994634 -280.364438)
			(xy 143.09471 -280.464514)
		)
		(stroke
			(width 0)
			(type solid)
		)
		(fill yes)
		(layer "In11.Cu")
		(net "M_L_CPU1_SB_DQ<11>")
	)
	(gr_poly
		(pts
			(xy 143.194786 -279.148286) (xy 143.09471 -279.04821) (xy 142.994634 -279.148286) (xy 142.994634 -279.192736)
			(xy 143.194786 -279.192736)
		)
		(stroke
			(width 0)
			(type solid)
		)
		(fill yes)
		(layer "In11.Cu")
		(net "M_L_CPU1_SB_DQ<8>")
	)
	(gr_poly
		(pts
			(xy 143.194786 -278.744426) (xy 143.194786 -278.699976) (xy 142.994634 -278.699976) (xy 142.994634 -278.744426)
			(xy 143.09471 -278.844502)
		)
		(stroke
			(width 0)
			(type solid)
		)
		(fill yes)
		(layer "In11.Cu")
		(net "M_L_CPU1_SB_DQ<7>")
	)
	(gr_poly
		(pts
			(xy 143.194786 -277.528274) (xy 143.09471 -277.428198) (xy 142.994634 -277.528274) (xy 142.994634 -277.572724)
			(xy 143.194786 -277.572724)
		)
		(stroke
			(width 0)
			(type solid)
		)
		(fill yes)
		(layer "In11.Cu")
		(net "M_L_CPU1_SB_DQ<4>")
	)
	(gr_poly
		(pts
			(xy 143.194786 -277.124668) (xy 143.194786 -277.076916) (xy 142.994634 -277.076916) (xy 142.994634 -277.124668)
			(xy 143.09471 -277.22449)
		)
		(stroke
			(width 0)
			(type solid)
		)
		(fill yes)
		(layer "In11.Cu")
		(net "M_L_CPU1_SB_DQS_DP<5>")
	)
	(gr_poly
		(pts
			(xy 143.194786 -275.908008) (xy 143.09471 -275.808186) (xy 142.994634 -275.908008) (xy 142.994634 -275.95576)
			(xy 143.194786 -275.95576)
		)
		(stroke
			(width 0)
			(type solid)
		)
		(fill yes)
		(layer "In11.Cu")
		(net "M_L_CPU1_SB_DQS_DP<0>")
	)
	(gr_poly
		(pts
			(xy 143.194786 -275.504402) (xy 143.194786 -275.459952) (xy 142.994634 -275.459952) (xy 142.994634 -275.504402)
			(xy 143.09471 -275.604478)
		)
		(stroke
			(width 0)
			(type solid)
		)
		(fill yes)
		(layer "In11.Cu")
		(net "M_L_CPU1_SB_DQ<3>")
	)
	(gr_poly
		(pts
			(xy 143.194786 -274.28825) (xy 143.09471 -274.188174) (xy 142.994634 -274.28825) (xy 142.994634 -274.3327)
			(xy 143.194786 -274.3327)
		)
		(stroke
			(width 0)
			(type solid)
		)
		(fill yes)
		(layer "In11.Cu")
		(net "M_L_CPU1_SB_DQ<0>")
	)
	(gr_poly
		(pts
			(xy 143.194786 -273.88439) (xy 143.194786 -273.83994) (xy 142.994634 -273.83994) (xy 142.994634 -273.88439)
			(xy 143.09471 -273.984466)
		)
		(stroke
			(width 0)
			(type solid)
		)
		(fill yes)
		(layer "In11.Cu")
		(net "M_L_CPU1_SB_CB<3>")
	)
	(gr_poly
		(pts
			(xy 143.194786 -272.668238) (xy 143.09471 -272.568162) (xy 142.994634 -272.668238) (xy 142.994634 -272.712688)
			(xy 143.194786 -272.712688)
		)
		(stroke
			(width 0)
			(type solid)
		)
		(fill yes)
		(layer "In11.Cu")
		(net "M_L_CPU1_SB_CB<0>")
	)
	(gr_poly
		(pts
			(xy 143.194786 -272.264632) (xy 143.194786 -272.21688) (xy 142.994634 -272.21688) (xy 142.994634 -272.264632)
			(xy 143.09471 -272.364454)
		)
		(stroke
			(width 0)
			(type solid)
		)
		(fill yes)
		(layer "In11.Cu")
		(net "M_L_CPU1_SB_DQS_DP<4>")
	)
	(gr_poly
		(pts
			(xy 143.194786 -271.047972) (xy 143.09471 -270.94815) (xy 142.994634 -271.047972) (xy 142.994634 -271.095724)
			(xy 143.194786 -271.095724)
		)
		(stroke
			(width 0)
			(type solid)
		)
		(fill yes)
		(layer "In11.Cu")
		(net "M_L_CPU1_SB_DQS_DP<9>")
	)
	(gr_poly
		(pts
			(xy 143.194786 -270.644366) (xy 143.194786 -270.599916) (xy 142.994634 -270.599916) (xy 142.994634 -270.644366)
			(xy 143.09471 -270.744442)
		)
		(stroke
			(width 0)
			(type solid)
		)
		(fill yes)
		(layer "In11.Cu")
		(net "M_L_CPU1_SB_CB<7>")
	)
	(gr_poly
		(pts
			(xy 143.194786 -269.428214) (xy 143.09471 -269.328138) (xy 142.994634 -269.428214) (xy 142.994634 -269.472664)
			(xy 143.194786 -269.472664)
		)
		(stroke
			(width 0)
			(type solid)
		)
		(fill yes)
		(layer "In11.Cu")
		(net "M_L_CPU1_SB_CB<4>")
	)
	(gr_poly
		(pts
			(xy 143.194786 -267.808202) (xy 143.09471 -267.708126) (xy 142.994634 -267.808202) (xy 142.994634 -267.852652)
			(xy 143.194786 -267.852652)
		)
		(stroke
			(width 0)
			(type solid)
		)
		(fill yes)
		(layer "In11.Cu")
		(net "M_L_CPU1_SB_RSP<0>")
	)
	(gr_poly
		(pts
			(xy 143.194786 -265.78433) (xy 143.194786 -265.73988) (xy 142.994634 -265.73988) (xy 142.994634 -265.78433)
			(xy 143.09471 -265.884406)
		)
		(stroke
			(width 0)
			(type solid)
		)
		(fill yes)
		(layer "In11.Cu")
		(net "M_L_CPU1_SB_CS_N<0>")
	)
	(gr_poly
		(pts
			(xy 143.194786 -264.561828) (xy 143.09471 -264.461752) (xy 142.994634 -264.561828) (xy 142.994634 -264.606278)
			(xy 143.194786 -264.606278)
		)
		(stroke
			(width 0)
			(type solid)
		)
		(fill yes)
		(layer "In11.Cu")
		(net "M_L_CPU1_SB_CA<6>")
	)
	(gr_poly
		(pts
			(xy 143.194786 -264.164318) (xy 143.194786 -264.119868) (xy 142.994634 -264.119868) (xy 142.994634 -264.164318)
			(xy 143.09471 -264.264394)
		)
		(stroke
			(width 0)
			(type solid)
		)
		(fill yes)
		(layer "In11.Cu")
		(net "M_L_CPU1_SB_CA<5>")
	)
	(gr_poly
		(pts
			(xy 143.194786 -262.948166) (xy 143.09471 -262.84809) (xy 142.994634 -262.948166) (xy 142.994634 -262.992616)
			(xy 143.194786 -262.992616)
		)
		(stroke
			(width 0)
			(type solid)
		)
		(fill yes)
		(layer "In11.Cu")
		(net "M_L_CPU1_SB_CA<2>")
	)
	(gr_poly
		(pts
			(xy 143.194786 -262.544306) (xy 143.194786 -262.499856) (xy 142.994634 -262.499856) (xy 142.994634 -262.544306)
			(xy 143.09471 -262.644382)
		)
		(stroke
			(width 0)
			(type solid)
		)
		(fill yes)
		(layer "In11.Cu")
		(net "M_L_CPU1_SB_CA<1>")
	)
	(gr_poly
		(pts
			(xy 143.28394 -224.695766) (xy 143.245332 -224.673414) (xy 143.108934 -224.70999) (xy 143.14551 -224.846642)
			(xy 143.183864 -224.868994)
		)
		(stroke
			(width 0)
			(type solid)
		)
		(fill yes)
		(layer "In11.Cu")
		(net "M_L_CPU1_SA_DQ<1>")
	)
	(gr_poly
		(pts
			(xy 143.28394 -223.075754) (xy 143.245332 -223.053402) (xy 143.108934 -223.089978) (xy 143.14551 -223.22663)
			(xy 143.183864 -223.248982)
		)
		(stroke
			(width 0)
			(type solid)
		)
		(fill yes)
		(layer "In11.Cu")
		(net "M_L_CPU1_SA_DQ<0>")
	)
	(gr_poly
		(pts
			(xy 143.286734 -226.31654) (xy 143.245586 -226.292664) (xy 143.108934 -226.329494) (xy 143.14551 -226.465892)
			(xy 143.186912 -226.489768)
		)
		(stroke
			(width 0)
			(type solid)
		)
		(fill yes)
		(layer "In11.Cu")
		(net "M_L_CPU1_SA_DQS_DP<0>")
	)
	(gr_poly
		(pts
			(xy 143.364712 -256.026158) (xy 143.264636 -255.926336) (xy 143.16456 -256.026158) (xy 143.16456 -256.07391)
			(xy 143.364712 -256.07391)
		)
		(stroke
			(width 0)
			(type solid)
		)
		(fill yes)
		(layer "In11.Cu")
		(net "M_L_CPU1_CLK_DP<0>")
	)
	(gr_poly
		(pts
			(xy 143.364712 -255.622552) (xy 143.364712 -255.578102) (xy 143.16456 -255.578102) (xy 143.16456 -255.622552)
			(xy 143.264636 -255.722628)
		)
		(stroke
			(width 0)
			(type solid)
		)
		(fill yes)
		(layer "In11.Cu")
		(net "M_L_CPU1_SA_PAR")
	)
	(gr_poly
		(pts
			(xy 143.364712 -254.4064) (xy 143.264636 -254.306324) (xy 143.16456 -254.4064) (xy 143.16456 -254.45085)
			(xy 143.364712 -254.45085)
		)
		(stroke
			(width 0)
			(type solid)
		)
		(fill yes)
		(layer "In11.Cu")
		(net "M_L_CPU1_SA_CA<4>")
	)
	(gr_poly
		(pts
			(xy 143.364712 -254.00254) (xy 143.364712 -253.95809) (xy 143.16456 -253.95809) (xy 143.16456 -254.00254)
			(xy 143.264636 -254.102616)
		)
		(stroke
			(width 0)
			(type solid)
		)
		(fill yes)
		(layer "In11.Cu")
		(net "M_L_CPU1_SA_CA<3>")
	)
	(gr_poly
		(pts
			(xy 143.364712 -252.786388) (xy 143.264636 -252.686312) (xy 143.16456 -252.786388) (xy 143.16456 -252.830838)
			(xy 143.364712 -252.830838)
		)
		(stroke
			(width 0)
			(type solid)
		)
		(fill yes)
		(layer "In11.Cu")
		(net "M_L_CPU1_SA_CA<0>")
	)
	(gr_poly
		(pts
			(xy 143.364712 -250.762516) (xy 143.364712 -250.718066) (xy 143.16456 -250.718066) (xy 143.16456 -250.762516)
			(xy 143.264636 -250.862592)
		)
		(stroke
			(width 0)
			(type solid)
		)
		(fill yes)
		(layer "In11.Cu")
		(net "M_L_CPU1_RESET_N")
	)
	(gr_poly
		(pts
			(xy 143.364712 -249.142504) (xy 143.364712 -249.098054) (xy 143.16456 -249.098054) (xy 143.16456 -249.142504)
			(xy 143.264636 -249.24258)
		)
		(stroke
			(width 0)
			(type solid)
		)
		(fill yes)
		(layer "In11.Cu")
		(net "M_L_CPU1_SA_CB<7>")
	)
	(gr_poly
		(pts
			(xy 143.364712 -247.926352) (xy 143.264636 -247.826276) (xy 143.16456 -247.926352) (xy 143.16456 -247.970802)
			(xy 143.364712 -247.970802)
		)
		(stroke
			(width 0)
			(type solid)
		)
		(fill yes)
		(layer "In11.Cu")
		(net "M_L_CPU1_SA_CB<4>")
	)
	(gr_poly
		(pts
			(xy 143.364712 -247.522746) (xy 143.364712 -247.474994) (xy 143.16456 -247.474994) (xy 143.16456 -247.522746)
			(xy 143.264636 -247.622568)
		)
		(stroke
			(width 0)
			(type solid)
		)
		(fill yes)
		(layer "In11.Cu")
		(net "M_L_CPU1_SA_DQS_DP<9>")
	)
	(gr_poly
		(pts
			(xy 143.364712 -246.306086) (xy 143.264636 -246.206264) (xy 143.16456 -246.306086) (xy 143.16456 -246.353838)
			(xy 143.364712 -246.353838)
		)
		(stroke
			(width 0)
			(type solid)
		)
		(fill yes)
		(layer "In11.Cu")
		(net "M_L_CPU1_SA_DQS_DP<4>")
	)
	(gr_poly
		(pts
			(xy 143.364712 -245.90248) (xy 143.364712 -245.85803) (xy 143.16456 -245.85803) (xy 143.16456 -245.90248)
			(xy 143.264636 -246.002556)
		)
		(stroke
			(width 0)
			(type solid)
		)
		(fill yes)
		(layer "In11.Cu")
		(net "M_L_CPU1_SA_CB<3>")
	)
	(gr_poly
		(pts
			(xy 143.364712 -244.686328) (xy 143.264636 -244.586252) (xy 143.16456 -244.686328) (xy 143.16456 -244.730778)
			(xy 143.364712 -244.730778)
		)
		(stroke
			(width 0)
			(type solid)
		)
		(fill yes)
		(layer "In11.Cu")
		(net "M_L_CPU1_SA_CB<0>")
	)
	(gr_poly
		(pts
			(xy 143.364712 -244.282468) (xy 143.364712 -244.238018) (xy 143.16456 -244.238018) (xy 143.16456 -244.282468)
			(xy 143.264636 -244.382544)
		)
		(stroke
			(width 0)
			(type solid)
		)
		(fill yes)
		(layer "In11.Cu")
		(net "M_L_CPU1_SA_DQ<31>")
	)
	(gr_poly
		(pts
			(xy 143.364712 -243.066316) (xy 143.264636 -242.96624) (xy 143.16456 -243.066316) (xy 143.16456 -243.110766)
			(xy 143.364712 -243.110766)
		)
		(stroke
			(width 0)
			(type solid)
		)
		(fill yes)
		(layer "In11.Cu")
		(net "M_L_CPU1_SA_DQ<28>")
	)
	(gr_poly
		(pts
			(xy 143.364712 -242.66271) (xy 143.364712 -242.614958) (xy 143.16456 -242.614958) (xy 143.16456 -242.66271)
			(xy 143.264636 -242.762532)
		)
		(stroke
			(width 0)
			(type solid)
		)
		(fill yes)
		(layer "In11.Cu")
		(net "M_L_CPU1_SA_DQS_DP<8>")
	)
	(gr_poly
		(pts
			(xy 143.364712 -241.44605) (xy 143.264636 -241.346228) (xy 143.16456 -241.44605) (xy 143.16456 -241.493802)
			(xy 143.364712 -241.493802)
		)
		(stroke
			(width 0)
			(type solid)
		)
		(fill yes)
		(layer "In11.Cu")
		(net "M_L_CPU1_SA_DQS_DP<3>")
	)
	(gr_poly
		(pts
			(xy 143.364712 -241.042444) (xy 143.364712 -240.997994) (xy 143.16456 -240.997994) (xy 143.16456 -241.042444)
			(xy 143.264636 -241.14252)
		)
		(stroke
			(width 0)
			(type solid)
		)
		(fill yes)
		(layer "In11.Cu")
		(net "M_L_CPU1_SA_DQ<27>")
	)
	(gr_poly
		(pts
			(xy 143.364712 -239.826292) (xy 143.264636 -239.726216) (xy 143.16456 -239.826292) (xy 143.16456 -239.870742)
			(xy 143.364712 -239.870742)
		)
		(stroke
			(width 0)
			(type solid)
		)
		(fill yes)
		(layer "In11.Cu")
		(net "M_L_CPU1_SA_DQ<24>")
	)
	(gr_poly
		(pts
			(xy 143.364712 -239.422432) (xy 143.364712 -239.377982) (xy 143.16456 -239.377982) (xy 143.16456 -239.422432)
			(xy 143.264636 -239.522508)
		)
		(stroke
			(width 0)
			(type solid)
		)
		(fill yes)
		(layer "In11.Cu")
		(net "M_L_CPU1_SA_DQ<23>")
	)
	(gr_poly
		(pts
			(xy 143.364712 -238.20628) (xy 143.264636 -238.106204) (xy 143.16456 -238.20628) (xy 143.16456 -238.25073)
			(xy 143.364712 -238.25073)
		)
		(stroke
			(width 0)
			(type solid)
		)
		(fill yes)
		(layer "In11.Cu")
		(net "M_L_CPU1_SA_DQ<20>")
	)
	(gr_poly
		(pts
			(xy 143.364712 -237.802674) (xy 143.364712 -237.754922) (xy 143.16456 -237.754922) (xy 143.16456 -237.802674)
			(xy 143.264636 -237.902496)
		)
		(stroke
			(width 0)
			(type solid)
		)
		(fill yes)
		(layer "In11.Cu")
		(net "M_L_CPU1_SA_DQS_DP<7>")
	)
	(gr_poly
		(pts
			(xy 143.364712 -236.586014) (xy 143.264636 -236.486192) (xy 143.16456 -236.586014) (xy 143.16456 -236.633766)
			(xy 143.364712 -236.633766)
		)
		(stroke
			(width 0)
			(type solid)
		)
		(fill yes)
		(layer "In11.Cu")
		(net "M_L_CPU1_SA_DQS_DP<2>")
	)
	(gr_poly
		(pts
			(xy 143.364712 -236.182408) (xy 143.364712 -236.137958) (xy 143.16456 -236.137958) (xy 143.16456 -236.182408)
			(xy 143.264636 -236.282484)
		)
		(stroke
			(width 0)
			(type solid)
		)
		(fill yes)
		(layer "In11.Cu")
		(net "M_L_CPU1_SA_DQ<19>")
	)
	(gr_poly
		(pts
			(xy 143.364712 -234.966256) (xy 143.264636 -234.86618) (xy 143.16456 -234.966256) (xy 143.16456 -235.010706)
			(xy 143.364712 -235.010706)
		)
		(stroke
			(width 0)
			(type solid)
		)
		(fill yes)
		(layer "In11.Cu")
		(net "M_L_CPU1_SA_DQ<16>")
	)
	(gr_poly
		(pts
			(xy 143.364712 -234.562396) (xy 143.364712 -234.517946) (xy 143.16456 -234.517946) (xy 143.16456 -234.562396)
			(xy 143.264636 -234.662472)
		)
		(stroke
			(width 0)
			(type solid)
		)
		(fill yes)
		(layer "In11.Cu")
		(net "M_L_CPU1_SA_DQ<15>")
	)
	(gr_poly
		(pts
			(xy 143.364712 -233.346244) (xy 143.264636 -233.246168) (xy 143.16456 -233.346244) (xy 143.16456 -233.390694)
			(xy 143.364712 -233.390694)
		)
		(stroke
			(width 0)
			(type solid)
		)
		(fill yes)
		(layer "In11.Cu")
		(net "M_L_CPU1_SA_DQ<12>")
	)
	(gr_poly
		(pts
			(xy 143.364712 -232.942638) (xy 143.364712 -232.894886) (xy 143.16456 -232.894886) (xy 143.16456 -232.942638)
			(xy 143.264636 -233.04246)
		)
		(stroke
			(width 0)
			(type solid)
		)
		(fill yes)
		(layer "In11.Cu")
		(net "M_L_CPU1_SA_DQS_DP<6>")
	)
	(gr_poly
		(pts
			(xy 143.364712 -231.725978) (xy 143.264636 -231.626156) (xy 143.16456 -231.725978) (xy 143.16456 -231.77373)
			(xy 143.364712 -231.77373)
		)
		(stroke
			(width 0)
			(type solid)
		)
		(fill yes)
		(layer "In11.Cu")
		(net "M_L_CPU1_SA_DQS_DP<1>")
	)
	(gr_poly
		(pts
			(xy 143.364712 -231.322626) (xy 143.364712 -231.278176) (xy 143.16456 -231.278176) (xy 143.16456 -231.322626)
			(xy 143.264636 -231.422702)
		)
		(stroke
			(width 0)
			(type solid)
		)
		(fill yes)
		(layer "In11.Cu")
		(net "M_L_CPU1_SA_DQ<11>")
	)
	(gr_poly
		(pts
			(xy 143.364712 -230.10622) (xy 143.264636 -230.006144) (xy 143.16456 -230.10622) (xy 143.16456 -230.15067)
			(xy 143.364712 -230.15067)
		)
		(stroke
			(width 0)
			(type solid)
		)
		(fill yes)
		(layer "In11.Cu")
		(net "M_L_CPU1_SA_DQ<8>")
	)
	(gr_poly
		(pts
			(xy 143.364712 -229.702614) (xy 143.364712 -229.658164) (xy 143.16456 -229.658164) (xy 143.16456 -229.702614)
			(xy 143.264636 -229.80269)
		)
		(stroke
			(width 0)
			(type solid)
		)
		(fill yes)
		(layer "In11.Cu")
		(net "M_L_CPU1_SA_DQ<7>")
	)
	(gr_poly
		(pts
			(xy 143.364712 -228.486462) (xy 143.264636 -228.386386) (xy 143.16456 -228.486462) (xy 143.16456 -228.530912)
			(xy 143.364712 -228.530912)
		)
		(stroke
			(width 0)
			(type solid)
		)
		(fill yes)
		(layer "In11.Cu")
		(net "M_L_CPU1_SA_DQ<4>")
	)
	(gr_poly
		(pts
			(xy 143.364712 -228.082856) (xy 143.364712 -228.035104) (xy 143.16456 -228.035104) (xy 143.16456 -228.082856)
			(xy 143.264636 -228.182678)
		)
		(stroke
			(width 0)
			(type solid)
		)
		(fill yes)
		(layer "In11.Cu")
		(net "M_L_CPU1_SA_DQS_DP<5>")
	)
	(gr_poly
		(pts
			(xy 143.370808 -251.160026) (xy 143.270986 -251.05995) (xy 143.17091 -251.160026) (xy 143.17091 -251.204476)
			(xy 143.370808 -251.204476)
		)
		(stroke
			(width 0)
			(type solid)
		)
		(fill yes)
		(layer "In11.Cu")
		(net "M_L_CPU1_SA_CS_N<0>")
	)
	(gr_poly
		(pts
			(xy 143.420592 -226.999546) (xy 143.384016 -226.863148) (xy 143.342614 -226.839272) (xy 143.242792 -227.0125)
			(xy 143.28394 -227.036376)
		)
		(stroke
			(width 0)
			(type solid)
		)
		(fill yes)
		(layer "In11.Cu")
		(net "M_L_CPU1_SA_DQS_DN<0>")
	)
	(gr_poly
		(pts
			(xy 143.420846 -225.379026) (xy 143.384016 -225.242374) (xy 143.345662 -225.220022) (xy 143.245586 -225.39325)
			(xy 143.284194 -225.415602)
		)
		(stroke
			(width 0)
			(type solid)
		)
		(fill yes)
		(layer "In11.Cu")
		(net "M_L_CPU1_SA_DQ<3>")
	)
	(gr_poly
		(pts
			(xy 143.420846 -223.759014) (xy 143.384016 -223.622362) (xy 143.345662 -223.60001) (xy 143.245586 -223.773238)
			(xy 143.284194 -223.79559)
		)
		(stroke
			(width 0)
			(type solid)
		)
		(fill yes)
		(layer "In11.Cu")
		(net "M_L_CPU1_SA_DQ<2>")
	)
	(gr_poly
		(pts
			(xy 143.664686 -292.918134) (xy 143.56461 -292.818058) (xy 143.464534 -292.918134) (xy 143.464534 -292.962584)
			(xy 143.664686 -292.962584)
		)
		(stroke
			(width 0)
			(type solid)
		)
		(fill yes)
		(layer "In11.Cu")
		(net "M_L_CPU1_SB_DQ<29>")
	)
	(gr_poly
		(pts
			(xy 143.664686 -292.514274) (xy 143.664686 -292.469824) (xy 143.464534 -292.469824) (xy 143.464534 -292.514274)
			(xy 143.56461 -292.61435)
		)
		(stroke
			(width 0)
			(type solid)
		)
		(fill yes)
		(layer "In11.Cu")
		(net "M_L_CPU1_SB_DQ<30>")
	)
	(gr_poly
		(pts
			(xy 143.664686 -291.297868) (xy 143.56461 -291.198046) (xy 143.464534 -291.297868) (xy 143.464534 -291.34562)
			(xy 143.664686 -291.34562)
		)
		(stroke
			(width 0)
			(type solid)
		)
		(fill yes)
		(layer "In11.Cu")
		(net "M_L_CPU1_SB_DQS_DN<8>")
	)
	(gr_poly
		(pts
			(xy 143.664686 -290.894516) (xy 143.664686 -290.846764) (xy 143.464534 -290.846764) (xy 143.464534 -290.894516)
			(xy 143.56461 -290.994338)
		)
		(stroke
			(width 0)
			(type solid)
		)
		(fill yes)
		(layer "In11.Cu")
		(net "M_L_CPU1_SB_DQS_DN<3>")
	)
	(gr_poly
		(pts
			(xy 143.664686 -289.67811) (xy 143.56461 -289.578034) (xy 143.464534 -289.67811) (xy 143.464534 -289.72256)
			(xy 143.664686 -289.72256)
		)
		(stroke
			(width 0)
			(type solid)
		)
		(fill yes)
		(layer "In11.Cu")
		(net "M_L_CPU1_SB_DQ<25>")
	)
	(gr_poly
		(pts
			(xy 143.664686 -289.27425) (xy 143.664686 -289.2298) (xy 143.464534 -289.2298) (xy 143.464534 -289.27425)
			(xy 143.56461 -289.374326)
		)
		(stroke
			(width 0)
			(type solid)
		)
		(fill yes)
		(layer "In11.Cu")
		(net "M_L_CPU1_SB_DQ<26>")
	)
	(gr_poly
		(pts
			(xy 143.664686 -288.058098) (xy 143.56461 -287.958022) (xy 143.464534 -288.058098) (xy 143.464534 -288.102548)
			(xy 143.664686 -288.102548)
		)
		(stroke
			(width 0)
			(type solid)
		)
		(fill yes)
		(layer "In11.Cu")
		(net "M_L_CPU1_SB_DQ<21>")
	)
	(gr_poly
		(pts
			(xy 143.664686 -287.654492) (xy 143.664686 -287.610042) (xy 143.464534 -287.610042) (xy 143.464534 -287.654492)
			(xy 143.56461 -287.754568)
		)
		(stroke
			(width 0)
			(type solid)
		)
		(fill yes)
		(layer "In11.Cu")
		(net "M_L_CPU1_SB_DQ<22>")
	)
	(gr_poly
		(pts
			(xy 143.664686 -286.438086) (xy 143.56461 -286.33801) (xy 143.464534 -286.438086) (xy 143.464534 -286.485838)
			(xy 143.664686 -286.485838)
		)
		(stroke
			(width 0)
			(type solid)
		)
		(fill yes)
		(layer "In11.Cu")
		(net "M_L_CPU1_SB_DQS_DN<7>")
	)
	(gr_poly
		(pts
			(xy 143.664686 -286.034734) (xy 143.664686 -285.986982) (xy 143.464534 -285.986982) (xy 143.464534 -286.034734)
			(xy 143.56461 -286.134556)
		)
		(stroke
			(width 0)
			(type solid)
		)
		(fill yes)
		(layer "In11.Cu")
		(net "M_L_CPU1_SB_DQS_DN<2>")
	)
	(gr_poly
		(pts
			(xy 143.664686 -284.818328) (xy 143.56461 -284.718252) (xy 143.464534 -284.818328) (xy 143.464534 -284.862778)
			(xy 143.664686 -284.862778)
		)
		(stroke
			(width 0)
			(type solid)
		)
		(fill yes)
		(layer "In11.Cu")
		(net "M_L_CPU1_SB_DQ<17>")
	)
	(gr_poly
		(pts
			(xy 143.664686 -284.414468) (xy 143.664686 -284.370018) (xy 143.464534 -284.370018) (xy 143.464534 -284.414468)
			(xy 143.56461 -284.514544)
		)
		(stroke
			(width 0)
			(type solid)
		)
		(fill yes)
		(layer "In11.Cu")
		(net "M_L_CPU1_SB_DQ<18>")
	)
	(gr_poly
		(pts
			(xy 143.664686 -283.198316) (xy 143.56461 -283.09824) (xy 143.464534 -283.198316) (xy 143.464534 -283.242766)
			(xy 143.664686 -283.242766)
		)
		(stroke
			(width 0)
			(type solid)
		)
		(fill yes)
		(layer "In11.Cu")
		(net "M_L_CPU1_SB_DQ<13>")
	)
	(gr_poly
		(pts
			(xy 143.664686 -282.794456) (xy 143.664686 -282.750006) (xy 143.464534 -282.750006) (xy 143.464534 -282.794456)
			(xy 143.56461 -282.894532)
		)
		(stroke
			(width 0)
			(type solid)
		)
		(fill yes)
		(layer "In11.Cu")
		(net "M_L_CPU1_SB_DQ<14>")
	)
	(gr_poly
		(pts
			(xy 143.664686 -281.57805) (xy 143.56461 -281.478228) (xy 143.464534 -281.57805) (xy 143.464534 -281.625802)
			(xy 143.664686 -281.625802)
		)
		(stroke
			(width 0)
			(type solid)
		)
		(fill yes)
		(layer "In11.Cu")
		(net "M_L_CPU1_SB_DQS_DN<6>")
	)
	(gr_poly
		(pts
			(xy 143.664686 -281.174698) (xy 143.664686 -281.126946) (xy 143.464534 -281.126946) (xy 143.464534 -281.174698)
			(xy 143.56461 -281.27452)
		)
		(stroke
			(width 0)
			(type solid)
		)
		(fill yes)
		(layer "In11.Cu")
		(net "M_L_CPU1_SB_DQS_DN<1>")
	)
	(gr_poly
		(pts
			(xy 143.664686 -279.958292) (xy 143.56461 -279.858216) (xy 143.464534 -279.958292) (xy 143.464534 -280.002742)
			(xy 143.664686 -280.002742)
		)
		(stroke
			(width 0)
			(type solid)
		)
		(fill yes)
		(layer "In11.Cu")
		(net "M_L_CPU1_SB_DQ<9>")
	)
	(gr_poly
		(pts
			(xy 143.664686 -279.554432) (xy 143.664686 -279.509982) (xy 143.464534 -279.509982) (xy 143.464534 -279.554432)
			(xy 143.56461 -279.654508)
		)
		(stroke
			(width 0)
			(type solid)
		)
		(fill yes)
		(layer "In11.Cu")
		(net "M_L_CPU1_SB_DQ<10>")
	)
	(gr_poly
		(pts
			(xy 143.664686 -278.33828) (xy 143.56461 -278.238204) (xy 143.464534 -278.33828) (xy 143.464534 -278.38273)
			(xy 143.664686 -278.38273)
		)
		(stroke
			(width 0)
			(type solid)
		)
		(fill yes)
		(layer "In11.Cu")
		(net "M_L_CPU1_SB_DQ<5>")
	)
	(gr_poly
		(pts
			(xy 143.664686 -277.93442) (xy 143.664686 -277.88997) (xy 143.464534 -277.88997) (xy 143.464534 -277.93442)
			(xy 143.56461 -278.034496)
		)
		(stroke
			(width 0)
			(type solid)
		)
		(fill yes)
		(layer "In11.Cu")
		(net "M_L_CPU1_SB_DQ<6>")
	)
	(gr_poly
		(pts
			(xy 143.664686 -276.718014) (xy 143.56461 -276.618192) (xy 143.464534 -276.718014) (xy 143.464534 -276.765766)
			(xy 143.664686 -276.765766)
		)
		(stroke
			(width 0)
			(type solid)
		)
		(fill yes)
		(layer "In11.Cu")
		(net "M_L_CPU1_SB_DQS_DN<5>")
	)
	(gr_poly
		(pts
			(xy 143.664686 -276.314662) (xy 143.664686 -276.26691) (xy 143.464534 -276.26691) (xy 143.464534 -276.314662)
			(xy 143.56461 -276.414484)
		)
		(stroke
			(width 0)
			(type solid)
		)
		(fill yes)
		(layer "In11.Cu")
		(net "M_L_CPU1_SB_DQS_DN<0>")
	)
	(gr_poly
		(pts
			(xy 143.664686 -275.098256) (xy 143.56461 -274.99818) (xy 143.464534 -275.098256) (xy 143.464534 -275.142706)
			(xy 143.664686 -275.142706)
		)
		(stroke
			(width 0)
			(type solid)
		)
		(fill yes)
		(layer "In11.Cu")
		(net "M_L_CPU1_SB_DQ<1>")
	)
	(gr_poly
		(pts
			(xy 143.664686 -274.694396) (xy 143.664686 -274.649946) (xy 143.464534 -274.649946) (xy 143.464534 -274.694396)
			(xy 143.56461 -274.794472)
		)
		(stroke
			(width 0)
			(type solid)
		)
		(fill yes)
		(layer "In11.Cu")
		(net "M_L_CPU1_SB_DQ<2>")
	)
	(gr_poly
		(pts
			(xy 143.664686 -273.478244) (xy 143.56461 -273.378168) (xy 143.464534 -273.478244) (xy 143.464534 -273.522694)
			(xy 143.664686 -273.522694)
		)
		(stroke
			(width 0)
			(type solid)
		)
		(fill yes)
		(layer "In11.Cu")
		(net "M_L_CPU1_SB_CB<1>")
	)
	(gr_poly
		(pts
			(xy 143.664686 -273.074384) (xy 143.664686 -273.029934) (xy 143.464534 -273.029934) (xy 143.464534 -273.074384)
			(xy 143.56461 -273.17446)
		)
		(stroke
			(width 0)
			(type solid)
		)
		(fill yes)
		(layer "In11.Cu")
		(net "M_L_CPU1_SB_CB<2>")
	)
	(gr_poly
		(pts
			(xy 143.664686 -271.857978) (xy 143.56461 -271.758156) (xy 143.464534 -271.857978) (xy 143.464534 -271.90573)
			(xy 143.664686 -271.90573)
		)
		(stroke
			(width 0)
			(type solid)
		)
		(fill yes)
		(layer "In11.Cu")
		(net "M_L_CPU1_SB_DQS_DN<4>")
	)
	(gr_poly
		(pts
			(xy 143.664686 -271.454626) (xy 143.664686 -271.406874) (xy 143.464534 -271.406874) (xy 143.464534 -271.454626)
			(xy 143.56461 -271.554448)
		)
		(stroke
			(width 0)
			(type solid)
		)
		(fill yes)
		(layer "In11.Cu")
		(net "M_L_CPU1_SB_DQS_DN<9>")
	)
	(gr_poly
		(pts
			(xy 143.664686 -270.23822) (xy 143.56461 -270.138144) (xy 143.464534 -270.23822) (xy 143.464534 -270.28267)
			(xy 143.664686 -270.28267)
		)
		(stroke
			(width 0)
			(type solid)
		)
		(fill yes)
		(layer "In11.Cu")
		(net "M_L_CPU1_SB_CB<5>")
	)
	(gr_poly
		(pts
			(xy 143.664686 -269.83436) (xy 143.664686 -269.78991) (xy 143.464534 -269.78991) (xy 143.464534 -269.83436)
			(xy 143.56461 -269.934436)
		)
		(stroke
			(width 0)
			(type solid)
		)
		(fill yes)
		(layer "In11.Cu")
		(net "M_L_CPU1_SB_CB<6>")
	)
	(gr_poly
		(pts
			(xy 143.664686 -266.998196) (xy 143.56461 -266.89812) (xy 143.464534 -266.998196) (xy 143.464534 -267.042646)
			(xy 143.664686 -267.042646)
		)
		(stroke
			(width 0)
			(type solid)
		)
		(fill yes)
		(layer "In11.Cu")
		(net "M_L_CPU1_SA_RSP<0>")
	)
	(gr_poly
		(pts
			(xy 143.664686 -266.594336) (xy 143.664686 -266.549886) (xy 143.464534 -266.549886) (xy 143.464534 -266.594336)
			(xy 143.56461 -266.694412)
		)
		(stroke
			(width 0)
			(type solid)
		)
		(fill yes)
		(layer "In11.Cu")
		(net "M_L_CPU1_SB_CS_N<1>")
	)
	(gr_poly
		(pts
			(xy 143.664686 -265.378184) (xy 143.56461 -265.278108) (xy 143.464534 -265.378184) (xy 143.464534 -265.422634)
			(xy 143.664686 -265.422634)
		)
		(stroke
			(width 0)
			(type solid)
		)
		(fill yes)
		(layer "In11.Cu")
		(net "M_L_CPU1_SB_PAR")
	)
	(gr_poly
		(pts
			(xy 143.664686 -263.758172) (xy 143.56461 -263.658096) (xy 143.464534 -263.758172) (xy 143.464534 -263.802622)
			(xy 143.664686 -263.802622)
		)
		(stroke
			(width 0)
			(type solid)
		)
		(fill yes)
		(layer "In11.Cu")
		(net "M_L_CPU1_SB_CA<4>")
	)
	(gr_poly
		(pts
			(xy 143.664686 -263.354312) (xy 143.664686 -263.309862) (xy 143.464534 -263.309862) (xy 143.464534 -263.354312)
			(xy 143.56461 -263.454388)
		)
		(stroke
			(width 0)
			(type solid)
		)
		(fill yes)
		(layer "In11.Cu")
		(net "M_L_CPU1_SB_CA<3>")
	)
	(gr_poly
		(pts
			(xy 143.664686 -262.13816) (xy 143.56461 -262.038084) (xy 143.464534 -262.13816) (xy 143.464534 -262.18261)
			(xy 143.664686 -262.18261)
		)
		(stroke
			(width 0)
			(type solid)
		)
		(fill yes)
		(layer "In11.Cu")
		(net "M_L_CPU1_SB_CA<0>")
	)
	(gr_poly
		(pts
			(xy 143.75384 -222.265748) (xy 143.715232 -222.243396) (xy 143.578834 -222.279972) (xy 143.61541 -222.416624)
			(xy 143.653764 -222.438976)
		)
		(stroke
			(width 0)
			(type solid)
		)
		(fill yes)
		(layer "In11.Cu")
		(net "M_L_CPU1_SA_DQ<0>")
	)
	(gr_poly
		(pts
			(xy 143.754094 -223.884998) (xy 143.71574 -223.862646) (xy 143.579088 -223.899222) (xy 143.615664 -224.035874)
			(xy 143.654018 -224.058226)
		)
		(stroke
			(width 0)
			(type solid)
		)
		(fill yes)
		(layer "In11.Cu")
		(net "M_L_CPU1_SA_DQ<1>")
	)
	(gr_poly
		(pts
			(xy 143.756888 -227.126546) (xy 143.71574 -227.10267) (xy 143.579088 -227.1395) (xy 143.615664 -227.275898)
			(xy 143.657066 -227.299774)
		)
		(stroke
			(width 0)
			(type solid)
		)
		(fill yes)
		(layer "In11.Cu")
		(net "M_L_CPU1_SA_DQS_DN<5>")
	)
	(gr_poly
		(pts
			(xy 143.757142 -225.505772) (xy 143.715994 -225.48215) (xy 143.579342 -225.518726) (xy 143.615918 -225.655378)
			(xy 143.657066 -225.679)
		)
		(stroke
			(width 0)
			(type solid)
		)
		(fill yes)
		(layer "In11.Cu")
		(net "M_L_CPU1_SA_DQS_DP<0>")
	)
	(gr_poly
		(pts
			(xy 143.823944 -246.712486) (xy 143.823944 -246.664988) (xy 143.624046 -246.664988) (xy 143.624046 -246.712486)
			(xy 143.724122 -246.812562)
		)
		(stroke
			(width 0)
			(type solid)
		)
		(fill yes)
		(layer "In11.Cu")
		(net "M_L_CPU1_SA_DQS_DN<4>")
	)
	(gr_poly
		(pts
			(xy 143.823944 -241.85245) (xy 143.823944 -241.804952) (xy 143.624046 -241.804952) (xy 143.624046 -241.85245)
			(xy 143.724122 -241.952526)
		)
		(stroke
			(width 0)
			(type solid)
		)
		(fill yes)
		(layer "In11.Cu")
		(net "M_L_CPU1_SA_DQS_DN<3>")
	)
	(gr_poly
		(pts
			(xy 143.823944 -236.992414) (xy 143.823944 -236.944916) (xy 143.624046 -236.944916) (xy 143.624046 -236.992414)
			(xy 143.724122 -237.09249)
		)
		(stroke
			(width 0)
			(type solid)
		)
		(fill yes)
		(layer "In11.Cu")
		(net "M_L_CPU1_SA_DQS_DN<2>")
	)
	(gr_poly
		(pts
			(xy 143.823944 -230.512366) (xy 143.823944 -230.467916) (xy 143.624046 -230.467916) (xy 143.624046 -230.512366)
			(xy 143.724122 -230.612442)
		)
		(stroke
			(width 0)
			(type solid)
		)
		(fill yes)
		(layer "In11.Cu")
		(net "M_L_CPU1_SA_DQ<10>")
	)
	(gr_poly
		(pts
			(xy 143.8275 -254.812546) (xy 143.8275 -254.768096) (xy 143.627602 -254.768096) (xy 143.627602 -254.812546)
			(xy 143.727424 -254.912368)
		)
		(stroke
			(width 0)
			(type solid)
		)
		(fill yes)
		(layer "In11.Cu")
		(net "M_L_CPU1_SA_CA<5>")
	)
	(gr_poly
		(pts
			(xy 143.8275 -253.192534) (xy 143.8275 -253.148084) (xy 143.627602 -253.148084) (xy 143.627602 -253.192534)
			(xy 143.727424 -253.292356)
		)
		(stroke
			(width 0)
			(type solid)
		)
		(fill yes)
		(layer "In11.Cu")
		(net "M_L_CPU1_SA_CA<1>")
	)
	(gr_poly
		(pts
			(xy 143.8275 -248.332498) (xy 143.8275 -248.288048) (xy 143.627602 -248.288048) (xy 143.627602 -248.332498)
			(xy 143.727424 -248.43232)
		)
		(stroke
			(width 0)
			(type solid)
		)
		(fill yes)
		(layer "In11.Cu")
		(net "M_L_CPU1_SA_CB<6>")
	)
	(gr_poly
		(pts
			(xy 143.8275 -245.092474) (xy 143.8275 -245.048024) (xy 143.627602 -245.048024) (xy 143.627602 -245.092474)
			(xy 143.727424 -245.192296)
		)
		(stroke
			(width 0)
			(type solid)
		)
		(fill yes)
		(layer "In11.Cu")
		(net "M_L_CPU1_SA_CB<2>")
	)
	(gr_poly
		(pts
			(xy 143.8275 -243.472462) (xy 143.8275 -243.428012) (xy 143.627602 -243.428012) (xy 143.627602 -243.472462)
			(xy 143.727424 -243.572284)
		)
		(stroke
			(width 0)
			(type solid)
		)
		(fill yes)
		(layer "In11.Cu")
		(net "M_L_CPU1_SA_DQ<30>")
	)
	(gr_poly
		(pts
			(xy 143.8275 -240.232438) (xy 143.8275 -240.187988) (xy 143.627602 -240.187988) (xy 143.627602 -240.232438)
			(xy 143.727424 -240.33226)
		)
		(stroke
			(width 0)
			(type solid)
		)
		(fill yes)
		(layer "In11.Cu")
		(net "M_L_CPU1_SA_DQ<26>")
	)
	(gr_poly
		(pts
			(xy 143.8275 -238.612426) (xy 143.8275 -238.567976) (xy 143.627602 -238.567976) (xy 143.627602 -238.612426)
			(xy 143.727424 -238.712248)
		)
		(stroke
			(width 0)
			(type solid)
		)
		(fill yes)
		(layer "In11.Cu")
		(net "M_L_CPU1_SA_DQ<22>")
	)
	(gr_poly
		(pts
			(xy 143.8275 -235.372402) (xy 143.8275 -235.327952) (xy 143.627602 -235.327952) (xy 143.627602 -235.372402)
			(xy 143.727424 -235.472224)
		)
		(stroke
			(width 0)
			(type solid)
		)
		(fill yes)
		(layer "In11.Cu")
		(net "M_L_CPU1_SA_DQ<18>")
	)
	(gr_poly
		(pts
			(xy 143.8275 -233.75239) (xy 143.8275 -233.70794) (xy 143.627602 -233.70794) (xy 143.627602 -233.75239)
			(xy 143.727424 -233.852212)
		)
		(stroke
			(width 0)
			(type solid)
		)
		(fill yes)
		(layer "In11.Cu")
		(net "M_L_CPU1_SA_DQ<14>")
	)
	(gr_poly
		(pts
			(xy 143.834866 -256.432812) (xy 143.834866 -256.38506) (xy 143.634714 -256.38506) (xy 143.634714 -256.432812)
			(xy 143.73479 -256.532634)
		)
		(stroke
			(width 0)
			(type solid)
		)
		(fill yes)
		(layer "In11.Cu")
		(net "M_L_CPU1_CLK_DN<0>")
	)
	(gr_poly
		(pts
			(xy 143.834866 -251.970032) (xy 143.73479 -251.869956) (xy 143.634714 -251.970032) (xy 143.634714 -252.014228)
			(xy 143.834866 -252.014228)
		)
		(stroke
			(width 0)
			(type solid)
		)
		(fill yes)
		(layer "In11.Cu")
		(net "M_L_CPU1_SA_CS_N<1>")
	)
	(gr_poly
		(pts
			(xy 143.834866 -250.35637) (xy 143.73479 -250.256294) (xy 143.634714 -250.35637) (xy 143.634714 -250.40082)
			(xy 143.834866 -250.40082)
		)
		(stroke
			(width 0)
			(type solid)
		)
		(fill yes)
		(layer "In11.Cu")
		(net "M_L_CPU1_ALERT_R_N")
	)
	(gr_poly
		(pts
			(xy 143.834866 -240.636298) (xy 143.73479 -240.536222) (xy 143.634714 -240.636298) (xy 143.634714 -240.680748)
			(xy 143.834866 -240.680748)
		)
		(stroke
			(width 0)
			(type solid)
		)
		(fill yes)
		(layer "In11.Cu")
		(net "M_L_CPU1_SA_DQ<25>")
	)
	(gr_poly
		(pts
			(xy 143.834866 -232.132632) (xy 143.834866 -232.08488) (xy 143.634714 -232.08488) (xy 143.634714 -232.132632)
			(xy 143.73479 -232.232454)
		)
		(stroke
			(width 0)
			(type solid)
		)
		(fill yes)
		(layer "In11.Cu")
		(net "M_L_CPU1_SA_DQS_DN<1>")
	)
	(gr_poly
		(pts
			(xy 143.840962 -255.216406) (xy 143.740886 -255.11633) (xy 143.64081 -255.216406) (xy 143.64081 -255.260856)
			(xy 143.840962 -255.260856)
		)
		(stroke
			(width 0)
			(type solid)
		)
		(fill yes)
		(layer "In11.Cu")
		(net "M_L_CPU1_SA_CA<6>")
	)
	(gr_poly
		(pts
			(xy 143.840962 -253.596394) (xy 143.740886 -253.496318) (xy 143.64081 -253.596394) (xy 143.64081 -253.640844)
			(xy 143.840962 -253.640844)
		)
		(stroke
			(width 0)
			(type solid)
		)
		(fill yes)
		(layer "In11.Cu")
		(net "M_L_CPU1_SA_CA<2>")
	)
	(gr_poly
		(pts
			(xy 143.840962 -243.876322) (xy 143.740886 -243.776246) (xy 143.64081 -243.876322) (xy 143.64081 -243.920772)
			(xy 143.840962 -243.920772)
		)
		(stroke
			(width 0)
			(type solid)
		)
		(fill yes)
		(layer "In11.Cu")
		(net "M_L_CPU1_SA_DQ<29>")
	)
	(gr_poly
		(pts
			(xy 143.840962 -242.256056) (xy 143.740886 -242.15598) (xy 143.64081 -242.256056) (xy 143.64081 -242.303554)
			(xy 143.840962 -242.303554)
		)
		(stroke
			(width 0)
			(type solid)
		)
		(fill yes)
		(layer "In11.Cu")
		(net "M_L_CPU1_SA_DQS_DN<8>")
	)
	(gr_poly
		(pts
			(xy 143.840962 -239.016286) (xy 143.740886 -238.91621) (xy 143.64081 -239.016286) (xy 143.64081 -239.060736)
			(xy 143.840962 -239.060736)
		)
		(stroke
			(width 0)
			(type solid)
		)
		(fill yes)
		(layer "In11.Cu")
		(net "M_L_CPU1_SA_DQ<21>")
	)
	(gr_poly
		(pts
			(xy 143.840962 -235.776262) (xy 143.740886 -235.676186) (xy 143.64081 -235.776262) (xy 143.64081 -235.820712)
			(xy 143.840962 -235.820712)
		)
		(stroke
			(width 0)
			(type solid)
		)
		(fill yes)
		(layer "In11.Cu")
		(net "M_L_CPU1_SA_DQ<17>")
	)
	(gr_poly
		(pts
			(xy 143.840962 -234.15625) (xy 143.740886 -234.056174) (xy 143.64081 -234.15625) (xy 143.64081 -234.2007)
			(xy 143.840962 -234.2007)
		)
		(stroke
			(width 0)
			(type solid)
		)
		(fill yes)
		(layer "In11.Cu")
		(net "M_L_CPU1_SA_DQ<13>")
	)
	(gr_poly
		(pts
			(xy 143.848836 -248.73585) (xy 143.74876 -248.635774) (xy 143.648938 -248.73585) (xy 143.648938 -248.7803)
			(xy 143.848836 -248.7803)
		)
		(stroke
			(width 0)
			(type solid)
		)
		(fill yes)
		(layer "In11.Cu")
		(net "M_L_CPU1_SA_CB<5>")
	)
	(gr_poly
		(pts
			(xy 143.848836 -247.115838) (xy 143.74876 -247.015762) (xy 143.648938 -247.115838) (xy 143.648938 -247.163336)
			(xy 143.848836 -247.163336)
		)
		(stroke
			(width 0)
			(type solid)
		)
		(fill yes)
		(layer "In11.Cu")
		(net "M_L_CPU1_SA_DQS_DN<9>")
	)
	(gr_poly
		(pts
			(xy 143.848836 -245.495826) (xy 143.74876 -245.39575) (xy 143.648938 -245.495826) (xy 143.648938 -245.540276)
			(xy 143.848836 -245.540276)
		)
		(stroke
			(width 0)
			(type solid)
		)
		(fill yes)
		(layer "In11.Cu")
		(net "M_L_CPU1_SA_CB<1>")
	)
	(gr_poly
		(pts
			(xy 143.848836 -237.395766) (xy 143.74876 -237.29569) (xy 143.648938 -237.395766) (xy 143.648938 -237.443264)
			(xy 143.848836 -237.443264)
		)
		(stroke
			(width 0)
			(type solid)
		)
		(fill yes)
		(layer "In11.Cu")
		(net "M_L_CPU1_SA_DQS_DN<7>")
	)
	(gr_poly
		(pts
			(xy 143.848836 -232.53573) (xy 143.74876 -232.435654) (xy 143.648938 -232.53573) (xy 143.648938 -232.583228)
			(xy 143.848836 -232.583228)
		)
		(stroke
			(width 0)
			(type solid)
		)
		(fill yes)
		(layer "In11.Cu")
		(net "M_L_CPU1_SA_DQS_DN<6>")
	)
	(gr_poly
		(pts
			(xy 143.88973 -224.57029) (xy 143.853154 -224.433638) (xy 143.814546 -224.41154) (xy 143.71447 -224.584768)
			(xy 143.753078 -224.606866)
		)
		(stroke
			(width 0)
			(type solid)
		)
		(fill yes)
		(layer "In11.Cu")
		(net "M_L_CPU1_SA_DQ<3>")
	)
	(gr_poly
		(pts
			(xy 143.890492 -227.809552) (xy 143.853916 -227.673154) (xy 143.812514 -227.649278) (xy 143.712692 -227.822506)
			(xy 143.75384 -227.846128)
		)
		(stroke
			(width 0)
			(type solid)
		)
		(fill yes)
		(layer "In11.Cu")
		(net "M_L_CPU1_SA_DQS_DP<5>")
	)
	(gr_poly
		(pts
			(xy 143.89735 -222.936562) (xy 143.84909 -222.80372) (xy 143.808704 -222.784924) (xy 143.724122 -222.966026)
			(xy 143.764508 -222.984822)
		)
		(stroke
			(width 0)
			(type solid)
		)
		(fill yes)
		(layer "In11.Cu")
		(net "M_L_CPU1_SA_DQ<2>")
	)
	(gr_poly
		(pts
			(xy 144.053814 -293.874952) (xy 143.953738 -293.701724) (xy 143.915384 -293.724076) (xy 143.878554 -293.860728)
			(xy 144.015206 -293.897304)
		)
		(stroke
			(width 0)
			(type solid)
		)
		(fill yes)
		(layer "In11.Cu")
		(net "M_L_CPU1_SB_DQ<31>")
	)
	(gr_poly
		(pts
			(xy 144.053814 -268.877542) (xy 144.015206 -268.85519) (xy 143.878554 -268.891766) (xy 143.915384 -269.028418)
			(xy 143.953738 -269.05077)
		)
		(stroke
			(width 0)
			(type solid)
		)
		(fill yes)
		(layer "In11.Cu")
		(net "M_L_CPU1_SB_CB<4>")
	)
	(gr_poly
		(pts
			(xy 144.123918 -285.628334) (xy 144.024096 -285.528258) (xy 143.92402 -285.628334) (xy 143.92402 -285.675832)
			(xy 144.123918 -285.675832)
		)
		(stroke
			(width 0)
			(type solid)
		)
		(fill yes)
		(layer "In11.Cu")
		(net "M_L_CPU1_SB_DQS_DP<2>")
	)
	(gr_poly
		(pts
			(xy 144.123918 -280.768298) (xy 144.024096 -280.668222) (xy 143.92402 -280.768298) (xy 143.92402 -280.815796)
			(xy 144.123918 -280.815796)
		)
		(stroke
			(width 0)
			(type solid)
		)
		(fill yes)
		(layer "In11.Cu")
		(net "M_L_CPU1_SB_DQS_DP<1>")
	)
	(gr_poly
		(pts
			(xy 144.123918 -275.908262) (xy 144.024096 -275.808186) (xy 143.92402 -275.908262) (xy 143.92402 -275.95576)
			(xy 144.123918 -275.95576)
		)
		(stroke
			(width 0)
			(type solid)
		)
		(fill yes)
		(layer "In11.Cu")
		(net "M_L_CPU1_SB_DQS_DP<0>")
	)
	(gr_poly
		(pts
			(xy 144.123918 -264.561828) (xy 144.023842 -264.461752) (xy 143.923766 -264.561828) (xy 143.923766 -264.606278)
			(xy 144.123918 -264.606278)
		)
		(stroke
			(width 0)
			(type solid)
		)
		(fill yes)
		(layer "In11.Cu")
		(net "M_L_CPU1_SB_CA<6>")
	)
	(gr_poly
		(pts
			(xy 144.127474 -288.868104) (xy 144.027398 -288.768282) (xy 143.927576 -288.868104) (xy 143.927576 -288.912554)
			(xy 144.127474 -288.912554)
		)
		(stroke
			(width 0)
			(type solid)
		)
		(fill yes)
		(layer "In11.Cu")
		(net "M_L_CPU1_SB_DQ<24>")
	)
	(gr_poly
		(pts
			(xy 144.127474 -284.008322) (xy 144.027398 -283.9085) (xy 143.927576 -284.008322) (xy 143.927576 -284.052772)
			(xy 144.127474 -284.052772)
		)
		(stroke
			(width 0)
			(type solid)
		)
		(fill yes)
		(layer "In11.Cu")
		(net "M_L_CPU1_SB_DQ<16>")
	)
	(gr_poly
		(pts
			(xy 144.127474 -282.38831) (xy 144.027398 -282.288488) (xy 143.927576 -282.38831) (xy 143.927576 -282.43276)
			(xy 144.127474 -282.43276)
		)
		(stroke
			(width 0)
			(type solid)
		)
		(fill yes)
		(layer "In11.Cu")
		(net "M_L_CPU1_SB_DQ<12>")
	)
	(gr_poly
		(pts
			(xy 144.127474 -279.148286) (xy 144.027398 -279.048464) (xy 143.927576 -279.148286) (xy 143.927576 -279.192736)
			(xy 144.127474 -279.192736)
		)
		(stroke
			(width 0)
			(type solid)
		)
		(fill yes)
		(layer "In11.Cu")
		(net "M_L_CPU1_SB_DQ<8>")
	)
	(gr_poly
		(pts
			(xy 144.127474 -277.528274) (xy 144.027398 -277.428452) (xy 143.927576 -277.528274) (xy 143.927576 -277.572724)
			(xy 144.127474 -277.572724)
		)
		(stroke
			(width 0)
			(type solid)
		)
		(fill yes)
		(layer "In11.Cu")
		(net "M_L_CPU1_SB_DQ<4>")
	)
	(gr_poly
		(pts
			(xy 144.127474 -274.28825) (xy 144.027398 -274.188428) (xy 143.927576 -274.28825) (xy 143.927576 -274.3327)
			(xy 144.127474 -274.3327)
		)
		(stroke
			(width 0)
			(type solid)
		)
		(fill yes)
		(layer "In11.Cu")
		(net "M_L_CPU1_SB_DQ<0>")
	)
	(gr_poly
		(pts
			(xy 144.127474 -262.948166) (xy 144.027398 -262.848344) (xy 143.927576 -262.948166) (xy 143.927576 -262.992616)
			(xy 144.127474 -262.992616)
		)
		(stroke
			(width 0)
			(type solid)
		)
		(fill yes)
		(layer "In11.Cu")
		(net "M_L_CPU1_SB_CA<2>")
	)
	(gr_poly
		(pts
			(xy 144.12849 -271.047972) (xy 144.028668 -270.94815) (xy 143.928592 -271.047972) (xy 143.928592 -271.095724)
			(xy 144.12849 -271.095724)
		)
		(stroke
			(width 0)
			(type solid)
		)
		(fill yes)
		(layer "In11.Cu")
		(net "M_L_CPU1_SB_DQS_DP<9>")
	)
	(gr_poly
		(pts
			(xy 144.12849 -267.808202) (xy 144.028668 -267.708126) (xy 143.928592 -267.808202) (xy 143.928592 -267.852652)
			(xy 144.12849 -267.852652)
		)
		(stroke
			(width 0)
			(type solid)
		)
		(fill yes)
		(layer "In11.Cu")
		(net "M_L_CPU1_SB_RSP<0>")
	)
	(gr_poly
		(pts
			(xy 144.13484 -288.464498) (xy 144.13484 -288.420048) (xy 143.934688 -288.420048) (xy 143.934688 -288.464498)
			(xy 144.034764 -288.564574)
		)
		(stroke
			(width 0)
			(type solid)
		)
		(fill yes)
		(layer "In11.Cu")
		(net "M_L_CPU1_SB_DQ<23>")
	)
	(gr_poly
		(pts
			(xy 144.13484 -287.248092) (xy 144.034764 -287.148016) (xy 143.934688 -287.248092) (xy 143.934688 -287.292542)
			(xy 144.13484 -287.292542)
		)
		(stroke
			(width 0)
			(type solid)
		)
		(fill yes)
		(layer "In11.Cu")
		(net "M_L_CPU1_SB_DQ<20>")
	)
	(gr_poly
		(pts
			(xy 144.13484 -286.844486) (xy 144.13484 -286.796734) (xy 143.934688 -286.796734) (xy 143.934688 -286.844486)
			(xy 144.034764 -286.944562)
		)
		(stroke
			(width 0)
			(type solid)
		)
		(fill yes)
		(layer "In11.Cu")
		(net "M_L_CPU1_SB_DQS_DP<7>")
	)
	(gr_poly
		(pts
			(xy 144.13484 -281.984704) (xy 144.13484 -281.936952) (xy 143.934688 -281.936952) (xy 143.934688 -281.984704)
			(xy 144.034764 -282.084526)
		)
		(stroke
			(width 0)
			(type solid)
		)
		(fill yes)
		(layer "In11.Cu")
		(net "M_L_CPU1_SB_DQS_DP<6>")
	)
	(gr_poly
		(pts
			(xy 144.13484 -272.668238) (xy 144.034764 -272.568162) (xy 143.934688 -272.668238) (xy 143.934688 -272.712688)
			(xy 144.13484 -272.712688)
		)
		(stroke
			(width 0)
			(type solid)
		)
		(fill yes)
		(layer "In11.Cu")
		(net "M_L_CPU1_SB_CB<0>")
	)
	(gr_poly
		(pts
			(xy 144.13484 -272.264632) (xy 144.13484 -272.21688) (xy 143.934688 -272.21688) (xy 143.934688 -272.264632)
			(xy 144.034764 -272.364454)
		)
		(stroke
			(width 0)
			(type solid)
		)
		(fill yes)
		(layer "In11.Cu")
		(net "M_L_CPU1_SB_DQS_DP<4>")
	)
	(gr_poly
		(pts
			(xy 144.140936 -290.084256) (xy 144.140936 -290.039806) (xy 143.941038 -290.039806) (xy 143.941038 -290.084256)
			(xy 144.04086 -290.184332)
		)
		(stroke
			(width 0)
			(type solid)
		)
		(fill yes)
		(layer "In11.Cu")
		(net "M_L_CPU1_SB_DQ<27>")
	)
	(gr_poly
		(pts
			(xy 144.140936 -280.364438) (xy 144.140936 -280.319988) (xy 143.941038 -280.319988) (xy 143.941038 -280.364438)
			(xy 144.04086 -280.464514)
		)
		(stroke
			(width 0)
			(type solid)
		)
		(fill yes)
		(layer "In11.Cu")
		(net "M_L_CPU1_SB_DQ<11>")
	)
	(gr_poly
		(pts
			(xy 144.140936 -278.744426) (xy 144.140936 -278.699976) (xy 143.941038 -278.699976) (xy 143.941038 -278.744426)
			(xy 144.04086 -278.844502)
		)
		(stroke
			(width 0)
			(type solid)
		)
		(fill yes)
		(layer "In11.Cu")
		(net "M_L_CPU1_SB_DQ<7>")
	)
	(gr_poly
		(pts
			(xy 144.140936 -277.124668) (xy 144.140936 -277.07717) (xy 143.941038 -277.07717) (xy 143.941038 -277.124668)
			(xy 144.04086 -277.224744)
		)
		(stroke
			(width 0)
			(type solid)
		)
		(fill yes)
		(layer "In11.Cu")
		(net "M_L_CPU1_SB_DQS_DP<5>")
	)
	(gr_poly
		(pts
			(xy 144.140936 -275.504402) (xy 144.140936 -275.459952) (xy 143.941038 -275.459952) (xy 143.941038 -275.504402)
			(xy 144.04086 -275.604478)
		)
		(stroke
			(width 0)
			(type solid)
		)
		(fill yes)
		(layer "In11.Cu")
		(net "M_L_CPU1_SB_DQ<3>")
	)
	(gr_poly
		(pts
			(xy 144.140936 -273.88439) (xy 144.140936 -273.83994) (xy 143.941038 -273.83994) (xy 143.941038 -273.88439)
			(xy 144.04086 -273.984466)
		)
		(stroke
			(width 0)
			(type solid)
		)
		(fill yes)
		(layer "In11.Cu")
		(net "M_L_CPU1_SB_CB<3>")
	)
	(gr_poly
		(pts
			(xy 144.140936 -270.644366) (xy 144.140936 -270.599916) (xy 143.941038 -270.599916) (xy 143.941038 -270.644366)
			(xy 144.04086 -270.744442)
		)
		(stroke
			(width 0)
			(type solid)
		)
		(fill yes)
		(layer "In11.Cu")
		(net "M_L_CPU1_SB_CB<7>")
	)
	(gr_poly
		(pts
			(xy 144.14881 -285.224982) (xy 144.14881 -285.180532) (xy 143.948912 -285.180532) (xy 143.948912 -285.224982)
			(xy 144.048734 -285.325058)
		)
		(stroke
			(width 0)
			(type solid)
		)
		(fill yes)
		(layer "In11.Cu")
		(net "M_L_CPU1_SB_DQ<19>")
	)
	(gr_poly
		(pts
			(xy 144.14881 -283.60497) (xy 144.14881 -283.56052) (xy 143.948912 -283.56052) (xy 143.948912 -283.60497)
			(xy 144.048734 -283.705046)
		)
		(stroke
			(width 0)
			(type solid)
		)
		(fill yes)
		(layer "In11.Cu")
		(net "M_L_CPU1_SB_DQ<15>")
	)
	(gr_poly
		(pts
			(xy 144.14881 -265.784838) (xy 144.14881 -265.740388) (xy 143.948912 -265.740388) (xy 143.948912 -265.784838)
			(xy 144.048734 -265.884914)
		)
		(stroke
			(width 0)
			(type solid)
		)
		(fill yes)
		(layer "In11.Cu")
		(net "M_L_CPU1_SB_CS_N<0>")
	)
	(gr_poly
		(pts
			(xy 144.14881 -264.164826) (xy 144.14881 -264.120376) (xy 143.948912 -264.120376) (xy 143.948912 -264.164826)
			(xy 144.048734 -264.264902)
		)
		(stroke
			(width 0)
			(type solid)
		)
		(fill yes)
		(layer "In11.Cu")
		(net "M_L_CPU1_SB_CA<5>")
	)
	(gr_poly
		(pts
			(xy 144.14881 -262.544814) (xy 144.14881 -262.500364) (xy 143.948912 -262.500364) (xy 143.948912 -262.544814)
			(xy 144.048734 -262.64489)
		)
		(stroke
			(width 0)
			(type solid)
		)
		(fill yes)
		(layer "In11.Cu")
		(net "M_L_CPU1_SB_CA<1>")
	)
	(gr_poly
		(pts
			(xy 144.15389 -293.328344) (xy 144.190466 -293.191692) (xy 144.054068 -293.155116) (xy 144.01546 -293.177468)
			(xy 144.115536 -293.350696)
		)
		(stroke
			(width 0)
			(type solid)
		)
		(fill yes)
		(layer "In11.Cu")
		(net "M_L_CPU1_SB_DQ<29>")
	)
	(gr_poly
		(pts
			(xy 144.190466 -269.560802) (xy 144.15389 -269.42415) (xy 144.115536 -269.401798) (xy 144.01546 -269.575026)
			(xy 144.054068 -269.597378)
		)
		(stroke
			(width 0)
			(type solid)
		)
		(fill yes)
		(layer "In11.Cu")
		(net "M_L_CPU1_SB_CB<6>")
	)
	(gr_poly
		(pts
			(xy 144.224248 -223.074992) (xy 144.185894 -223.05264) (xy 144.049242 -223.089216) (xy 144.085818 -223.225868)
			(xy 144.124426 -223.24822)
		)
		(stroke
			(width 0)
			(type solid)
		)
		(fill yes)
		(layer "In11.Cu")
		(net "M_L_CPU1_SA_DQ<1>")
	)
	(gr_poly
		(pts
			(xy 144.227042 -226.31654) (xy 144.185894 -226.292664) (xy 144.049242 -226.329494) (xy 144.085818 -226.465892)
			(xy 144.12722 -226.489768)
		)
		(stroke
			(width 0)
			(type solid)
		)
		(fill yes)
		(layer "In11.Cu")
		(net "M_L_CPU1_SA_DQS_DN<5>")
	)
	(gr_poly
		(pts
			(xy 144.292828 -249.143012) (xy 144.292828 -249.098562) (xy 144.09293 -249.098562) (xy 144.09293 -249.143012)
			(xy 144.193006 -249.243088)
		)
		(stroke
			(width 0)
			(type solid)
		)
		(fill yes)
		(layer "In11.Cu")
		(net "M_L_CPU1_SA_CB<7>")
	)
	(gr_poly
		(pts
			(xy 144.292828 -247.523) (xy 144.292828 -247.475502) (xy 144.09293 -247.475502) (xy 144.09293 -247.523)
			(xy 144.193006 -247.623076)
		)
		(stroke
			(width 0)
			(type solid)
		)
		(fill yes)
		(layer "In11.Cu")
		(net "M_L_CPU1_SA_DQS_DP<9>")
	)
	(gr_poly
		(pts
			(xy 144.292828 -245.902988) (xy 144.292828 -245.858538) (xy 144.09293 -245.858538) (xy 144.09293 -245.902988)
			(xy 144.193006 -246.003064)
		)
		(stroke
			(width 0)
			(type solid)
		)
		(fill yes)
		(layer "In11.Cu")
		(net "M_L_CPU1_SA_CB<3>")
	)
	(gr_poly
		(pts
			(xy 144.292828 -237.802928) (xy 144.292828 -237.75543) (xy 144.09293 -237.75543) (xy 144.09293 -237.802928)
			(xy 144.193006 -237.903004)
		)
		(stroke
			(width 0)
			(type solid)
		)
		(fill yes)
		(layer "In11.Cu")
		(net "M_L_CPU1_SA_DQS_DP<7>")
	)
	(gr_poly
		(pts
			(xy 144.292828 -232.942892) (xy 144.292828 -232.895394) (xy 144.09293 -232.895394) (xy 144.09293 -232.942892)
			(xy 144.193006 -233.042968)
		)
		(stroke
			(width 0)
			(type solid)
		)
		(fill yes)
		(layer "In11.Cu")
		(net "M_L_CPU1_SA_DQS_DP<6>")
	)
	(gr_poly
		(pts
			(xy 144.293844 -256.026412) (xy 144.194022 -255.926336) (xy 144.093946 -256.026412) (xy 144.093946 -256.07391)
			(xy 144.293844 -256.07391)
		)
		(stroke
			(width 0)
			(type solid)
		)
		(fill yes)
		(layer "In11.Cu")
		(net "M_L_CPU1_CLK_DP<0>")
	)
	(gr_poly
		(pts
			(xy 144.299178 -255.622552) (xy 144.299178 -255.578102) (xy 144.099026 -255.578102) (xy 144.099026 -255.622552)
			(xy 144.199102 -255.722628)
		)
		(stroke
			(width 0)
			(type solid)
		)
		(fill yes)
		(layer "In11.Cu")
		(net "M_L_CPU1_SA_PAR")
	)
	(gr_poly
		(pts
			(xy 144.299178 -254.00254) (xy 144.299178 -253.95809) (xy 144.099026 -253.95809) (xy 144.099026 -254.00254)
			(xy 144.199102 -254.102616)
		)
		(stroke
			(width 0)
			(type solid)
		)
		(fill yes)
		(layer "In11.Cu")
		(net "M_L_CPU1_SA_CA<3>")
	)
	(gr_poly
		(pts
			(xy 144.299178 -244.282468) (xy 144.299178 -244.238018) (xy 144.099026 -244.238018) (xy 144.099026 -244.282468)
			(xy 144.199102 -244.382544)
		)
		(stroke
			(width 0)
			(type solid)
		)
		(fill yes)
		(layer "In11.Cu")
		(net "M_L_CPU1_SA_DQ<31>")
	)
	(gr_poly
		(pts
			(xy 144.299178 -242.66271) (xy 144.299178 -242.615212) (xy 144.099026 -242.615212) (xy 144.099026 -242.66271)
			(xy 144.199102 -242.762786)
		)
		(stroke
			(width 0)
			(type solid)
		)
		(fill yes)
		(layer "In11.Cu")
		(net "M_L_CPU1_SA_DQS_DP<8>")
	)
	(gr_poly
		(pts
			(xy 144.299178 -239.422432) (xy 144.299178 -239.377982) (xy 144.099026 -239.377982) (xy 144.099026 -239.422432)
			(xy 144.199102 -239.522508)
		)
		(stroke
			(width 0)
			(type solid)
		)
		(fill yes)
		(layer "In11.Cu")
		(net "M_L_CPU1_SA_DQ<23>")
	)
	(gr_poly
		(pts
			(xy 144.299178 -236.182408) (xy 144.299178 -236.137958) (xy 144.099026 -236.137958) (xy 144.099026 -236.182408)
			(xy 144.199102 -236.282484)
		)
		(stroke
			(width 0)
			(type solid)
		)
		(fill yes)
		(layer "In11.Cu")
		(net "M_L_CPU1_SA_DQ<19>")
	)
	(gr_poly
		(pts
			(xy 144.299178 -234.562396) (xy 144.299178 -234.517946) (xy 144.099026 -234.517946) (xy 144.099026 -234.562396)
			(xy 144.199102 -234.662472)
		)
		(stroke
			(width 0)
			(type solid)
		)
		(fill yes)
		(layer "In11.Cu")
		(net "M_L_CPU1_SA_DQ<15>")
	)
	(gr_poly
		(pts
			(xy 144.304766 -250.762516) (xy 144.304766 -250.718066) (xy 144.104614 -250.718066) (xy 144.104614 -250.762516)
			(xy 144.20469 -250.862592)
		)
		(stroke
			(width 0)
			(type solid)
		)
		(fill yes)
		(layer "In11.Cu")
		(net "M_L_CPU1_RESET_N")
	)
	(gr_poly
		(pts
			(xy 144.304766 -241.042444) (xy 144.304766 -240.997994) (xy 144.104614 -240.997994) (xy 144.104614 -241.042444)
			(xy 144.20469 -241.14252)
		)
		(stroke
			(width 0)
			(type solid)
		)
		(fill yes)
		(layer "In11.Cu")
		(net "M_L_CPU1_SA_DQ<27>")
	)
	(gr_poly
		(pts
			(xy 144.30502 -231.725978) (xy 144.204944 -231.626156) (xy 144.104868 -231.725978) (xy 144.104868 -231.77373)
			(xy 144.30502 -231.77373)
		)
		(stroke
			(width 0)
			(type solid)
		)
		(fill yes)
		(layer "In11.Cu")
		(net "M_L_CPU1_SA_DQS_DP<1>")
	)
	(gr_poly
		(pts
			(xy 144.310862 -254.4064) (xy 144.21104 -254.306578) (xy 144.110964 -254.4064) (xy 144.110964 -254.45085)
			(xy 144.310862 -254.45085)
		)
		(stroke
			(width 0)
			(type solid)
		)
		(fill yes)
		(layer "In11.Cu")
		(net "M_L_CPU1_SA_CA<4>")
	)
	(gr_poly
		(pts
			(xy 144.310862 -252.786388) (xy 144.21104 -252.686566) (xy 144.110964 -252.786388) (xy 144.110964 -252.830838)
			(xy 144.310862 -252.830838)
		)
		(stroke
			(width 0)
			(type solid)
		)
		(fill yes)
		(layer "In11.Cu")
		(net "M_L_CPU1_SA_CA<0>")
	)
	(gr_poly
		(pts
			(xy 144.310862 -247.926352) (xy 144.21104 -247.82653) (xy 144.110964 -247.926352) (xy 144.110964 -247.970802)
			(xy 144.310862 -247.970802)
		)
		(stroke
			(width 0)
			(type solid)
		)
		(fill yes)
		(layer "In11.Cu")
		(net "M_L_CPU1_SA_CB<4>")
	)
	(gr_poly
		(pts
			(xy 144.310862 -244.686328) (xy 144.21104 -244.586506) (xy 144.110964 -244.686328) (xy 144.110964 -244.730778)
			(xy 144.310862 -244.730778)
		)
		(stroke
			(width 0)
			(type solid)
		)
		(fill yes)
		(layer "In11.Cu")
		(net "M_L_CPU1_SA_CB<0>")
	)
	(gr_poly
		(pts
			(xy 144.310862 -243.066316) (xy 144.21104 -242.966494) (xy 144.110964 -243.066316) (xy 144.110964 -243.110766)
			(xy 144.310862 -243.110766)
		)
		(stroke
			(width 0)
			(type solid)
		)
		(fill yes)
		(layer "In11.Cu")
		(net "M_L_CPU1_SA_DQ<28>")
	)
	(gr_poly
		(pts
			(xy 144.310862 -239.826292) (xy 144.21104 -239.72647) (xy 144.110964 -239.826292) (xy 144.110964 -239.870742)
			(xy 144.310862 -239.870742)
		)
		(stroke
			(width 0)
			(type solid)
		)
		(fill yes)
		(layer "In11.Cu")
		(net "M_L_CPU1_SA_DQ<24>")
	)
	(gr_poly
		(pts
			(xy 144.310862 -238.20628) (xy 144.21104 -238.106458) (xy 144.110964 -238.20628) (xy 144.110964 -238.25073)
			(xy 144.310862 -238.25073)
		)
		(stroke
			(width 0)
			(type solid)
		)
		(fill yes)
		(layer "In11.Cu")
		(net "M_L_CPU1_SA_DQ<20>")
	)
	(gr_poly
		(pts
			(xy 144.310862 -234.966256) (xy 144.21104 -234.866434) (xy 144.110964 -234.966256) (xy 144.110964 -235.010706)
			(xy 144.310862 -235.010706)
		)
		(stroke
			(width 0)
			(type solid)
		)
		(fill yes)
		(layer "In11.Cu")
		(net "M_L_CPU1_SA_DQ<16>")
	)
	(gr_poly
		(pts
			(xy 144.310862 -233.346244) (xy 144.21104 -233.246422) (xy 144.110964 -233.346244) (xy 144.110964 -233.390694)
			(xy 144.310862 -233.390694)
		)
		(stroke
			(width 0)
			(type solid)
		)
		(fill yes)
		(layer "In11.Cu")
		(net "M_L_CPU1_SA_DQ<12>")
	)
	(gr_poly
		(pts
			(xy 144.314418 -246.30634) (xy 144.214342 -246.206264) (xy 144.11452 -246.30634) (xy 144.11452 -246.353838)
			(xy 144.314418 -246.353838)
		)
		(stroke
			(width 0)
			(type solid)
		)
		(fill yes)
		(layer "In11.Cu")
		(net "M_L_CPU1_SA_DQS_DP<4>")
	)
	(gr_poly
		(pts
			(xy 144.314418 -241.446304) (xy 144.214342 -241.346228) (xy 144.11452 -241.446304) (xy 144.11452 -241.493802)
			(xy 144.314418 -241.493802)
		)
		(stroke
			(width 0)
			(type solid)
		)
		(fill yes)
		(layer "In11.Cu")
		(net "M_L_CPU1_SA_DQS_DP<3>")
	)
	(gr_poly
		(pts
			(xy 144.314418 -236.586268) (xy 144.214342 -236.486192) (xy 144.11452 -236.586268) (xy 144.11452 -236.633766)
			(xy 144.314418 -236.633766)
		)
		(stroke
			(width 0)
			(type solid)
		)
		(fill yes)
		(layer "In11.Cu")
		(net "M_L_CPU1_SA_DQS_DP<2>")
	)
	(gr_poly
		(pts
			(xy 144.31772 -251.159772) (xy 144.217644 -251.059696) (xy 144.117822 -251.159772) (xy 144.117822 -251.204222)
			(xy 144.31772 -251.204222)
		)
		(stroke
			(width 0)
			(type solid)
		)
		(fill yes)
		(layer "In11.Cu")
		(net "M_L_CPU1_SA_CS_N<0>")
	)
	(gr_poly
		(pts
			(xy 144.35963 -222.141796) (xy 144.323054 -222.005144) (xy 144.284446 -221.982792) (xy 144.18437 -222.15602)
			(xy 144.222978 -222.178372)
		)
		(stroke
			(width 0)
			(type solid)
		)
		(fill yes)
		(layer "In11.Cu")
		(net "M_L_CPU1_SA_DQ<2>")
	)
	(gr_poly
		(pts
			(xy 144.360646 -226.999546) (xy 144.32407 -226.863148) (xy 144.282668 -226.839272) (xy 144.182846 -227.0125)
			(xy 144.223994 -227.036376)
		)
		(stroke
			(width 0)
			(type solid)
		)
		(fill yes)
		(layer "In11.Cu")
		(net "M_L_CPU1_SA_DQS_DP<5>")
	)
	(gr_poly
		(pts
			(xy 144.3609 -225.379026) (xy 144.324324 -225.242374) (xy 144.282922 -225.218752) (xy 144.1831 -225.39198)
			(xy 144.224248 -225.415602)
		)
		(stroke
			(width 0)
			(type solid)
		)
		(fill yes)
		(layer "In11.Cu")
		(net "M_L_CPU1_SA_DQS_DN<0>")
	)
	(gr_poly
		(pts
			(xy 144.361154 -223.758252) (xy 144.324324 -223.6216) (xy 144.28597 -223.599502) (xy 144.185894 -223.77273)
			(xy 144.224502 -223.794828)
		)
		(stroke
			(width 0)
			(type solid)
		)
		(fill yes)
		(layer "In11.Cu")
		(net "M_L_CPU1_SA_DQ<3>")
	)
	(gr_poly
		(pts
			(xy 144.523714 -294.684958) (xy 144.423638 -294.51173) (xy 144.385284 -294.534082) (xy 144.348454 -294.670734)
			(xy 144.485106 -294.70731)
		)
		(stroke
			(width 0)
			(type solid)
		)
		(fill yes)
		(layer "In11.Cu")
		(net "M_L_CPU1_SB_DQ<31>")
	)
	(gr_poly
		(pts
			(xy 144.523968 -293.064946) (xy 144.423892 -292.891718) (xy 144.385538 -292.91407) (xy 144.348962 -293.050722)
			(xy 144.48536 -293.087298)
		)
		(stroke
			(width 0)
			(type solid)
		)
		(fill yes)
		(layer "In11.Cu")
		(net "M_L_CPU1_SB_DQ<30>")
	)
	(gr_poly
		(pts
			(xy 144.523968 -269.687548) (xy 144.48536 -269.665196) (xy 144.348962 -269.701772) (xy 144.385538 -269.838424)
			(xy 144.423892 -269.860776)
		)
		(stroke
			(width 0)
			(type solid)
		)
		(fill yes)
		(layer "In11.Cu")
		(net "M_L_CPU1_SB_CB<5>")
	)
	(gr_poly
		(pts
			(xy 144.592802 -284.81782) (xy 144.49298 -284.717744) (xy 144.392904 -284.81782) (xy 144.392904 -284.86227)
			(xy 144.592802 -284.86227)
		)
		(stroke
			(width 0)
			(type solid)
		)
		(fill yes)
		(layer "In11.Cu")
		(net "M_L_CPU1_SB_DQ<17>")
	)
	(gr_poly
		(pts
			(xy 144.592802 -283.197808) (xy 144.49298 -283.097732) (xy 144.392904 -283.197808) (xy 144.392904 -283.242258)
			(xy 144.592802 -283.242258)
		)
		(stroke
			(width 0)
			(type solid)
		)
		(fill yes)
		(layer "In11.Cu")
		(net "M_L_CPU1_SB_DQ<13>")
	)
	(gr_poly
		(pts
			(xy 144.592802 -265.377676) (xy 144.49298 -265.2776) (xy 144.392904 -265.377676) (xy 144.392904 -265.422126)
			(xy 144.592802 -265.422126)
		)
		(stroke
			(width 0)
			(type solid)
		)
		(fill yes)
		(layer "In11.Cu")
		(net "M_L_CPU1_SB_PAR")
	)
	(gr_poly
		(pts
			(xy 144.592802 -263.757664) (xy 144.49298 -263.657588) (xy 144.392904 -263.757664) (xy 144.392904 -263.802114)
			(xy 144.592802 -263.802114)
		)
		(stroke
			(width 0)
			(type solid)
		)
		(fill yes)
		(layer "In11.Cu")
		(net "M_L_CPU1_SB_CA<4>")
	)
	(gr_poly
		(pts
			(xy 144.592802 -262.137652) (xy 144.49298 -262.037576) (xy 144.392904 -262.137652) (xy 144.392904 -262.182102)
			(xy 144.592802 -262.182102)
		)
		(stroke
			(width 0)
			(type solid)
		)
		(fill yes)
		(layer "In11.Cu")
		(net "M_L_CPU1_SB_CA<0>")
	)
	(gr_poly
		(pts
			(xy 144.597374 -273.074384) (xy 144.597374 -273.029934) (xy 144.397476 -273.029934) (xy 144.397476 -273.074384)
			(xy 144.497298 -273.174206)
		)
		(stroke
			(width 0)
			(type solid)
		)
		(fill yes)
		(layer "In11.Cu")
		(net "M_L_CPU1_SB_CB<2>")
	)
	(gr_poly
		(pts
			(xy 144.59839 -271.454372) (xy 144.59839 -271.406874) (xy 144.398238 -271.406874) (xy 144.398238 -271.454372)
			(xy 144.498314 -271.554448)
		)
		(stroke
			(width 0)
			(type solid)
		)
		(fill yes)
		(layer "In11.Cu")
		(net "M_L_CPU1_SB_DQS_DN<9>")
	)
	(gr_poly
		(pts
			(xy 144.598898 -279.958292) (xy 144.499076 -279.858216) (xy 144.399 -279.958292) (xy 144.399 -280.002742)
			(xy 144.598898 -280.002742)
		)
		(stroke
			(width 0)
			(type solid)
		)
		(fill yes)
		(layer "In11.Cu")
		(net "M_L_CPU1_SB_DQ<9>")
	)
	(gr_poly
		(pts
			(xy 144.598898 -278.33828) (xy 144.499076 -278.238204) (xy 144.399 -278.33828) (xy 144.399 -278.38273)
			(xy 144.598898 -278.38273)
		)
		(stroke
			(width 0)
			(type solid)
		)
		(fill yes)
		(layer "In11.Cu")
		(net "M_L_CPU1_SB_DQ<5>")
	)
	(gr_poly
		(pts
			(xy 144.598898 -276.718014) (xy 144.499076 -276.617938) (xy 144.399 -276.718014) (xy 144.399 -276.765512)
			(xy 144.598898 -276.765512)
		)
		(stroke
			(width 0)
			(type solid)
		)
		(fill yes)
		(layer "In11.Cu")
		(net "M_L_CPU1_SB_DQS_DN<5>")
	)
	(gr_poly
		(pts
			(xy 144.598898 -275.098256) (xy 144.499076 -274.99818) (xy 144.399 -275.098256) (xy 144.399 -275.142706)
			(xy 144.598898 -275.142706)
		)
		(stroke
			(width 0)
			(type solid)
		)
		(fill yes)
		(layer "In11.Cu")
		(net "M_L_CPU1_SB_DQ<1>")
	)
	(gr_poly
		(pts
			(xy 144.598898 -273.478244) (xy 144.499076 -273.378168) (xy 144.399 -273.478244) (xy 144.399 -273.522694)
			(xy 144.598898 -273.522694)
		)
		(stroke
			(width 0)
			(type solid)
		)
		(fill yes)
		(layer "In11.Cu")
		(net "M_L_CPU1_SB_CB<1>")
	)
	(gr_poly
		(pts
			(xy 144.598898 -266.998196) (xy 144.499076 -266.89812) (xy 144.399 -266.998196) (xy 144.399 -267.042646)
			(xy 144.598898 -267.042646)
		)
		(stroke
			(width 0)
			(type solid)
		)
		(fill yes)
		(layer "In11.Cu")
		(net "M_L_CPU1_SA_RSP<0>")
	)
	(gr_poly
		(pts
			(xy 144.60474 -271.857978) (xy 144.504664 -271.758156) (xy 144.404588 -271.857978) (xy 144.404588 -271.90573)
			(xy 144.60474 -271.90573)
		)
		(stroke
			(width 0)
			(type solid)
		)
		(fill yes)
		(layer "In11.Cu")
		(net "M_L_CPU1_SB_DQS_DN<4>")
	)
	(gr_poly
		(pts
			(xy 144.60474 -268.618208) (xy 144.504664 -268.518132) (xy 144.404588 -268.618208) (xy 144.404588 -268.662658)
			(xy 144.60474 -268.662658)
		)
		(stroke
			(width 0)
			(type solid)
		)
		(fill yes)
		(layer "In11.Cu")
		(net "M_L_CPU1_SB_CB<4>")
	)
	(gr_poly
		(pts
			(xy 144.610836 -284.414468) (xy 144.610836 -284.370018) (xy 144.410938 -284.370018) (xy 144.410938 -284.414468)
			(xy 144.511014 -284.51429)
		)
		(stroke
			(width 0)
			(type solid)
		)
		(fill yes)
		(layer "In11.Cu")
		(net "M_L_CPU1_SB_DQ<18>")
	)
	(gr_poly
		(pts
			(xy 144.610836 -282.794456) (xy 144.610836 -282.750006) (xy 144.410938 -282.750006) (xy 144.410938 -282.794456)
			(xy 144.511014 -282.894278)
		)
		(stroke
			(width 0)
			(type solid)
		)
		(fill yes)
		(layer "In11.Cu")
		(net "M_L_CPU1_SB_DQ<14>")
	)
	(gr_poly
		(pts
			(xy 144.610836 -279.554432) (xy 144.610836 -279.509982) (xy 144.410938 -279.509982) (xy 144.410938 -279.554432)
			(xy 144.511014 -279.654254)
		)
		(stroke
			(width 0)
			(type solid)
		)
		(fill yes)
		(layer "In11.Cu")
		(net "M_L_CPU1_SB_DQ<10>")
	)
	(gr_poly
		(pts
			(xy 144.610836 -277.93442) (xy 144.610836 -277.88997) (xy 144.410938 -277.88997) (xy 144.410938 -277.93442)
			(xy 144.511014 -278.034242)
		)
		(stroke
			(width 0)
			(type solid)
		)
		(fill yes)
		(layer "In11.Cu")
		(net "M_L_CPU1_SB_DQ<6>")
	)
	(gr_poly
		(pts
			(xy 144.610836 -274.694396) (xy 144.610836 -274.649946) (xy 144.410938 -274.649946) (xy 144.410938 -274.694396)
			(xy 144.511014 -274.794218)
		)
		(stroke
			(width 0)
			(type solid)
		)
		(fill yes)
		(layer "In11.Cu")
		(net "M_L_CPU1_SB_DQ<2>")
	)
	(gr_poly
		(pts
			(xy 144.610836 -266.594336) (xy 144.610836 -266.549886) (xy 144.410938 -266.549886) (xy 144.410938 -266.594336)
			(xy 144.511014 -266.694158)
		)
		(stroke
			(width 0)
			(type solid)
		)
		(fill yes)
		(layer "In11.Cu")
		(net "M_L_CPU1_SB_CS_N<1>")
	)
	(gr_poly
		(pts
			(xy 144.610836 -263.354312) (xy 144.610836 -263.309862) (xy 144.410938 -263.309862) (xy 144.410938 -263.354312)
			(xy 144.511014 -263.454134)
		)
		(stroke
			(width 0)
			(type solid)
		)
		(fill yes)
		(layer "In11.Cu")
		(net "M_L_CPU1_SB_CA<3>")
	)
	(gr_poly
		(pts
			(xy 144.614392 -286.03448) (xy 144.614392 -285.986982) (xy 144.414494 -285.986982) (xy 144.414494 -286.03448)
			(xy 144.514316 -286.134556)
		)
		(stroke
			(width 0)
			(type solid)
		)
		(fill yes)
		(layer "In11.Cu")
		(net "M_L_CPU1_SB_DQS_DN<2>")
	)
	(gr_poly
		(pts
			(xy 144.614392 -281.174444) (xy 144.614392 -281.126946) (xy 144.414494 -281.126946) (xy 144.414494 -281.174444)
			(xy 144.514316 -281.27452)
		)
		(stroke
			(width 0)
			(type solid)
		)
		(fill yes)
		(layer "In11.Cu")
		(net "M_L_CPU1_SB_DQS_DN<1>")
	)
	(gr_poly
		(pts
			(xy 144.614392 -276.314408) (xy 144.614392 -276.26691) (xy 144.414494 -276.26691) (xy 144.414494 -276.314408)
			(xy 144.514316 -276.414484)
		)
		(stroke
			(width 0)
			(type solid)
		)
		(fill yes)
		(layer "In11.Cu")
		(net "M_L_CPU1_SB_DQS_DN<0>")
	)
	(gr_poly
		(pts
			(xy 144.62379 -294.13835) (xy 144.660366 -294.001698) (xy 144.523968 -293.965122) (xy 144.48536 -293.987474)
			(xy 144.585436 -294.160702)
		)
		(stroke
			(width 0)
			(type solid)
		)
		(fill yes)
		(layer "In11.Cu")
		(net "M_L_CPU1_SB_DQ<29>")
	)
	(gr_poly
		(pts
			(xy 144.624044 -292.518338) (xy 144.660874 -292.381686) (xy 144.524222 -292.34511) (xy 144.485614 -292.367462)
			(xy 144.58569 -292.54069)
		)
		(stroke
			(width 0)
			(type solid)
		)
		(fill yes)
		(layer "In11.Cu")
		(net "M_L_CPU1_SB_DQ<28>")
	)
	(gr_poly
		(pts
			(xy 144.660874 -270.370808) (xy 144.624044 -270.234156) (xy 144.58569 -270.211804) (xy 144.485614 -270.385032)
			(xy 144.524222 -270.407384)
		)
		(stroke
			(width 0)
			(type solid)
		)
		(fill yes)
		(layer "In11.Cu")
		(net "M_L_CPU1_SB_CB<7>")
	)
	(gr_poly
		(pts
			(xy 144.693894 -222.264986) (xy 144.65554 -222.242634) (xy 144.518888 -222.27921) (xy 144.555464 -222.415862)
			(xy 144.593818 -222.438214)
		)
		(stroke
			(width 0)
			(type solid)
		)
		(fill yes)
		(layer "In11.Cu")
		(net "M_L_CPU1_SA_DQ<1>")
	)
	(gr_poly
		(pts
			(xy 144.696688 -223.886522) (xy 144.65554 -223.8629) (xy 144.518888 -223.899476) (xy 144.555464 -224.035874)
			(xy 144.596866 -224.05975)
		)
		(stroke
			(width 0)
			(type solid)
		)
		(fill yes)
		(layer "In11.Cu")
		(net "M_L_CPU1_SA_DQS_DP<0>")
	)
	(gr_poly
		(pts
			(xy 144.761712 -247.116346) (xy 144.66189 -247.01627) (xy 144.561814 -247.116346) (xy 144.561814 -247.163844)
			(xy 144.761712 -247.163844)
		)
		(stroke
			(width 0)
			(type solid)
		)
		(fill yes)
		(layer "In11.Cu")
		(net "M_L_CPU1_SA_DQS_DN<9>")
	)
	(gr_poly
		(pts
			(xy 144.761712 -237.396274) (xy 144.66189 -237.296198) (xy 144.561814 -237.396274) (xy 144.561814 -237.443772)
			(xy 144.761712 -237.443772)
		)
		(stroke
			(width 0)
			(type solid)
		)
		(fill yes)
		(layer "In11.Cu")
		(net "M_L_CPU1_SA_DQS_DN<7>")
	)
	(gr_poly
		(pts
			(xy 144.761712 -232.536238) (xy 144.66189 -232.436162) (xy 144.561814 -232.536238) (xy 144.561814 -232.583736)
			(xy 144.761712 -232.583736)
		)
		(stroke
			(width 0)
			(type solid)
		)
		(fill yes)
		(layer "In11.Cu")
		(net "M_L_CPU1_SA_DQS_DN<6>")
	)
	(gr_poly
		(pts
			(xy 144.763998 -248.736612) (xy 144.663922 -248.636536) (xy 144.563846 -248.736612) (xy 144.563846 -248.781062)
			(xy 144.763998 -248.781062)
		)
		(stroke
			(width 0)
			(type solid)
		)
		(fill yes)
		(layer "In11.Cu")
		(net "M_L_CPU1_SA_CB<5>")
	)
	(gr_poly
		(pts
			(xy 144.763998 -245.496588) (xy 144.663922 -245.396512) (xy 144.563846 -245.496588) (xy 144.563846 -245.541038)
			(xy 144.763998 -245.541038)
		)
		(stroke
			(width 0)
			(type solid)
		)
		(fill yes)
		(layer "In11.Cu")
		(net "M_L_CPU1_SA_CB<1>")
	)
	(gr_poly
		(pts
			(xy 144.769078 -255.216406) (xy 144.669002 -255.11633) (xy 144.568926 -255.216406) (xy 144.568926 -255.260856)
			(xy 144.769078 -255.260856)
		)
		(stroke
			(width 0)
			(type solid)
		)
		(fill yes)
		(layer "In11.Cu")
		(net "M_L_CPU1_SA_CA<6>")
	)
	(gr_poly
		(pts
			(xy 144.769078 -253.596394) (xy 144.669002 -253.496318) (xy 144.568926 -253.596394) (xy 144.568926 -253.640844)
			(xy 144.769078 -253.640844)
		)
		(stroke
			(width 0)
			(type solid)
		)
		(fill yes)
		(layer "In11.Cu")
		(net "M_L_CPU1_SA_CA<2>")
	)
	(gr_poly
		(pts
			(xy 144.769078 -243.876322) (xy 144.669002 -243.776246) (xy 144.568926 -243.876322) (xy 144.568926 -243.920772)
			(xy 144.769078 -243.920772)
		)
		(stroke
			(width 0)
			(type solid)
		)
		(fill yes)
		(layer "In11.Cu")
		(net "M_L_CPU1_SA_DQ<29>")
	)
	(gr_poly
		(pts
			(xy 144.769078 -242.256056) (xy 144.669002 -242.156234) (xy 144.568926 -242.256056) (xy 144.568926 -242.303808)
			(xy 144.769078 -242.303808)
		)
		(stroke
			(width 0)
			(type solid)
		)
		(fill yes)
		(layer "In11.Cu")
		(net "M_L_CPU1_SA_DQS_DN<8>")
	)
	(gr_poly
		(pts
			(xy 144.769078 -239.016286) (xy 144.669002 -238.91621) (xy 144.568926 -239.016286) (xy 144.568926 -239.060736)
			(xy 144.769078 -239.060736)
		)
		(stroke
			(width 0)
			(type solid)
		)
		(fill yes)
		(layer "In11.Cu")
		(net "M_L_CPU1_SA_DQ<21>")
	)
	(gr_poly
		(pts
			(xy 144.769078 -235.776262) (xy 144.669002 -235.676186) (xy 144.568926 -235.776262) (xy 144.568926 -235.820712)
			(xy 144.769078 -235.820712)
		)
		(stroke
			(width 0)
			(type solid)
		)
		(fill yes)
		(layer "In11.Cu")
		(net "M_L_CPU1_SA_DQ<17>")
	)
	(gr_poly
		(pts
			(xy 144.769078 -234.15625) (xy 144.669002 -234.056174) (xy 144.568926 -234.15625) (xy 144.568926 -234.2007)
			(xy 144.769078 -234.2007)
		)
		(stroke
			(width 0)
			(type solid)
		)
		(fill yes)
		(layer "In11.Cu")
		(net "M_L_CPU1_SA_DQ<13>")
	)
	(gr_poly
		(pts
			(xy 144.769078 -232.132632) (xy 144.769078 -232.08488) (xy 144.568926 -232.08488) (xy 144.568926 -232.132632)
			(xy 144.669002 -232.232454)
		)
		(stroke
			(width 0)
			(type solid)
		)
		(fill yes)
		(layer "In11.Cu")
		(net "M_L_CPU1_SA_DQS_DN<1>")
	)
	(gr_poly
		(pts
			(xy 144.77492 -250.35637) (xy 144.674844 -250.256294) (xy 144.574768 -250.35637) (xy 144.574768 -250.40082)
			(xy 144.77492 -250.40082)
		)
		(stroke
			(width 0)
			(type solid)
		)
		(fill yes)
		(layer "In11.Cu")
		(net "M_L_CPU1_ALERT_R_N")
	)
	(gr_poly
		(pts
			(xy 144.77492 -240.636298) (xy 144.674844 -240.536222) (xy 144.574768 -240.636298) (xy 144.574768 -240.680748)
			(xy 144.77492 -240.680748)
		)
		(stroke
			(width 0)
			(type solid)
		)
		(fill yes)
		(layer "In11.Cu")
		(net "M_L_CPU1_SA_DQ<25>")
	)
	(gr_poly
		(pts
			(xy 144.775174 -251.970032) (xy 144.675098 -251.869956) (xy 144.575022 -251.970032) (xy 144.575022 -252.014482)
			(xy 144.775174 -252.014482)
		)
		(stroke
			(width 0)
			(type solid)
		)
		(fill yes)
		(layer "In11.Cu")
		(net "M_L_CPU1_SA_CS_N<1>")
	)
	(gr_poly
		(pts
			(xy 144.784318 -246.712994) (xy 144.784318 -246.665242) (xy 144.58442 -246.665242) (xy 144.58442 -246.712994)
			(xy 144.684242 -246.81307)
		)
		(stroke
			(width 0)
			(type solid)
		)
		(fill yes)
		(layer "In11.Cu")
		(net "M_L_CPU1_SA_DQS_DN<4>")
	)
	(gr_poly
		(pts
			(xy 144.784318 -241.852958) (xy 144.784318 -241.805206) (xy 144.58442 -241.805206) (xy 144.58442 -241.852958)
			(xy 144.684242 -241.953034)
		)
		(stroke
			(width 0)
			(type solid)
		)
		(fill yes)
		(layer "In11.Cu")
		(net "M_L_CPU1_SA_DQS_DN<3>")
	)
	(gr_poly
		(pts
			(xy 144.784318 -236.992922) (xy 144.784318 -236.94517) (xy 144.58442 -236.94517) (xy 144.58442 -236.992922)
			(xy 144.684242 -237.092744)
		)
		(stroke
			(width 0)
			(type solid)
		)
		(fill yes)
		(layer "In11.Cu")
		(net "M_L_CPU1_SA_DQS_DN<2>")
	)
	(gr_poly
		(pts
			(xy 144.78889 -256.433066) (xy 144.78889 -256.385314) (xy 144.588992 -256.385314) (xy 144.588992 -256.433066)
			(xy 144.688814 -256.532888)
		)
		(stroke
			(width 0)
			(type solid)
		)
		(fill yes)
		(layer "In11.Cu")
		(net "M_L_CPU1_CLK_DN<0>")
	)
	(gr_poly
		(pts
			(xy 144.829022 -222.95104) (xy 144.792446 -222.814388) (xy 144.754092 -222.792036) (xy 144.654016 -222.965264)
			(xy 144.69237 -222.987616)
		)
		(stroke
			(width 0)
			(type solid)
		)
		(fill yes)
		(layer "In11.Cu")
		(net "M_L_CPU1_SA_DQ<3>")
	)
	(gr_poly
		(pts
			(xy 144.830038 -226.191064) (xy 144.793208 -226.054412) (xy 144.75206 -226.030536) (xy 144.651984 -226.203764)
			(xy 144.693386 -226.22764)
		)
		(stroke
			(width 0)
			(type solid)
		)
		(fill yes)
		(layer "In11.Cu")
		(net "M_L_CPU1_SA_DQS_DP<5>")
	)
	(gr_poly
		(pts
			(xy 144.993868 -295.494964) (xy 144.893792 -295.321736) (xy 144.855438 -295.344088) (xy 144.818862 -295.48074)
			(xy 144.95526 -295.517316)
		)
		(stroke
			(width 0)
			(type solid)
		)
		(fill yes)
		(layer "In11.Cu")
		(net "M_L_CPU1_SB_DQ<31>")
	)
	(gr_poly
		(pts
			(xy 144.993868 -293.874952) (xy 144.893792 -293.701724) (xy 144.855438 -293.724076) (xy 144.818862 -293.860728)
			(xy 144.95526 -293.897304)
		)
		(stroke
			(width 0)
			(type solid)
		)
		(fill yes)
		(layer "In11.Cu")
		(net "M_L_CPU1_SB_DQ<30>")
	)
	(gr_poly
		(pts
			(xy 144.996662 -270.498316) (xy 144.955514 -270.47444) (xy 144.818862 -270.51127) (xy 144.855438 -270.647668)
			(xy 144.89684 -270.671544)
		)
		(stroke
			(width 0)
			(type solid)
		)
		(fill yes)
		(layer "In11.Cu")
		(net "M_L_CPU1_SB_DQS_DP<9>")
	)
	(gr_poly
		(pts
			(xy 145.063972 -285.22422) (xy 145.063972 -285.17977) (xy 144.86382 -285.17977) (xy 144.86382 -285.22422)
			(xy 144.963896 -285.324296)
		)
		(stroke
			(width 0)
			(type solid)
		)
		(fill yes)
		(layer "In11.Cu")
		(net "M_L_CPU1_SB_DQ<19>")
	)
	(gr_poly
		(pts
			(xy 145.063972 -283.604208) (xy 145.063972 -283.559758) (xy 144.86382 -283.559758) (xy 144.86382 -283.604208)
			(xy 144.963896 -283.704284)
		)
		(stroke
			(width 0)
			(type solid)
		)
		(fill yes)
		(layer "In11.Cu")
		(net "M_L_CPU1_SB_DQ<15>")
	)
	(gr_poly
		(pts
			(xy 145.063972 -265.784076) (xy 145.063972 -265.739626) (xy 144.86382 -265.739626) (xy 144.86382 -265.784076)
			(xy 144.963896 -265.884152)
		)
		(stroke
			(width 0)
			(type solid)
		)
		(fill yes)
		(layer "In11.Cu")
		(net "M_L_CPU1_SB_CS_N<0>")
	)
	(gr_poly
		(pts
			(xy 145.063972 -264.164064) (xy 145.063972 -264.119614) (xy 144.86382 -264.119614) (xy 144.86382 -264.164064)
			(xy 144.963896 -264.26414)
		)
		(stroke
			(width 0)
			(type solid)
		)
		(fill yes)
		(layer "In11.Cu")
		(net "M_L_CPU1_SB_CA<5>")
	)
	(gr_poly
		(pts
			(xy 145.063972 -262.544052) (xy 145.063972 -262.499602) (xy 144.86382 -262.499602) (xy 144.86382 -262.544052)
			(xy 144.963896 -262.644128)
		)
		(stroke
			(width 0)
			(type solid)
		)
		(fill yes)
		(layer "In11.Cu")
		(net "M_L_CPU1_SB_CA<1>")
	)
	(gr_poly
		(pts
			(xy 145.068798 -267.808202) (xy 144.968722 -267.708126) (xy 144.868646 -267.808202) (xy 144.868646 -267.852652)
			(xy 145.068798 -267.852652)
		)
		(stroke
			(width 0)
			(type solid)
		)
		(fill yes)
		(layer "In11.Cu")
		(net "M_L_CPU1_SB_RSP<0>")
	)
	(gr_poly
		(pts
			(xy 145.069306 -280.364438) (xy 145.069306 -280.319988) (xy 144.869154 -280.319988) (xy 144.869154 -280.364438)
			(xy 144.96923 -280.464514)
		)
		(stroke
			(width 0)
			(type solid)
		)
		(fill yes)
		(layer "In11.Cu")
		(net "M_L_CPU1_SB_DQ<11>")
	)
	(gr_poly
		(pts
			(xy 145.069306 -278.744426) (xy 145.069306 -278.699976) (xy 144.869154 -278.699976) (xy 144.869154 -278.744426)
			(xy 144.96923 -278.844502)
		)
		(stroke
			(width 0)
			(type solid)
		)
		(fill yes)
		(layer "In11.Cu")
		(net "M_L_CPU1_SB_DQ<7>")
	)
	(gr_poly
		(pts
			(xy 145.069306 -277.124668) (xy 145.069306 -277.076916) (xy 144.869154 -277.076916) (xy 144.869154 -277.124668)
			(xy 144.96923 -277.22449)
		)
		(stroke
			(width 0)
			(type solid)
		)
		(fill yes)
		(layer "In11.Cu")
		(net "M_L_CPU1_SB_DQS_DP<5>")
	)
	(gr_poly
		(pts
			(xy 145.069306 -275.504402) (xy 145.069306 -275.459952) (xy 144.869154 -275.459952) (xy 144.869154 -275.504402)
			(xy 144.96923 -275.604478)
		)
		(stroke
			(width 0)
			(type solid)
		)
		(fill yes)
		(layer "In11.Cu")
		(net "M_L_CPU1_SB_DQ<3>")
	)
	(gr_poly
		(pts
			(xy 145.069306 -273.88439) (xy 145.069306 -273.83994) (xy 144.869154 -273.83994) (xy 144.869154 -273.88439)
			(xy 144.96923 -273.984466)
		)
		(stroke
			(width 0)
			(type solid)
		)
		(fill yes)
		(layer "In11.Cu")
		(net "M_L_CPU1_SB_CB<3>")
	)
	(gr_poly
		(pts
			(xy 145.074894 -272.264632) (xy 145.074894 -272.21688) (xy 144.874742 -272.21688) (xy 144.874742 -272.264632)
			(xy 144.974818 -272.364454)
		)
		(stroke
			(width 0)
			(type solid)
		)
		(fill yes)
		(layer "In11.Cu")
		(net "M_L_CPU1_SB_DQS_DP<4>")
	)
	(gr_poly
		(pts
			(xy 145.074894 -269.428214) (xy 144.974818 -269.328138) (xy 144.874742 -269.428214) (xy 144.874742 -269.472664)
			(xy 145.074894 -269.472664)
		)
		(stroke
			(width 0)
			(type solid)
		)
		(fill yes)
		(layer "In11.Cu")
		(net "M_L_CPU1_SB_CB<5>")
	)
	(gr_poly
		(pts
			(xy 145.074894 -269.024354) (xy 145.074894 -268.979904) (xy 144.874742 -268.979904) (xy 144.874742 -269.024354)
			(xy 144.974818 -269.12443)
		)
		(stroke
			(width 0)
			(type solid)
		)
		(fill yes)
		(layer "In11.Cu")
		(net "M_L_CPU1_SB_CB<6>")
	)
	(gr_poly
		(pts
			(xy 145.084292 -285.627826) (xy 144.984216 -285.528004) (xy 144.884394 -285.627826) (xy 144.884394 -285.675578)
			(xy 145.084292 -285.675578)
		)
		(stroke
			(width 0)
			(type solid)
		)
		(fill yes)
		(layer "In11.Cu")
		(net "M_L_CPU1_SB_DQS_DP<2>")
	)
	(gr_poly
		(pts
			(xy 145.084292 -280.76779) (xy 144.984216 -280.667968) (xy 144.884394 -280.76779) (xy 144.884394 -280.815542)
			(xy 145.084292 -280.815542)
		)
		(stroke
			(width 0)
			(type solid)
		)
		(fill yes)
		(layer "In11.Cu")
		(net "M_L_CPU1_SB_DQS_DP<1>")
	)
	(gr_poly
		(pts
			(xy 145.084292 -275.907754) (xy 144.984216 -275.807932) (xy 144.884394 -275.907754) (xy 144.884394 -275.955506)
			(xy 145.084292 -275.955506)
		)
		(stroke
			(width 0)
			(type solid)
		)
		(fill yes)
		(layer "In11.Cu")
		(net "M_L_CPU1_SB_DQS_DP<0>")
	)
	(gr_poly
		(pts
			(xy 145.084546 -264.561574) (xy 144.98447 -264.461498) (xy 144.884394 -264.561574) (xy 144.884394 -264.606024)
			(xy 145.084546 -264.606024)
		)
		(stroke
			(width 0)
			(type solid)
		)
		(fill yes)
		(layer "In11.Cu")
		(net "M_L_CPU1_SB_CA<6>")
	)
	(gr_poly
		(pts
			(xy 145.086832 -272.667984) (xy 144.986756 -272.568162) (xy 144.88668 -272.667984) (xy 144.88668 -272.712434)
			(xy 145.086832 -272.712434)
		)
		(stroke
			(width 0)
			(type solid)
		)
		(fill yes)
		(layer "In11.Cu")
		(net "M_L_CPU1_SB_CB<0>")
	)
	(gr_poly
		(pts
			(xy 145.09369 -294.948356) (xy 145.130266 -294.811704) (xy 144.993868 -294.775128) (xy 144.95526 -294.79748)
			(xy 145.055336 -294.970708)
		)
		(stroke
			(width 0)
			(type solid)
		)
		(fill yes)
		(layer "In11.Cu")
		(net "M_L_CPU1_SB_DQ<29>")
	)
	(gr_poly
		(pts
			(xy 145.093944 -293.328344) (xy 145.130774 -293.191692) (xy 144.994122 -293.155116) (xy 144.955514 -293.177468)
			(xy 145.05559 -293.350696)
		)
		(stroke
			(width 0)
			(type solid)
		)
		(fill yes)
		(layer "In11.Cu")
		(net "M_L_CPU1_SB_DQ<28>")
	)
	(gr_poly
		(pts
			(xy 145.130266 -271.181322) (xy 145.09369 -271.044924) (xy 145.052288 -271.021048) (xy 144.952466 -271.194276)
			(xy 144.993614 -271.218152)
		)
		(stroke
			(width 0)
			(type solid)
		)
		(fill yes)
		(layer "In11.Cu")
		(net "M_L_CPU1_SB_DQS_DN<9>")
	)
	(gr_poly
		(pts
			(xy 145.166842 -224.69729) (xy 145.125694 -224.673414) (xy 144.989042 -224.70999) (xy 145.025618 -224.846642)
			(xy 145.066766 -224.870518)
		)
		(stroke
			(width 0)
			(type solid)
		)
		(fill yes)
		(layer "In11.Cu")
		(net "M_L_CPU1_SA_DQS_DN<5>")
	)
	(gr_poly
		(pts
			(xy 145.16735 -223.076008) (xy 145.126202 -223.052132) (xy 144.98955 -223.088708) (xy 145.026126 -223.22536)
			(xy 145.067274 -223.249236)
		)
		(stroke
			(width 0)
			(type solid)
		)
		(fill yes)
		(layer "In11.Cu")
		(net "M_L_CPU1_SA_DQS_DP<0>")
	)
	(gr_poly
		(pts
			(xy 145.229326 -256.025904) (xy 145.129504 -255.926082) (xy 145.029428 -256.025904) (xy 145.029428 -256.073656)
			(xy 145.229326 -256.073656)
		)
		(stroke
			(width 0)
			(type solid)
		)
		(fill yes)
		(layer "In11.Cu")
		(net "M_L_CPU1_CLK_DP<0>")
	)
	(gr_poly
		(pts
			(xy 145.229326 -241.445796) (xy 145.129504 -241.345974) (xy 145.029428 -241.445796) (xy 145.029428 -241.493548)
			(xy 145.229326 -241.493548)
		)
		(stroke
			(width 0)
			(type solid)
		)
		(fill yes)
		(layer "In11.Cu")
		(net "M_L_CPU1_SA_DQS_DP<3>")
	)
	(gr_poly
		(pts
			(xy 145.231612 -234.966002) (xy 145.131536 -234.86618) (xy 145.03146 -234.966002) (xy 145.03146 -235.010452)
			(xy 145.231612 -235.010452)
		)
		(stroke
			(width 0)
			(type solid)
		)
		(fill yes)
		(layer "In11.Cu")
		(net "M_L_CPU1_SA_DQ<16>")
	)
	(gr_poly
		(pts
			(xy 145.233898 -251.160026) (xy 145.133822 -251.060204) (xy 145.033746 -251.160026) (xy 145.033746 -251.204476)
			(xy 145.233898 -251.204476)
		)
		(stroke
			(width 0)
			(type solid)
		)
		(fill yes)
		(layer "In11.Cu")
		(net "M_L_CPU1_SA_CS_N<0>")
	)
	(gr_poly
		(pts
			(xy 145.24482 -241.042444) (xy 145.24482 -240.997994) (xy 145.044668 -240.997994) (xy 145.044668 -241.042444)
			(xy 145.144744 -241.14252)
		)
		(stroke
			(width 0)
			(type solid)
		)
		(fill yes)
		(layer "In11.Cu")
		(net "M_L_CPU1_SA_DQ<27>")
	)
	(gr_poly
		(pts
			(xy 145.253456 -236.182408) (xy 145.253456 -236.137958) (xy 145.053558 -236.137958) (xy 145.053558 -236.182408)
			(xy 145.15338 -236.282484)
		)
		(stroke
			(width 0)
			(type solid)
		)
		(fill yes)
		(layer "In11.Cu")
		(net "M_L_CPU1_SA_DQ<19>")
	)
	(gr_poly
		(pts
			(xy 145.253456 -234.562396) (xy 145.253456 -234.517946) (xy 145.053558 -234.517946) (xy 145.053558 -234.562396)
			(xy 145.15338 -234.662472)
		)
		(stroke
			(width 0)
			(type solid)
		)
		(fill yes)
		(layer "In11.Cu")
		(net "M_L_CPU1_SA_DQ<15>")
	)
	(gr_poly
		(pts
			(xy 145.266918 -237.802928) (xy 145.266918 -237.75543) (xy 145.066766 -237.75543) (xy 145.066766 -237.802928)
			(xy 145.166842 -237.903004)
		)
		(stroke
			(width 0)
			(type solid)
		)
		(fill yes)
		(layer "In11.Cu")
		(net "M_L_CPU1_SA_DQS_DP<7>")
	)
	(gr_poly
		(pts
			(xy 145.266918 -232.942892) (xy 145.266918 -232.895394) (xy 145.066766 -232.895394) (xy 145.066766 -232.942892)
			(xy 145.166842 -233.042968)
		)
		(stroke
			(width 0)
			(type solid)
		)
		(fill yes)
		(layer "In11.Cu")
		(net "M_L_CPU1_SA_DQS_DP<6>")
	)
	(gr_poly
		(pts
			(xy 145.301716 -225.378264) (xy 145.264886 -225.241866) (xy 145.223738 -225.21799) (xy 145.123662 -225.391218)
			(xy 145.165064 -225.41484)
		)
		(stroke
			(width 0)
			(type solid)
		)
		(fill yes)
		(layer "In11.Cu")
		(net "M_L_CPU1_SA_DQS_DP<5>")
	)
	(gr_poly
		(pts
			(xy 145.463768 -294.684958) (xy 145.363692 -294.51173) (xy 145.325338 -294.534082) (xy 145.288762 -294.670734)
			(xy 145.42516 -294.70731)
		)
		(stroke
			(width 0)
			(type solid)
		)
		(fill yes)
		(layer "In11.Cu")
		(net "M_L_CPU1_SB_DQ<30>")
	)
	(gr_poly
		(pts
			(xy 145.467832 -271.307052) (xy 145.42643 -271.283176) (xy 145.289778 -271.319752) (xy 145.326608 -271.456404)
			(xy 145.367756 -271.48028)
		)
		(stroke
			(width 0)
			(type solid)
		)
		(fill yes)
		(layer "In11.Cu")
		(net "M_L_CPU1_SB_DQS_DN<4>")
	)
	(gr_poly
		(pts
			(xy 145.5293 -276.314916) (xy 145.5293 -276.267164) (xy 145.329402 -276.267164) (xy 145.329402 -276.314916)
			(xy 145.429478 -276.414738)
		)
		(stroke
			(width 0)
			(type solid)
		)
		(fill yes)
		(layer "In11.Cu")
		(net "M_L_CPU1_SB_DQS_DN<0>")
	)
	(gr_poly
		(pts
			(xy 145.531586 -273.074638) (xy 145.531586 -273.030188) (xy 145.331434 -273.030188) (xy 145.331434 -273.074638)
			(xy 145.43151 -273.17446)
		)
		(stroke
			(width 0)
			(type solid)
		)
		(fill yes)
		(layer "In11.Cu")
		(net "M_L_CPU1_SB_CB<2>")
	)
	(gr_poly
		(pts
			(xy 145.563844 -294.13835) (xy 145.600674 -294.001698) (xy 145.464022 -293.965122) (xy 145.425414 -293.987474)
			(xy 145.52549 -294.160702)
		)
		(stroke
			(width 0)
			(type solid)
		)
		(fill yes)
		(layer "In11.Cu")
		(net "M_L_CPU1_SB_DQ<28>")
	)
	(gr_poly
		(pts
			(xy 145.599658 -271.992852) (xy 145.562828 -271.8562) (xy 145.52168 -271.832324) (xy 145.421604 -272.005552)
			(xy 145.463006 -272.029428)
		)
		(stroke
			(width 0)
			(type solid)
		)
		(fill yes)
		(layer "In11.Cu")
		(net "M_L_CPU1_SB_DQS_DP<4>")
	)
	(gr_poly
		(pts
			(xy 145.636742 -223.886522) (xy 145.595594 -223.8629) (xy 145.458942 -223.899476) (xy 145.495518 -224.035874)
			(xy 145.53692 -224.05975)
		)
		(stroke
			(width 0)
			(type solid)
		)
		(fill yes)
		(layer "In11.Cu")
		(net "M_L_CPU1_SA_DQS_DN<5>")
	)
	(gr_poly
		(pts
			(xy 145.715228 -251.970032) (xy 145.615152 -251.869956) (xy 145.515076 -251.970032) (xy 145.515076 -252.014228)
			(xy 145.715228 -252.014228)
		)
		(stroke
			(width 0)
			(type solid)
		)
		(fill yes)
		(layer "In11.Cu")
		(net "M_L_CPU1_SA_CS_N<1>")
	)
	(gr_poly
		(pts
			(xy 145.720562 -235.372402) (xy 145.720562 -235.327952) (xy 145.520664 -235.327952) (xy 145.520664 -235.372402)
			(xy 145.62074 -235.472224)
		)
		(stroke
			(width 0)
			(type solid)
		)
		(fill yes)
		(layer "In11.Cu")
		(net "M_L_CPU1_SA_DQ<18>")
	)
	(gr_poly
		(pts
			(xy 145.937732 -293.87546) (xy 145.837656 -293.702232) (xy 145.796508 -293.726108) (xy 145.759678 -293.86276)
			(xy 145.89633 -293.899336)
		)
		(stroke
			(width 0)
			(type solid)
		)
		(fill yes)
		(layer "In11.Cu")
		(net "M_L_CPU1_SB_DQS_DP<8>")
	)
	(gr_poly
		(pts
			(xy 146.2405 -223.759522) (xy 146.203924 -223.623124) (xy 146.162522 -223.599248) (xy 146.0627 -223.772476)
			(xy 146.103848 -223.796352)
		)
		(stroke
			(width 0)
			(type solid)
		)
		(fill yes)
		(layer "In11.Cu")
		(net "M_L_CPU1_SA_DQS_DP<5>")
	)
	(gr_poly
		(pts
			(xy 146.406616 -294.684196) (xy 146.306794 -294.510968) (xy 146.265392 -294.534844) (xy 146.228816 -294.671242)
			(xy 146.365468 -294.708072)
		)
		(stroke
			(width 0)
			(type solid)
		)
		(fill yes)
		(layer "In11.Cu")
		(net "M_L_CPU1_SB_DQS_DP<8>")
	)
	(gr_poly
		(pts
			(xy 146.503898 -294.137588) (xy 146.540474 -294.00119) (xy 146.403822 -293.96436) (xy 146.362674 -293.988236)
			(xy 146.462496 -294.161464)
		)
		(stroke
			(width 0)
			(type solid)
		)
		(fill yes)
		(layer "In11.Cu")
		(net "M_L_CPU1_SB_DQS_DN<8>")
	)
	(gr_poly
		(pts
			(xy 325.433182 -223.772222) (xy 325.33336 -223.598994) (xy 325.291958 -223.62287) (xy 325.255382 -223.759268)
			(xy 325.392034 -223.795844)
		)
		(stroke
			(width 0)
			(type solid)
		)
		(fill yes)
		(layer "In11.Cu")
		(net "M_F_CPU0_SA_DQS_DP<5>")
	)
	(gr_poly
		(pts
			(xy 325.907908 -222.981266) (xy 325.808086 -222.808038) (xy 325.766684 -222.83166) (xy 325.730108 -222.968312)
			(xy 325.86676 -223.004888)
		)
		(stroke
			(width 0)
			(type solid)
		)
		(fill yes)
		(layer "In11.Cu")
		(net "M_F_CPU0_SA_DQS_DN<0>")
	)
	(gr_poly
		(pts
			(xy 325.97471 -247.115838) (xy 325.874888 -247.015762) (xy 325.774812 -247.115838) (xy 325.774812 -247.163336)
			(xy 325.97471 -247.163336)
		)
		(stroke
			(width 0)
			(type solid)
		)
		(fill yes)
		(layer "In11.Cu")
		(net "M_F_CPU0_SA_DQS_DN<9>")
	)
	(gr_poly
		(pts
			(xy 325.986648 -253.59614) (xy 325.886572 -253.496064) (xy 325.78675 -253.59614) (xy 325.78675 -253.64059)
			(xy 325.986648 -253.64059)
		)
		(stroke
			(width 0)
			(type solid)
		)
		(fill yes)
		(layer "In11.Cu")
		(net "M_F_CPU0_SA_CA<2>")
	)
	(gr_poly
		(pts
			(xy 326.000364 -224.03562) (xy 326.03694 -223.899222) (xy 325.900288 -223.862392) (xy 325.85914 -223.886268)
			(xy 325.958962 -224.059496)
		)
		(stroke
			(width 0)
			(type solid)
		)
		(fill yes)
		(layer "In11.Cu")
		(net "M_F_CPU0_SA_DQS_DN<5>")
	)
	(gr_poly
		(pts
			(xy 326.1995 -294.797734) (xy 326.160892 -294.775636) (xy 326.024494 -294.812212) (xy 326.06107 -294.948864)
			(xy 326.099424 -294.970962)
		)
		(stroke
			(width 0)
			(type solid)
		)
		(fill yes)
		(layer "In11.Cu")
		(net "M_F_CPU0_SB_DQ<28>")
	)
	(gr_poly
		(pts
			(xy 326.356726 -227.000054) (xy 326.272398 -226.818952) (xy 326.229218 -226.839018) (xy 326.180704 -226.97186)
			(xy 326.3138 -227.02012)
		)
		(stroke
			(width 0)
			(type solid)
		)
		(fill yes)
		(layer "In11.Cu")
		(net "M_F_CPU0_SA_DQS_DP<5>")
	)
	(gr_poly
		(pts
			(xy 326.369934 -225.392488) (xy 326.269858 -225.21926) (xy 326.231504 -225.241612) (xy 326.194674 -225.37801)
			(xy 326.331326 -225.41484)
		)
		(stroke
			(width 0)
			(type solid)
		)
		(fill yes)
		(layer "In11.Cu")
		(net "M_F_CPU0_SA_DQS_DN<0>")
	)
	(gr_poly
		(pts
			(xy 326.369934 -224.69602) (xy 326.331326 -224.673668) (xy 326.194674 -224.710498) (xy 326.231504 -224.846896)
			(xy 326.269858 -224.869248)
		)
		(stroke
			(width 0)
			(type solid)
		)
		(fill yes)
		(layer "In11.Cu")
		(net "M_F_CPU0_SA_DQS_DN<0>")
	)
	(gr_poly
		(pts
			(xy 326.373998 -223.773492) (xy 326.274176 -223.600264) (xy 326.232774 -223.62414) (xy 326.196198 -223.760792)
			(xy 326.33285 -223.797368)
		)
		(stroke
			(width 0)
			(type solid)
		)
		(fill yes)
		(layer "In11.Cu")
		(net "M_F_CPU0_SA_DQS_DN<0>")
	)
	(gr_poly
		(pts
			(xy 326.428608 -247.923812) (xy 326.328532 -247.823736) (xy 326.228456 -247.923812) (xy 326.228456 -247.968262)
			(xy 326.428608 -247.968262)
		)
		(stroke
			(width 0)
			(type solid)
		)
		(fill yes)
		(layer "In11.Cu")
		(net "M_F_CPU0_SA_CB<4>")
	)
	(gr_poly
		(pts
			(xy 326.440292 -247.521984) (xy 326.440292 -247.474486) (xy 326.240394 -247.474486) (xy 326.240394 -247.521984)
			(xy 326.34047 -247.62206)
		)
		(stroke
			(width 0)
			(type solid)
		)
		(fill yes)
		(layer "In11.Cu")
		(net "M_F_CPU0_SA_DQS_DP<9>")
	)
	(gr_poly
		(pts
			(xy 326.442324 -254.002286) (xy 326.442324 -253.957836) (xy 326.242426 -253.957836) (xy 326.242426 -254.002286)
			(xy 326.342502 -254.102362)
		)
		(stroke
			(width 0)
			(type solid)
		)
		(fill yes)
		(layer "In11.Cu")
		(net "M_F_CPU0_SA_CA<3>")
	)
	(gr_poly
		(pts
			(xy 326.442324 -252.382274) (xy 326.442324 -252.337824) (xy 326.242426 -252.337824) (xy 326.242426 -252.382274)
			(xy 326.342502 -252.48235)
		)
		(stroke
			(width 0)
			(type solid)
		)
		(fill yes)
		(layer "In11.Cu")
		(net "M_F_CPU0_SA_CS_N<1>")
	)
	(gr_poly
		(pts
			(xy 326.442324 -242.662456) (xy 326.442324 -242.614958) (xy 326.242426 -242.614958) (xy 326.242426 -242.662456)
			(xy 326.342502 -242.762532)
		)
		(stroke
			(width 0)
			(type solid)
		)
		(fill yes)
		(layer "In11.Cu")
		(net "M_F_CPU0_SA_DQS_DP<8>")
	)
	(gr_poly
		(pts
			(xy 326.442324 -236.182154) (xy 326.442324 -236.137704) (xy 326.242426 -236.137704) (xy 326.242426 -236.182154)
			(xy 326.342502 -236.28223)
		)
		(stroke
			(width 0)
			(type solid)
		)
		(fill yes)
		(layer "In11.Cu")
		(net "M_F_CPU0_SA_DQ<19>")
	)
	(gr_poly
		(pts
			(xy 326.442324 -234.562142) (xy 326.442324 -234.517692) (xy 326.242426 -234.517692) (xy 326.242426 -234.562142)
			(xy 326.342502 -234.662218)
		)
		(stroke
			(width 0)
			(type solid)
		)
		(fill yes)
		(layer "In11.Cu")
		(net "M_F_CPU0_SA_DQ<15>")
	)
	(gr_poly
		(pts
			(xy 326.442324 -232.942384) (xy 326.442324 -232.894886) (xy 326.242172 -232.894886) (xy 326.242172 -232.942384)
			(xy 326.342248 -233.04246)
		)
		(stroke
			(width 0)
			(type solid)
		)
		(fill yes)
		(layer "In11.Cu")
		(net "M_F_CPU0_SA_DQS_DP<6>")
	)
	(gr_poly
		(pts
			(xy 326.45604 -226.512374) (xy 326.504554 -226.379532) (xy 326.371458 -226.331018) (xy 326.328278 -226.351084)
			(xy 326.41286 -226.53244)
		)
		(stroke
			(width 0)
			(type solid)
		)
		(fill yes)
		(layer "In11.Cu")
		(net "M_F_CPU0_SA_DQS_DN<5>")
	)
	(gr_poly
		(pts
			(xy 326.456802 -237.80242) (xy 326.456802 -237.754922) (xy 326.256904 -237.754922) (xy 326.256904 -237.80242)
			(xy 326.356726 -237.902496)
		)
		(stroke
			(width 0)
			(type solid)
		)
		(fill yes)
		(layer "In11.Cu")
		(net "M_F_CPU0_SA_DQS_DP<7>")
	)
	(gr_poly
		(pts
			(xy 326.463914 -239.422178) (xy 326.463914 -239.377728) (xy 326.263762 -239.377728) (xy 326.263762 -239.422178)
			(xy 326.363838 -239.522254)
		)
		(stroke
			(width 0)
			(type solid)
		)
		(fill yes)
		(layer "In11.Cu")
		(net "M_F_CPU0_SA_DQ<23>")
	)
	(gr_poly
		(pts
			(xy 326.464422 -254.405892) (xy 326.364346 -254.30607) (xy 326.26427 -254.405892) (xy 326.26427 -254.450342)
			(xy 326.464422 -254.450342)
		)
		(stroke
			(width 0)
			(type solid)
		)
		(fill yes)
		(layer "In11.Cu")
		(net "M_F_CPU0_SA_CA<4>")
	)
	(gr_poly
		(pts
			(xy 326.464422 -252.78588) (xy 326.364346 -252.686058) (xy 326.26427 -252.78588) (xy 326.26427 -252.83033)
			(xy 326.464422 -252.83033)
		)
		(stroke
			(width 0)
			(type solid)
		)
		(fill yes)
		(layer "In11.Cu")
		(net "M_F_CPU0_SA_CA<0>")
	)
	(gr_poly
		(pts
			(xy 326.464422 -244.68582) (xy 326.364346 -244.585998) (xy 326.26427 -244.68582) (xy 326.26427 -244.73027)
			(xy 326.464422 -244.73027)
		)
		(stroke
			(width 0)
			(type solid)
		)
		(fill yes)
		(layer "In11.Cu")
		(net "M_F_CPU0_SA_CB<0>")
	)
	(gr_poly
		(pts
			(xy 326.466454 -256.025904) (xy 326.366378 -255.925828) (xy 326.266556 -256.025904) (xy 326.266556 -256.073402)
			(xy 326.466454 -256.073402)
		)
		(stroke
			(width 0)
			(type solid)
		)
		(fill yes)
		(layer "In11.Cu")
		(net "M_F_CPU0_CLK_DP<0>")
	)
	(gr_poly
		(pts
			(xy 326.468994 -223.223582) (xy 326.50557 -223.087184) (xy 326.368918 -223.050354) (xy 326.32777 -223.07423)
			(xy 326.427846 -223.247458)
		)
		(stroke
			(width 0)
			(type solid)
		)
		(fill yes)
		(layer "In11.Cu")
		(net "M_F_CPU0_SA_DQS_DP<0>")
	)
	(gr_poly
		(pts
			(xy 326.670416 -293.986458) (xy 326.632062 -293.964106) (xy 326.49541 -294.000682) (xy 326.531986 -294.137334)
			(xy 326.570594 -294.159686)
		)
		(stroke
			(width 0)
			(type solid)
		)
		(fill yes)
		(layer "In11.Cu")
		(net "M_F_CPU0_SB_DQ<28>")
	)
	(gr_poly
		(pts
			(xy 326.742298 -284.818074) (xy 326.642476 -284.717998) (xy 326.5424 -284.818074) (xy 326.5424 -284.862524)
			(xy 326.742298 -284.862524)
		)
		(stroke
			(width 0)
			(type solid)
		)
		(fill yes)
		(layer "In11.Cu")
		(net "M_F_CPU0_SB_DQ<17>")
	)
	(gr_poly
		(pts
			(xy 326.742298 -283.198062) (xy 326.642476 -283.097986) (xy 326.5424 -283.198062) (xy 326.5424 -283.242512)
			(xy 326.742298 -283.242512)
		)
		(stroke
			(width 0)
			(type solid)
		)
		(fill yes)
		(layer "In11.Cu")
		(net "M_F_CPU0_SB_DQ<13>")
	)
	(gr_poly
		(pts
			(xy 326.747632 -286.437832) (xy 326.647556 -286.337756) (xy 326.54748 -286.437832) (xy 326.54748 -286.48533)
			(xy 326.747632 -286.48533)
		)
		(stroke
			(width 0)
			(type solid)
		)
		(fill yes)
		(layer "In11.Cu")
		(net "M_F_CPU0_SB_DQS_DN<7>")
	)
	(gr_poly
		(pts
			(xy 326.764396 -279.554432) (xy 326.764396 -279.509982) (xy 326.564244 -279.509982) (xy 326.564244 -279.554432)
			(xy 326.66432 -279.654254)
		)
		(stroke
			(width 0)
			(type solid)
		)
		(fill yes)
		(layer "In11.Cu")
		(net "M_F_CPU0_SB_DQ<10>")
	)
	(gr_poly
		(pts
			(xy 326.764396 -274.694396) (xy 326.764396 -274.649946) (xy 326.564244 -274.649946) (xy 326.564244 -274.694396)
			(xy 326.66432 -274.794218)
		)
		(stroke
			(width 0)
			(type solid)
		)
		(fill yes)
		(layer "In11.Cu")
		(net "M_F_CPU0_SB_DQ<2>")
	)
	(gr_poly
		(pts
			(xy 326.764396 -273.074384) (xy 326.764396 -273.029934) (xy 326.564244 -273.029934) (xy 326.564244 -273.074384)
			(xy 326.66432 -273.174206)
		)
		(stroke
			(width 0)
			(type solid)
		)
		(fill yes)
		(layer "In11.Cu")
		(net "M_F_CPU0_SB_CB<2>")
	)
	(gr_poly
		(pts
			(xy 326.764396 -269.83436) (xy 326.764396 -269.78991) (xy 326.564244 -269.78991) (xy 326.564244 -269.83436)
			(xy 326.66432 -269.934182)
		)
		(stroke
			(width 0)
			(type solid)
		)
		(fill yes)
		(layer "In11.Cu")
		(net "M_F_CPU0_SB_CB<6>")
	)
	(gr_poly
		(pts
			(xy 326.764396 -264.974324) (xy 326.764396 -264.929874) (xy 326.564244 -264.929874) (xy 326.564244 -264.974324)
			(xy 326.66432 -265.074146)
		)
		(stroke
			(width 0)
			(type solid)
		)
		(fill yes)
		(layer "In11.Cu")
		(net "M_F_CPU0_SB_PAR")
	)
	(gr_poly
		(pts
			(xy 326.766428 -281.174444) (xy 326.766428 -281.126946) (xy 326.56653 -281.126946) (xy 326.56653 -281.174444)
			(xy 326.666352 -281.27452)
		)
		(stroke
			(width 0)
			(type solid)
		)
		(fill yes)
		(layer "In11.Cu")
		(net "M_F_CPU0_SB_DQS_DN<1>")
	)
	(gr_poly
		(pts
			(xy 326.829674 -232.1433) (xy 326.837802 -232.09631) (xy 326.640952 -232.061512) (xy 326.63257 -232.108502)
			(xy 326.71385 -232.224326)
		)
		(stroke
			(width 0)
			(type solid)
		)
		(fill yes)
		(layer "In11.Cu")
		(net "M_F_CPU0_SA_DQS_DN<1>")
	)
	(gr_poly
		(pts
			(xy 326.841866 -222.96501) (xy 326.74179 -222.791782) (xy 326.703436 -222.814134) (xy 326.66686 -222.950786)
			(xy 326.803258 -222.987362)
		)
		(stroke
			(width 0)
			(type solid)
		)
		(fill yes)
		(layer "In11.Cu")
		(net "M_F_CPU0_SA_DQ<3>")
	)
	(gr_poly
		(pts
			(xy 326.84339 -226.20224) (xy 326.743568 -226.029012) (xy 326.702166 -226.052888) (xy 326.66559 -226.189286)
			(xy 326.802242 -226.226116)
		)
		(stroke
			(width 0)
			(type solid)
		)
		(fill yes)
		(layer "In11.Cu")
		(net "M_F_CPU0_SA_DQS_DN<0>")
	)
	(gr_poly
		(pts
			(xy 326.90689 -256.432812) (xy 326.90689 -256.38506) (xy 326.706992 -256.38506) (xy 326.706992 -256.432812)
			(xy 326.807068 -256.532634)
		)
		(stroke
			(width 0)
			(type solid)
		)
		(fill yes)
		(layer "In11.Cu")
		(net "M_F_CPU0_CLK_DN<0>")
	)
	(gr_poly
		(pts
			(xy 326.911462 -246.71274) (xy 326.911462 -246.664988) (xy 326.711564 -246.664988) (xy 326.711564 -246.71274)
			(xy 326.81164 -246.812816)
		)
		(stroke
			(width 0)
			(type solid)
		)
		(fill yes)
		(layer "In11.Cu")
		(net "M_F_CPU0_SA_DQS_DN<4>")
	)
	(gr_poly
		(pts
			(xy 326.911462 -241.852704) (xy 326.911462 -241.804952) (xy 326.711564 -241.804952) (xy 326.711564 -241.852704)
			(xy 326.81164 -241.95278)
		)
		(stroke
			(width 0)
			(type solid)
		)
		(fill yes)
		(layer "In11.Cu")
		(net "M_F_CPU0_SA_DQS_DN<3>")
	)
	(gr_poly
		(pts
			(xy 326.911462 -236.992668) (xy 326.911462 -236.944916) (xy 326.711564 -236.944916) (xy 326.711564 -236.992668)
			(xy 326.81164 -237.092744)
		)
		(stroke
			(width 0)
			(type solid)
		)
		(fill yes)
		(layer "In11.Cu")
		(net "M_F_CPU0_SA_DQS_DN<2>")
	)
	(gr_poly
		(pts
			(xy 326.921114 -250.356116) (xy 326.821038 -250.25604) (xy 326.720962 -250.356116) (xy 326.720962 -250.400566)
			(xy 326.921114 -250.400566)
		)
		(stroke
			(width 0)
			(type solid)
		)
		(fill yes)
		(layer "In11.Cu")
		(net "M_F_CPU0_ALERT_R_N")
	)
	(gr_poly
		(pts
			(xy 326.926702 -255.216152) (xy 326.826626 -255.116076) (xy 326.72655 -255.216152) (xy 326.72655 -255.260602)
			(xy 326.926702 -255.260602)
		)
		(stroke
			(width 0)
			(type solid)
		)
		(fill yes)
		(layer "In11.Cu")
		(net "M_F_CPU0_SA_CA<6>")
	)
	(gr_poly
		(pts
			(xy 326.926702 -253.59614) (xy 326.826626 -253.496064) (xy 326.72655 -253.59614) (xy 326.72655 -253.64059)
			(xy 326.926702 -253.64059)
		)
		(stroke
			(width 0)
			(type solid)
		)
		(fill yes)
		(layer "In11.Cu")
		(net "M_F_CPU0_SA_CA<2>")
	)
	(gr_poly
		(pts
			(xy 326.926702 -248.736104) (xy 326.826626 -248.636028) (xy 326.72655 -248.736104) (xy 326.72655 -248.780554)
			(xy 326.926702 -248.780554)
		)
		(stroke
			(width 0)
			(type solid)
		)
		(fill yes)
		(layer "In11.Cu")
		(net "M_F_CPU0_SA_CB<5>")
	)
	(gr_poly
		(pts
			(xy 326.926702 -247.115838) (xy 326.826626 -247.016016) (xy 326.72655 -247.115838) (xy 326.72655 -247.16359)
			(xy 326.926702 -247.16359)
		)
		(stroke
			(width 0)
			(type solid)
		)
		(fill yes)
		(layer "In11.Cu")
		(net "M_F_CPU0_SA_DQS_DN<9>")
	)
	(gr_poly
		(pts
			(xy 326.926702 -245.49608) (xy 326.826626 -245.396004) (xy 326.72655 -245.49608) (xy 326.72655 -245.54053)
			(xy 326.926702 -245.54053)
		)
		(stroke
			(width 0)
			(type solid)
		)
		(fill yes)
		(layer "In11.Cu")
		(net "M_F_CPU0_SA_CB<1>")
	)
	(gr_poly
		(pts
			(xy 326.926702 -243.876068) (xy 326.826626 -243.775992) (xy 326.72655 -243.876068) (xy 326.72655 -243.920518)
			(xy 326.926702 -243.920518)
		)
		(stroke
			(width 0)
			(type solid)
		)
		(fill yes)
		(layer "In11.Cu")
		(net "M_F_CPU0_SA_DQ<29>")
	)
	(gr_poly
		(pts
			(xy 326.926702 -242.255802) (xy 326.826626 -242.15598) (xy 326.72655 -242.255802) (xy 326.72655 -242.303554)
			(xy 326.926702 -242.303554)
		)
		(stroke
			(width 0)
			(type solid)
		)
		(fill yes)
		(layer "In11.Cu")
		(net "M_F_CPU0_SA_DQS_DN<8>")
	)
	(gr_poly
		(pts
			(xy 326.926702 -239.016032) (xy 326.826626 -238.915956) (xy 326.72655 -239.016032) (xy 326.72655 -239.060482)
			(xy 326.926702 -239.060482)
		)
		(stroke
			(width 0)
			(type solid)
		)
		(fill yes)
		(layer "In11.Cu")
		(net "M_F_CPU0_SA_DQ<21>")
	)
	(gr_poly
		(pts
			(xy 326.926702 -237.395766) (xy 326.826626 -237.295944) (xy 326.72655 -237.395766) (xy 326.72655 -237.443518)
			(xy 326.926702 -237.443518)
		)
		(stroke
			(width 0)
			(type solid)
		)
		(fill yes)
		(layer "In11.Cu")
		(net "M_F_CPU0_SA_DQS_DN<7>")
	)
	(gr_poly
		(pts
			(xy 326.926702 -235.776008) (xy 326.826626 -235.675932) (xy 326.72655 -235.776008) (xy 326.72655 -235.820458)
			(xy 326.926702 -235.820458)
		)
		(stroke
			(width 0)
			(type solid)
		)
		(fill yes)
		(layer "In11.Cu")
		(net "M_F_CPU0_SA_DQ<17>")
	)
	(gr_poly
		(pts
			(xy 326.926702 -234.155996) (xy 326.826626 -234.05592) (xy 326.72655 -234.155996) (xy 326.72655 -234.200446)
			(xy 326.926702 -234.200446)
		)
		(stroke
			(width 0)
			(type solid)
		)
		(fill yes)
		(layer "In11.Cu")
		(net "M_F_CPU0_SA_DQ<13>")
	)
	(gr_poly
		(pts
			(xy 326.926702 -232.53573) (xy 326.826626 -232.435908) (xy 326.72655 -232.53573) (xy 326.72655 -232.583482)
			(xy 326.926702 -232.583482)
		)
		(stroke
			(width 0)
			(type solid)
		)
		(fill yes)
		(layer "In11.Cu")
		(net "M_F_CPU0_SA_DQS_DN<6>")
	)
	(gr_poly
		(pts
			(xy 326.932036 -240.636298) (xy 326.83196 -240.536222) (xy 326.731884 -240.636298) (xy 326.731884 -240.680748)
			(xy 326.932036 -240.680748)
		)
		(stroke
			(width 0)
			(type solid)
		)
		(fill yes)
		(layer "In11.Cu")
		(net "M_F_CPU0_SA_DQ<25>")
	)
	(gr_poly
		(pts
			(xy 326.93991 -224.035112) (xy 326.976486 -223.89846) (xy 326.839834 -223.861884) (xy 326.801226 -223.883982)
			(xy 326.901302 -224.05721)
		)
		(stroke
			(width 0)
			(type solid)
		)
		(fill yes)
		(layer "In11.Cu")
		(net "M_F_CPU0_SA_DQS_DP<0>")
	)
	(gr_poly
		(pts
			(xy 326.940418 -225.655632) (xy 326.976994 -225.519234) (xy 326.840342 -225.482404) (xy 326.799194 -225.50628)
			(xy 326.899016 -225.679508)
		)
		(stroke
			(width 0)
			(type solid)
		)
		(fill yes)
		(layer "In11.Cu")
		(net "M_F_CPU0_SA_DQS_DP<0>")
	)
	(gr_poly
		(pts
			(xy 326.940418 -222.415608) (xy 326.976994 -222.278956) (xy 326.840342 -222.24238) (xy 326.801988 -222.264732)
			(xy 326.90181 -222.43796)
		)
		(stroke
			(width 0)
			(type solid)
		)
		(fill yes)
		(layer "In11.Cu")
		(net "M_F_CPU0_SA_DQ<1>")
	)
	(gr_poly
		(pts
			(xy 326.97674 -224.569528) (xy 326.940164 -224.432876) (xy 326.901556 -224.410524) (xy 326.801734 -224.583752)
			(xy 326.840088 -224.606104)
		)
		(stroke
			(width 0)
			(type solid)
		)
		(fill yes)
		(layer "In11.Cu")
		(net "M_F_CPU0_SA_DQS_DP<0>")
	)
	(gr_poly
		(pts
			(xy 327.140316 -293.177214) (xy 327.101708 -293.154862) (xy 326.96531 -293.191438) (xy 327.001886 -293.32809)
			(xy 327.04024 -293.350442)
		)
		(stroke
			(width 0)
			(type solid)
		)
		(fill yes)
		(layer "In11.Cu")
		(net "M_F_CPU0_SB_DQ<28>")
	)
	(gr_poly
		(pts
			(xy 327.20915 -269.427706) (xy 327.109074 -269.327884) (xy 327.008998 -269.427706) (xy 327.008998 -269.472156)
			(xy 327.20915 -269.472156)
		)
		(stroke
			(width 0)
			(type solid)
		)
		(fill yes)
		(layer "In11.Cu")
		(net "M_F_CPU0_SB_CB<4>")
	)
	(gr_poly
		(pts
			(xy 327.211436 -287.247584) (xy 327.111614 -287.147508) (xy 327.011538 -287.247584) (xy 327.011538 -287.292034)
			(xy 327.211436 -287.292034)
		)
		(stroke
			(width 0)
			(type solid)
		)
		(fill yes)
		(layer "In11.Cu")
		(net "M_F_CPU0_SB_DQ<20>")
	)
	(gr_poly
		(pts
			(xy 327.211436 -285.627572) (xy 327.111614 -285.527496) (xy 327.011538 -285.627572) (xy 327.011538 -285.675324)
			(xy 327.211436 -285.675324)
		)
		(stroke
			(width 0)
			(type solid)
		)
		(fill yes)
		(layer "In11.Cu")
		(net "M_F_CPU0_SB_DQS_DP<2>")
	)
	(gr_poly
		(pts
			(xy 327.211436 -280.767536) (xy 327.111614 -280.66746) (xy 327.011538 -280.767536) (xy 327.011538 -280.815288)
			(xy 327.211436 -280.815288)
		)
		(stroke
			(width 0)
			(type solid)
		)
		(fill yes)
		(layer "In11.Cu")
		(net "M_F_CPU0_SB_DQS_DP<1>")
	)
	(gr_poly
		(pts
			(xy 327.215754 -286.844232) (xy 327.215754 -286.796734) (xy 327.015856 -286.796734) (xy 327.015856 -286.844232)
			(xy 327.115678 -286.944308)
		)
		(stroke
			(width 0)
			(type solid)
		)
		(fill yes)
		(layer "In11.Cu")
		(net "M_F_CPU0_SB_DQS_DP<7>")
	)
	(gr_poly
		(pts
			(xy 327.221342 -267.807948) (xy 327.121266 -267.707872) (xy 327.02119 -267.807948) (xy 327.02119 -267.852398)
			(xy 327.221342 -267.852398)
		)
		(stroke
			(width 0)
			(type solid)
		)
		(fill yes)
		(layer "In11.Cu")
		(net "M_F_CPU0_SB_RSP<0>")
	)
	(gr_poly
		(pts
			(xy 327.22693 -285.22422) (xy 327.22693 -285.17977) (xy 327.026778 -285.17977) (xy 327.026778 -285.22422)
			(xy 327.126854 -285.324296)
		)
		(stroke
			(width 0)
			(type solid)
		)
		(fill yes)
		(layer "In11.Cu")
		(net "M_F_CPU0_SB_DQ<19>")
	)
	(gr_poly
		(pts
			(xy 327.22693 -283.604208) (xy 327.22693 -283.559758) (xy 327.026778 -283.559758) (xy 327.026778 -283.604208)
			(xy 327.126854 -283.704284)
		)
		(stroke
			(width 0)
			(type solid)
		)
		(fill yes)
		(layer "In11.Cu")
		(net "M_F_CPU0_SB_DQ<15>")
	)
	(gr_poly
		(pts
			(xy 327.309988 -225.392488) (xy 327.209912 -225.21926) (xy 327.171558 -225.241612) (xy 327.134982 -225.37801)
			(xy 327.27138 -225.41484)
		)
		(stroke
			(width 0)
			(type solid)
		)
		(fill yes)
		(layer "In11.Cu")
		(net "M_F_CPU0_SA_DQ<3>")
	)
	(gr_poly
		(pts
			(xy 327.309988 -224.69602) (xy 327.27138 -224.673668) (xy 327.134982 -224.710498) (xy 327.171558 -224.846896)
			(xy 327.209912 -224.869248)
		)
		(stroke
			(width 0)
			(type solid)
		)
		(fill yes)
		(layer "In11.Cu")
		(net "M_F_CPU0_SA_DQ<3>")
	)
	(gr_poly
		(pts
			(xy 327.309988 -222.152464) (xy 327.209912 -221.979236) (xy 327.171558 -222.001334) (xy 327.134982 -222.137986)
			(xy 327.27138 -222.174816)
		)
		(stroke
			(width 0)
			(type solid)
		)
		(fill yes)
		(layer "In11.Cu")
		(net "M_F_CPU0_SA_DQ<2>")
	)
	(gr_poly
		(pts
			(xy 327.310496 -223.772984) (xy 327.21042 -223.599756) (xy 327.172066 -223.622108) (xy 327.13549 -223.75876)
			(xy 327.271888 -223.795336)
		)
		(stroke
			(width 0)
			(type solid)
		)
		(fill yes)
		(layer "In11.Cu")
		(net "M_F_CPU0_SA_DQ<3>")
	)
	(gr_poly
		(pts
			(xy 327.313798 -227.013008) (xy 327.213722 -226.83978) (xy 327.172574 -226.863402) (xy 327.135998 -227.000054)
			(xy 327.27265 -227.03663)
		)
		(stroke
			(width 0)
			(type solid)
		)
		(fill yes)
		(layer "In11.Cu")
		(net "M_F_CPU0_SA_DQS_DN<0>")
	)
	(gr_poly
		(pts
			(xy 327.381362 -246.306086) (xy 327.28154 -246.20601) (xy 327.181464 -246.306086) (xy 327.181464 -246.353584)
			(xy 327.381362 -246.353584)
		)
		(stroke
			(width 0)
			(type solid)
		)
		(fill yes)
		(layer "In11.Cu")
		(net "M_F_CPU0_SA_DQS_DP<4>")
	)
	(gr_poly
		(pts
			(xy 327.381362 -241.44605) (xy 327.28154 -241.345974) (xy 327.181464 -241.44605) (xy 327.181464 -241.493548)
			(xy 327.381362 -241.493548)
		)
		(stroke
			(width 0)
			(type solid)
		)
		(fill yes)
		(layer "In11.Cu")
		(net "M_F_CPU0_SA_DQS_DP<3>")
	)
	(gr_poly
		(pts
			(xy 327.381362 -236.586014) (xy 327.28154 -236.485938) (xy 327.181464 -236.586014) (xy 327.181464 -236.633512)
			(xy 327.381362 -236.633512)
		)
		(stroke
			(width 0)
			(type solid)
		)
		(fill yes)
		(layer "In11.Cu")
		(net "M_F_CPU0_SA_DQS_DP<2>")
	)
	(gr_poly
		(pts
			(xy 327.381362 -231.725978) (xy 327.28154 -231.625902) (xy 327.181464 -231.725978) (xy 327.181464 -231.773476)
			(xy 327.381362 -231.773476)
		)
		(stroke
			(width 0)
			(type solid)
		)
		(fill yes)
		(layer "In11.Cu")
		(net "M_F_CPU0_SA_DQS_DP<1>")
	)
	(gr_poly
		(pts
			(xy 327.384918 -254.406146) (xy 327.284842 -254.306324) (xy 327.18502 -254.406146) (xy 327.18502 -254.450596)
			(xy 327.384918 -254.450596)
		)
		(stroke
			(width 0)
			(type solid)
		)
		(fill yes)
		(layer "In11.Cu")
		(net "M_F_CPU0_SA_CA<4>")
	)
	(gr_poly
		(pts
			(xy 327.384918 -252.786134) (xy 327.284842 -252.686312) (xy 327.18502 -252.786134) (xy 327.18502 -252.830584)
			(xy 327.384918 -252.830584)
		)
		(stroke
			(width 0)
			(type solid)
		)
		(fill yes)
		(layer "In11.Cu")
		(net "M_F_CPU0_SA_CA<0>")
	)
	(gr_poly
		(pts
			(xy 327.384918 -247.926098) (xy 327.284842 -247.826276) (xy 327.18502 -247.926098) (xy 327.18502 -247.970548)
			(xy 327.384918 -247.970548)
		)
		(stroke
			(width 0)
			(type solid)
		)
		(fill yes)
		(layer "In11.Cu")
		(net "M_F_CPU0_SA_CB<4>")
	)
	(gr_poly
		(pts
			(xy 327.384918 -244.686074) (xy 327.284842 -244.586252) (xy 327.18502 -244.686074) (xy 327.18502 -244.730524)
			(xy 327.384918 -244.730524)
		)
		(stroke
			(width 0)
			(type solid)
		)
		(fill yes)
		(layer "In11.Cu")
		(net "M_F_CPU0_SA_CB<0>")
	)
	(gr_poly
		(pts
			(xy 327.384918 -243.066062) (xy 327.284842 -242.96624) (xy 327.18502 -243.066062) (xy 327.18502 -243.110512)
			(xy 327.384918 -243.110512)
		)
		(stroke
			(width 0)
			(type solid)
		)
		(fill yes)
		(layer "In11.Cu")
		(net "M_F_CPU0_SA_DQ<28>")
	)
	(gr_poly
		(pts
			(xy 327.384918 -239.826038) (xy 327.284842 -239.726216) (xy 327.18502 -239.826038) (xy 327.18502 -239.870488)
			(xy 327.384918 -239.870488)
		)
		(stroke
			(width 0)
			(type solid)
		)
		(fill yes)
		(layer "In11.Cu")
		(net "M_F_CPU0_SA_DQ<24>")
	)
	(gr_poly
		(pts
			(xy 327.384918 -238.206026) (xy 327.284842 -238.106204) (xy 327.18502 -238.206026) (xy 327.18502 -238.250476)
			(xy 327.384918 -238.250476)
		)
		(stroke
			(width 0)
			(type solid)
		)
		(fill yes)
		(layer "In11.Cu")
		(net "M_F_CPU0_SA_DQ<20>")
	)
	(gr_poly
		(pts
			(xy 327.384918 -234.966002) (xy 327.284842 -234.86618) (xy 327.18502 -234.966002) (xy 327.18502 -235.010452)
			(xy 327.384918 -235.010452)
		)
		(stroke
			(width 0)
			(type solid)
		)
		(fill yes)
		(layer "In11.Cu")
		(net "M_F_CPU0_SA_DQ<16>")
	)
	(gr_poly
		(pts
			(xy 327.384918 -233.34599) (xy 327.284842 -233.246168) (xy 327.18502 -233.34599) (xy 327.18502 -233.39044)
			(xy 327.384918 -233.39044)
		)
		(stroke
			(width 0)
			(type solid)
		)
		(fill yes)
		(layer "In11.Cu")
		(net "M_F_CPU0_SA_DQ<12>")
	)
	(gr_poly
		(pts
			(xy 327.391268 -250.762262) (xy 327.391268 -250.717812) (xy 327.191116 -250.717812) (xy 327.191116 -250.762262)
			(xy 327.291192 -250.862338)
		)
		(stroke
			(width 0)
			(type solid)
		)
		(fill yes)
		(layer "In11.Cu")
		(net "M_F_CPU0_RESET_N")
	)
	(gr_poly
		(pts
			(xy 327.392284 -227.941378) (xy 327.41235 -227.898198) (xy 327.231248 -227.813616) (xy 327.211182 -227.856796)
			(xy 327.259442 -227.989638)
		)
		(stroke
			(width 0)
			(type solid)
		)
		(fill yes)
		(layer "In11.Cu")
		(net "M_F_CPU0_SA_DQS_DP<5>")
	)
	(gr_poly
		(pts
			(xy 327.396856 -255.622298) (xy 327.396856 -255.577848) (xy 327.196958 -255.577848) (xy 327.196958 -255.622298)
			(xy 327.29678 -255.722374)
		)
		(stroke
			(width 0)
			(type solid)
		)
		(fill yes)
		(layer "In11.Cu")
		(net "M_F_CPU0_SA_PAR")
	)
	(gr_poly
		(pts
			(xy 327.396856 -254.002286) (xy 327.396856 -253.957836) (xy 327.196958 -253.957836) (xy 327.196958 -254.002286)
			(xy 327.29678 -254.102362)
		)
		(stroke
			(width 0)
			(type solid)
		)
		(fill yes)
		(layer "In11.Cu")
		(net "M_F_CPU0_SA_CA<3>")
	)
	(gr_poly
		(pts
			(xy 327.396856 -252.382274) (xy 327.396856 -252.337824) (xy 327.196958 -252.337824) (xy 327.196958 -252.382274)
			(xy 327.29678 -252.48235)
		)
		(stroke
			(width 0)
			(type solid)
		)
		(fill yes)
		(layer "In11.Cu")
		(net "M_F_CPU0_SA_CS_N<1>")
	)
	(gr_poly
		(pts
			(xy 327.396856 -249.14225) (xy 327.396856 -249.0978) (xy 327.196958 -249.0978) (xy 327.196958 -249.14225)
			(xy 327.29678 -249.242326)
		)
		(stroke
			(width 0)
			(type solid)
		)
		(fill yes)
		(layer "In11.Cu")
		(net "M_F_CPU0_SA_CB<7>")
	)
	(gr_poly
		(pts
			(xy 327.396856 -247.522492) (xy 327.396856 -247.474994) (xy 327.196958 -247.474994) (xy 327.196958 -247.522492)
			(xy 327.29678 -247.622568)
		)
		(stroke
			(width 0)
			(type solid)
		)
		(fill yes)
		(layer "In11.Cu")
		(net "M_F_CPU0_SA_DQS_DP<9>")
	)
	(gr_poly
		(pts
			(xy 327.396856 -245.902226) (xy 327.396856 -245.857776) (xy 327.196958 -245.857776) (xy 327.196958 -245.902226)
			(xy 327.29678 -246.002302)
		)
		(stroke
			(width 0)
			(type solid)
		)
		(fill yes)
		(layer "In11.Cu")
		(net "M_F_CPU0_SA_CB<3>")
	)
	(gr_poly
		(pts
			(xy 327.396856 -244.282214) (xy 327.396856 -244.237764) (xy 327.196958 -244.237764) (xy 327.196958 -244.282214)
			(xy 327.29678 -244.38229)
		)
		(stroke
			(width 0)
			(type solid)
		)
		(fill yes)
		(layer "In11.Cu")
		(net "M_F_CPU0_SA_DQ<31>")
	)
	(gr_poly
		(pts
			(xy 327.396856 -242.662456) (xy 327.396856 -242.614958) (xy 327.196958 -242.614958) (xy 327.196958 -242.662456)
			(xy 327.29678 -242.762532)
		)
		(stroke
			(width 0)
			(type solid)
		)
		(fill yes)
		(layer "In11.Cu")
		(net "M_F_CPU0_SA_DQS_DP<8>")
	)
	(gr_poly
		(pts
			(xy 327.396856 -239.422178) (xy 327.396856 -239.377728) (xy 327.196958 -239.377728) (xy 327.196958 -239.422178)
			(xy 327.29678 -239.522254)
		)
		(stroke
			(width 0)
			(type solid)
		)
		(fill yes)
		(layer "In11.Cu")
		(net "M_F_CPU0_SA_DQ<23>")
	)
	(gr_poly
		(pts
			(xy 327.396856 -237.80242) (xy 327.396856 -237.754922) (xy 327.196958 -237.754922) (xy 327.196958 -237.80242)
			(xy 327.29678 -237.902496)
		)
		(stroke
			(width 0)
			(type solid)
		)
		(fill yes)
		(layer "In11.Cu")
		(net "M_F_CPU0_SA_DQS_DP<7>")
	)
	(gr_poly
		(pts
			(xy 327.396856 -236.182154) (xy 327.396856 -236.137704) (xy 327.196958 -236.137704) (xy 327.196958 -236.182154)
			(xy 327.29678 -236.28223)
		)
		(stroke
			(width 0)
			(type solid)
		)
		(fill yes)
		(layer "In11.Cu")
		(net "M_F_CPU0_SA_DQ<19>")
	)
	(gr_poly
		(pts
			(xy 327.396856 -234.562142) (xy 327.396856 -234.517692) (xy 327.196958 -234.517692) (xy 327.196958 -234.562142)
			(xy 327.29678 -234.662218)
		)
		(stroke
			(width 0)
			(type solid)
		)
		(fill yes)
		(layer "In11.Cu")
		(net "M_F_CPU0_SA_DQ<15>")
	)
	(gr_poly
		(pts
			(xy 327.396856 -232.942384) (xy 327.396856 -232.894886) (xy 327.196958 -232.894886) (xy 327.196958 -232.942384)
			(xy 327.29678 -233.04246)
		)
		(stroke
			(width 0)
			(type solid)
		)
		(fill yes)
		(layer "In11.Cu")
		(net "M_F_CPU0_SA_DQS_DP<6>")
	)
	(gr_poly
		(pts
			(xy 327.401936 -256.026158) (xy 327.30186 -255.926082) (xy 327.202038 -256.026158) (xy 327.202038 -256.073656)
			(xy 327.401936 -256.073656)
		)
		(stroke
			(width 0)
			(type solid)
		)
		(fill yes)
		(layer "In11.Cu")
		(net "M_F_CPU0_CLK_DP<0>")
	)
	(gr_poly
		(pts
			(xy 327.402952 -241.042698) (xy 327.402952 -240.998248) (xy 327.203054 -240.998248) (xy 327.203054 -241.042698)
			(xy 327.302876 -241.142774)
		)
		(stroke
			(width 0)
			(type solid)
		)
		(fill yes)
		(layer "In11.Cu")
		(net "M_F_CPU0_SA_DQ<27>")
	)
	(gr_poly
		(pts
			(xy 327.409556 -226.464368) (xy 327.446132 -226.327716) (xy 327.30948 -226.29114) (xy 327.268332 -226.315016)
			(xy 327.368154 -226.488244)
		)
		(stroke
			(width 0)
			(type solid)
		)
		(fill yes)
		(layer "In11.Cu")
		(net "M_F_CPU0_SA_DQS_DP<0>")
	)
	(gr_poly
		(pts
			(xy 327.410064 -223.225614) (xy 327.44664 -223.088962) (xy 327.309988 -223.052386) (xy 327.271634 -223.074738)
			(xy 327.371456 -223.247966)
		)
		(stroke
			(width 0)
			(type solid)
		)
		(fill yes)
		(layer "In11.Cu")
		(net "M_F_CPU0_SA_DQ<1>")
	)
	(gr_poly
		(pts
			(xy 327.61047 -295.607232) (xy 327.571862 -295.58488) (xy 327.43521 -295.621456) (xy 327.47204 -295.758108)
			(xy 327.510394 -295.78046)
		)
		(stroke
			(width 0)
			(type solid)
		)
		(fill yes)
		(layer "In11.Cu")
		(net "M_F_CPU0_SB_DQ<29>")
	)
	(gr_poly
		(pts
			(xy 327.62063 -292.34892) (xy 327.582022 -292.326822) (xy 327.445624 -292.363398) (xy 327.4822 -292.50005)
			(xy 327.520554 -292.522148)
		)
		(stroke
			(width 0)
			(type solid)
		)
		(fill yes)
		(layer "In11.Cu")
		(net "M_F_CPU0_SB_DQ<28>")
	)
	(gr_poly
		(pts
			(xy 327.681336 -287.653984) (xy 327.681336 -287.609534) (xy 327.481438 -287.609534) (xy 327.481438 -287.653984)
			(xy 327.581514 -287.75406)
		)
		(stroke
			(width 0)
			(type solid)
		)
		(fill yes)
		(layer "In11.Cu")
		(net "M_F_CPU0_SB_DQ<22>")
	)
	(gr_poly
		(pts
			(xy 327.681336 -286.034226) (xy 327.681336 -285.986728) (xy 327.481438 -285.986728) (xy 327.481438 -286.034226)
			(xy 327.581514 -286.134302)
		)
		(stroke
			(width 0)
			(type solid)
		)
		(fill yes)
		(layer "In11.Cu")
		(net "M_F_CPU0_SB_DQS_DN<2>")
	)
	(gr_poly
		(pts
			(xy 327.681336 -281.17419) (xy 327.681336 -281.126692) (xy 327.481438 -281.126692) (xy 327.481438 -281.17419)
			(xy 327.581514 -281.274266)
		)
		(stroke
			(width 0)
			(type solid)
		)
		(fill yes)
		(layer "In11.Cu")
		(net "M_F_CPU0_SB_DQS_DN<1>")
	)
	(gr_poly
		(pts
			(xy 327.684892 -289.273996) (xy 327.684892 -289.229546) (xy 327.484994 -289.229546) (xy 327.484994 -289.273996)
			(xy 327.584816 -289.373818)
		)
		(stroke
			(width 0)
			(type solid)
		)
		(fill yes)
		(layer "In11.Cu")
		(net "M_F_CPU0_SB_DQ<26>")
	)
	(gr_poly
		(pts
			(xy 327.684892 -284.414214) (xy 327.684892 -284.369764) (xy 327.484994 -284.369764) (xy 327.484994 -284.414214)
			(xy 327.584816 -284.514036)
		)
		(stroke
			(width 0)
			(type solid)
		)
		(fill yes)
		(layer "In11.Cu")
		(net "M_F_CPU0_SB_DQ<18>")
	)
	(gr_poly
		(pts
			(xy 327.684892 -282.794202) (xy 327.684892 -282.749752) (xy 327.484994 -282.749752) (xy 327.484994 -282.794202)
			(xy 327.584816 -282.894024)
		)
		(stroke
			(width 0)
			(type solid)
		)
		(fill yes)
		(layer "In11.Cu")
		(net "M_F_CPU0_SB_DQ<14>")
	)
	(gr_poly
		(pts
			(xy 327.684892 -279.554178) (xy 327.684892 -279.509728) (xy 327.484994 -279.509728) (xy 327.484994 -279.554178)
			(xy 327.584816 -279.654)
		)
		(stroke
			(width 0)
			(type solid)
		)
		(fill yes)
		(layer "In11.Cu")
		(net "M_F_CPU0_SB_DQ<10>")
	)
	(gr_poly
		(pts
			(xy 327.684892 -277.934166) (xy 327.684892 -277.889716) (xy 327.484994 -277.889716) (xy 327.484994 -277.934166)
			(xy 327.584816 -278.033988)
		)
		(stroke
			(width 0)
			(type solid)
		)
		(fill yes)
		(layer "In11.Cu")
		(net "M_F_CPU0_SB_DQ<6>")
	)
	(gr_poly
		(pts
			(xy 327.684892 -274.694142) (xy 327.684892 -274.649692) (xy 327.484994 -274.649692) (xy 327.484994 -274.694142)
			(xy 327.584816 -274.793964)
		)
		(stroke
			(width 0)
			(type solid)
		)
		(fill yes)
		(layer "In11.Cu")
		(net "M_F_CPU0_SB_DQ<2>")
	)
	(gr_poly
		(pts
			(xy 327.684892 -273.07413) (xy 327.684892 -273.02968) (xy 327.484994 -273.02968) (xy 327.484994 -273.07413)
			(xy 327.584816 -273.173952)
		)
		(stroke
			(width 0)
			(type solid)
		)
		(fill yes)
		(layer "In11.Cu")
		(net "M_F_CPU0_SB_CB<2>")
	)
	(gr_poly
		(pts
			(xy 327.684892 -264.97407) (xy 327.684892 -264.92962) (xy 327.484994 -264.92962) (xy 327.484994 -264.97407)
			(xy 327.584816 -265.073892)
		)
		(stroke
			(width 0)
			(type solid)
		)
		(fill yes)
		(layer "In11.Cu")
		(net "M_F_CPU0_SB_PAR")
	)
	(gr_poly
		(pts
			(xy 327.692258 -290.894008) (xy 327.692258 -290.846256) (xy 327.492106 -290.846256) (xy 327.492106 -290.894008)
			(xy 327.592182 -290.99383)
		)
		(stroke
			(width 0)
			(type solid)
		)
		(fill yes)
		(layer "In11.Cu")
		(net "M_F_CPU0_SB_DQS_DN<3>")
	)
	(gr_poly
		(pts
			(xy 327.69683 -289.677856) (xy 327.596754 -289.57778) (xy 327.496678 -289.677856) (xy 327.496678 -289.722306)
			(xy 327.69683 -289.722306)
		)
		(stroke
			(width 0)
			(type solid)
		)
		(fill yes)
		(layer "In11.Cu")
		(net "M_F_CPU0_SB_DQ<25>")
	)
	(gr_poly
		(pts
			(xy 327.69683 -286.437832) (xy 327.596754 -286.337756) (xy 327.496678 -286.437832) (xy 327.496678 -286.48533)
			(xy 327.69683 -286.48533)
		)
		(stroke
			(width 0)
			(type solid)
		)
		(fill yes)
		(layer "In11.Cu")
		(net "M_F_CPU0_SB_DQS_DN<7>")
	)
	(gr_poly
		(pts
			(xy 327.69683 -284.818074) (xy 327.596754 -284.717998) (xy 327.496678 -284.818074) (xy 327.496678 -284.862524)
			(xy 327.69683 -284.862524)
		)
		(stroke
			(width 0)
			(type solid)
		)
		(fill yes)
		(layer "In11.Cu")
		(net "M_F_CPU0_SB_DQ<17>")
	)
	(gr_poly
		(pts
			(xy 327.69683 -283.198062) (xy 327.596754 -283.097986) (xy 327.496678 -283.198062) (xy 327.496678 -283.242512)
			(xy 327.69683 -283.242512)
		)
		(stroke
			(width 0)
			(type solid)
		)
		(fill yes)
		(layer "In11.Cu")
		(net "M_F_CPU0_SB_DQ<13>")
	)
	(gr_poly
		(pts
			(xy 327.698354 -269.834106) (xy 327.698354 -269.789656) (xy 327.498456 -269.789656) (xy 327.498456 -269.834106)
			(xy 327.598532 -269.933928)
		)
		(stroke
			(width 0)
			(type solid)
		)
		(fill yes)
		(layer "In11.Cu")
		(net "M_F_CPU0_SB_CB<6>")
	)
	(gr_poly
		(pts
			(xy 327.746614 -294.67048) (xy 327.710038 -294.533828) (xy 327.671684 -294.511476) (xy 327.571608 -294.684704)
			(xy 327.610216 -294.707056)
		)
		(stroke
			(width 0)
			(type solid)
		)
		(fill yes)
		(layer "In11.Cu")
		(net "M_F_CPU0_SB_DQ<30>")
	)
	(gr_poly
		(pts
			(xy 327.781412 -226.204526) (xy 327.681336 -226.031298) (xy 327.642728 -226.053396) (xy 327.606152 -226.190048)
			(xy 327.742804 -226.226624)
		)
		(stroke
			(width 0)
			(type solid)
		)
		(fill yes)
		(layer "In11.Cu")
		(net "M_F_CPU0_SA_DQ<3>")
	)
	(gr_poly
		(pts
			(xy 327.781412 -222.964502) (xy 327.681336 -222.791274) (xy 327.642728 -222.813372) (xy 327.606152 -222.950024)
			(xy 327.742804 -222.9866)
		)
		(stroke
			(width 0)
			(type solid)
		)
		(fill yes)
		(layer "In11.Cu")
		(net "M_F_CPU0_SA_DQ<2>")
	)
	(gr_poly
		(pts
			(xy 327.846944 -240.635536) (xy 327.747122 -240.53546) (xy 327.647046 -240.635536) (xy 327.647046 -240.679986)
			(xy 327.846944 -240.679986)
		)
		(stroke
			(width 0)
			(type solid)
		)
		(fill yes)
		(layer "In11.Cu")
		(net "M_F_CPU0_SA_DQ<25>")
	)
	(gr_poly
		(pts
			(xy 327.854818 -255.216152) (xy 327.754996 -255.116076) (xy 327.65492 -255.216152) (xy 327.65492 -255.260602)
			(xy 327.854818 -255.260602)
		)
		(stroke
			(width 0)
			(type solid)
		)
		(fill yes)
		(layer "In11.Cu")
		(net "M_F_CPU0_SA_CA<6>")
	)
	(gr_poly
		(pts
			(xy 327.854818 -253.59614) (xy 327.754996 -253.496064) (xy 327.65492 -253.59614) (xy 327.65492 -253.64059)
			(xy 327.854818 -253.64059)
		)
		(stroke
			(width 0)
			(type solid)
		)
		(fill yes)
		(layer "In11.Cu")
		(net "M_F_CPU0_SA_CA<2>")
	)
	(gr_poly
		(pts
			(xy 327.854818 -248.736104) (xy 327.754996 -248.636028) (xy 327.65492 -248.736104) (xy 327.65492 -248.780554)
			(xy 327.854818 -248.780554)
		)
		(stroke
			(width 0)
			(type solid)
		)
		(fill yes)
		(layer "In11.Cu")
		(net "M_F_CPU0_SA_CB<5>")
	)
	(gr_poly
		(pts
			(xy 327.854818 -247.115838) (xy 327.754996 -247.015762) (xy 327.65492 -247.115838) (xy 327.65492 -247.163336)
			(xy 327.854818 -247.163336)
		)
		(stroke
			(width 0)
			(type solid)
		)
		(fill yes)
		(layer "In11.Cu")
		(net "M_F_CPU0_SA_DQS_DN<9>")
	)
	(gr_poly
		(pts
			(xy 327.854818 -245.49608) (xy 327.754996 -245.396004) (xy 327.65492 -245.49608) (xy 327.65492 -245.54053)
			(xy 327.854818 -245.54053)
		)
		(stroke
			(width 0)
			(type solid)
		)
		(fill yes)
		(layer "In11.Cu")
		(net "M_F_CPU0_SA_CB<1>")
	)
	(gr_poly
		(pts
			(xy 327.854818 -243.876068) (xy 327.754996 -243.775992) (xy 327.65492 -243.876068) (xy 327.65492 -243.920518)
			(xy 327.854818 -243.920518)
		)
		(stroke
			(width 0)
			(type solid)
		)
		(fill yes)
		(layer "In11.Cu")
		(net "M_F_CPU0_SA_DQ<29>")
	)
	(gr_poly
		(pts
			(xy 327.854818 -242.255802) (xy 327.754996 -242.155726) (xy 327.65492 -242.255802) (xy 327.65492 -242.3033)
			(xy 327.854818 -242.3033)
		)
		(stroke
			(width 0)
			(type solid)
		)
		(fill yes)
		(layer "In11.Cu")
		(net "M_F_CPU0_SA_DQS_DN<8>")
	)
	(gr_poly
		(pts
			(xy 327.854818 -239.016032) (xy 327.754996 -238.915956) (xy 327.65492 -239.016032) (xy 327.65492 -239.060482)
			(xy 327.854818 -239.060482)
		)
		(stroke
			(width 0)
			(type solid)
		)
		(fill yes)
		(layer "In11.Cu")
		(net "M_F_CPU0_SA_DQ<21>")
	)
	(gr_poly
		(pts
			(xy 327.854818 -237.395766) (xy 327.754996 -237.29569) (xy 327.65492 -237.395766) (xy 327.65492 -237.443264)
			(xy 327.854818 -237.443264)
		)
		(stroke
			(width 0)
			(type solid)
		)
		(fill yes)
		(layer "In11.Cu")
		(net "M_F_CPU0_SA_DQS_DN<7>")
	)
	(gr_poly
		(pts
			(xy 327.854818 -235.776008) (xy 327.754996 -235.675932) (xy 327.65492 -235.776008) (xy 327.65492 -235.820458)
			(xy 327.854818 -235.820458)
		)
		(stroke
			(width 0)
			(type solid)
		)
		(fill yes)
		(layer "In11.Cu")
		(net "M_F_CPU0_SA_DQ<17>")
	)
	(gr_poly
		(pts
			(xy 327.854818 -234.155996) (xy 327.754996 -234.05592) (xy 327.65492 -234.155996) (xy 327.65492 -234.200446)
			(xy 327.854818 -234.200446)
		)
		(stroke
			(width 0)
			(type solid)
		)
		(fill yes)
		(layer "In11.Cu")
		(net "M_F_CPU0_SA_DQ<13>")
	)
	(gr_poly
		(pts
			(xy 327.854818 -232.53573) (xy 327.754996 -232.435654) (xy 327.65492 -232.53573) (xy 327.65492 -232.583228)
			(xy 327.854818 -232.583228)
		)
		(stroke
			(width 0)
			(type solid)
		)
		(fill yes)
		(layer "In11.Cu")
		(net "M_F_CPU0_SA_DQS_DN<6>")
	)
	(gr_poly
		(pts
			(xy 327.861168 -256.432558) (xy 327.861168 -256.384806) (xy 327.661016 -256.384806) (xy 327.661016 -256.432558)
			(xy 327.761092 -256.53238)
		)
		(stroke
			(width 0)
			(type solid)
		)
		(fill yes)
		(layer "In11.Cu")
		(net "M_F_CPU0_CLK_DN<0>")
	)
	(gr_poly
		(pts
			(xy 327.861168 -250.356116) (xy 327.761092 -250.25604) (xy 327.661016 -250.356116) (xy 327.661016 -250.400566)
			(xy 327.861168 -250.400566)
		)
		(stroke
			(width 0)
			(type solid)
		)
		(fill yes)
		(layer "In11.Cu")
		(net "M_F_CPU0_ALERT_R_N")
	)
	(gr_poly
		(pts
			(xy 327.86828 -254.812292) (xy 327.86828 -254.767842) (xy 327.668382 -254.767842) (xy 327.668382 -254.812292)
			(xy 327.768458 -254.912114)
		)
		(stroke
			(width 0)
			(type solid)
		)
		(fill yes)
		(layer "In11.Cu")
		(net "M_F_CPU0_SA_CA<5>")
	)
	(gr_poly
		(pts
			(xy 327.86828 -253.19228) (xy 327.86828 -253.14783) (xy 327.668382 -253.14783) (xy 327.668382 -253.19228)
			(xy 327.768458 -253.292102)
		)
		(stroke
			(width 0)
			(type solid)
		)
		(fill yes)
		(layer "In11.Cu")
		(net "M_F_CPU0_SA_CA<1>")
	)
	(gr_poly
		(pts
			(xy 327.86828 -251.572268) (xy 327.86828 -251.527818) (xy 327.668382 -251.527818) (xy 327.668382 -251.572268)
			(xy 327.768458 -251.67209)
		)
		(stroke
			(width 0)
			(type solid)
		)
		(fill yes)
		(layer "In11.Cu")
		(net "M_F_CPU0_SA_CS_N<0>")
	)
	(gr_poly
		(pts
			(xy 327.86828 -248.332244) (xy 327.86828 -248.287794) (xy 327.668382 -248.287794) (xy 327.668382 -248.332244)
			(xy 327.768458 -248.432066)
		)
		(stroke
			(width 0)
			(type solid)
		)
		(fill yes)
		(layer "In11.Cu")
		(net "M_F_CPU0_SA_CB<6>")
	)
	(gr_poly
		(pts
			(xy 327.86828 -245.09222) (xy 327.86828 -245.04777) (xy 327.668382 -245.04777) (xy 327.668382 -245.09222)
			(xy 327.768458 -245.192042)
		)
		(stroke
			(width 0)
			(type solid)
		)
		(fill yes)
		(layer "In11.Cu")
		(net "M_F_CPU0_SA_CB<2>")
	)
	(gr_poly
		(pts
			(xy 327.86828 -243.472208) (xy 327.86828 -243.427758) (xy 327.668382 -243.427758) (xy 327.668382 -243.472208)
			(xy 327.768458 -243.57203)
		)
		(stroke
			(width 0)
			(type solid)
		)
		(fill yes)
		(layer "In11.Cu")
		(net "M_F_CPU0_SA_DQ<30>")
	)
	(gr_poly
		(pts
			(xy 327.86828 -240.232184) (xy 327.86828 -240.187734) (xy 327.668382 -240.187734) (xy 327.668382 -240.232184)
			(xy 327.768458 -240.332006)
		)
		(stroke
			(width 0)
			(type solid)
		)
		(fill yes)
		(layer "In11.Cu")
		(net "M_F_CPU0_SA_DQ<26>")
	)
	(gr_poly
		(pts
			(xy 327.86828 -238.612172) (xy 327.86828 -238.567722) (xy 327.668382 -238.567722) (xy 327.668382 -238.612172)
			(xy 327.768458 -238.711994)
		)
		(stroke
			(width 0)
			(type solid)
		)
		(fill yes)
		(layer "In11.Cu")
		(net "M_F_CPU0_SA_DQ<22>")
	)
	(gr_poly
		(pts
			(xy 327.86828 -235.372148) (xy 327.86828 -235.327698) (xy 327.668382 -235.327698) (xy 327.668382 -235.372148)
			(xy 327.768458 -235.47197)
		)
		(stroke
			(width 0)
			(type solid)
		)
		(fill yes)
		(layer "In11.Cu")
		(net "M_F_CPU0_SA_DQ<18>")
	)
	(gr_poly
		(pts
			(xy 327.86828 -233.752136) (xy 327.86828 -233.707686) (xy 327.668382 -233.707686) (xy 327.668382 -233.752136)
			(xy 327.768458 -233.851958)
		)
		(stroke
			(width 0)
			(type solid)
		)
		(fill yes)
		(layer "In11.Cu")
		(net "M_F_CPU0_SA_DQ<14>")
	)
	(gr_poly
		(pts
			(xy 327.871836 -246.712232) (xy 327.871836 -246.664734) (xy 327.671938 -246.664734) (xy 327.671938 -246.712232)
			(xy 327.77176 -246.812308)
		)
		(stroke
			(width 0)
			(type solid)
		)
		(fill yes)
		(layer "In11.Cu")
		(net "M_F_CPU0_SA_DQS_DN<4>")
	)
	(gr_poly
		(pts
			(xy 327.871836 -241.852196) (xy 327.871836 -241.804698) (xy 327.671938 -241.804698) (xy 327.671938 -241.852196)
			(xy 327.77176 -241.952272)
		)
		(stroke
			(width 0)
			(type solid)
		)
		(fill yes)
		(layer "In11.Cu")
		(net "M_F_CPU0_SA_DQS_DN<3>")
	)
	(gr_poly
		(pts
			(xy 327.871836 -236.99216) (xy 327.871836 -236.944662) (xy 327.671938 -236.944662) (xy 327.671938 -236.99216)
			(xy 327.77176 -237.092236)
		)
		(stroke
			(width 0)
			(type solid)
		)
		(fill yes)
		(layer "In11.Cu")
		(net "M_F_CPU0_SA_DQS_DN<2>")
	)
	(gr_poly
		(pts
			(xy 327.871836 -232.132124) (xy 327.871836 -232.084626) (xy 327.671938 -232.084626) (xy 327.671938 -232.132124)
			(xy 327.77176 -232.2322)
		)
		(stroke
			(width 0)
			(type solid)
		)
		(fill yes)
		(layer "In11.Cu")
		(net "M_F_CPU0_SA_DQS_DN<1>")
	)
	(gr_poly
		(pts
			(xy 327.871836 -230.512112) (xy 327.871836 -230.467662) (xy 327.671938 -230.467662) (xy 327.671938 -230.512112)
			(xy 327.77176 -230.612188)
		)
		(stroke
			(width 0)
			(type solid)
		)
		(fill yes)
		(layer "In11.Cu")
		(net "M_F_CPU0_SA_DQ<10>")
	)
	(gr_poly
		(pts
			(xy 327.871836 -227.272342) (xy 327.871836 -227.224844) (xy 327.671938 -227.224844) (xy 327.671938 -227.272342)
			(xy 327.77176 -227.372418)
		)
		(stroke
			(width 0)
			(type solid)
		)
		(fill yes)
		(layer "In11.Cu")
		(net "M_F_CPU0_SA_DQS_DN<0>")
	)
	(gr_poly
		(pts
			(xy 327.879964 -224.035112) (xy 327.91654 -223.89846) (xy 327.779888 -223.861884) (xy 327.74128 -223.883982)
			(xy 327.841356 -224.05721)
		)
		(stroke
			(width 0)
			(type solid)
		)
		(fill yes)
		(layer "In11.Cu")
		(net "M_F_CPU0_SA_DQ<1>")
	)
	(gr_poly
		(pts
			(xy 327.880218 -225.655632) (xy 327.916794 -225.51898) (xy 327.780142 -225.482404) (xy 327.741788 -225.504756)
			(xy 327.84161 -225.677984)
		)
		(stroke
			(width 0)
			(type solid)
		)
		(fill yes)
		(layer "In11.Cu")
		(net "M_F_CPU0_SA_DQ<1>")
	)
	(gr_poly
		(pts
			(xy 327.880218 -222.415608) (xy 327.916794 -222.278956) (xy 327.780142 -222.24238) (xy 327.741788 -222.264732)
			(xy 327.84161 -222.43796)
		)
		(stroke
			(width 0)
			(type solid)
		)
		(fill yes)
		(layer "In11.Cu")
		(net "M_F_CPU0_SA_DQ<0>")
	)
	(gr_poly
		(pts
			(xy 327.916794 -224.569528) (xy 327.880218 -224.432876) (xy 327.84161 -224.410524) (xy 327.741788 -224.583752)
			(xy 327.780142 -224.606104)
		)
		(stroke
			(width 0)
			(type solid)
		)
		(fill yes)
		(layer "In11.Cu")
		(net "M_F_CPU0_SA_DQ<1>")
	)
	(gr_poly
		(pts
			(xy 328.07275 -281.995626) (xy 328.081132 -281.948636) (xy 327.884028 -281.914092) (xy 327.8759 -281.960828)
			(xy 327.956926 -282.076652)
		)
		(stroke
			(width 0)
			(type solid)
		)
		(fill yes)
		(layer "In11.Cu")
		(net "M_F_CPU0_SB_DQS_DP<6>")
	)
	(gr_poly
		(pts
			(xy 328.081386 -294.795702) (xy 328.042778 -294.773604) (xy 327.906126 -294.81018) (xy 327.942702 -294.946832)
			(xy 327.98131 -294.96893)
		)
		(stroke
			(width 0)
			(type solid)
		)
		(fill yes)
		(layer "In11.Cu")
		(net "M_F_CPU0_SB_DQ<29>")
	)
	(gr_poly
		(pts
			(xy 328.155046 -290.084002) (xy 328.155046 -290.039552) (xy 327.954894 -290.039552) (xy 327.954894 -290.084002)
			(xy 328.05497 -290.184078)
		)
		(stroke
			(width 0)
			(type solid)
		)
		(fill yes)
		(layer "In11.Cu")
		(net "M_F_CPU0_SB_DQ<27>")
	)
	(gr_poly
		(pts
			(xy 328.155046 -288.464244) (xy 328.155046 -288.419794) (xy 327.954894 -288.419794) (xy 327.954894 -288.464244)
			(xy 328.05497 -288.56432)
		)
		(stroke
			(width 0)
			(type solid)
		)
		(fill yes)
		(layer "In11.Cu")
		(net "M_F_CPU0_SB_DQ<23>")
	)
	(gr_poly
		(pts
			(xy 328.155046 -286.844232) (xy 328.155046 -286.796734) (xy 327.954894 -286.796734) (xy 327.954894 -286.844232)
			(xy 328.05497 -286.944308)
		)
		(stroke
			(width 0)
			(type solid)
		)
		(fill yes)
		(layer "In11.Cu")
		(net "M_F_CPU0_SB_DQS_DP<7>")
	)
	(gr_poly
		(pts
			(xy 328.155046 -285.22422) (xy 328.155046 -285.17977) (xy 327.954894 -285.17977) (xy 327.954894 -285.22422)
			(xy 328.05497 -285.324296)
		)
		(stroke
			(width 0)
			(type solid)
		)
		(fill yes)
		(layer "In11.Cu")
		(net "M_F_CPU0_SB_DQ<19>")
	)
	(gr_poly
		(pts
			(xy 328.155046 -283.604208) (xy 328.155046 -283.559758) (xy 327.954894 -283.559758) (xy 327.954894 -283.604208)
			(xy 328.05497 -283.704284)
		)
		(stroke
			(width 0)
			(type solid)
		)
		(fill yes)
		(layer "In11.Cu")
		(net "M_F_CPU0_SB_DQ<15>")
	)
	(gr_poly
		(pts
			(xy 328.155046 -280.364184) (xy 328.155046 -280.319734) (xy 327.954894 -280.319734) (xy 327.954894 -280.364184)
			(xy 328.05497 -280.46426)
		)
		(stroke
			(width 0)
			(type solid)
		)
		(fill yes)
		(layer "In11.Cu")
		(net "M_F_CPU0_SB_DQ<11>")
	)
	(gr_poly
		(pts
			(xy 328.155046 -278.744172) (xy 328.155046 -278.699722) (xy 327.954894 -278.699722) (xy 327.954894 -278.744172)
			(xy 328.05497 -278.844248)
		)
		(stroke
			(width 0)
			(type solid)
		)
		(fill yes)
		(layer "In11.Cu")
		(net "M_F_CPU0_SB_DQ<7>")
	)
	(gr_poly
		(pts
			(xy 328.155046 -275.504148) (xy 328.155046 -275.459698) (xy 327.954894 -275.459698) (xy 327.954894 -275.504148)
			(xy 328.05497 -275.604224)
		)
		(stroke
			(width 0)
			(type solid)
		)
		(fill yes)
		(layer "In11.Cu")
		(net "M_F_CPU0_SB_DQ<3>")
	)
	(gr_poly
		(pts
			(xy 328.155046 -273.884136) (xy 328.155046 -273.839686) (xy 327.954894 -273.839686) (xy 327.954894 -273.884136)
			(xy 328.05497 -273.984212)
		)
		(stroke
			(width 0)
			(type solid)
		)
		(fill yes)
		(layer "In11.Cu")
		(net "M_F_CPU0_SB_CB<3>")
	)
	(gr_poly
		(pts
			(xy 328.155046 -270.644112) (xy 328.155046 -270.599662) (xy 327.954894 -270.599662) (xy 327.954894 -270.644112)
			(xy 328.05497 -270.744188)
		)
		(stroke
			(width 0)
			(type solid)
		)
		(fill yes)
		(layer "In11.Cu")
		(net "M_F_CPU0_SB_CB<7>")
	)
	(gr_poly
		(pts
			(xy 328.155046 -265.784076) (xy 328.155046 -265.739626) (xy 327.954894 -265.739626) (xy 327.954894 -265.784076)
			(xy 328.05497 -265.884152)
		)
		(stroke
			(width 0)
			(type solid)
		)
		(fill yes)
		(layer "In11.Cu")
		(net "M_F_CPU0_SB_CS_N<0>")
	)
	(gr_poly
		(pts
			(xy 328.155046 -262.544052) (xy 328.155046 -262.499602) (xy 327.954894 -262.499602) (xy 327.954894 -262.544052)
			(xy 328.05497 -262.644128)
		)
		(stroke
			(width 0)
			(type solid)
		)
		(fill yes)
		(layer "In11.Cu")
		(net "M_F_CPU0_SB_CA<1>")
	)
	(gr_poly
		(pts
			(xy 328.161142 -292.107874) (xy 328.061066 -292.007798) (xy 327.96099 -292.107874) (xy 327.96099 -292.152324)
			(xy 328.161142 -292.152324)
		)
		(stroke
			(width 0)
			(type solid)
		)
		(fill yes)
		(layer "In11.Cu")
		(net "M_F_CPU0_SB_DQ<28>")
	)
	(gr_poly
		(pts
			(xy 328.161142 -277.123906) (xy 328.161142 -277.076408) (xy 327.96099 -277.076408) (xy 327.96099 -277.123906)
			(xy 328.061066 -277.223982)
		)
		(stroke
			(width 0)
			(type solid)
		)
		(fill yes)
		(layer "In11.Cu")
		(net "M_F_CPU0_SB_DQS_DP<5>")
	)
	(gr_poly
		(pts
			(xy 328.161142 -272.26387) (xy 328.161142 -272.216372) (xy 327.96099 -272.216372) (xy 327.96099 -272.26387)
			(xy 328.061066 -272.363946)
		)
		(stroke
			(width 0)
			(type solid)
		)
		(fill yes)
		(layer "In11.Cu")
		(net "M_F_CPU0_SB_DQS_DP<4>")
	)
	(gr_poly
		(pts
			(xy 328.161142 -269.42796) (xy 328.061066 -269.327884) (xy 327.96099 -269.42796) (xy 327.96099 -269.47241)
			(xy 328.161142 -269.47241)
		)
		(stroke
			(width 0)
			(type solid)
		)
		(fill yes)
		(layer "In11.Cu")
		(net "M_F_CPU0_SB_CB<4>")
	)
	(gr_poly
		(pts
			(xy 328.161396 -267.807948) (xy 328.06132 -267.707872) (xy 327.961244 -267.807948) (xy 327.961244 -267.852398)
			(xy 328.161396 -267.852398)
		)
		(stroke
			(width 0)
			(type solid)
		)
		(fill yes)
		(layer "In11.Cu")
		(net "M_F_CPU0_SB_RSP<0>")
	)
	(gr_poly
		(pts
			(xy 328.168254 -288.86785) (xy 328.068432 -288.768028) (xy 327.968356 -288.86785) (xy 327.968356 -288.9123)
			(xy 328.168254 -288.9123)
		)
		(stroke
			(width 0)
			(type solid)
		)
		(fill yes)
		(layer "In11.Cu")
		(net "M_F_CPU0_SB_DQ<24>")
	)
	(gr_poly
		(pts
			(xy 328.168254 -284.008068) (xy 328.068432 -283.908246) (xy 327.968356 -284.008068) (xy 327.968356 -284.052518)
			(xy 328.168254 -284.052518)
		)
		(stroke
			(width 0)
			(type solid)
		)
		(fill yes)
		(layer "In11.Cu")
		(net "M_F_CPU0_SB_DQ<16>")
	)
	(gr_poly
		(pts
			(xy 328.168254 -282.388056) (xy 328.068432 -282.288234) (xy 327.968356 -282.388056) (xy 327.968356 -282.432506)
			(xy 328.168254 -282.432506)
		)
		(stroke
			(width 0)
			(type solid)
		)
		(fill yes)
		(layer "In11.Cu")
		(net "M_F_CPU0_SB_DQ<12>")
	)
	(gr_poly
		(pts
			(xy 328.168254 -279.148032) (xy 328.068432 -279.04821) (xy 327.968356 -279.148032) (xy 327.968356 -279.192482)
			(xy 328.168254 -279.192482)
		)
		(stroke
			(width 0)
			(type solid)
		)
		(fill yes)
		(layer "In11.Cu")
		(net "M_F_CPU0_SB_DQ<8>")
	)
	(gr_poly
		(pts
			(xy 328.168254 -277.52802) (xy 328.068432 -277.428198) (xy 327.968356 -277.52802) (xy 327.968356 -277.57247)
			(xy 328.168254 -277.57247)
		)
		(stroke
			(width 0)
			(type solid)
		)
		(fill yes)
		(layer "In11.Cu")
		(net "M_F_CPU0_SB_DQ<4>")
	)
	(gr_poly
		(pts
			(xy 328.168254 -274.287996) (xy 328.068432 -274.188174) (xy 327.968356 -274.287996) (xy 327.968356 -274.332446)
			(xy 328.168254 -274.332446)
		)
		(stroke
			(width 0)
			(type solid)
		)
		(fill yes)
		(layer "In11.Cu")
		(net "M_F_CPU0_SB_DQ<0>")
	)
	(gr_poly
		(pts
			(xy 328.168254 -272.667984) (xy 328.068432 -272.568162) (xy 327.968356 -272.667984) (xy 327.968356 -272.712434)
			(xy 328.168254 -272.712434)
		)
		(stroke
			(width 0)
			(type solid)
		)
		(fill yes)
		(layer "In11.Cu")
		(net "M_F_CPU0_SB_CB<0>")
	)
	(gr_poly
		(pts
			(xy 328.168254 -264.567924) (xy 328.068432 -264.468102) (xy 327.968356 -264.567924) (xy 327.968356 -264.612374)
			(xy 328.168254 -264.612374)
		)
		(stroke
			(width 0)
			(type solid)
		)
		(fill yes)
		(layer "In11.Cu")
		(net "M_F_CPU0_SB_CA<6>")
	)
	(gr_poly
		(pts
			(xy 328.17181 -290.487862) (xy 328.071734 -290.387786) (xy 327.971912 -290.487862) (xy 327.971912 -290.53536)
			(xy 328.17181 -290.53536)
		)
		(stroke
			(width 0)
			(type solid)
		)
		(fill yes)
		(layer "In11.Cu")
		(net "M_F_CPU0_SB_DQS_DP<3>")
	)
	(gr_poly
		(pts
			(xy 328.17181 -287.248092) (xy 328.071734 -287.148016) (xy 327.971912 -287.248092) (xy 327.971912 -287.292542)
			(xy 328.17181 -287.292542)
		)
		(stroke
			(width 0)
			(type solid)
		)
		(fill yes)
		(layer "In11.Cu")
		(net "M_F_CPU0_SB_DQ<20>")
	)
	(gr_poly
		(pts
			(xy 328.17181 -285.62808) (xy 328.071734 -285.528004) (xy 327.971912 -285.62808) (xy 327.971912 -285.675578)
			(xy 328.17181 -285.675578)
		)
		(stroke
			(width 0)
			(type solid)
		)
		(fill yes)
		(layer "In11.Cu")
		(net "M_F_CPU0_SB_DQS_DP<2>")
	)
	(gr_poly
		(pts
			(xy 328.17181 -280.768044) (xy 328.071734 -280.667968) (xy 327.971912 -280.768044) (xy 327.971912 -280.815542)
			(xy 328.17181 -280.815542)
		)
		(stroke
			(width 0)
			(type solid)
		)
		(fill yes)
		(layer "In11.Cu")
		(net "M_F_CPU0_SB_DQS_DP<1>")
	)
	(gr_poly
		(pts
			(xy 328.17181 -275.908008) (xy 328.071734 -275.807932) (xy 327.971912 -275.908008) (xy 327.971912 -275.955506)
			(xy 328.17181 -275.955506)
		)
		(stroke
			(width 0)
			(type solid)
		)
		(fill yes)
		(layer "In11.Cu")
		(net "M_F_CPU0_SB_DQS_DP<0>")
	)
	(gr_poly
		(pts
			(xy 328.17181 -271.047972) (xy 328.071734 -270.947896) (xy 327.971912 -271.047972) (xy 327.971912 -271.09547)
			(xy 328.17181 -271.09547)
		)
		(stroke
			(width 0)
			(type solid)
		)
		(fill yes)
		(layer "In11.Cu")
		(net "M_F_CPU0_SB_DQS_DP<9>")
	)
	(gr_poly
		(pts
			(xy 328.179938 -264.164064) (xy 328.179938 -264.119614) (xy 327.979786 -264.119614) (xy 327.979786 -264.164064)
			(xy 328.079862 -264.263886)
		)
		(stroke
			(width 0)
			(type solid)
		)
		(fill yes)
		(layer "In11.Cu")
		(net "M_F_CPU0_SB_CA<5>")
	)
	(gr_poly
		(pts
			(xy 328.18197 -262.948166) (xy 328.081894 -262.848344) (xy 327.981818 -262.948166) (xy 327.981818 -262.992616)
			(xy 328.18197 -262.992616)
		)
		(stroke
			(width 0)
			(type solid)
		)
		(fill yes)
		(layer "In11.Cu")
		(net "M_F_CPU0_SB_CA<2>")
	)
	(gr_poly
		(pts
			(xy 328.217022 -293.860474) (xy 328.180446 -293.723822) (xy 328.142092 -293.70147) (xy 328.042016 -293.874698)
			(xy 328.080624 -293.89705)
		)
		(stroke
			(width 0)
			(type solid)
		)
		(fill yes)
		(layer "In11.Cu")
		(net "M_F_CPU0_SB_DQ<30>")
	)
	(gr_poly
		(pts
			(xy 328.250042 -225.392488) (xy 328.149966 -225.21926) (xy 328.111612 -225.241612) (xy 328.074782 -225.37801)
			(xy 328.211434 -225.41484)
		)
		(stroke
			(width 0)
			(type solid)
		)
		(fill yes)
		(layer "In11.Cu")
		(net "M_F_CPU0_SA_DQ<2>")
	)
	(gr_poly
		(pts
			(xy 328.250042 -224.69602) (xy 328.211434 -224.673668) (xy 328.074782 -224.710498) (xy 328.111612 -224.846896)
			(xy 328.149966 -224.869248)
		)
		(stroke
			(width 0)
			(type solid)
		)
		(fill yes)
		(layer "In11.Cu")
		(net "M_F_CPU0_SA_DQ<2>")
	)
	(gr_poly
		(pts
			(xy 328.251312 -223.774508) (xy 328.151236 -223.60128) (xy 328.112628 -223.623378) (xy 328.076052 -223.76003)
			(xy 328.212704 -223.796606)
		)
		(stroke
			(width 0)
			(type solid)
		)
		(fill yes)
		(layer "In11.Cu")
		(net "M_F_CPU0_SA_DQ<2>")
	)
	(gr_poly
		(pts
			(xy 328.330052 -231.322372) (xy 328.330052 -231.277922) (xy 328.13244 -231.277922) (xy 328.13244 -231.322372)
			(xy 328.231246 -231.422448)
		)
		(stroke
			(width 0)
			(type solid)
		)
		(fill yes)
		(layer "In11.Cu")
		(net "M_F_CPU0_SA_DQ<11>")
	)
	(gr_poly
		(pts
			(xy 328.331322 -256.025904) (xy 328.231246 -255.926082) (xy 328.13117 -256.025904) (xy 328.13117 -256.073656)
			(xy 328.331322 -256.073656)
		)
		(stroke
			(width 0)
			(type solid)
		)
		(fill yes)
		(layer "In11.Cu")
		(net "M_F_CPU0_CLK_DP<0>")
	)
	(gr_poly
		(pts
			(xy 328.331322 -255.622298) (xy 328.331322 -255.577848) (xy 328.13117 -255.577848) (xy 328.13117 -255.622298)
			(xy 328.231246 -255.722374)
		)
		(stroke
			(width 0)
			(type solid)
		)
		(fill yes)
		(layer "In11.Cu")
		(net "M_F_CPU0_SA_PAR")
	)
	(gr_poly
		(pts
			(xy 328.331322 -254.406146) (xy 328.231246 -254.30607) (xy 328.13117 -254.406146) (xy 328.13117 -254.450596)
			(xy 328.331322 -254.450596)
		)
		(stroke
			(width 0)
			(type solid)
		)
		(fill yes)
		(layer "In11.Cu")
		(net "M_F_CPU0_SA_CA<4>")
	)
	(gr_poly
		(pts
			(xy 328.331322 -254.002286) (xy 328.331322 -253.957836) (xy 328.13117 -253.957836) (xy 328.13117 -254.002286)
			(xy 328.231246 -254.102362)
		)
		(stroke
			(width 0)
			(type solid)
		)
		(fill yes)
		(layer "In11.Cu")
		(net "M_F_CPU0_SA_CA<3>")
	)
	(gr_poly
		(pts
			(xy 328.331322 -252.786134) (xy 328.231246 -252.686058) (xy 328.13117 -252.786134) (xy 328.13117 -252.830584)
			(xy 328.331322 -252.830584)
		)
		(stroke
			(width 0)
			(type solid)
		)
		(fill yes)
		(layer "In11.Cu")
		(net "M_F_CPU0_SA_CA<0>")
	)
	(gr_poly
		(pts
			(xy 328.331322 -252.382274) (xy 328.331322 -252.337824) (xy 328.13117 -252.337824) (xy 328.13117 -252.382274)
			(xy 328.231246 -252.48235)
		)
		(stroke
			(width 0)
			(type solid)
		)
		(fill yes)
		(layer "In11.Cu")
		(net "M_F_CPU0_SA_CS_N<1>")
	)
	(gr_poly
		(pts
			(xy 328.331322 -250.762262) (xy 328.331322 -250.717812) (xy 328.13117 -250.717812) (xy 328.13117 -250.762262)
			(xy 328.231246 -250.862338)
		)
		(stroke
			(width 0)
			(type solid)
		)
		(fill yes)
		(layer "In11.Cu")
		(net "M_F_CPU0_RESET_N")
	)
	(gr_poly
		(pts
			(xy 328.331322 -249.14225) (xy 328.331322 -249.0978) (xy 328.13117 -249.0978) (xy 328.13117 -249.14225)
			(xy 328.231246 -249.242326)
		)
		(stroke
			(width 0)
			(type solid)
		)
		(fill yes)
		(layer "In11.Cu")
		(net "M_F_CPU0_SA_CB<7>")
	)
	(gr_poly
		(pts
			(xy 328.331322 -247.926098) (xy 328.231246 -247.826022) (xy 328.13117 -247.926098) (xy 328.13117 -247.970548)
			(xy 328.331322 -247.970548)
		)
		(stroke
			(width 0)
			(type solid)
		)
		(fill yes)
		(layer "In11.Cu")
		(net "M_F_CPU0_SA_CB<4>")
	)
	(gr_poly
		(pts
			(xy 328.331322 -247.522492) (xy 328.331322 -247.47474) (xy 328.13117 -247.47474) (xy 328.13117 -247.522492)
			(xy 328.231246 -247.622314)
		)
		(stroke
			(width 0)
			(type solid)
		)
		(fill yes)
		(layer "In11.Cu")
		(net "M_F_CPU0_SA_DQS_DP<9>")
	)
	(gr_poly
		(pts
			(xy 328.331322 -246.305832) (xy 328.231246 -246.20601) (xy 328.13117 -246.305832) (xy 328.13117 -246.353584)
			(xy 328.331322 -246.353584)
		)
		(stroke
			(width 0)
			(type solid)
		)
		(fill yes)
		(layer "In11.Cu")
		(net "M_F_CPU0_SA_DQS_DP<4>")
	)
	(gr_poly
		(pts
			(xy 328.331322 -245.902226) (xy 328.331322 -245.857776) (xy 328.13117 -245.857776) (xy 328.13117 -245.902226)
			(xy 328.231246 -246.002302)
		)
		(stroke
			(width 0)
			(type solid)
		)
		(fill yes)
		(layer "In11.Cu")
		(net "M_F_CPU0_SA_CB<3>")
	)
	(gr_poly
		(pts
			(xy 328.331322 -244.686074) (xy 328.231246 -244.585998) (xy 328.13117 -244.686074) (xy 328.13117 -244.730524)
			(xy 328.331322 -244.730524)
		)
		(stroke
			(width 0)
			(type solid)
		)
		(fill yes)
		(layer "In11.Cu")
		(net "M_F_CPU0_SA_CB<0>")
	)
	(gr_poly
		(pts
			(xy 328.331322 -244.282214) (xy 328.331322 -244.237764) (xy 328.13117 -244.237764) (xy 328.13117 -244.282214)
			(xy 328.231246 -244.38229)
		)
		(stroke
			(width 0)
			(type solid)
		)
		(fill yes)
		(layer "In11.Cu")
		(net "M_F_CPU0_SA_DQ<31>")
	)
	(gr_poly
		(pts
			(xy 328.331322 -243.066062) (xy 328.231246 -242.965986) (xy 328.13117 -243.066062) (xy 328.13117 -243.110512)
			(xy 328.331322 -243.110512)
		)
		(stroke
			(width 0)
			(type solid)
		)
		(fill yes)
		(layer "In11.Cu")
		(net "M_F_CPU0_SA_DQ<28>")
	)
	(gr_poly
		(pts
			(xy 328.331322 -242.662456) (xy 328.331322 -242.614704) (xy 328.13117 -242.614704) (xy 328.13117 -242.662456)
			(xy 328.231246 -242.762278)
		)
		(stroke
			(width 0)
			(type solid)
		)
		(fill yes)
		(layer "In11.Cu")
		(net "M_F_CPU0_SA_DQS_DP<8>")
	)
	(gr_poly
		(pts
			(xy 328.331322 -241.445796) (xy 328.231246 -241.345974) (xy 328.13117 -241.445796) (xy 328.13117 -241.493548)
			(xy 328.331322 -241.493548)
		)
		(stroke
			(width 0)
			(type solid)
		)
		(fill yes)
		(layer "In11.Cu")
		(net "M_F_CPU0_SA_DQS_DP<3>")
	)
	(gr_poly
		(pts
			(xy 328.331322 -241.04219) (xy 328.331322 -240.99774) (xy 328.13117 -240.99774) (xy 328.13117 -241.04219)
			(xy 328.231246 -241.142266)
		)
		(stroke
			(width 0)
			(type solid)
		)
		(fill yes)
		(layer "In11.Cu")
		(net "M_F_CPU0_SA_DQ<27>")
	)
	(gr_poly
		(pts
			(xy 328.331322 -239.826038) (xy 328.231246 -239.725962) (xy 328.13117 -239.826038) (xy 328.13117 -239.870488)
			(xy 328.331322 -239.870488)
		)
		(stroke
			(width 0)
			(type solid)
		)
		(fill yes)
		(layer "In11.Cu")
		(net "M_F_CPU0_SA_DQ<24>")
	)
	(gr_poly
		(pts
			(xy 328.331322 -239.422178) (xy 328.331322 -239.377728) (xy 328.13117 -239.377728) (xy 328.13117 -239.422178)
			(xy 328.231246 -239.522254)
		)
		(stroke
			(width 0)
			(type solid)
		)
		(fill yes)
		(layer "In11.Cu")
		(net "M_F_CPU0_SA_DQ<23>")
	)
	(gr_poly
		(pts
			(xy 328.331322 -238.206026) (xy 328.231246 -238.10595) (xy 328.13117 -238.206026) (xy 328.13117 -238.250476)
			(xy 328.331322 -238.250476)
		)
		(stroke
			(width 0)
			(type solid)
		)
		(fill yes)
		(layer "In11.Cu")
		(net "M_F_CPU0_SA_DQ<20>")
	)
	(gr_poly
		(pts
			(xy 328.331322 -237.80242) (xy 328.331322 -237.754668) (xy 328.13117 -237.754668) (xy 328.13117 -237.80242)
			(xy 328.231246 -237.902242)
		)
		(stroke
			(width 0)
			(type solid)
		)
		(fill yes)
		(layer "In11.Cu")
		(net "M_F_CPU0_SA_DQS_DP<7>")
	)
	(gr_poly
		(pts
			(xy 328.331322 -236.58576) (xy 328.231246 -236.485938) (xy 328.13117 -236.58576) (xy 328.13117 -236.633512)
			(xy 328.331322 -236.633512)
		)
		(stroke
			(width 0)
			(type solid)
		)
		(fill yes)
		(layer "In11.Cu")
		(net "M_F_CPU0_SA_DQS_DP<2>")
	)
	(gr_poly
		(pts
			(xy 328.331322 -236.182154) (xy 328.331322 -236.137704) (xy 328.13117 -236.137704) (xy 328.13117 -236.182154)
			(xy 328.231246 -236.28223)
		)
		(stroke
			(width 0)
			(type solid)
		)
		(fill yes)
		(layer "In11.Cu")
		(net "M_F_CPU0_SA_DQ<19>")
	)
	(gr_poly
		(pts
			(xy 328.331322 -234.966002) (xy 328.231246 -234.865926) (xy 328.13117 -234.966002) (xy 328.13117 -235.010452)
			(xy 328.331322 -235.010452)
		)
		(stroke
			(width 0)
			(type solid)
		)
		(fill yes)
		(layer "In11.Cu")
		(net "M_F_CPU0_SA_DQ<16>")
	)
	(gr_poly
		(pts
			(xy 328.331322 -234.562142) (xy 328.331322 -234.517692) (xy 328.13117 -234.517692) (xy 328.13117 -234.562142)
			(xy 328.231246 -234.662218)
		)
		(stroke
			(width 0)
			(type solid)
		)
		(fill yes)
		(layer "In11.Cu")
		(net "M_F_CPU0_SA_DQ<15>")
	)
	(gr_poly
		(pts
			(xy 328.331322 -233.34599) (xy 328.231246 -233.245914) (xy 328.13117 -233.34599) (xy 328.13117 -233.39044)
			(xy 328.331322 -233.39044)
		)
		(stroke
			(width 0)
			(type solid)
		)
		(fill yes)
		(layer "In11.Cu")
		(net "M_F_CPU0_SA_DQ<12>")
	)
	(gr_poly
		(pts
			(xy 328.331322 -232.942384) (xy 328.331322 -232.894632) (xy 328.13117 -232.894632) (xy 328.13117 -232.942384)
			(xy 328.231246 -233.042206)
		)
		(stroke
			(width 0)
			(type solid)
		)
		(fill yes)
		(layer "In11.Cu")
		(net "M_F_CPU0_SA_DQS_DP<6>")
	)
	(gr_poly
		(pts
			(xy 328.331322 -231.725724) (xy 328.231246 -231.625902) (xy 328.13117 -231.725724) (xy 328.13117 -231.773476)
			(xy 328.331322 -231.773476)
		)
		(stroke
			(width 0)
			(type solid)
		)
		(fill yes)
		(layer "In11.Cu")
		(net "M_F_CPU0_SA_DQS_DP<1>")
	)
	(gr_poly
		(pts
			(xy 328.331322 -230.105966) (xy 328.231246 -230.006144) (xy 328.13117 -230.105966) (xy 328.13117 -230.150416)
			(xy 328.331322 -230.150416)
		)
		(stroke
			(width 0)
			(type solid)
		)
		(fill yes)
		(layer "In11.Cu")
		(net "M_F_CPU0_SA_DQ<8>")
	)
	(gr_poly
		(pts
			(xy 328.331322 -229.70236) (xy 328.331322 -229.65791) (xy 328.13117 -229.65791) (xy 328.13117 -229.70236)
			(xy 328.231246 -229.802436)
		)
		(stroke
			(width 0)
			(type solid)
		)
		(fill yes)
		(layer "In11.Cu")
		(net "M_F_CPU0_SA_DQ<7>")
	)
	(gr_poly
		(pts
			(xy 328.331322 -228.486208) (xy 328.231246 -228.386132) (xy 328.13117 -228.486208) (xy 328.13117 -228.530658)
			(xy 328.331322 -228.530658)
		)
		(stroke
			(width 0)
			(type solid)
		)
		(fill yes)
		(layer "In11.Cu")
		(net "M_F_CPU0_SA_DQ<4>")
	)
	(gr_poly
		(pts
			(xy 328.331322 -228.082602) (xy 328.331322 -228.03485) (xy 328.13117 -228.03485) (xy 328.13117 -228.082602)
			(xy 328.231246 -228.182424)
		)
		(stroke
			(width 0)
			(type solid)
		)
		(fill yes)
		(layer "In11.Cu")
		(net "M_F_CPU0_SA_DQS_DP<5>")
	)
	(gr_poly
		(pts
			(xy 328.331322 -226.865942) (xy 328.231246 -226.76612) (xy 328.13117 -226.865942) (xy 328.13117 -226.913694)
			(xy 328.331322 -226.913694)
		)
		(stroke
			(width 0)
			(type solid)
		)
		(fill yes)
		(layer "In11.Cu")
		(net "M_F_CPU0_SA_DQS_DP<0>")
	)
	(gr_poly
		(pts
			(xy 328.331322 -226.462336) (xy 328.331322 -226.417886) (xy 328.13117 -226.417886) (xy 328.13117 -226.462336)
			(xy 328.231246 -226.562412)
		)
		(stroke
			(width 0)
			(type solid)
		)
		(fill yes)
		(layer "In11.Cu")
		(net "M_F_CPU0_SA_DQ<3>")
	)
	(gr_poly
		(pts
			(xy 328.349864 -223.225106) (xy 328.38644 -223.088454) (xy 328.249788 -223.051878) (xy 328.21118 -223.073976)
			(xy 328.311256 -223.247204)
		)
		(stroke
			(width 0)
			(type solid)
		)
		(fill yes)
		(layer "In11.Cu")
		(net "M_F_CPU0_SA_DQ<0>")
	)
	(gr_poly
		(pts
			(xy 328.55027 -293.98722) (xy 328.511662 -293.964868) (xy 328.37501 -294.001444) (xy 328.41184 -294.138096)
			(xy 328.450194 -294.160448)
		)
		(stroke
			(width 0)
			(type solid)
		)
		(fill yes)
		(layer "In11.Cu")
		(net "M_F_CPU0_SB_DQ<29>")
	)
	(gr_poly
		(pts
			(xy 328.631296 -291.297614) (xy 328.53122 -291.197792) (xy 328.431144 -291.297614) (xy 328.431144 -291.345366)
			(xy 328.631296 -291.345366)
		)
		(stroke
			(width 0)
			(type solid)
		)
		(fill yes)
		(layer "In11.Cu")
		(net "M_F_CPU0_SB_DQS_DN<8>")
	)
	(gr_poly
		(pts
			(xy 328.631296 -290.894262) (xy 328.631296 -290.84651) (xy 328.431144 -290.84651) (xy 328.431144 -290.894262)
			(xy 328.53122 -290.994084)
		)
		(stroke
			(width 0)
			(type solid)
		)
		(fill yes)
		(layer "In11.Cu")
		(net "M_F_CPU0_SB_DQS_DN<3>")
	)
	(gr_poly
		(pts
			(xy 328.631296 -289.677856) (xy 328.53122 -289.57778) (xy 328.431144 -289.677856) (xy 328.431144 -289.722306)
			(xy 328.631296 -289.722306)
		)
		(stroke
			(width 0)
			(type solid)
		)
		(fill yes)
		(layer "In11.Cu")
		(net "M_F_CPU0_SB_DQ<25>")
	)
	(gr_poly
		(pts
			(xy 328.631296 -289.273996) (xy 328.631296 -289.229546) (xy 328.431144 -289.229546) (xy 328.431144 -289.273996)
			(xy 328.53122 -289.374072)
		)
		(stroke
			(width 0)
			(type solid)
		)
		(fill yes)
		(layer "In11.Cu")
		(net "M_F_CPU0_SB_DQ<26>")
	)
	(gr_poly
		(pts
			(xy 328.631296 -288.057844) (xy 328.53122 -287.957768) (xy 328.431144 -288.057844) (xy 328.431144 -288.102294)
			(xy 328.631296 -288.102294)
		)
		(stroke
			(width 0)
			(type solid)
		)
		(fill yes)
		(layer "In11.Cu")
		(net "M_F_CPU0_SB_DQ<21>")
	)
	(gr_poly
		(pts
			(xy 328.631296 -287.654238) (xy 328.631296 -287.609788) (xy 328.431144 -287.609788) (xy 328.431144 -287.654238)
			(xy 328.53122 -287.75406)
		)
		(stroke
			(width 0)
			(type solid)
		)
		(fill yes)
		(layer "In11.Cu")
		(net "M_F_CPU0_SB_DQ<22>")
	)
	(gr_poly
		(pts
			(xy 328.631296 -286.437832) (xy 328.53122 -286.337756) (xy 328.431144 -286.437832) (xy 328.431144 -286.485584)
			(xy 328.631296 -286.485584)
		)
		(stroke
			(width 0)
			(type solid)
		)
		(fill yes)
		(layer "In11.Cu")
		(net "M_F_CPU0_SB_DQS_DN<7>")
	)
	(gr_poly
		(pts
			(xy 328.631296 -286.03448) (xy 328.631296 -285.986728) (xy 328.431144 -285.986728) (xy 328.431144 -286.03448)
			(xy 328.53122 -286.134302)
		)
		(stroke
			(width 0)
			(type solid)
		)
		(fill yes)
		(layer "In11.Cu")
		(net "M_F_CPU0_SB_DQS_DN<2>")
	)
	(gr_poly
		(pts
			(xy 328.631296 -284.818074) (xy 328.53122 -284.717998) (xy 328.431144 -284.818074) (xy 328.431144 -284.862524)
			(xy 328.631296 -284.862524)
		)
		(stroke
			(width 0)
			(type solid)
		)
		(fill yes)
		(layer "In11.Cu")
		(net "M_F_CPU0_SB_DQ<17>")
	)
	(gr_poly
		(pts
			(xy 328.631296 -284.414214) (xy 328.631296 -284.369764) (xy 328.431144 -284.369764) (xy 328.431144 -284.414214)
			(xy 328.53122 -284.51429)
		)
		(stroke
			(width 0)
			(type solid)
		)
		(fill yes)
		(layer "In11.Cu")
		(net "M_F_CPU0_SB_DQ<18>")
	)
	(gr_poly
		(pts
			(xy 328.631296 -283.198062) (xy 328.53122 -283.097986) (xy 328.431144 -283.198062) (xy 328.431144 -283.242512)
			(xy 328.631296 -283.242512)
		)
		(stroke
			(width 0)
			(type solid)
		)
		(fill yes)
		(layer "In11.Cu")
		(net "M_F_CPU0_SB_DQ<13>")
	)
	(gr_poly
		(pts
			(xy 328.631296 -282.794202) (xy 328.631296 -282.749752) (xy 328.431144 -282.749752) (xy 328.431144 -282.794202)
			(xy 328.53122 -282.894278)
		)
		(stroke
			(width 0)
			(type solid)
		)
		(fill yes)
		(layer "In11.Cu")
		(net "M_F_CPU0_SB_DQ<14>")
	)
	(gr_poly
		(pts
			(xy 328.631296 -281.577796) (xy 328.53122 -281.477974) (xy 328.431144 -281.577796) (xy 328.431144 -281.625548)
			(xy 328.631296 -281.625548)
		)
		(stroke
			(width 0)
			(type solid)
		)
		(fill yes)
		(layer "In11.Cu")
		(net "M_F_CPU0_SB_DQS_DN<6>")
	)
	(gr_poly
		(pts
			(xy 328.631296 -281.174444) (xy 328.631296 -281.126692) (xy 328.431144 -281.126692) (xy 328.431144 -281.174444)
			(xy 328.53122 -281.274266)
		)
		(stroke
			(width 0)
			(type solid)
		)
		(fill yes)
		(layer "In11.Cu")
		(net "M_F_CPU0_SB_DQS_DN<1>")
	)
	(gr_poly
		(pts
			(xy 328.631296 -279.958038) (xy 328.53122 -279.857962) (xy 328.431144 -279.958038) (xy 328.431144 -280.002488)
			(xy 328.631296 -280.002488)
		)
		(stroke
			(width 0)
			(type solid)
		)
		(fill yes)
		(layer "In11.Cu")
		(net "M_F_CPU0_SB_DQ<9>")
	)
	(gr_poly
		(pts
			(xy 328.631296 -279.554178) (xy 328.631296 -279.509728) (xy 328.431144 -279.509728) (xy 328.431144 -279.554178)
			(xy 328.53122 -279.654254)
		)
		(stroke
			(width 0)
			(type solid)
		)
		(fill yes)
		(layer "In11.Cu")
		(net "M_F_CPU0_SB_DQ<10>")
	)
	(gr_poly
		(pts
			(xy 328.631296 -278.338026) (xy 328.53122 -278.23795) (xy 328.431144 -278.338026) (xy 328.431144 -278.382476)
			(xy 328.631296 -278.382476)
		)
		(stroke
			(width 0)
			(type solid)
		)
		(fill yes)
		(layer "In11.Cu")
		(net "M_F_CPU0_SB_DQ<5>")
	)
	(gr_poly
		(pts
			(xy 328.631296 -277.934166) (xy 328.631296 -277.889716) (xy 328.431144 -277.889716) (xy 328.431144 -277.934166)
			(xy 328.53122 -278.034242)
		)
		(stroke
			(width 0)
			(type solid)
		)
		(fill yes)
		(layer "In11.Cu")
		(net "M_F_CPU0_SB_DQ<6>")
	)
	(gr_poly
		(pts
			(xy 328.631296 -276.71776) (xy 328.53122 -276.617938) (xy 328.431144 -276.71776) (xy 328.431144 -276.765512)
			(xy 328.631296 -276.765512)
		)
		(stroke
			(width 0)
			(type solid)
		)
		(fill yes)
		(layer "In11.Cu")
		(net "M_F_CPU0_SB_DQS_DN<5>")
	)
	(gr_poly
		(pts
			(xy 328.631296 -276.314408) (xy 328.631296 -276.266656) (xy 328.431144 -276.266656) (xy 328.431144 -276.314408)
			(xy 328.53122 -276.41423)
		)
		(stroke
			(width 0)
			(type solid)
		)
		(fill yes)
		(layer "In11.Cu")
		(net "M_F_CPU0_SB_DQS_DN<0>")
	)
	(gr_poly
		(pts
			(xy 328.631296 -275.098002) (xy 328.53122 -274.997926) (xy 328.431144 -275.098002) (xy 328.431144 -275.142452)
			(xy 328.631296 -275.142452)
		)
		(stroke
			(width 0)
			(type solid)
		)
		(fill yes)
		(layer "In11.Cu")
		(net "M_F_CPU0_SB_DQ<1>")
	)
	(gr_poly
		(pts
			(xy 328.631296 -274.694142) (xy 328.631296 -274.649692) (xy 328.431144 -274.649692) (xy 328.431144 -274.694142)
			(xy 328.53122 -274.794218)
		)
		(stroke
			(width 0)
			(type solid)
		)
		(fill yes)
		(layer "In11.Cu")
		(net "M_F_CPU0_SB_DQ<2>")
	)
	(gr_poly
		(pts
			(xy 328.631296 -273.47799) (xy 328.53122 -273.377914) (xy 328.431144 -273.47799) (xy 328.431144 -273.52244)
			(xy 328.631296 -273.52244)
		)
		(stroke
			(width 0)
			(type solid)
		)
		(fill yes)
		(layer "In11.Cu")
		(net "M_F_CPU0_SB_CB<1>")
	)
	(gr_poly
		(pts
			(xy 328.631296 -273.07413) (xy 328.631296 -273.02968) (xy 328.431144 -273.02968) (xy 328.431144 -273.07413)
			(xy 328.53122 -273.174206)
		)
		(stroke
			(width 0)
			(type solid)
		)
		(fill yes)
		(layer "In11.Cu")
		(net "M_F_CPU0_SB_CB<2>")
	)
	(gr_poly
		(pts
			(xy 328.631296 -271.857724) (xy 328.53122 -271.757902) (xy 328.431144 -271.857724) (xy 328.431144 -271.905476)
			(xy 328.631296 -271.905476)
		)
		(stroke
			(width 0)
			(type solid)
		)
		(fill yes)
		(layer "In11.Cu")
		(net "M_F_CPU0_SB_DQS_DN<4>")
	)
	(gr_poly
		(pts
			(xy 328.631296 -271.454372) (xy 328.631296 -271.40662) (xy 328.431144 -271.40662) (xy 328.431144 -271.454372)
			(xy 328.53122 -271.554194)
		)
		(stroke
			(width 0)
			(type solid)
		)
		(fill yes)
		(layer "In11.Cu")
		(net "M_F_CPU0_SB_DQS_DN<9>")
	)
	(gr_poly
		(pts
			(xy 328.631296 -270.237966) (xy 328.53122 -270.13789) (xy 328.431144 -270.237966) (xy 328.431144 -270.282416)
			(xy 328.631296 -270.282416)
		)
		(stroke
			(width 0)
			(type solid)
		)
		(fill yes)
		(layer "In11.Cu")
		(net "M_F_CPU0_SB_CB<5>")
	)
	(gr_poly
		(pts
			(xy 328.631296 -269.834106) (xy 328.631296 -269.789656) (xy 328.431144 -269.789656) (xy 328.431144 -269.834106)
			(xy 328.53122 -269.934182)
		)
		(stroke
			(width 0)
			(type solid)
		)
		(fill yes)
		(layer "In11.Cu")
		(net "M_F_CPU0_SB_CB<6>")
	)
	(gr_poly
		(pts
			(xy 328.631296 -266.997942) (xy 328.53122 -266.897866) (xy 328.431144 -266.997942) (xy 328.431144 -267.042392)
			(xy 328.631296 -267.042392)
		)
		(stroke
			(width 0)
			(type solid)
		)
		(fill yes)
		(layer "In11.Cu")
		(net "M_F_CPU0_SA_RSP<0>")
	)
	(gr_poly
		(pts
			(xy 328.631296 -266.594082) (xy 328.631296 -266.549632) (xy 328.431144 -266.549632) (xy 328.431144 -266.594082)
			(xy 328.53122 -266.694158)
		)
		(stroke
			(width 0)
			(type solid)
		)
		(fill yes)
		(layer "In11.Cu")
		(net "M_F_CPU0_SB_CS_N<1>")
	)
	(gr_poly
		(pts
			(xy 328.631296 -264.97407) (xy 328.631296 -264.92962) (xy 328.431144 -264.92962) (xy 328.431144 -264.97407)
			(xy 328.53122 -265.074146)
		)
		(stroke
			(width 0)
			(type solid)
		)
		(fill yes)
		(layer "In11.Cu")
		(net "M_F_CPU0_SB_PAR")
	)
	(gr_poly
		(pts
			(xy 328.631296 -263.757918) (xy 328.53122 -263.657842) (xy 328.431144 -263.757918) (xy 328.431144 -263.802368)
			(xy 328.631296 -263.802368)
		)
		(stroke
			(width 0)
			(type solid)
		)
		(fill yes)
		(layer "In11.Cu")
		(net "M_F_CPU0_SB_CA<4>")
	)
	(gr_poly
		(pts
			(xy 328.631296 -263.354058) (xy 328.631296 -263.309608) (xy 328.431144 -263.309608) (xy 328.431144 -263.354058)
			(xy 328.53122 -263.454134)
		)
		(stroke
			(width 0)
			(type solid)
		)
		(fill yes)
		(layer "In11.Cu")
		(net "M_F_CPU0_SB_CA<3>")
	)
	(gr_poly
		(pts
			(xy 328.631296 -262.137906) (xy 328.53122 -262.03783) (xy 328.431144 -262.137906) (xy 328.431144 -262.182356)
			(xy 328.631296 -262.182356)
		)
		(stroke
			(width 0)
			(type solid)
		)
		(fill yes)
		(layer "In11.Cu")
		(net "M_F_CPU0_SB_CA<0>")
	)
	(gr_poly
		(pts
			(xy 328.676254 -296.308526) (xy 328.639678 -296.171874) (xy 328.601324 -296.149776) (xy 328.501248 -296.323004)
			(xy 328.539602 -296.345102)
		)
		(stroke
			(width 0)
			(type solid)
		)
		(fill yes)
		(layer "In11.Cu")
		(net "M_F_CPU0_SB_DQ<31>")
	)
	(gr_poly
		(pts
			(xy 328.676508 -293.068502) (xy 328.639932 -292.93185) (xy 328.601324 -292.909498) (xy 328.501502 -293.082726)
			(xy 328.539856 -293.105078)
		)
		(stroke
			(width 0)
			(type solid)
		)
		(fill yes)
		(layer "In11.Cu")
		(net "M_F_CPU0_SB_DQ<30>")
	)
	(gr_poly
		(pts
			(xy 328.799952 -230.915972) (xy 328.701146 -230.815896) (xy 328.60234 -230.915972) (xy 328.60234 -230.960422)
			(xy 328.799952 -230.960422)
		)
		(stroke
			(width 0)
			(type solid)
		)
		(fill yes)
		(layer "In11.Cu")
		(net "M_F_CPU0_SA_DQ<9>")
	)
	(gr_poly
		(pts
			(xy 328.801222 -256.432558) (xy 328.801222 -256.384806) (xy 328.60107 -256.384806) (xy 328.60107 -256.432558)
			(xy 328.701146 -256.53238)
		)
		(stroke
			(width 0)
			(type solid)
		)
		(fill yes)
		(layer "In11.Cu")
		(net "M_F_CPU0_CLK_DN<0>")
	)
	(gr_poly
		(pts
			(xy 328.801222 -255.216152) (xy 328.701146 -255.116076) (xy 328.60107 -255.216152) (xy 328.60107 -255.260602)
			(xy 328.801222 -255.260602)
		)
		(stroke
			(width 0)
			(type solid)
		)
		(fill yes)
		(layer "In11.Cu")
		(net "M_F_CPU0_SA_CA<6>")
	)
	(gr_poly
		(pts
			(xy 328.801222 -254.812292) (xy 328.801222 -254.767842) (xy 328.60107 -254.767842) (xy 328.60107 -254.812292)
			(xy 328.701146 -254.912368)
		)
		(stroke
			(width 0)
			(type solid)
		)
		(fill yes)
		(layer "In11.Cu")
		(net "M_F_CPU0_SA_CA<5>")
	)
	(gr_poly
		(pts
			(xy 328.801222 -253.59614) (xy 328.701146 -253.496064) (xy 328.60107 -253.59614) (xy 328.60107 -253.64059)
			(xy 328.801222 -253.64059)
		)
		(stroke
			(width 0)
			(type solid)
		)
		(fill yes)
		(layer "In11.Cu")
		(net "M_F_CPU0_SA_CA<2>")
	)
	(gr_poly
		(pts
			(xy 328.801222 -253.19228) (xy 328.801222 -253.14783) (xy 328.60107 -253.14783) (xy 328.60107 -253.19228)
			(xy 328.701146 -253.292356)
		)
		(stroke
			(width 0)
			(type solid)
		)
		(fill yes)
		(layer "In11.Cu")
		(net "M_F_CPU0_SA_CA<1>")
	)
	(gr_poly
		(pts
			(xy 328.801222 -251.572268) (xy 328.801222 -251.527818) (xy 328.60107 -251.527818) (xy 328.60107 -251.572268)
			(xy 328.701146 -251.672344)
		)
		(stroke
			(width 0)
			(type solid)
		)
		(fill yes)
		(layer "In11.Cu")
		(net "M_F_CPU0_SA_CS_N<0>")
	)
	(gr_poly
		(pts
			(xy 328.801222 -250.356116) (xy 328.701146 -250.25604) (xy 328.60107 -250.356116) (xy 328.60107 -250.400566)
			(xy 328.801222 -250.400566)
		)
		(stroke
			(width 0)
			(type solid)
		)
		(fill yes)
		(layer "In11.Cu")
		(net "M_F_CPU0_ALERT_R_N")
	)
	(gr_poly
		(pts
			(xy 328.801222 -248.736104) (xy 328.701146 -248.636028) (xy 328.60107 -248.736104) (xy 328.60107 -248.780554)
			(xy 328.801222 -248.780554)
		)
		(stroke
			(width 0)
			(type solid)
		)
		(fill yes)
		(layer "In11.Cu")
		(net "M_F_CPU0_SA_CB<5>")
	)
	(gr_poly
		(pts
			(xy 328.801222 -248.332244) (xy 328.801222 -248.287794) (xy 328.60107 -248.287794) (xy 328.60107 -248.332244)
			(xy 328.701146 -248.43232)
		)
		(stroke
			(width 0)
			(type solid)
		)
		(fill yes)
		(layer "In11.Cu")
		(net "M_F_CPU0_SA_CB<6>")
	)
	(gr_poly
		(pts
			(xy 328.801222 -247.115838) (xy 328.701146 -247.016016) (xy 328.60107 -247.115838) (xy 328.60107 -247.16359)
			(xy 328.801222 -247.16359)
		)
		(stroke
			(width 0)
			(type solid)
		)
		(fill yes)
		(layer "In11.Cu")
		(net "M_F_CPU0_SA_DQS_DN<9>")
	)
	(gr_poly
		(pts
			(xy 328.801222 -246.712486) (xy 328.801222 -246.664734) (xy 328.60107 -246.664734) (xy 328.60107 -246.712486)
			(xy 328.701146 -246.812308)
		)
		(stroke
			(width 0)
			(type solid)
		)
		(fill yes)
		(layer "In11.Cu")
		(net "M_F_CPU0_SA_DQS_DN<4>")
	)
	(gr_poly
		(pts
			(xy 328.801222 -245.49608) (xy 328.701146 -245.396004) (xy 328.60107 -245.49608) (xy 328.60107 -245.54053)
			(xy 328.801222 -245.54053)
		)
		(stroke
			(width 0)
			(type solid)
		)
		(fill yes)
		(layer "In11.Cu")
		(net "M_F_CPU0_SA_CB<1>")
	)
	(gr_poly
		(pts
			(xy 328.801222 -245.09222) (xy 328.801222 -245.04777) (xy 328.60107 -245.04777) (xy 328.60107 -245.09222)
			(xy 328.701146 -245.192296)
		)
		(stroke
			(width 0)
			(type solid)
		)
		(fill yes)
		(layer "In11.Cu")
		(net "M_F_CPU0_SA_CB<2>")
	)
	(gr_poly
		(pts
			(xy 328.801222 -243.876068) (xy 328.701146 -243.775992) (xy 328.60107 -243.876068) (xy 328.60107 -243.920518)
			(xy 328.801222 -243.920518)
		)
		(stroke
			(width 0)
			(type solid)
		)
		(fill yes)
		(layer "In11.Cu")
		(net "M_F_CPU0_SA_DQ<29>")
	)
	(gr_poly
		(pts
			(xy 328.801222 -243.472208) (xy 328.801222 -243.427758) (xy 328.60107 -243.427758) (xy 328.60107 -243.472208)
			(xy 328.701146 -243.572284)
		)
		(stroke
			(width 0)
			(type solid)
		)
		(fill yes)
		(layer "In11.Cu")
		(net "M_F_CPU0_SA_DQ<30>")
	)
	(gr_poly
		(pts
			(xy 328.801222 -242.255802) (xy 328.701146 -242.15598) (xy 328.60107 -242.255802) (xy 328.60107 -242.303554)
			(xy 328.801222 -242.303554)
		)
		(stroke
			(width 0)
			(type solid)
		)
		(fill yes)
		(layer "In11.Cu")
		(net "M_F_CPU0_SA_DQS_DN<8>")
	)
	(gr_poly
		(pts
			(xy 328.801222 -241.85245) (xy 328.801222 -241.804698) (xy 328.60107 -241.804698) (xy 328.60107 -241.85245)
			(xy 328.701146 -241.952272)
		)
		(stroke
			(width 0)
			(type solid)
		)
		(fill yes)
		(layer "In11.Cu")
		(net "M_F_CPU0_SA_DQS_DN<3>")
	)
	(gr_poly
		(pts
			(xy 328.801222 -240.636044) (xy 328.701146 -240.535968) (xy 328.60107 -240.636044) (xy 328.60107 -240.680494)
			(xy 328.801222 -240.680494)
		)
		(stroke
			(width 0)
			(type solid)
		)
		(fill yes)
		(layer "In11.Cu")
		(net "M_F_CPU0_SA_DQ<25>")
	)
	(gr_poly
		(pts
			(xy 328.801222 -240.232184) (xy 328.801222 -240.187734) (xy 328.60107 -240.187734) (xy 328.60107 -240.232184)
			(xy 328.701146 -240.33226)
		)
		(stroke
			(width 0)
			(type solid)
		)
		(fill yes)
		(layer "In11.Cu")
		(net "M_F_CPU0_SA_DQ<26>")
	)
	(gr_poly
		(pts
			(xy 328.801222 -239.016032) (xy 328.701146 -238.915956) (xy 328.60107 -239.016032) (xy 328.60107 -239.060482)
			(xy 328.801222 -239.060482)
		)
		(stroke
			(width 0)
			(type solid)
		)
		(fill yes)
		(layer "In11.Cu")
		(net "M_F_CPU0_SA_DQ<21>")
	)
	(gr_poly
		(pts
			(xy 328.801222 -238.612172) (xy 328.801222 -238.567722) (xy 328.60107 -238.567722) (xy 328.60107 -238.612172)
			(xy 328.701146 -238.712248)
		)
		(stroke
			(width 0)
			(type solid)
		)
		(fill yes)
		(layer "In11.Cu")
		(net "M_F_CPU0_SA_DQ<22>")
	)
	(gr_poly
		(pts
			(xy 328.801222 -237.395766) (xy 328.701146 -237.295944) (xy 328.60107 -237.395766) (xy 328.60107 -237.443518)
			(xy 328.801222 -237.443518)
		)
		(stroke
			(width 0)
			(type solid)
		)
		(fill yes)
		(layer "In11.Cu")
		(net "M_F_CPU0_SA_DQS_DN<7>")
	)
	(gr_poly
		(pts
			(xy 328.801222 -236.992414) (xy 328.801222 -236.944662) (xy 328.60107 -236.944662) (xy 328.60107 -236.992414)
			(xy 328.701146 -237.092236)
		)
		(stroke
			(width 0)
			(type solid)
		)
		(fill yes)
		(layer "In11.Cu")
		(net "M_F_CPU0_SA_DQS_DN<2>")
	)
	(gr_poly
		(pts
			(xy 328.801222 -235.776008) (xy 328.701146 -235.675932) (xy 328.60107 -235.776008) (xy 328.60107 -235.820458)
			(xy 328.801222 -235.820458)
		)
		(stroke
			(width 0)
			(type solid)
		)
		(fill yes)
		(layer "In11.Cu")
		(net "M_F_CPU0_SA_DQ<17>")
	)
	(gr_poly
		(pts
			(xy 328.801222 -235.372148) (xy 328.801222 -235.327698) (xy 328.60107 -235.327698) (xy 328.60107 -235.372148)
			(xy 328.701146 -235.472224)
		)
		(stroke
			(width 0)
			(type solid)
		)
		(fill yes)
		(layer "In11.Cu")
		(net "M_F_CPU0_SA_DQ<18>")
	)
	(gr_poly
		(pts
			(xy 328.801222 -234.155996) (xy 328.701146 -234.05592) (xy 328.60107 -234.155996) (xy 328.60107 -234.200446)
			(xy 328.801222 -234.200446)
		)
		(stroke
			(width 0)
			(type solid)
		)
		(fill yes)
		(layer "In11.Cu")
		(net "M_F_CPU0_SA_DQ<13>")
	)
	(gr_poly
		(pts
			(xy 328.801222 -233.752136) (xy 328.801222 -233.707686) (xy 328.60107 -233.707686) (xy 328.60107 -233.752136)
			(xy 328.701146 -233.852212)
		)
		(stroke
			(width 0)
			(type solid)
		)
		(fill yes)
		(layer "In11.Cu")
		(net "M_F_CPU0_SA_DQ<14>")
	)
	(gr_poly
		(pts
			(xy 328.801222 -232.53573) (xy 328.701146 -232.435908) (xy 328.60107 -232.53573) (xy 328.60107 -232.583482)
			(xy 328.801222 -232.583482)
		)
		(stroke
			(width 0)
			(type solid)
		)
		(fill yes)
		(layer "In11.Cu")
		(net "M_F_CPU0_SA_DQS_DN<6>")
	)
	(gr_poly
		(pts
			(xy 328.801222 -232.132378) (xy 328.801222 -232.084626) (xy 328.60107 -232.084626) (xy 328.60107 -232.132378)
			(xy 328.701146 -232.2322)
		)
		(stroke
			(width 0)
			(type solid)
		)
		(fill yes)
		(layer "In11.Cu")
		(net "M_F_CPU0_SA_DQS_DN<1>")
	)
	(gr_poly
		(pts
			(xy 328.801222 -230.512366) (xy 328.801222 -230.467916) (xy 328.60107 -230.467916) (xy 328.60107 -230.512366)
			(xy 328.701146 -230.612188)
		)
		(stroke
			(width 0)
			(type solid)
		)
		(fill yes)
		(layer "In11.Cu")
		(net "M_F_CPU0_SA_DQ<10>")
	)
	(gr_poly
		(pts
			(xy 328.801222 -229.29596) (xy 328.701146 -229.195884) (xy 328.60107 -229.29596) (xy 328.60107 -229.34041)
			(xy 328.801222 -229.34041)
		)
		(stroke
			(width 0)
			(type solid)
		)
		(fill yes)
		(layer "In11.Cu")
		(net "M_F_CPU0_SA_DQ<5>")
	)
	(gr_poly
		(pts
			(xy 328.801222 -228.892354) (xy 328.801222 -228.847904) (xy 328.60107 -228.847904) (xy 328.60107 -228.892354)
			(xy 328.701146 -228.99243)
		)
		(stroke
			(width 0)
			(type solid)
		)
		(fill yes)
		(layer "In11.Cu")
		(net "M_F_CPU0_SA_DQ<6>")
	)
	(gr_poly
		(pts
			(xy 328.801222 -227.675948) (xy 328.701146 -227.576126) (xy 328.60107 -227.675948) (xy 328.60107 -227.7237)
			(xy 328.801222 -227.7237)
		)
		(stroke
			(width 0)
			(type solid)
		)
		(fill yes)
		(layer "In11.Cu")
		(net "M_F_CPU0_SA_DQS_DN<5>")
	)
	(gr_poly
		(pts
			(xy 328.801222 -227.272596) (xy 328.801222 -227.224844) (xy 328.60107 -227.224844) (xy 328.60107 -227.272596)
			(xy 328.701146 -227.372418)
		)
		(stroke
			(width 0)
			(type solid)
		)
		(fill yes)
		(layer "In11.Cu")
		(net "M_F_CPU0_SA_DQS_DN<0>")
	)
	(gr_poly
		(pts
			(xy 328.801222 -226.05619) (xy 328.701146 -225.956114) (xy 328.60107 -226.05619) (xy 328.60107 -226.10064)
			(xy 328.801222 -226.10064)
		)
		(stroke
			(width 0)
			(type solid)
		)
		(fill yes)
		(layer "In11.Cu")
		(net "M_F_CPU0_SA_DQ<1>")
	)
	(gr_poly
		(pts
			(xy 328.801222 -225.65233) (xy 328.801222 -225.60788) (xy 328.60107 -225.60788) (xy 328.60107 -225.65233)
			(xy 328.701146 -225.752406)
		)
		(stroke
			(width 0)
			(type solid)
		)
		(fill yes)
		(layer "In11.Cu")
		(net "M_F_CPU0_SA_DQ<2>")
	)
	(gr_poly
		(pts
			(xy 328.819764 -224.035112) (xy 328.85634 -223.89846) (xy 328.719688 -223.861884) (xy 328.68108 -223.883982)
			(xy 328.781156 -224.05721)
		)
		(stroke
			(width 0)
			(type solid)
		)
		(fill yes)
		(layer "In11.Cu")
		(net "M_F_CPU0_SA_DQ<0>")
	)
	(gr_poly
		(pts
			(xy 328.856594 -224.569528) (xy 328.820018 -224.432876) (xy 328.78141 -224.410524) (xy 328.681588 -224.583752)
			(xy 328.719942 -224.606104)
		)
		(stroke
			(width 0)
			(type solid)
		)
		(fill yes)
		(layer "In11.Cu")
		(net "M_F_CPU0_SA_DQ<0>")
	)
	(gr_poly
		(pts
			(xy 329.030838 -293.158926) (xy 328.99223 -293.136828) (xy 328.855832 -293.173404) (xy 328.892408 -293.310056)
			(xy 328.930762 -293.332154)
		)
		(stroke
			(width 0)
			(type solid)
		)
		(fill yes)
		(layer "In11.Cu")
		(net "M_F_CPU0_SB_DQ<29>")
	)
	(gr_poly
		(pts
			(xy 329.101196 -292.107874) (xy 329.00112 -292.007798) (xy 328.901044 -292.107874) (xy 328.901044 -292.152324)
			(xy 329.101196 -292.152324)
		)
		(stroke
			(width 0)
			(type solid)
		)
		(fill yes)
		(layer "In11.Cu")
		(net "M_F_CPU0_SB_DQ<28>")
	)
	(gr_poly
		(pts
			(xy 329.101196 -291.704268) (xy 329.101196 -291.656516) (xy 328.901044 -291.656516) (xy 328.901044 -291.704268)
			(xy 329.00112 -291.80409)
		)
		(stroke
			(width 0)
			(type solid)
		)
		(fill yes)
		(layer "In11.Cu")
		(net "M_F_CPU0_SB_DQS_DP<8>")
	)
	(gr_poly
		(pts
			(xy 329.101196 -290.487608) (xy 329.00112 -290.387786) (xy 328.901044 -290.487608) (xy 328.901044 -290.53536)
			(xy 329.101196 -290.53536)
		)
		(stroke
			(width 0)
			(type solid)
		)
		(fill yes)
		(layer "In11.Cu")
		(net "M_F_CPU0_SB_DQS_DP<3>")
	)
	(gr_poly
		(pts
			(xy 329.101196 -290.084002) (xy 329.101196 -290.039552) (xy 328.901044 -290.039552) (xy 328.901044 -290.084002)
			(xy 329.00112 -290.184078)
		)
		(stroke
			(width 0)
			(type solid)
		)
		(fill yes)
		(layer "In11.Cu")
		(net "M_F_CPU0_SB_DQ<27>")
	)
	(gr_poly
		(pts
			(xy 329.101196 -288.86785) (xy 329.00112 -288.767774) (xy 328.901044 -288.86785) (xy 328.901044 -288.9123)
			(xy 329.101196 -288.9123)
		)
		(stroke
			(width 0)
			(type solid)
		)
		(fill yes)
		(layer "In11.Cu")
		(net "M_F_CPU0_SB_DQ<24>")
	)
	(gr_poly
		(pts
			(xy 329.101196 -288.464244) (xy 329.101196 -288.419794) (xy 328.901044 -288.419794) (xy 328.901044 -288.464244)
			(xy 329.00112 -288.56432)
		)
		(stroke
			(width 0)
			(type solid)
		)
		(fill yes)
		(layer "In11.Cu")
		(net "M_F_CPU0_SB_DQ<23>")
	)
	(gr_poly
		(pts
			(xy 329.101196 -287.247838) (xy 329.00112 -287.148016) (xy 328.901044 -287.247838) (xy 328.901044 -287.292288)
			(xy 329.101196 -287.292288)
		)
		(stroke
			(width 0)
			(type solid)
		)
		(fill yes)
		(layer "In11.Cu")
		(net "M_F_CPU0_SB_DQ<20>")
	)
	(gr_poly
		(pts
			(xy 329.101196 -286.844232) (xy 329.101196 -286.79648) (xy 328.901044 -286.79648) (xy 328.901044 -286.844232)
			(xy 329.00112 -286.944308)
		)
		(stroke
			(width 0)
			(type solid)
		)
		(fill yes)
		(layer "In11.Cu")
		(net "M_F_CPU0_SB_DQS_DP<7>")
	)
	(gr_poly
		(pts
			(xy 329.101196 -285.627826) (xy 329.00112 -285.528004) (xy 328.901044 -285.627826) (xy 328.901044 -285.675578)
			(xy 329.101196 -285.675578)
		)
		(stroke
			(width 0)
			(type solid)
		)
		(fill yes)
		(layer "In11.Cu")
		(net "M_F_CPU0_SB_DQS_DP<2>")
	)
	(gr_poly
		(pts
			(xy 329.101196 -285.22422) (xy 329.101196 -285.17977) (xy 328.901044 -285.17977) (xy 328.901044 -285.22422)
			(xy 329.00112 -285.324296)
		)
		(stroke
			(width 0)
			(type solid)
		)
		(fill yes)
		(layer "In11.Cu")
		(net "M_F_CPU0_SB_DQ<19>")
	)
	(gr_poly
		(pts
			(xy 329.101196 -284.008068) (xy 329.00112 -283.907992) (xy 328.901044 -284.008068) (xy 328.901044 -284.052518)
			(xy 329.101196 -284.052518)
		)
		(stroke
			(width 0)
			(type solid)
		)
		(fill yes)
		(layer "In11.Cu")
		(net "M_F_CPU0_SB_DQ<16>")
	)
	(gr_poly
		(pts
			(xy 329.101196 -283.604208) (xy 329.101196 -283.559758) (xy 328.901044 -283.559758) (xy 328.901044 -283.604208)
			(xy 329.00112 -283.704284)
		)
		(stroke
			(width 0)
			(type solid)
		)
		(fill yes)
		(layer "In11.Cu")
		(net "M_F_CPU0_SB_DQ<15>")
	)
	(gr_poly
		(pts
			(xy 329.101196 -282.388056) (xy 329.00112 -282.28798) (xy 328.901044 -282.388056) (xy 328.901044 -282.432506)
			(xy 329.101196 -282.432506)
		)
		(stroke
			(width 0)
			(type solid)
		)
		(fill yes)
		(layer "In11.Cu")
		(net "M_F_CPU0_SB_DQ<12>")
	)
	(gr_poly
		(pts
			(xy 329.101196 -281.98445) (xy 329.101196 -281.936698) (xy 328.901044 -281.936698) (xy 328.901044 -281.98445)
			(xy 329.00112 -282.084272)
		)
		(stroke
			(width 0)
			(type solid)
		)
		(fill yes)
		(layer "In11.Cu")
		(net "M_F_CPU0_SB_DQS_DP<6>")
	)
	(gr_poly
		(pts
			(xy 329.101196 -280.76779) (xy 329.00112 -280.667968) (xy 328.901044 -280.76779) (xy 328.901044 -280.815542)
			(xy 329.101196 -280.815542)
		)
		(stroke
			(width 0)
			(type solid)
		)
		(fill yes)
		(layer "In11.Cu")
		(net "M_F_CPU0_SB_DQS_DP<1>")
	)
	(gr_poly
		(pts
			(xy 329.101196 -280.364184) (xy 329.101196 -280.319734) (xy 328.901044 -280.319734) (xy 328.901044 -280.364184)
			(xy 329.00112 -280.46426)
		)
		(stroke
			(width 0)
			(type solid)
		)
		(fill yes)
		(layer "In11.Cu")
		(net "M_F_CPU0_SB_DQ<11>")
	)
	(gr_poly
		(pts
			(xy 329.101196 -279.148032) (xy 329.00112 -279.047956) (xy 328.901044 -279.148032) (xy 328.901044 -279.192482)
			(xy 329.101196 -279.192482)
		)
		(stroke
			(width 0)
			(type solid)
		)
		(fill yes)
		(layer "In11.Cu")
		(net "M_F_CPU0_SB_DQ<8>")
	)
	(gr_poly
		(pts
			(xy 329.101196 -278.744172) (xy 329.101196 -278.699722) (xy 328.901044 -278.699722) (xy 328.901044 -278.744172)
			(xy 329.00112 -278.844248)
		)
		(stroke
			(width 0)
			(type solid)
		)
		(fill yes)
		(layer "In11.Cu")
		(net "M_F_CPU0_SB_DQ<7>")
	)
	(gr_poly
		(pts
			(xy 329.101196 -277.52802) (xy 329.00112 -277.427944) (xy 328.901044 -277.52802) (xy 328.901044 -277.57247)
			(xy 329.101196 -277.57247)
		)
		(stroke
			(width 0)
			(type solid)
		)
		(fill yes)
		(layer "In11.Cu")
		(net "M_F_CPU0_SB_DQ<4>")
	)
	(gr_poly
		(pts
			(xy 329.101196 -277.124414) (xy 329.101196 -277.076662) (xy 328.901044 -277.076662) (xy 328.901044 -277.124414)
			(xy 329.00112 -277.224236)
		)
		(stroke
			(width 0)
			(type solid)
		)
		(fill yes)
		(layer "In11.Cu")
		(net "M_F_CPU0_SB_DQS_DP<5>")
	)
	(gr_poly
		(pts
			(xy 329.101196 -275.907754) (xy 329.00112 -275.807932) (xy 328.901044 -275.907754) (xy 328.901044 -275.955506)
			(xy 329.101196 -275.955506)
		)
		(stroke
			(width 0)
			(type solid)
		)
		(fill yes)
		(layer "In11.Cu")
		(net "M_F_CPU0_SB_DQS_DP<0>")
	)
	(gr_poly
		(pts
			(xy 329.101196 -275.504148) (xy 329.101196 -275.459698) (xy 328.901044 -275.459698) (xy 328.901044 -275.504148)
			(xy 329.00112 -275.604224)
		)
		(stroke
			(width 0)
			(type solid)
		)
		(fill yes)
		(layer "In11.Cu")
		(net "M_F_CPU0_SB_DQ<3>")
	)
	(gr_poly
		(pts
			(xy 329.101196 -274.287996) (xy 329.00112 -274.18792) (xy 328.901044 -274.287996) (xy 328.901044 -274.332446)
			(xy 329.101196 -274.332446)
		)
		(stroke
			(width 0)
			(type solid)
		)
		(fill yes)
		(layer "In11.Cu")
		(net "M_F_CPU0_SB_DQ<0>")
	)
	(gr_poly
		(pts
			(xy 329.101196 -273.884136) (xy 329.101196 -273.839686) (xy 328.901044 -273.839686) (xy 328.901044 -273.884136)
			(xy 329.00112 -273.984212)
		)
		(stroke
			(width 0)
			(type solid)
		)
		(fill yes)
		(layer "In11.Cu")
		(net "M_F_CPU0_SB_CB<3>")
	)
	(gr_poly
		(pts
			(xy 329.101196 -272.667984) (xy 329.00112 -272.567908) (xy 328.901044 -272.667984) (xy 328.901044 -272.712434)
			(xy 329.101196 -272.712434)
		)
		(stroke
			(width 0)
			(type solid)
		)
		(fill yes)
		(layer "In11.Cu")
		(net "M_F_CPU0_SB_CB<0>")
	)
	(gr_poly
		(pts
			(xy 329.101196 -272.264378) (xy 329.101196 -272.216626) (xy 328.901044 -272.216626) (xy 328.901044 -272.264378)
			(xy 329.00112 -272.3642)
		)
		(stroke
			(width 0)
			(type solid)
		)
		(fill yes)
		(layer "In11.Cu")
		(net "M_F_CPU0_SB_DQS_DP<4>")
	)
	(gr_poly
		(pts
			(xy 329.101196 -271.047718) (xy 329.00112 -270.947896) (xy 328.901044 -271.047718) (xy 328.901044 -271.09547)
			(xy 329.101196 -271.09547)
		)
		(stroke
			(width 0)
			(type solid)
		)
		(fill yes)
		(layer "In11.Cu")
		(net "M_F_CPU0_SB_DQS_DP<9>")
	)
	(gr_poly
		(pts
			(xy 329.101196 -270.644112) (xy 329.101196 -270.599662) (xy 328.901044 -270.599662) (xy 328.901044 -270.644112)
			(xy 329.00112 -270.744188)
		)
		(stroke
			(width 0)
			(type solid)
		)
		(fill yes)
		(layer "In11.Cu")
		(net "M_F_CPU0_SB_CB<7>")
	)
	(gr_poly
		(pts
			(xy 329.101196 -269.42796) (xy 329.00112 -269.327884) (xy 328.901044 -269.42796) (xy 328.901044 -269.47241)
			(xy 329.101196 -269.47241)
		)
		(stroke
			(width 0)
			(type solid)
		)
		(fill yes)
		(layer "In11.Cu")
		(net "M_F_CPU0_SB_CB<4>")
	)
	(gr_poly
		(pts
			(xy 329.101196 -267.807948) (xy 329.00112 -267.707872) (xy 328.901044 -267.807948) (xy 328.901044 -267.852398)
			(xy 329.101196 -267.852398)
		)
		(stroke
			(width 0)
			(type solid)
		)
		(fill yes)
		(layer "In11.Cu")
		(net "M_F_CPU0_SB_RSP<0>")
	)
	(gr_poly
		(pts
			(xy 329.101196 -265.784076) (xy 329.101196 -265.739626) (xy 328.901044 -265.739626) (xy 328.901044 -265.784076)
			(xy 329.00112 -265.884152)
		)
		(stroke
			(width 0)
			(type solid)
		)
		(fill yes)
		(layer "In11.Cu")
		(net "M_F_CPU0_SB_CS_N<0>")
	)
	(gr_poly
		(pts
			(xy 329.101196 -264.567924) (xy 329.00112 -264.467848) (xy 328.901044 -264.567924) (xy 328.901044 -264.612374)
			(xy 329.101196 -264.612374)
		)
		(stroke
			(width 0)
			(type solid)
		)
		(fill yes)
		(layer "In11.Cu")
		(net "M_F_CPU0_SB_CA<6>")
	)
	(gr_poly
		(pts
			(xy 329.101196 -264.164064) (xy 329.101196 -264.119614) (xy 328.901044 -264.119614) (xy 328.901044 -264.164064)
			(xy 329.00112 -264.26414)
		)
		(stroke
			(width 0)
			(type solid)
		)
		(fill yes)
		(layer "In11.Cu")
		(net "M_F_CPU0_SB_CA<5>")
	)
	(gr_poly
		(pts
			(xy 329.101196 -262.947912) (xy 329.00112 -262.847836) (xy 328.901044 -262.947912) (xy 328.901044 -262.992362)
			(xy 329.101196 -262.992362)
		)
		(stroke
			(width 0)
			(type solid)
		)
		(fill yes)
		(layer "In11.Cu")
		(net "M_F_CPU0_SB_CA<2>")
	)
	(gr_poly
		(pts
			(xy 329.101196 -262.544052) (xy 329.101196 -262.499602) (xy 328.901044 -262.499602) (xy 328.901044 -262.544052)
			(xy 329.00112 -262.644128)
		)
		(stroke
			(width 0)
			(type solid)
		)
		(fill yes)
		(layer "In11.Cu")
		(net "M_F_CPU0_SB_CA<1>")
	)
	(gr_poly
		(pts
			(xy 329.156822 -295.480486) (xy 329.120246 -295.343834) (xy 329.081892 -295.321482) (xy 328.981816 -295.49471)
			(xy 329.020424 -295.517062)
		)
		(stroke
			(width 0)
			(type solid)
		)
		(fill yes)
		(layer "In11.Cu")
		(net "M_F_CPU0_SB_DQ<31>")
	)
	(gr_poly
		(pts
			(xy 329.269852 -231.322372) (xy 329.269852 -231.277922) (xy 329.07224 -231.277922) (xy 329.07224 -231.322372)
			(xy 329.171046 -231.422448)
		)
		(stroke
			(width 0)
			(type solid)
		)
		(fill yes)
		(layer "In11.Cu")
		(net "M_F_CPU0_SA_DQ<11>")
	)
	(gr_poly
		(pts
			(xy 329.271122 -256.025904) (xy 329.171046 -255.926082) (xy 329.07097 -256.025904) (xy 329.07097 -256.073656)
			(xy 329.271122 -256.073656)
		)
		(stroke
			(width 0)
			(type solid)
		)
		(fill yes)
		(layer "In11.Cu")
		(net "M_F_CPU0_CLK_DP<0>")
	)
	(gr_poly
		(pts
			(xy 329.271122 -255.622298) (xy 329.271122 -255.577848) (xy 329.07097 -255.577848) (xy 329.07097 -255.622298)
			(xy 329.171046 -255.722374)
		)
		(stroke
			(width 0)
			(type solid)
		)
		(fill yes)
		(layer "In11.Cu")
		(net "M_F_CPU0_SA_PAR")
	)
	(gr_poly
		(pts
			(xy 329.271122 -254.406146) (xy 329.171046 -254.30607) (xy 329.07097 -254.406146) (xy 329.07097 -254.450596)
			(xy 329.271122 -254.450596)
		)
		(stroke
			(width 0)
			(type solid)
		)
		(fill yes)
		(layer "In11.Cu")
		(net "M_F_CPU0_SA_CA<4>")
	)
	(gr_poly
		(pts
			(xy 329.271122 -254.002286) (xy 329.271122 -253.957836) (xy 329.07097 -253.957836) (xy 329.07097 -254.002286)
			(xy 329.171046 -254.102362)
		)
		(stroke
			(width 0)
			(type solid)
		)
		(fill yes)
		(layer "In11.Cu")
		(net "M_F_CPU0_SA_CA<3>")
	)
	(gr_poly
		(pts
			(xy 329.271122 -252.786134) (xy 329.171046 -252.686058) (xy 329.07097 -252.786134) (xy 329.07097 -252.830584)
			(xy 329.271122 -252.830584)
		)
		(stroke
			(width 0)
			(type solid)
		)
		(fill yes)
		(layer "In11.Cu")
		(net "M_F_CPU0_SA_CA<0>")
	)
	(gr_poly
		(pts
			(xy 329.271122 -252.382274) (xy 329.271122 -252.337824) (xy 329.07097 -252.337824) (xy 329.07097 -252.382274)
			(xy 329.171046 -252.48235)
		)
		(stroke
			(width 0)
			(type solid)
		)
		(fill yes)
		(layer "In11.Cu")
		(net "M_F_CPU0_SA_CS_N<1>")
	)
	(gr_poly
		(pts
			(xy 329.271122 -250.762262) (xy 329.271122 -250.717812) (xy 329.07097 -250.717812) (xy 329.07097 -250.762262)
			(xy 329.171046 -250.862338)
		)
		(stroke
			(width 0)
			(type solid)
		)
		(fill yes)
		(layer "In11.Cu")
		(net "M_F_CPU0_RESET_N")
	)
	(gr_poly
		(pts
			(xy 329.271122 -249.14225) (xy 329.271122 -249.0978) (xy 329.07097 -249.0978) (xy 329.07097 -249.14225)
			(xy 329.171046 -249.242326)
		)
		(stroke
			(width 0)
			(type solid)
		)
		(fill yes)
		(layer "In11.Cu")
		(net "M_F_CPU0_SA_CB<7>")
	)
	(gr_poly
		(pts
			(xy 329.271122 -247.926098) (xy 329.171046 -247.826022) (xy 329.07097 -247.926098) (xy 329.07097 -247.970548)
			(xy 329.271122 -247.970548)
		)
		(stroke
			(width 0)
			(type solid)
		)
		(fill yes)
		(layer "In11.Cu")
		(net "M_F_CPU0_SA_CB<4>")
	)
	(gr_poly
		(pts
			(xy 329.271122 -247.522492) (xy 329.271122 -247.47474) (xy 329.07097 -247.47474) (xy 329.07097 -247.522492)
			(xy 329.171046 -247.622314)
		)
		(stroke
			(width 0)
			(type solid)
		)
		(fill yes)
		(layer "In11.Cu")
		(net "M_F_CPU0_SA_DQS_DP<9>")
	)
	(gr_poly
		(pts
			(xy 329.271122 -246.305832) (xy 329.171046 -246.20601) (xy 329.07097 -246.305832) (xy 329.07097 -246.353584)
			(xy 329.271122 -246.353584)
		)
		(stroke
			(width 0)
			(type solid)
		)
		(fill yes)
		(layer "In11.Cu")
		(net "M_F_CPU0_SA_DQS_DP<4>")
	)
	(gr_poly
		(pts
			(xy 329.271122 -245.902226) (xy 329.271122 -245.857776) (xy 329.07097 -245.857776) (xy 329.07097 -245.902226)
			(xy 329.171046 -246.002302)
		)
		(stroke
			(width 0)
			(type solid)
		)
		(fill yes)
		(layer "In11.Cu")
		(net "M_F_CPU0_SA_CB<3>")
	)
	(gr_poly
		(pts
			(xy 329.271122 -244.686074) (xy 329.171046 -244.585998) (xy 329.07097 -244.686074) (xy 329.07097 -244.730524)
			(xy 329.271122 -244.730524)
		)
		(stroke
			(width 0)
			(type solid)
		)
		(fill yes)
		(layer "In11.Cu")
		(net "M_F_CPU0_SA_CB<0>")
	)
	(gr_poly
		(pts
			(xy 329.271122 -244.282214) (xy 329.271122 -244.237764) (xy 329.07097 -244.237764) (xy 329.07097 -244.282214)
			(xy 329.171046 -244.38229)
		)
		(stroke
			(width 0)
			(type solid)
		)
		(fill yes)
		(layer "In11.Cu")
		(net "M_F_CPU0_SA_DQ<31>")
	)
	(gr_poly
		(pts
			(xy 329.271122 -243.066062) (xy 329.171046 -242.965986) (xy 329.07097 -243.066062) (xy 329.07097 -243.110512)
			(xy 329.271122 -243.110512)
		)
		(stroke
			(width 0)
			(type solid)
		)
		(fill yes)
		(layer "In11.Cu")
		(net "M_F_CPU0_SA_DQ<28>")
	)
	(gr_poly
		(pts
			(xy 329.271122 -242.662456) (xy 329.271122 -242.614704) (xy 329.07097 -242.614704) (xy 329.07097 -242.662456)
			(xy 329.171046 -242.762278)
		)
		(stroke
			(width 0)
			(type solid)
		)
		(fill yes)
		(layer "In11.Cu")
		(net "M_F_CPU0_SA_DQS_DP<8>")
	)
	(gr_poly
		(pts
			(xy 329.271122 -241.445796) (xy 329.171046 -241.345974) (xy 329.07097 -241.445796) (xy 329.07097 -241.493548)
			(xy 329.271122 -241.493548)
		)
		(stroke
			(width 0)
			(type solid)
		)
		(fill yes)
		(layer "In11.Cu")
		(net "M_F_CPU0_SA_DQS_DP<3>")
	)
	(gr_poly
		(pts
			(xy 329.271122 -241.04219) (xy 329.271122 -240.99774) (xy 329.07097 -240.99774) (xy 329.07097 -241.04219)
			(xy 329.171046 -241.142266)
		)
		(stroke
			(width 0)
			(type solid)
		)
		(fill yes)
		(layer "In11.Cu")
		(net "M_F_CPU0_SA_DQ<27>")
	)
	(gr_poly
		(pts
			(xy 329.271122 -239.826038) (xy 329.171046 -239.725962) (xy 329.07097 -239.826038) (xy 329.07097 -239.870488)
			(xy 329.271122 -239.870488)
		)
		(stroke
			(width 0)
			(type solid)
		)
		(fill yes)
		(layer "In11.Cu")
		(net "M_F_CPU0_SA_DQ<24>")
	)
	(gr_poly
		(pts
			(xy 329.271122 -239.422178) (xy 329.271122 -239.377728) (xy 329.07097 -239.377728) (xy 329.07097 -239.422178)
			(xy 329.171046 -239.522254)
		)
		(stroke
			(width 0)
			(type solid)
		)
		(fill yes)
		(layer "In11.Cu")
		(net "M_F_CPU0_SA_DQ<23>")
	)
	(gr_poly
		(pts
			(xy 329.271122 -238.206026) (xy 329.171046 -238.10595) (xy 329.07097 -238.206026) (xy 329.07097 -238.250476)
			(xy 329.271122 -238.250476)
		)
		(stroke
			(width 0)
			(type solid)
		)
		(fill yes)
		(layer "In11.Cu")
		(net "M_F_CPU0_SA_DQ<20>")
	)
	(gr_poly
		(pts
			(xy 329.271122 -237.80242) (xy 329.271122 -237.754668) (xy 329.07097 -237.754668) (xy 329.07097 -237.80242)
			(xy 329.171046 -237.902242)
		)
		(stroke
			(width 0)
			(type solid)
		)
		(fill yes)
		(layer "In11.Cu")
		(net "M_F_CPU0_SA_DQS_DP<7>")
	)
	(gr_poly
		(pts
			(xy 329.271122 -236.58576) (xy 329.171046 -236.485938) (xy 329.07097 -236.58576) (xy 329.07097 -236.633512)
			(xy 329.271122 -236.633512)
		)
		(stroke
			(width 0)
			(type solid)
		)
		(fill yes)
		(layer "In11.Cu")
		(net "M_F_CPU0_SA_DQS_DP<2>")
	)
	(gr_poly
		(pts
			(xy 329.271122 -236.182154) (xy 329.271122 -236.137704) (xy 329.07097 -236.137704) (xy 329.07097 -236.182154)
			(xy 329.171046 -236.28223)
		)
		(stroke
			(width 0)
			(type solid)
		)
		(fill yes)
		(layer "In11.Cu")
		(net "M_F_CPU0_SA_DQ<19>")
	)
	(gr_poly
		(pts
			(xy 329.271122 -234.966002) (xy 329.171046 -234.865926) (xy 329.07097 -234.966002) (xy 329.07097 -235.010452)
			(xy 329.271122 -235.010452)
		)
		(stroke
			(width 0)
			(type solid)
		)
		(fill yes)
		(layer "In11.Cu")
		(net "M_F_CPU0_SA_DQ<16>")
	)
	(gr_poly
		(pts
			(xy 329.271122 -234.562142) (xy 329.271122 -234.517692) (xy 329.07097 -234.517692) (xy 329.07097 -234.562142)
			(xy 329.171046 -234.662218)
		)
		(stroke
			(width 0)
			(type solid)
		)
		(fill yes)
		(layer "In11.Cu")
		(net "M_F_CPU0_SA_DQ<15>")
	)
	(gr_poly
		(pts
			(xy 329.271122 -233.34599) (xy 329.171046 -233.245914) (xy 329.07097 -233.34599) (xy 329.07097 -233.39044)
			(xy 329.271122 -233.39044)
		)
		(stroke
			(width 0)
			(type solid)
		)
		(fill yes)
		(layer "In11.Cu")
		(net "M_F_CPU0_SA_DQ<12>")
	)
	(gr_poly
		(pts
			(xy 329.271122 -232.942384) (xy 329.271122 -232.894632) (xy 329.07097 -232.894632) (xy 329.07097 -232.942384)
			(xy 329.171046 -233.042206)
		)
		(stroke
			(width 0)
			(type solid)
		)
		(fill yes)
		(layer "In11.Cu")
		(net "M_F_CPU0_SA_DQS_DP<6>")
	)
	(gr_poly
		(pts
			(xy 329.271122 -231.725724) (xy 329.171046 -231.625902) (xy 329.07097 -231.725724) (xy 329.07097 -231.773476)
			(xy 329.271122 -231.773476)
		)
		(stroke
			(width 0)
			(type solid)
		)
		(fill yes)
		(layer "In11.Cu")
		(net "M_F_CPU0_SA_DQS_DP<1>")
	)
	(gr_poly
		(pts
			(xy 329.271122 -230.105966) (xy 329.171046 -230.006144) (xy 329.07097 -230.105966) (xy 329.07097 -230.150416)
			(xy 329.271122 -230.150416)
		)
		(stroke
			(width 0)
			(type solid)
		)
		(fill yes)
		(layer "In11.Cu")
		(net "M_F_CPU0_SA_DQ<8>")
	)
	(gr_poly
		(pts
			(xy 329.271122 -229.70236) (xy 329.271122 -229.65791) (xy 329.07097 -229.65791) (xy 329.07097 -229.70236)
			(xy 329.171046 -229.802436)
		)
		(stroke
			(width 0)
			(type solid)
		)
		(fill yes)
		(layer "In11.Cu")
		(net "M_F_CPU0_SA_DQ<7>")
	)
	(gr_poly
		(pts
			(xy 329.271122 -228.486208) (xy 329.171046 -228.386132) (xy 329.07097 -228.486208) (xy 329.07097 -228.530658)
			(xy 329.271122 -228.530658)
		)
		(stroke
			(width 0)
			(type solid)
		)
		(fill yes)
		(layer "In11.Cu")
		(net "M_F_CPU0_SA_DQ<4>")
	)
	(gr_poly
		(pts
			(xy 329.271122 -228.082602) (xy 329.271122 -228.03485) (xy 329.07097 -228.03485) (xy 329.07097 -228.082602)
			(xy 329.171046 -228.182424)
		)
		(stroke
			(width 0)
			(type solid)
		)
		(fill yes)
		(layer "In11.Cu")
		(net "M_F_CPU0_SA_DQS_DP<5>")
	)
	(gr_poly
		(pts
			(xy 329.271122 -226.865942) (xy 329.171046 -226.76612) (xy 329.07097 -226.865942) (xy 329.07097 -226.913694)
			(xy 329.271122 -226.913694)
		)
		(stroke
			(width 0)
			(type solid)
		)
		(fill yes)
		(layer "In11.Cu")
		(net "M_F_CPU0_SA_DQS_DP<0>")
	)
	(gr_poly
		(pts
			(xy 329.271122 -226.462336) (xy 329.271122 -226.417886) (xy 329.07097 -226.417886) (xy 329.07097 -226.462336)
			(xy 329.171046 -226.562412)
		)
		(stroke
			(width 0)
			(type solid)
		)
		(fill yes)
		(layer "In11.Cu")
		(net "M_F_CPU0_SA_DQ<3>")
	)
	(gr_poly
		(pts
			(xy 329.271122 -225.246184) (xy 329.171046 -225.146108) (xy 329.07097 -225.246184) (xy 329.07097 -225.290634)
			(xy 329.271122 -225.290634)
		)
		(stroke
			(width 0)
			(type solid)
		)
		(fill yes)
		(layer "In11.Cu")
		(net "M_F_CPU0_SA_DQ<0>")
	)
	(gr_poly
		(pts
			(xy 329.571096 -292.51402) (xy 329.571096 -292.46957) (xy 329.370944 -292.46957) (xy 329.370944 -292.51402)
			(xy 329.47102 -292.614096)
		)
		(stroke
			(width 0)
			(type solid)
		)
		(fill yes)
		(layer "In11.Cu")
		(net "M_F_CPU0_SB_DQ<30>")
	)
	(gr_poly
		(pts
			(xy 329.571096 -291.297614) (xy 329.47102 -291.197792) (xy 329.370944 -291.297614) (xy 329.370944 -291.345366)
			(xy 329.571096 -291.345366)
		)
		(stroke
			(width 0)
			(type solid)
		)
		(fill yes)
		(layer "In11.Cu")
		(net "M_F_CPU0_SB_DQS_DN<8>")
	)
	(gr_poly
		(pts
			(xy 329.571096 -290.894262) (xy 329.571096 -290.84651) (xy 329.370944 -290.84651) (xy 329.370944 -290.894262)
			(xy 329.47102 -290.994084)
		)
		(stroke
			(width 0)
			(type solid)
		)
		(fill yes)
		(layer "In11.Cu")
		(net "M_F_CPU0_SB_DQS_DN<3>")
	)
	(gr_poly
		(pts
			(xy 329.571096 -289.677856) (xy 329.47102 -289.57778) (xy 329.370944 -289.677856) (xy 329.370944 -289.722306)
			(xy 329.571096 -289.722306)
		)
		(stroke
			(width 0)
			(type solid)
		)
		(fill yes)
		(layer "In11.Cu")
		(net "M_F_CPU0_SB_DQ<25>")
	)
	(gr_poly
		(pts
			(xy 329.571096 -289.273996) (xy 329.571096 -289.229546) (xy 329.370944 -289.229546) (xy 329.370944 -289.273996)
			(xy 329.47102 -289.374072)
		)
		(stroke
			(width 0)
			(type solid)
		)
		(fill yes)
		(layer "In11.Cu")
		(net "M_F_CPU0_SB_DQ<26>")
	)
	(gr_poly
		(pts
			(xy 329.571096 -288.057844) (xy 329.47102 -287.957768) (xy 329.370944 -288.057844) (xy 329.370944 -288.102294)
			(xy 329.571096 -288.102294)
		)
		(stroke
			(width 0)
			(type solid)
		)
		(fill yes)
		(layer "In11.Cu")
		(net "M_F_CPU0_SB_DQ<21>")
	)
	(gr_poly
		(pts
			(xy 329.571096 -287.654238) (xy 329.571096 -287.609788) (xy 329.370944 -287.609788) (xy 329.370944 -287.654238)
			(xy 329.47102 -287.75406)
		)
		(stroke
			(width 0)
			(type solid)
		)
		(fill yes)
		(layer "In11.Cu")
		(net "M_F_CPU0_SB_DQ<22>")
	)
	(gr_poly
		(pts
			(xy 329.571096 -286.437832) (xy 329.47102 -286.337756) (xy 329.370944 -286.437832) (xy 329.370944 -286.485584)
			(xy 329.571096 -286.485584)
		)
		(stroke
			(width 0)
			(type solid)
		)
		(fill yes)
		(layer "In11.Cu")
		(net "M_F_CPU0_SB_DQS_DN<7>")
	)
	(gr_poly
		(pts
			(xy 329.571096 -286.03448) (xy 329.571096 -285.986728) (xy 329.370944 -285.986728) (xy 329.370944 -286.03448)
			(xy 329.47102 -286.134302)
		)
		(stroke
			(width 0)
			(type solid)
		)
		(fill yes)
		(layer "In11.Cu")
		(net "M_F_CPU0_SB_DQS_DN<2>")
	)
	(gr_poly
		(pts
			(xy 329.571096 -284.818074) (xy 329.47102 -284.717998) (xy 329.370944 -284.818074) (xy 329.370944 -284.862524)
			(xy 329.571096 -284.862524)
		)
		(stroke
			(width 0)
			(type solid)
		)
		(fill yes)
		(layer "In11.Cu")
		(net "M_F_CPU0_SB_DQ<17>")
	)
	(gr_poly
		(pts
			(xy 329.571096 -284.414214) (xy 329.571096 -284.369764) (xy 329.370944 -284.369764) (xy 329.370944 -284.414214)
			(xy 329.47102 -284.51429)
		)
		(stroke
			(width 0)
			(type solid)
		)
		(fill yes)
		(layer "In11.Cu")
		(net "M_F_CPU0_SB_DQ<18>")
	)
	(gr_poly
		(pts
			(xy 329.571096 -283.198062) (xy 329.47102 -283.097986) (xy 329.370944 -283.198062) (xy 329.370944 -283.242512)
			(xy 329.571096 -283.242512)
		)
		(stroke
			(width 0)
			(type solid)
		)
		(fill yes)
		(layer "In11.Cu")
		(net "M_F_CPU0_SB_DQ<13>")
	)
	(gr_poly
		(pts
			(xy 329.571096 -282.794202) (xy 329.571096 -282.749752) (xy 329.370944 -282.749752) (xy 329.370944 -282.794202)
			(xy 329.47102 -282.894278)
		)
		(stroke
			(width 0)
			(type solid)
		)
		(fill yes)
		(layer "In11.Cu")
		(net "M_F_CPU0_SB_DQ<14>")
	)
	(gr_poly
		(pts
			(xy 329.571096 -281.577796) (xy 329.47102 -281.477974) (xy 329.370944 -281.577796) (xy 329.370944 -281.625548)
			(xy 329.571096 -281.625548)
		)
		(stroke
			(width 0)
			(type solid)
		)
		(fill yes)
		(layer "In11.Cu")
		(net "M_F_CPU0_SB_DQS_DN<6>")
	)
	(gr_poly
		(pts
			(xy 329.571096 -281.174444) (xy 329.571096 -281.126692) (xy 329.370944 -281.126692) (xy 329.370944 -281.174444)
			(xy 329.47102 -281.274266)
		)
		(stroke
			(width 0)
			(type solid)
		)
		(fill yes)
		(layer "In11.Cu")
		(net "M_F_CPU0_SB_DQS_DN<1>")
	)
	(gr_poly
		(pts
			(xy 329.571096 -279.958038) (xy 329.47102 -279.857962) (xy 329.370944 -279.958038) (xy 329.370944 -280.002488)
			(xy 329.571096 -280.002488)
		)
		(stroke
			(width 0)
			(type solid)
		)
		(fill yes)
		(layer "In11.Cu")
		(net "M_F_CPU0_SB_DQ<9>")
	)
	(gr_poly
		(pts
			(xy 329.571096 -279.554178) (xy 329.571096 -279.509728) (xy 329.370944 -279.509728) (xy 329.370944 -279.554178)
			(xy 329.47102 -279.654254)
		)
		(stroke
			(width 0)
			(type solid)
		)
		(fill yes)
		(layer "In11.Cu")
		(net "M_F_CPU0_SB_DQ<10>")
	)
	(gr_poly
		(pts
			(xy 329.571096 -278.338026) (xy 329.47102 -278.23795) (xy 329.370944 -278.338026) (xy 329.370944 -278.382476)
			(xy 329.571096 -278.382476)
		)
		(stroke
			(width 0)
			(type solid)
		)
		(fill yes)
		(layer "In11.Cu")
		(net "M_F_CPU0_SB_DQ<5>")
	)
	(gr_poly
		(pts
			(xy 329.571096 -277.934166) (xy 329.571096 -277.889716) (xy 329.370944 -277.889716) (xy 329.370944 -277.934166)
			(xy 329.47102 -278.034242)
		)
		(stroke
			(width 0)
			(type solid)
		)
		(fill yes)
		(layer "In11.Cu")
		(net "M_F_CPU0_SB_DQ<6>")
	)
	(gr_poly
		(pts
			(xy 329.571096 -276.71776) (xy 329.47102 -276.617938) (xy 329.370944 -276.71776) (xy 329.370944 -276.765512)
			(xy 329.571096 -276.765512)
		)
		(stroke
			(width 0)
			(type solid)
		)
		(fill yes)
		(layer "In11.Cu")
		(net "M_F_CPU0_SB_DQS_DN<5>")
	)
	(gr_poly
		(pts
			(xy 329.571096 -276.314408) (xy 329.571096 -276.266656) (xy 329.370944 -276.266656) (xy 329.370944 -276.314408)
			(xy 329.47102 -276.41423)
		)
		(stroke
			(width 0)
			(type solid)
		)
		(fill yes)
		(layer "In11.Cu")
		(net "M_F_CPU0_SB_DQS_DN<0>")
	)
	(gr_poly
		(pts
			(xy 329.571096 -275.098002) (xy 329.47102 -274.997926) (xy 329.370944 -275.098002) (xy 329.370944 -275.142452)
			(xy 329.571096 -275.142452)
		)
		(stroke
			(width 0)
			(type solid)
		)
		(fill yes)
		(layer "In11.Cu")
		(net "M_F_CPU0_SB_DQ<1>")
	)
	(gr_poly
		(pts
			(xy 329.571096 -274.694142) (xy 329.571096 -274.649692) (xy 329.370944 -274.649692) (xy 329.370944 -274.694142)
			(xy 329.47102 -274.794218)
		)
		(stroke
			(width 0)
			(type solid)
		)
		(fill yes)
		(layer "In11.Cu")
		(net "M_F_CPU0_SB_DQ<2>")
	)
	(gr_poly
		(pts
			(xy 329.571096 -273.47799) (xy 329.47102 -273.377914) (xy 329.370944 -273.47799) (xy 329.370944 -273.52244)
			(xy 329.571096 -273.52244)
		)
		(stroke
			(width 0)
			(type solid)
		)
		(fill yes)
		(layer "In11.Cu")
		(net "M_F_CPU0_SB_CB<1>")
	)
	(gr_poly
		(pts
			(xy 329.571096 -273.07413) (xy 329.571096 -273.02968) (xy 329.370944 -273.02968) (xy 329.370944 -273.07413)
			(xy 329.47102 -273.174206)
		)
		(stroke
			(width 0)
			(type solid)
		)
		(fill yes)
		(layer "In11.Cu")
		(net "M_F_CPU0_SB_CB<2>")
	)
	(gr_poly
		(pts
			(xy 329.571096 -271.857724) (xy 329.47102 -271.757902) (xy 329.370944 -271.857724) (xy 329.370944 -271.905476)
			(xy 329.571096 -271.905476)
		)
		(stroke
			(width 0)
			(type solid)
		)
		(fill yes)
		(layer "In11.Cu")
		(net "M_F_CPU0_SB_DQS_DN<4>")
	)
	(gr_poly
		(pts
			(xy 329.571096 -271.454372) (xy 329.571096 -271.40662) (xy 329.370944 -271.40662) (xy 329.370944 -271.454372)
			(xy 329.47102 -271.554194)
		)
		(stroke
			(width 0)
			(type solid)
		)
		(fill yes)
		(layer "In11.Cu")
		(net "M_F_CPU0_SB_DQS_DN<9>")
	)
	(gr_poly
		(pts
			(xy 329.571096 -270.237966) (xy 329.47102 -270.13789) (xy 329.370944 -270.237966) (xy 329.370944 -270.282416)
			(xy 329.571096 -270.282416)
		)
		(stroke
			(width 0)
			(type solid)
		)
		(fill yes)
		(layer "In11.Cu")
		(net "M_F_CPU0_SB_CB<5>")
	)
	(gr_poly
		(pts
			(xy 329.571096 -269.834106) (xy 329.571096 -269.789656) (xy 329.370944 -269.789656) (xy 329.370944 -269.834106)
			(xy 329.47102 -269.934182)
		)
		(stroke
			(width 0)
			(type solid)
		)
		(fill yes)
		(layer "In11.Cu")
		(net "M_F_CPU0_SB_CB<6>")
	)
	(gr_poly
		(pts
			(xy 329.571096 -266.594082) (xy 329.571096 -266.549632) (xy 329.370944 -266.549632) (xy 329.370944 -266.594082)
			(xy 329.47102 -266.694158)
		)
		(stroke
			(width 0)
			(type solid)
		)
		(fill yes)
		(layer "In11.Cu")
		(net "M_F_CPU0_SB_CS_N<1>")
	)
	(gr_poly
		(pts
			(xy 329.571096 -264.97407) (xy 329.571096 -264.92962) (xy 329.370944 -264.92962) (xy 329.370944 -264.97407)
			(xy 329.47102 -265.074146)
		)
		(stroke
			(width 0)
			(type solid)
		)
		(fill yes)
		(layer "In11.Cu")
		(net "M_F_CPU0_SB_PAR")
	)
	(gr_poly
		(pts
			(xy 329.571096 -263.757918) (xy 329.47102 -263.657842) (xy 329.370944 -263.757918) (xy 329.370944 -263.802368)
			(xy 329.571096 -263.802368)
		)
		(stroke
			(width 0)
			(type solid)
		)
		(fill yes)
		(layer "In11.Cu")
		(net "M_F_CPU0_SB_CA<4>")
	)
	(gr_poly
		(pts
			(xy 329.571096 -263.354058) (xy 329.571096 -263.309608) (xy 329.370944 -263.309608) (xy 329.370944 -263.354058)
			(xy 329.47102 -263.454134)
		)
		(stroke
			(width 0)
			(type solid)
		)
		(fill yes)
		(layer "In11.Cu")
		(net "M_F_CPU0_SB_CA<3>")
	)
	(gr_poly
		(pts
			(xy 329.571096 -262.137906) (xy 329.47102 -262.03783) (xy 329.370944 -262.137906) (xy 329.370944 -262.182356)
			(xy 329.571096 -262.182356)
		)
		(stroke
			(width 0)
			(type solid)
		)
		(fill yes)
		(layer "In11.Cu")
		(net "M_F_CPU0_SB_CA<0>")
	)
	(gr_poly
		(pts
			(xy 329.57135 -266.997942) (xy 329.471274 -266.897866) (xy 329.371198 -266.997942) (xy 329.371198 -267.042392)
			(xy 329.57135 -267.042392)
		)
		(stroke
			(width 0)
			(type solid)
		)
		(fill yes)
		(layer "In11.Cu")
		(net "M_F_CPU0_SA_RSP<0>")
	)
	(gr_poly
		(pts
			(xy 329.616562 -294.688514) (xy 329.579986 -294.551862) (xy 329.541632 -294.529764) (xy 329.441556 -294.702992)
			(xy 329.47991 -294.72509)
		)
		(stroke
			(width 0)
			(type solid)
		)
		(fill yes)
		(layer "In11.Cu")
		(net "M_F_CPU0_SB_DQ<31>")
	)
	(gr_poly
		(pts
			(xy 329.740006 -230.915972) (xy 329.6412 -230.815896) (xy 329.542394 -230.915972) (xy 329.542394 -230.960422)
			(xy 329.740006 -230.960422)
		)
		(stroke
			(width 0)
			(type solid)
		)
		(fill yes)
		(layer "In11.Cu")
		(net "M_F_CPU0_SA_DQ<9>")
	)
	(gr_poly
		(pts
			(xy 329.741276 -256.432558) (xy 329.741276 -256.384806) (xy 329.541124 -256.384806) (xy 329.541124 -256.432558)
			(xy 329.6412 -256.53238)
		)
		(stroke
			(width 0)
			(type solid)
		)
		(fill yes)
		(layer "In11.Cu")
		(net "M_F_CPU0_CLK_DN<0>")
	)
	(gr_poly
		(pts
			(xy 329.741276 -255.216152) (xy 329.6412 -255.116076) (xy 329.541124 -255.216152) (xy 329.541124 -255.260602)
			(xy 329.741276 -255.260602)
		)
		(stroke
			(width 0)
			(type solid)
		)
		(fill yes)
		(layer "In11.Cu")
		(net "M_F_CPU0_SA_CA<6>")
	)
	(gr_poly
		(pts
			(xy 329.741276 -254.812292) (xy 329.741276 -254.767842) (xy 329.541124 -254.767842) (xy 329.541124 -254.812292)
			(xy 329.6412 -254.912368)
		)
		(stroke
			(width 0)
			(type solid)
		)
		(fill yes)
		(layer "In11.Cu")
		(net "M_F_CPU0_SA_CA<5>")
	)
	(gr_poly
		(pts
			(xy 329.741276 -253.59614) (xy 329.6412 -253.496064) (xy 329.541124 -253.59614) (xy 329.541124 -253.64059)
			(xy 329.741276 -253.64059)
		)
		(stroke
			(width 0)
			(type solid)
		)
		(fill yes)
		(layer "In11.Cu")
		(net "M_F_CPU0_SA_CA<2>")
	)
	(gr_poly
		(pts
			(xy 329.741276 -253.19228) (xy 329.741276 -253.14783) (xy 329.541124 -253.14783) (xy 329.541124 -253.19228)
			(xy 329.6412 -253.292356)
		)
		(stroke
			(width 0)
			(type solid)
		)
		(fill yes)
		(layer "In11.Cu")
		(net "M_F_CPU0_SA_CA<1>")
	)
	(gr_poly
		(pts
			(xy 329.741276 -251.572268) (xy 329.741276 -251.527818) (xy 329.541124 -251.527818) (xy 329.541124 -251.572268)
			(xy 329.6412 -251.672344)
		)
		(stroke
			(width 0)
			(type solid)
		)
		(fill yes)
		(layer "In11.Cu")
		(net "M_F_CPU0_SA_CS_N<0>")
	)
	(gr_poly
		(pts
			(xy 329.741276 -250.356116) (xy 329.6412 -250.25604) (xy 329.541124 -250.356116) (xy 329.541124 -250.400566)
			(xy 329.741276 -250.400566)
		)
		(stroke
			(width 0)
			(type solid)
		)
		(fill yes)
		(layer "In11.Cu")
		(net "M_F_CPU0_ALERT_R_N")
	)
	(gr_poly
		(pts
			(xy 329.741276 -248.736104) (xy 329.6412 -248.636028) (xy 329.541124 -248.736104) (xy 329.541124 -248.780554)
			(xy 329.741276 -248.780554)
		)
		(stroke
			(width 0)
			(type solid)
		)
		(fill yes)
		(layer "In11.Cu")
		(net "M_F_CPU0_SA_CB<5>")
	)
	(gr_poly
		(pts
			(xy 329.741276 -248.332244) (xy 329.741276 -248.287794) (xy 329.541124 -248.287794) (xy 329.541124 -248.332244)
			(xy 329.6412 -248.43232)
		)
		(stroke
			(width 0)
			(type solid)
		)
		(fill yes)
		(layer "In11.Cu")
		(net "M_F_CPU0_SA_CB<6>")
	)
	(gr_poly
		(pts
			(xy 329.741276 -247.115838) (xy 329.6412 -247.016016) (xy 329.541124 -247.115838) (xy 329.541124 -247.16359)
			(xy 329.741276 -247.16359)
		)
		(stroke
			(width 0)
			(type solid)
		)
		(fill yes)
		(layer "In11.Cu")
		(net "M_F_CPU0_SA_DQS_DN<9>")
	)
	(gr_poly
		(pts
			(xy 329.741276 -246.712486) (xy 329.741276 -246.664734) (xy 329.541124 -246.664734) (xy 329.541124 -246.712486)
			(xy 329.6412 -246.812308)
		)
		(stroke
			(width 0)
			(type solid)
		)
		(fill yes)
		(layer "In11.Cu")
		(net "M_F_CPU0_SA_DQS_DN<4>")
	)
	(gr_poly
		(pts
			(xy 329.741276 -245.49608) (xy 329.6412 -245.396004) (xy 329.541124 -245.49608) (xy 329.541124 -245.54053)
			(xy 329.741276 -245.54053)
		)
		(stroke
			(width 0)
			(type solid)
		)
		(fill yes)
		(layer "In11.Cu")
		(net "M_F_CPU0_SA_CB<1>")
	)
	(gr_poly
		(pts
			(xy 329.741276 -245.09222) (xy 329.741276 -245.04777) (xy 329.541124 -245.04777) (xy 329.541124 -245.09222)
			(xy 329.6412 -245.192296)
		)
		(stroke
			(width 0)
			(type solid)
		)
		(fill yes)
		(layer "In11.Cu")
		(net "M_F_CPU0_SA_CB<2>")
	)
	(gr_poly
		(pts
			(xy 329.741276 -243.876068) (xy 329.6412 -243.775992) (xy 329.541124 -243.876068) (xy 329.541124 -243.920518)
			(xy 329.741276 -243.920518)
		)
		(stroke
			(width 0)
			(type solid)
		)
		(fill yes)
		(layer "In11.Cu")
		(net "M_F_CPU0_SA_DQ<29>")
	)
	(gr_poly
		(pts
			(xy 329.741276 -243.472208) (xy 329.741276 -243.427758) (xy 329.541124 -243.427758) (xy 329.541124 -243.472208)
			(xy 329.6412 -243.572284)
		)
		(stroke
			(width 0)
			(type solid)
		)
		(fill yes)
		(layer "In11.Cu")
		(net "M_F_CPU0_SA_DQ<30>")
	)
	(gr_poly
		(pts
			(xy 329.741276 -242.255802) (xy 329.6412 -242.15598) (xy 329.541124 -242.255802) (xy 329.541124 -242.303554)
			(xy 329.741276 -242.303554)
		)
		(stroke
			(width 0)
			(type solid)
		)
		(fill yes)
		(layer "In11.Cu")
		(net "M_F_CPU0_SA_DQS_DN<8>")
	)
	(gr_poly
		(pts
			(xy 329.741276 -241.85245) (xy 329.741276 -241.804698) (xy 329.541124 -241.804698) (xy 329.541124 -241.85245)
			(xy 329.6412 -241.952272)
		)
		(stroke
			(width 0)
			(type solid)
		)
		(fill yes)
		(layer "In11.Cu")
		(net "M_F_CPU0_SA_DQS_DN<3>")
	)
	(gr_poly
		(pts
			(xy 329.741276 -240.636044) (xy 329.6412 -240.535968) (xy 329.541124 -240.636044) (xy 329.541124 -240.680494)
			(xy 329.741276 -240.680494)
		)
		(stroke
			(width 0)
			(type solid)
		)
		(fill yes)
		(layer "In11.Cu")
		(net "M_F_CPU0_SA_DQ<25>")
	)
	(gr_poly
		(pts
			(xy 329.741276 -240.232184) (xy 329.741276 -240.187734) (xy 329.541124 -240.187734) (xy 329.541124 -240.232184)
			(xy 329.6412 -240.33226)
		)
		(stroke
			(width 0)
			(type solid)
		)
		(fill yes)
		(layer "In11.Cu")
		(net "M_F_CPU0_SA_DQ<26>")
	)
	(gr_poly
		(pts
			(xy 329.741276 -239.016032) (xy 329.6412 -238.915956) (xy 329.541124 -239.016032) (xy 329.541124 -239.060482)
			(xy 329.741276 -239.060482)
		)
		(stroke
			(width 0)
			(type solid)
		)
		(fill yes)
		(layer "In11.Cu")
		(net "M_F_CPU0_SA_DQ<21>")
	)
	(gr_poly
		(pts
			(xy 329.741276 -238.612172) (xy 329.741276 -238.567722) (xy 329.541124 -238.567722) (xy 329.541124 -238.612172)
			(xy 329.6412 -238.712248)
		)
		(stroke
			(width 0)
			(type solid)
		)
		(fill yes)
		(layer "In11.Cu")
		(net "M_F_CPU0_SA_DQ<22>")
	)
	(gr_poly
		(pts
			(xy 329.741276 -237.395766) (xy 329.6412 -237.295944) (xy 329.541124 -237.395766) (xy 329.541124 -237.443518)
			(xy 329.741276 -237.443518)
		)
		(stroke
			(width 0)
			(type solid)
		)
		(fill yes)
		(layer "In11.Cu")
		(net "M_F_CPU0_SA_DQS_DN<7>")
	)
	(gr_poly
		(pts
			(xy 329.741276 -236.992414) (xy 329.741276 -236.944662) (xy 329.541124 -236.944662) (xy 329.541124 -236.992414)
			(xy 329.6412 -237.092236)
		)
		(stroke
			(width 0)
			(type solid)
		)
		(fill yes)
		(layer "In11.Cu")
		(net "M_F_CPU0_SA_DQS_DN<2>")
	)
	(gr_poly
		(pts
			(xy 329.741276 -235.776008) (xy 329.6412 -235.675932) (xy 329.541124 -235.776008) (xy 329.541124 -235.820458)
			(xy 329.741276 -235.820458)
		)
		(stroke
			(width 0)
			(type solid)
		)
		(fill yes)
		(layer "In11.Cu")
		(net "M_F_CPU0_SA_DQ<17>")
	)
	(gr_poly
		(pts
			(xy 329.741276 -235.372148) (xy 329.741276 -235.327698) (xy 329.541124 -235.327698) (xy 329.541124 -235.372148)
			(xy 329.6412 -235.472224)
		)
		(stroke
			(width 0)
			(type solid)
		)
		(fill yes)
		(layer "In11.Cu")
		(net "M_F_CPU0_SA_DQ<18>")
	)
	(gr_poly
		(pts
			(xy 329.741276 -234.155996) (xy 329.6412 -234.05592) (xy 329.541124 -234.155996) (xy 329.541124 -234.200446)
			(xy 329.741276 -234.200446)
		)
		(stroke
			(width 0)
			(type solid)
		)
		(fill yes)
		(layer "In11.Cu")
		(net "M_F_CPU0_SA_DQ<13>")
	)
	(gr_poly
		(pts
			(xy 329.741276 -233.752136) (xy 329.741276 -233.707686) (xy 329.541124 -233.707686) (xy 329.541124 -233.752136)
			(xy 329.6412 -233.852212)
		)
		(stroke
			(width 0)
			(type solid)
		)
		(fill yes)
		(layer "In11.Cu")
		(net "M_F_CPU0_SA_DQ<14>")
	)
	(gr_poly
		(pts
			(xy 329.741276 -232.53573) (xy 329.6412 -232.435908) (xy 329.541124 -232.53573) (xy 329.541124 -232.583482)
			(xy 329.741276 -232.583482)
		)
		(stroke
			(width 0)
			(type solid)
		)
		(fill yes)
		(layer "In11.Cu")
		(net "M_F_CPU0_SA_DQS_DN<6>")
	)
	(gr_poly
		(pts
			(xy 329.741276 -232.132378) (xy 329.741276 -232.084626) (xy 329.541124 -232.084626) (xy 329.541124 -232.132378)
			(xy 329.6412 -232.2322)
		)
		(stroke
			(width 0)
			(type solid)
		)
		(fill yes)
		(layer "In11.Cu")
		(net "M_F_CPU0_SA_DQS_DN<1>")
	)
	(gr_poly
		(pts
			(xy 329.741276 -230.512366) (xy 329.741276 -230.467916) (xy 329.541124 -230.467916) (xy 329.541124 -230.512366)
			(xy 329.6412 -230.612188)
		)
		(stroke
			(width 0)
			(type solid)
		)
		(fill yes)
		(layer "In11.Cu")
		(net "M_F_CPU0_SA_DQ<10>")
	)
	(gr_poly
		(pts
			(xy 329.741276 -229.29596) (xy 329.6412 -229.195884) (xy 329.541124 -229.29596) (xy 329.541124 -229.34041)
			(xy 329.741276 -229.34041)
		)
		(stroke
			(width 0)
			(type solid)
		)
		(fill yes)
		(layer "In11.Cu")
		(net "M_F_CPU0_SA_DQ<5>")
	)
	(gr_poly
		(pts
			(xy 329.741276 -228.892354) (xy 329.741276 -228.847904) (xy 329.541124 -228.847904) (xy 329.541124 -228.892354)
			(xy 329.6412 -228.99243)
		)
		(stroke
			(width 0)
			(type solid)
		)
		(fill yes)
		(layer "In11.Cu")
		(net "M_F_CPU0_SA_DQ<6>")
	)
	(gr_poly
		(pts
			(xy 329.741276 -227.675948) (xy 329.6412 -227.576126) (xy 329.541124 -227.675948) (xy 329.541124 -227.7237)
			(xy 329.741276 -227.7237)
		)
		(stroke
			(width 0)
			(type solid)
		)
		(fill yes)
		(layer "In11.Cu")
		(net "M_F_CPU0_SA_DQS_DN<5>")
	)
	(gr_poly
		(pts
			(xy 329.741276 -227.272596) (xy 329.741276 -227.224844) (xy 329.541124 -227.224844) (xy 329.541124 -227.272596)
			(xy 329.6412 -227.372418)
		)
		(stroke
			(width 0)
			(type solid)
		)
		(fill yes)
		(layer "In11.Cu")
		(net "M_F_CPU0_SA_DQS_DN<0>")
	)
	(gr_poly
		(pts
			(xy 329.741276 -226.05619) (xy 329.6412 -225.956114) (xy 329.541124 -226.05619) (xy 329.541124 -226.10064)
			(xy 329.741276 -226.10064)
		)
		(stroke
			(width 0)
			(type solid)
		)
		(fill yes)
		(layer "In11.Cu")
		(net "M_F_CPU0_SA_DQ<1>")
	)
	(gr_poly
		(pts
			(xy 329.741276 -225.65233) (xy 329.741276 -225.60788) (xy 329.541124 -225.60788) (xy 329.541124 -225.65233)
			(xy 329.6412 -225.752406)
		)
		(stroke
			(width 0)
			(type solid)
		)
		(fill yes)
		(layer "In11.Cu")
		(net "M_F_CPU0_SA_DQ<2>")
	)
	(gr_poly
		(pts
			(xy 330.04125 -292.107874) (xy 329.941174 -292.007798) (xy 329.841098 -292.107874) (xy 329.841098 -292.152324)
			(xy 330.04125 -292.152324)
		)
		(stroke
			(width 0)
			(type solid)
		)
		(fill yes)
		(layer "In11.Cu")
		(net "M_F_CPU0_SB_DQ<28>")
	)
	(gr_poly
		(pts
			(xy 330.04125 -291.704268) (xy 330.04125 -291.656516) (xy 329.841098 -291.656516) (xy 329.841098 -291.704268)
			(xy 329.941174 -291.80409)
		)
		(stroke
			(width 0)
			(type solid)
		)
		(fill yes)
		(layer "In11.Cu")
		(net "M_F_CPU0_SB_DQS_DP<8>")
	)
	(gr_poly
		(pts
			(xy 330.04125 -290.487608) (xy 329.941174 -290.387786) (xy 329.841098 -290.487608) (xy 329.841098 -290.53536)
			(xy 330.04125 -290.53536)
		)
		(stroke
			(width 0)
			(type solid)
		)
		(fill yes)
		(layer "In11.Cu")
		(net "M_F_CPU0_SB_DQS_DP<3>")
	)
	(gr_poly
		(pts
			(xy 330.04125 -290.084002) (xy 330.04125 -290.039552) (xy 329.841098 -290.039552) (xy 329.841098 -290.084002)
			(xy 329.941174 -290.184078)
		)
		(stroke
			(width 0)
			(type solid)
		)
		(fill yes)
		(layer "In11.Cu")
		(net "M_F_CPU0_SB_DQ<27>")
	)
	(gr_poly
		(pts
			(xy 330.04125 -288.86785) (xy 329.941174 -288.767774) (xy 329.841098 -288.86785) (xy 329.841098 -288.9123)
			(xy 330.04125 -288.9123)
		)
		(stroke
			(width 0)
			(type solid)
		)
		(fill yes)
		(layer "In11.Cu")
		(net "M_F_CPU0_SB_DQ<24>")
	)
	(gr_poly
		(pts
			(xy 330.04125 -288.464244) (xy 330.04125 -288.419794) (xy 329.841098 -288.419794) (xy 329.841098 -288.464244)
			(xy 329.941174 -288.56432)
		)
		(stroke
			(width 0)
			(type solid)
		)
		(fill yes)
		(layer "In11.Cu")
		(net "M_F_CPU0_SB_DQ<23>")
	)
	(gr_poly
		(pts
			(xy 330.04125 -287.247838) (xy 329.941174 -287.148016) (xy 329.841098 -287.247838) (xy 329.841098 -287.292288)
			(xy 330.04125 -287.292288)
		)
		(stroke
			(width 0)
			(type solid)
		)
		(fill yes)
		(layer "In11.Cu")
		(net "M_F_CPU0_SB_DQ<20>")
	)
	(gr_poly
		(pts
			(xy 330.04125 -286.844232) (xy 330.04125 -286.79648) (xy 329.841098 -286.79648) (xy 329.841098 -286.844232)
			(xy 329.941174 -286.944308)
		)
		(stroke
			(width 0)
			(type solid)
		)
		(fill yes)
		(layer "In11.Cu")
		(net "M_F_CPU0_SB_DQS_DP<7>")
	)
	(gr_poly
		(pts
			(xy 330.04125 -285.627826) (xy 329.941174 -285.528004) (xy 329.841098 -285.627826) (xy 329.841098 -285.675578)
			(xy 330.04125 -285.675578)
		)
		(stroke
			(width 0)
			(type solid)
		)
		(fill yes)
		(layer "In11.Cu")
		(net "M_F_CPU0_SB_DQS_DP<2>")
	)
	(gr_poly
		(pts
			(xy 330.04125 -285.22422) (xy 330.04125 -285.17977) (xy 329.841098 -285.17977) (xy 329.841098 -285.22422)
			(xy 329.941174 -285.324296)
		)
		(stroke
			(width 0)
			(type solid)
		)
		(fill yes)
		(layer "In11.Cu")
		(net "M_F_CPU0_SB_DQ<19>")
	)
	(gr_poly
		(pts
			(xy 330.04125 -284.008068) (xy 329.941174 -283.907992) (xy 329.841098 -284.008068) (xy 329.841098 -284.052518)
			(xy 330.04125 -284.052518)
		)
		(stroke
			(width 0)
			(type solid)
		)
		(fill yes)
		(layer "In11.Cu")
		(net "M_F_CPU0_SB_DQ<16>")
	)
	(gr_poly
		(pts
			(xy 330.04125 -283.604208) (xy 330.04125 -283.559758) (xy 329.841098 -283.559758) (xy 329.841098 -283.604208)
			(xy 329.941174 -283.704284)
		)
		(stroke
			(width 0)
			(type solid)
		)
		(fill yes)
		(layer "In11.Cu")
		(net "M_F_CPU0_SB_DQ<15>")
	)
	(gr_poly
		(pts
			(xy 330.04125 -282.388056) (xy 329.941174 -282.28798) (xy 329.841098 -282.388056) (xy 329.841098 -282.432506)
			(xy 330.04125 -282.432506)
		)
		(stroke
			(width 0)
			(type solid)
		)
		(fill yes)
		(layer "In11.Cu")
		(net "M_F_CPU0_SB_DQ<12>")
	)
	(gr_poly
		(pts
			(xy 330.04125 -281.98445) (xy 330.04125 -281.936698) (xy 329.841098 -281.936698) (xy 329.841098 -281.98445)
			(xy 329.941174 -282.084272)
		)
		(stroke
			(width 0)
			(type solid)
		)
		(fill yes)
		(layer "In11.Cu")
		(net "M_F_CPU0_SB_DQS_DP<6>")
	)
	(gr_poly
		(pts
			(xy 330.04125 -280.76779) (xy 329.941174 -280.667968) (xy 329.841098 -280.76779) (xy 329.841098 -280.815542)
			(xy 330.04125 -280.815542)
		)
		(stroke
			(width 0)
			(type solid)
		)
		(fill yes)
		(layer "In11.Cu")
		(net "M_F_CPU0_SB_DQS_DP<1>")
	)
	(gr_poly
		(pts
			(xy 330.04125 -280.364184) (xy 330.04125 -280.319734) (xy 329.841098 -280.319734) (xy 329.841098 -280.364184)
			(xy 329.941174 -280.46426)
		)
		(stroke
			(width 0)
			(type solid)
		)
		(fill yes)
		(layer "In11.Cu")
		(net "M_F_CPU0_SB_DQ<11>")
	)
	(gr_poly
		(pts
			(xy 330.04125 -279.148032) (xy 329.941174 -279.047956) (xy 329.841098 -279.148032) (xy 329.841098 -279.192482)
			(xy 330.04125 -279.192482)
		)
		(stroke
			(width 0)
			(type solid)
		)
		(fill yes)
		(layer "In11.Cu")
		(net "M_F_CPU0_SB_DQ<8>")
	)
	(gr_poly
		(pts
			(xy 330.04125 -278.744172) (xy 330.04125 -278.699722) (xy 329.841098 -278.699722) (xy 329.841098 -278.744172)
			(xy 329.941174 -278.844248)
		)
		(stroke
			(width 0)
			(type solid)
		)
		(fill yes)
		(layer "In11.Cu")
		(net "M_F_CPU0_SB_DQ<7>")
	)
	(gr_poly
		(pts
			(xy 330.04125 -277.52802) (xy 329.941174 -277.427944) (xy 329.841098 -277.52802) (xy 329.841098 -277.57247)
			(xy 330.04125 -277.57247)
		)
		(stroke
			(width 0)
			(type solid)
		)
		(fill yes)
		(layer "In11.Cu")
		(net "M_F_CPU0_SB_DQ<4>")
	)
	(gr_poly
		(pts
			(xy 330.04125 -277.124414) (xy 330.04125 -277.076662) (xy 329.841098 -277.076662) (xy 329.841098 -277.124414)
			(xy 329.941174 -277.224236)
		)
		(stroke
			(width 0)
			(type solid)
		)
		(fill yes)
		(layer "In11.Cu")
		(net "M_F_CPU0_SB_DQS_DP<5>")
	)
	(gr_poly
		(pts
			(xy 330.04125 -275.907754) (xy 329.941174 -275.807932) (xy 329.841098 -275.907754) (xy 329.841098 -275.955506)
			(xy 330.04125 -275.955506)
		)
		(stroke
			(width 0)
			(type solid)
		)
		(fill yes)
		(layer "In11.Cu")
		(net "M_F_CPU0_SB_DQS_DP<0>")
	)
	(gr_poly
		(pts
			(xy 330.04125 -275.504148) (xy 330.04125 -275.459698) (xy 329.841098 -275.459698) (xy 329.841098 -275.504148)
			(xy 329.941174 -275.604224)
		)
		(stroke
			(width 0)
			(type solid)
		)
		(fill yes)
		(layer "In11.Cu")
		(net "M_F_CPU0_SB_DQ<3>")
	)
	(gr_poly
		(pts
			(xy 330.04125 -274.287996) (xy 329.941174 -274.18792) (xy 329.841098 -274.287996) (xy 329.841098 -274.332446)
			(xy 330.04125 -274.332446)
		)
		(stroke
			(width 0)
			(type solid)
		)
		(fill yes)
		(layer "In11.Cu")
		(net "M_F_CPU0_SB_DQ<0>")
	)
	(gr_poly
		(pts
			(xy 330.04125 -273.884136) (xy 330.04125 -273.839686) (xy 329.841098 -273.839686) (xy 329.841098 -273.884136)
			(xy 329.941174 -273.984212)
		)
		(stroke
			(width 0)
			(type solid)
		)
		(fill yes)
		(layer "In11.Cu")
		(net "M_F_CPU0_SB_CB<3>")
	)
	(gr_poly
		(pts
			(xy 330.04125 -272.667984) (xy 329.941174 -272.567908) (xy 329.841098 -272.667984) (xy 329.841098 -272.712434)
			(xy 330.04125 -272.712434)
		)
		(stroke
			(width 0)
			(type solid)
		)
		(fill yes)
		(layer "In11.Cu")
		(net "M_F_CPU0_SB_CB<0>")
	)
	(gr_poly
		(pts
			(xy 330.04125 -272.264378) (xy 330.04125 -272.216626) (xy 329.841098 -272.216626) (xy 329.841098 -272.264378)
			(xy 329.941174 -272.3642)
		)
		(stroke
			(width 0)
			(type solid)
		)
		(fill yes)
		(layer "In11.Cu")
		(net "M_F_CPU0_SB_DQS_DP<4>")
	)
	(gr_poly
		(pts
			(xy 330.04125 -271.047718) (xy 329.941174 -270.947896) (xy 329.841098 -271.047718) (xy 329.841098 -271.09547)
			(xy 330.04125 -271.09547)
		)
		(stroke
			(width 0)
			(type solid)
		)
		(fill yes)
		(layer "In11.Cu")
		(net "M_F_CPU0_SB_DQS_DP<9>")
	)
	(gr_poly
		(pts
			(xy 330.04125 -270.644112) (xy 330.04125 -270.599662) (xy 329.841098 -270.599662) (xy 329.841098 -270.644112)
			(xy 329.941174 -270.744188)
		)
		(stroke
			(width 0)
			(type solid)
		)
		(fill yes)
		(layer "In11.Cu")
		(net "M_F_CPU0_SB_CB<7>")
	)
	(gr_poly
		(pts
			(xy 330.04125 -269.42796) (xy 329.941174 -269.327884) (xy 329.841098 -269.42796) (xy 329.841098 -269.47241)
			(xy 330.04125 -269.47241)
		)
		(stroke
			(width 0)
			(type solid)
		)
		(fill yes)
		(layer "In11.Cu")
		(net "M_F_CPU0_SB_CB<4>")
	)
	(gr_poly
		(pts
			(xy 330.04125 -267.807948) (xy 329.941174 -267.707872) (xy 329.841098 -267.807948) (xy 329.841098 -267.852398)
			(xy 330.04125 -267.852398)
		)
		(stroke
			(width 0)
			(type solid)
		)
		(fill yes)
		(layer "In11.Cu")
		(net "M_F_CPU0_SB_RSP<0>")
	)
	(gr_poly
		(pts
			(xy 330.04125 -265.784076) (xy 330.04125 -265.739626) (xy 329.841098 -265.739626) (xy 329.841098 -265.784076)
			(xy 329.941174 -265.884152)
		)
		(stroke
			(width 0)
			(type solid)
		)
		(fill yes)
		(layer "In11.Cu")
		(net "M_F_CPU0_SB_CS_N<0>")
	)
	(gr_poly
		(pts
			(xy 330.04125 -264.567924) (xy 329.941174 -264.467848) (xy 329.841098 -264.567924) (xy 329.841098 -264.612374)
			(xy 330.04125 -264.612374)
		)
		(stroke
			(width 0)
			(type solid)
		)
		(fill yes)
		(layer "In11.Cu")
		(net "M_F_CPU0_SB_CA<6>")
	)
	(gr_poly
		(pts
			(xy 330.04125 -264.164064) (xy 330.04125 -264.119614) (xy 329.841098 -264.119614) (xy 329.841098 -264.164064)
			(xy 329.941174 -264.26414)
		)
		(stroke
			(width 0)
			(type solid)
		)
		(fill yes)
		(layer "In11.Cu")
		(net "M_F_CPU0_SB_CA<5>")
	)
	(gr_poly
		(pts
			(xy 330.04125 -262.947912) (xy 329.941174 -262.847836) (xy 329.841098 -262.947912) (xy 329.841098 -262.992362)
			(xy 330.04125 -262.992362)
		)
		(stroke
			(width 0)
			(type solid)
		)
		(fill yes)
		(layer "In11.Cu")
		(net "M_F_CPU0_SB_CA<2>")
	)
	(gr_poly
		(pts
			(xy 330.04125 -262.544052) (xy 330.04125 -262.499602) (xy 329.841098 -262.499602) (xy 329.841098 -262.544052)
			(xy 329.941174 -262.644128)
		)
		(stroke
			(width 0)
			(type solid)
		)
		(fill yes)
		(layer "In11.Cu")
		(net "M_F_CPU0_SB_CA<1>")
	)
	(gr_poly
		(pts
			(xy 330.09713 -293.860474) (xy 330.0603 -293.723822) (xy 330.021946 -293.70147) (xy 329.92187 -293.874698)
			(xy 329.960478 -293.89705)
		)
		(stroke
			(width 0)
			(type solid)
		)
		(fill yes)
		(layer "In11.Cu")
		(net "M_F_CPU0_SB_DQ<31>")
	)
	(gr_poly
		(pts
			(xy 330.209906 -231.322372) (xy 330.209906 -231.277922) (xy 330.012294 -231.277922) (xy 330.012294 -231.322372)
			(xy 330.1111 -231.422448)
		)
		(stroke
			(width 0)
			(type solid)
		)
		(fill yes)
		(layer "In11.Cu")
		(net "M_F_CPU0_SA_DQ<11>")
	)
	(gr_poly
		(pts
			(xy 330.211176 -256.025904) (xy 330.1111 -255.926082) (xy 330.011024 -256.025904) (xy 330.011024 -256.073656)
			(xy 330.211176 -256.073656)
		)
		(stroke
			(width 0)
			(type solid)
		)
		(fill yes)
		(layer "In11.Cu")
		(net "M_F_CPU0_CLK_DP<0>")
	)
	(gr_poly
		(pts
			(xy 330.211176 -255.622298) (xy 330.211176 -255.577848) (xy 330.011024 -255.577848) (xy 330.011024 -255.622298)
			(xy 330.1111 -255.722374)
		)
		(stroke
			(width 0)
			(type solid)
		)
		(fill yes)
		(layer "In11.Cu")
		(net "M_F_CPU0_SA_PAR")
	)
	(gr_poly
		(pts
			(xy 330.211176 -254.406146) (xy 330.1111 -254.30607) (xy 330.011024 -254.406146) (xy 330.011024 -254.450596)
			(xy 330.211176 -254.450596)
		)
		(stroke
			(width 0)
			(type solid)
		)
		(fill yes)
		(layer "In11.Cu")
		(net "M_F_CPU0_SA_CA<4>")
	)
	(gr_poly
		(pts
			(xy 330.211176 -254.002286) (xy 330.211176 -253.957836) (xy 330.011024 -253.957836) (xy 330.011024 -254.002286)
			(xy 330.1111 -254.102362)
		)
		(stroke
			(width 0)
			(type solid)
		)
		(fill yes)
		(layer "In11.Cu")
		(net "M_F_CPU0_SA_CA<3>")
	)
	(gr_poly
		(pts
			(xy 330.211176 -252.786134) (xy 330.1111 -252.686058) (xy 330.011024 -252.786134) (xy 330.011024 -252.830584)
			(xy 330.211176 -252.830584)
		)
		(stroke
			(width 0)
			(type solid)
		)
		(fill yes)
		(layer "In11.Cu")
		(net "M_F_CPU0_SA_CA<0>")
	)
	(gr_poly
		(pts
			(xy 330.211176 -252.382274) (xy 330.211176 -252.337824) (xy 330.011024 -252.337824) (xy 330.011024 -252.382274)
			(xy 330.1111 -252.48235)
		)
		(stroke
			(width 0)
			(type solid)
		)
		(fill yes)
		(layer "In11.Cu")
		(net "M_F_CPU0_SA_CS_N<1>")
	)
	(gr_poly
		(pts
			(xy 330.211176 -250.762262) (xy 330.211176 -250.717812) (xy 330.011024 -250.717812) (xy 330.011024 -250.762262)
			(xy 330.1111 -250.862338)
		)
		(stroke
			(width 0)
			(type solid)
		)
		(fill yes)
		(layer "In11.Cu")
		(net "M_F_CPU0_RESET_N")
	)
	(gr_poly
		(pts
			(xy 330.211176 -249.14225) (xy 330.211176 -249.0978) (xy 330.011024 -249.0978) (xy 330.011024 -249.14225)
			(xy 330.1111 -249.242326)
		)
		(stroke
			(width 0)
			(type solid)
		)
		(fill yes)
		(layer "In11.Cu")
		(net "M_F_CPU0_SA_CB<7>")
	)
	(gr_poly
		(pts
			(xy 330.211176 -247.926098) (xy 330.1111 -247.826022) (xy 330.011024 -247.926098) (xy 330.011024 -247.970548)
			(xy 330.211176 -247.970548)
		)
		(stroke
			(width 0)
			(type solid)
		)
		(fill yes)
		(layer "In11.Cu")
		(net "M_F_CPU0_SA_CB<4>")
	)
	(gr_poly
		(pts
			(xy 330.211176 -247.522492) (xy 330.211176 -247.47474) (xy 330.011024 -247.47474) (xy 330.011024 -247.522492)
			(xy 330.1111 -247.622314)
		)
		(stroke
			(width 0)
			(type solid)
		)
		(fill yes)
		(layer "In11.Cu")
		(net "M_F_CPU0_SA_DQS_DP<9>")
	)
	(gr_poly
		(pts
			(xy 330.211176 -246.305832) (xy 330.1111 -246.20601) (xy 330.011024 -246.305832) (xy 330.011024 -246.353584)
			(xy 330.211176 -246.353584)
		)
		(stroke
			(width 0)
			(type solid)
		)
		(fill yes)
		(layer "In11.Cu")
		(net "M_F_CPU0_SA_DQS_DP<4>")
	)
	(gr_poly
		(pts
			(xy 330.211176 -245.902226) (xy 330.211176 -245.857776) (xy 330.011024 -245.857776) (xy 330.011024 -245.902226)
			(xy 330.1111 -246.002302)
		)
		(stroke
			(width 0)
			(type solid)
		)
		(fill yes)
		(layer "In11.Cu")
		(net "M_F_CPU0_SA_CB<3>")
	)
	(gr_poly
		(pts
			(xy 330.211176 -244.686074) (xy 330.1111 -244.585998) (xy 330.011024 -244.686074) (xy 330.011024 -244.730524)
			(xy 330.211176 -244.730524)
		)
		(stroke
			(width 0)
			(type solid)
		)
		(fill yes)
		(layer "In11.Cu")
		(net "M_F_CPU0_SA_CB<0>")
	)
	(gr_poly
		(pts
			(xy 330.211176 -244.282214) (xy 330.211176 -244.237764) (xy 330.011024 -244.237764) (xy 330.011024 -244.282214)
			(xy 330.1111 -244.38229)
		)
		(stroke
			(width 0)
			(type solid)
		)
		(fill yes)
		(layer "In11.Cu")
		(net "M_F_CPU0_SA_DQ<31>")
	)
	(gr_poly
		(pts
			(xy 330.211176 -243.066062) (xy 330.1111 -242.965986) (xy 330.011024 -243.066062) (xy 330.011024 -243.110512)
			(xy 330.211176 -243.110512)
		)
		(stroke
			(width 0)
			(type solid)
		)
		(fill yes)
		(layer "In11.Cu")
		(net "M_F_CPU0_SA_DQ<28>")
	)
	(gr_poly
		(pts
			(xy 330.211176 -242.662456) (xy 330.211176 -242.614704) (xy 330.011024 -242.614704) (xy 330.011024 -242.662456)
			(xy 330.1111 -242.762278)
		)
		(stroke
			(width 0)
			(type solid)
		)
		(fill yes)
		(layer "In11.Cu")
		(net "M_F_CPU0_SA_DQS_DP<8>")
	)
	(gr_poly
		(pts
			(xy 330.211176 -241.445796) (xy 330.1111 -241.345974) (xy 330.011024 -241.445796) (xy 330.011024 -241.493548)
			(xy 330.211176 -241.493548)
		)
		(stroke
			(width 0)
			(type solid)
		)
		(fill yes)
		(layer "In11.Cu")
		(net "M_F_CPU0_SA_DQS_DP<3>")
	)
	(gr_poly
		(pts
			(xy 330.211176 -241.04219) (xy 330.211176 -240.99774) (xy 330.011024 -240.99774) (xy 330.011024 -241.04219)
			(xy 330.1111 -241.142266)
		)
		(stroke
			(width 0)
			(type solid)
		)
		(fill yes)
		(layer "In11.Cu")
		(net "M_F_CPU0_SA_DQ<27>")
	)
	(gr_poly
		(pts
			(xy 330.211176 -239.826038) (xy 330.1111 -239.725962) (xy 330.011024 -239.826038) (xy 330.011024 -239.870488)
			(xy 330.211176 -239.870488)
		)
		(stroke
			(width 0)
			(type solid)
		)
		(fill yes)
		(layer "In11.Cu")
		(net "M_F_CPU0_SA_DQ<24>")
	)
	(gr_poly
		(pts
			(xy 330.211176 -239.422178) (xy 330.211176 -239.377728) (xy 330.011024 -239.377728) (xy 330.011024 -239.422178)
			(xy 330.1111 -239.522254)
		)
		(stroke
			(width 0)
			(type solid)
		)
		(fill yes)
		(layer "In11.Cu")
		(net "M_F_CPU0_SA_DQ<23>")
	)
	(gr_poly
		(pts
			(xy 330.211176 -238.206026) (xy 330.1111 -238.10595) (xy 330.011024 -238.206026) (xy 330.011024 -238.250476)
			(xy 330.211176 -238.250476)
		)
		(stroke
			(width 0)
			(type solid)
		)
		(fill yes)
		(layer "In11.Cu")
		(net "M_F_CPU0_SA_DQ<20>")
	)
	(gr_poly
		(pts
			(xy 330.211176 -237.80242) (xy 330.211176 -237.754668) (xy 330.011024 -237.754668) (xy 330.011024 -237.80242)
			(xy 330.1111 -237.902242)
		)
		(stroke
			(width 0)
			(type solid)
		)
		(fill yes)
		(layer "In11.Cu")
		(net "M_F_CPU0_SA_DQS_DP<7>")
	)
	(gr_poly
		(pts
			(xy 330.211176 -236.58576) (xy 330.1111 -236.485938) (xy 330.011024 -236.58576) (xy 330.011024 -236.633512)
			(xy 330.211176 -236.633512)
		)
		(stroke
			(width 0)
			(type solid)
		)
		(fill yes)
		(layer "In11.Cu")
		(net "M_F_CPU0_SA_DQS_DP<2>")
	)
	(gr_poly
		(pts
			(xy 330.211176 -236.182154) (xy 330.211176 -236.137704) (xy 330.011024 -236.137704) (xy 330.011024 -236.182154)
			(xy 330.1111 -236.28223)
		)
		(stroke
			(width 0)
			(type solid)
		)
		(fill yes)
		(layer "In11.Cu")
		(net "M_F_CPU0_SA_DQ<19>")
	)
	(gr_poly
		(pts
			(xy 330.211176 -234.966002) (xy 330.1111 -234.865926) (xy 330.011024 -234.966002) (xy 330.011024 -235.010452)
			(xy 330.211176 -235.010452)
		)
		(stroke
			(width 0)
			(type solid)
		)
		(fill yes)
		(layer "In11.Cu")
		(net "M_F_CPU0_SA_DQ<16>")
	)
	(gr_poly
		(pts
			(xy 330.211176 -234.562142) (xy 330.211176 -234.517692) (xy 330.011024 -234.517692) (xy 330.011024 -234.562142)
			(xy 330.1111 -234.662218)
		)
		(stroke
			(width 0)
			(type solid)
		)
		(fill yes)
		(layer "In11.Cu")
		(net "M_F_CPU0_SA_DQ<15>")
	)
	(gr_poly
		(pts
			(xy 330.211176 -233.34599) (xy 330.1111 -233.245914) (xy 330.011024 -233.34599) (xy 330.011024 -233.39044)
			(xy 330.211176 -233.39044)
		)
		(stroke
			(width 0)
			(type solid)
		)
		(fill yes)
		(layer "In11.Cu")
		(net "M_F_CPU0_SA_DQ<12>")
	)
	(gr_poly
		(pts
			(xy 330.211176 -232.942384) (xy 330.211176 -232.894632) (xy 330.011024 -232.894632) (xy 330.011024 -232.942384)
			(xy 330.1111 -233.042206)
		)
		(stroke
			(width 0)
			(type solid)
		)
		(fill yes)
		(layer "In11.Cu")
		(net "M_F_CPU0_SA_DQS_DP<6>")
	)
	(gr_poly
		(pts
			(xy 330.211176 -231.725724) (xy 330.1111 -231.625902) (xy 330.011024 -231.725724) (xy 330.011024 -231.773476)
			(xy 330.211176 -231.773476)
		)
		(stroke
			(width 0)
			(type solid)
		)
		(fill yes)
		(layer "In11.Cu")
		(net "M_F_CPU0_SA_DQS_DP<1>")
	)
	(gr_poly
		(pts
			(xy 330.211176 -230.105966) (xy 330.1111 -230.006144) (xy 330.011024 -230.105966) (xy 330.011024 -230.150416)
			(xy 330.211176 -230.150416)
		)
		(stroke
			(width 0)
			(type solid)
		)
		(fill yes)
		(layer "In11.Cu")
		(net "M_F_CPU0_SA_DQ<8>")
	)
	(gr_poly
		(pts
			(xy 330.211176 -229.70236) (xy 330.211176 -229.65791) (xy 330.011024 -229.65791) (xy 330.011024 -229.70236)
			(xy 330.1111 -229.802436)
		)
		(stroke
			(width 0)
			(type solid)
		)
		(fill yes)
		(layer "In11.Cu")
		(net "M_F_CPU0_SA_DQ<7>")
	)
	(gr_poly
		(pts
			(xy 330.211176 -228.486208) (xy 330.1111 -228.386132) (xy 330.011024 -228.486208) (xy 330.011024 -228.530658)
			(xy 330.211176 -228.530658)
		)
		(stroke
			(width 0)
			(type solid)
		)
		(fill yes)
		(layer "In11.Cu")
		(net "M_F_CPU0_SA_DQ<4>")
	)
	(gr_poly
		(pts
			(xy 330.211176 -228.082602) (xy 330.211176 -228.03485) (xy 330.011024 -228.03485) (xy 330.011024 -228.082602)
			(xy 330.1111 -228.182424)
		)
		(stroke
			(width 0)
			(type solid)
		)
		(fill yes)
		(layer "In11.Cu")
		(net "M_F_CPU0_SA_DQS_DP<5>")
	)
	(gr_poly
		(pts
			(xy 330.211176 -226.865942) (xy 330.1111 -226.76612) (xy 330.011024 -226.865942) (xy 330.011024 -226.913694)
			(xy 330.211176 -226.913694)
		)
		(stroke
			(width 0)
			(type solid)
		)
		(fill yes)
		(layer "In11.Cu")
		(net "M_F_CPU0_SA_DQS_DP<0>")
	)
	(gr_poly
		(pts
			(xy 330.211176 -226.462336) (xy 330.211176 -226.417886) (xy 330.011024 -226.417886) (xy 330.011024 -226.462336)
			(xy 330.1111 -226.562412)
		)
		(stroke
			(width 0)
			(type solid)
		)
		(fill yes)
		(layer "In11.Cu")
		(net "M_F_CPU0_SA_DQ<3>")
	)
	(gr_poly
		(pts
			(xy 330.211176 -225.246184) (xy 330.1111 -225.146108) (xy 330.011024 -225.246184) (xy 330.011024 -225.290634)
			(xy 330.211176 -225.290634)
		)
		(stroke
			(width 0)
			(type solid)
		)
		(fill yes)
		(layer "In11.Cu")
		(net "M_F_CPU0_SA_DQ<0>")
	)
	(gr_poly
		(pts
			(xy 330.51115 -292.91788) (xy 330.411074 -292.817804) (xy 330.310998 -292.91788) (xy 330.310998 -292.96233)
			(xy 330.51115 -292.96233)
		)
		(stroke
			(width 0)
			(type solid)
		)
		(fill yes)
		(layer "In11.Cu")
		(net "M_F_CPU0_SB_DQ<29>")
	)
	(gr_poly
		(pts
			(xy 330.51115 -292.51402) (xy 330.51115 -292.46957) (xy 330.310998 -292.46957) (xy 330.310998 -292.51402)
			(xy 330.411074 -292.614096)
		)
		(stroke
			(width 0)
			(type solid)
		)
		(fill yes)
		(layer "In11.Cu")
		(net "M_F_CPU0_SB_DQ<30>")
	)
	(gr_poly
		(pts
			(xy 330.51115 -291.297614) (xy 330.411074 -291.197792) (xy 330.310998 -291.297614) (xy 330.310998 -291.345366)
			(xy 330.51115 -291.345366)
		)
		(stroke
			(width 0)
			(type solid)
		)
		(fill yes)
		(layer "In11.Cu")
		(net "M_F_CPU0_SB_DQS_DN<8>")
	)
	(gr_poly
		(pts
			(xy 330.51115 -290.894262) (xy 330.51115 -290.84651) (xy 330.310998 -290.84651) (xy 330.310998 -290.894262)
			(xy 330.411074 -290.994084)
		)
		(stroke
			(width 0)
			(type solid)
		)
		(fill yes)
		(layer "In11.Cu")
		(net "M_F_CPU0_SB_DQS_DN<3>")
	)
	(gr_poly
		(pts
			(xy 330.51115 -289.677856) (xy 330.411074 -289.57778) (xy 330.310998 -289.677856) (xy 330.310998 -289.722306)
			(xy 330.51115 -289.722306)
		)
		(stroke
			(width 0)
			(type solid)
		)
		(fill yes)
		(layer "In11.Cu")
		(net "M_F_CPU0_SB_DQ<25>")
	)
	(gr_poly
		(pts
			(xy 330.51115 -289.273996) (xy 330.51115 -289.229546) (xy 330.310998 -289.229546) (xy 330.310998 -289.273996)
			(xy 330.411074 -289.374072)
		)
		(stroke
			(width 0)
			(type solid)
		)
		(fill yes)
		(layer "In11.Cu")
		(net "M_F_CPU0_SB_DQ<26>")
	)
	(gr_poly
		(pts
			(xy 330.51115 -288.057844) (xy 330.411074 -287.957768) (xy 330.310998 -288.057844) (xy 330.310998 -288.102294)
			(xy 330.51115 -288.102294)
		)
		(stroke
			(width 0)
			(type solid)
		)
		(fill yes)
		(layer "In11.Cu")
		(net "M_F_CPU0_SB_DQ<21>")
	)
	(gr_poly
		(pts
			(xy 330.51115 -287.654238) (xy 330.51115 -287.609788) (xy 330.310998 -287.609788) (xy 330.310998 -287.654238)
			(xy 330.411074 -287.75406)
		)
		(stroke
			(width 0)
			(type solid)
		)
		(fill yes)
		(layer "In11.Cu")
		(net "M_F_CPU0_SB_DQ<22>")
	)
	(gr_poly
		(pts
			(xy 330.51115 -286.437832) (xy 330.411074 -286.337756) (xy 330.310998 -286.437832) (xy 330.310998 -286.485584)
			(xy 330.51115 -286.485584)
		)
		(stroke
			(width 0)
			(type solid)
		)
		(fill yes)
		(layer "In11.Cu")
		(net "M_F_CPU0_SB_DQS_DN<7>")
	)
	(gr_poly
		(pts
			(xy 330.51115 -286.03448) (xy 330.51115 -285.986728) (xy 330.310998 -285.986728) (xy 330.310998 -286.03448)
			(xy 330.411074 -286.134302)
		)
		(stroke
			(width 0)
			(type solid)
		)
		(fill yes)
		(layer "In11.Cu")
		(net "M_F_CPU0_SB_DQS_DN<2>")
	)
	(gr_poly
		(pts
			(xy 330.51115 -284.818074) (xy 330.411074 -284.717998) (xy 330.310998 -284.818074) (xy 330.310998 -284.862524)
			(xy 330.51115 -284.862524)
		)
		(stroke
			(width 0)
			(type solid)
		)
		(fill yes)
		(layer "In11.Cu")
		(net "M_F_CPU0_SB_DQ<17>")
	)
	(gr_poly
		(pts
			(xy 330.51115 -284.414214) (xy 330.51115 -284.369764) (xy 330.310998 -284.369764) (xy 330.310998 -284.414214)
			(xy 330.411074 -284.51429)
		)
		(stroke
			(width 0)
			(type solid)
		)
		(fill yes)
		(layer "In11.Cu")
		(net "M_F_CPU0_SB_DQ<18>")
	)
	(gr_poly
		(pts
			(xy 330.51115 -283.198062) (xy 330.411074 -283.097986) (xy 330.310998 -283.198062) (xy 330.310998 -283.242512)
			(xy 330.51115 -283.242512)
		)
		(stroke
			(width 0)
			(type solid)
		)
		(fill yes)
		(layer "In11.Cu")
		(net "M_F_CPU0_SB_DQ<13>")
	)
	(gr_poly
		(pts
			(xy 330.51115 -282.794202) (xy 330.51115 -282.749752) (xy 330.310998 -282.749752) (xy 330.310998 -282.794202)
			(xy 330.411074 -282.894278)
		)
		(stroke
			(width 0)
			(type solid)
		)
		(fill yes)
		(layer "In11.Cu")
		(net "M_F_CPU0_SB_DQ<14>")
	)
	(gr_poly
		(pts
			(xy 330.51115 -281.577796) (xy 330.411074 -281.477974) (xy 330.310998 -281.577796) (xy 330.310998 -281.625548)
			(xy 330.51115 -281.625548)
		)
		(stroke
			(width 0)
			(type solid)
		)
		(fill yes)
		(layer "In11.Cu")
		(net "M_F_CPU0_SB_DQS_DN<6>")
	)
	(gr_poly
		(pts
			(xy 330.51115 -281.174444) (xy 330.51115 -281.126692) (xy 330.310998 -281.126692) (xy 330.310998 -281.174444)
			(xy 330.411074 -281.274266)
		)
		(stroke
			(width 0)
			(type solid)
		)
		(fill yes)
		(layer "In11.Cu")
		(net "M_F_CPU0_SB_DQS_DN<1>")
	)
	(gr_poly
		(pts
			(xy 330.51115 -279.958038) (xy 330.411074 -279.857962) (xy 330.310998 -279.958038) (xy 330.310998 -280.002488)
			(xy 330.51115 -280.002488)
		)
		(stroke
			(width 0)
			(type solid)
		)
		(fill yes)
		(layer "In11.Cu")
		(net "M_F_CPU0_SB_DQ<9>")
	)
	(gr_poly
		(pts
			(xy 330.51115 -279.554178) (xy 330.51115 -279.509728) (xy 330.310998 -279.509728) (xy 330.310998 -279.554178)
			(xy 330.411074 -279.654254)
		)
		(stroke
			(width 0)
			(type solid)
		)
		(fill yes)
		(layer "In11.Cu")
		(net "M_F_CPU0_SB_DQ<10>")
	)
	(gr_poly
		(pts
			(xy 330.51115 -278.338026) (xy 330.411074 -278.23795) (xy 330.310998 -278.338026) (xy 330.310998 -278.382476)
			(xy 330.51115 -278.382476)
		)
		(stroke
			(width 0)
			(type solid)
		)
		(fill yes)
		(layer "In11.Cu")
		(net "M_F_CPU0_SB_DQ<5>")
	)
	(gr_poly
		(pts
			(xy 330.51115 -277.934166) (xy 330.51115 -277.889716) (xy 330.310998 -277.889716) (xy 330.310998 -277.934166)
			(xy 330.411074 -278.034242)
		)
		(stroke
			(width 0)
			(type solid)
		)
		(fill yes)
		(layer "In11.Cu")
		(net "M_F_CPU0_SB_DQ<6>")
	)
	(gr_poly
		(pts
			(xy 330.51115 -276.71776) (xy 330.411074 -276.617938) (xy 330.310998 -276.71776) (xy 330.310998 -276.765512)
			(xy 330.51115 -276.765512)
		)
		(stroke
			(width 0)
			(type solid)
		)
		(fill yes)
		(layer "In11.Cu")
		(net "M_F_CPU0_SB_DQS_DN<5>")
	)
	(gr_poly
		(pts
			(xy 330.51115 -276.314408) (xy 330.51115 -276.266656) (xy 330.310998 -276.266656) (xy 330.310998 -276.314408)
			(xy 330.411074 -276.41423)
		)
		(stroke
			(width 0)
			(type solid)
		)
		(fill yes)
		(layer "In11.Cu")
		(net "M_F_CPU0_SB_DQS_DN<0>")
	)
	(gr_poly
		(pts
			(xy 330.51115 -275.098002) (xy 330.411074 -274.997926) (xy 330.310998 -275.098002) (xy 330.310998 -275.142452)
			(xy 330.51115 -275.142452)
		)
		(stroke
			(width 0)
			(type solid)
		)
		(fill yes)
		(layer "In11.Cu")
		(net "M_F_CPU0_SB_DQ<1>")
	)
	(gr_poly
		(pts
			(xy 330.51115 -274.694142) (xy 330.51115 -274.649692) (xy 330.310998 -274.649692) (xy 330.310998 -274.694142)
			(xy 330.411074 -274.794218)
		)
		(stroke
			(width 0)
			(type solid)
		)
		(fill yes)
		(layer "In11.Cu")
		(net "M_F_CPU0_SB_DQ<2>")
	)
	(gr_poly
		(pts
			(xy 330.51115 -273.47799) (xy 330.411074 -273.377914) (xy 330.310998 -273.47799) (xy 330.310998 -273.52244)
			(xy 330.51115 -273.52244)
		)
		(stroke
			(width 0)
			(type solid)
		)
		(fill yes)
		(layer "In11.Cu")
		(net "M_F_CPU0_SB_CB<1>")
	)
	(gr_poly
		(pts
			(xy 330.51115 -273.07413) (xy 330.51115 -273.02968) (xy 330.310998 -273.02968) (xy 330.310998 -273.07413)
			(xy 330.411074 -273.174206)
		)
		(stroke
			(width 0)
			(type solid)
		)
		(fill yes)
		(layer "In11.Cu")
		(net "M_F_CPU0_SB_CB<2>")
	)
	(gr_poly
		(pts
			(xy 330.51115 -271.857724) (xy 330.411074 -271.757902) (xy 330.310998 -271.857724) (xy 330.310998 -271.905476)
			(xy 330.51115 -271.905476)
		)
		(stroke
			(width 0)
			(type solid)
		)
		(fill yes)
		(layer "In11.Cu")
		(net "M_F_CPU0_SB_DQS_DN<4>")
	)
	(gr_poly
		(pts
			(xy 330.51115 -271.454372) (xy 330.51115 -271.40662) (xy 330.310998 -271.40662) (xy 330.310998 -271.454372)
			(xy 330.411074 -271.554194)
		)
		(stroke
			(width 0)
			(type solid)
		)
		(fill yes)
		(layer "In11.Cu")
		(net "M_F_CPU0_SB_DQS_DN<9>")
	)
	(gr_poly
		(pts
			(xy 330.51115 -270.237966) (xy 330.411074 -270.13789) (xy 330.310998 -270.237966) (xy 330.310998 -270.282416)
			(xy 330.51115 -270.282416)
		)
		(stroke
			(width 0)
			(type solid)
		)
		(fill yes)
		(layer "In11.Cu")
		(net "M_F_CPU0_SB_CB<5>")
	)
	(gr_poly
		(pts
			(xy 330.51115 -269.834106) (xy 330.51115 -269.789656) (xy 330.310998 -269.789656) (xy 330.310998 -269.834106)
			(xy 330.411074 -269.934182)
		)
		(stroke
			(width 0)
			(type solid)
		)
		(fill yes)
		(layer "In11.Cu")
		(net "M_F_CPU0_SB_CB<6>")
	)
	(gr_poly
		(pts
			(xy 330.51115 -266.997942) (xy 330.411074 -266.897866) (xy 330.310998 -266.997942) (xy 330.310998 -267.042392)
			(xy 330.51115 -267.042392)
		)
		(stroke
			(width 0)
			(type solid)
		)
		(fill yes)
		(layer "In11.Cu")
		(net "M_F_CPU0_SA_RSP<0>")
	)
	(gr_poly
		(pts
			(xy 330.51115 -266.594082) (xy 330.51115 -266.549632) (xy 330.310998 -266.549632) (xy 330.310998 -266.594082)
			(xy 330.411074 -266.694158)
		)
		(stroke
			(width 0)
			(type solid)
		)
		(fill yes)
		(layer "In11.Cu")
		(net "M_F_CPU0_SB_CS_N<1>")
	)
	(gr_poly
		(pts
			(xy 330.51115 -264.97407) (xy 330.51115 -264.92962) (xy 330.310998 -264.92962) (xy 330.310998 -264.97407)
			(xy 330.411074 -265.074146)
		)
		(stroke
			(width 0)
			(type solid)
		)
		(fill yes)
		(layer "In11.Cu")
		(net "M_F_CPU0_SB_PAR")
	)
	(gr_poly
		(pts
			(xy 330.51115 -263.757918) (xy 330.411074 -263.657842) (xy 330.310998 -263.757918) (xy 330.310998 -263.802368)
			(xy 330.51115 -263.802368)
		)
		(stroke
			(width 0)
			(type solid)
		)
		(fill yes)
		(layer "In11.Cu")
		(net "M_F_CPU0_SB_CA<4>")
	)
	(gr_poly
		(pts
			(xy 330.51115 -263.354058) (xy 330.51115 -263.309608) (xy 330.310998 -263.309608) (xy 330.310998 -263.354058)
			(xy 330.411074 -263.454134)
		)
		(stroke
			(width 0)
			(type solid)
		)
		(fill yes)
		(layer "In11.Cu")
		(net "M_F_CPU0_SB_CA<3>")
	)
	(gr_poly
		(pts
			(xy 330.51115 -262.137906) (xy 330.411074 -262.03783) (xy 330.310998 -262.137906) (xy 330.310998 -262.182356)
			(xy 330.51115 -262.182356)
		)
		(stroke
			(width 0)
			(type solid)
		)
		(fill yes)
		(layer "In11.Cu")
		(net "M_F_CPU0_SB_CA<0>")
	)
	(gr_poly
		(pts
			(xy 330.679806 -230.915972) (xy 330.581 -230.815896) (xy 330.482194 -230.915972) (xy 330.482194 -230.960422)
			(xy 330.679806 -230.960422)
		)
		(stroke
			(width 0)
			(type solid)
		)
		(fill yes)
		(layer "In11.Cu")
		(net "M_F_CPU0_SA_DQ<9>")
	)
	(gr_poly
		(pts
			(xy 330.681076 -256.432558) (xy 330.681076 -256.384806) (xy 330.480924 -256.384806) (xy 330.480924 -256.432558)
			(xy 330.581 -256.53238)
		)
		(stroke
			(width 0)
			(type solid)
		)
		(fill yes)
		(layer "In11.Cu")
		(net "M_F_CPU0_CLK_DN<0>")
	)
	(gr_poly
		(pts
			(xy 330.681076 -255.216152) (xy 330.581 -255.116076) (xy 330.480924 -255.216152) (xy 330.480924 -255.260602)
			(xy 330.681076 -255.260602)
		)
		(stroke
			(width 0)
			(type solid)
		)
		(fill yes)
		(layer "In11.Cu")
		(net "M_F_CPU0_SA_CA<6>")
	)
	(gr_poly
		(pts
			(xy 330.681076 -254.812292) (xy 330.681076 -254.767842) (xy 330.480924 -254.767842) (xy 330.480924 -254.812292)
			(xy 330.581 -254.912368)
		)
		(stroke
			(width 0)
			(type solid)
		)
		(fill yes)
		(layer "In11.Cu")
		(net "M_F_CPU0_SA_CA<5>")
	)
	(gr_poly
		(pts
			(xy 330.681076 -253.59614) (xy 330.581 -253.496064) (xy 330.480924 -253.59614) (xy 330.480924 -253.64059)
			(xy 330.681076 -253.64059)
		)
		(stroke
			(width 0)
			(type solid)
		)
		(fill yes)
		(layer "In11.Cu")
		(net "M_F_CPU0_SA_CA<2>")
	)
	(gr_poly
		(pts
			(xy 330.681076 -253.19228) (xy 330.681076 -253.14783) (xy 330.480924 -253.14783) (xy 330.480924 -253.19228)
			(xy 330.581 -253.292356)
		)
		(stroke
			(width 0)
			(type solid)
		)
		(fill yes)
		(layer "In11.Cu")
		(net "M_F_CPU0_SA_CA<1>")
	)
	(gr_poly
		(pts
			(xy 330.681076 -251.572268) (xy 330.681076 -251.527818) (xy 330.480924 -251.527818) (xy 330.480924 -251.572268)
			(xy 330.581 -251.672344)
		)
		(stroke
			(width 0)
			(type solid)
		)
		(fill yes)
		(layer "In11.Cu")
		(net "M_F_CPU0_SA_CS_N<0>")
	)
	(gr_poly
		(pts
			(xy 330.681076 -250.356116) (xy 330.581 -250.25604) (xy 330.480924 -250.356116) (xy 330.480924 -250.400566)
			(xy 330.681076 -250.400566)
		)
		(stroke
			(width 0)
			(type solid)
		)
		(fill yes)
		(layer "In11.Cu")
		(net "M_F_CPU0_ALERT_R_N")
	)
	(gr_poly
		(pts
			(xy 330.681076 -248.736104) (xy 330.581 -248.636028) (xy 330.480924 -248.736104) (xy 330.480924 -248.780554)
			(xy 330.681076 -248.780554)
		)
		(stroke
			(width 0)
			(type solid)
		)
		(fill yes)
		(layer "In11.Cu")
		(net "M_F_CPU0_SA_CB<5>")
	)
	(gr_poly
		(pts
			(xy 330.681076 -248.332244) (xy 330.681076 -248.287794) (xy 330.480924 -248.287794) (xy 330.480924 -248.332244)
			(xy 330.581 -248.43232)
		)
		(stroke
			(width 0)
			(type solid)
		)
		(fill yes)
		(layer "In11.Cu")
		(net "M_F_CPU0_SA_CB<6>")
	)
	(gr_poly
		(pts
			(xy 330.681076 -247.115838) (xy 330.581 -247.016016) (xy 330.480924 -247.115838) (xy 330.480924 -247.16359)
			(xy 330.681076 -247.16359)
		)
		(stroke
			(width 0)
			(type solid)
		)
		(fill yes)
		(layer "In11.Cu")
		(net "M_F_CPU0_SA_DQS_DN<9>")
	)
	(gr_poly
		(pts
			(xy 330.681076 -246.712486) (xy 330.681076 -246.664734) (xy 330.480924 -246.664734) (xy 330.480924 -246.712486)
			(xy 330.581 -246.812308)
		)
		(stroke
			(width 0)
			(type solid)
		)
		(fill yes)
		(layer "In11.Cu")
		(net "M_F_CPU0_SA_DQS_DN<4>")
	)
	(gr_poly
		(pts
			(xy 330.681076 -245.49608) (xy 330.581 -245.396004) (xy 330.480924 -245.49608) (xy 330.480924 -245.54053)
			(xy 330.681076 -245.54053)
		)
		(stroke
			(width 0)
			(type solid)
		)
		(fill yes)
		(layer "In11.Cu")
		(net "M_F_CPU0_SA_CB<1>")
	)
	(gr_poly
		(pts
			(xy 330.681076 -245.09222) (xy 330.681076 -245.04777) (xy 330.480924 -245.04777) (xy 330.480924 -245.09222)
			(xy 330.581 -245.192296)
		)
		(stroke
			(width 0)
			(type solid)
		)
		(fill yes)
		(layer "In11.Cu")
		(net "M_F_CPU0_SA_CB<2>")
	)
	(gr_poly
		(pts
			(xy 330.681076 -243.876068) (xy 330.581 -243.775992) (xy 330.480924 -243.876068) (xy 330.480924 -243.920518)
			(xy 330.681076 -243.920518)
		)
		(stroke
			(width 0)
			(type solid)
		)
		(fill yes)
		(layer "In11.Cu")
		(net "M_F_CPU0_SA_DQ<29>")
	)
	(gr_poly
		(pts
			(xy 330.681076 -243.472208) (xy 330.681076 -243.427758) (xy 330.480924 -243.427758) (xy 330.480924 -243.472208)
			(xy 330.581 -243.572284)
		)
		(stroke
			(width 0)
			(type solid)
		)
		(fill yes)
		(layer "In11.Cu")
		(net "M_F_CPU0_SA_DQ<30>")
	)
	(gr_poly
		(pts
			(xy 330.681076 -242.255802) (xy 330.581 -242.15598) (xy 330.480924 -242.255802) (xy 330.480924 -242.303554)
			(xy 330.681076 -242.303554)
		)
		(stroke
			(width 0)
			(type solid)
		)
		(fill yes)
		(layer "In11.Cu")
		(net "M_F_CPU0_SA_DQS_DN<8>")
	)
	(gr_poly
		(pts
			(xy 330.681076 -241.85245) (xy 330.681076 -241.804698) (xy 330.480924 -241.804698) (xy 330.480924 -241.85245)
			(xy 330.581 -241.952272)
		)
		(stroke
			(width 0)
			(type solid)
		)
		(fill yes)
		(layer "In11.Cu")
		(net "M_F_CPU0_SA_DQS_DN<3>")
	)
	(gr_poly
		(pts
			(xy 330.681076 -240.636044) (xy 330.581 -240.535968) (xy 330.480924 -240.636044) (xy 330.480924 -240.680494)
			(xy 330.681076 -240.680494)
		)
		(stroke
			(width 0)
			(type solid)
		)
		(fill yes)
		(layer "In11.Cu")
		(net "M_F_CPU0_SA_DQ<25>")
	)
	(gr_poly
		(pts
			(xy 330.681076 -240.232184) (xy 330.681076 -240.187734) (xy 330.480924 -240.187734) (xy 330.480924 -240.232184)
			(xy 330.581 -240.33226)
		)
		(stroke
			(width 0)
			(type solid)
		)
		(fill yes)
		(layer "In11.Cu")
		(net "M_F_CPU0_SA_DQ<26>")
	)
	(gr_poly
		(pts
			(xy 330.681076 -239.016032) (xy 330.581 -238.915956) (xy 330.480924 -239.016032) (xy 330.480924 -239.060482)
			(xy 330.681076 -239.060482)
		)
		(stroke
			(width 0)
			(type solid)
		)
		(fill yes)
		(layer "In11.Cu")
		(net "M_F_CPU0_SA_DQ<21>")
	)
	(gr_poly
		(pts
			(xy 330.681076 -238.612172) (xy 330.681076 -238.567722) (xy 330.480924 -238.567722) (xy 330.480924 -238.612172)
			(xy 330.581 -238.712248)
		)
		(stroke
			(width 0)
			(type solid)
		)
		(fill yes)
		(layer "In11.Cu")
		(net "M_F_CPU0_SA_DQ<22>")
	)
	(gr_poly
		(pts
			(xy 330.681076 -237.395766) (xy 330.581 -237.295944) (xy 330.480924 -237.395766) (xy 330.480924 -237.443518)
			(xy 330.681076 -237.443518)
		)
		(stroke
			(width 0)
			(type solid)
		)
		(fill yes)
		(layer "In11.Cu")
		(net "M_F_CPU0_SA_DQS_DN<7>")
	)
	(gr_poly
		(pts
			(xy 330.681076 -236.992414) (xy 330.681076 -236.944662) (xy 330.480924 -236.944662) (xy 330.480924 -236.992414)
			(xy 330.581 -237.092236)
		)
		(stroke
			(width 0)
			(type solid)
		)
		(fill yes)
		(layer "In11.Cu")
		(net "M_F_CPU0_SA_DQS_DN<2>")
	)
	(gr_poly
		(pts
			(xy 330.681076 -235.776008) (xy 330.581 -235.675932) (xy 330.480924 -235.776008) (xy 330.480924 -235.820458)
			(xy 330.681076 -235.820458)
		)
		(stroke
			(width 0)
			(type solid)
		)
		(fill yes)
		(layer "In11.Cu")
		(net "M_F_CPU0_SA_DQ<17>")
	)
	(gr_poly
		(pts
			(xy 330.681076 -235.372148) (xy 330.681076 -235.327698) (xy 330.480924 -235.327698) (xy 330.480924 -235.372148)
			(xy 330.581 -235.472224)
		)
		(stroke
			(width 0)
			(type solid)
		)
		(fill yes)
		(layer "In11.Cu")
		(net "M_F_CPU0_SA_DQ<18>")
	)
	(gr_poly
		(pts
			(xy 330.681076 -234.155996) (xy 330.581 -234.05592) (xy 330.480924 -234.155996) (xy 330.480924 -234.200446)
			(xy 330.681076 -234.200446)
		)
		(stroke
			(width 0)
			(type solid)
		)
		(fill yes)
		(layer "In11.Cu")
		(net "M_F_CPU0_SA_DQ<13>")
	)
	(gr_poly
		(pts
			(xy 330.681076 -233.752136) (xy 330.681076 -233.707686) (xy 330.480924 -233.707686) (xy 330.480924 -233.752136)
			(xy 330.581 -233.852212)
		)
		(stroke
			(width 0)
			(type solid)
		)
		(fill yes)
		(layer "In11.Cu")
		(net "M_F_CPU0_SA_DQ<14>")
	)
	(gr_poly
		(pts
			(xy 330.681076 -232.53573) (xy 330.581 -232.435908) (xy 330.480924 -232.53573) (xy 330.480924 -232.583482)
			(xy 330.681076 -232.583482)
		)
		(stroke
			(width 0)
			(type solid)
		)
		(fill yes)
		(layer "In11.Cu")
		(net "M_F_CPU0_SA_DQS_DN<6>")
	)
	(gr_poly
		(pts
			(xy 330.681076 -232.132378) (xy 330.681076 -232.084626) (xy 330.480924 -232.084626) (xy 330.480924 -232.132378)
			(xy 330.581 -232.2322)
		)
		(stroke
			(width 0)
			(type solid)
		)
		(fill yes)
		(layer "In11.Cu")
		(net "M_F_CPU0_SA_DQS_DN<1>")
	)
	(gr_poly
		(pts
			(xy 330.681076 -230.512366) (xy 330.681076 -230.467916) (xy 330.480924 -230.467916) (xy 330.480924 -230.512366)
			(xy 330.581 -230.612188)
		)
		(stroke
			(width 0)
			(type solid)
		)
		(fill yes)
		(layer "In11.Cu")
		(net "M_F_CPU0_SA_DQ<10>")
	)
	(gr_poly
		(pts
			(xy 330.681076 -229.29596) (xy 330.581 -229.195884) (xy 330.480924 -229.29596) (xy 330.480924 -229.34041)
			(xy 330.681076 -229.34041)
		)
		(stroke
			(width 0)
			(type solid)
		)
		(fill yes)
		(layer "In11.Cu")
		(net "M_F_CPU0_SA_DQ<5>")
	)
	(gr_poly
		(pts
			(xy 330.681076 -228.892354) (xy 330.681076 -228.847904) (xy 330.480924 -228.847904) (xy 330.480924 -228.892354)
			(xy 330.581 -228.99243)
		)
		(stroke
			(width 0)
			(type solid)
		)
		(fill yes)
		(layer "In11.Cu")
		(net "M_F_CPU0_SA_DQ<6>")
	)
	(gr_poly
		(pts
			(xy 330.681076 -227.675948) (xy 330.581 -227.576126) (xy 330.480924 -227.675948) (xy 330.480924 -227.7237)
			(xy 330.681076 -227.7237)
		)
		(stroke
			(width 0)
			(type solid)
		)
		(fill yes)
		(layer "In11.Cu")
		(net "M_F_CPU0_SA_DQS_DN<5>")
	)
	(gr_poly
		(pts
			(xy 330.681076 -227.272596) (xy 330.681076 -227.224844) (xy 330.480924 -227.224844) (xy 330.480924 -227.272596)
			(xy 330.581 -227.372418)
		)
		(stroke
			(width 0)
			(type solid)
		)
		(fill yes)
		(layer "In11.Cu")
		(net "M_F_CPU0_SA_DQS_DN<0>")
	)
	(gr_poly
		(pts
			(xy 330.681076 -226.05619) (xy 330.581 -225.956114) (xy 330.480924 -226.05619) (xy 330.480924 -226.10064)
			(xy 330.681076 -226.10064)
		)
		(stroke
			(width 0)
			(type solid)
		)
		(fill yes)
		(layer "In11.Cu")
		(net "M_F_CPU0_SA_DQ<1>")
	)
	(gr_poly
		(pts
			(xy 330.681076 -225.65233) (xy 330.681076 -225.60788) (xy 330.480924 -225.60788) (xy 330.480924 -225.65233)
			(xy 330.581 -225.752406)
		)
		(stroke
			(width 0)
			(type solid)
		)
		(fill yes)
		(layer "In11.Cu")
		(net "M_F_CPU0_SA_DQ<2>")
	)
	(gr_poly
		(pts
			(xy 330.98105 -293.324026) (xy 330.98105 -293.279576) (xy 330.780898 -293.279576) (xy 330.780898 -293.324026)
			(xy 330.880974 -293.424102)
		)
		(stroke
			(width 0)
			(type solid)
		)
		(fill yes)
		(layer "In11.Cu")
		(net "M_F_CPU0_SB_DQ<31>")
	)
	(gr_poly
		(pts
			(xy 330.98105 -292.107874) (xy 330.880974 -292.007798) (xy 330.780898 -292.107874) (xy 330.780898 -292.152324)
			(xy 330.98105 -292.152324)
		)
		(stroke
			(width 0)
			(type solid)
		)
		(fill yes)
		(layer "In11.Cu")
		(net "M_F_CPU0_SB_DQ<28>")
	)
	(gr_poly
		(pts
			(xy 330.98105 -291.704268) (xy 330.98105 -291.656516) (xy 330.780898 -291.656516) (xy 330.780898 -291.704268)
			(xy 330.880974 -291.80409)
		)
		(stroke
			(width 0)
			(type solid)
		)
		(fill yes)
		(layer "In11.Cu")
		(net "M_F_CPU0_SB_DQS_DP<8>")
	)
	(gr_poly
		(pts
			(xy 330.98105 -290.487608) (xy 330.880974 -290.387786) (xy 330.780898 -290.487608) (xy 330.780898 -290.53536)
			(xy 330.98105 -290.53536)
		)
		(stroke
			(width 0)
			(type solid)
		)
		(fill yes)
		(layer "In11.Cu")
		(net "M_F_CPU0_SB_DQS_DP<3>")
	)
	(gr_poly
		(pts
			(xy 330.98105 -290.084002) (xy 330.98105 -290.039552) (xy 330.780898 -290.039552) (xy 330.780898 -290.084002)
			(xy 330.880974 -290.184078)
		)
		(stroke
			(width 0)
			(type solid)
		)
		(fill yes)
		(layer "In11.Cu")
		(net "M_F_CPU0_SB_DQ<27>")
	)
	(gr_poly
		(pts
			(xy 330.98105 -288.86785) (xy 330.880974 -288.767774) (xy 330.780898 -288.86785) (xy 330.780898 -288.9123)
			(xy 330.98105 -288.9123)
		)
		(stroke
			(width 0)
			(type solid)
		)
		(fill yes)
		(layer "In11.Cu")
		(net "M_F_CPU0_SB_DQ<24>")
	)
	(gr_poly
		(pts
			(xy 330.98105 -288.464244) (xy 330.98105 -288.419794) (xy 330.780898 -288.419794) (xy 330.780898 -288.464244)
			(xy 330.880974 -288.56432)
		)
		(stroke
			(width 0)
			(type solid)
		)
		(fill yes)
		(layer "In11.Cu")
		(net "M_F_CPU0_SB_DQ<23>")
	)
	(gr_poly
		(pts
			(xy 330.98105 -287.247838) (xy 330.880974 -287.148016) (xy 330.780898 -287.247838) (xy 330.780898 -287.292288)
			(xy 330.98105 -287.292288)
		)
		(stroke
			(width 0)
			(type solid)
		)
		(fill yes)
		(layer "In11.Cu")
		(net "M_F_CPU0_SB_DQ<20>")
	)
	(gr_poly
		(pts
			(xy 330.98105 -286.844232) (xy 330.98105 -286.79648) (xy 330.780898 -286.79648) (xy 330.780898 -286.844232)
			(xy 330.880974 -286.944308)
		)
		(stroke
			(width 0)
			(type solid)
		)
		(fill yes)
		(layer "In11.Cu")
		(net "M_F_CPU0_SB_DQS_DP<7>")
	)
	(gr_poly
		(pts
			(xy 330.98105 -285.627826) (xy 330.880974 -285.528004) (xy 330.780898 -285.627826) (xy 330.780898 -285.675578)
			(xy 330.98105 -285.675578)
		)
		(stroke
			(width 0)
			(type solid)
		)
		(fill yes)
		(layer "In11.Cu")
		(net "M_F_CPU0_SB_DQS_DP<2>")
	)
	(gr_poly
		(pts
			(xy 330.98105 -285.22422) (xy 330.98105 -285.17977) (xy 330.780898 -285.17977) (xy 330.780898 -285.22422)
			(xy 330.880974 -285.324296)
		)
		(stroke
			(width 0)
			(type solid)
		)
		(fill yes)
		(layer "In11.Cu")
		(net "M_F_CPU0_SB_DQ<19>")
	)
	(gr_poly
		(pts
			(xy 330.98105 -284.008068) (xy 330.880974 -283.907992) (xy 330.780898 -284.008068) (xy 330.780898 -284.052518)
			(xy 330.98105 -284.052518)
		)
		(stroke
			(width 0)
			(type solid)
		)
		(fill yes)
		(layer "In11.Cu")
		(net "M_F_CPU0_SB_DQ<16>")
	)
	(gr_poly
		(pts
			(xy 330.98105 -283.604208) (xy 330.98105 -283.559758) (xy 330.780898 -283.559758) (xy 330.780898 -283.604208)
			(xy 330.880974 -283.704284)
		)
		(stroke
			(width 0)
			(type solid)
		)
		(fill yes)
		(layer "In11.Cu")
		(net "M_F_CPU0_SB_DQ<15>")
	)
	(gr_poly
		(pts
			(xy 330.98105 -282.388056) (xy 330.880974 -282.28798) (xy 330.780898 -282.388056) (xy 330.780898 -282.432506)
			(xy 330.98105 -282.432506)
		)
		(stroke
			(width 0)
			(type solid)
		)
		(fill yes)
		(layer "In11.Cu")
		(net "M_F_CPU0_SB_DQ<12>")
	)
	(gr_poly
		(pts
			(xy 330.98105 -281.98445) (xy 330.98105 -281.936698) (xy 330.780898 -281.936698) (xy 330.780898 -281.98445)
			(xy 330.880974 -282.084272)
		)
		(stroke
			(width 0)
			(type solid)
		)
		(fill yes)
		(layer "In11.Cu")
		(net "M_F_CPU0_SB_DQS_DP<6>")
	)
	(gr_poly
		(pts
			(xy 330.98105 -280.76779) (xy 330.880974 -280.667968) (xy 330.780898 -280.76779) (xy 330.780898 -280.815542)
			(xy 330.98105 -280.815542)
		)
		(stroke
			(width 0)
			(type solid)
		)
		(fill yes)
		(layer "In11.Cu")
		(net "M_F_CPU0_SB_DQS_DP<1>")
	)
	(gr_poly
		(pts
			(xy 330.98105 -280.364184) (xy 330.98105 -280.319734) (xy 330.780898 -280.319734) (xy 330.780898 -280.364184)
			(xy 330.880974 -280.46426)
		)
		(stroke
			(width 0)
			(type solid)
		)
		(fill yes)
		(layer "In11.Cu")
		(net "M_F_CPU0_SB_DQ<11>")
	)
	(gr_poly
		(pts
			(xy 330.98105 -279.148032) (xy 330.880974 -279.047956) (xy 330.780898 -279.148032) (xy 330.780898 -279.192482)
			(xy 330.98105 -279.192482)
		)
		(stroke
			(width 0)
			(type solid)
		)
		(fill yes)
		(layer "In11.Cu")
		(net "M_F_CPU0_SB_DQ<8>")
	)
	(gr_poly
		(pts
			(xy 330.98105 -278.744172) (xy 330.98105 -278.699722) (xy 330.780898 -278.699722) (xy 330.780898 -278.744172)
			(xy 330.880974 -278.844248)
		)
		(stroke
			(width 0)
			(type solid)
		)
		(fill yes)
		(layer "In11.Cu")
		(net "M_F_CPU0_SB_DQ<7>")
	)
	(gr_poly
		(pts
			(xy 330.98105 -277.52802) (xy 330.880974 -277.427944) (xy 330.780898 -277.52802) (xy 330.780898 -277.57247)
			(xy 330.98105 -277.57247)
		)
		(stroke
			(width 0)
			(type solid)
		)
		(fill yes)
		(layer "In11.Cu")
		(net "M_F_CPU0_SB_DQ<4>")
	)
	(gr_poly
		(pts
			(xy 330.98105 -277.124414) (xy 330.98105 -277.076662) (xy 330.780898 -277.076662) (xy 330.780898 -277.124414)
			(xy 330.880974 -277.224236)
		)
		(stroke
			(width 0)
			(type solid)
		)
		(fill yes)
		(layer "In11.Cu")
		(net "M_F_CPU0_SB_DQS_DP<5>")
	)
	(gr_poly
		(pts
			(xy 330.98105 -275.907754) (xy 330.880974 -275.807932) (xy 330.780898 -275.907754) (xy 330.780898 -275.955506)
			(xy 330.98105 -275.955506)
		)
		(stroke
			(width 0)
			(type solid)
		)
		(fill yes)
		(layer "In11.Cu")
		(net "M_F_CPU0_SB_DQS_DP<0>")
	)
	(gr_poly
		(pts
			(xy 330.98105 -275.504148) (xy 330.98105 -275.459698) (xy 330.780898 -275.459698) (xy 330.780898 -275.504148)
			(xy 330.880974 -275.604224)
		)
		(stroke
			(width 0)
			(type solid)
		)
		(fill yes)
		(layer "In11.Cu")
		(net "M_F_CPU0_SB_DQ<3>")
	)
	(gr_poly
		(pts
			(xy 330.98105 -274.287996) (xy 330.880974 -274.18792) (xy 330.780898 -274.287996) (xy 330.780898 -274.332446)
			(xy 330.98105 -274.332446)
		)
		(stroke
			(width 0)
			(type solid)
		)
		(fill yes)
		(layer "In11.Cu")
		(net "M_F_CPU0_SB_DQ<0>")
	)
	(gr_poly
		(pts
			(xy 330.98105 -273.884136) (xy 330.98105 -273.839686) (xy 330.780898 -273.839686) (xy 330.780898 -273.884136)
			(xy 330.880974 -273.984212)
		)
		(stroke
			(width 0)
			(type solid)
		)
		(fill yes)
		(layer "In11.Cu")
		(net "M_F_CPU0_SB_CB<3>")
	)
	(gr_poly
		(pts
			(xy 330.98105 -272.667984) (xy 330.880974 -272.567908) (xy 330.780898 -272.667984) (xy 330.780898 -272.712434)
			(xy 330.98105 -272.712434)
		)
		(stroke
			(width 0)
			(type solid)
		)
		(fill yes)
		(layer "In11.Cu")
		(net "M_F_CPU0_SB_CB<0>")
	)
	(gr_poly
		(pts
			(xy 330.98105 -272.264378) (xy 330.98105 -272.216626) (xy 330.780898 -272.216626) (xy 330.780898 -272.264378)
			(xy 330.880974 -272.3642)
		)
		(stroke
			(width 0)
			(type solid)
		)
		(fill yes)
		(layer "In11.Cu")
		(net "M_F_CPU0_SB_DQS_DP<4>")
	)
	(gr_poly
		(pts
			(xy 330.98105 -271.047718) (xy 330.880974 -270.947896) (xy 330.780898 -271.047718) (xy 330.780898 -271.09547)
			(xy 330.98105 -271.09547)
		)
		(stroke
			(width 0)
			(type solid)
		)
		(fill yes)
		(layer "In11.Cu")
		(net "M_F_CPU0_SB_DQS_DP<9>")
	)
	(gr_poly
		(pts
			(xy 330.98105 -270.644112) (xy 330.98105 -270.599662) (xy 330.780898 -270.599662) (xy 330.780898 -270.644112)
			(xy 330.880974 -270.744188)
		)
		(stroke
			(width 0)
			(type solid)
		)
		(fill yes)
		(layer "In11.Cu")
		(net "M_F_CPU0_SB_CB<7>")
	)
	(gr_poly
		(pts
			(xy 330.98105 -269.42796) (xy 330.880974 -269.327884) (xy 330.780898 -269.42796) (xy 330.780898 -269.47241)
			(xy 330.98105 -269.47241)
		)
		(stroke
			(width 0)
			(type solid)
		)
		(fill yes)
		(layer "In11.Cu")
		(net "M_F_CPU0_SB_CB<4>")
	)
	(gr_poly
		(pts
			(xy 330.98105 -264.164064) (xy 330.98105 -264.119614) (xy 330.780898 -264.119614) (xy 330.780898 -264.164064)
			(xy 330.880974 -264.26414)
		)
		(stroke
			(width 0)
			(type solid)
		)
		(fill yes)
		(layer "In11.Cu")
		(net "M_F_CPU0_SB_CA<5>")
	)
	(gr_poly
		(pts
			(xy 330.98105 -262.947912) (xy 330.880974 -262.847836) (xy 330.780898 -262.947912) (xy 330.780898 -262.992362)
			(xy 330.98105 -262.992362)
		)
		(stroke
			(width 0)
			(type solid)
		)
		(fill yes)
		(layer "In11.Cu")
		(net "M_F_CPU0_SB_CA<2>")
	)
	(gr_poly
		(pts
			(xy 330.98105 -262.544052) (xy 330.98105 -262.499602) (xy 330.780898 -262.499602) (xy 330.780898 -262.544052)
			(xy 330.880974 -262.644128)
		)
		(stroke
			(width 0)
			(type solid)
		)
		(fill yes)
		(layer "In11.Cu")
		(net "M_F_CPU0_SB_CA<1>")
	)
	(gr_poly
		(pts
			(xy 330.981304 -267.807948) (xy 330.881228 -267.707872) (xy 330.781152 -267.807948) (xy 330.781152 -267.852398)
			(xy 330.981304 -267.852398)
		)
		(stroke
			(width 0)
			(type solid)
		)
		(fill yes)
		(layer "In11.Cu")
		(net "M_F_CPU0_SB_RSP<0>")
	)
	(gr_poly
		(pts
			(xy 330.981304 -265.784076) (xy 330.981304 -265.739626) (xy 330.781152 -265.739626) (xy 330.781152 -265.784076)
			(xy 330.881228 -265.884152)
		)
		(stroke
			(width 0)
			(type solid)
		)
		(fill yes)
		(layer "In11.Cu")
		(net "M_F_CPU0_SB_CS_N<0>")
	)
	(gr_poly
		(pts
			(xy 330.981304 -264.567924) (xy 330.881228 -264.467848) (xy 330.781152 -264.567924) (xy 330.781152 -264.612374)
			(xy 330.981304 -264.612374)
		)
		(stroke
			(width 0)
			(type solid)
		)
		(fill yes)
		(layer "In11.Cu")
		(net "M_F_CPU0_SB_CA<6>")
	)
	(gr_poly
		(pts
			(xy 331.14996 -231.322372) (xy 331.14996 -231.277922) (xy 330.952348 -231.277922) (xy 330.952348 -231.322372)
			(xy 331.051154 -231.422448)
		)
		(stroke
			(width 0)
			(type solid)
		)
		(fill yes)
		(layer "In11.Cu")
		(net "M_F_CPU0_SA_DQ<11>")
	)
	(gr_poly
		(pts
			(xy 331.15123 -256.025904) (xy 331.051154 -255.926082) (xy 330.951078 -256.025904) (xy 330.951078 -256.073656)
			(xy 331.15123 -256.073656)
		)
		(stroke
			(width 0)
			(type solid)
		)
		(fill yes)
		(layer "In11.Cu")
		(net "M_F_CPU0_CLK_DP<0>")
	)
	(gr_poly
		(pts
			(xy 331.15123 -255.622298) (xy 331.15123 -255.577848) (xy 330.951078 -255.577848) (xy 330.951078 -255.622298)
			(xy 331.051154 -255.722374)
		)
		(stroke
			(width 0)
			(type solid)
		)
		(fill yes)
		(layer "In11.Cu")
		(net "M_F_CPU0_SA_PAR")
	)
	(gr_poly
		(pts
			(xy 331.15123 -254.406146) (xy 331.051154 -254.30607) (xy 330.951078 -254.406146) (xy 330.951078 -254.450596)
			(xy 331.15123 -254.450596)
		)
		(stroke
			(width 0)
			(type solid)
		)
		(fill yes)
		(layer "In11.Cu")
		(net "M_F_CPU0_SA_CA<4>")
	)
	(gr_poly
		(pts
			(xy 331.15123 -254.002286) (xy 331.15123 -253.957836) (xy 330.951078 -253.957836) (xy 330.951078 -254.002286)
			(xy 331.051154 -254.102362)
		)
		(stroke
			(width 0)
			(type solid)
		)
		(fill yes)
		(layer "In11.Cu")
		(net "M_F_CPU0_SA_CA<3>")
	)
	(gr_poly
		(pts
			(xy 331.15123 -252.786134) (xy 331.051154 -252.686058) (xy 330.951078 -252.786134) (xy 330.951078 -252.830584)
			(xy 331.15123 -252.830584)
		)
		(stroke
			(width 0)
			(type solid)
		)
		(fill yes)
		(layer "In11.Cu")
		(net "M_F_CPU0_SA_CA<0>")
	)
	(gr_poly
		(pts
			(xy 331.15123 -252.382274) (xy 331.15123 -252.337824) (xy 330.951078 -252.337824) (xy 330.951078 -252.382274)
			(xy 331.051154 -252.48235)
		)
		(stroke
			(width 0)
			(type solid)
		)
		(fill yes)
		(layer "In11.Cu")
		(net "M_F_CPU0_SA_CS_N<1>")
	)
	(gr_poly
		(pts
			(xy 331.15123 -250.762262) (xy 331.15123 -250.717812) (xy 330.951078 -250.717812) (xy 330.951078 -250.762262)
			(xy 331.051154 -250.862338)
		)
		(stroke
			(width 0)
			(type solid)
		)
		(fill yes)
		(layer "In11.Cu")
		(net "M_F_CPU0_RESET_N")
	)
	(gr_poly
		(pts
			(xy 331.15123 -249.14225) (xy 331.15123 -249.0978) (xy 330.951078 -249.0978) (xy 330.951078 -249.14225)
			(xy 331.051154 -249.242326)
		)
		(stroke
			(width 0)
			(type solid)
		)
		(fill yes)
		(layer "In11.Cu")
		(net "M_F_CPU0_SA_CB<7>")
	)
	(gr_poly
		(pts
			(xy 331.15123 -247.926098) (xy 331.051154 -247.826022) (xy 330.951078 -247.926098) (xy 330.951078 -247.970548)
			(xy 331.15123 -247.970548)
		)
		(stroke
			(width 0)
			(type solid)
		)
		(fill yes)
		(layer "In11.Cu")
		(net "M_F_CPU0_SA_CB<4>")
	)
	(gr_poly
		(pts
			(xy 331.15123 -247.522492) (xy 331.15123 -247.47474) (xy 330.951078 -247.47474) (xy 330.951078 -247.522492)
			(xy 331.051154 -247.622314)
		)
		(stroke
			(width 0)
			(type solid)
		)
		(fill yes)
		(layer "In11.Cu")
		(net "M_F_CPU0_SA_DQS_DP<9>")
	)
	(gr_poly
		(pts
			(xy 331.15123 -246.305832) (xy 331.051154 -246.20601) (xy 330.951078 -246.305832) (xy 330.951078 -246.353584)
			(xy 331.15123 -246.353584)
		)
		(stroke
			(width 0)
			(type solid)
		)
		(fill yes)
		(layer "In11.Cu")
		(net "M_F_CPU0_SA_DQS_DP<4>")
	)
	(gr_poly
		(pts
			(xy 331.15123 -245.902226) (xy 331.15123 -245.857776) (xy 330.951078 -245.857776) (xy 330.951078 -245.902226)
			(xy 331.051154 -246.002302)
		)
		(stroke
			(width 0)
			(type solid)
		)
		(fill yes)
		(layer "In11.Cu")
		(net "M_F_CPU0_SA_CB<3>")
	)
	(gr_poly
		(pts
			(xy 331.15123 -244.686074) (xy 331.051154 -244.585998) (xy 330.951078 -244.686074) (xy 330.951078 -244.730524)
			(xy 331.15123 -244.730524)
		)
		(stroke
			(width 0)
			(type solid)
		)
		(fill yes)
		(layer "In11.Cu")
		(net "M_F_CPU0_SA_CB<0>")
	)
	(gr_poly
		(pts
			(xy 331.15123 -244.282214) (xy 331.15123 -244.237764) (xy 330.951078 -244.237764) (xy 330.951078 -244.282214)
			(xy 331.051154 -244.38229)
		)
		(stroke
			(width 0)
			(type solid)
		)
		(fill yes)
		(layer "In11.Cu")
		(net "M_F_CPU0_SA_DQ<31>")
	)
	(gr_poly
		(pts
			(xy 331.15123 -243.066062) (xy 331.051154 -242.965986) (xy 330.951078 -243.066062) (xy 330.951078 -243.110512)
			(xy 331.15123 -243.110512)
		)
		(stroke
			(width 0)
			(type solid)
		)
		(fill yes)
		(layer "In11.Cu")
		(net "M_F_CPU0_SA_DQ<28>")
	)
	(gr_poly
		(pts
			(xy 331.15123 -242.662456) (xy 331.15123 -242.614704) (xy 330.951078 -242.614704) (xy 330.951078 -242.662456)
			(xy 331.051154 -242.762278)
		)
		(stroke
			(width 0)
			(type solid)
		)
		(fill yes)
		(layer "In11.Cu")
		(net "M_F_CPU0_SA_DQS_DP<8>")
	)
	(gr_poly
		(pts
			(xy 331.15123 -241.445796) (xy 331.051154 -241.345974) (xy 330.951078 -241.445796) (xy 330.951078 -241.493548)
			(xy 331.15123 -241.493548)
		)
		(stroke
			(width 0)
			(type solid)
		)
		(fill yes)
		(layer "In11.Cu")
		(net "M_F_CPU0_SA_DQS_DP<3>")
	)
	(gr_poly
		(pts
			(xy 331.15123 -241.04219) (xy 331.15123 -240.99774) (xy 330.951078 -240.99774) (xy 330.951078 -241.04219)
			(xy 331.051154 -241.142266)
		)
		(stroke
			(width 0)
			(type solid)
		)
		(fill yes)
		(layer "In11.Cu")
		(net "M_F_CPU0_SA_DQ<27>")
	)
	(gr_poly
		(pts
			(xy 331.15123 -239.826038) (xy 331.051154 -239.725962) (xy 330.951078 -239.826038) (xy 330.951078 -239.870488)
			(xy 331.15123 -239.870488)
		)
		(stroke
			(width 0)
			(type solid)
		)
		(fill yes)
		(layer "In11.Cu")
		(net "M_F_CPU0_SA_DQ<24>")
	)
	(gr_poly
		(pts
			(xy 331.15123 -239.422178) (xy 331.15123 -239.377728) (xy 330.951078 -239.377728) (xy 330.951078 -239.422178)
			(xy 331.051154 -239.522254)
		)
		(stroke
			(width 0)
			(type solid)
		)
		(fill yes)
		(layer "In11.Cu")
		(net "M_F_CPU0_SA_DQ<23>")
	)
	(gr_poly
		(pts
			(xy 331.15123 -238.206026) (xy 331.051154 -238.10595) (xy 330.951078 -238.206026) (xy 330.951078 -238.250476)
			(xy 331.15123 -238.250476)
		)
		(stroke
			(width 0)
			(type solid)
		)
		(fill yes)
		(layer "In11.Cu")
		(net "M_F_CPU0_SA_DQ<20>")
	)
	(gr_poly
		(pts
			(xy 331.15123 -237.80242) (xy 331.15123 -237.754668) (xy 330.951078 -237.754668) (xy 330.951078 -237.80242)
			(xy 331.051154 -237.902242)
		)
		(stroke
			(width 0)
			(type solid)
		)
		(fill yes)
		(layer "In11.Cu")
		(net "M_F_CPU0_SA_DQS_DP<7>")
	)
	(gr_poly
		(pts
			(xy 331.15123 -236.58576) (xy 331.051154 -236.485938) (xy 330.951078 -236.58576) (xy 330.951078 -236.633512)
			(xy 331.15123 -236.633512)
		)
		(stroke
			(width 0)
			(type solid)
		)
		(fill yes)
		(layer "In11.Cu")
		(net "M_F_CPU0_SA_DQS_DP<2>")
	)
	(gr_poly
		(pts
			(xy 331.15123 -236.182154) (xy 331.15123 -236.137704) (xy 330.951078 -236.137704) (xy 330.951078 -236.182154)
			(xy 331.051154 -236.28223)
		)
		(stroke
			(width 0)
			(type solid)
		)
		(fill yes)
		(layer "In11.Cu")
		(net "M_F_CPU0_SA_DQ<19>")
	)
	(gr_poly
		(pts
			(xy 331.15123 -234.966002) (xy 331.051154 -234.865926) (xy 330.951078 -234.966002) (xy 330.951078 -235.010452)
			(xy 331.15123 -235.010452)
		)
		(stroke
			(width 0)
			(type solid)
		)
		(fill yes)
		(layer "In11.Cu")
		(net "M_F_CPU0_SA_DQ<16>")
	)
	(gr_poly
		(pts
			(xy 331.15123 -234.562142) (xy 331.15123 -234.517692) (xy 330.951078 -234.517692) (xy 330.951078 -234.562142)
			(xy 331.051154 -234.662218)
		)
		(stroke
			(width 0)
			(type solid)
		)
		(fill yes)
		(layer "In11.Cu")
		(net "M_F_CPU0_SA_DQ<15>")
	)
	(gr_poly
		(pts
			(xy 331.15123 -233.34599) (xy 331.051154 -233.245914) (xy 330.951078 -233.34599) (xy 330.951078 -233.39044)
			(xy 331.15123 -233.39044)
		)
		(stroke
			(width 0)
			(type solid)
		)
		(fill yes)
		(layer "In11.Cu")
		(net "M_F_CPU0_SA_DQ<12>")
	)
	(gr_poly
		(pts
			(xy 331.15123 -232.942384) (xy 331.15123 -232.894632) (xy 330.951078 -232.894632) (xy 330.951078 -232.942384)
			(xy 331.051154 -233.042206)
		)
		(stroke
			(width 0)
			(type solid)
		)
		(fill yes)
		(layer "In11.Cu")
		(net "M_F_CPU0_SA_DQS_DP<6>")
	)
	(gr_poly
		(pts
			(xy 331.15123 -231.725724) (xy 331.051154 -231.625902) (xy 330.951078 -231.725724) (xy 330.951078 -231.773476)
			(xy 331.15123 -231.773476)
		)
		(stroke
			(width 0)
			(type solid)
		)
		(fill yes)
		(layer "In11.Cu")
		(net "M_F_CPU0_SA_DQS_DP<1>")
	)
	(gr_poly
		(pts
			(xy 331.15123 -230.105966) (xy 331.051154 -230.006144) (xy 330.951078 -230.105966) (xy 330.951078 -230.150416)
			(xy 331.15123 -230.150416)
		)
		(stroke
			(width 0)
			(type solid)
		)
		(fill yes)
		(layer "In11.Cu")
		(net "M_F_CPU0_SA_DQ<8>")
	)
	(gr_poly
		(pts
			(xy 331.15123 -229.70236) (xy 331.15123 -229.65791) (xy 330.951078 -229.65791) (xy 330.951078 -229.70236)
			(xy 331.051154 -229.802436)
		)
		(stroke
			(width 0)
			(type solid)
		)
		(fill yes)
		(layer "In11.Cu")
		(net "M_F_CPU0_SA_DQ<7>")
	)
	(gr_poly
		(pts
			(xy 331.15123 -228.486208) (xy 331.051154 -228.386132) (xy 330.951078 -228.486208) (xy 330.951078 -228.530658)
			(xy 331.15123 -228.530658)
		)
		(stroke
			(width 0)
			(type solid)
		)
		(fill yes)
		(layer "In11.Cu")
		(net "M_F_CPU0_SA_DQ<4>")
	)
	(gr_poly
		(pts
			(xy 331.15123 -228.082602) (xy 331.15123 -228.03485) (xy 330.951078 -228.03485) (xy 330.951078 -228.082602)
			(xy 331.051154 -228.182424)
		)
		(stroke
			(width 0)
			(type solid)
		)
		(fill yes)
		(layer "In11.Cu")
		(net "M_F_CPU0_SA_DQS_DP<5>")
	)
	(gr_poly
		(pts
			(xy 331.15123 -226.865942) (xy 331.051154 -226.76612) (xy 330.951078 -226.865942) (xy 330.951078 -226.913694)
			(xy 331.15123 -226.913694)
		)
		(stroke
			(width 0)
			(type solid)
		)
		(fill yes)
		(layer "In11.Cu")
		(net "M_F_CPU0_SA_DQS_DP<0>")
	)
	(gr_poly
		(pts
			(xy 331.15123 -226.462336) (xy 331.15123 -226.417886) (xy 330.951078 -226.417886) (xy 330.951078 -226.462336)
			(xy 331.051154 -226.562412)
		)
		(stroke
			(width 0)
			(type solid)
		)
		(fill yes)
		(layer "In11.Cu")
		(net "M_F_CPU0_SA_DQ<3>")
	)
	(gr_poly
		(pts
			(xy 331.15123 -225.246184) (xy 331.051154 -225.146108) (xy 330.951078 -225.246184) (xy 330.951078 -225.290634)
			(xy 331.15123 -225.290634)
		)
		(stroke
			(width 0)
			(type solid)
		)
		(fill yes)
		(layer "In11.Cu")
		(net "M_F_CPU0_SA_DQ<0>")
	)
	(gr_poly
		(pts
			(xy 331.451204 -292.91788) (xy 331.351128 -292.817804) (xy 331.251052 -292.91788) (xy 331.251052 -292.96233)
			(xy 331.451204 -292.96233)
		)
		(stroke
			(width 0)
			(type solid)
		)
		(fill yes)
		(layer "In11.Cu")
		(net "M_F_CPU0_SB_DQ<29>")
	)
	(gr_poly
		(pts
			(xy 331.451204 -292.51402) (xy 331.451204 -292.46957) (xy 331.251052 -292.46957) (xy 331.251052 -292.51402)
			(xy 331.351128 -292.614096)
		)
		(stroke
			(width 0)
			(type solid)
		)
		(fill yes)
		(layer "In11.Cu")
		(net "M_F_CPU0_SB_DQ<30>")
	)
	(gr_poly
		(pts
			(xy 331.451204 -291.297614) (xy 331.351128 -291.197792) (xy 331.251052 -291.297614) (xy 331.251052 -291.345366)
			(xy 331.451204 -291.345366)
		)
		(stroke
			(width 0)
			(type solid)
		)
		(fill yes)
		(layer "In11.Cu")
		(net "M_F_CPU0_SB_DQS_DN<8>")
	)
	(gr_poly
		(pts
			(xy 331.451204 -290.894262) (xy 331.451204 -290.84651) (xy 331.251052 -290.84651) (xy 331.251052 -290.894262)
			(xy 331.351128 -290.994084)
		)
		(stroke
			(width 0)
			(type solid)
		)
		(fill yes)
		(layer "In11.Cu")
		(net "M_F_CPU0_SB_DQS_DN<3>")
	)
	(gr_poly
		(pts
			(xy 331.451204 -289.677856) (xy 331.351128 -289.57778) (xy 331.251052 -289.677856) (xy 331.251052 -289.722306)
			(xy 331.451204 -289.722306)
		)
		(stroke
			(width 0)
			(type solid)
		)
		(fill yes)
		(layer "In11.Cu")
		(net "M_F_CPU0_SB_DQ<25>")
	)
	(gr_poly
		(pts
			(xy 331.451204 -289.273996) (xy 331.451204 -289.229546) (xy 331.251052 -289.229546) (xy 331.251052 -289.273996)
			(xy 331.351128 -289.374072)
		)
		(stroke
			(width 0)
			(type solid)
		)
		(fill yes)
		(layer "In11.Cu")
		(net "M_F_CPU0_SB_DQ<26>")
	)
	(gr_poly
		(pts
			(xy 331.451204 -288.057844) (xy 331.351128 -287.957768) (xy 331.251052 -288.057844) (xy 331.251052 -288.102294)
			(xy 331.451204 -288.102294)
		)
		(stroke
			(width 0)
			(type solid)
		)
		(fill yes)
		(layer "In11.Cu")
		(net "M_F_CPU0_SB_DQ<21>")
	)
	(gr_poly
		(pts
			(xy 331.451204 -287.654238) (xy 331.451204 -287.609788) (xy 331.251052 -287.609788) (xy 331.251052 -287.654238)
			(xy 331.351128 -287.75406)
		)
		(stroke
			(width 0)
			(type solid)
		)
		(fill yes)
		(layer "In11.Cu")
		(net "M_F_CPU0_SB_DQ<22>")
	)
	(gr_poly
		(pts
			(xy 331.451204 -286.437832) (xy 331.351128 -286.337756) (xy 331.251052 -286.437832) (xy 331.251052 -286.485584)
			(xy 331.451204 -286.485584)
		)
		(stroke
			(width 0)
			(type solid)
		)
		(fill yes)
		(layer "In11.Cu")
		(net "M_F_CPU0_SB_DQS_DN<7>")
	)
	(gr_poly
		(pts
			(xy 331.451204 -286.03448) (xy 331.451204 -285.986728) (xy 331.251052 -285.986728) (xy 331.251052 -286.03448)
			(xy 331.351128 -286.134302)
		)
		(stroke
			(width 0)
			(type solid)
		)
		(fill yes)
		(layer "In11.Cu")
		(net "M_F_CPU0_SB_DQS_DN<2>")
	)
	(gr_poly
		(pts
			(xy 331.451204 -284.818074) (xy 331.351128 -284.717998) (xy 331.251052 -284.818074) (xy 331.251052 -284.862524)
			(xy 331.451204 -284.862524)
		)
		(stroke
			(width 0)
			(type solid)
		)
		(fill yes)
		(layer "In11.Cu")
		(net "M_F_CPU0_SB_DQ<17>")
	)
	(gr_poly
		(pts
			(xy 331.451204 -284.414214) (xy 331.451204 -284.369764) (xy 331.251052 -284.369764) (xy 331.251052 -284.414214)
			(xy 331.351128 -284.51429)
		)
		(stroke
			(width 0)
			(type solid)
		)
		(fill yes)
		(layer "In11.Cu")
		(net "M_F_CPU0_SB_DQ<18>")
	)
	(gr_poly
		(pts
			(xy 331.451204 -283.198062) (xy 331.351128 -283.097986) (xy 331.251052 -283.198062) (xy 331.251052 -283.242512)
			(xy 331.451204 -283.242512)
		)
		(stroke
			(width 0)
			(type solid)
		)
		(fill yes)
		(layer "In11.Cu")
		(net "M_F_CPU0_SB_DQ<13>")
	)
	(gr_poly
		(pts
			(xy 331.451204 -282.794202) (xy 331.451204 -282.749752) (xy 331.251052 -282.749752) (xy 331.251052 -282.794202)
			(xy 331.351128 -282.894278)
		)
		(stroke
			(width 0)
			(type solid)
		)
		(fill yes)
		(layer "In11.Cu")
		(net "M_F_CPU0_SB_DQ<14>")
	)
	(gr_poly
		(pts
			(xy 331.451204 -281.577796) (xy 331.351128 -281.477974) (xy 331.251052 -281.577796) (xy 331.251052 -281.625548)
			(xy 331.451204 -281.625548)
		)
		(stroke
			(width 0)
			(type solid)
		)
		(fill yes)
		(layer "In11.Cu")
		(net "M_F_CPU0_SB_DQS_DN<6>")
	)
	(gr_poly
		(pts
			(xy 331.451204 -281.174444) (xy 331.451204 -281.126692) (xy 331.251052 -281.126692) (xy 331.251052 -281.174444)
			(xy 331.351128 -281.274266)
		)
		(stroke
			(width 0)
			(type solid)
		)
		(fill yes)
		(layer "In11.Cu")
		(net "M_F_CPU0_SB_DQS_DN<1>")
	)
	(gr_poly
		(pts
			(xy 331.451204 -279.958038) (xy 331.351128 -279.857962) (xy 331.251052 -279.958038) (xy 331.251052 -280.002488)
			(xy 331.451204 -280.002488)
		)
		(stroke
			(width 0)
			(type solid)
		)
		(fill yes)
		(layer "In11.Cu")
		(net "M_F_CPU0_SB_DQ<9>")
	)
	(gr_poly
		(pts
			(xy 331.451204 -279.554178) (xy 331.451204 -279.509728) (xy 331.251052 -279.509728) (xy 331.251052 -279.554178)
			(xy 331.351128 -279.654254)
		)
		(stroke
			(width 0)
			(type solid)
		)
		(fill yes)
		(layer "In11.Cu")
		(net "M_F_CPU0_SB_DQ<10>")
	)
	(gr_poly
		(pts
			(xy 331.451204 -278.338026) (xy 331.351128 -278.23795) (xy 331.251052 -278.338026) (xy 331.251052 -278.382476)
			(xy 331.451204 -278.382476)
		)
		(stroke
			(width 0)
			(type solid)
		)
		(fill yes)
		(layer "In11.Cu")
		(net "M_F_CPU0_SB_DQ<5>")
	)
	(gr_poly
		(pts
			(xy 331.451204 -277.934166) (xy 331.451204 -277.889716) (xy 331.251052 -277.889716) (xy 331.251052 -277.934166)
			(xy 331.351128 -278.034242)
		)
		(stroke
			(width 0)
			(type solid)
		)
		(fill yes)
		(layer "In11.Cu")
		(net "M_F_CPU0_SB_DQ<6>")
	)
	(gr_poly
		(pts
			(xy 331.451204 -276.71776) (xy 331.351128 -276.617938) (xy 331.251052 -276.71776) (xy 331.251052 -276.765512)
			(xy 331.451204 -276.765512)
		)
		(stroke
			(width 0)
			(type solid)
		)
		(fill yes)
		(layer "In11.Cu")
		(net "M_F_CPU0_SB_DQS_DN<5>")
	)
	(gr_poly
		(pts
			(xy 331.451204 -276.314408) (xy 331.451204 -276.266656) (xy 331.251052 -276.266656) (xy 331.251052 -276.314408)
			(xy 331.351128 -276.41423)
		)
		(stroke
			(width 0)
			(type solid)
		)
		(fill yes)
		(layer "In11.Cu")
		(net "M_F_CPU0_SB_DQS_DN<0>")
	)
	(gr_poly
		(pts
			(xy 331.451204 -275.098002) (xy 331.351128 -274.997926) (xy 331.251052 -275.098002) (xy 331.251052 -275.142452)
			(xy 331.451204 -275.142452)
		)
		(stroke
			(width 0)
			(type solid)
		)
		(fill yes)
		(layer "In11.Cu")
		(net "M_F_CPU0_SB_DQ<1>")
	)
	(gr_poly
		(pts
			(xy 331.451204 -274.694142) (xy 331.451204 -274.649692) (xy 331.251052 -274.649692) (xy 331.251052 -274.694142)
			(xy 331.351128 -274.794218)
		)
		(stroke
			(width 0)
			(type solid)
		)
		(fill yes)
		(layer "In11.Cu")
		(net "M_F_CPU0_SB_DQ<2>")
	)
	(gr_poly
		(pts
			(xy 331.451204 -273.47799) (xy 331.351128 -273.377914) (xy 331.251052 -273.47799) (xy 331.251052 -273.52244)
			(xy 331.451204 -273.52244)
		)
		(stroke
			(width 0)
			(type solid)
		)
		(fill yes)
		(layer "In11.Cu")
		(net "M_F_CPU0_SB_CB<1>")
	)
	(gr_poly
		(pts
			(xy 331.451204 -273.07413) (xy 331.451204 -273.02968) (xy 331.251052 -273.02968) (xy 331.251052 -273.07413)
			(xy 331.351128 -273.174206)
		)
		(stroke
			(width 0)
			(type solid)
		)
		(fill yes)
		(layer "In11.Cu")
		(net "M_F_CPU0_SB_CB<2>")
	)
	(gr_poly
		(pts
			(xy 331.451204 -271.857724) (xy 331.351128 -271.757902) (xy 331.251052 -271.857724) (xy 331.251052 -271.905476)
			(xy 331.451204 -271.905476)
		)
		(stroke
			(width 0)
			(type solid)
		)
		(fill yes)
		(layer "In11.Cu")
		(net "M_F_CPU0_SB_DQS_DN<4>")
	)
	(gr_poly
		(pts
			(xy 331.451204 -271.454372) (xy 331.451204 -271.40662) (xy 331.251052 -271.40662) (xy 331.251052 -271.454372)
			(xy 331.351128 -271.554194)
		)
		(stroke
			(width 0)
			(type solid)
		)
		(fill yes)
		(layer "In11.Cu")
		(net "M_F_CPU0_SB_DQS_DN<9>")
	)
	(gr_poly
		(pts
			(xy 331.451204 -270.237966) (xy 331.351128 -270.13789) (xy 331.251052 -270.237966) (xy 331.251052 -270.282416)
			(xy 331.451204 -270.282416)
		)
		(stroke
			(width 0)
			(type solid)
		)
		(fill yes)
		(layer "In11.Cu")
		(net "M_F_CPU0_SB_CB<5>")
	)
	(gr_poly
		(pts
			(xy 331.451204 -269.834106) (xy 331.451204 -269.789656) (xy 331.251052 -269.789656) (xy 331.251052 -269.834106)
			(xy 331.351128 -269.934182)
		)
		(stroke
			(width 0)
			(type solid)
		)
		(fill yes)
		(layer "In11.Cu")
		(net "M_F_CPU0_SB_CB<6>")
	)
	(gr_poly
		(pts
			(xy 331.451204 -266.997942) (xy 331.351128 -266.897866) (xy 331.251052 -266.997942) (xy 331.251052 -267.042392)
			(xy 331.451204 -267.042392)
		)
		(stroke
			(width 0)
			(type solid)
		)
		(fill yes)
		(layer "In11.Cu")
		(net "M_F_CPU0_SA_RSP<0>")
	)
	(gr_poly
		(pts
			(xy 331.451204 -266.594082) (xy 331.451204 -266.549632) (xy 331.251052 -266.549632) (xy 331.251052 -266.594082)
			(xy 331.351128 -266.694158)
		)
		(stroke
			(width 0)
			(type solid)
		)
		(fill yes)
		(layer "In11.Cu")
		(net "M_F_CPU0_SB_CS_N<1>")
	)
	(gr_poly
		(pts
			(xy 331.451204 -264.97407) (xy 331.451204 -264.92962) (xy 331.251052 -264.92962) (xy 331.251052 -264.97407)
			(xy 331.351128 -265.074146)
		)
		(stroke
			(width 0)
			(type solid)
		)
		(fill yes)
		(layer "In11.Cu")
		(net "M_F_CPU0_SB_PAR")
	)
	(gr_poly
		(pts
			(xy 331.451204 -263.757918) (xy 331.351128 -263.657842) (xy 331.251052 -263.757918) (xy 331.251052 -263.802368)
			(xy 331.451204 -263.802368)
		)
		(stroke
			(width 0)
			(type solid)
		)
		(fill yes)
		(layer "In11.Cu")
		(net "M_F_CPU0_SB_CA<4>")
	)
	(gr_poly
		(pts
			(xy 331.451204 -263.354058) (xy 331.451204 -263.309608) (xy 331.251052 -263.309608) (xy 331.251052 -263.354058)
			(xy 331.351128 -263.454134)
		)
		(stroke
			(width 0)
			(type solid)
		)
		(fill yes)
		(layer "In11.Cu")
		(net "M_F_CPU0_SB_CA<3>")
	)
	(gr_poly
		(pts
			(xy 331.451204 -262.137906) (xy 331.351128 -262.03783) (xy 331.251052 -262.137906) (xy 331.251052 -262.182356)
			(xy 331.451204 -262.182356)
		)
		(stroke
			(width 0)
			(type solid)
		)
		(fill yes)
		(layer "In11.Cu")
		(net "M_F_CPU0_SB_CA<0>")
	)
	(gr_poly
		(pts
			(xy 331.61986 -230.915972) (xy 331.521054 -230.815896) (xy 331.422248 -230.915972) (xy 331.422248 -230.960422)
			(xy 331.61986 -230.960422)
		)
		(stroke
			(width 0)
			(type solid)
		)
		(fill yes)
		(layer "In11.Cu")
		(net "M_F_CPU0_SA_DQ<9>")
	)
	(gr_poly
		(pts
			(xy 331.62113 -256.432558) (xy 331.62113 -256.384806) (xy 331.420978 -256.384806) (xy 331.420978 -256.432558)
			(xy 331.521054 -256.53238)
		)
		(stroke
			(width 0)
			(type solid)
		)
		(fill yes)
		(layer "In11.Cu")
		(net "M_F_CPU0_CLK_DN<0>")
	)
	(gr_poly
		(pts
			(xy 331.62113 -255.216152) (xy 331.521054 -255.116076) (xy 331.420978 -255.216152) (xy 331.420978 -255.260602)
			(xy 331.62113 -255.260602)
		)
		(stroke
			(width 0)
			(type solid)
		)
		(fill yes)
		(layer "In11.Cu")
		(net "M_F_CPU0_SA_CA<6>")
	)
	(gr_poly
		(pts
			(xy 331.62113 -254.812292) (xy 331.62113 -254.767842) (xy 331.420978 -254.767842) (xy 331.420978 -254.812292)
			(xy 331.521054 -254.912368)
		)
		(stroke
			(width 0)
			(type solid)
		)
		(fill yes)
		(layer "In11.Cu")
		(net "M_F_CPU0_SA_CA<5>")
	)
	(gr_poly
		(pts
			(xy 331.62113 -253.59614) (xy 331.521054 -253.496064) (xy 331.420978 -253.59614) (xy 331.420978 -253.64059)
			(xy 331.62113 -253.64059)
		)
		(stroke
			(width 0)
			(type solid)
		)
		(fill yes)
		(layer "In11.Cu")
		(net "M_F_CPU0_SA_CA<2>")
	)
	(gr_poly
		(pts
			(xy 331.62113 -253.19228) (xy 331.62113 -253.14783) (xy 331.420978 -253.14783) (xy 331.420978 -253.19228)
			(xy 331.521054 -253.292356)
		)
		(stroke
			(width 0)
			(type solid)
		)
		(fill yes)
		(layer "In11.Cu")
		(net "M_F_CPU0_SA_CA<1>")
	)
	(gr_poly
		(pts
			(xy 331.62113 -251.572268) (xy 331.62113 -251.527818) (xy 331.420978 -251.527818) (xy 331.420978 -251.572268)
			(xy 331.521054 -251.672344)
		)
		(stroke
			(width 0)
			(type solid)
		)
		(fill yes)
		(layer "In11.Cu")
		(net "M_F_CPU0_SA_CS_N<0>")
	)
	(gr_poly
		(pts
			(xy 331.62113 -250.356116) (xy 331.521054 -250.25604) (xy 331.420978 -250.356116) (xy 331.420978 -250.400566)
			(xy 331.62113 -250.400566)
		)
		(stroke
			(width 0)
			(type solid)
		)
		(fill yes)
		(layer "In11.Cu")
		(net "M_F_CPU0_ALERT_R_N")
	)
	(gr_poly
		(pts
			(xy 331.62113 -248.736104) (xy 331.521054 -248.636028) (xy 331.420978 -248.736104) (xy 331.420978 -248.780554)
			(xy 331.62113 -248.780554)
		)
		(stroke
			(width 0)
			(type solid)
		)
		(fill yes)
		(layer "In11.Cu")
		(net "M_F_CPU0_SA_CB<5>")
	)
	(gr_poly
		(pts
			(xy 331.62113 -248.332244) (xy 331.62113 -248.287794) (xy 331.420978 -248.287794) (xy 331.420978 -248.332244)
			(xy 331.521054 -248.43232)
		)
		(stroke
			(width 0)
			(type solid)
		)
		(fill yes)
		(layer "In11.Cu")
		(net "M_F_CPU0_SA_CB<6>")
	)
	(gr_poly
		(pts
			(xy 331.62113 -247.115838) (xy 331.521054 -247.016016) (xy 331.420978 -247.115838) (xy 331.420978 -247.16359)
			(xy 331.62113 -247.16359)
		)
		(stroke
			(width 0)
			(type solid)
		)
		(fill yes)
		(layer "In11.Cu")
		(net "M_F_CPU0_SA_DQS_DN<9>")
	)
	(gr_poly
		(pts
			(xy 331.62113 -246.712486) (xy 331.62113 -246.664734) (xy 331.420978 -246.664734) (xy 331.420978 -246.712486)
			(xy 331.521054 -246.812308)
		)
		(stroke
			(width 0)
			(type solid)
		)
		(fill yes)
		(layer "In11.Cu")
		(net "M_F_CPU0_SA_DQS_DN<4>")
	)
	(gr_poly
		(pts
			(xy 331.62113 -245.49608) (xy 331.521054 -245.396004) (xy 331.420978 -245.49608) (xy 331.420978 -245.54053)
			(xy 331.62113 -245.54053)
		)
		(stroke
			(width 0)
			(type solid)
		)
		(fill yes)
		(layer "In11.Cu")
		(net "M_F_CPU0_SA_CB<1>")
	)
	(gr_poly
		(pts
			(xy 331.62113 -245.09222) (xy 331.62113 -245.04777) (xy 331.420978 -245.04777) (xy 331.420978 -245.09222)
			(xy 331.521054 -245.192296)
		)
		(stroke
			(width 0)
			(type solid)
		)
		(fill yes)
		(layer "In11.Cu")
		(net "M_F_CPU0_SA_CB<2>")
	)
	(gr_poly
		(pts
			(xy 331.62113 -243.876068) (xy 331.521054 -243.775992) (xy 331.420978 -243.876068) (xy 331.420978 -243.920518)
			(xy 331.62113 -243.920518)
		)
		(stroke
			(width 0)
			(type solid)
		)
		(fill yes)
		(layer "In11.Cu")
		(net "M_F_CPU0_SA_DQ<29>")
	)
	(gr_poly
		(pts
			(xy 331.62113 -243.472208) (xy 331.62113 -243.427758) (xy 331.420978 -243.427758) (xy 331.420978 -243.472208)
			(xy 331.521054 -243.572284)
		)
		(stroke
			(width 0)
			(type solid)
		)
		(fill yes)
		(layer "In11.Cu")
		(net "M_F_CPU0_SA_DQ<30>")
	)
	(gr_poly
		(pts
			(xy 331.62113 -242.255802) (xy 331.521054 -242.15598) (xy 331.420978 -242.255802) (xy 331.420978 -242.303554)
			(xy 331.62113 -242.303554)
		)
		(stroke
			(width 0)
			(type solid)
		)
		(fill yes)
		(layer "In11.Cu")
		(net "M_F_CPU0_SA_DQS_DN<8>")
	)
	(gr_poly
		(pts
			(xy 331.62113 -241.85245) (xy 331.62113 -241.804698) (xy 331.420978 -241.804698) (xy 331.420978 -241.85245)
			(xy 331.521054 -241.952272)
		)
		(stroke
			(width 0)
			(type solid)
		)
		(fill yes)
		(layer "In11.Cu")
		(net "M_F_CPU0_SA_DQS_DN<3>")
	)
	(gr_poly
		(pts
			(xy 331.62113 -240.636044) (xy 331.521054 -240.535968) (xy 331.420978 -240.636044) (xy 331.420978 -240.680494)
			(xy 331.62113 -240.680494)
		)
		(stroke
			(width 0)
			(type solid)
		)
		(fill yes)
		(layer "In11.Cu")
		(net "M_F_CPU0_SA_DQ<25>")
	)
	(gr_poly
		(pts
			(xy 331.62113 -240.232184) (xy 331.62113 -240.187734) (xy 331.420978 -240.187734) (xy 331.420978 -240.232184)
			(xy 331.521054 -240.33226)
		)
		(stroke
			(width 0)
			(type solid)
		)
		(fill yes)
		(layer "In11.Cu")
		(net "M_F_CPU0_SA_DQ<26>")
	)
	(gr_poly
		(pts
			(xy 331.62113 -239.016032) (xy 331.521054 -238.915956) (xy 331.420978 -239.016032) (xy 331.420978 -239.060482)
			(xy 331.62113 -239.060482)
		)
		(stroke
			(width 0)
			(type solid)
		)
		(fill yes)
		(layer "In11.Cu")
		(net "M_F_CPU0_SA_DQ<21>")
	)
	(gr_poly
		(pts
			(xy 331.62113 -238.612172) (xy 331.62113 -238.567722) (xy 331.420978 -238.567722) (xy 331.420978 -238.612172)
			(xy 331.521054 -238.712248)
		)
		(stroke
			(width 0)
			(type solid)
		)
		(fill yes)
		(layer "In11.Cu")
		(net "M_F_CPU0_SA_DQ<22>")
	)
	(gr_poly
		(pts
			(xy 331.62113 -237.395766) (xy 331.521054 -237.295944) (xy 331.420978 -237.395766) (xy 331.420978 -237.443518)
			(xy 331.62113 -237.443518)
		)
		(stroke
			(width 0)
			(type solid)
		)
		(fill yes)
		(layer "In11.Cu")
		(net "M_F_CPU0_SA_DQS_DN<7>")
	)
	(gr_poly
		(pts
			(xy 331.62113 -236.992414) (xy 331.62113 -236.944662) (xy 331.420978 -236.944662) (xy 331.420978 -236.992414)
			(xy 331.521054 -237.092236)
		)
		(stroke
			(width 0)
			(type solid)
		)
		(fill yes)
		(layer "In11.Cu")
		(net "M_F_CPU0_SA_DQS_DN<2>")
	)
	(gr_poly
		(pts
			(xy 331.62113 -235.776008) (xy 331.521054 -235.675932) (xy 331.420978 -235.776008) (xy 331.420978 -235.820458)
			(xy 331.62113 -235.820458)
		)
		(stroke
			(width 0)
			(type solid)
		)
		(fill yes)
		(layer "In11.Cu")
		(net "M_F_CPU0_SA_DQ<17>")
	)
	(gr_poly
		(pts
			(xy 331.62113 -235.372148) (xy 331.62113 -235.327698) (xy 331.420978 -235.327698) (xy 331.420978 -235.372148)
			(xy 331.521054 -235.472224)
		)
		(stroke
			(width 0)
			(type solid)
		)
		(fill yes)
		(layer "In11.Cu")
		(net "M_F_CPU0_SA_DQ<18>")
	)
	(gr_poly
		(pts
			(xy 331.62113 -234.155996) (xy 331.521054 -234.05592) (xy 331.420978 -234.155996) (xy 331.420978 -234.200446)
			(xy 331.62113 -234.200446)
		)
		(stroke
			(width 0)
			(type solid)
		)
		(fill yes)
		(layer "In11.Cu")
		(net "M_F_CPU0_SA_DQ<13>")
	)
	(gr_poly
		(pts
			(xy 331.62113 -233.752136) (xy 331.62113 -233.707686) (xy 331.420978 -233.707686) (xy 331.420978 -233.752136)
			(xy 331.521054 -233.852212)
		)
		(stroke
			(width 0)
			(type solid)
		)
		(fill yes)
		(layer "In11.Cu")
		(net "M_F_CPU0_SA_DQ<14>")
	)
	(gr_poly
		(pts
			(xy 331.62113 -232.53573) (xy 331.521054 -232.435908) (xy 331.420978 -232.53573) (xy 331.420978 -232.583482)
			(xy 331.62113 -232.583482)
		)
		(stroke
			(width 0)
			(type solid)
		)
		(fill yes)
		(layer "In11.Cu")
		(net "M_F_CPU0_SA_DQS_DN<6>")
	)
	(gr_poly
		(pts
			(xy 331.62113 -232.132378) (xy 331.62113 -232.084626) (xy 331.420978 -232.084626) (xy 331.420978 -232.132378)
			(xy 331.521054 -232.2322)
		)
		(stroke
			(width 0)
			(type solid)
		)
		(fill yes)
		(layer "In11.Cu")
		(net "M_F_CPU0_SA_DQS_DN<1>")
	)
	(gr_poly
		(pts
			(xy 331.62113 -230.512366) (xy 331.62113 -230.467916) (xy 331.420978 -230.467916) (xy 331.420978 -230.512366)
			(xy 331.521054 -230.612188)
		)
		(stroke
			(width 0)
			(type solid)
		)
		(fill yes)
		(layer "In11.Cu")
		(net "M_F_CPU0_SA_DQ<10>")
	)
	(gr_poly
		(pts
			(xy 331.62113 -229.29596) (xy 331.521054 -229.195884) (xy 331.420978 -229.29596) (xy 331.420978 -229.34041)
			(xy 331.62113 -229.34041)
		)
		(stroke
			(width 0)
			(type solid)
		)
		(fill yes)
		(layer "In11.Cu")
		(net "M_F_CPU0_SA_DQ<5>")
	)
	(gr_poly
		(pts
			(xy 331.62113 -228.892354) (xy 331.62113 -228.847904) (xy 331.420978 -228.847904) (xy 331.420978 -228.892354)
			(xy 331.521054 -228.99243)
		)
		(stroke
			(width 0)
			(type solid)
		)
		(fill yes)
		(layer "In11.Cu")
		(net "M_F_CPU0_SA_DQ<6>")
	)
	(gr_poly
		(pts
			(xy 331.62113 -227.675948) (xy 331.521054 -227.576126) (xy 331.420978 -227.675948) (xy 331.420978 -227.7237)
			(xy 331.62113 -227.7237)
		)
		(stroke
			(width 0)
			(type solid)
		)
		(fill yes)
		(layer "In11.Cu")
		(net "M_F_CPU0_SA_DQS_DN<5>")
	)
	(gr_poly
		(pts
			(xy 331.62113 -227.272596) (xy 331.62113 -227.224844) (xy 331.420978 -227.224844) (xy 331.420978 -227.272596)
			(xy 331.521054 -227.372418)
		)
		(stroke
			(width 0)
			(type solid)
		)
		(fill yes)
		(layer "In11.Cu")
		(net "M_F_CPU0_SA_DQS_DN<0>")
	)
	(gr_poly
		(pts
			(xy 331.62113 -226.05619) (xy 331.521054 -225.956114) (xy 331.420978 -226.05619) (xy 331.420978 -226.10064)
			(xy 331.62113 -226.10064)
		)
		(stroke
			(width 0)
			(type solid)
		)
		(fill yes)
		(layer "In11.Cu")
		(net "M_F_CPU0_SA_DQ<1>")
	)
	(gr_poly
		(pts
			(xy 331.62113 -225.65233) (xy 331.62113 -225.60788) (xy 331.420978 -225.60788) (xy 331.420978 -225.65233)
			(xy 331.521054 -225.752406)
		)
		(stroke
			(width 0)
			(type solid)
		)
		(fill yes)
		(layer "In11.Cu")
		(net "M_F_CPU0_SA_DQ<2>")
	)
	(gr_poly
		(pts
			(xy 331.88148 -293.331392) (xy 331.88529 -293.287196) (xy 331.686154 -293.269924) (xy 331.68209 -293.31412)
			(xy 331.773022 -293.422324)
		)
		(stroke
			(width 0)
			(type solid)
		)
		(fill yes)
		(layer "In11.Cu")
		(net "M_F_CPU0_SB_DQ<31>")
	)
	(gr_poly
		(pts
			(xy 331.921104 -292.107874) (xy 331.821028 -292.007798) (xy 331.720952 -292.107874) (xy 331.720952 -292.152324)
			(xy 331.921104 -292.152324)
		)
		(stroke
			(width 0)
			(type solid)
		)
		(fill yes)
		(layer "In11.Cu")
		(net "M_F_CPU0_SB_DQ<28>")
	)
	(gr_poly
		(pts
			(xy 331.921104 -291.704268) (xy 331.921104 -291.656516) (xy 331.720952 -291.656516) (xy 331.720952 -291.704268)
			(xy 331.821028 -291.80409)
		)
		(stroke
			(width 0)
			(type solid)
		)
		(fill yes)
		(layer "In11.Cu")
		(net "M_F_CPU0_SB_DQS_DP<8>")
	)
	(gr_poly
		(pts
			(xy 331.921104 -290.487608) (xy 331.821028 -290.387786) (xy 331.720952 -290.487608) (xy 331.720952 -290.53536)
			(xy 331.921104 -290.53536)
		)
		(stroke
			(width 0)
			(type solid)
		)
		(fill yes)
		(layer "In11.Cu")
		(net "M_F_CPU0_SB_DQS_DP<3>")
	)
	(gr_poly
		(pts
			(xy 331.921104 -290.084002) (xy 331.921104 -290.039552) (xy 331.720952 -290.039552) (xy 331.720952 -290.084002)
			(xy 331.821028 -290.184078)
		)
		(stroke
			(width 0)
			(type solid)
		)
		(fill yes)
		(layer "In11.Cu")
		(net "M_F_CPU0_SB_DQ<27>")
	)
	(gr_poly
		(pts
			(xy 331.921104 -288.86785) (xy 331.821028 -288.767774) (xy 331.720952 -288.86785) (xy 331.720952 -288.9123)
			(xy 331.921104 -288.9123)
		)
		(stroke
			(width 0)
			(type solid)
		)
		(fill yes)
		(layer "In11.Cu")
		(net "M_F_CPU0_SB_DQ<24>")
	)
	(gr_poly
		(pts
			(xy 331.921104 -288.464244) (xy 331.921104 -288.419794) (xy 331.720952 -288.419794) (xy 331.720952 -288.464244)
			(xy 331.821028 -288.56432)
		)
		(stroke
			(width 0)
			(type solid)
		)
		(fill yes)
		(layer "In11.Cu")
		(net "M_F_CPU0_SB_DQ<23>")
	)
	(gr_poly
		(pts
			(xy 331.921104 -287.247838) (xy 331.821028 -287.148016) (xy 331.720952 -287.247838) (xy 331.720952 -287.292288)
			(xy 331.921104 -287.292288)
		)
		(stroke
			(width 0)
			(type solid)
		)
		(fill yes)
		(layer "In11.Cu")
		(net "M_F_CPU0_SB_DQ<20>")
	)
	(gr_poly
		(pts
			(xy 331.921104 -286.844232) (xy 331.921104 -286.79648) (xy 331.720952 -286.79648) (xy 331.720952 -286.844232)
			(xy 331.821028 -286.944308)
		)
		(stroke
			(width 0)
			(type solid)
		)
		(fill yes)
		(layer "In11.Cu")
		(net "M_F_CPU0_SB_DQS_DP<7>")
	)
	(gr_poly
		(pts
			(xy 331.921104 -285.627826) (xy 331.821028 -285.528004) (xy 331.720952 -285.627826) (xy 331.720952 -285.675578)
			(xy 331.921104 -285.675578)
		)
		(stroke
			(width 0)
			(type solid)
		)
		(fill yes)
		(layer "In11.Cu")
		(net "M_F_CPU0_SB_DQS_DP<2>")
	)
	(gr_poly
		(pts
			(xy 331.921104 -285.22422) (xy 331.921104 -285.17977) (xy 331.720952 -285.17977) (xy 331.720952 -285.22422)
			(xy 331.821028 -285.324296)
		)
		(stroke
			(width 0)
			(type solid)
		)
		(fill yes)
		(layer "In11.Cu")
		(net "M_F_CPU0_SB_DQ<19>")
	)
	(gr_poly
		(pts
			(xy 331.921104 -284.008068) (xy 331.821028 -283.907992) (xy 331.720952 -284.008068) (xy 331.720952 -284.052518)
			(xy 331.921104 -284.052518)
		)
		(stroke
			(width 0)
			(type solid)
		)
		(fill yes)
		(layer "In11.Cu")
		(net "M_F_CPU0_SB_DQ<16>")
	)
	(gr_poly
		(pts
			(xy 331.921104 -283.604208) (xy 331.921104 -283.559758) (xy 331.720952 -283.559758) (xy 331.720952 -283.604208)
			(xy 331.821028 -283.704284)
		)
		(stroke
			(width 0)
			(type solid)
		)
		(fill yes)
		(layer "In11.Cu")
		(net "M_F_CPU0_SB_DQ<15>")
	)
	(gr_poly
		(pts
			(xy 331.921104 -282.388056) (xy 331.821028 -282.28798) (xy 331.720952 -282.388056) (xy 331.720952 -282.432506)
			(xy 331.921104 -282.432506)
		)
		(stroke
			(width 0)
			(type solid)
		)
		(fill yes)
		(layer "In11.Cu")
		(net "M_F_CPU0_SB_DQ<12>")
	)
	(gr_poly
		(pts
			(xy 331.921104 -281.98445) (xy 331.921104 -281.936698) (xy 331.720952 -281.936698) (xy 331.720952 -281.98445)
			(xy 331.821028 -282.084272)
		)
		(stroke
			(width 0)
			(type solid)
		)
		(fill yes)
		(layer "In11.Cu")
		(net "M_F_CPU0_SB_DQS_DP<6>")
	)
	(gr_poly
		(pts
			(xy 331.921104 -280.76779) (xy 331.821028 -280.667968) (xy 331.720952 -280.76779) (xy 331.720952 -280.815542)
			(xy 331.921104 -280.815542)
		)
		(stroke
			(width 0)
			(type solid)
		)
		(fill yes)
		(layer "In11.Cu")
		(net "M_F_CPU0_SB_DQS_DP<1>")
	)
	(gr_poly
		(pts
			(xy 331.921104 -280.364184) (xy 331.921104 -280.319734) (xy 331.720952 -280.319734) (xy 331.720952 -280.364184)
			(xy 331.821028 -280.46426)
		)
		(stroke
			(width 0)
			(type solid)
		)
		(fill yes)
		(layer "In11.Cu")
		(net "M_F_CPU0_SB_DQ<11>")
	)
	(gr_poly
		(pts
			(xy 331.921104 -279.148032) (xy 331.821028 -279.047956) (xy 331.720952 -279.148032) (xy 331.720952 -279.192482)
			(xy 331.921104 -279.192482)
		)
		(stroke
			(width 0)
			(type solid)
		)
		(fill yes)
		(layer "In11.Cu")
		(net "M_F_CPU0_SB_DQ<8>")
	)
	(gr_poly
		(pts
			(xy 331.921104 -278.744172) (xy 331.921104 -278.699722) (xy 331.720952 -278.699722) (xy 331.720952 -278.744172)
			(xy 331.821028 -278.844248)
		)
		(stroke
			(width 0)
			(type solid)
		)
		(fill yes)
		(layer "In11.Cu")
		(net "M_F_CPU0_SB_DQ<7>")
	)
	(gr_poly
		(pts
			(xy 331.921104 -277.52802) (xy 331.821028 -277.427944) (xy 331.720952 -277.52802) (xy 331.720952 -277.57247)
			(xy 331.921104 -277.57247)
		)
		(stroke
			(width 0)
			(type solid)
		)
		(fill yes)
		(layer "In11.Cu")
		(net "M_F_CPU0_SB_DQ<4>")
	)
	(gr_poly
		(pts
			(xy 331.921104 -277.124414) (xy 331.921104 -277.076662) (xy 331.720952 -277.076662) (xy 331.720952 -277.124414)
			(xy 331.821028 -277.224236)
		)
		(stroke
			(width 0)
			(type solid)
		)
		(fill yes)
		(layer "In11.Cu")
		(net "M_F_CPU0_SB_DQS_DP<5>")
	)
	(gr_poly
		(pts
			(xy 331.921104 -275.907754) (xy 331.821028 -275.807932) (xy 331.720952 -275.907754) (xy 331.720952 -275.955506)
			(xy 331.921104 -275.955506)
		)
		(stroke
			(width 0)
			(type solid)
		)
		(fill yes)
		(layer "In11.Cu")
		(net "M_F_CPU0_SB_DQS_DP<0>")
	)
	(gr_poly
		(pts
			(xy 331.921104 -275.504148) (xy 331.921104 -275.459698) (xy 331.720952 -275.459698) (xy 331.720952 -275.504148)
			(xy 331.821028 -275.604224)
		)
		(stroke
			(width 0)
			(type solid)
		)
		(fill yes)
		(layer "In11.Cu")
		(net "M_F_CPU0_SB_DQ<3>")
	)
	(gr_poly
		(pts
			(xy 331.921104 -274.287996) (xy 331.821028 -274.18792) (xy 331.720952 -274.287996) (xy 331.720952 -274.332446)
			(xy 331.921104 -274.332446)
		)
		(stroke
			(width 0)
			(type solid)
		)
		(fill yes)
		(layer "In11.Cu")
		(net "M_F_CPU0_SB_DQ<0>")
	)
	(gr_poly
		(pts
			(xy 331.921104 -273.884136) (xy 331.921104 -273.839686) (xy 331.720952 -273.839686) (xy 331.720952 -273.884136)
			(xy 331.821028 -273.984212)
		)
		(stroke
			(width 0)
			(type solid)
		)
		(fill yes)
		(layer "In11.Cu")
		(net "M_F_CPU0_SB_CB<3>")
	)
	(gr_poly
		(pts
			(xy 331.921104 -272.667984) (xy 331.821028 -272.567908) (xy 331.720952 -272.667984) (xy 331.720952 -272.712434)
			(xy 331.921104 -272.712434)
		)
		(stroke
			(width 0)
			(type solid)
		)
		(fill yes)
		(layer "In11.Cu")
		(net "M_F_CPU0_SB_CB<0>")
	)
	(gr_poly
		(pts
			(xy 331.921104 -272.264378) (xy 331.921104 -272.216626) (xy 331.720952 -272.216626) (xy 331.720952 -272.264378)
			(xy 331.821028 -272.3642)
		)
		(stroke
			(width 0)
			(type solid)
		)
		(fill yes)
		(layer "In11.Cu")
		(net "M_F_CPU0_SB_DQS_DP<4>")
	)
	(gr_poly
		(pts
			(xy 331.921104 -271.047718) (xy 331.821028 -270.947896) (xy 331.720952 -271.047718) (xy 331.720952 -271.09547)
			(xy 331.921104 -271.09547)
		)
		(stroke
			(width 0)
			(type solid)
		)
		(fill yes)
		(layer "In11.Cu")
		(net "M_F_CPU0_SB_DQS_DP<9>")
	)
	(gr_poly
		(pts
			(xy 331.921104 -270.644112) (xy 331.921104 -270.599662) (xy 331.720952 -270.599662) (xy 331.720952 -270.644112)
			(xy 331.821028 -270.744188)
		)
		(stroke
			(width 0)
			(type solid)
		)
		(fill yes)
		(layer "In11.Cu")
		(net "M_F_CPU0_SB_CB<7>")
	)
	(gr_poly
		(pts
			(xy 331.921104 -269.42796) (xy 331.821028 -269.327884) (xy 331.720952 -269.42796) (xy 331.720952 -269.47241)
			(xy 331.921104 -269.47241)
		)
		(stroke
			(width 0)
			(type solid)
		)
		(fill yes)
		(layer "In11.Cu")
		(net "M_F_CPU0_SB_CB<4>")
	)
	(gr_poly
		(pts
			(xy 331.921104 -265.784076) (xy 331.921104 -265.739626) (xy 331.720952 -265.739626) (xy 331.720952 -265.784076)
			(xy 331.821028 -265.884152)
		)
		(stroke
			(width 0)
			(type solid)
		)
		(fill yes)
		(layer "In11.Cu")
		(net "M_F_CPU0_SB_CS_N<0>")
	)
	(gr_poly
		(pts
			(xy 331.921104 -264.567924) (xy 331.821028 -264.467848) (xy 331.720952 -264.567924) (xy 331.720952 -264.612374)
			(xy 331.921104 -264.612374)
		)
		(stroke
			(width 0)
			(type solid)
		)
		(fill yes)
		(layer "In11.Cu")
		(net "M_F_CPU0_SB_CA<6>")
	)
	(gr_poly
		(pts
			(xy 331.921104 -264.164064) (xy 331.921104 -264.119614) (xy 331.720952 -264.119614) (xy 331.720952 -264.164064)
			(xy 331.821028 -264.26414)
		)
		(stroke
			(width 0)
			(type solid)
		)
		(fill yes)
		(layer "In11.Cu")
		(net "M_F_CPU0_SB_CA<5>")
	)
	(gr_poly
		(pts
			(xy 331.921104 -262.947912) (xy 331.821028 -262.847836) (xy 331.720952 -262.947912) (xy 331.720952 -262.992362)
			(xy 331.921104 -262.992362)
		)
		(stroke
			(width 0)
			(type solid)
		)
		(fill yes)
		(layer "In11.Cu")
		(net "M_F_CPU0_SB_CA<2>")
	)
	(gr_poly
		(pts
			(xy 331.921104 -262.544052) (xy 331.921104 -262.499602) (xy 331.720952 -262.499602) (xy 331.720952 -262.544052)
			(xy 331.821028 -262.644128)
		)
		(stroke
			(width 0)
			(type solid)
		)
		(fill yes)
		(layer "In11.Cu")
		(net "M_F_CPU0_SB_CA<1>")
	)
	(gr_poly
		(pts
			(xy 331.921358 -267.807948) (xy 331.821282 -267.707872) (xy 331.721206 -267.807948) (xy 331.721206 -267.852398)
			(xy 331.921358 -267.852398)
		)
		(stroke
			(width 0)
			(type solid)
		)
		(fill yes)
		(layer "In11.Cu")
		(net "M_F_CPU0_SB_RSP<0>")
	)
	(gr_poly
		(pts
			(xy 332.043024 -246.346726) (xy 332.038706 -246.299228) (xy 331.930502 -246.20855) (xy 331.83957 -246.316754)
			(xy 331.843634 -246.364252)
		)
		(stroke
			(width 0)
			(type solid)
		)
		(fill yes)
		(layer "In11.Cu")
		(net "M_F_CPU0_SA_DQS_DP<4>")
	)
	(gr_poly
		(pts
			(xy 332.043024 -241.48669) (xy 332.038706 -241.439192) (xy 331.930502 -241.348514) (xy 331.83957 -241.456718)
			(xy 331.843634 -241.504216)
		)
		(stroke
			(width 0)
			(type solid)
		)
		(fill yes)
		(layer "In11.Cu")
		(net "M_F_CPU0_SA_DQS_DP<3>")
	)
	(gr_poly
		(pts
			(xy 332.043024 -236.626654) (xy 332.038706 -236.579156) (xy 331.930502 -236.488478) (xy 331.83957 -236.596682)
			(xy 331.843634 -236.64418)
		)
		(stroke
			(width 0)
			(type solid)
		)
		(fill yes)
		(layer "In11.Cu")
		(net "M_F_CPU0_SA_DQS_DP<2>")
	)
	(gr_poly
		(pts
			(xy 332.043024 -231.766618) (xy 332.038706 -231.71912) (xy 331.930502 -231.628442) (xy 331.83957 -231.736646)
			(xy 331.843634 -231.784144)
		)
		(stroke
			(width 0)
			(type solid)
		)
		(fill yes)
		(layer "In11.Cu")
		(net "M_F_CPU0_SA_DQS_DP<1>")
	)
	(gr_poly
		(pts
			(xy 332.043024 -226.906836) (xy 332.038706 -226.859338) (xy 331.930502 -226.76866) (xy 331.83957 -226.876864)
			(xy 331.843634 -226.924362)
		)
		(stroke
			(width 0)
			(type solid)
		)
		(fill yes)
		(layer "In11.Cu")
		(net "M_F_CPU0_SA_DQS_DP<0>")
	)
	(gr_poly
		(pts
			(xy 332.053946 -256.066036) (xy 332.049628 -256.018538) (xy 331.941424 -255.927606) (xy 331.850492 -256.036064)
			(xy 331.854556 -256.083308)
		)
		(stroke
			(width 0)
			(type solid)
		)
		(fill yes)
		(layer "In11.Cu")
		(net "M_F_CPU0_CLK_DP<0>")
	)
	(gr_poly
		(pts
			(xy 332.05547 -254.442976) (xy 332.05166 -254.398526) (xy 331.943456 -254.307594) (xy 331.852524 -254.416052)
			(xy 331.856334 -254.460248)
		)
		(stroke
			(width 0)
			(type solid)
		)
		(fill yes)
		(layer "In11.Cu")
		(net "M_F_CPU0_SA_CA<4>")
	)
	(gr_poly
		(pts
			(xy 332.05547 -252.822964) (xy 332.05166 -252.778514) (xy 331.943456 -252.687582) (xy 331.852524 -252.79604)
			(xy 331.856334 -252.840236)
		)
		(stroke
			(width 0)
			(type solid)
		)
		(fill yes)
		(layer "In11.Cu")
		(net "M_F_CPU0_SA_CA<0>")
	)
	(gr_poly
		(pts
			(xy 332.05547 -247.962928) (xy 332.05166 -247.918478) (xy 331.943456 -247.827546) (xy 331.852524 -247.936004)
			(xy 331.856334 -247.9802)
		)
		(stroke
			(width 0)
			(type solid)
		)
		(fill yes)
		(layer "In11.Cu")
		(net "M_F_CPU0_SA_CB<4>")
	)
	(gr_poly
		(pts
			(xy 332.05547 -244.722904) (xy 332.05166 -244.678454) (xy 331.943456 -244.587522) (xy 331.852524 -244.69598)
			(xy 331.856334 -244.740176)
		)
		(stroke
			(width 0)
			(type solid)
		)
		(fill yes)
		(layer "In11.Cu")
		(net "M_F_CPU0_SA_CB<0>")
	)
	(gr_poly
		(pts
			(xy 332.05547 -243.102892) (xy 332.05166 -243.058442) (xy 331.943456 -242.96751) (xy 331.852524 -243.075968)
			(xy 331.856334 -243.120164)
		)
		(stroke
			(width 0)
			(type solid)
		)
		(fill yes)
		(layer "In11.Cu")
		(net "M_F_CPU0_SA_DQ<28>")
	)
	(gr_poly
		(pts
			(xy 332.05547 -239.862868) (xy 332.05166 -239.818418) (xy 331.943456 -239.727486) (xy 331.852524 -239.835944)
			(xy 331.856334 -239.88014)
		)
		(stroke
			(width 0)
			(type solid)
		)
		(fill yes)
		(layer "In11.Cu")
		(net "M_F_CPU0_SA_DQ<24>")
	)
	(gr_poly
		(pts
			(xy 332.05547 -238.242856) (xy 332.05166 -238.198406) (xy 331.943456 -238.107474) (xy 331.852524 -238.215932)
			(xy 331.856334 -238.260128)
		)
		(stroke
			(width 0)
			(type solid)
		)
		(fill yes)
		(layer "In11.Cu")
		(net "M_F_CPU0_SA_DQ<20>")
	)
	(gr_poly
		(pts
			(xy 332.05547 -235.002832) (xy 332.05166 -234.958382) (xy 331.943456 -234.86745) (xy 331.852524 -234.975908)
			(xy 331.856334 -235.020104)
		)
		(stroke
			(width 0)
			(type solid)
		)
		(fill yes)
		(layer "In11.Cu")
		(net "M_F_CPU0_SA_DQ<16>")
	)
	(gr_poly
		(pts
			(xy 332.05547 -233.38282) (xy 332.05166 -233.33837) (xy 331.943456 -233.247438) (xy 331.852524 -233.355896)
			(xy 331.856334 -233.400092)
		)
		(stroke
			(width 0)
			(type solid)
		)
		(fill yes)
		(layer "In11.Cu")
		(net "M_F_CPU0_SA_DQ<12>")
	)
	(gr_poly
		(pts
			(xy 332.05547 -230.142796) (xy 332.05166 -230.098346) (xy 331.943456 -230.007668) (xy 331.852524 -230.115872)
			(xy 331.856334 -230.160068)
		)
		(stroke
			(width 0)
			(type solid)
		)
		(fill yes)
		(layer "In11.Cu")
		(net "M_F_CPU0_SA_DQ<8>")
	)
	(gr_poly
		(pts
			(xy 332.05547 -228.523038) (xy 332.05166 -228.478588) (xy 331.943456 -228.387656) (xy 331.852524 -228.496114)
			(xy 331.856334 -228.54031)
		)
		(stroke
			(width 0)
			(type solid)
		)
		(fill yes)
		(layer "In11.Cu")
		(net "M_F_CPU0_SA_DQ<4>")
	)
	(gr_poly
		(pts
			(xy 332.05547 -225.283014) (xy 332.05166 -225.238564) (xy 331.943456 -225.147632) (xy 331.852524 -225.25609)
			(xy 331.856334 -225.300286)
		)
		(stroke
			(width 0)
			(type solid)
		)
		(fill yes)
		(layer "In11.Cu")
		(net "M_F_CPU0_SA_DQ<0>")
	)
	(gr_poly
		(pts
			(xy 332.090014 -231.322372) (xy 332.090014 -231.277922) (xy 331.892402 -231.277922) (xy 331.892402 -231.322372)
			(xy 331.991208 -231.422448)
		)
		(stroke
			(width 0)
			(type solid)
		)
		(fill yes)
		(layer "In11.Cu")
		(net "M_F_CPU0_SA_DQ<11>")
	)
	(gr_poly
		(pts
			(xy 332.091284 -255.622298) (xy 332.091284 -255.577848) (xy 331.891132 -255.577848) (xy 331.891132 -255.622298)
			(xy 331.991208 -255.722374)
		)
		(stroke
			(width 0)
			(type solid)
		)
		(fill yes)
		(layer "In11.Cu")
		(net "M_F_CPU0_SA_PAR")
	)
	(gr_poly
		(pts
			(xy 332.091284 -254.002286) (xy 332.091284 -253.957836) (xy 331.891132 -253.957836) (xy 331.891132 -254.002286)
			(xy 331.991208 -254.102362)
		)
		(stroke
			(width 0)
			(type solid)
		)
		(fill yes)
		(layer "In11.Cu")
		(net "M_F_CPU0_SA_CA<3>")
	)
	(gr_poly
		(pts
			(xy 332.091284 -252.382274) (xy 332.091284 -252.337824) (xy 331.891132 -252.337824) (xy 331.891132 -252.382274)
			(xy 331.991208 -252.48235)
		)
		(stroke
			(width 0)
			(type solid)
		)
		(fill yes)
		(layer "In11.Cu")
		(net "M_F_CPU0_SA_CS_N<1>")
	)
	(gr_poly
		(pts
			(xy 332.091284 -250.762262) (xy 332.091284 -250.717812) (xy 331.891132 -250.717812) (xy 331.891132 -250.762262)
			(xy 331.991208 -250.862338)
		)
		(stroke
			(width 0)
			(type solid)
		)
		(fill yes)
		(layer "In11.Cu")
		(net "M_F_CPU0_RESET_N")
	)
	(gr_poly
		(pts
			(xy 332.091284 -249.14225) (xy 332.091284 -249.0978) (xy 331.891132 -249.0978) (xy 331.891132 -249.14225)
			(xy 331.991208 -249.242326)
		)
		(stroke
			(width 0)
			(type solid)
		)
		(fill yes)
		(layer "In11.Cu")
		(net "M_F_CPU0_SA_CB<7>")
	)
	(gr_poly
		(pts
			(xy 332.091284 -247.522492) (xy 332.091284 -247.47474) (xy 331.891132 -247.47474) (xy 331.891132 -247.522492)
			(xy 331.991208 -247.622314)
		)
		(stroke
			(width 0)
			(type solid)
		)
		(fill yes)
		(layer "In11.Cu")
		(net "M_F_CPU0_SA_DQS_DP<9>")
	)
	(gr_poly
		(pts
			(xy 332.091284 -245.902226) (xy 332.091284 -245.857776) (xy 331.891132 -245.857776) (xy 331.891132 -245.902226)
			(xy 331.991208 -246.002302)
		)
		(stroke
			(width 0)
			(type solid)
		)
		(fill yes)
		(layer "In11.Cu")
		(net "M_F_CPU0_SA_CB<3>")
	)
	(gr_poly
		(pts
			(xy 332.091284 -244.282214) (xy 332.091284 -244.237764) (xy 331.891132 -244.237764) (xy 331.891132 -244.282214)
			(xy 331.991208 -244.38229)
		)
		(stroke
			(width 0)
			(type solid)
		)
		(fill yes)
		(layer "In11.Cu")
		(net "M_F_CPU0_SA_DQ<31>")
	)
	(gr_poly
		(pts
			(xy 332.091284 -242.662456) (xy 332.091284 -242.614704) (xy 331.891132 -242.614704) (xy 331.891132 -242.662456)
			(xy 331.991208 -242.762278)
		)
		(stroke
			(width 0)
			(type solid)
		)
		(fill yes)
		(layer "In11.Cu")
		(net "M_F_CPU0_SA_DQS_DP<8>")
	)
	(gr_poly
		(pts
			(xy 332.091284 -241.04219) (xy 332.091284 -240.99774) (xy 331.891132 -240.99774) (xy 331.891132 -241.04219)
			(xy 331.991208 -241.142266)
		)
		(stroke
			(width 0)
			(type solid)
		)
		(fill yes)
		(layer "In11.Cu")
		(net "M_F_CPU0_SA_DQ<27>")
	)
	(gr_poly
		(pts
			(xy 332.091284 -239.422178) (xy 332.091284 -239.377728) (xy 331.891132 -239.377728) (xy 331.891132 -239.422178)
			(xy 331.991208 -239.522254)
		)
		(stroke
			(width 0)
			(type solid)
		)
		(fill yes)
		(layer "In11.Cu")
		(net "M_F_CPU0_SA_DQ<23>")
	)
	(gr_poly
		(pts
			(xy 332.091284 -237.80242) (xy 332.091284 -237.754668) (xy 331.891132 -237.754668) (xy 331.891132 -237.80242)
			(xy 331.991208 -237.902242)
		)
		(stroke
			(width 0)
			(type solid)
		)
		(fill yes)
		(layer "In11.Cu")
		(net "M_F_CPU0_SA_DQS_DP<7>")
	)
	(gr_poly
		(pts
			(xy 332.091284 -236.182154) (xy 332.091284 -236.137704) (xy 331.891132 -236.137704) (xy 331.891132 -236.182154)
			(xy 331.991208 -236.28223)
		)
		(stroke
			(width 0)
			(type solid)
		)
		(fill yes)
		(layer "In11.Cu")
		(net "M_F_CPU0_SA_DQ<19>")
	)
	(gr_poly
		(pts
			(xy 332.091284 -234.562142) (xy 332.091284 -234.517692) (xy 331.891132 -234.517692) (xy 331.891132 -234.562142)
			(xy 331.991208 -234.662218)
		)
		(stroke
			(width 0)
			(type solid)
		)
		(fill yes)
		(layer "In11.Cu")
		(net "M_F_CPU0_SA_DQ<15>")
	)
	(gr_poly
		(pts
			(xy 332.091284 -232.942384) (xy 332.091284 -232.894632) (xy 331.891132 -232.894632) (xy 331.891132 -232.942384)
			(xy 331.991208 -233.042206)
		)
		(stroke
			(width 0)
			(type solid)
		)
		(fill yes)
		(layer "In11.Cu")
		(net "M_F_CPU0_SA_DQS_DP<6>")
	)
	(gr_poly
		(pts
			(xy 332.091284 -229.70236) (xy 332.091284 -229.65791) (xy 331.891132 -229.65791) (xy 331.891132 -229.70236)
			(xy 331.991208 -229.802436)
		)
		(stroke
			(width 0)
			(type solid)
		)
		(fill yes)
		(layer "In11.Cu")
		(net "M_F_CPU0_SA_DQ<7>")
	)
	(gr_poly
		(pts
			(xy 332.091284 -228.082602) (xy 332.091284 -228.03485) (xy 331.891132 -228.03485) (xy 331.891132 -228.082602)
			(xy 331.991208 -228.182424)
		)
		(stroke
			(width 0)
			(type solid)
		)
		(fill yes)
		(layer "In11.Cu")
		(net "M_F_CPU0_SA_DQS_DP<5>")
	)
	(gr_poly
		(pts
			(xy 332.091284 -226.462336) (xy 332.091284 -226.417886) (xy 331.891132 -226.417886) (xy 331.891132 -226.462336)
			(xy 331.991208 -226.562412)
		)
		(stroke
			(width 0)
			(type solid)
		)
		(fill yes)
		(layer "In11.Cu")
		(net "M_F_CPU0_SA_DQ<3>")
	)
	(gr_poly
		(pts
			(xy 332.33868 -290.900612) (xy 332.342998 -290.853368) (xy 332.143608 -290.835842) (xy 332.139544 -290.88334)
			(xy 332.230476 -290.991544)
		)
		(stroke
			(width 0)
			(type solid)
		)
		(fill yes)
		(layer "In11.Cu")
		(net "M_F_CPU0_SB_DQS_DN<3>")
	)
	(gr_poly
		(pts
			(xy 332.33868 -286.041084) (xy 332.342998 -285.993586) (xy 332.143608 -285.97606) (xy 332.139544 -286.023558)
			(xy 332.230476 -286.131762)
		)
		(stroke
			(width 0)
			(type solid)
		)
		(fill yes)
		(layer "In11.Cu")
		(net "M_F_CPU0_SB_DQS_DN<2>")
	)
	(gr_poly
		(pts
			(xy 332.33868 -276.321012) (xy 332.342998 -276.273514) (xy 332.143608 -276.255988) (xy 332.139544 -276.303486)
			(xy 332.230476 -276.41169)
		)
		(stroke
			(width 0)
			(type solid)
		)
		(fill yes)
		(layer "In11.Cu")
		(net "M_F_CPU0_SB_DQS_DN<0>")
	)
	(gr_poly
		(pts
			(xy 332.33868 -271.460976) (xy 332.342998 -271.413478) (xy 332.143608 -271.395952) (xy 332.139544 -271.44345)
			(xy 332.230476 -271.551654)
		)
		(stroke
			(width 0)
			(type solid)
		)
		(fill yes)
		(layer "In11.Cu")
		(net "M_F_CPU0_SB_DQS_DN<9>")
	)
	(gr_poly
		(pts
			(xy 332.351634 -292.52164) (xy 332.355698 -292.47719) (xy 332.156308 -292.459918) (xy 332.152498 -292.504114)
			(xy 332.24343 -292.612572)
		)
		(stroke
			(width 0)
			(type solid)
		)
		(fill yes)
		(layer "In11.Cu")
		(net "M_F_CPU0_SB_DQ<30>")
	)
	(gr_poly
		(pts
			(xy 332.351634 -289.281616) (xy 332.355698 -289.237166) (xy 332.156308 -289.219894) (xy 332.152498 -289.26409)
			(xy 332.24343 -289.372548)
		)
		(stroke
			(width 0)
			(type solid)
		)
		(fill yes)
		(layer "In11.Cu")
		(net "M_F_CPU0_SB_DQ<26>")
	)
	(gr_poly
		(pts
			(xy 332.351634 -287.661858) (xy 332.355698 -287.617408) (xy 332.156308 -287.600136) (xy 332.152498 -287.644332)
			(xy 332.24343 -287.752536)
		)
		(stroke
			(width 0)
			(type solid)
		)
		(fill yes)
		(layer "In11.Cu")
		(net "M_F_CPU0_SB_DQ<22>")
	)
	(gr_poly
		(pts
			(xy 332.351634 -284.421834) (xy 332.355698 -284.377384) (xy 332.156308 -284.360112) (xy 332.152498 -284.404308)
			(xy 332.24343 -284.512766)
		)
		(stroke
			(width 0)
			(type solid)
		)
		(fill yes)
		(layer "In11.Cu")
		(net "M_F_CPU0_SB_DQ<18>")
	)
	(gr_poly
		(pts
			(xy 332.351634 -282.801822) (xy 332.355698 -282.757372) (xy 332.156308 -282.7401) (xy 332.152498 -282.784296)
			(xy 332.24343 -282.892754)
		)
		(stroke
			(width 0)
			(type solid)
		)
		(fill yes)
		(layer "In11.Cu")
		(net "M_F_CPU0_SB_DQ<14>")
	)
	(gr_poly
		(pts
			(xy 332.351634 -279.561798) (xy 332.355698 -279.517348) (xy 332.156308 -279.500076) (xy 332.152498 -279.544272)
			(xy 332.24343 -279.65273)
		)
		(stroke
			(width 0)
			(type solid)
		)
		(fill yes)
		(layer "In11.Cu")
		(net "M_F_CPU0_SB_DQ<10>")
	)
	(gr_poly
		(pts
			(xy 332.351634 -277.941786) (xy 332.355698 -277.897336) (xy 332.156308 -277.880064) (xy 332.152498 -277.92426)
			(xy 332.24343 -278.032718)
		)
		(stroke
			(width 0)
			(type solid)
		)
		(fill yes)
		(layer "In11.Cu")
		(net "M_F_CPU0_SB_DQ<6>")
	)
	(gr_poly
		(pts
			(xy 332.351634 -274.701762) (xy 332.355698 -274.657312) (xy 332.156308 -274.64004) (xy 332.152498 -274.684236)
			(xy 332.24343 -274.792694)
		)
		(stroke
			(width 0)
			(type solid)
		)
		(fill yes)
		(layer "In11.Cu")
		(net "M_F_CPU0_SB_DQ<2>")
	)
	(gr_poly
		(pts
			(xy 332.351634 -273.08175) (xy 332.355698 -273.0373) (xy 332.156308 -273.020028) (xy 332.152498 -273.064224)
			(xy 332.24343 -273.172682)
		)
		(stroke
			(width 0)
			(type solid)
		)
		(fill yes)
		(layer "In11.Cu")
		(net "M_F_CPU0_SB_CB<2>")
	)
	(gr_poly
		(pts
			(xy 332.351634 -269.841726) (xy 332.355698 -269.797276) (xy 332.156308 -269.780004) (xy 332.152498 -269.8242)
			(xy 332.24343 -269.932658)
		)
		(stroke
			(width 0)
			(type solid)
		)
		(fill yes)
		(layer "In11.Cu")
		(net "M_F_CPU0_SB_CB<6>")
	)
	(gr_poly
		(pts
			(xy 332.351634 -266.601702) (xy 332.355698 -266.557252) (xy 332.156308 -266.53998) (xy 332.152498 -266.584176)
			(xy 332.24343 -266.692634)
		)
		(stroke
			(width 0)
			(type solid)
		)
		(fill yes)
		(layer "In11.Cu")
		(net "M_F_CPU0_SB_CS_N<1>")
	)
	(gr_poly
		(pts
			(xy 332.351634 -264.98169) (xy 332.355698 -264.93724) (xy 332.156308 -264.919968) (xy 332.152498 -264.964164)
			(xy 332.24343 -265.072622)
		)
		(stroke
			(width 0)
			(type solid)
		)
		(fill yes)
		(layer "In11.Cu")
		(net "M_F_CPU0_SB_PAR")
	)
	(gr_poly
		(pts
			(xy 332.351634 -263.361678) (xy 332.355698 -263.317228) (xy 332.156308 -263.299956) (xy 332.152498 -263.344152)
			(xy 332.24343 -263.45261)
		)
		(stroke
			(width 0)
			(type solid)
		)
		(fill yes)
		(layer "In11.Cu")
		(net "M_F_CPU0_SB_CA<3>")
	)
	(gr_poly
		(pts
			(xy 332.391004 -292.91788) (xy 332.290928 -292.817804) (xy 332.190852 -292.91788) (xy 332.190852 -292.96233)
			(xy 332.391004 -292.96233)
		)
		(stroke
			(width 0)
			(type solid)
		)
		(fill yes)
		(layer "In11.Cu")
		(net "M_F_CPU0_SB_DQ<29>")
	)
	(gr_poly
		(pts
			(xy 332.391004 -281.174444) (xy 332.391004 -281.126692) (xy 332.190852 -281.126692) (xy 332.190852 -281.174444)
			(xy 332.290928 -281.274266)
		)
		(stroke
			(width 0)
			(type solid)
		)
		(fill yes)
		(layer "In11.Cu")
		(net "M_F_CPU0_SB_DQS_DN<1>")
	)
	(gr_poly
		(pts
			(xy 332.391258 -291.297614) (xy 332.291182 -291.197792) (xy 332.191106 -291.297614) (xy 332.191106 -291.345366)
			(xy 332.391258 -291.345366)
		)
		(stroke
			(width 0)
			(type solid)
		)
		(fill yes)
		(layer "In11.Cu")
		(net "M_F_CPU0_SB_DQS_DN<8>")
	)
	(gr_poly
		(pts
			(xy 332.391258 -289.677856) (xy 332.291182 -289.57778) (xy 332.191106 -289.677856) (xy 332.191106 -289.722306)
			(xy 332.391258 -289.722306)
		)
		(stroke
			(width 0)
			(type solid)
		)
		(fill yes)
		(layer "In11.Cu")
		(net "M_F_CPU0_SB_DQ<25>")
	)
	(gr_poly
		(pts
			(xy 332.391258 -288.057844) (xy 332.291182 -287.957768) (xy 332.191106 -288.057844) (xy 332.191106 -288.102294)
			(xy 332.391258 -288.102294)
		)
		(stroke
			(width 0)
			(type solid)
		)
		(fill yes)
		(layer "In11.Cu")
		(net "M_F_CPU0_SB_DQ<21>")
	)
	(gr_poly
		(pts
			(xy 332.391258 -286.437832) (xy 332.291182 -286.337756) (xy 332.191106 -286.437832) (xy 332.191106 -286.485584)
			(xy 332.391258 -286.485584)
		)
		(stroke
			(width 0)
			(type solid)
		)
		(fill yes)
		(layer "In11.Cu")
		(net "M_F_CPU0_SB_DQS_DN<7>")
	)
	(gr_poly
		(pts
			(xy 332.391258 -284.818074) (xy 332.291182 -284.717998) (xy 332.191106 -284.818074) (xy 332.191106 -284.862524)
			(xy 332.391258 -284.862524)
		)
		(stroke
			(width 0)
			(type solid)
		)
		(fill yes)
		(layer "In11.Cu")
		(net "M_F_CPU0_SB_DQ<17>")
	)
	(gr_poly
		(pts
			(xy 332.391258 -283.198062) (xy 332.291182 -283.097986) (xy 332.191106 -283.198062) (xy 332.191106 -283.242512)
			(xy 332.391258 -283.242512)
		)
		(stroke
			(width 0)
			(type solid)
		)
		(fill yes)
		(layer "In11.Cu")
		(net "M_F_CPU0_SB_DQ<13>")
	)
	(gr_poly
		(pts
			(xy 332.391258 -281.577796) (xy 332.291182 -281.477974) (xy 332.191106 -281.577796) (xy 332.191106 -281.625548)
			(xy 332.391258 -281.625548)
		)
		(stroke
			(width 0)
			(type solid)
		)
		(fill yes)
		(layer "In11.Cu")
		(net "M_F_CPU0_SB_DQS_DN<6>")
	)
	(gr_poly
		(pts
			(xy 332.391258 -279.958038) (xy 332.291182 -279.857962) (xy 332.191106 -279.958038) (xy 332.191106 -280.002488)
			(xy 332.391258 -280.002488)
		)
		(stroke
			(width 0)
			(type solid)
		)
		(fill yes)
		(layer "In11.Cu")
		(net "M_F_CPU0_SB_DQ<9>")
	)
	(gr_poly
		(pts
			(xy 332.391258 -278.338026) (xy 332.291182 -278.23795) (xy 332.191106 -278.338026) (xy 332.191106 -278.382476)
			(xy 332.391258 -278.382476)
		)
		(stroke
			(width 0)
			(type solid)
		)
		(fill yes)
		(layer "In11.Cu")
		(net "M_F_CPU0_SB_DQ<5>")
	)
	(gr_poly
		(pts
			(xy 332.391258 -276.71776) (xy 332.291182 -276.617938) (xy 332.191106 -276.71776) (xy 332.191106 -276.765512)
			(xy 332.391258 -276.765512)
		)
		(stroke
			(width 0)
			(type solid)
		)
		(fill yes)
		(layer "In11.Cu")
		(net "M_F_CPU0_SB_DQS_DN<5>")
	)
	(gr_poly
		(pts
			(xy 332.391258 -275.098002) (xy 332.291182 -274.997926) (xy 332.191106 -275.098002) (xy 332.191106 -275.142452)
			(xy 332.391258 -275.142452)
		)
		(stroke
			(width 0)
			(type solid)
		)
		(fill yes)
		(layer "In11.Cu")
		(net "M_F_CPU0_SB_DQ<1>")
	)
	(gr_poly
		(pts
			(xy 332.391258 -273.47799) (xy 332.291182 -273.377914) (xy 332.191106 -273.47799) (xy 332.191106 -273.52244)
			(xy 332.391258 -273.52244)
		)
		(stroke
			(width 0)
			(type solid)
		)
		(fill yes)
		(layer "In11.Cu")
		(net "M_F_CPU0_SB_CB<1>")
	)
	(gr_poly
		(pts
			(xy 332.391258 -271.857724) (xy 332.291182 -271.757902) (xy 332.191106 -271.857724) (xy 332.191106 -271.905476)
			(xy 332.391258 -271.905476)
		)
		(stroke
			(width 0)
			(type solid)
		)
		(fill yes)
		(layer "In11.Cu")
		(net "M_F_CPU0_SB_DQS_DN<4>")
	)
	(gr_poly
		(pts
			(xy 332.391258 -270.237966) (xy 332.291182 -270.13789) (xy 332.191106 -270.237966) (xy 332.191106 -270.282416)
			(xy 332.391258 -270.282416)
		)
		(stroke
			(width 0)
			(type solid)
		)
		(fill yes)
		(layer "In11.Cu")
		(net "M_F_CPU0_SB_CB<5>")
	)
	(gr_poly
		(pts
			(xy 332.391258 -266.997942) (xy 332.291182 -266.897866) (xy 332.191106 -266.997942) (xy 332.191106 -267.042392)
			(xy 332.391258 -267.042392)
		)
		(stroke
			(width 0)
			(type solid)
		)
		(fill yes)
		(layer "In11.Cu")
		(net "M_F_CPU0_SA_RSP<0>")
	)
	(gr_poly
		(pts
			(xy 332.391258 -263.757918) (xy 332.291182 -263.657842) (xy 332.191106 -263.757918) (xy 332.191106 -263.802368)
			(xy 332.391258 -263.802368)
		)
		(stroke
			(width 0)
			(type solid)
		)
		(fill yes)
		(layer "In11.Cu")
		(net "M_F_CPU0_SB_CA<4>")
	)
	(gr_poly
		(pts
			(xy 332.391258 -262.137906) (xy 332.291182 -262.03783) (xy 332.191106 -262.137906) (xy 332.191106 -262.182356)
			(xy 332.391258 -262.182356)
		)
		(stroke
			(width 0)
			(type solid)
		)
		(fill yes)
		(layer "In11.Cu")
		(net "M_F_CPU0_SB_CA<0>")
	)
	(gr_poly
		(pts
			(xy 332.559914 -230.915972) (xy 332.461108 -230.815896) (xy 332.362302 -230.915972) (xy 332.362302 -230.960422)
			(xy 332.559914 -230.960422)
		)
		(stroke
			(width 0)
			(type solid)
		)
		(fill yes)
		(layer "In11.Cu")
		(net "M_F_CPU0_SA_DQ<9>")
	)
	(gr_poly
		(pts
			(xy 332.561184 -255.216152) (xy 332.461108 -255.116076) (xy 332.361032 -255.216152) (xy 332.361032 -255.260602)
			(xy 332.561184 -255.260602)
		)
		(stroke
			(width 0)
			(type solid)
		)
		(fill yes)
		(layer "In11.Cu")
		(net "M_F_CPU0_SA_CA<6>")
	)
	(gr_poly
		(pts
			(xy 332.561184 -253.59614) (xy 332.461108 -253.496064) (xy 332.361032 -253.59614) (xy 332.361032 -253.64059)
			(xy 332.561184 -253.64059)
		)
		(stroke
			(width 0)
			(type solid)
		)
		(fill yes)
		(layer "In11.Cu")
		(net "M_F_CPU0_SA_CA<2>")
	)
	(gr_poly
		(pts
			(xy 332.561184 -250.356116) (xy 332.461108 -250.25604) (xy 332.361032 -250.356116) (xy 332.361032 -250.400566)
			(xy 332.561184 -250.400566)
		)
		(stroke
			(width 0)
			(type solid)
		)
		(fill yes)
		(layer "In11.Cu")
		(net "M_F_CPU0_ALERT_R_N")
	)
	(gr_poly
		(pts
			(xy 332.561184 -248.736104) (xy 332.461108 -248.636028) (xy 332.361032 -248.736104) (xy 332.361032 -248.780554)
			(xy 332.561184 -248.780554)
		)
		(stroke
			(width 0)
			(type solid)
		)
		(fill yes)
		(layer "In11.Cu")
		(net "M_F_CPU0_SA_CB<5>")
	)
	(gr_poly
		(pts
			(xy 332.561184 -247.115838) (xy 332.461108 -247.016016) (xy 332.361032 -247.115838) (xy 332.361032 -247.16359)
			(xy 332.561184 -247.16359)
		)
		(stroke
			(width 0)
			(type solid)
		)
		(fill yes)
		(layer "In11.Cu")
		(net "M_F_CPU0_SA_DQS_DN<9>")
	)
	(gr_poly
		(pts
			(xy 332.561184 -245.49608) (xy 332.461108 -245.396004) (xy 332.361032 -245.49608) (xy 332.361032 -245.54053)
			(xy 332.561184 -245.54053)
		)
		(stroke
			(width 0)
			(type solid)
		)
		(fill yes)
		(layer "In11.Cu")
		(net "M_F_CPU0_SA_CB<1>")
	)
	(gr_poly
		(pts
			(xy 332.561184 -243.876068) (xy 332.461108 -243.775992) (xy 332.361032 -243.876068) (xy 332.361032 -243.920518)
			(xy 332.561184 -243.920518)
		)
		(stroke
			(width 0)
			(type solid)
		)
		(fill yes)
		(layer "In11.Cu")
		(net "M_F_CPU0_SA_DQ<29>")
	)
	(gr_poly
		(pts
			(xy 332.561184 -242.255802) (xy 332.461108 -242.15598) (xy 332.361032 -242.255802) (xy 332.361032 -242.303554)
			(xy 332.561184 -242.303554)
		)
		(stroke
			(width 0)
			(type solid)
		)
		(fill yes)
		(layer "In11.Cu")
		(net "M_F_CPU0_SA_DQS_DN<8>")
	)
	(gr_poly
		(pts
			(xy 332.561184 -240.636044) (xy 332.461108 -240.535968) (xy 332.361032 -240.636044) (xy 332.361032 -240.680494)
			(xy 332.561184 -240.680494)
		)
		(stroke
			(width 0)
			(type solid)
		)
		(fill yes)
		(layer "In11.Cu")
		(net "M_F_CPU0_SA_DQ<25>")
	)
	(gr_poly
		(pts
			(xy 332.561184 -239.016032) (xy 332.461108 -238.915956) (xy 332.361032 -239.016032) (xy 332.361032 -239.060482)
			(xy 332.561184 -239.060482)
		)
		(stroke
			(width 0)
			(type solid)
		)
		(fill yes)
		(layer "In11.Cu")
		(net "M_F_CPU0_SA_DQ<21>")
	)
	(gr_poly
		(pts
			(xy 332.561184 -237.395766) (xy 332.461108 -237.295944) (xy 332.361032 -237.395766) (xy 332.361032 -237.443518)
			(xy 332.561184 -237.443518)
		)
		(stroke
			(width 0)
			(type solid)
		)
		(fill yes)
		(layer "In11.Cu")
		(net "M_F_CPU0_SA_DQS_DN<7>")
	)
	(gr_poly
		(pts
			(xy 332.561184 -235.776008) (xy 332.461108 -235.675932) (xy 332.361032 -235.776008) (xy 332.361032 -235.820458)
			(xy 332.561184 -235.820458)
		)
		(stroke
			(width 0)
			(type solid)
		)
		(fill yes)
		(layer "In11.Cu")
		(net "M_F_CPU0_SA_DQ<17>")
	)
	(gr_poly
		(pts
			(xy 332.561184 -234.155996) (xy 332.461108 -234.05592) (xy 332.361032 -234.155996) (xy 332.361032 -234.200446)
			(xy 332.561184 -234.200446)
		)
		(stroke
			(width 0)
			(type solid)
		)
		(fill yes)
		(layer "In11.Cu")
		(net "M_F_CPU0_SA_DQ<13>")
	)
	(gr_poly
		(pts
			(xy 332.561184 -232.53573) (xy 332.461108 -232.435908) (xy 332.361032 -232.53573) (xy 332.361032 -232.583482)
			(xy 332.561184 -232.583482)
		)
		(stroke
			(width 0)
			(type solid)
		)
		(fill yes)
		(layer "In11.Cu")
		(net "M_F_CPU0_SA_DQS_DN<6>")
	)
	(gr_poly
		(pts
			(xy 332.561184 -229.29596) (xy 332.461108 -229.195884) (xy 332.361032 -229.29596) (xy 332.361032 -229.34041)
			(xy 332.561184 -229.34041)
		)
		(stroke
			(width 0)
			(type solid)
		)
		(fill yes)
		(layer "In11.Cu")
		(net "M_F_CPU0_SA_DQ<5>")
	)
	(gr_poly
		(pts
			(xy 332.561184 -227.675948) (xy 332.461108 -227.576126) (xy 332.361032 -227.675948) (xy 332.361032 -227.7237)
			(xy 332.561184 -227.7237)
		)
		(stroke
			(width 0)
			(type solid)
		)
		(fill yes)
		(layer "In11.Cu")
		(net "M_F_CPU0_SA_DQS_DN<5>")
	)
	(gr_poly
		(pts
			(xy 332.561184 -226.05619) (xy 332.461108 -225.956114) (xy 332.361032 -226.05619) (xy 332.361032 -226.10064)
			(xy 332.561184 -226.10064)
		)
		(stroke
			(width 0)
			(type solid)
		)
		(fill yes)
		(layer "In11.Cu")
		(net "M_F_CPU0_SA_DQ<1>")
	)
	(gr_poly
		(pts
			(xy 332.861158 -291.704268) (xy 332.861158 -291.656516) (xy 332.661006 -291.656516) (xy 332.661006 -291.704268)
			(xy 332.761082 -291.80409)
		)
		(stroke
			(width 0)
			(type solid)
		)
		(fill yes)
		(layer "In11.Cu")
		(net "M_F_CPU0_SB_DQS_DP<8>")
	)
	(gr_poly
		(pts
			(xy 332.861158 -290.084002) (xy 332.861158 -290.039552) (xy 332.661006 -290.039552) (xy 332.661006 -290.084002)
			(xy 332.761082 -290.184078)
		)
		(stroke
			(width 0)
			(type solid)
		)
		(fill yes)
		(layer "In11.Cu")
		(net "M_F_CPU0_SB_DQ<27>")
	)
	(gr_poly
		(pts
			(xy 332.861158 -288.464244) (xy 332.861158 -288.419794) (xy 332.661006 -288.419794) (xy 332.661006 -288.464244)
			(xy 332.761082 -288.56432)
		)
		(stroke
			(width 0)
			(type solid)
		)
		(fill yes)
		(layer "In11.Cu")
		(net "M_F_CPU0_SB_DQ<23>")
	)
	(gr_poly
		(pts
			(xy 332.861158 -286.844232) (xy 332.861158 -286.79648) (xy 332.661006 -286.79648) (xy 332.661006 -286.844232)
			(xy 332.761082 -286.944308)
		)
		(stroke
			(width 0)
			(type solid)
		)
		(fill yes)
		(layer "In11.Cu")
		(net "M_F_CPU0_SB_DQS_DP<7>")
	)
	(gr_poly
		(pts
			(xy 332.861158 -285.22422) (xy 332.861158 -285.17977) (xy 332.661006 -285.17977) (xy 332.661006 -285.22422)
			(xy 332.761082 -285.324296)
		)
		(stroke
			(width 0)
			(type solid)
		)
		(fill yes)
		(layer "In11.Cu")
		(net "M_F_CPU0_SB_DQ<19>")
	)
	(gr_poly
		(pts
			(xy 332.861158 -283.604208) (xy 332.861158 -283.559758) (xy 332.661006 -283.559758) (xy 332.661006 -283.604208)
			(xy 332.761082 -283.704284)
		)
		(stroke
			(width 0)
			(type solid)
		)
		(fill yes)
		(layer "In11.Cu")
		(net "M_F_CPU0_SB_DQ<15>")
	)
	(gr_poly
		(pts
			(xy 332.861158 -281.98445) (xy 332.861158 -281.936698) (xy 332.661006 -281.936698) (xy 332.661006 -281.98445)
			(xy 332.761082 -282.084272)
		)
		(stroke
			(width 0)
			(type solid)
		)
		(fill yes)
		(layer "In11.Cu")
		(net "M_F_CPU0_SB_DQS_DP<6>")
	)
	(gr_poly
		(pts
			(xy 332.861158 -280.364184) (xy 332.861158 -280.319734) (xy 332.661006 -280.319734) (xy 332.661006 -280.364184)
			(xy 332.761082 -280.46426)
		)
		(stroke
			(width 0)
			(type solid)
		)
		(fill yes)
		(layer "In11.Cu")
		(net "M_F_CPU0_SB_DQ<11>")
	)
	(gr_poly
		(pts
			(xy 332.861158 -278.744172) (xy 332.861158 -278.699722) (xy 332.661006 -278.699722) (xy 332.661006 -278.744172)
			(xy 332.761082 -278.844248)
		)
		(stroke
			(width 0)
			(type solid)
		)
		(fill yes)
		(layer "In11.Cu")
		(net "M_F_CPU0_SB_DQ<7>")
	)
	(gr_poly
		(pts
			(xy 332.861158 -277.124414) (xy 332.861158 -277.076662) (xy 332.661006 -277.076662) (xy 332.661006 -277.124414)
			(xy 332.761082 -277.224236)
		)
		(stroke
			(width 0)
			(type solid)
		)
		(fill yes)
		(layer "In11.Cu")
		(net "M_F_CPU0_SB_DQS_DP<5>")
	)
	(gr_poly
		(pts
			(xy 332.861158 -275.504148) (xy 332.861158 -275.459698) (xy 332.661006 -275.459698) (xy 332.661006 -275.504148)
			(xy 332.761082 -275.604224)
		)
		(stroke
			(width 0)
			(type solid)
		)
		(fill yes)
		(layer "In11.Cu")
		(net "M_F_CPU0_SB_DQ<3>")
	)
	(gr_poly
		(pts
			(xy 332.861158 -273.884136) (xy 332.861158 -273.839686) (xy 332.661006 -273.839686) (xy 332.661006 -273.884136)
			(xy 332.761082 -273.984212)
		)
		(stroke
			(width 0)
			(type solid)
		)
		(fill yes)
		(layer "In11.Cu")
		(net "M_F_CPU0_SB_CB<3>")
	)
	(gr_poly
		(pts
			(xy 332.861158 -272.264378) (xy 332.861158 -272.216626) (xy 332.661006 -272.216626) (xy 332.661006 -272.264378)
			(xy 332.761082 -272.3642)
		)
		(stroke
			(width 0)
			(type solid)
		)
		(fill yes)
		(layer "In11.Cu")
		(net "M_F_CPU0_SB_DQS_DP<4>")
	)
	(gr_poly
		(pts
			(xy 332.861158 -270.644112) (xy 332.861158 -270.599662) (xy 332.661006 -270.599662) (xy 332.661006 -270.644112)
			(xy 332.761082 -270.744188)
		)
		(stroke
			(width 0)
			(type solid)
		)
		(fill yes)
		(layer "In11.Cu")
		(net "M_F_CPU0_SB_CB<7>")
	)
	(gr_poly
		(pts
			(xy 332.861158 -265.784076) (xy 332.861158 -265.739626) (xy 332.661006 -265.739626) (xy 332.661006 -265.784076)
			(xy 332.761082 -265.884152)
		)
		(stroke
			(width 0)
			(type solid)
		)
		(fill yes)
		(layer "In11.Cu")
		(net "M_F_CPU0_SB_CS_N<0>")
	)
	(gr_poly
		(pts
			(xy 332.861158 -264.164064) (xy 332.861158 -264.119614) (xy 332.661006 -264.119614) (xy 332.661006 -264.164064)
			(xy 332.761082 -264.26414)
		)
		(stroke
			(width 0)
			(type solid)
		)
		(fill yes)
		(layer "In11.Cu")
		(net "M_F_CPU0_SB_CA<5>")
	)
	(gr_poly
		(pts
			(xy 332.861158 -262.544052) (xy 332.861158 -262.499602) (xy 332.661006 -262.499602) (xy 332.661006 -262.544052)
			(xy 332.761082 -262.644128)
		)
		(stroke
			(width 0)
			(type solid)
		)
		(fill yes)
		(layer "In11.Cu")
		(net "M_F_CPU0_SB_CA<1>")
	)
	(gr_poly
		(pts
			(xy 333.029814 -231.322372) (xy 333.029814 -231.277922) (xy 332.832202 -231.277922) (xy 332.832202 -231.322372)
			(xy 332.931008 -231.422448)
		)
		(stroke
			(width 0)
			(type solid)
		)
		(fill yes)
		(layer "In11.Cu")
		(net "M_F_CPU0_SA_DQ<11>")
	)
	(gr_poly
		(pts
			(xy 333.031084 -255.622298) (xy 333.031084 -255.577848) (xy 332.830932 -255.577848) (xy 332.830932 -255.622298)
			(xy 332.931008 -255.722374)
		)
		(stroke
			(width 0)
			(type solid)
		)
		(fill yes)
		(layer "In11.Cu")
		(net "M_F_CPU0_SA_PAR")
	)
	(gr_poly
		(pts
			(xy 333.031084 -254.002286) (xy 333.031084 -253.957836) (xy 332.830932 -253.957836) (xy 332.830932 -254.002286)
			(xy 332.931008 -254.102362)
		)
		(stroke
			(width 0)
			(type solid)
		)
		(fill yes)
		(layer "In11.Cu")
		(net "M_F_CPU0_SA_CA<3>")
	)
	(gr_poly
		(pts
			(xy 333.031084 -252.382274) (xy 333.031084 -252.337824) (xy 332.830932 -252.337824) (xy 332.830932 -252.382274)
			(xy 332.931008 -252.48235)
		)
		(stroke
			(width 0)
			(type solid)
		)
		(fill yes)
		(layer "In11.Cu")
		(net "M_F_CPU0_SA_CS_N<1>")
	)
	(gr_poly
		(pts
			(xy 333.031084 -250.762262) (xy 333.031084 -250.717812) (xy 332.830932 -250.717812) (xy 332.830932 -250.762262)
			(xy 332.931008 -250.862338)
		)
		(stroke
			(width 0)
			(type solid)
		)
		(fill yes)
		(layer "In11.Cu")
		(net "M_F_CPU0_RESET_N")
	)
	(gr_poly
		(pts
			(xy 333.031084 -249.14225) (xy 333.031084 -249.0978) (xy 332.830932 -249.0978) (xy 332.830932 -249.14225)
			(xy 332.931008 -249.242326)
		)
		(stroke
			(width 0)
			(type solid)
		)
		(fill yes)
		(layer "In11.Cu")
		(net "M_F_CPU0_SA_CB<7>")
	)
	(gr_poly
		(pts
			(xy 333.031084 -247.522492) (xy 333.031084 -247.47474) (xy 332.830932 -247.47474) (xy 332.830932 -247.522492)
			(xy 332.931008 -247.622314)
		)
		(stroke
			(width 0)
			(type solid)
		)
		(fill yes)
		(layer "In11.Cu")
		(net "M_F_CPU0_SA_DQS_DP<9>")
	)
	(gr_poly
		(pts
			(xy 333.031084 -245.902226) (xy 333.031084 -245.857776) (xy 332.830932 -245.857776) (xy 332.830932 -245.902226)
			(xy 332.931008 -246.002302)
		)
		(stroke
			(width 0)
			(type solid)
		)
		(fill yes)
		(layer "In11.Cu")
		(net "M_F_CPU0_SA_CB<3>")
	)
	(gr_poly
		(pts
			(xy 333.031084 -244.282214) (xy 333.031084 -244.237764) (xy 332.830932 -244.237764) (xy 332.830932 -244.282214)
			(xy 332.931008 -244.38229)
		)
		(stroke
			(width 0)
			(type solid)
		)
		(fill yes)
		(layer "In11.Cu")
		(net "M_F_CPU0_SA_DQ<31>")
	)
	(gr_poly
		(pts
			(xy 333.031084 -242.662456) (xy 333.031084 -242.614704) (xy 332.830932 -242.614704) (xy 332.830932 -242.662456)
			(xy 332.931008 -242.762278)
		)
		(stroke
			(width 0)
			(type solid)
		)
		(fill yes)
		(layer "In11.Cu")
		(net "M_F_CPU0_SA_DQS_DP<8>")
	)
	(gr_poly
		(pts
			(xy 333.031084 -241.04219) (xy 333.031084 -240.99774) (xy 332.830932 -240.99774) (xy 332.830932 -241.04219)
			(xy 332.931008 -241.142266)
		)
		(stroke
			(width 0)
			(type solid)
		)
		(fill yes)
		(layer "In11.Cu")
		(net "M_F_CPU0_SA_DQ<27>")
	)
	(gr_poly
		(pts
			(xy 333.031084 -239.422178) (xy 333.031084 -239.377728) (xy 332.830932 -239.377728) (xy 332.830932 -239.422178)
			(xy 332.931008 -239.522254)
		)
		(stroke
			(width 0)
			(type solid)
		)
		(fill yes)
		(layer "In11.Cu")
		(net "M_F_CPU0_SA_DQ<23>")
	)
	(gr_poly
		(pts
			(xy 333.031084 -237.80242) (xy 333.031084 -237.754668) (xy 332.830932 -237.754668) (xy 332.830932 -237.80242)
			(xy 332.931008 -237.902242)
		)
		(stroke
			(width 0)
			(type solid)
		)
		(fill yes)
		(layer "In11.Cu")
		(net "M_F_CPU0_SA_DQS_DP<7>")
	)
	(gr_poly
		(pts
			(xy 333.031084 -236.182154) (xy 333.031084 -236.137704) (xy 332.830932 -236.137704) (xy 332.830932 -236.182154)
			(xy 332.931008 -236.28223)
		)
		(stroke
			(width 0)
			(type solid)
		)
		(fill yes)
		(layer "In11.Cu")
		(net "M_F_CPU0_SA_DQ<19>")
	)
	(gr_poly
		(pts
			(xy 333.031084 -234.562142) (xy 333.031084 -234.517692) (xy 332.830932 -234.517692) (xy 332.830932 -234.562142)
			(xy 332.931008 -234.662218)
		)
		(stroke
			(width 0)
			(type solid)
		)
		(fill yes)
		(layer "In11.Cu")
		(net "M_F_CPU0_SA_DQ<15>")
	)
	(gr_poly
		(pts
			(xy 333.031084 -232.942384) (xy 333.031084 -232.894632) (xy 332.830932 -232.894632) (xy 332.830932 -232.942384)
			(xy 332.931008 -233.042206)
		)
		(stroke
			(width 0)
			(type solid)
		)
		(fill yes)
		(layer "In11.Cu")
		(net "M_F_CPU0_SA_DQS_DP<6>")
	)
	(gr_poly
		(pts
			(xy 333.031084 -229.70236) (xy 333.031084 -229.65791) (xy 332.830932 -229.65791) (xy 332.830932 -229.70236)
			(xy 332.931008 -229.802436)
		)
		(stroke
			(width 0)
			(type solid)
		)
		(fill yes)
		(layer "In11.Cu")
		(net "M_F_CPU0_SA_DQ<7>")
	)
	(gr_poly
		(pts
			(xy 333.031084 -228.082602) (xy 333.031084 -228.03485) (xy 332.830932 -228.03485) (xy 332.830932 -228.082602)
			(xy 332.931008 -228.182424)
		)
		(stroke
			(width 0)
			(type solid)
		)
		(fill yes)
		(layer "In11.Cu")
		(net "M_F_CPU0_SA_DQS_DP<5>")
	)
	(gr_poly
		(pts
			(xy 333.031084 -226.462336) (xy 333.031084 -226.417886) (xy 332.830932 -226.417886) (xy 332.830932 -226.462336)
			(xy 332.931008 -226.562412)
		)
		(stroke
			(width 0)
			(type solid)
		)
		(fill yes)
		(layer "In11.Cu")
		(net "M_F_CPU0_SA_DQ<3>")
	)
	(gr_poly
		(pts
			(xy 333.331058 -292.91788) (xy 333.230982 -292.817804) (xy 333.130906 -292.91788) (xy 333.130906 -292.96233)
			(xy 333.331058 -292.96233)
		)
		(stroke
			(width 0)
			(type solid)
		)
		(fill yes)
		(layer "In11.Cu")
		(net "M_F_CPU0_SB_DQ<29>")
	)
	(gr_poly
		(pts
			(xy 333.331058 -291.297614) (xy 333.230982 -291.197792) (xy 333.130906 -291.297614) (xy 333.130906 -291.345366)
			(xy 333.331058 -291.345366)
		)
		(stroke
			(width 0)
			(type solid)
		)
		(fill yes)
		(layer "In11.Cu")
		(net "M_F_CPU0_SB_DQS_DN<8>")
	)
	(gr_poly
		(pts
			(xy 333.331058 -289.677856) (xy 333.230982 -289.57778) (xy 333.130906 -289.677856) (xy 333.130906 -289.722306)
			(xy 333.331058 -289.722306)
		)
		(stroke
			(width 0)
			(type solid)
		)
		(fill yes)
		(layer "In11.Cu")
		(net "M_F_CPU0_SB_DQ<25>")
	)
	(gr_poly
		(pts
			(xy 333.331058 -288.057844) (xy 333.230982 -287.957768) (xy 333.130906 -288.057844) (xy 333.130906 -288.102294)
			(xy 333.331058 -288.102294)
		)
		(stroke
			(width 0)
			(type solid)
		)
		(fill yes)
		(layer "In11.Cu")
		(net "M_F_CPU0_SB_DQ<21>")
	)
	(gr_poly
		(pts
			(xy 333.331058 -286.437832) (xy 333.230982 -286.337756) (xy 333.130906 -286.437832) (xy 333.130906 -286.485584)
			(xy 333.331058 -286.485584)
		)
		(stroke
			(width 0)
			(type solid)
		)
		(fill yes)
		(layer "In11.Cu")
		(net "M_F_CPU0_SB_DQS_DN<7>")
	)
	(gr_poly
		(pts
			(xy 333.331058 -284.818074) (xy 333.230982 -284.717998) (xy 333.130906 -284.818074) (xy 333.130906 -284.862524)
			(xy 333.331058 -284.862524)
		)
		(stroke
			(width 0)
			(type solid)
		)
		(fill yes)
		(layer "In11.Cu")
		(net "M_F_CPU0_SB_DQ<17>")
	)
	(gr_poly
		(pts
			(xy 333.331058 -283.198062) (xy 333.230982 -283.097986) (xy 333.130906 -283.198062) (xy 333.130906 -283.242512)
			(xy 333.331058 -283.242512)
		)
		(stroke
			(width 0)
			(type solid)
		)
		(fill yes)
		(layer "In11.Cu")
		(net "M_F_CPU0_SB_DQ<13>")
	)
	(gr_poly
		(pts
			(xy 333.331058 -281.577796) (xy 333.230982 -281.477974) (xy 333.130906 -281.577796) (xy 333.130906 -281.625548)
			(xy 333.331058 -281.625548)
		)
		(stroke
			(width 0)
			(type solid)
		)
		(fill yes)
		(layer "In11.Cu")
		(net "M_F_CPU0_SB_DQS_DN<6>")
	)
	(gr_poly
		(pts
			(xy 333.331058 -279.958038) (xy 333.230982 -279.857962) (xy 333.130906 -279.958038) (xy 333.130906 -280.002488)
			(xy 333.331058 -280.002488)
		)
		(stroke
			(width 0)
			(type solid)
		)
		(fill yes)
		(layer "In11.Cu")
		(net "M_F_CPU0_SB_DQ<9>")
	)
	(gr_poly
		(pts
			(xy 333.331058 -278.338026) (xy 333.230982 -278.23795) (xy 333.130906 -278.338026) (xy 333.130906 -278.382476)
			(xy 333.331058 -278.382476)
		)
		(stroke
			(width 0)
			(type solid)
		)
		(fill yes)
		(layer "In11.Cu")
		(net "M_F_CPU0_SB_DQ<5>")
	)
	(gr_poly
		(pts
			(xy 333.331058 -276.71776) (xy 333.230982 -276.617938) (xy 333.130906 -276.71776) (xy 333.130906 -276.765512)
			(xy 333.331058 -276.765512)
		)
		(stroke
			(width 0)
			(type solid)
		)
		(fill yes)
		(layer "In11.Cu")
		(net "M_F_CPU0_SB_DQS_DN<5>")
	)
	(gr_poly
		(pts
			(xy 333.331058 -275.098002) (xy 333.230982 -274.997926) (xy 333.130906 -275.098002) (xy 333.130906 -275.142452)
			(xy 333.331058 -275.142452)
		)
		(stroke
			(width 0)
			(type solid)
		)
		(fill yes)
		(layer "In11.Cu")
		(net "M_F_CPU0_SB_DQ<1>")
	)
	(gr_poly
		(pts
			(xy 333.331058 -273.47799) (xy 333.230982 -273.377914) (xy 333.130906 -273.47799) (xy 333.130906 -273.52244)
			(xy 333.331058 -273.52244)
		)
		(stroke
			(width 0)
			(type solid)
		)
		(fill yes)
		(layer "In11.Cu")
		(net "M_F_CPU0_SB_CB<1>")
	)
	(gr_poly
		(pts
			(xy 333.331058 -271.857724) (xy 333.230982 -271.757902) (xy 333.130906 -271.857724) (xy 333.130906 -271.905476)
			(xy 333.331058 -271.905476)
		)
		(stroke
			(width 0)
			(type solid)
		)
		(fill yes)
		(layer "In11.Cu")
		(net "M_F_CPU0_SB_DQS_DN<4>")
	)
	(gr_poly
		(pts
			(xy 333.331058 -270.237966) (xy 333.230982 -270.13789) (xy 333.130906 -270.237966) (xy 333.130906 -270.282416)
			(xy 333.331058 -270.282416)
		)
		(stroke
			(width 0)
			(type solid)
		)
		(fill yes)
		(layer "In11.Cu")
		(net "M_F_CPU0_SB_CB<5>")
	)
	(gr_poly
		(pts
			(xy 333.331058 -263.757918) (xy 333.230982 -263.657842) (xy 333.130906 -263.757918) (xy 333.130906 -263.802368)
			(xy 333.331058 -263.802368)
		)
		(stroke
			(width 0)
			(type solid)
		)
		(fill yes)
		(layer "In11.Cu")
		(net "M_F_CPU0_SB_CA<4>")
	)
	(gr_poly
		(pts
			(xy 333.331058 -262.137906) (xy 333.230982 -262.03783) (xy 333.130906 -262.137906) (xy 333.130906 -262.182356)
			(xy 333.331058 -262.182356)
		)
		(stroke
			(width 0)
			(type solid)
		)
		(fill yes)
		(layer "In11.Cu")
		(net "M_F_CPU0_SB_CA<0>")
	)
	(gr_poly
		(pts
			(xy 333.331312 -266.997942) (xy 333.231236 -266.897866) (xy 333.13116 -266.997942) (xy 333.13116 -267.042392)
			(xy 333.331312 -267.042392)
		)
		(stroke
			(width 0)
			(type solid)
		)
		(fill yes)
		(layer "In11.Cu")
		(net "M_F_CPU0_SA_RSP<0>")
	)
	(gr_poly
		(pts
			(xy 333.452978 -247.156732) (xy 333.44866 -247.109234) (xy 333.340456 -247.018556) (xy 333.249524 -247.12676)
			(xy 333.253588 -247.174258)
		)
		(stroke
			(width 0)
			(type solid)
		)
		(fill yes)
		(layer "In11.Cu")
		(net "M_F_CPU0_SA_DQS_DN<9>")
	)
	(gr_poly
		(pts
			(xy 333.452978 -242.296696) (xy 333.44866 -242.249452) (xy 333.340456 -242.15852) (xy 333.249524 -242.266724)
			(xy 333.253588 -242.314222)
		)
		(stroke
			(width 0)
			(type solid)
		)
		(fill yes)
		(layer "In11.Cu")
		(net "M_F_CPU0_SA_DQS_DN<8>")
	)
	(gr_poly
		(pts
			(xy 333.452978 -237.43666) (xy 333.44866 -237.389416) (xy 333.340456 -237.298484) (xy 333.249524 -237.406688)
			(xy 333.253588 -237.454186)
		)
		(stroke
			(width 0)
			(type solid)
		)
		(fill yes)
		(layer "In11.Cu")
		(net "M_F_CPU0_SA_DQS_DN<7>")
	)
	(gr_poly
		(pts
			(xy 333.452978 -232.576624) (xy 333.44866 -232.52938) (xy 333.340456 -232.438448) (xy 333.249524 -232.546652)
			(xy 333.253588 -232.59415)
		)
		(stroke
			(width 0)
			(type solid)
		)
		(fill yes)
		(layer "In11.Cu")
		(net "M_F_CPU0_SA_DQS_DN<6>")
	)
	(gr_poly
		(pts
			(xy 333.452978 -227.716842) (xy 333.44866 -227.669344) (xy 333.340456 -227.578666) (xy 333.249524 -227.68687)
			(xy 333.253588 -227.734368)
		)
		(stroke
			(width 0)
			(type solid)
		)
		(fill yes)
		(layer "In11.Cu")
		(net "M_F_CPU0_SA_DQS_DN<5>")
	)
	(gr_poly
		(pts
			(xy 333.464662 -230.952802) (xy 333.460598 -230.908606) (xy 333.35341 -230.817674) (xy 333.263748 -230.925878)
			(xy 333.267558 -230.970074)
		)
		(stroke
			(width 0)
			(type solid)
		)
		(fill yes)
		(layer "In11.Cu")
		(net "M_F_CPU0_SA_DQ<9>")
	)
	(gr_poly
		(pts
			(xy 333.465678 -255.252982) (xy 333.461614 -255.208532) (xy 333.35341 -255.1176) (xy 333.262478 -255.226058)
			(xy 333.266288 -255.270254)
		)
		(stroke
			(width 0)
			(type solid)
		)
		(fill yes)
		(layer "In11.Cu")
		(net "M_F_CPU0_SA_CA<6>")
	)
	(gr_poly
		(pts
			(xy 333.465678 -253.63297) (xy 333.461614 -253.58852) (xy 333.35341 -253.497588) (xy 333.262478 -253.606046)
			(xy 333.266288 -253.650242)
		)
		(stroke
			(width 0)
			(type solid)
		)
		(fill yes)
		(layer "In11.Cu")
		(net "M_F_CPU0_SA_CA<2>")
	)
	(gr_poly
		(pts
			(xy 333.465678 -250.392946) (xy 333.461614 -250.348496) (xy 333.35341 -250.257564) (xy 333.262478 -250.366022)
			(xy 333.266288 -250.410218)
		)
		(stroke
			(width 0)
			(type solid)
		)
		(fill yes)
		(layer "In11.Cu")
		(net "M_F_CPU0_ALERT_R_N")
	)
	(gr_poly
		(pts
			(xy 333.465678 -248.772934) (xy 333.461614 -248.728484) (xy 333.35341 -248.637552) (xy 333.262478 -248.74601)
			(xy 333.266288 -248.790206)
		)
		(stroke
			(width 0)
			(type solid)
		)
		(fill yes)
		(layer "In11.Cu")
		(net "M_F_CPU0_SA_CB<5>")
	)
	(gr_poly
		(pts
			(xy 333.465678 -245.53291) (xy 333.461614 -245.48846) (xy 333.35341 -245.397528) (xy 333.262478 -245.505986)
			(xy 333.266288 -245.550182)
		)
		(stroke
			(width 0)
			(type solid)
		)
		(fill yes)
		(layer "In11.Cu")
		(net "M_F_CPU0_SA_CB<1>")
	)
	(gr_poly
		(pts
			(xy 333.465678 -243.912898) (xy 333.461614 -243.868448) (xy 333.35341 -243.777516) (xy 333.262478 -243.885974)
			(xy 333.266288 -243.93017)
		)
		(stroke
			(width 0)
			(type solid)
		)
		(fill yes)
		(layer "In11.Cu")
		(net "M_F_CPU0_SA_DQ<29>")
	)
	(gr_poly
		(pts
			(xy 333.465678 -240.672874) (xy 333.461614 -240.628424) (xy 333.35341 -240.537492) (xy 333.262478 -240.64595)
			(xy 333.266288 -240.690146)
		)
		(stroke
			(width 0)
			(type solid)
		)
		(fill yes)
		(layer "In11.Cu")
		(net "M_F_CPU0_SA_DQ<25>")
	)
	(gr_poly
		(pts
			(xy 333.465678 -239.052862) (xy 333.461614 -239.008412) (xy 333.35341 -238.91748) (xy 333.262478 -239.025938)
			(xy 333.266288 -239.070134)
		)
		(stroke
			(width 0)
			(type solid)
		)
		(fill yes)
		(layer "In11.Cu")
		(net "M_F_CPU0_SA_DQ<21>")
	)
	(gr_poly
		(pts
			(xy 333.465678 -235.812838) (xy 333.461614 -235.768388) (xy 333.35341 -235.677456) (xy 333.262478 -235.785914)
			(xy 333.266288 -235.83011)
		)
		(stroke
			(width 0)
			(type solid)
		)
		(fill yes)
		(layer "In11.Cu")
		(net "M_F_CPU0_SA_DQ<17>")
	)
	(gr_poly
		(pts
			(xy 333.465678 -234.192826) (xy 333.461614 -234.148376) (xy 333.35341 -234.057444) (xy 333.262478 -234.165902)
			(xy 333.266288 -234.210098)
		)
		(stroke
			(width 0)
			(type solid)
		)
		(fill yes)
		(layer "In11.Cu")
		(net "M_F_CPU0_SA_DQ<13>")
	)
	(gr_poly
		(pts
			(xy 333.465678 -229.33279) (xy 333.461868 -229.28834) (xy 333.35341 -229.197662) (xy 333.262478 -229.305866)
			(xy 333.266542 -229.350062)
		)
		(stroke
			(width 0)
			(type solid)
		)
		(fill yes)
		(layer "In11.Cu")
		(net "M_F_CPU0_SA_DQ<5>")
	)
	(gr_poly
		(pts
			(xy 333.465678 -226.09302) (xy 333.461614 -226.04857) (xy 333.35341 -225.957638) (xy 333.262478 -226.066096)
			(xy 333.266288 -226.110292)
		)
		(stroke
			(width 0)
			(type solid)
		)
		(fill yes)
		(layer "In11.Cu")
		(net "M_F_CPU0_SA_DQ<1>")
	)
	(gr_poly
		(pts
			(xy 333.748634 -291.710872) (xy 333.752952 -291.663374) (xy 333.553562 -291.645848) (xy 333.549498 -291.693346)
			(xy 333.64043 -291.80155)
		)
		(stroke
			(width 0)
			(type solid)
		)
		(fill yes)
		(layer "In11.Cu")
		(net "M_F_CPU0_SB_DQS_DP<8>")
	)
	(gr_poly
		(pts
			(xy 333.748634 -286.850836) (xy 333.752952 -286.803338) (xy 333.553562 -286.786066) (xy 333.549498 -286.83331)
			(xy 333.64043 -286.941768)
		)
		(stroke
			(width 0)
			(type solid)
		)
		(fill yes)
		(layer "In11.Cu")
		(net "M_F_CPU0_SB_DQS_DP<7>")
	)
	(gr_poly
		(pts
			(xy 333.748634 -281.9908) (xy 333.752952 -281.943556) (xy 333.553562 -281.92603) (xy 333.549498 -281.973528)
			(xy 333.64043 -282.081732)
		)
		(stroke
			(width 0)
			(type solid)
		)
		(fill yes)
		(layer "In11.Cu")
		(net "M_F_CPU0_SB_DQS_DP<6>")
	)
	(gr_poly
		(pts
			(xy 333.748634 -277.130764) (xy 333.752952 -277.08352) (xy 333.553562 -277.065994) (xy 333.549498 -277.113492)
			(xy 333.64043 -277.221696)
		)
		(stroke
			(width 0)
			(type solid)
		)
		(fill yes)
		(layer "In11.Cu")
		(net "M_F_CPU0_SB_DQS_DP<5>")
	)
	(gr_poly
		(pts
			(xy 333.748634 -272.270728) (xy 333.752952 -272.223484) (xy 333.553562 -272.205958) (xy 333.549498 -272.253456)
			(xy 333.64043 -272.36166)
		)
		(stroke
			(width 0)
			(type solid)
		)
		(fill yes)
		(layer "In11.Cu")
		(net "M_F_CPU0_SB_DQS_DP<4>")
	)
	(gr_poly
		(pts
			(xy 333.761588 -290.091622) (xy 333.765398 -290.047172) (xy 333.566262 -290.0299) (xy 333.562452 -290.074096)
			(xy 333.653384 -290.182554)
		)
		(stroke
			(width 0)
			(type solid)
		)
		(fill yes)
		(layer "In11.Cu")
		(net "M_F_CPU0_SB_DQ<27>")
	)
	(gr_poly
		(pts
			(xy 333.761588 -285.23184) (xy 333.765398 -285.18739) (xy 333.566262 -285.170118) (xy 333.562452 -285.214314)
			(xy 333.653384 -285.322772)
		)
		(stroke
			(width 0)
			(type solid)
		)
		(fill yes)
		(layer "In11.Cu")
		(net "M_F_CPU0_SB_DQ<19>")
	)
	(gr_poly
		(pts
			(xy 333.761588 -283.611828) (xy 333.765398 -283.567378) (xy 333.566262 -283.550106) (xy 333.562452 -283.594302)
			(xy 333.653384 -283.70276)
		)
		(stroke
			(width 0)
			(type solid)
		)
		(fill yes)
		(layer "In11.Cu")
		(net "M_F_CPU0_SB_DQ<15>")
	)
	(gr_poly
		(pts
			(xy 333.761588 -280.371804) (xy 333.765398 -280.327354) (xy 333.566262 -280.310082) (xy 333.562452 -280.354278)
			(xy 333.653384 -280.462736)
		)
		(stroke
			(width 0)
			(type solid)
		)
		(fill yes)
		(layer "In11.Cu")
		(net "M_F_CPU0_SB_DQ<11>")
	)
	(gr_poly
		(pts
			(xy 333.761588 -278.751792) (xy 333.765398 -278.707342) (xy 333.566262 -278.69007) (xy 333.562452 -278.734266)
			(xy 333.653384 -278.842724)
		)
		(stroke
			(width 0)
			(type solid)
		)
		(fill yes)
		(layer "In11.Cu")
		(net "M_F_CPU0_SB_DQ<7>")
	)
	(gr_poly
		(pts
			(xy 333.761588 -275.511768) (xy 333.765398 -275.467318) (xy 333.566262 -275.450046) (xy 333.562452 -275.494242)
			(xy 333.653384 -275.6027)
		)
		(stroke
			(width 0)
			(type solid)
		)
		(fill yes)
		(layer "In11.Cu")
		(net "M_F_CPU0_SB_DQ<3>")
	)
	(gr_poly
		(pts
			(xy 333.761588 -273.891756) (xy 333.765398 -273.847306) (xy 333.566262 -273.830034) (xy 333.562452 -273.87423)
			(xy 333.653384 -273.982688)
		)
		(stroke
			(width 0)
			(type solid)
		)
		(fill yes)
		(layer "In11.Cu")
		(net "M_F_CPU0_SB_CB<3>")
	)
	(gr_poly
		(pts
			(xy 333.761588 -270.651732) (xy 333.765398 -270.607282) (xy 333.566262 -270.59001) (xy 333.562452 -270.634206)
			(xy 333.653384 -270.742664)
		)
		(stroke
			(width 0)
			(type solid)
		)
		(fill yes)
		(layer "In11.Cu")
		(net "M_F_CPU0_SB_CB<7>")
	)
	(gr_poly
		(pts
			(xy 333.761588 -265.791696) (xy 333.765398 -265.747246) (xy 333.566262 -265.729974) (xy 333.562452 -265.77417)
			(xy 333.653384 -265.882628)
		)
		(stroke
			(width 0)
			(type solid)
		)
		(fill yes)
		(layer "In11.Cu")
		(net "M_F_CPU0_SB_CS_N<0>")
	)
	(gr_poly
		(pts
			(xy 333.761588 -264.171684) (xy 333.765398 -264.127234) (xy 333.566262 -264.109962) (xy 333.562452 -264.154158)
			(xy 333.653384 -264.262616)
		)
		(stroke
			(width 0)
			(type solid)
		)
		(fill yes)
		(layer "In11.Cu")
		(net "M_F_CPU0_SB_CA<5>")
	)
	(gr_poly
		(pts
			(xy 333.761588 -262.551672) (xy 333.765398 -262.507222) (xy 333.566262 -262.48995) (xy 333.562452 -262.534146)
			(xy 333.653384 -262.642604)
		)
		(stroke
			(width 0)
			(type solid)
		)
		(fill yes)
		(layer "In11.Cu")
		(net "M_F_CPU0_SB_CA<1>")
	)
	(gr_poly
		(pts
			(xy 333.761842 -288.471864) (xy 333.765652 -288.427414) (xy 333.566516 -288.410142) (xy 333.562452 -288.454338)
			(xy 333.653384 -288.562542)
		)
		(stroke
			(width 0)
			(type solid)
		)
		(fill yes)
		(layer "In11.Cu")
		(net "M_F_CPU0_SB_DQ<23>")
	)
	(gr_poly
		(pts
			(xy 386.173472 -255.226058) (xy 386.08254 -255.1176) (xy 385.974336 -255.208532) (xy 385.970526 -255.252982)
			(xy 386.169662 -255.270254)
		)
		(stroke
			(width 0)
			(type solid)
		)
		(fill yes)
		(layer "In11.Cu")
		(net "M_L_CPU0_SA_CA<6>")
	)
	(gr_poly
		(pts
			(xy 386.173472 -253.606046) (xy 386.08254 -253.497588) (xy 385.974336 -253.58852) (xy 385.970526 -253.63297)
			(xy 386.169662 -253.650242)
		)
		(stroke
			(width 0)
			(type solid)
		)
		(fill yes)
		(layer "In11.Cu")
		(net "M_L_CPU0_SA_CA<2>")
	)
	(gr_poly
		(pts
			(xy 386.173472 -250.366022) (xy 386.08254 -250.257564) (xy 385.974336 -250.348496) (xy 385.970526 -250.392946)
			(xy 386.169662 -250.410218)
		)
		(stroke
			(width 0)
			(type solid)
		)
		(fill yes)
		(layer "In11.Cu")
		(net "M_L_CPU0_ALERT_R_N")
	)
	(gr_poly
		(pts
			(xy 386.173472 -248.74601) (xy 386.08254 -248.637552) (xy 385.974336 -248.728484) (xy 385.970526 -248.772934)
			(xy 386.169662 -248.790206)
		)
		(stroke
			(width 0)
			(type solid)
		)
		(fill yes)
		(layer "In11.Cu")
		(net "M_L_CPU0_SA_CB<5>")
	)
	(gr_poly
		(pts
			(xy 386.173472 -245.505986) (xy 386.08254 -245.397528) (xy 385.974336 -245.48846) (xy 385.970526 -245.53291)
			(xy 386.169662 -245.550182)
		)
		(stroke
			(width 0)
			(type solid)
		)
		(fill yes)
		(layer "In11.Cu")
		(net "M_L_CPU0_SA_CB<1>")
	)
	(gr_poly
		(pts
			(xy 386.173472 -243.885974) (xy 386.08254 -243.777516) (xy 385.974336 -243.868448) (xy 385.970526 -243.912898)
			(xy 386.169662 -243.93017)
		)
		(stroke
			(width 0)
			(type solid)
		)
		(fill yes)
		(layer "In11.Cu")
		(net "M_L_CPU0_SA_DQ<29>")
	)
	(gr_poly
		(pts
			(xy 386.173472 -240.64595) (xy 386.08254 -240.537492) (xy 385.974336 -240.628424) (xy 385.970526 -240.672874)
			(xy 386.169662 -240.690146)
		)
		(stroke
			(width 0)
			(type solid)
		)
		(fill yes)
		(layer "In11.Cu")
		(net "M_L_CPU0_SA_DQ<25>")
	)
	(gr_poly
		(pts
			(xy 386.173472 -239.025938) (xy 386.08254 -238.91748) (xy 385.974336 -239.008412) (xy 385.970526 -239.052862)
			(xy 386.169662 -239.070134)
		)
		(stroke
			(width 0)
			(type solid)
		)
		(fill yes)
		(layer "In11.Cu")
		(net "M_L_CPU0_SA_DQ<21>")
	)
	(gr_poly
		(pts
			(xy 386.173472 -235.785914) (xy 386.08254 -235.677456) (xy 385.974336 -235.768388) (xy 385.970526 -235.812838)
			(xy 386.169662 -235.83011)
		)
		(stroke
			(width 0)
			(type solid)
		)
		(fill yes)
		(layer "In11.Cu")
		(net "M_L_CPU0_SA_DQ<17>")
	)
	(gr_poly
		(pts
			(xy 386.173472 -234.165902) (xy 386.08254 -234.057444) (xy 385.974336 -234.148376) (xy 385.970526 -234.192826)
			(xy 386.169662 -234.210098)
		)
		(stroke
			(width 0)
			(type solid)
		)
		(fill yes)
		(layer "In11.Cu")
		(net "M_L_CPU0_SA_DQ<13>")
	)
	(gr_poly
		(pts
			(xy 386.173472 -230.925878) (xy 386.08254 -230.817674) (xy 385.974082 -230.908352) (xy 385.970272 -230.952802)
			(xy 386.169408 -230.970074)
		)
		(stroke
			(width 0)
			(type solid)
		)
		(fill yes)
		(layer "In11.Cu")
		(net "M_L_CPU0_SA_DQ<9>")
	)
	(gr_poly
		(pts
			(xy 386.173472 -229.305866) (xy 386.08254 -229.197662) (xy 385.974082 -229.28834) (xy 385.970272 -229.33279)
			(xy 386.169408 -229.350062)
		)
		(stroke
			(width 0)
			(type solid)
		)
		(fill yes)
		(layer "In11.Cu")
		(net "M_L_CPU0_SA_DQ<5>")
	)
	(gr_poly
		(pts
			(xy 386.173472 -226.066096) (xy 386.08254 -225.957638) (xy 385.974336 -226.04857) (xy 385.970526 -226.09302)
			(xy 386.169662 -226.110292)
		)
		(stroke
			(width 0)
			(type solid)
		)
		(fill yes)
		(layer "In11.Cu")
		(net "M_L_CPU0_SA_DQ<1>")
	)
	(gr_poly
		(pts
			(xy 386.175504 -247.125998) (xy 386.084572 -247.01754) (xy 385.976368 -247.108472) (xy 385.97205 -247.15597)
			(xy 386.17144 -247.173496)
		)
		(stroke
			(width 0)
			(type solid)
		)
		(fill yes)
		(layer "In11.Cu")
		(net "M_L_CPU0_SA_DQS_DN<9>")
	)
	(gr_poly
		(pts
			(xy 386.175504 -242.265962) (xy 386.084572 -242.157504) (xy 385.976368 -242.248436) (xy 385.97205 -242.295934)
			(xy 386.17144 -242.31346)
		)
		(stroke
			(width 0)
			(type solid)
		)
		(fill yes)
		(layer "In11.Cu")
		(net "M_L_CPU0_SA_DQS_DN<8>")
	)
	(gr_poly
		(pts
			(xy 386.175504 -237.405926) (xy 386.084572 -237.297468) (xy 385.976368 -237.3884) (xy 385.97205 -237.435898)
			(xy 386.17144 -237.45317)
		)
		(stroke
			(width 0)
			(type solid)
		)
		(fill yes)
		(layer "In11.Cu")
		(net "M_L_CPU0_SA_DQS_DN<7>")
	)
	(gr_poly
		(pts
			(xy 386.175504 -232.54589) (xy 386.084572 -232.437432) (xy 385.976368 -232.528364) (xy 385.97205 -232.575862)
			(xy 386.17144 -232.593134)
		)
		(stroke
			(width 0)
			(type solid)
		)
		(fill yes)
		(layer "In11.Cu")
		(net "M_L_CPU0_SA_DQS_DN<6>")
	)
	(gr_poly
		(pts
			(xy 386.175504 -227.686108) (xy 386.084572 -227.57765) (xy 385.976368 -227.668582) (xy 385.97205 -227.71608)
			(xy 386.17144 -227.733352)
		)
		(stroke
			(width 0)
			(type solid)
		)
		(fill yes)
		(layer "In11.Cu")
		(net "M_L_CPU0_SA_DQS_DN<5>")
	)
	(gr_poly
		(pts
			(xy 386.176012 -251.979684) (xy 386.08508 -251.87148) (xy 385.976622 -251.962412) (xy 385.972812 -252.006608)
			(xy 386.172202 -252.024134)
		)
		(stroke
			(width 0)
			(type solid)
		)
		(fill yes)
		(layer "In11.Cu")
		(net "M_L_CPU0_SA_CS_N<1>")
	)
	(gr_poly
		(pts
			(xy 386.473446 -290.074096) (xy 386.469636 -290.0299) (xy 386.270246 -290.047172) (xy 386.27431 -290.091622)
			(xy 386.382514 -290.182554)
		)
		(stroke
			(width 0)
			(type solid)
		)
		(fill yes)
		(layer "In11.Cu")
		(net "M_L_CPU0_SB_DQ<27>")
	)
	(gr_poly
		(pts
			(xy 386.473446 -288.454338) (xy 386.469382 -288.410142) (xy 386.270246 -288.427414) (xy 386.274056 -288.471864)
			(xy 386.382514 -288.562542)
		)
		(stroke
			(width 0)
			(type solid)
		)
		(fill yes)
		(layer "In11.Cu")
		(net "M_L_CPU0_SB_DQ<23>")
	)
	(gr_poly
		(pts
			(xy 386.473446 -285.214314) (xy 386.469636 -285.170118) (xy 386.270246 -285.18739) (xy 386.27431 -285.23184)
			(xy 386.382514 -285.322772)
		)
		(stroke
			(width 0)
			(type solid)
		)
		(fill yes)
		(layer "In11.Cu")
		(net "M_L_CPU0_SB_DQ<19>")
	)
	(gr_poly
		(pts
			(xy 386.473446 -283.594302) (xy 386.469636 -283.550106) (xy 386.270246 -283.567378) (xy 386.27431 -283.611828)
			(xy 386.382514 -283.70276)
		)
		(stroke
			(width 0)
			(type solid)
		)
		(fill yes)
		(layer "In11.Cu")
		(net "M_L_CPU0_SB_DQ<15>")
	)
	(gr_poly
		(pts
			(xy 386.473446 -280.354278) (xy 386.469636 -280.310082) (xy 386.270246 -280.327354) (xy 386.27431 -280.371804)
			(xy 386.382514 -280.462736)
		)
		(stroke
			(width 0)
			(type solid)
		)
		(fill yes)
		(layer "In11.Cu")
		(net "M_L_CPU0_SB_DQ<11>")
	)
	(gr_poly
		(pts
			(xy 386.473446 -278.734266) (xy 386.469636 -278.69007) (xy 386.270246 -278.707342) (xy 386.27431 -278.751792)
			(xy 386.382514 -278.842724)
		)
		(stroke
			(width 0)
			(type solid)
		)
		(fill yes)
		(layer "In11.Cu")
		(net "M_L_CPU0_SB_DQ<7>")
	)
	(gr_poly
		(pts
			(xy 386.473446 -275.494242) (xy 386.469636 -275.450046) (xy 386.270246 -275.467318) (xy 386.27431 -275.511768)
			(xy 386.382514 -275.6027)
		)
		(stroke
			(width 0)
			(type solid)
		)
		(fill yes)
		(layer "In11.Cu")
		(net "M_L_CPU0_SB_DQ<3>")
	)
	(gr_poly
		(pts
			(xy 386.473446 -273.87423) (xy 386.469636 -273.830034) (xy 386.270246 -273.847306) (xy 386.27431 -273.891756)
			(xy 386.382514 -273.982688)
		)
		(stroke
			(width 0)
			(type solid)
		)
		(fill yes)
		(layer "In11.Cu")
		(net "M_L_CPU0_SB_CB<3>")
	)
	(gr_poly
		(pts
			(xy 386.473446 -270.634206) (xy 386.469636 -270.59001) (xy 386.270246 -270.607282) (xy 386.27431 -270.651732)
			(xy 386.382514 -270.742664)
		)
		(stroke
			(width 0)
			(type solid)
		)
		(fill yes)
		(layer "In11.Cu")
		(net "M_L_CPU0_SB_CB<7>")
	)
	(gr_poly
		(pts
			(xy 386.473446 -265.77417) (xy 386.469636 -265.729974) (xy 386.270246 -265.747246) (xy 386.27431 -265.791696)
			(xy 386.382514 -265.882628)
		)
		(stroke
			(width 0)
			(type solid)
		)
		(fill yes)
		(layer "In11.Cu")
		(net "M_L_CPU0_SB_CS_N<0>")
	)
	(gr_poly
		(pts
			(xy 386.473446 -264.154158) (xy 386.469636 -264.109962) (xy 386.270246 -264.127234) (xy 386.27431 -264.171684)
			(xy 386.382514 -264.262616)
		)
		(stroke
			(width 0)
			(type solid)
		)
		(fill yes)
		(layer "In11.Cu")
		(net "M_L_CPU0_SB_CA<5>")
	)
	(gr_poly
		(pts
			(xy 386.473446 -262.534146) (xy 386.469636 -262.48995) (xy 386.270246 -262.507222) (xy 386.27431 -262.551672)
			(xy 386.382514 -262.642604)
		)
		(stroke
			(width 0)
			(type solid)
		)
		(fill yes)
		(layer "In11.Cu")
		(net "M_L_CPU0_SB_CA<1>")
	)
	(gr_poly
		(pts
			(xy 386.4864 -291.693346) (xy 386.482336 -291.645848) (xy 386.282946 -291.663374) (xy 386.287264 -291.710872)
			(xy 386.395468 -291.80155)
		)
		(stroke
			(width 0)
			(type solid)
		)
		(fill yes)
		(layer "In11.Cu")
		(net "M_L_CPU0_SB_DQS_DP<8>")
	)
	(gr_poly
		(pts
			(xy 386.4864 -286.83331) (xy 386.482336 -286.786066) (xy 386.282946 -286.803338) (xy 386.287264 -286.850836)
			(xy 386.395468 -286.941768)
		)
		(stroke
			(width 0)
			(type solid)
		)
		(fill yes)
		(layer "In11.Cu")
		(net "M_L_CPU0_SB_DQS_DP<7>")
	)
	(gr_poly
		(pts
			(xy 386.4864 -281.973528) (xy 386.482336 -281.92603) (xy 386.282946 -281.943556) (xy 386.287264 -281.9908)
			(xy 386.395468 -282.081732)
		)
		(stroke
			(width 0)
			(type solid)
		)
		(fill yes)
		(layer "In11.Cu")
		(net "M_L_CPU0_SB_DQS_DP<6>")
	)
	(gr_poly
		(pts
			(xy 386.4864 -277.113492) (xy 386.482336 -277.065994) (xy 386.282946 -277.08352) (xy 386.287264 -277.130764)
			(xy 386.395468 -277.221696)
		)
		(stroke
			(width 0)
			(type solid)
		)
		(fill yes)
		(layer "In11.Cu")
		(net "M_L_CPU0_SB_DQS_DP<5>")
	)
	(gr_poly
		(pts
			(xy 386.4864 -272.253456) (xy 386.482336 -272.205958) (xy 386.282946 -272.223484) (xy 386.287264 -272.270728)
			(xy 386.395468 -272.36166)
		)
		(stroke
			(width 0)
			(type solid)
		)
		(fill yes)
		(layer "In11.Cu")
		(net "M_L_CPU0_SB_DQS_DP<4>")
	)
	(gr_poly
		(pts
			(xy 386.605018 -255.622298) (xy 386.605018 -255.577848) (xy 386.404866 -255.577848) (xy 386.404866 -255.622298)
			(xy 386.504942 -255.722374)
		)
		(stroke
			(width 0)
			(type solid)
		)
		(fill yes)
		(layer "In11.Cu")
		(net "M_L_CPU0_SA_PAR")
	)
	(gr_poly
		(pts
			(xy 386.605018 -254.002286) (xy 386.605018 -253.957836) (xy 386.404866 -253.957836) (xy 386.404866 -254.002286)
			(xy 386.504942 -254.102362)
		)
		(stroke
			(width 0)
			(type solid)
		)
		(fill yes)
		(layer "In11.Cu")
		(net "M_L_CPU0_SA_CA<3>")
	)
	(gr_poly
		(pts
			(xy 386.605018 -250.762262) (xy 386.605018 -250.717812) (xy 386.404866 -250.717812) (xy 386.404866 -250.762262)
			(xy 386.504942 -250.862338)
		)
		(stroke
			(width 0)
			(type solid)
		)
		(fill yes)
		(layer "In11.Cu")
		(net "M_L_CPU0_RESET_N")
	)
	(gr_poly
		(pts
			(xy 386.605018 -249.14225) (xy 386.605018 -249.0978) (xy 386.404866 -249.0978) (xy 386.404866 -249.14225)
			(xy 386.504942 -249.242326)
		)
		(stroke
			(width 0)
			(type solid)
		)
		(fill yes)
		(layer "In11.Cu")
		(net "M_L_CPU0_SA_CB<7>")
	)
	(gr_poly
		(pts
			(xy 386.605018 -247.522492) (xy 386.605018 -247.47474) (xy 386.404866 -247.47474) (xy 386.404866 -247.522492)
			(xy 386.504942 -247.622314)
		)
		(stroke
			(width 0)
			(type solid)
		)
		(fill yes)
		(layer "In11.Cu")
		(net "M_L_CPU0_SA_DQS_DP<9>")
	)
	(gr_poly
		(pts
			(xy 386.605018 -245.902226) (xy 386.605018 -245.857776) (xy 386.404866 -245.857776) (xy 386.404866 -245.902226)
			(xy 386.504942 -246.002302)
		)
		(stroke
			(width 0)
			(type solid)
		)
		(fill yes)
		(layer "In11.Cu")
		(net "M_L_CPU0_SA_CB<3>")
	)
	(gr_poly
		(pts
			(xy 386.605018 -244.282214) (xy 386.605018 -244.237764) (xy 386.404866 -244.237764) (xy 386.404866 -244.282214)
			(xy 386.504942 -244.38229)
		)
		(stroke
			(width 0)
			(type solid)
		)
		(fill yes)
		(layer "In11.Cu")
		(net "M_L_CPU0_SA_DQ<31>")
	)
	(gr_poly
		(pts
			(xy 386.605018 -242.662456) (xy 386.605018 -242.614704) (xy 386.404866 -242.614704) (xy 386.404866 -242.662456)
			(xy 386.504942 -242.762278)
		)
		(stroke
			(width 0)
			(type solid)
		)
		(fill yes)
		(layer "In11.Cu")
		(net "M_L_CPU0_SA_DQS_DP<8>")
	)
	(gr_poly
		(pts
			(xy 386.605018 -241.04219) (xy 386.605018 -240.99774) (xy 386.404866 -240.99774) (xy 386.404866 -241.04219)
			(xy 386.504942 -241.142266)
		)
		(stroke
			(width 0)
			(type solid)
		)
		(fill yes)
		(layer "In11.Cu")
		(net "M_L_CPU0_SA_DQ<27>")
	)
	(gr_poly
		(pts
			(xy 386.605018 -239.422178) (xy 386.605018 -239.377728) (xy 386.404866 -239.377728) (xy 386.404866 -239.422178)
			(xy 386.504942 -239.522254)
		)
		(stroke
			(width 0)
			(type solid)
		)
		(fill yes)
		(layer "In11.Cu")
		(net "M_L_CPU0_SA_DQ<23>")
	)
	(gr_poly
		(pts
			(xy 386.605018 -237.80242) (xy 386.605018 -237.754668) (xy 386.404866 -237.754668) (xy 386.404866 -237.80242)
			(xy 386.504942 -237.902242)
		)
		(stroke
			(width 0)
			(type solid)
		)
		(fill yes)
		(layer "In11.Cu")
		(net "M_L_CPU0_SA_DQS_DP<7>")
	)
	(gr_poly
		(pts
			(xy 386.605018 -236.182154) (xy 386.605018 -236.137704) (xy 386.404866 -236.137704) (xy 386.404866 -236.182154)
			(xy 386.504942 -236.28223)
		)
		(stroke
			(width 0)
			(type solid)
		)
		(fill yes)
		(layer "In11.Cu")
		(net "M_L_CPU0_SA_DQ<19>")
	)
	(gr_poly
		(pts
			(xy 386.605018 -234.562142) (xy 386.605018 -234.517692) (xy 386.404866 -234.517692) (xy 386.404866 -234.562142)
			(xy 386.504942 -234.662218)
		)
		(stroke
			(width 0)
			(type solid)
		)
		(fill yes)
		(layer "In11.Cu")
		(net "M_L_CPU0_SA_DQ<15>")
	)
	(gr_poly
		(pts
			(xy 386.605018 -232.942384) (xy 386.605018 -232.894632) (xy 386.404866 -232.894632) (xy 386.404866 -232.942384)
			(xy 386.504942 -233.042206)
		)
		(stroke
			(width 0)
			(type solid)
		)
		(fill yes)
		(layer "In11.Cu")
		(net "M_L_CPU0_SA_DQS_DP<6>")
	)
	(gr_poly
		(pts
			(xy 386.605018 -231.322372) (xy 386.605018 -231.277922) (xy 386.404866 -231.277922) (xy 386.404866 -231.322372)
			(xy 386.504942 -231.422448)
		)
		(stroke
			(width 0)
			(type solid)
		)
		(fill yes)
		(layer "In11.Cu")
		(net "M_L_CPU0_SA_DQ<11>")
	)
	(gr_poly
		(pts
			(xy 386.605018 -229.70236) (xy 386.605018 -229.65791) (xy 386.404866 -229.65791) (xy 386.404866 -229.70236)
			(xy 386.504942 -229.802436)
		)
		(stroke
			(width 0)
			(type solid)
		)
		(fill yes)
		(layer "In11.Cu")
		(net "M_L_CPU0_SA_DQ<7>")
	)
	(gr_poly
		(pts
			(xy 386.605018 -228.082602) (xy 386.605018 -228.03485) (xy 386.404866 -228.03485) (xy 386.404866 -228.082602)
			(xy 386.504942 -228.182424)
		)
		(stroke
			(width 0)
			(type solid)
		)
		(fill yes)
		(layer "In11.Cu")
		(net "M_L_CPU0_SA_DQS_DP<5>")
	)
	(gr_poly
		(pts
			(xy 386.605018 -226.462336) (xy 386.605018 -226.417886) (xy 386.404866 -226.417886) (xy 386.404866 -226.462336)
			(xy 386.504942 -226.562412)
		)
		(stroke
			(width 0)
			(type solid)
		)
		(fill yes)
		(layer "In11.Cu")
		(net "M_L_CPU0_SA_DQ<3>")
	)
	(gr_poly
		(pts
			(xy 386.904992 -291.297614) (xy 386.804916 -291.197792) (xy 386.70484 -291.297614) (xy 386.70484 -291.345366)
			(xy 386.904992 -291.345366)
		)
		(stroke
			(width 0)
			(type solid)
		)
		(fill yes)
		(layer "In11.Cu")
		(net "M_L_CPU0_SB_DQS_DN<8>")
	)
	(gr_poly
		(pts
			(xy 386.904992 -289.677856) (xy 386.804916 -289.57778) (xy 386.70484 -289.677856) (xy 386.70484 -289.722306)
			(xy 386.904992 -289.722306)
		)
		(stroke
			(width 0)
			(type solid)
		)
		(fill yes)
		(layer "In11.Cu")
		(net "M_L_CPU0_SB_DQ<25>")
	)
	(gr_poly
		(pts
			(xy 386.904992 -288.057844) (xy 386.804916 -287.957768) (xy 386.70484 -288.057844) (xy 386.70484 -288.102294)
			(xy 386.904992 -288.102294)
		)
		(stroke
			(width 0)
			(type solid)
		)
		(fill yes)
		(layer "In11.Cu")
		(net "M_L_CPU0_SB_DQ<21>")
	)
	(gr_poly
		(pts
			(xy 386.904992 -286.437832) (xy 386.804916 -286.337756) (xy 386.70484 -286.437832) (xy 386.70484 -286.485584)
			(xy 386.904992 -286.485584)
		)
		(stroke
			(width 0)
			(type solid)
		)
		(fill yes)
		(layer "In11.Cu")
		(net "M_L_CPU0_SB_DQS_DN<7>")
	)
	(gr_poly
		(pts
			(xy 386.904992 -284.818074) (xy 386.804916 -284.717998) (xy 386.70484 -284.818074) (xy 386.70484 -284.862524)
			(xy 386.904992 -284.862524)
		)
		(stroke
			(width 0)
			(type solid)
		)
		(fill yes)
		(layer "In11.Cu")
		(net "M_L_CPU0_SB_DQ<17>")
	)
	(gr_poly
		(pts
			(xy 386.904992 -283.198062) (xy 386.804916 -283.097986) (xy 386.70484 -283.198062) (xy 386.70484 -283.242512)
			(xy 386.904992 -283.242512)
		)
		(stroke
			(width 0)
			(type solid)
		)
		(fill yes)
		(layer "In11.Cu")
		(net "M_L_CPU0_SB_DQ<13>")
	)
	(gr_poly
		(pts
			(xy 386.904992 -281.577796) (xy 386.804916 -281.477974) (xy 386.70484 -281.577796) (xy 386.70484 -281.625548)
			(xy 386.904992 -281.625548)
		)
		(stroke
			(width 0)
			(type solid)
		)
		(fill yes)
		(layer "In11.Cu")
		(net "M_L_CPU0_SB_DQS_DN<6>")
	)
	(gr_poly
		(pts
			(xy 386.904992 -279.958038) (xy 386.804916 -279.857962) (xy 386.70484 -279.958038) (xy 386.70484 -280.002488)
			(xy 386.904992 -280.002488)
		)
		(stroke
			(width 0)
			(type solid)
		)
		(fill yes)
		(layer "In11.Cu")
		(net "M_L_CPU0_SB_DQ<9>")
	)
	(gr_poly
		(pts
			(xy 386.904992 -278.338026) (xy 386.804916 -278.23795) (xy 386.70484 -278.338026) (xy 386.70484 -278.382476)
			(xy 386.904992 -278.382476)
		)
		(stroke
			(width 0)
			(type solid)
		)
		(fill yes)
		(layer "In11.Cu")
		(net "M_L_CPU0_SB_DQ<5>")
	)
	(gr_poly
		(pts
			(xy 386.904992 -276.71776) (xy 386.804916 -276.617938) (xy 386.70484 -276.71776) (xy 386.70484 -276.765512)
			(xy 386.904992 -276.765512)
		)
		(stroke
			(width 0)
			(type solid)
		)
		(fill yes)
		(layer "In11.Cu")
		(net "M_L_CPU0_SB_DQS_DN<5>")
	)
	(gr_poly
		(pts
			(xy 386.904992 -275.098002) (xy 386.804916 -274.997926) (xy 386.70484 -275.098002) (xy 386.70484 -275.142452)
			(xy 386.904992 -275.142452)
		)
		(stroke
			(width 0)
			(type solid)
		)
		(fill yes)
		(layer "In11.Cu")
		(net "M_L_CPU0_SB_DQ<1>")
	)
	(gr_poly
		(pts
			(xy 386.904992 -273.47799) (xy 386.804916 -273.377914) (xy 386.70484 -273.47799) (xy 386.70484 -273.52244)
			(xy 386.904992 -273.52244)
		)
		(stroke
			(width 0)
			(type solid)
		)
		(fill yes)
		(layer "In11.Cu")
		(net "M_L_CPU0_SB_CB<1>")
	)
	(gr_poly
		(pts
			(xy 386.904992 -271.857724) (xy 386.804916 -271.757902) (xy 386.70484 -271.857724) (xy 386.70484 -271.905476)
			(xy 386.904992 -271.905476)
		)
		(stroke
			(width 0)
			(type solid)
		)
		(fill yes)
		(layer "In11.Cu")
		(net "M_L_CPU0_SB_DQS_DN<4>")
	)
	(gr_poly
		(pts
			(xy 386.904992 -270.237966) (xy 386.804916 -270.13789) (xy 386.70484 -270.237966) (xy 386.70484 -270.282416)
			(xy 386.904992 -270.282416)
		)
		(stroke
			(width 0)
			(type solid)
		)
		(fill yes)
		(layer "In11.Cu")
		(net "M_L_CPU0_SB_CB<5>")
	)
	(gr_poly
		(pts
			(xy 386.904992 -266.997942) (xy 386.804916 -266.897866) (xy 386.70484 -266.997942) (xy 386.70484 -267.042392)
			(xy 386.904992 -267.042392)
		)
		(stroke
			(width 0)
			(type solid)
		)
		(fill yes)
		(layer "In11.Cu")
		(net "M_L_CPU0_SA_RSP<0>")
	)
	(gr_poly
		(pts
			(xy 386.904992 -265.37793) (xy 386.804916 -265.277854) (xy 386.70484 -265.37793) (xy 386.70484 -265.42238)
			(xy 386.904992 -265.42238)
		)
		(stroke
			(width 0)
			(type solid)
		)
		(fill yes)
		(layer "In11.Cu")
		(net "M_L_CPU0_SB_PAR")
	)
	(gr_poly
		(pts
			(xy 386.904992 -263.757918) (xy 386.804916 -263.657842) (xy 386.70484 -263.757918) (xy 386.70484 -263.802368)
			(xy 386.904992 -263.802368)
		)
		(stroke
			(width 0)
			(type solid)
		)
		(fill yes)
		(layer "In11.Cu")
		(net "M_L_CPU0_SB_CA<4>")
	)
	(gr_poly
		(pts
			(xy 386.904992 -262.137906) (xy 386.804916 -262.03783) (xy 386.70484 -262.137906) (xy 386.70484 -262.182356)
			(xy 386.904992 -262.182356)
		)
		(stroke
			(width 0)
			(type solid)
		)
		(fill yes)
		(layer "In11.Cu")
		(net "M_L_CPU0_SB_CA<0>")
	)
	(gr_poly
		(pts
			(xy 387.074918 -255.216152) (xy 386.974842 -255.116076) (xy 386.874766 -255.216152) (xy 386.874766 -255.260602)
			(xy 387.074918 -255.260602)
		)
		(stroke
			(width 0)
			(type solid)
		)
		(fill yes)
		(layer "In11.Cu")
		(net "M_L_CPU0_SA_CA<6>")
	)
	(gr_poly
		(pts
			(xy 387.074918 -253.59614) (xy 386.974842 -253.496064) (xy 386.874766 -253.59614) (xy 386.874766 -253.64059)
			(xy 387.074918 -253.64059)
		)
		(stroke
			(width 0)
			(type solid)
		)
		(fill yes)
		(layer "In11.Cu")
		(net "M_L_CPU0_SA_CA<2>")
	)
	(gr_poly
		(pts
			(xy 387.074918 -251.969778) (xy 386.974842 -251.869702) (xy 386.874766 -251.969778) (xy 386.874766 -252.014228)
			(xy 387.074918 -252.014228)
		)
		(stroke
			(width 0)
			(type solid)
		)
		(fill yes)
		(layer "In11.Cu")
		(net "M_L_CPU0_SA_CS_N<1>")
	)
	(gr_poly
		(pts
			(xy 387.074918 -250.356116) (xy 386.974842 -250.25604) (xy 386.874766 -250.356116) (xy 386.874766 -250.400566)
			(xy 387.074918 -250.400566)
		)
		(stroke
			(width 0)
			(type solid)
		)
		(fill yes)
		(layer "In11.Cu")
		(net "M_L_CPU0_ALERT_R_N")
	)
	(gr_poly
		(pts
			(xy 387.074918 -248.736104) (xy 386.974842 -248.636028) (xy 386.874766 -248.736104) (xy 386.874766 -248.780554)
			(xy 387.074918 -248.780554)
		)
		(stroke
			(width 0)
			(type solid)
		)
		(fill yes)
		(layer "In11.Cu")
		(net "M_L_CPU0_SA_CB<5>")
	)
	(gr_poly
		(pts
			(xy 387.074918 -247.115838) (xy 386.974842 -247.016016) (xy 386.874766 -247.115838) (xy 386.874766 -247.16359)
			(xy 387.074918 -247.16359)
		)
		(stroke
			(width 0)
			(type solid)
		)
		(fill yes)
		(layer "In11.Cu")
		(net "M_L_CPU0_SA_DQS_DN<9>")
	)
	(gr_poly
		(pts
			(xy 387.074918 -245.49608) (xy 386.974842 -245.396004) (xy 386.874766 -245.49608) (xy 386.874766 -245.54053)
			(xy 387.074918 -245.54053)
		)
		(stroke
			(width 0)
			(type solid)
		)
		(fill yes)
		(layer "In11.Cu")
		(net "M_L_CPU0_SA_CB<1>")
	)
	(gr_poly
		(pts
			(xy 387.074918 -243.876068) (xy 386.974842 -243.775992) (xy 386.874766 -243.876068) (xy 386.874766 -243.920518)
			(xy 387.074918 -243.920518)
		)
		(stroke
			(width 0)
			(type solid)
		)
		(fill yes)
		(layer "In11.Cu")
		(net "M_L_CPU0_SA_DQ<29>")
	)
	(gr_poly
		(pts
			(xy 387.074918 -242.255802) (xy 386.974842 -242.15598) (xy 386.874766 -242.255802) (xy 386.874766 -242.303554)
			(xy 387.074918 -242.303554)
		)
		(stroke
			(width 0)
			(type solid)
		)
		(fill yes)
		(layer "In11.Cu")
		(net "M_L_CPU0_SA_DQS_DN<8>")
	)
	(gr_poly
		(pts
			(xy 387.074918 -240.636044) (xy 386.974842 -240.535968) (xy 386.874766 -240.636044) (xy 386.874766 -240.680494)
			(xy 387.074918 -240.680494)
		)
		(stroke
			(width 0)
			(type solid)
		)
		(fill yes)
		(layer "In11.Cu")
		(net "M_L_CPU0_SA_DQ<25>")
	)
	(gr_poly
		(pts
			(xy 387.074918 -239.016032) (xy 386.974842 -238.915956) (xy 386.874766 -239.016032) (xy 386.874766 -239.060482)
			(xy 387.074918 -239.060482)
		)
		(stroke
			(width 0)
			(type solid)
		)
		(fill yes)
		(layer "In11.Cu")
		(net "M_L_CPU0_SA_DQ<21>")
	)
	(gr_poly
		(pts
			(xy 387.074918 -237.395766) (xy 386.974842 -237.295944) (xy 386.874766 -237.395766) (xy 386.874766 -237.443518)
			(xy 387.074918 -237.443518)
		)
		(stroke
			(width 0)
			(type solid)
		)
		(fill yes)
		(layer "In11.Cu")
		(net "M_L_CPU0_SA_DQS_DN<7>")
	)
	(gr_poly
		(pts
			(xy 387.074918 -235.776008) (xy 386.974842 -235.675932) (xy 386.874766 -235.776008) (xy 386.874766 -235.820458)
			(xy 387.074918 -235.820458)
		)
		(stroke
			(width 0)
			(type solid)
		)
		(fill yes)
		(layer "In11.Cu")
		(net "M_L_CPU0_SA_DQ<17>")
	)
	(gr_poly
		(pts
			(xy 387.074918 -234.155996) (xy 386.974842 -234.05592) (xy 386.874766 -234.155996) (xy 386.874766 -234.200446)
			(xy 387.074918 -234.200446)
		)
		(stroke
			(width 0)
			(type solid)
		)
		(fill yes)
		(layer "In11.Cu")
		(net "M_L_CPU0_SA_DQ<13>")
	)
	(gr_poly
		(pts
			(xy 387.074918 -232.53573) (xy 386.974842 -232.435908) (xy 386.874766 -232.53573) (xy 386.874766 -232.583482)
			(xy 387.074918 -232.583482)
		)
		(stroke
			(width 0)
			(type solid)
		)
		(fill yes)
		(layer "In11.Cu")
		(net "M_L_CPU0_SA_DQS_DN<6>")
	)
	(gr_poly
		(pts
			(xy 387.074918 -230.915972) (xy 386.974842 -230.815896) (xy 386.874766 -230.915972) (xy 386.874766 -230.960422)
			(xy 387.074918 -230.960422)
		)
		(stroke
			(width 0)
			(type solid)
		)
		(fill yes)
		(layer "In11.Cu")
		(net "M_L_CPU0_SA_DQ<9>")
	)
	(gr_poly
		(pts
			(xy 387.074918 -229.29596) (xy 386.974842 -229.195884) (xy 386.874766 -229.29596) (xy 386.874766 -229.34041)
			(xy 387.074918 -229.34041)
		)
		(stroke
			(width 0)
			(type solid)
		)
		(fill yes)
		(layer "In11.Cu")
		(net "M_L_CPU0_SA_DQ<5>")
	)
	(gr_poly
		(pts
			(xy 387.074918 -227.675948) (xy 386.974842 -227.576126) (xy 386.874766 -227.675948) (xy 386.874766 -227.7237)
			(xy 387.074918 -227.7237)
		)
		(stroke
			(width 0)
			(type solid)
		)
		(fill yes)
		(layer "In11.Cu")
		(net "M_L_CPU0_SA_DQS_DN<5>")
	)
	(gr_poly
		(pts
			(xy 387.074918 -226.05619) (xy 386.974842 -225.956114) (xy 386.874766 -226.05619) (xy 386.874766 -226.10064)
			(xy 387.074918 -226.10064)
		)
		(stroke
			(width 0)
			(type solid)
		)
		(fill yes)
		(layer "In11.Cu")
		(net "M_L_CPU0_SA_DQ<1>")
	)
	(gr_poly
		(pts
			(xy 387.374892 -291.704268) (xy 387.374892 -291.656516) (xy 387.17474 -291.656516) (xy 387.17474 -291.704268)
			(xy 387.274816 -291.80409)
		)
		(stroke
			(width 0)
			(type solid)
		)
		(fill yes)
		(layer "In11.Cu")
		(net "M_L_CPU0_SB_DQS_DP<8>")
	)
	(gr_poly
		(pts
			(xy 387.374892 -290.084002) (xy 387.374892 -290.039552) (xy 387.17474 -290.039552) (xy 387.17474 -290.084002)
			(xy 387.274816 -290.184078)
		)
		(stroke
			(width 0)
			(type solid)
		)
		(fill yes)
		(layer "In11.Cu")
		(net "M_L_CPU0_SB_DQ<27>")
	)
	(gr_poly
		(pts
			(xy 387.374892 -288.464244) (xy 387.374892 -288.419794) (xy 387.17474 -288.419794) (xy 387.17474 -288.464244)
			(xy 387.274816 -288.56432)
		)
		(stroke
			(width 0)
			(type solid)
		)
		(fill yes)
		(layer "In11.Cu")
		(net "M_L_CPU0_SB_DQ<23>")
	)
	(gr_poly
		(pts
			(xy 387.374892 -286.844232) (xy 387.374892 -286.79648) (xy 387.17474 -286.79648) (xy 387.17474 -286.844232)
			(xy 387.274816 -286.944308)
		)
		(stroke
			(width 0)
			(type solid)
		)
		(fill yes)
		(layer "In11.Cu")
		(net "M_L_CPU0_SB_DQS_DP<7>")
	)
	(gr_poly
		(pts
			(xy 387.374892 -285.22422) (xy 387.374892 -285.17977) (xy 387.17474 -285.17977) (xy 387.17474 -285.22422)
			(xy 387.274816 -285.324296)
		)
		(stroke
			(width 0)
			(type solid)
		)
		(fill yes)
		(layer "In11.Cu")
		(net "M_L_CPU0_SB_DQ<19>")
	)
	(gr_poly
		(pts
			(xy 387.374892 -283.604208) (xy 387.374892 -283.559758) (xy 387.17474 -283.559758) (xy 387.17474 -283.604208)
			(xy 387.274816 -283.704284)
		)
		(stroke
			(width 0)
			(type solid)
		)
		(fill yes)
		(layer "In11.Cu")
		(net "M_L_CPU0_SB_DQ<15>")
	)
	(gr_poly
		(pts
			(xy 387.374892 -281.98445) (xy 387.374892 -281.936698) (xy 387.17474 -281.936698) (xy 387.17474 -281.98445)
			(xy 387.274816 -282.084272)
		)
		(stroke
			(width 0)
			(type solid)
		)
		(fill yes)
		(layer "In11.Cu")
		(net "M_L_CPU0_SB_DQS_DP<6>")
	)
	(gr_poly
		(pts
			(xy 387.374892 -280.364184) (xy 387.374892 -280.319734) (xy 387.17474 -280.319734) (xy 387.17474 -280.364184)
			(xy 387.274816 -280.46426)
		)
		(stroke
			(width 0)
			(type solid)
		)
		(fill yes)
		(layer "In11.Cu")
		(net "M_L_CPU0_SB_DQ<11>")
	)
	(gr_poly
		(pts
			(xy 387.374892 -278.744172) (xy 387.374892 -278.699722) (xy 387.17474 -278.699722) (xy 387.17474 -278.744172)
			(xy 387.274816 -278.844248)
		)
		(stroke
			(width 0)
			(type solid)
		)
		(fill yes)
		(layer "In11.Cu")
		(net "M_L_CPU0_SB_DQ<7>")
	)
	(gr_poly
		(pts
			(xy 387.374892 -277.124414) (xy 387.374892 -277.076662) (xy 387.17474 -277.076662) (xy 387.17474 -277.124414)
			(xy 387.274816 -277.224236)
		)
		(stroke
			(width 0)
			(type solid)
		)
		(fill yes)
		(layer "In11.Cu")
		(net "M_L_CPU0_SB_DQS_DP<5>")
	)
	(gr_poly
		(pts
			(xy 387.374892 -275.504148) (xy 387.374892 -275.459698) (xy 387.17474 -275.459698) (xy 387.17474 -275.504148)
			(xy 387.274816 -275.604224)
		)
		(stroke
			(width 0)
			(type solid)
		)
		(fill yes)
		(layer "In11.Cu")
		(net "M_L_CPU0_SB_DQ<3>")
	)
	(gr_poly
		(pts
			(xy 387.374892 -273.884136) (xy 387.374892 -273.839686) (xy 387.17474 -273.839686) (xy 387.17474 -273.884136)
			(xy 387.274816 -273.984212)
		)
		(stroke
			(width 0)
			(type solid)
		)
		(fill yes)
		(layer "In11.Cu")
		(net "M_L_CPU0_SB_CB<3>")
	)
	(gr_poly
		(pts
			(xy 387.374892 -272.264378) (xy 387.374892 -272.216626) (xy 387.17474 -272.216626) (xy 387.17474 -272.264378)
			(xy 387.274816 -272.3642)
		)
		(stroke
			(width 0)
			(type solid)
		)
		(fill yes)
		(layer "In11.Cu")
		(net "M_L_CPU0_SB_DQS_DP<4>")
	)
	(gr_poly
		(pts
			(xy 387.374892 -270.644112) (xy 387.374892 -270.599662) (xy 387.17474 -270.599662) (xy 387.17474 -270.644112)
			(xy 387.274816 -270.744188)
		)
		(stroke
			(width 0)
			(type solid)
		)
		(fill yes)
		(layer "In11.Cu")
		(net "M_L_CPU0_SB_CB<7>")
	)
	(gr_poly
		(pts
			(xy 387.374892 -265.784076) (xy 387.374892 -265.739626) (xy 387.17474 -265.739626) (xy 387.17474 -265.784076)
			(xy 387.274816 -265.884152)
		)
		(stroke
			(width 0)
			(type solid)
		)
		(fill yes)
		(layer "In11.Cu")
		(net "M_L_CPU0_SB_CS_N<0>")
	)
	(gr_poly
		(pts
			(xy 387.374892 -264.164064) (xy 387.374892 -264.119614) (xy 387.17474 -264.119614) (xy 387.17474 -264.164064)
			(xy 387.274816 -264.26414)
		)
		(stroke
			(width 0)
			(type solid)
		)
		(fill yes)
		(layer "In11.Cu")
		(net "M_L_CPU0_SB_CA<5>")
	)
	(gr_poly
		(pts
			(xy 387.374892 -262.544052) (xy 387.374892 -262.499602) (xy 387.17474 -262.499602) (xy 387.17474 -262.544052)
			(xy 387.274816 -262.644128)
		)
		(stroke
			(width 0)
			(type solid)
		)
		(fill yes)
		(layer "In11.Cu")
		(net "M_L_CPU0_SB_CA<1>")
	)
	(gr_poly
		(pts
			(xy 387.544818 -255.622298) (xy 387.544818 -255.577848) (xy 387.344666 -255.577848) (xy 387.344666 -255.622298)
			(xy 387.444742 -255.722374)
		)
		(stroke
			(width 0)
			(type solid)
		)
		(fill yes)
		(layer "In11.Cu")
		(net "M_L_CPU0_SA_PAR")
	)
	(gr_poly
		(pts
			(xy 387.544818 -254.002286) (xy 387.544818 -253.957836) (xy 387.344666 -253.957836) (xy 387.344666 -254.002286)
			(xy 387.444742 -254.102362)
		)
		(stroke
			(width 0)
			(type solid)
		)
		(fill yes)
		(layer "In11.Cu")
		(net "M_L_CPU0_SA_CA<3>")
	)
	(gr_poly
		(pts
			(xy 387.544818 -250.762262) (xy 387.544818 -250.717812) (xy 387.344666 -250.717812) (xy 387.344666 -250.762262)
			(xy 387.444742 -250.862338)
		)
		(stroke
			(width 0)
			(type solid)
		)
		(fill yes)
		(layer "In11.Cu")
		(net "M_L_CPU0_RESET_N")
	)
	(gr_poly
		(pts
			(xy 387.544818 -249.14225) (xy 387.544818 -249.0978) (xy 387.344666 -249.0978) (xy 387.344666 -249.14225)
			(xy 387.444742 -249.242326)
		)
		(stroke
			(width 0)
			(type solid)
		)
		(fill yes)
		(layer "In11.Cu")
		(net "M_L_CPU0_SA_CB<7>")
	)
	(gr_poly
		(pts
			(xy 387.544818 -247.522492) (xy 387.544818 -247.47474) (xy 387.344666 -247.47474) (xy 387.344666 -247.522492)
			(xy 387.444742 -247.622314)
		)
		(stroke
			(width 0)
			(type solid)
		)
		(fill yes)
		(layer "In11.Cu")
		(net "M_L_CPU0_SA_DQS_DP<9>")
	)
	(gr_poly
		(pts
			(xy 387.544818 -245.902226) (xy 387.544818 -245.857776) (xy 387.344666 -245.857776) (xy 387.344666 -245.902226)
			(xy 387.444742 -246.002302)
		)
		(stroke
			(width 0)
			(type solid)
		)
		(fill yes)
		(layer "In11.Cu")
		(net "M_L_CPU0_SA_CB<3>")
	)
	(gr_poly
		(pts
			(xy 387.544818 -244.282214) (xy 387.544818 -244.237764) (xy 387.344666 -244.237764) (xy 387.344666 -244.282214)
			(xy 387.444742 -244.38229)
		)
		(stroke
			(width 0)
			(type solid)
		)
		(fill yes)
		(layer "In11.Cu")
		(net "M_L_CPU0_SA_DQ<31>")
	)
	(gr_poly
		(pts
			(xy 387.544818 -242.662456) (xy 387.544818 -242.614704) (xy 387.344666 -242.614704) (xy 387.344666 -242.662456)
			(xy 387.444742 -242.762278)
		)
		(stroke
			(width 0)
			(type solid)
		)
		(fill yes)
		(layer "In11.Cu")
		(net "M_L_CPU0_SA_DQS_DP<8>")
	)
	(gr_poly
		(pts
			(xy 387.544818 -241.04219) (xy 387.544818 -240.99774) (xy 387.344666 -240.99774) (xy 387.344666 -241.04219)
			(xy 387.444742 -241.142266)
		)
		(stroke
			(width 0)
			(type solid)
		)
		(fill yes)
		(layer "In11.Cu")
		(net "M_L_CPU0_SA_DQ<27>")
	)
	(gr_poly
		(pts
			(xy 387.544818 -239.422178) (xy 387.544818 -239.377728) (xy 387.344666 -239.377728) (xy 387.344666 -239.422178)
			(xy 387.444742 -239.522254)
		)
		(stroke
			(width 0)
			(type solid)
		)
		(fill yes)
		(layer "In11.Cu")
		(net "M_L_CPU0_SA_DQ<23>")
	)
	(gr_poly
		(pts
			(xy 387.544818 -237.80242) (xy 387.544818 -237.754668) (xy 387.344666 -237.754668) (xy 387.344666 -237.80242)
			(xy 387.444742 -237.902242)
		)
		(stroke
			(width 0)
			(type solid)
		)
		(fill yes)
		(layer "In11.Cu")
		(net "M_L_CPU0_SA_DQS_DP<7>")
	)
	(gr_poly
		(pts
			(xy 387.544818 -236.182154) (xy 387.544818 -236.137704) (xy 387.344666 -236.137704) (xy 387.344666 -236.182154)
			(xy 387.444742 -236.28223)
		)
		(stroke
			(width 0)
			(type solid)
		)
		(fill yes)
		(layer "In11.Cu")
		(net "M_L_CPU0_SA_DQ<19>")
	)
	(gr_poly
		(pts
			(xy 387.544818 -234.562142) (xy 387.544818 -234.517692) (xy 387.344666 -234.517692) (xy 387.344666 -234.562142)
			(xy 387.444742 -234.662218)
		)
		(stroke
			(width 0)
			(type solid)
		)
		(fill yes)
		(layer "In11.Cu")
		(net "M_L_CPU0_SA_DQ<15>")
	)
	(gr_poly
		(pts
			(xy 387.544818 -232.942384) (xy 387.544818 -232.894632) (xy 387.344666 -232.894632) (xy 387.344666 -232.942384)
			(xy 387.444742 -233.042206)
		)
		(stroke
			(width 0)
			(type solid)
		)
		(fill yes)
		(layer "In11.Cu")
		(net "M_L_CPU0_SA_DQS_DP<6>")
	)
	(gr_poly
		(pts
			(xy 387.544818 -231.322372) (xy 387.544818 -231.277922) (xy 387.344666 -231.277922) (xy 387.344666 -231.322372)
			(xy 387.444742 -231.422448)
		)
		(stroke
			(width 0)
			(type solid)
		)
		(fill yes)
		(layer "In11.Cu")
		(net "M_L_CPU0_SA_DQ<11>")
	)
	(gr_poly
		(pts
			(xy 387.544818 -229.70236) (xy 387.544818 -229.65791) (xy 387.344666 -229.65791) (xy 387.344666 -229.70236)
			(xy 387.444742 -229.802436)
		)
		(stroke
			(width 0)
			(type solid)
		)
		(fill yes)
		(layer "In11.Cu")
		(net "M_L_CPU0_SA_DQ<7>")
	)
	(gr_poly
		(pts
			(xy 387.544818 -228.082602) (xy 387.544818 -228.03485) (xy 387.344666 -228.03485) (xy 387.344666 -228.082602)
			(xy 387.444742 -228.182424)
		)
		(stroke
			(width 0)
			(type solid)
		)
		(fill yes)
		(layer "In11.Cu")
		(net "M_L_CPU0_SA_DQS_DP<5>")
	)
	(gr_poly
		(pts
			(xy 387.544818 -226.462336) (xy 387.544818 -226.417886) (xy 387.344666 -226.417886) (xy 387.344666 -226.462336)
			(xy 387.444742 -226.562412)
		)
		(stroke
			(width 0)
			(type solid)
		)
		(fill yes)
		(layer "In11.Cu")
		(net "M_L_CPU0_SA_DQ<3>")
	)
	(gr_poly
		(pts
			(xy 387.583426 -254.416052) (xy 387.492494 -254.307594) (xy 387.38429 -254.398526) (xy 387.380226 -254.442976)
			(xy 387.579616 -254.460248)
		)
		(stroke
			(width 0)
			(type solid)
		)
		(fill yes)
		(layer "In11.Cu")
		(net "M_L_CPU0_SA_CA<4>")
	)
	(gr_poly
		(pts
			(xy 387.583426 -252.79604) (xy 387.492494 -252.687582) (xy 387.38429 -252.778514) (xy 387.380226 -252.822964)
			(xy 387.579616 -252.840236)
		)
		(stroke
			(width 0)
			(type solid)
		)
		(fill yes)
		(layer "In11.Cu")
		(net "M_L_CPU0_SA_CA<0>")
	)
	(gr_poly
		(pts
			(xy 387.583426 -247.936004) (xy 387.492494 -247.827546) (xy 387.38429 -247.918478) (xy 387.380226 -247.962928)
			(xy 387.579616 -247.9802)
		)
		(stroke
			(width 0)
			(type solid)
		)
		(fill yes)
		(layer "In11.Cu")
		(net "M_L_CPU0_SA_CB<4>")
	)
	(gr_poly
		(pts
			(xy 387.583426 -244.69598) (xy 387.492494 -244.587522) (xy 387.38429 -244.678454) (xy 387.380226 -244.722904)
			(xy 387.579616 -244.740176)
		)
		(stroke
			(width 0)
			(type solid)
		)
		(fill yes)
		(layer "In11.Cu")
		(net "M_L_CPU0_SA_CB<0>")
	)
	(gr_poly
		(pts
			(xy 387.583426 -243.075968) (xy 387.492494 -242.96751) (xy 387.38429 -243.058442) (xy 387.380226 -243.102892)
			(xy 387.579616 -243.120164)
		)
		(stroke
			(width 0)
			(type solid)
		)
		(fill yes)
		(layer "In11.Cu")
		(net "M_L_CPU0_SA_DQ<28>")
	)
	(gr_poly
		(pts
			(xy 387.583426 -239.835944) (xy 387.492494 -239.727486) (xy 387.38429 -239.818418) (xy 387.380226 -239.862868)
			(xy 387.579616 -239.88014)
		)
		(stroke
			(width 0)
			(type solid)
		)
		(fill yes)
		(layer "In11.Cu")
		(net "M_L_CPU0_SA_DQ<24>")
	)
	(gr_poly
		(pts
			(xy 387.583426 -238.215932) (xy 387.492494 -238.107474) (xy 387.38429 -238.198406) (xy 387.380226 -238.242856)
			(xy 387.579616 -238.260128)
		)
		(stroke
			(width 0)
			(type solid)
		)
		(fill yes)
		(layer "In11.Cu")
		(net "M_L_CPU0_SA_DQ<20>")
	)
	(gr_poly
		(pts
			(xy 387.583426 -234.975908) (xy 387.492494 -234.86745) (xy 387.38429 -234.958382) (xy 387.380226 -235.002832)
			(xy 387.579616 -235.020104)
		)
		(stroke
			(width 0)
			(type solid)
		)
		(fill yes)
		(layer "In11.Cu")
		(net "M_L_CPU0_SA_DQ<16>")
	)
	(gr_poly
		(pts
			(xy 387.583426 -233.355896) (xy 387.492494 -233.247438) (xy 387.38429 -233.33837) (xy 387.380226 -233.38282)
			(xy 387.579616 -233.400092)
		)
		(stroke
			(width 0)
			(type solid)
		)
		(fill yes)
		(layer "In11.Cu")
		(net "M_L_CPU0_SA_DQ<12>")
	)
	(gr_poly
		(pts
			(xy 387.583426 -230.115872) (xy 387.492494 -230.007668) (xy 387.38429 -230.098346) (xy 387.380226 -230.142796)
			(xy 387.579616 -230.160068)
		)
		(stroke
			(width 0)
			(type solid)
		)
		(fill yes)
		(layer "In11.Cu")
		(net "M_L_CPU0_SA_DQ<8>")
	)
	(gr_poly
		(pts
			(xy 387.583426 -228.496114) (xy 387.492494 -228.387656) (xy 387.38429 -228.478588) (xy 387.380226 -228.523038)
			(xy 387.579616 -228.54031)
		)
		(stroke
			(width 0)
			(type solid)
		)
		(fill yes)
		(layer "In11.Cu")
		(net "M_L_CPU0_SA_DQ<4>")
	)
	(gr_poly
		(pts
			(xy 387.583426 -225.25609) (xy 387.492494 -225.147632) (xy 387.38429 -225.238564) (xy 387.380226 -225.283014)
			(xy 387.579616 -225.300286)
		)
		(stroke
			(width 0)
			(type solid)
		)
		(fill yes)
		(layer "In11.Cu")
		(net "M_L_CPU0_SA_DQ<0>")
	)
	(gr_poly
		(pts
			(xy 387.585458 -246.315992) (xy 387.494526 -246.207534) (xy 387.386322 -246.298466) (xy 387.382258 -246.345964)
			(xy 387.581394 -246.363236)
		)
		(stroke
			(width 0)
			(type solid)
		)
		(fill yes)
		(layer "In11.Cu")
		(net "M_L_CPU0_SA_DQS_DP<4>")
	)
	(gr_poly
		(pts
			(xy 387.585458 -241.455956) (xy 387.494526 -241.347498) (xy 387.386322 -241.43843) (xy 387.382258 -241.485928)
			(xy 387.581394 -241.5032)
		)
		(stroke
			(width 0)
			(type solid)
		)
		(fill yes)
		(layer "In11.Cu")
		(net "M_L_CPU0_SA_DQS_DP<3>")
	)
	(gr_poly
		(pts
			(xy 387.585458 -236.59592) (xy 387.494526 -236.487462) (xy 387.386322 -236.578394) (xy 387.382258 -236.625892)
			(xy 387.581394 -236.643164)
		)
		(stroke
			(width 0)
			(type solid)
		)
		(fill yes)
		(layer "In11.Cu")
		(net "M_L_CPU0_SA_DQS_DP<2>")
	)
	(gr_poly
		(pts
			(xy 387.585458 -231.735884) (xy 387.494526 -231.627426) (xy 387.386322 -231.718358) (xy 387.382258 -231.765856)
			(xy 387.581394 -231.783128)
		)
		(stroke
			(width 0)
			(type solid)
		)
		(fill yes)
		(layer "In11.Cu")
		(net "M_L_CPU0_SA_DQS_DP<1>")
	)
	(gr_poly
		(pts
			(xy 387.585458 -226.876102) (xy 387.494526 -226.767644) (xy 387.386322 -226.858576) (xy 387.382258 -226.906074)
			(xy 387.581394 -226.9236)
		)
		(stroke
			(width 0)
			(type solid)
		)
		(fill yes)
		(layer "In11.Cu")
		(net "M_L_CPU0_SA_DQS_DP<0>")
	)
	(gr_poly
		(pts
			(xy 387.585966 -251.169678) (xy 387.495034 -251.061474) (xy 387.38683 -251.152406) (xy 387.382766 -251.196602)
			(xy 387.582156 -251.214128)
		)
		(stroke
			(width 0)
			(type solid)
		)
		(fill yes)
		(layer "In11.Cu")
		(net "M_L_CPU0_SA_CS_N<0>")
	)
	(gr_poly
		(pts
			(xy 387.59638 -256.036826) (xy 387.505448 -255.928622) (xy 387.397244 -256.0193) (xy 387.392926 -256.066798)
			(xy 387.592316 -256.084324)
		)
		(stroke
			(width 0)
			(type solid)
		)
		(fill yes)
		(layer "In11.Cu")
		(net "M_L_CPU0_CLK_DP<0>")
	)
	(gr_poly
		(pts
			(xy 387.844792 -292.91788) (xy 387.744716 -292.817804) (xy 387.64464 -292.91788) (xy 387.64464 -292.96233)
			(xy 387.844792 -292.96233)
		)
		(stroke
			(width 0)
			(type solid)
		)
		(fill yes)
		(layer "In11.Cu")
		(net "M_L_CPU0_SB_DQ<29>")
	)
	(gr_poly
		(pts
			(xy 387.844792 -291.297614) (xy 387.744716 -291.197792) (xy 387.64464 -291.297614) (xy 387.64464 -291.345366)
			(xy 387.844792 -291.345366)
		)
		(stroke
			(width 0)
			(type solid)
		)
		(fill yes)
		(layer "In11.Cu")
		(net "M_L_CPU0_SB_DQS_DN<8>")
	)
	(gr_poly
		(pts
			(xy 387.844792 -289.677856) (xy 387.744716 -289.57778) (xy 387.64464 -289.677856) (xy 387.64464 -289.722306)
			(xy 387.844792 -289.722306)
		)
		(stroke
			(width 0)
			(type solid)
		)
		(fill yes)
		(layer "In11.Cu")
		(net "M_L_CPU0_SB_DQ<25>")
	)
	(gr_poly
		(pts
			(xy 387.844792 -288.057844) (xy 387.744716 -287.957768) (xy 387.64464 -288.057844) (xy 387.64464 -288.102294)
			(xy 387.844792 -288.102294)
		)
		(stroke
			(width 0)
			(type solid)
		)
		(fill yes)
		(layer "In11.Cu")
		(net "M_L_CPU0_SB_DQ<21>")
	)
	(gr_poly
		(pts
			(xy 387.844792 -286.437832) (xy 387.744716 -286.337756) (xy 387.64464 -286.437832) (xy 387.64464 -286.485584)
			(xy 387.844792 -286.485584)
		)
		(stroke
			(width 0)
			(type solid)
		)
		(fill yes)
		(layer "In11.Cu")
		(net "M_L_CPU0_SB_DQS_DN<7>")
	)
	(gr_poly
		(pts
			(xy 387.844792 -284.818074) (xy 387.744716 -284.717998) (xy 387.64464 -284.818074) (xy 387.64464 -284.862524)
			(xy 387.844792 -284.862524)
		)
		(stroke
			(width 0)
			(type solid)
		)
		(fill yes)
		(layer "In11.Cu")
		(net "M_L_CPU0_SB_DQ<17>")
	)
	(gr_poly
		(pts
			(xy 387.844792 -283.198062) (xy 387.744716 -283.097986) (xy 387.64464 -283.198062) (xy 387.64464 -283.242512)
			(xy 387.844792 -283.242512)
		)
		(stroke
			(width 0)
			(type solid)
		)
		(fill yes)
		(layer "In11.Cu")
		(net "M_L_CPU0_SB_DQ<13>")
	)
	(gr_poly
		(pts
			(xy 387.844792 -281.577796) (xy 387.744716 -281.477974) (xy 387.64464 -281.577796) (xy 387.64464 -281.625548)
			(xy 387.844792 -281.625548)
		)
		(stroke
			(width 0)
			(type solid)
		)
		(fill yes)
		(layer "In11.Cu")
		(net "M_L_CPU0_SB_DQS_DN<6>")
	)
	(gr_poly
		(pts
			(xy 387.844792 -279.958038) (xy 387.744716 -279.857962) (xy 387.64464 -279.958038) (xy 387.64464 -280.002488)
			(xy 387.844792 -280.002488)
		)
		(stroke
			(width 0)
			(type solid)
		)
		(fill yes)
		(layer "In11.Cu")
		(net "M_L_CPU0_SB_DQ<9>")
	)
	(gr_poly
		(pts
			(xy 387.844792 -278.338026) (xy 387.744716 -278.23795) (xy 387.64464 -278.338026) (xy 387.64464 -278.382476)
			(xy 387.844792 -278.382476)
		)
		(stroke
			(width 0)
			(type solid)
		)
		(fill yes)
		(layer "In11.Cu")
		(net "M_L_CPU0_SB_DQ<5>")
	)
	(gr_poly
		(pts
			(xy 387.844792 -276.71776) (xy 387.744716 -276.617938) (xy 387.64464 -276.71776) (xy 387.64464 -276.765512)
			(xy 387.844792 -276.765512)
		)
		(stroke
			(width 0)
			(type solid)
		)
		(fill yes)
		(layer "In11.Cu")
		(net "M_L_CPU0_SB_DQS_DN<5>")
	)
	(gr_poly
		(pts
			(xy 387.844792 -275.098002) (xy 387.744716 -274.997926) (xy 387.64464 -275.098002) (xy 387.64464 -275.142452)
			(xy 387.844792 -275.142452)
		)
		(stroke
			(width 0)
			(type solid)
		)
		(fill yes)
		(layer "In11.Cu")
		(net "M_L_CPU0_SB_DQ<1>")
	)
	(gr_poly
		(pts
			(xy 387.844792 -273.47799) (xy 387.744716 -273.377914) (xy 387.64464 -273.47799) (xy 387.64464 -273.52244)
			(xy 387.844792 -273.52244)
		)
		(stroke
			(width 0)
			(type solid)
		)
		(fill yes)
		(layer "In11.Cu")
		(net "M_L_CPU0_SB_CB<1>")
	)
	(gr_poly
		(pts
			(xy 387.844792 -271.857724) (xy 387.744716 -271.757902) (xy 387.64464 -271.857724) (xy 387.64464 -271.905476)
			(xy 387.844792 -271.905476)
		)
		(stroke
			(width 0)
			(type solid)
		)
		(fill yes)
		(layer "In11.Cu")
		(net "M_L_CPU0_SB_DQS_DN<4>")
	)
	(gr_poly
		(pts
			(xy 387.844792 -270.237966) (xy 387.744716 -270.13789) (xy 387.64464 -270.237966) (xy 387.64464 -270.282416)
			(xy 387.844792 -270.282416)
		)
		(stroke
			(width 0)
			(type solid)
		)
		(fill yes)
		(layer "In11.Cu")
		(net "M_L_CPU0_SB_CB<5>")
	)
	(gr_poly
		(pts
			(xy 387.844792 -266.997942) (xy 387.744716 -266.897866) (xy 387.64464 -266.997942) (xy 387.64464 -267.042392)
			(xy 387.844792 -267.042392)
		)
		(stroke
			(width 0)
			(type solid)
		)
		(fill yes)
		(layer "In11.Cu")
		(net "M_L_CPU0_SA_RSP<0>")
	)
	(gr_poly
		(pts
			(xy 387.844792 -265.37793) (xy 387.744716 -265.277854) (xy 387.64464 -265.37793) (xy 387.64464 -265.42238)
			(xy 387.844792 -265.42238)
		)
		(stroke
			(width 0)
			(type solid)
		)
		(fill yes)
		(layer "In11.Cu")
		(net "M_L_CPU0_SB_PAR")
	)
	(gr_poly
		(pts
			(xy 387.844792 -263.757918) (xy 387.744716 -263.657842) (xy 387.64464 -263.757918) (xy 387.64464 -263.802368)
			(xy 387.844792 -263.802368)
		)
		(stroke
			(width 0)
			(type solid)
		)
		(fill yes)
		(layer "In11.Cu")
		(net "M_L_CPU0_SB_CA<4>")
	)
	(gr_poly
		(pts
			(xy 387.844792 -262.137906) (xy 387.744716 -262.03783) (xy 387.64464 -262.137906) (xy 387.64464 -262.182356)
			(xy 387.844792 -262.182356)
		)
		(stroke
			(width 0)
			(type solid)
		)
		(fill yes)
		(layer "In11.Cu")
		(net "M_L_CPU0_SB_CA<0>")
	)
	(gr_poly
		(pts
			(xy 387.8834 -292.504114) (xy 387.87959 -292.459918) (xy 387.680454 -292.47719) (xy 387.684264 -292.52164)
			(xy 387.792468 -292.612572)
		)
		(stroke
			(width 0)
			(type solid)
		)
		(fill yes)
		(layer "In11.Cu")
		(net "M_L_CPU0_SB_DQ<30>")
	)
	(gr_poly
		(pts
			(xy 387.8834 -289.26409) (xy 387.87959 -289.219894) (xy 387.680454 -289.237166) (xy 387.684264 -289.281616)
			(xy 387.792468 -289.372548)
		)
		(stroke
			(width 0)
			(type solid)
		)
		(fill yes)
		(layer "In11.Cu")
		(net "M_L_CPU0_SB_DQ<26>")
	)
	(gr_poly
		(pts
			(xy 387.8834 -287.644332) (xy 387.87959 -287.600136) (xy 387.680454 -287.617408) (xy 387.684264 -287.661858)
			(xy 387.792468 -287.752536)
		)
		(stroke
			(width 0)
			(type solid)
		)
		(fill yes)
		(layer "In11.Cu")
		(net "M_L_CPU0_SB_DQ<22>")
	)
	(gr_poly
		(pts
			(xy 387.8834 -284.404308) (xy 387.87959 -284.360112) (xy 387.680454 -284.377384) (xy 387.684264 -284.421834)
			(xy 387.792468 -284.512766)
		)
		(stroke
			(width 0)
			(type solid)
		)
		(fill yes)
		(layer "In11.Cu")
		(net "M_L_CPU0_SB_DQ<18>")
	)
	(gr_poly
		(pts
			(xy 387.8834 -282.784296) (xy 387.87959 -282.7401) (xy 387.680454 -282.757372) (xy 387.684264 -282.801822)
			(xy 387.792468 -282.892754)
		)
		(stroke
			(width 0)
			(type solid)
		)
		(fill yes)
		(layer "In11.Cu")
		(net "M_L_CPU0_SB_DQ<14>")
	)
	(gr_poly
		(pts
			(xy 387.8834 -279.544272) (xy 387.87959 -279.500076) (xy 387.680454 -279.517348) (xy 387.684264 -279.561798)
			(xy 387.792468 -279.65273)
		)
		(stroke
			(width 0)
			(type solid)
		)
		(fill yes)
		(layer "In11.Cu")
		(net "M_L_CPU0_SB_DQ<10>")
	)
	(gr_poly
		(pts
			(xy 387.8834 -277.92426) (xy 387.87959 -277.880064) (xy 387.680454 -277.897336) (xy 387.684264 -277.941786)
			(xy 387.792468 -278.032718)
		)
		(stroke
			(width 0)
			(type solid)
		)
		(fill yes)
		(layer "In11.Cu")
		(net "M_L_CPU0_SB_DQ<6>")
	)
	(gr_poly
		(pts
			(xy 387.8834 -274.684236) (xy 387.87959 -274.64004) (xy 387.680454 -274.657312) (xy 387.684264 -274.701762)
			(xy 387.792468 -274.792694)
		)
		(stroke
			(width 0)
			(type solid)
		)
		(fill yes)
		(layer "In11.Cu")
		(net "M_L_CPU0_SB_DQ<2>")
	)
	(gr_poly
		(pts
			(xy 387.8834 -273.064224) (xy 387.87959 -273.020028) (xy 387.680454 -273.0373) (xy 387.684264 -273.08175)
			(xy 387.792468 -273.172682)
		)
		(stroke
			(width 0)
			(type solid)
		)
		(fill yes)
		(layer "In11.Cu")
		(net "M_L_CPU0_SB_CB<2>")
	)
	(gr_poly
		(pts
			(xy 387.8834 -269.8242) (xy 387.87959 -269.780004) (xy 387.680454 -269.797276) (xy 387.684264 -269.841726)
			(xy 387.792468 -269.932658)
		)
		(stroke
			(width 0)
			(type solid)
		)
		(fill yes)
		(layer "In11.Cu")
		(net "M_L_CPU0_SB_CB<6>")
	)
	(gr_poly
		(pts
			(xy 387.8834 -266.584176) (xy 387.87959 -266.53998) (xy 387.680454 -266.557252) (xy 387.684264 -266.601702)
			(xy 387.792468 -266.692634)
		)
		(stroke
			(width 0)
			(type solid)
		)
		(fill yes)
		(layer "In11.Cu")
		(net "M_L_CPU0_SB_CS_N<1>")
	)
	(gr_poly
		(pts
			(xy 387.8834 -263.344152) (xy 387.87959 -263.299956) (xy 387.680454 -263.317228) (xy 387.684264 -263.361678)
			(xy 387.792468 -263.45261)
		)
		(stroke
			(width 0)
			(type solid)
		)
		(fill yes)
		(layer "In11.Cu")
		(net "M_L_CPU0_SB_CA<3>")
	)
	(gr_poly
		(pts
			(xy 387.896354 -290.88334) (xy 387.89229 -290.835842) (xy 387.6929 -290.853368) (xy 387.697218 -290.900612)
			(xy 387.805422 -290.991544)
		)
		(stroke
			(width 0)
			(type solid)
		)
		(fill yes)
		(layer "In11.Cu")
		(net "M_L_CPU0_SB_DQS_DN<3>")
	)
	(gr_poly
		(pts
			(xy 387.896354 -286.023558) (xy 387.89229 -285.97606) (xy 387.6929 -285.993586) (xy 387.697218 -286.041084)
			(xy 387.805422 -286.131762)
		)
		(stroke
			(width 0)
			(type solid)
		)
		(fill yes)
		(layer "In11.Cu")
		(net "M_L_CPU0_SB_DQS_DN<2>")
	)
	(gr_poly
		(pts
			(xy 387.896354 -281.163522) (xy 387.89229 -281.116024) (xy 387.6929 -281.13355) (xy 387.697218 -281.181048)
			(xy 387.805422 -281.271726)
		)
		(stroke
			(width 0)
			(type solid)
		)
		(fill yes)
		(layer "In11.Cu")
		(net "M_L_CPU0_SB_DQS_DN<1>")
	)
	(gr_poly
		(pts
			(xy 387.896354 -276.303486) (xy 387.89229 -276.255988) (xy 387.6929 -276.273514) (xy 387.697218 -276.321012)
			(xy 387.805422 -276.41169)
		)
		(stroke
			(width 0)
			(type solid)
		)
		(fill yes)
		(layer "In11.Cu")
		(net "M_L_CPU0_SB_DQS_DN<0>")
	)
	(gr_poly
		(pts
			(xy 387.896354 -271.44345) (xy 387.89229 -271.395952) (xy 387.6929 -271.413478) (xy 387.697218 -271.460976)
			(xy 387.805422 -271.551654)
		)
		(stroke
			(width 0)
			(type solid)
		)
		(fill yes)
		(layer "In11.Cu")
		(net "M_L_CPU0_SB_DQS_DN<9>")
	)
	(gr_poly
		(pts
			(xy 388.008622 -251.969778) (xy 387.908546 -251.869702) (xy 387.808724 -251.969778) (xy 387.808724 -252.014228)
			(xy 388.008622 -252.014228)
		)
		(stroke
			(width 0)
			(type solid)
		)
		(fill yes)
		(layer "In11.Cu")
		(net "M_L_CPU0_SA_CS_N<1>")
	)
	(gr_poly
		(pts
			(xy 388.014972 -256.432558) (xy 388.014972 -256.384806) (xy 387.81482 -256.384806) (xy 387.81482 -256.432558)
			(xy 387.914896 -256.53238)
		)
		(stroke
			(width 0)
			(type solid)
		)
		(fill yes)
		(layer "In11.Cu")
		(net "M_L_CPU0_CLK_DN<0>")
	)
	(gr_poly
		(pts
			(xy 388.014972 -255.216152) (xy 387.914896 -255.116076) (xy 387.81482 -255.216152) (xy 387.81482 -255.260602)
			(xy 388.014972 -255.260602)
		)
		(stroke
			(width 0)
			(type solid)
		)
		(fill yes)
		(layer "In11.Cu")
		(net "M_L_CPU0_SA_CA<6>")
	)
	(gr_poly
		(pts
			(xy 388.014972 -254.812292) (xy 388.014972 -254.767842) (xy 387.81482 -254.767842) (xy 387.81482 -254.812292)
			(xy 387.914896 -254.912368)
		)
		(stroke
			(width 0)
			(type solid)
		)
		(fill yes)
		(layer "In11.Cu")
		(net "M_L_CPU0_SA_CA<5>")
	)
	(gr_poly
		(pts
			(xy 388.014972 -253.59614) (xy 387.914896 -253.496064) (xy 387.81482 -253.59614) (xy 387.81482 -253.64059)
			(xy 388.014972 -253.64059)
		)
		(stroke
			(width 0)
			(type solid)
		)
		(fill yes)
		(layer "In11.Cu")
		(net "M_L_CPU0_SA_CA<2>")
	)
	(gr_poly
		(pts
			(xy 388.014972 -253.19228) (xy 388.014972 -253.14783) (xy 387.81482 -253.14783) (xy 387.81482 -253.19228)
			(xy 387.914896 -253.292356)
		)
		(stroke
			(width 0)
			(type solid)
		)
		(fill yes)
		(layer "In11.Cu")
		(net "M_L_CPU0_SA_CA<1>")
	)
	(gr_poly
		(pts
			(xy 388.014972 -250.356116) (xy 387.914896 -250.25604) (xy 387.81482 -250.356116) (xy 387.81482 -250.400566)
			(xy 388.014972 -250.400566)
		)
		(stroke
			(width 0)
			(type solid)
		)
		(fill yes)
		(layer "In11.Cu")
		(net "M_L_CPU0_ALERT_R_N")
	)
	(gr_poly
		(pts
			(xy 388.014972 -248.736104) (xy 387.914896 -248.636028) (xy 387.81482 -248.736104) (xy 387.81482 -248.780554)
			(xy 388.014972 -248.780554)
		)
		(stroke
			(width 0)
			(type solid)
		)
		(fill yes)
		(layer "In11.Cu")
		(net "M_L_CPU0_SA_CB<5>")
	)
	(gr_poly
		(pts
			(xy 388.014972 -248.332244) (xy 388.014972 -248.287794) (xy 387.81482 -248.287794) (xy 387.81482 -248.332244)
			(xy 387.914896 -248.43232)
		)
		(stroke
			(width 0)
			(type solid)
		)
		(fill yes)
		(layer "In11.Cu")
		(net "M_L_CPU0_SA_CB<6>")
	)
	(gr_poly
		(pts
			(xy 388.014972 -247.115838) (xy 387.914896 -247.016016) (xy 387.81482 -247.115838) (xy 387.81482 -247.16359)
			(xy 388.014972 -247.16359)
		)
		(stroke
			(width 0)
			(type solid)
		)
		(fill yes)
		(layer "In11.Cu")
		(net "M_L_CPU0_SA_DQS_DN<9>")
	)
	(gr_poly
		(pts
			(xy 388.014972 -246.712486) (xy 388.014972 -246.664734) (xy 387.81482 -246.664734) (xy 387.81482 -246.712486)
			(xy 387.914896 -246.812308)
		)
		(stroke
			(width 0)
			(type solid)
		)
		(fill yes)
		(layer "In11.Cu")
		(net "M_L_CPU0_SA_DQS_DN<4>")
	)
	(gr_poly
		(pts
			(xy 388.014972 -245.49608) (xy 387.914896 -245.396004) (xy 387.81482 -245.49608) (xy 387.81482 -245.54053)
			(xy 388.014972 -245.54053)
		)
		(stroke
			(width 0)
			(type solid)
		)
		(fill yes)
		(layer "In11.Cu")
		(net "M_L_CPU0_SA_CB<1>")
	)
	(gr_poly
		(pts
			(xy 388.014972 -245.09222) (xy 388.014972 -245.04777) (xy 387.81482 -245.04777) (xy 387.81482 -245.09222)
			(xy 387.914896 -245.192296)
		)
		(stroke
			(width 0)
			(type solid)
		)
		(fill yes)
		(layer "In11.Cu")
		(net "M_L_CPU0_SA_CB<2>")
	)
	(gr_poly
		(pts
			(xy 388.014972 -243.876068) (xy 387.914896 -243.775992) (xy 387.81482 -243.876068) (xy 387.81482 -243.920518)
			(xy 388.014972 -243.920518)
		)
		(stroke
			(width 0)
			(type solid)
		)
		(fill yes)
		(layer "In11.Cu")
		(net "M_L_CPU0_SA_DQ<29>")
	)
	(gr_poly
		(pts
			(xy 388.014972 -243.472208) (xy 388.014972 -243.427758) (xy 387.81482 -243.427758) (xy 387.81482 -243.472208)
			(xy 387.914896 -243.572284)
		)
		(stroke
			(width 0)
			(type solid)
		)
		(fill yes)
		(layer "In11.Cu")
		(net "M_L_CPU0_SA_DQ<30>")
	)
	(gr_poly
		(pts
			(xy 388.014972 -242.255802) (xy 387.914896 -242.15598) (xy 387.81482 -242.255802) (xy 387.81482 -242.303554)
			(xy 388.014972 -242.303554)
		)
		(stroke
			(width 0)
			(type solid)
		)
		(fill yes)
		(layer "In11.Cu")
		(net "M_L_CPU0_SA_DQS_DN<8>")
	)
	(gr_poly
		(pts
			(xy 388.014972 -241.85245) (xy 388.014972 -241.804698) (xy 387.81482 -241.804698) (xy 387.81482 -241.85245)
			(xy 387.914896 -241.952272)
		)
		(stroke
			(width 0)
			(type solid)
		)
		(fill yes)
		(layer "In11.Cu")
		(net "M_L_CPU0_SA_DQS_DN<3>")
	)
	(gr_poly
		(pts
			(xy 388.014972 -240.636044) (xy 387.914896 -240.535968) (xy 387.81482 -240.636044) (xy 387.81482 -240.680494)
			(xy 388.014972 -240.680494)
		)
		(stroke
			(width 0)
			(type solid)
		)
		(fill yes)
		(layer "In11.Cu")
		(net "M_L_CPU0_SA_DQ<25>")
	)
	(gr_poly
		(pts
			(xy 388.014972 -240.232184) (xy 388.014972 -240.187734) (xy 387.81482 -240.187734) (xy 387.81482 -240.232184)
			(xy 387.914896 -240.33226)
		)
		(stroke
			(width 0)
			(type solid)
		)
		(fill yes)
		(layer "In11.Cu")
		(net "M_L_CPU0_SA_DQ<26>")
	)
	(gr_poly
		(pts
			(xy 388.014972 -239.016032) (xy 387.914896 -238.915956) (xy 387.81482 -239.016032) (xy 387.81482 -239.060482)
			(xy 388.014972 -239.060482)
		)
		(stroke
			(width 0)
			(type solid)
		)
		(fill yes)
		(layer "In11.Cu")
		(net "M_L_CPU0_SA_DQ<21>")
	)
	(gr_poly
		(pts
			(xy 388.014972 -238.612172) (xy 388.014972 -238.567722) (xy 387.81482 -238.567722) (xy 387.81482 -238.612172)
			(xy 387.914896 -238.712248)
		)
		(stroke
			(width 0)
			(type solid)
		)
		(fill yes)
		(layer "In11.Cu")
		(net "M_L_CPU0_SA_DQ<22>")
	)
	(gr_poly
		(pts
			(xy 388.014972 -237.395766) (xy 387.914896 -237.295944) (xy 387.81482 -237.395766) (xy 387.81482 -237.443518)
			(xy 388.014972 -237.443518)
		)
		(stroke
			(width 0)
			(type solid)
		)
		(fill yes)
		(layer "In11.Cu")
		(net "M_L_CPU0_SA_DQS_DN<7>")
	)
	(gr_poly
		(pts
			(xy 388.014972 -236.992414) (xy 388.014972 -236.944662) (xy 387.81482 -236.944662) (xy 387.81482 -236.992414)
			(xy 387.914896 -237.092236)
		)
		(stroke
			(width 0)
			(type solid)
		)
		(fill yes)
		(layer "In11.Cu")
		(net "M_L_CPU0_SA_DQS_DN<2>")
	)
	(gr_poly
		(pts
			(xy 388.014972 -235.776008) (xy 387.914896 -235.675932) (xy 387.81482 -235.776008) (xy 387.81482 -235.820458)
			(xy 388.014972 -235.820458)
		)
		(stroke
			(width 0)
			(type solid)
		)
		(fill yes)
		(layer "In11.Cu")
		(net "M_L_CPU0_SA_DQ<17>")
	)
	(gr_poly
		(pts
			(xy 388.014972 -235.372148) (xy 388.014972 -235.327698) (xy 387.81482 -235.327698) (xy 387.81482 -235.372148)
			(xy 387.914896 -235.472224)
		)
		(stroke
			(width 0)
			(type solid)
		)
		(fill yes)
		(layer "In11.Cu")
		(net "M_L_CPU0_SA_DQ<18>")
	)
	(gr_poly
		(pts
			(xy 388.014972 -234.155996) (xy 387.914896 -234.05592) (xy 387.81482 -234.155996) (xy 387.81482 -234.200446)
			(xy 388.014972 -234.200446)
		)
		(stroke
			(width 0)
			(type solid)
		)
		(fill yes)
		(layer "In11.Cu")
		(net "M_L_CPU0_SA_DQ<13>")
	)
	(gr_poly
		(pts
			(xy 388.014972 -233.752136) (xy 388.014972 -233.707686) (xy 387.81482 -233.707686) (xy 387.81482 -233.752136)
			(xy 387.914896 -233.852212)
		)
		(stroke
			(width 0)
			(type solid)
		)
		(fill yes)
		(layer "In11.Cu")
		(net "M_L_CPU0_SA_DQ<14>")
	)
	(gr_poly
		(pts
			(xy 388.014972 -232.53573) (xy 387.914896 -232.435908) (xy 387.81482 -232.53573) (xy 387.81482 -232.583482)
			(xy 388.014972 -232.583482)
		)
		(stroke
			(width 0)
			(type solid)
		)
		(fill yes)
		(layer "In11.Cu")
		(net "M_L_CPU0_SA_DQS_DN<6>")
	)
	(gr_poly
		(pts
			(xy 388.014972 -232.132378) (xy 388.014972 -232.084626) (xy 387.81482 -232.084626) (xy 387.81482 -232.132378)
			(xy 387.914896 -232.2322)
		)
		(stroke
			(width 0)
			(type solid)
		)
		(fill yes)
		(layer "In11.Cu")
		(net "M_L_CPU0_SA_DQS_DN<1>")
	)
	(gr_poly
		(pts
			(xy 388.014972 -230.915972) (xy 387.914896 -230.815896) (xy 387.81482 -230.915972) (xy 387.81482 -230.960422)
			(xy 388.014972 -230.960422)
		)
		(stroke
			(width 0)
			(type solid)
		)
		(fill yes)
		(layer "In11.Cu")
		(net "M_L_CPU0_SA_DQ<9>")
	)
	(gr_poly
		(pts
			(xy 388.014972 -230.512366) (xy 388.014972 -230.467916) (xy 387.81482 -230.467916) (xy 387.81482 -230.512366)
			(xy 387.914896 -230.612188)
		)
		(stroke
			(width 0)
			(type solid)
		)
		(fill yes)
		(layer "In11.Cu")
		(net "M_L_CPU0_SA_DQ<10>")
	)
	(gr_poly
		(pts
			(xy 388.014972 -229.29596) (xy 387.914896 -229.195884) (xy 387.81482 -229.29596) (xy 387.81482 -229.34041)
			(xy 388.014972 -229.34041)
		)
		(stroke
			(width 0)
			(type solid)
		)
		(fill yes)
		(layer "In11.Cu")
		(net "M_L_CPU0_SA_DQ<5>")
	)
	(gr_poly
		(pts
			(xy 388.014972 -228.892354) (xy 388.014972 -228.847904) (xy 387.81482 -228.847904) (xy 387.81482 -228.892354)
			(xy 387.914896 -228.99243)
		)
		(stroke
			(width 0)
			(type solid)
		)
		(fill yes)
		(layer "In11.Cu")
		(net "M_L_CPU0_SA_DQ<6>")
	)
	(gr_poly
		(pts
			(xy 388.014972 -227.675948) (xy 387.914896 -227.576126) (xy 387.81482 -227.675948) (xy 387.81482 -227.7237)
			(xy 388.014972 -227.7237)
		)
		(stroke
			(width 0)
			(type solid)
		)
		(fill yes)
		(layer "In11.Cu")
		(net "M_L_CPU0_SA_DQS_DN<5>")
	)
	(gr_poly
		(pts
			(xy 388.014972 -227.272596) (xy 388.014972 -227.224844) (xy 387.81482 -227.224844) (xy 387.81482 -227.272596)
			(xy 387.914896 -227.372418)
		)
		(stroke
			(width 0)
			(type solid)
		)
		(fill yes)
		(layer "In11.Cu")
		(net "M_L_CPU0_SA_DQS_DN<0>")
	)
	(gr_poly
		(pts
			(xy 388.014972 -226.05619) (xy 387.914896 -225.956114) (xy 387.81482 -226.05619) (xy 387.81482 -226.10064)
			(xy 388.014972 -226.10064)
		)
		(stroke
			(width 0)
			(type solid)
		)
		(fill yes)
		(layer "In11.Cu")
		(net "M_L_CPU0_SA_DQ<1>")
	)
	(gr_poly
		(pts
			(xy 388.014972 -225.65233) (xy 388.014972 -225.60788) (xy 387.81482 -225.60788) (xy 387.81482 -225.65233)
			(xy 387.914896 -225.752406)
		)
		(stroke
			(width 0)
			(type solid)
		)
		(fill yes)
		(layer "In11.Cu")
		(net "M_L_CPU0_SA_DQ<2>")
	)
	(gr_poly
		(pts
			(xy 388.308596 -264.561574) (xy 388.20852 -264.461498) (xy 388.108698 -264.561574) (xy 388.108698 -264.606024)
			(xy 388.308596 -264.606024)
		)
		(stroke
			(width 0)
			(type solid)
		)
		(fill yes)
		(layer "In11.Cu")
		(net "M_L_CPU0_SB_CA<6>")
	)
	(gr_poly
		(pts
			(xy 388.314946 -292.107874) (xy 388.21487 -292.007798) (xy 388.114794 -292.107874) (xy 388.114794 -292.152324)
			(xy 388.314946 -292.152324)
		)
		(stroke
			(width 0)
			(type solid)
		)
		(fill yes)
		(layer "In11.Cu")
		(net "M_L_CPU0_SB_DQ<28>")
	)
	(gr_poly
		(pts
			(xy 388.314946 -291.704268) (xy 388.314946 -291.656516) (xy 388.114794 -291.656516) (xy 388.114794 -291.704268)
			(xy 388.21487 -291.80409)
		)
		(stroke
			(width 0)
			(type solid)
		)
		(fill yes)
		(layer "In11.Cu")
		(net "M_L_CPU0_SB_DQS_DP<8>")
	)
	(gr_poly
		(pts
			(xy 388.314946 -290.487608) (xy 388.21487 -290.387786) (xy 388.114794 -290.487608) (xy 388.114794 -290.53536)
			(xy 388.314946 -290.53536)
		)
		(stroke
			(width 0)
			(type solid)
		)
		(fill yes)
		(layer "In11.Cu")
		(net "M_L_CPU0_SB_DQS_DP<3>")
	)
	(gr_poly
		(pts
			(xy 388.314946 -290.084002) (xy 388.314946 -290.039552) (xy 388.114794 -290.039552) (xy 388.114794 -290.084002)
			(xy 388.21487 -290.184078)
		)
		(stroke
			(width 0)
			(type solid)
		)
		(fill yes)
		(layer "In11.Cu")
		(net "M_L_CPU0_SB_DQ<27>")
	)
	(gr_poly
		(pts
			(xy 388.314946 -288.86785) (xy 388.21487 -288.767774) (xy 388.114794 -288.86785) (xy 388.114794 -288.9123)
			(xy 388.314946 -288.9123)
		)
		(stroke
			(width 0)
			(type solid)
		)
		(fill yes)
		(layer "In11.Cu")
		(net "M_L_CPU0_SB_DQ<24>")
	)
	(gr_poly
		(pts
			(xy 388.314946 -288.464244) (xy 388.314946 -288.419794) (xy 388.114794 -288.419794) (xy 388.114794 -288.464244)
			(xy 388.21487 -288.56432)
		)
		(stroke
			(width 0)
			(type solid)
		)
		(fill yes)
		(layer "In11.Cu")
		(net "M_L_CPU0_SB_DQ<23>")
	)
	(gr_poly
		(pts
			(xy 388.314946 -287.247838) (xy 388.21487 -287.148016) (xy 388.114794 -287.247838) (xy 388.114794 -287.292288)
			(xy 388.314946 -287.292288)
		)
		(stroke
			(width 0)
			(type solid)
		)
		(fill yes)
		(layer "In11.Cu")
		(net "M_L_CPU0_SB_DQ<20>")
	)
	(gr_poly
		(pts
			(xy 388.314946 -286.844232) (xy 388.314946 -286.79648) (xy 388.114794 -286.79648) (xy 388.114794 -286.844232)
			(xy 388.21487 -286.944308)
		)
		(stroke
			(width 0)
			(type solid)
		)
		(fill yes)
		(layer "In11.Cu")
		(net "M_L_CPU0_SB_DQS_DP<7>")
	)
	(gr_poly
		(pts
			(xy 388.314946 -285.627826) (xy 388.21487 -285.528004) (xy 388.114794 -285.627826) (xy 388.114794 -285.675578)
			(xy 388.314946 -285.675578)
		)
		(stroke
			(width 0)
			(type solid)
		)
		(fill yes)
		(layer "In11.Cu")
		(net "M_L_CPU0_SB_DQS_DP<2>")
	)
	(gr_poly
		(pts
			(xy 388.314946 -285.22422) (xy 388.314946 -285.17977) (xy 388.114794 -285.17977) (xy 388.114794 -285.22422)
			(xy 388.21487 -285.324296)
		)
		(stroke
			(width 0)
			(type solid)
		)
		(fill yes)
		(layer "In11.Cu")
		(net "M_L_CPU0_SB_DQ<19>")
	)
	(gr_poly
		(pts
			(xy 388.314946 -284.008068) (xy 388.21487 -283.907992) (xy 388.114794 -284.008068) (xy 388.114794 -284.052518)
			(xy 388.314946 -284.052518)
		)
		(stroke
			(width 0)
			(type solid)
		)
		(fill yes)
		(layer "In11.Cu")
		(net "M_L_CPU0_SB_DQ<16>")
	)
	(gr_poly
		(pts
			(xy 388.314946 -283.604208) (xy 388.314946 -283.559758) (xy 388.114794 -283.559758) (xy 388.114794 -283.604208)
			(xy 388.21487 -283.704284)
		)
		(stroke
			(width 0)
			(type solid)
		)
		(fill yes)
		(layer "In11.Cu")
		(net "M_L_CPU0_SB_DQ<15>")
	)
	(gr_poly
		(pts
			(xy 388.314946 -282.388056) (xy 388.21487 -282.28798) (xy 388.114794 -282.388056) (xy 388.114794 -282.432506)
			(xy 388.314946 -282.432506)
		)
		(stroke
			(width 0)
			(type solid)
		)
		(fill yes)
		(layer "In11.Cu")
		(net "M_L_CPU0_SB_DQ<12>")
	)
	(gr_poly
		(pts
			(xy 388.314946 -281.98445) (xy 388.314946 -281.936698) (xy 388.114794 -281.936698) (xy 388.114794 -281.98445)
			(xy 388.21487 -282.084272)
		)
		(stroke
			(width 0)
			(type solid)
		)
		(fill yes)
		(layer "In11.Cu")
		(net "M_L_CPU0_SB_DQS_DP<6>")
	)
	(gr_poly
		(pts
			(xy 388.314946 -280.76779) (xy 388.21487 -280.667968) (xy 388.114794 -280.76779) (xy 388.114794 -280.815542)
			(xy 388.314946 -280.815542)
		)
		(stroke
			(width 0)
			(type solid)
		)
		(fill yes)
		(layer "In11.Cu")
		(net "M_L_CPU0_SB_DQS_DP<1>")
	)
	(gr_poly
		(pts
			(xy 388.314946 -280.364184) (xy 388.314946 -280.319734) (xy 388.114794 -280.319734) (xy 388.114794 -280.364184)
			(xy 388.21487 -280.46426)
		)
		(stroke
			(width 0)
			(type solid)
		)
		(fill yes)
		(layer "In11.Cu")
		(net "M_L_CPU0_SB_DQ<11>")
	)
	(gr_poly
		(pts
			(xy 388.314946 -279.148032) (xy 388.21487 -279.047956) (xy 388.114794 -279.148032) (xy 388.114794 -279.192482)
			(xy 388.314946 -279.192482)
		)
		(stroke
			(width 0)
			(type solid)
		)
		(fill yes)
		(layer "In11.Cu")
		(net "M_L_CPU0_SB_DQ<8>")
	)
	(gr_poly
		(pts
			(xy 388.314946 -278.744172) (xy 388.314946 -278.699722) (xy 388.114794 -278.699722) (xy 388.114794 -278.744172)
			(xy 388.21487 -278.844248)
		)
		(stroke
			(width 0)
			(type solid)
		)
		(fill yes)
		(layer "In11.Cu")
		(net "M_L_CPU0_SB_DQ<7>")
	)
	(gr_poly
		(pts
			(xy 388.314946 -277.52802) (xy 388.21487 -277.427944) (xy 388.114794 -277.52802) (xy 388.114794 -277.57247)
			(xy 388.314946 -277.57247)
		)
		(stroke
			(width 0)
			(type solid)
		)
		(fill yes)
		(layer "In11.Cu")
		(net "M_L_CPU0_SB_DQ<4>")
	)
	(gr_poly
		(pts
			(xy 388.314946 -277.124414) (xy 388.314946 -277.076662) (xy 388.114794 -277.076662) (xy 388.114794 -277.124414)
			(xy 388.21487 -277.224236)
		)
		(stroke
			(width 0)
			(type solid)
		)
		(fill yes)
		(layer "In11.Cu")
		(net "M_L_CPU0_SB_DQS_DP<5>")
	)
	(gr_poly
		(pts
			(xy 388.314946 -275.907754) (xy 388.21487 -275.807932) (xy 388.114794 -275.907754) (xy 388.114794 -275.955506)
			(xy 388.314946 -275.955506)
		)
		(stroke
			(width 0)
			(type solid)
		)
		(fill yes)
		(layer "In11.Cu")
		(net "M_L_CPU0_SB_DQS_DP<0>")
	)
	(gr_poly
		(pts
			(xy 388.314946 -275.504148) (xy 388.314946 -275.459698) (xy 388.114794 -275.459698) (xy 388.114794 -275.504148)
			(xy 388.21487 -275.604224)
		)
		(stroke
			(width 0)
			(type solid)
		)
		(fill yes)
		(layer "In11.Cu")
		(net "M_L_CPU0_SB_DQ<3>")
	)
	(gr_poly
		(pts
			(xy 388.314946 -274.287996) (xy 388.21487 -274.18792) (xy 388.114794 -274.287996) (xy 388.114794 -274.332446)
			(xy 388.314946 -274.332446)
		)
		(stroke
			(width 0)
			(type solid)
		)
		(fill yes)
		(layer "In11.Cu")
		(net "M_L_CPU0_SB_DQ<0>")
	)
	(gr_poly
		(pts
			(xy 388.314946 -273.884136) (xy 388.314946 -273.839686) (xy 388.114794 -273.839686) (xy 388.114794 -273.884136)
			(xy 388.21487 -273.984212)
		)
		(stroke
			(width 0)
			(type solid)
		)
		(fill yes)
		(layer "In11.Cu")
		(net "M_L_CPU0_SB_CB<3>")
	)
	(gr_poly
		(pts
			(xy 388.314946 -272.667984) (xy 388.21487 -272.567908) (xy 388.114794 -272.667984) (xy 388.114794 -272.712434)
			(xy 388.314946 -272.712434)
		)
		(stroke
			(width 0)
			(type solid)
		)
		(fill yes)
		(layer "In11.Cu")
		(net "M_L_CPU0_SB_CB<0>")
	)
	(gr_poly
		(pts
			(xy 388.314946 -272.264378) (xy 388.314946 -272.216626) (xy 388.114794 -272.216626) (xy 388.114794 -272.264378)
			(xy 388.21487 -272.3642)
		)
		(stroke
			(width 0)
			(type solid)
		)
		(fill yes)
		(layer "In11.Cu")
		(net "M_L_CPU0_SB_DQS_DP<4>")
	)
	(gr_poly
		(pts
			(xy 388.314946 -271.047718) (xy 388.21487 -270.947896) (xy 388.114794 -271.047718) (xy 388.114794 -271.09547)
			(xy 388.314946 -271.09547)
		)
		(stroke
			(width 0)
			(type solid)
		)
		(fill yes)
		(layer "In11.Cu")
		(net "M_L_CPU0_SB_DQS_DP<9>")
	)
	(gr_poly
		(pts
			(xy 388.314946 -270.644112) (xy 388.314946 -270.599662) (xy 388.114794 -270.599662) (xy 388.114794 -270.644112)
			(xy 388.21487 -270.744188)
		)
		(stroke
			(width 0)
			(type solid)
		)
		(fill yes)
		(layer "In11.Cu")
		(net "M_L_CPU0_SB_CB<7>")
	)
	(gr_poly
		(pts
			(xy 388.314946 -269.42796) (xy 388.21487 -269.327884) (xy 388.114794 -269.42796) (xy 388.114794 -269.47241)
			(xy 388.314946 -269.47241)
		)
		(stroke
			(width 0)
			(type solid)
		)
		(fill yes)
		(layer "In11.Cu")
		(net "M_L_CPU0_SB_CB<4>")
	)
	(gr_poly
		(pts
			(xy 388.314946 -267.807948) (xy 388.21487 -267.707872) (xy 388.114794 -267.807948) (xy 388.114794 -267.852398)
			(xy 388.314946 -267.852398)
		)
		(stroke
			(width 0)
			(type solid)
		)
		(fill yes)
		(layer "In11.Cu")
		(net "M_L_CPU0_SB_RSP<0>")
	)
	(gr_poly
		(pts
			(xy 388.314946 -265.784076) (xy 388.314946 -265.739626) (xy 388.114794 -265.739626) (xy 388.114794 -265.784076)
			(xy 388.21487 -265.884152)
		)
		(stroke
			(width 0)
			(type solid)
		)
		(fill yes)
		(layer "In11.Cu")
		(net "M_L_CPU0_SB_CS_N<0>")
	)
	(gr_poly
		(pts
			(xy 388.314946 -264.164064) (xy 388.314946 -264.119614) (xy 388.114794 -264.119614) (xy 388.114794 -264.164064)
			(xy 388.21487 -264.26414)
		)
		(stroke
			(width 0)
			(type solid)
		)
		(fill yes)
		(layer "In11.Cu")
		(net "M_L_CPU0_SB_CA<5>")
	)
	(gr_poly
		(pts
			(xy 388.314946 -262.947912) (xy 388.21487 -262.847836) (xy 388.114794 -262.947912) (xy 388.114794 -262.992362)
			(xy 388.314946 -262.992362)
		)
		(stroke
			(width 0)
			(type solid)
		)
		(fill yes)
		(layer "In11.Cu")
		(net "M_L_CPU0_SB_CA<2>")
	)
	(gr_poly
		(pts
			(xy 388.314946 -262.544052) (xy 388.314946 -262.499602) (xy 388.114794 -262.499602) (xy 388.114794 -262.544052)
			(xy 388.21487 -262.644128)
		)
		(stroke
			(width 0)
			(type solid)
		)
		(fill yes)
		(layer "In11.Cu")
		(net "M_L_CPU0_SB_CA<1>")
	)
	(gr_poly
		(pts
			(xy 388.484872 -256.025904) (xy 388.384796 -255.926082) (xy 388.28472 -256.025904) (xy 388.28472 -256.073656)
			(xy 388.484872 -256.073656)
		)
		(stroke
			(width 0)
			(type solid)
		)
		(fill yes)
		(layer "In11.Cu")
		(net "M_L_CPU0_CLK_DP<0>")
	)
	(gr_poly
		(pts
			(xy 388.484872 -255.622298) (xy 388.484872 -255.577848) (xy 388.28472 -255.577848) (xy 388.28472 -255.622298)
			(xy 388.384796 -255.722374)
		)
		(stroke
			(width 0)
			(type solid)
		)
		(fill yes)
		(layer "In11.Cu")
		(net "M_L_CPU0_SA_PAR")
	)
	(gr_poly
		(pts
			(xy 388.484872 -254.406146) (xy 388.384796 -254.30607) (xy 388.28472 -254.406146) (xy 388.28472 -254.450596)
			(xy 388.484872 -254.450596)
		)
		(stroke
			(width 0)
			(type solid)
		)
		(fill yes)
		(layer "In11.Cu")
		(net "M_L_CPU0_SA_CA<4>")
	)
	(gr_poly
		(pts
			(xy 388.484872 -254.002286) (xy 388.484872 -253.957836) (xy 388.28472 -253.957836) (xy 388.28472 -254.002286)
			(xy 388.384796 -254.102362)
		)
		(stroke
			(width 0)
			(type solid)
		)
		(fill yes)
		(layer "In11.Cu")
		(net "M_L_CPU0_SA_CA<3>")
	)
	(gr_poly
		(pts
			(xy 388.484872 -252.786134) (xy 388.384796 -252.686058) (xy 388.28472 -252.786134) (xy 388.28472 -252.830584)
			(xy 388.484872 -252.830584)
		)
		(stroke
			(width 0)
			(type solid)
		)
		(fill yes)
		(layer "In11.Cu")
		(net "M_L_CPU0_SA_CA<0>")
	)
	(gr_poly
		(pts
			(xy 388.484872 -250.762262) (xy 388.484872 -250.717812) (xy 388.28472 -250.717812) (xy 388.28472 -250.762262)
			(xy 388.384796 -250.862338)
		)
		(stroke
			(width 0)
			(type solid)
		)
		(fill yes)
		(layer "In11.Cu")
		(net "M_L_CPU0_RESET_N")
	)
	(gr_poly
		(pts
			(xy 388.484872 -249.14225) (xy 388.484872 -249.0978) (xy 388.28472 -249.0978) (xy 388.28472 -249.14225)
			(xy 388.384796 -249.242326)
		)
		(stroke
			(width 0)
			(type solid)
		)
		(fill yes)
		(layer "In11.Cu")
		(net "M_L_CPU0_SA_CB<7>")
	)
	(gr_poly
		(pts
			(xy 388.484872 -247.926098) (xy 388.384796 -247.826022) (xy 388.28472 -247.926098) (xy 388.28472 -247.970548)
			(xy 388.484872 -247.970548)
		)
		(stroke
			(width 0)
			(type solid)
		)
		(fill yes)
		(layer "In11.Cu")
		(net "M_L_CPU0_SA_CB<4>")
	)
	(gr_poly
		(pts
			(xy 388.484872 -247.522492) (xy 388.484872 -247.47474) (xy 388.28472 -247.47474) (xy 388.28472 -247.522492)
			(xy 388.384796 -247.622314)
		)
		(stroke
			(width 0)
			(type solid)
		)
		(fill yes)
		(layer "In11.Cu")
		(net "M_L_CPU0_SA_DQS_DP<9>")
	)
	(gr_poly
		(pts
			(xy 388.484872 -246.305832) (xy 388.384796 -246.20601) (xy 388.28472 -246.305832) (xy 388.28472 -246.353584)
			(xy 388.484872 -246.353584)
		)
		(stroke
			(width 0)
			(type solid)
		)
		(fill yes)
		(layer "In11.Cu")
		(net "M_L_CPU0_SA_DQS_DP<4>")
	)
	(gr_poly
		(pts
			(xy 388.484872 -245.902226) (xy 388.484872 -245.857776) (xy 388.28472 -245.857776) (xy 388.28472 -245.902226)
			(xy 388.384796 -246.002302)
		)
		(stroke
			(width 0)
			(type solid)
		)
		(fill yes)
		(layer "In11.Cu")
		(net "M_L_CPU0_SA_CB<3>")
	)
	(gr_poly
		(pts
			(xy 388.484872 -244.686074) (xy 388.384796 -244.585998) (xy 388.28472 -244.686074) (xy 388.28472 -244.730524)
			(xy 388.484872 -244.730524)
		)
		(stroke
			(width 0)
			(type solid)
		)
		(fill yes)
		(layer "In11.Cu")
		(net "M_L_CPU0_SA_CB<0>")
	)
	(gr_poly
		(pts
			(xy 388.484872 -244.282214) (xy 388.484872 -244.237764) (xy 388.28472 -244.237764) (xy 388.28472 -244.282214)
			(xy 388.384796 -244.38229)
		)
		(stroke
			(width 0)
			(type solid)
		)
		(fill yes)
		(layer "In11.Cu")
		(net "M_L_CPU0_SA_DQ<31>")
	)
	(gr_poly
		(pts
			(xy 388.484872 -243.066062) (xy 388.384796 -242.965986) (xy 388.28472 -243.066062) (xy 388.28472 -243.110512)
			(xy 388.484872 -243.110512)
		)
		(stroke
			(width 0)
			(type solid)
		)
		(fill yes)
		(layer "In11.Cu")
		(net "M_L_CPU0_SA_DQ<28>")
	)
	(gr_poly
		(pts
			(xy 388.484872 -242.662456) (xy 388.484872 -242.614704) (xy 388.28472 -242.614704) (xy 388.28472 -242.662456)
			(xy 388.384796 -242.762278)
		)
		(stroke
			(width 0)
			(type solid)
		)
		(fill yes)
		(layer "In11.Cu")
		(net "M_L_CPU0_SA_DQS_DP<8>")
	)
	(gr_poly
		(pts
			(xy 388.484872 -241.445796) (xy 388.384796 -241.345974) (xy 388.28472 -241.445796) (xy 388.28472 -241.493548)
			(xy 388.484872 -241.493548)
		)
		(stroke
			(width 0)
			(type solid)
		)
		(fill yes)
		(layer "In11.Cu")
		(net "M_L_CPU0_SA_DQS_DP<3>")
	)
	(gr_poly
		(pts
			(xy 388.484872 -241.04219) (xy 388.484872 -240.99774) (xy 388.28472 -240.99774) (xy 388.28472 -241.04219)
			(xy 388.384796 -241.142266)
		)
		(stroke
			(width 0)
			(type solid)
		)
		(fill yes)
		(layer "In11.Cu")
		(net "M_L_CPU0_SA_DQ<27>")
	)
	(gr_poly
		(pts
			(xy 388.484872 -239.826038) (xy 388.384796 -239.725962) (xy 388.28472 -239.826038) (xy 388.28472 -239.870488)
			(xy 388.484872 -239.870488)
		)
		(stroke
			(width 0)
			(type solid)
		)
		(fill yes)
		(layer "In11.Cu")
		(net "M_L_CPU0_SA_DQ<24>")
	)
	(gr_poly
		(pts
			(xy 388.484872 -239.422178) (xy 388.484872 -239.377728) (xy 388.28472 -239.377728) (xy 388.28472 -239.422178)
			(xy 388.384796 -239.522254)
		)
		(stroke
			(width 0)
			(type solid)
		)
		(fill yes)
		(layer "In11.Cu")
		(net "M_L_CPU0_SA_DQ<23>")
	)
	(gr_poly
		(pts
			(xy 388.484872 -238.206026) (xy 388.384796 -238.10595) (xy 388.28472 -238.206026) (xy 388.28472 -238.250476)
			(xy 388.484872 -238.250476)
		)
		(stroke
			(width 0)
			(type solid)
		)
		(fill yes)
		(layer "In11.Cu")
		(net "M_L_CPU0_SA_DQ<20>")
	)
	(gr_poly
		(pts
			(xy 388.484872 -237.80242) (xy 388.484872 -237.754668) (xy 388.28472 -237.754668) (xy 388.28472 -237.80242)
			(xy 388.384796 -237.902242)
		)
		(stroke
			(width 0)
			(type solid)
		)
		(fill yes)
		(layer "In11.Cu")
		(net "M_L_CPU0_SA_DQS_DP<7>")
	)
	(gr_poly
		(pts
			(xy 388.484872 -236.58576) (xy 388.384796 -236.485938) (xy 388.28472 -236.58576) (xy 388.28472 -236.633512)
			(xy 388.484872 -236.633512)
		)
		(stroke
			(width 0)
			(type solid)
		)
		(fill yes)
		(layer "In11.Cu")
		(net "M_L_CPU0_SA_DQS_DP<2>")
	)
	(gr_poly
		(pts
			(xy 388.484872 -236.182154) (xy 388.484872 -236.137704) (xy 388.28472 -236.137704) (xy 388.28472 -236.182154)
			(xy 388.384796 -236.28223)
		)
		(stroke
			(width 0)
			(type solid)
		)
		(fill yes)
		(layer "In11.Cu")
		(net "M_L_CPU0_SA_DQ<19>")
	)
	(gr_poly
		(pts
			(xy 388.484872 -234.966002) (xy 388.384796 -234.865926) (xy 388.28472 -234.966002) (xy 388.28472 -235.010452)
			(xy 388.484872 -235.010452)
		)
		(stroke
			(width 0)
			(type solid)
		)
		(fill yes)
		(layer "In11.Cu")
		(net "M_L_CPU0_SA_DQ<16>")
	)
	(gr_poly
		(pts
			(xy 388.484872 -234.562142) (xy 388.484872 -234.517692) (xy 388.28472 -234.517692) (xy 388.28472 -234.562142)
			(xy 388.384796 -234.662218)
		)
		(stroke
			(width 0)
			(type solid)
		)
		(fill yes)
		(layer "In11.Cu")
		(net "M_L_CPU0_SA_DQ<15>")
	)
	(gr_poly
		(pts
			(xy 388.484872 -233.34599) (xy 388.384796 -233.245914) (xy 388.28472 -233.34599) (xy 388.28472 -233.39044)
			(xy 388.484872 -233.39044)
		)
		(stroke
			(width 0)
			(type solid)
		)
		(fill yes)
		(layer "In11.Cu")
		(net "M_L_CPU0_SA_DQ<12>")
	)
	(gr_poly
		(pts
			(xy 388.484872 -232.942384) (xy 388.484872 -232.894632) (xy 388.28472 -232.894632) (xy 388.28472 -232.942384)
			(xy 388.384796 -233.042206)
		)
		(stroke
			(width 0)
			(type solid)
		)
		(fill yes)
		(layer "In11.Cu")
		(net "M_L_CPU0_SA_DQS_DP<6>")
	)
	(gr_poly
		(pts
			(xy 388.484872 -231.725724) (xy 388.384796 -231.625902) (xy 388.28472 -231.725724) (xy 388.28472 -231.773476)
			(xy 388.484872 -231.773476)
		)
		(stroke
			(width 0)
			(type solid)
		)
		(fill yes)
		(layer "In11.Cu")
		(net "M_L_CPU0_SA_DQS_DP<1>")
	)
	(gr_poly
		(pts
			(xy 388.484872 -231.322372) (xy 388.484872 -231.277922) (xy 388.28472 -231.277922) (xy 388.28472 -231.322372)
			(xy 388.384796 -231.422448)
		)
		(stroke
			(width 0)
			(type solid)
		)
		(fill yes)
		(layer "In11.Cu")
		(net "M_L_CPU0_SA_DQ<11>")
	)
	(gr_poly
		(pts
			(xy 388.484872 -230.105966) (xy 388.384796 -230.006144) (xy 388.28472 -230.105966) (xy 388.28472 -230.150416)
			(xy 388.484872 -230.150416)
		)
		(stroke
			(width 0)
			(type solid)
		)
		(fill yes)
		(layer "In11.Cu")
		(net "M_L_CPU0_SA_DQ<8>")
	)
	(gr_poly
		(pts
			(xy 388.484872 -229.70236) (xy 388.484872 -229.65791) (xy 388.28472 -229.65791) (xy 388.28472 -229.70236)
			(xy 388.384796 -229.802436)
		)
		(stroke
			(width 0)
			(type solid)
		)
		(fill yes)
		(layer "In11.Cu")
		(net "M_L_CPU0_SA_DQ<7>")
	)
	(gr_poly
		(pts
			(xy 388.484872 -228.486208) (xy 388.384796 -228.386132) (xy 388.28472 -228.486208) (xy 388.28472 -228.530658)
			(xy 388.484872 -228.530658)
		)
		(stroke
			(width 0)
			(type solid)
		)
		(fill yes)
		(layer "In11.Cu")
		(net "M_L_CPU0_SA_DQ<4>")
	)
	(gr_poly
		(pts
			(xy 388.484872 -228.082602) (xy 388.484872 -228.03485) (xy 388.28472 -228.03485) (xy 388.28472 -228.082602)
			(xy 388.384796 -228.182424)
		)
		(stroke
			(width 0)
			(type solid)
		)
		(fill yes)
		(layer "In11.Cu")
		(net "M_L_CPU0_SA_DQS_DP<5>")
	)
	(gr_poly
		(pts
			(xy 388.484872 -226.865942) (xy 388.384796 -226.76612) (xy 388.28472 -226.865942) (xy 388.28472 -226.913694)
			(xy 388.484872 -226.913694)
		)
		(stroke
			(width 0)
			(type solid)
		)
		(fill yes)
		(layer "In11.Cu")
		(net "M_L_CPU0_SA_DQS_DP<0>")
	)
	(gr_poly
		(pts
			(xy 388.484872 -226.462336) (xy 388.484872 -226.417886) (xy 388.28472 -226.417886) (xy 388.28472 -226.462336)
			(xy 388.384796 -226.562412)
		)
		(stroke
			(width 0)
			(type solid)
		)
		(fill yes)
		(layer "In11.Cu")
		(net "M_L_CPU0_SA_DQ<3>")
	)
	(gr_poly
		(pts
			(xy 388.484872 -225.246184) (xy 388.384796 -225.146108) (xy 388.28472 -225.246184) (xy 388.28472 -225.290634)
			(xy 388.484872 -225.290634)
		)
		(stroke
			(width 0)
			(type solid)
		)
		(fill yes)
		(layer "In11.Cu")
		(net "M_L_CPU0_SA_DQ<0>")
	)
	(gr_poly
		(pts
			(xy 388.490968 -251.159772) (xy 388.391146 -251.059696) (xy 388.29107 -251.159772) (xy 388.29107 -251.204222)
			(xy 388.490968 -251.204222)
		)
		(stroke
			(width 0)
			(type solid)
		)
		(fill yes)
		(layer "In11.Cu")
		(net "M_L_CPU0_SA_CS_N<0>")
	)
	(gr_poly
		(pts
			(xy 388.784846 -292.91788) (xy 388.68477 -292.817804) (xy 388.584694 -292.91788) (xy 388.584694 -292.96233)
			(xy 388.784846 -292.96233)
		)
		(stroke
			(width 0)
			(type solid)
		)
		(fill yes)
		(layer "In11.Cu")
		(net "M_L_CPU0_SB_DQ<29>")
	)
	(gr_poly
		(pts
			(xy 388.784846 -292.51402) (xy 388.784846 -292.46957) (xy 388.584694 -292.46957) (xy 388.584694 -292.51402)
			(xy 388.68477 -292.614096)
		)
		(stroke
			(width 0)
			(type solid)
		)
		(fill yes)
		(layer "In11.Cu")
		(net "M_L_CPU0_SB_DQ<30>")
	)
	(gr_poly
		(pts
			(xy 388.784846 -291.297614) (xy 388.68477 -291.197792) (xy 388.584694 -291.297614) (xy 388.584694 -291.345366)
			(xy 388.784846 -291.345366)
		)
		(stroke
			(width 0)
			(type solid)
		)
		(fill yes)
		(layer "In11.Cu")
		(net "M_L_CPU0_SB_DQS_DN<8>")
	)
	(gr_poly
		(pts
			(xy 388.784846 -290.894262) (xy 388.784846 -290.84651) (xy 388.584694 -290.84651) (xy 388.584694 -290.894262)
			(xy 388.68477 -290.994084)
		)
		(stroke
			(width 0)
			(type solid)
		)
		(fill yes)
		(layer "In11.Cu")
		(net "M_L_CPU0_SB_DQS_DN<3>")
	)
	(gr_poly
		(pts
			(xy 388.784846 -289.677856) (xy 388.68477 -289.57778) (xy 388.584694 -289.677856) (xy 388.584694 -289.722306)
			(xy 388.784846 -289.722306)
		)
		(stroke
			(width 0)
			(type solid)
		)
		(fill yes)
		(layer "In11.Cu")
		(net "M_L_CPU0_SB_DQ<25>")
	)
	(gr_poly
		(pts
			(xy 388.784846 -289.273996) (xy 388.784846 -289.229546) (xy 388.584694 -289.229546) (xy 388.584694 -289.273996)
			(xy 388.68477 -289.374072)
		)
		(stroke
			(width 0)
			(type solid)
		)
		(fill yes)
		(layer "In11.Cu")
		(net "M_L_CPU0_SB_DQ<26>")
	)
	(gr_poly
		(pts
			(xy 388.784846 -288.057844) (xy 388.68477 -287.957768) (xy 388.584694 -288.057844) (xy 388.584694 -288.102294)
			(xy 388.784846 -288.102294)
		)
		(stroke
			(width 0)
			(type solid)
		)
		(fill yes)
		(layer "In11.Cu")
		(net "M_L_CPU0_SB_DQ<21>")
	)
	(gr_poly
		(pts
			(xy 388.784846 -287.654238) (xy 388.784846 -287.609788) (xy 388.584694 -287.609788) (xy 388.584694 -287.654238)
			(xy 388.68477 -287.75406)
		)
		(stroke
			(width 0)
			(type solid)
		)
		(fill yes)
		(layer "In11.Cu")
		(net "M_L_CPU0_SB_DQ<22>")
	)
	(gr_poly
		(pts
			(xy 388.784846 -286.437832) (xy 388.68477 -286.337756) (xy 388.584694 -286.437832) (xy 388.584694 -286.485584)
			(xy 388.784846 -286.485584)
		)
		(stroke
			(width 0)
			(type solid)
		)
		(fill yes)
		(layer "In11.Cu")
		(net "M_L_CPU0_SB_DQS_DN<7>")
	)
	(gr_poly
		(pts
			(xy 388.784846 -286.03448) (xy 388.784846 -285.986728) (xy 388.584694 -285.986728) (xy 388.584694 -286.03448)
			(xy 388.68477 -286.134302)
		)
		(stroke
			(width 0)
			(type solid)
		)
		(fill yes)
		(layer "In11.Cu")
		(net "M_L_CPU0_SB_DQS_DN<2>")
	)
	(gr_poly
		(pts
			(xy 388.784846 -284.818074) (xy 388.68477 -284.717998) (xy 388.584694 -284.818074) (xy 388.584694 -284.862524)
			(xy 388.784846 -284.862524)
		)
		(stroke
			(width 0)
			(type solid)
		)
		(fill yes)
		(layer "In11.Cu")
		(net "M_L_CPU0_SB_DQ<17>")
	)
	(gr_poly
		(pts
			(xy 388.784846 -284.414214) (xy 388.784846 -284.369764) (xy 388.584694 -284.369764) (xy 388.584694 -284.414214)
			(xy 388.68477 -284.51429)
		)
		(stroke
			(width 0)
			(type solid)
		)
		(fill yes)
		(layer "In11.Cu")
		(net "M_L_CPU0_SB_DQ<18>")
	)
	(gr_poly
		(pts
			(xy 388.784846 -283.198062) (xy 388.68477 -283.097986) (xy 388.584694 -283.198062) (xy 388.584694 -283.242512)
			(xy 388.784846 -283.242512)
		)
		(stroke
			(width 0)
			(type solid)
		)
		(fill yes)
		(layer "In11.Cu")
		(net "M_L_CPU0_SB_DQ<13>")
	)
	(gr_poly
		(pts
			(xy 388.784846 -282.794202) (xy 388.784846 -282.749752) (xy 388.584694 -282.749752) (xy 388.584694 -282.794202)
			(xy 388.68477 -282.894278)
		)
		(stroke
			(width 0)
			(type solid)
		)
		(fill yes)
		(layer "In11.Cu")
		(net "M_L_CPU0_SB_DQ<14>")
	)
	(gr_poly
		(pts
			(xy 388.784846 -281.577796) (xy 388.68477 -281.477974) (xy 388.584694 -281.577796) (xy 388.584694 -281.625548)
			(xy 388.784846 -281.625548)
		)
		(stroke
			(width 0)
			(type solid)
		)
		(fill yes)
		(layer "In11.Cu")
		(net "M_L_CPU0_SB_DQS_DN<6>")
	)
	(gr_poly
		(pts
			(xy 388.784846 -281.174444) (xy 388.784846 -281.126692) (xy 388.584694 -281.126692) (xy 388.584694 -281.174444)
			(xy 388.68477 -281.274266)
		)
		(stroke
			(width 0)
			(type solid)
		)
		(fill yes)
		(layer "In11.Cu")
		(net "M_L_CPU0_SB_DQS_DN<1>")
	)
	(gr_poly
		(pts
			(xy 388.784846 -279.958038) (xy 388.68477 -279.857962) (xy 388.584694 -279.958038) (xy 388.584694 -280.002488)
			(xy 388.784846 -280.002488)
		)
		(stroke
			(width 0)
			(type solid)
		)
		(fill yes)
		(layer "In11.Cu")
		(net "M_L_CPU0_SB_DQ<9>")
	)
	(gr_poly
		(pts
			(xy 388.784846 -279.554178) (xy 388.784846 -279.509728) (xy 388.584694 -279.509728) (xy 388.584694 -279.554178)
			(xy 388.68477 -279.654254)
		)
		(stroke
			(width 0)
			(type solid)
		)
		(fill yes)
		(layer "In11.Cu")
		(net "M_L_CPU0_SB_DQ<10>")
	)
	(gr_poly
		(pts
			(xy 388.784846 -278.338026) (xy 388.68477 -278.23795) (xy 388.584694 -278.338026) (xy 388.584694 -278.382476)
			(xy 388.784846 -278.382476)
		)
		(stroke
			(width 0)
			(type solid)
		)
		(fill yes)
		(layer "In11.Cu")
		(net "M_L_CPU0_SB_DQ<5>")
	)
	(gr_poly
		(pts
			(xy 388.784846 -277.934166) (xy 388.784846 -277.889716) (xy 388.584694 -277.889716) (xy 388.584694 -277.934166)
			(xy 388.68477 -278.034242)
		)
		(stroke
			(width 0)
			(type solid)
		)
		(fill yes)
		(layer "In11.Cu")
		(net "M_L_CPU0_SB_DQ<6>")
	)
	(gr_poly
		(pts
			(xy 388.784846 -276.71776) (xy 388.68477 -276.617938) (xy 388.584694 -276.71776) (xy 388.584694 -276.765512)
			(xy 388.784846 -276.765512)
		)
		(stroke
			(width 0)
			(type solid)
		)
		(fill yes)
		(layer "In11.Cu")
		(net "M_L_CPU0_SB_DQS_DN<5>")
	)
	(gr_poly
		(pts
			(xy 388.784846 -276.314408) (xy 388.784846 -276.266656) (xy 388.584694 -276.266656) (xy 388.584694 -276.314408)
			(xy 388.68477 -276.41423)
		)
		(stroke
			(width 0)
			(type solid)
		)
		(fill yes)
		(layer "In11.Cu")
		(net "M_L_CPU0_SB_DQS_DN<0>")
	)
	(gr_poly
		(pts
			(xy 388.784846 -275.098002) (xy 388.68477 -274.997926) (xy 388.584694 -275.098002) (xy 388.584694 -275.142452)
			(xy 388.784846 -275.142452)
		)
		(stroke
			(width 0)
			(type solid)
		)
		(fill yes)
		(layer "In11.Cu")
		(net "M_L_CPU0_SB_DQ<1>")
	)
	(gr_poly
		(pts
			(xy 388.784846 -274.694142) (xy 388.784846 -274.649692) (xy 388.584694 -274.649692) (xy 388.584694 -274.694142)
			(xy 388.68477 -274.794218)
		)
		(stroke
			(width 0)
			(type solid)
		)
		(fill yes)
		(layer "In11.Cu")
		(net "M_L_CPU0_SB_DQ<2>")
	)
	(gr_poly
		(pts
			(xy 388.784846 -273.47799) (xy 388.68477 -273.377914) (xy 388.584694 -273.47799) (xy 388.584694 -273.52244)
			(xy 388.784846 -273.52244)
		)
		(stroke
			(width 0)
			(type solid)
		)
		(fill yes)
		(layer "In11.Cu")
		(net "M_L_CPU0_SB_CB<1>")
	)
	(gr_poly
		(pts
			(xy 388.784846 -273.07413) (xy 388.784846 -273.02968) (xy 388.584694 -273.02968) (xy 388.584694 -273.07413)
			(xy 388.68477 -273.174206)
		)
		(stroke
			(width 0)
			(type solid)
		)
		(fill yes)
		(layer "In11.Cu")
		(net "M_L_CPU0_SB_CB<2>")
	)
	(gr_poly
		(pts
			(xy 388.784846 -271.857724) (xy 388.68477 -271.757902) (xy 388.584694 -271.857724) (xy 388.584694 -271.905476)
			(xy 388.784846 -271.905476)
		)
		(stroke
			(width 0)
			(type solid)
		)
		(fill yes)
		(layer "In11.Cu")
		(net "M_L_CPU0_SB_DQS_DN<4>")
	)
	(gr_poly
		(pts
			(xy 388.784846 -271.454372) (xy 388.784846 -271.40662) (xy 388.584694 -271.40662) (xy 388.584694 -271.454372)
			(xy 388.68477 -271.554194)
		)
		(stroke
			(width 0)
			(type solid)
		)
		(fill yes)
		(layer "In11.Cu")
		(net "M_L_CPU0_SB_DQS_DN<9>")
	)
	(gr_poly
		(pts
			(xy 388.784846 -270.237966) (xy 388.68477 -270.13789) (xy 388.584694 -270.237966) (xy 388.584694 -270.282416)
			(xy 388.784846 -270.282416)
		)
		(stroke
			(width 0)
			(type solid)
		)
		(fill yes)
		(layer "In11.Cu")
		(net "M_L_CPU0_SB_CB<5>")
	)
	(gr_poly
		(pts
			(xy 388.784846 -269.834106) (xy 388.784846 -269.789656) (xy 388.584694 -269.789656) (xy 388.584694 -269.834106)
			(xy 388.68477 -269.934182)
		)
		(stroke
			(width 0)
			(type solid)
		)
		(fill yes)
		(layer "In11.Cu")
		(net "M_L_CPU0_SB_CB<6>")
	)
	(gr_poly
		(pts
			(xy 388.784846 -266.997942) (xy 388.68477 -266.897866) (xy 388.584694 -266.997942) (xy 388.584694 -267.042392)
			(xy 388.784846 -267.042392)
		)
		(stroke
			(width 0)
			(type solid)
		)
		(fill yes)
		(layer "In11.Cu")
		(net "M_L_CPU0_SA_RSP<0>")
	)
	(gr_poly
		(pts
			(xy 388.784846 -266.594082) (xy 388.784846 -266.549632) (xy 388.584694 -266.549632) (xy 388.584694 -266.594082)
			(xy 388.68477 -266.694158)
		)
		(stroke
			(width 0)
			(type solid)
		)
		(fill yes)
		(layer "In11.Cu")
		(net "M_L_CPU0_SB_CS_N<1>")
	)
	(gr_poly
		(pts
			(xy 388.784846 -265.37793) (xy 388.68477 -265.277854) (xy 388.584694 -265.37793) (xy 388.584694 -265.42238)
			(xy 388.784846 -265.42238)
		)
		(stroke
			(width 0)
			(type solid)
		)
		(fill yes)
		(layer "In11.Cu")
		(net "M_L_CPU0_SB_PAR")
	)
	(gr_poly
		(pts
			(xy 388.784846 -263.757918) (xy 388.68477 -263.657842) (xy 388.584694 -263.757918) (xy 388.584694 -263.802368)
			(xy 388.784846 -263.802368)
		)
		(stroke
			(width 0)
			(type solid)
		)
		(fill yes)
		(layer "In11.Cu")
		(net "M_L_CPU0_SB_CA<4>")
	)
	(gr_poly
		(pts
			(xy 388.784846 -263.354058) (xy 388.784846 -263.309608) (xy 388.584694 -263.309608) (xy 388.584694 -263.354058)
			(xy 388.68477 -263.454134)
		)
		(stroke
			(width 0)
			(type solid)
		)
		(fill yes)
		(layer "In11.Cu")
		(net "M_L_CPU0_SB_CA<3>")
	)
	(gr_poly
		(pts
			(xy 388.784846 -262.137906) (xy 388.68477 -262.03783) (xy 388.584694 -262.137906) (xy 388.584694 -262.182356)
			(xy 388.784846 -262.182356)
		)
		(stroke
			(width 0)
			(type solid)
		)
		(fill yes)
		(layer "In11.Cu")
		(net "M_L_CPU0_SB_CA<0>")
	)
	(gr_poly
		(pts
			(xy 388.954772 -253.19228) (xy 388.954772 -253.14783) (xy 388.75462 -253.14783) (xy 388.75462 -253.19228)
			(xy 388.854696 -253.292356)
		)
		(stroke
			(width 0)
			(type solid)
		)
		(fill yes)
		(layer "In11.Cu")
		(net "M_L_CPU0_SA_CA<1>")
	)
	(gr_poly
		(pts
			(xy 388.955026 -256.432558) (xy 388.955026 -256.384806) (xy 388.754874 -256.384806) (xy 388.754874 -256.432558)
			(xy 388.85495 -256.53238)
		)
		(stroke
			(width 0)
			(type solid)
		)
		(fill yes)
		(layer "In11.Cu")
		(net "M_L_CPU0_CLK_DN<0>")
	)
	(gr_poly
		(pts
			(xy 388.955026 -255.216152) (xy 388.85495 -255.116076) (xy 388.754874 -255.216152) (xy 388.754874 -255.260602)
			(xy 388.955026 -255.260602)
		)
		(stroke
			(width 0)
			(type solid)
		)
		(fill yes)
		(layer "In11.Cu")
		(net "M_L_CPU0_SA_CA<6>")
	)
	(gr_poly
		(pts
			(xy 388.955026 -254.812292) (xy 388.955026 -254.767842) (xy 388.754874 -254.767842) (xy 388.754874 -254.812292)
			(xy 388.85495 -254.912368)
		)
		(stroke
			(width 0)
			(type solid)
		)
		(fill yes)
		(layer "In11.Cu")
		(net "M_L_CPU0_SA_CA<5>")
	)
	(gr_poly
		(pts
			(xy 388.955026 -253.59614) (xy 388.85495 -253.496064) (xy 388.754874 -253.59614) (xy 388.754874 -253.64059)
			(xy 388.955026 -253.64059)
		)
		(stroke
			(width 0)
			(type solid)
		)
		(fill yes)
		(layer "In11.Cu")
		(net "M_L_CPU0_SA_CA<2>")
	)
	(gr_poly
		(pts
			(xy 388.955026 -250.356116) (xy 388.85495 -250.25604) (xy 388.754874 -250.356116) (xy 388.754874 -250.400566)
			(xy 388.955026 -250.400566)
		)
		(stroke
			(width 0)
			(type solid)
		)
		(fill yes)
		(layer "In11.Cu")
		(net "M_L_CPU0_ALERT_R_N")
	)
	(gr_poly
		(pts
			(xy 388.955026 -248.736104) (xy 388.85495 -248.636028) (xy 388.754874 -248.736104) (xy 388.754874 -248.780554)
			(xy 388.955026 -248.780554)
		)
		(stroke
			(width 0)
			(type solid)
		)
		(fill yes)
		(layer "In11.Cu")
		(net "M_L_CPU0_SA_CB<5>")
	)
	(gr_poly
		(pts
			(xy 388.955026 -248.332244) (xy 388.955026 -248.287794) (xy 388.754874 -248.287794) (xy 388.754874 -248.332244)
			(xy 388.85495 -248.43232)
		)
		(stroke
			(width 0)
			(type solid)
		)
		(fill yes)
		(layer "In11.Cu")
		(net "M_L_CPU0_SA_CB<6>")
	)
	(gr_poly
		(pts
			(xy 388.955026 -247.115838) (xy 388.85495 -247.016016) (xy 388.754874 -247.115838) (xy 388.754874 -247.16359)
			(xy 388.955026 -247.16359)
		)
		(stroke
			(width 0)
			(type solid)
		)
		(fill yes)
		(layer "In11.Cu")
		(net "M_L_CPU0_SA_DQS_DN<9>")
	)
	(gr_poly
		(pts
			(xy 388.955026 -246.712486) (xy 388.955026 -246.664734) (xy 388.754874 -246.664734) (xy 388.754874 -246.712486)
			(xy 388.85495 -246.812308)
		)
		(stroke
			(width 0)
			(type solid)
		)
		(fill yes)
		(layer "In11.Cu")
		(net "M_L_CPU0_SA_DQS_DN<4>")
	)
	(gr_poly
		(pts
			(xy 388.955026 -245.49608) (xy 388.85495 -245.396004) (xy 388.754874 -245.49608) (xy 388.754874 -245.54053)
			(xy 388.955026 -245.54053)
		)
		(stroke
			(width 0)
			(type solid)
		)
		(fill yes)
		(layer "In11.Cu")
		(net "M_L_CPU0_SA_CB<1>")
	)
	(gr_poly
		(pts
			(xy 388.955026 -245.09222) (xy 388.955026 -245.04777) (xy 388.754874 -245.04777) (xy 388.754874 -245.09222)
			(xy 388.85495 -245.192296)
		)
		(stroke
			(width 0)
			(type solid)
		)
		(fill yes)
		(layer "In11.Cu")
		(net "M_L_CPU0_SA_CB<2>")
	)
	(gr_poly
		(pts
			(xy 388.955026 -243.876068) (xy 388.85495 -243.775992) (xy 388.754874 -243.876068) (xy 388.754874 -243.920518)
			(xy 388.955026 -243.920518)
		)
		(stroke
			(width 0)
			(type solid)
		)
		(fill yes)
		(layer "In11.Cu")
		(net "M_L_CPU0_SA_DQ<29>")
	)
	(gr_poly
		(pts
			(xy 388.955026 -243.472208) (xy 388.955026 -243.427758) (xy 388.754874 -243.427758) (xy 388.754874 -243.472208)
			(xy 388.85495 -243.572284)
		)
		(stroke
			(width 0)
			(type solid)
		)
		(fill yes)
		(layer "In11.Cu")
		(net "M_L_CPU0_SA_DQ<30>")
	)
	(gr_poly
		(pts
			(xy 388.955026 -242.255802) (xy 388.85495 -242.15598) (xy 388.754874 -242.255802) (xy 388.754874 -242.303554)
			(xy 388.955026 -242.303554)
		)
		(stroke
			(width 0)
			(type solid)
		)
		(fill yes)
		(layer "In11.Cu")
		(net "M_L_CPU0_SA_DQS_DN<8>")
	)
	(gr_poly
		(pts
			(xy 388.955026 -241.85245) (xy 388.955026 -241.804698) (xy 388.754874 -241.804698) (xy 388.754874 -241.85245)
			(xy 388.85495 -241.952272)
		)
		(stroke
			(width 0)
			(type solid)
		)
		(fill yes)
		(layer "In11.Cu")
		(net "M_L_CPU0_SA_DQS_DN<3>")
	)
	(gr_poly
		(pts
			(xy 388.955026 -240.636044) (xy 388.85495 -240.535968) (xy 388.754874 -240.636044) (xy 388.754874 -240.680494)
			(xy 388.955026 -240.680494)
		)
		(stroke
			(width 0)
			(type solid)
		)
		(fill yes)
		(layer "In11.Cu")
		(net "M_L_CPU0_SA_DQ<25>")
	)
	(gr_poly
		(pts
			(xy 388.955026 -240.232184) (xy 388.955026 -240.187734) (xy 388.754874 -240.187734) (xy 388.754874 -240.232184)
			(xy 388.85495 -240.33226)
		)
		(stroke
			(width 0)
			(type solid)
		)
		(fill yes)
		(layer "In11.Cu")
		(net "M_L_CPU0_SA_DQ<26>")
	)
	(gr_poly
		(pts
			(xy 388.955026 -239.016032) (xy 388.85495 -238.915956) (xy 388.754874 -239.016032) (xy 388.754874 -239.060482)
			(xy 388.955026 -239.060482)
		)
		(stroke
			(width 0)
			(type solid)
		)
		(fill yes)
		(layer "In11.Cu")
		(net "M_L_CPU0_SA_DQ<21>")
	)
	(gr_poly
		(pts
			(xy 388.955026 -238.612172) (xy 388.955026 -238.567722) (xy 388.754874 -238.567722) (xy 388.754874 -238.612172)
			(xy 388.85495 -238.712248)
		)
		(stroke
			(width 0)
			(type solid)
		)
		(fill yes)
		(layer "In11.Cu")
		(net "M_L_CPU0_SA_DQ<22>")
	)
	(gr_poly
		(pts
			(xy 388.955026 -237.395766) (xy 388.85495 -237.295944) (xy 388.754874 -237.395766) (xy 388.754874 -237.443518)
			(xy 388.955026 -237.443518)
		)
		(stroke
			(width 0)
			(type solid)
		)
		(fill yes)
		(layer "In11.Cu")
		(net "M_L_CPU0_SA_DQS_DN<7>")
	)
	(gr_poly
		(pts
			(xy 388.955026 -236.992414) (xy 388.955026 -236.944662) (xy 388.754874 -236.944662) (xy 388.754874 -236.992414)
			(xy 388.85495 -237.092236)
		)
		(stroke
			(width 0)
			(type solid)
		)
		(fill yes)
		(layer "In11.Cu")
		(net "M_L_CPU0_SA_DQS_DN<2>")
	)
	(gr_poly
		(pts
			(xy 388.955026 -235.776008) (xy 388.85495 -235.675932) (xy 388.754874 -235.776008) (xy 388.754874 -235.820458)
			(xy 388.955026 -235.820458)
		)
		(stroke
			(width 0)
			(type solid)
		)
		(fill yes)
		(layer "In11.Cu")
		(net "M_L_CPU0_SA_DQ<17>")
	)
	(gr_poly
		(pts
			(xy 388.955026 -235.372148) (xy 388.955026 -235.327698) (xy 388.754874 -235.327698) (xy 388.754874 -235.372148)
			(xy 388.85495 -235.472224)
		)
		(stroke
			(width 0)
			(type solid)
		)
		(fill yes)
		(layer "In11.Cu")
		(net "M_L_CPU0_SA_DQ<18>")
	)
	(gr_poly
		(pts
			(xy 388.955026 -234.155996) (xy 388.85495 -234.05592) (xy 388.754874 -234.155996) (xy 388.754874 -234.200446)
			(xy 388.955026 -234.200446)
		)
		(stroke
			(width 0)
			(type solid)
		)
		(fill yes)
		(layer "In11.Cu")
		(net "M_L_CPU0_SA_DQ<13>")
	)
	(gr_poly
		(pts
			(xy 388.955026 -233.752136) (xy 388.955026 -233.707686) (xy 388.754874 -233.707686) (xy 388.754874 -233.752136)
			(xy 388.85495 -233.852212)
		)
		(stroke
			(width 0)
			(type solid)
		)
		(fill yes)
		(layer "In11.Cu")
		(net "M_L_CPU0_SA_DQ<14>")
	)
	(gr_poly
		(pts
			(xy 388.955026 -232.53573) (xy 388.85495 -232.435908) (xy 388.754874 -232.53573) (xy 388.754874 -232.583482)
			(xy 388.955026 -232.583482)
		)
		(stroke
			(width 0)
			(type solid)
		)
		(fill yes)
		(layer "In11.Cu")
		(net "M_L_CPU0_SA_DQS_DN<6>")
	)
	(gr_poly
		(pts
			(xy 388.955026 -232.132378) (xy 388.955026 -232.084626) (xy 388.754874 -232.084626) (xy 388.754874 -232.132378)
			(xy 388.85495 -232.2322)
		)
		(stroke
			(width 0)
			(type solid)
		)
		(fill yes)
		(layer "In11.Cu")
		(net "M_L_CPU0_SA_DQS_DN<1>")
	)
	(gr_poly
		(pts
			(xy 388.955026 -230.915972) (xy 388.85495 -230.815896) (xy 388.754874 -230.915972) (xy 388.754874 -230.960422)
			(xy 388.955026 -230.960422)
		)
		(stroke
			(width 0)
			(type solid)
		)
		(fill yes)
		(layer "In11.Cu")
		(net "M_L_CPU0_SA_DQ<9>")
	)
	(gr_poly
		(pts
			(xy 388.955026 -230.512366) (xy 388.955026 -230.467916) (xy 388.754874 -230.467916) (xy 388.754874 -230.512366)
			(xy 388.85495 -230.612188)
		)
		(stroke
			(width 0)
			(type solid)
		)
		(fill yes)
		(layer "In11.Cu")
		(net "M_L_CPU0_SA_DQ<10>")
	)
	(gr_poly
		(pts
			(xy 388.955026 -229.29596) (xy 388.85495 -229.195884) (xy 388.754874 -229.29596) (xy 388.754874 -229.34041)
			(xy 388.955026 -229.34041)
		)
		(stroke
			(width 0)
			(type solid)
		)
		(fill yes)
		(layer "In11.Cu")
		(net "M_L_CPU0_SA_DQ<5>")
	)
	(gr_poly
		(pts
			(xy 388.955026 -228.892354) (xy 388.955026 -228.847904) (xy 388.754874 -228.847904) (xy 388.754874 -228.892354)
			(xy 388.85495 -228.99243)
		)
		(stroke
			(width 0)
			(type solid)
		)
		(fill yes)
		(layer "In11.Cu")
		(net "M_L_CPU0_SA_DQ<6>")
	)
	(gr_poly
		(pts
			(xy 388.955026 -227.675948) (xy 388.85495 -227.576126) (xy 388.754874 -227.675948) (xy 388.754874 -227.7237)
			(xy 388.955026 -227.7237)
		)
		(stroke
			(width 0)
			(type solid)
		)
		(fill yes)
		(layer "In11.Cu")
		(net "M_L_CPU0_SA_DQS_DN<5>")
	)
	(gr_poly
		(pts
			(xy 388.955026 -227.272596) (xy 388.955026 -227.224844) (xy 388.754874 -227.224844) (xy 388.754874 -227.272596)
			(xy 388.85495 -227.372418)
		)
		(stroke
			(width 0)
			(type solid)
		)
		(fill yes)
		(layer "In11.Cu")
		(net "M_L_CPU0_SA_DQS_DN<0>")
	)
	(gr_poly
		(pts
			(xy 388.955026 -226.05619) (xy 388.85495 -225.956114) (xy 388.754874 -226.05619) (xy 388.754874 -226.10064)
			(xy 388.955026 -226.10064)
		)
		(stroke
			(width 0)
			(type solid)
		)
		(fill yes)
		(layer "In11.Cu")
		(net "M_L_CPU0_SA_DQ<1>")
	)
	(gr_poly
		(pts
			(xy 388.955026 -225.65233) (xy 388.955026 -225.60788) (xy 388.754874 -225.60788) (xy 388.754874 -225.65233)
			(xy 388.85495 -225.752406)
		)
		(stroke
			(width 0)
			(type solid)
		)
		(fill yes)
		(layer "In11.Cu")
		(net "M_L_CPU0_SA_DQ<2>")
	)
	(gr_poly
		(pts
			(xy 388.960868 -251.969778) (xy 388.861046 -251.869702) (xy 388.76097 -251.969778) (xy 388.76097 -252.014228)
			(xy 388.960868 -252.014228)
		)
		(stroke
			(width 0)
			(type solid)
		)
		(fill yes)
		(layer "In11.Cu")
		(net "M_L_CPU0_SA_CS_N<1>")
	)
	(gr_poly
		(pts
			(xy 389.24865 -264.561574) (xy 389.148574 -264.461498) (xy 389.048752 -264.561574) (xy 389.048752 -264.606024)
			(xy 389.24865 -264.606024)
		)
		(stroke
			(width 0)
			(type solid)
		)
		(fill yes)
		(layer "In11.Cu")
		(net "M_L_CPU0_SB_CA<6>")
	)
	(gr_poly
		(pts
			(xy 389.255 -293.324026) (xy 389.255 -293.279576) (xy 389.054848 -293.279576) (xy 389.054848 -293.324026)
			(xy 389.154924 -293.424102)
		)
		(stroke
			(width 0)
			(type solid)
		)
		(fill yes)
		(layer "In11.Cu")
		(net "M_L_CPU0_SB_DQ<31>")
	)
	(gr_poly
		(pts
			(xy 389.255 -292.107874) (xy 389.154924 -292.007798) (xy 389.054848 -292.107874) (xy 389.054848 -292.152324)
			(xy 389.255 -292.152324)
		)
		(stroke
			(width 0)
			(type solid)
		)
		(fill yes)
		(layer "In11.Cu")
		(net "M_L_CPU0_SB_DQ<28>")
	)
	(gr_poly
		(pts
			(xy 389.255 -291.704268) (xy 389.255 -291.656516) (xy 389.054848 -291.656516) (xy 389.054848 -291.704268)
			(xy 389.154924 -291.80409)
		)
		(stroke
			(width 0)
			(type solid)
		)
		(fill yes)
		(layer "In11.Cu")
		(net "M_L_CPU0_SB_DQS_DP<8>")
	)
	(gr_poly
		(pts
			(xy 389.255 -290.487608) (xy 389.154924 -290.387786) (xy 389.054848 -290.487608) (xy 389.054848 -290.53536)
			(xy 389.255 -290.53536)
		)
		(stroke
			(width 0)
			(type solid)
		)
		(fill yes)
		(layer "In11.Cu")
		(net "M_L_CPU0_SB_DQS_DP<3>")
	)
	(gr_poly
		(pts
			(xy 389.255 -290.084002) (xy 389.255 -290.039552) (xy 389.054848 -290.039552) (xy 389.054848 -290.084002)
			(xy 389.154924 -290.184078)
		)
		(stroke
			(width 0)
			(type solid)
		)
		(fill yes)
		(layer "In11.Cu")
		(net "M_L_CPU0_SB_DQ<27>")
	)
	(gr_poly
		(pts
			(xy 389.255 -288.86785) (xy 389.154924 -288.767774) (xy 389.054848 -288.86785) (xy 389.054848 -288.9123)
			(xy 389.255 -288.9123)
		)
		(stroke
			(width 0)
			(type solid)
		)
		(fill yes)
		(layer "In11.Cu")
		(net "M_L_CPU0_SB_DQ<24>")
	)
	(gr_poly
		(pts
			(xy 389.255 -288.464244) (xy 389.255 -288.419794) (xy 389.054848 -288.419794) (xy 389.054848 -288.464244)
			(xy 389.154924 -288.56432)
		)
		(stroke
			(width 0)
			(type solid)
		)
		(fill yes)
		(layer "In11.Cu")
		(net "M_L_CPU0_SB_DQ<23>")
	)
	(gr_poly
		(pts
			(xy 389.255 -287.247838) (xy 389.154924 -287.148016) (xy 389.054848 -287.247838) (xy 389.054848 -287.292288)
			(xy 389.255 -287.292288)
		)
		(stroke
			(width 0)
			(type solid)
		)
		(fill yes)
		(layer "In11.Cu")
		(net "M_L_CPU0_SB_DQ<20>")
	)
	(gr_poly
		(pts
			(xy 389.255 -286.844232) (xy 389.255 -286.79648) (xy 389.054848 -286.79648) (xy 389.054848 -286.844232)
			(xy 389.154924 -286.944308)
		)
		(stroke
			(width 0)
			(type solid)
		)
		(fill yes)
		(layer "In11.Cu")
		(net "M_L_CPU0_SB_DQS_DP<7>")
	)
	(gr_poly
		(pts
			(xy 389.255 -285.627826) (xy 389.154924 -285.528004) (xy 389.054848 -285.627826) (xy 389.054848 -285.675578)
			(xy 389.255 -285.675578)
		)
		(stroke
			(width 0)
			(type solid)
		)
		(fill yes)
		(layer "In11.Cu")
		(net "M_L_CPU0_SB_DQS_DP<2>")
	)
	(gr_poly
		(pts
			(xy 389.255 -285.22422) (xy 389.255 -285.17977) (xy 389.054848 -285.17977) (xy 389.054848 -285.22422)
			(xy 389.154924 -285.324296)
		)
		(stroke
			(width 0)
			(type solid)
		)
		(fill yes)
		(layer "In11.Cu")
		(net "M_L_CPU0_SB_DQ<19>")
	)
	(gr_poly
		(pts
			(xy 389.255 -284.008068) (xy 389.154924 -283.907992) (xy 389.054848 -284.008068) (xy 389.054848 -284.052518)
			(xy 389.255 -284.052518)
		)
		(stroke
			(width 0)
			(type solid)
		)
		(fill yes)
		(layer "In11.Cu")
		(net "M_L_CPU0_SB_DQ<16>")
	)
	(gr_poly
		(pts
			(xy 389.255 -283.604208) (xy 389.255 -283.559758) (xy 389.054848 -283.559758) (xy 389.054848 -283.604208)
			(xy 389.154924 -283.704284)
		)
		(stroke
			(width 0)
			(type solid)
		)
		(fill yes)
		(layer "In11.Cu")
		(net "M_L_CPU0_SB_DQ<15>")
	)
	(gr_poly
		(pts
			(xy 389.255 -282.388056) (xy 389.154924 -282.28798) (xy 389.054848 -282.388056) (xy 389.054848 -282.432506)
			(xy 389.255 -282.432506)
		)
		(stroke
			(width 0)
			(type solid)
		)
		(fill yes)
		(layer "In11.Cu")
		(net "M_L_CPU0_SB_DQ<12>")
	)
	(gr_poly
		(pts
			(xy 389.255 -281.98445) (xy 389.255 -281.936698) (xy 389.054848 -281.936698) (xy 389.054848 -281.98445)
			(xy 389.154924 -282.084272)
		)
		(stroke
			(width 0)
			(type solid)
		)
		(fill yes)
		(layer "In11.Cu")
		(net "M_L_CPU0_SB_DQS_DP<6>")
	)
	(gr_poly
		(pts
			(xy 389.255 -280.76779) (xy 389.154924 -280.667968) (xy 389.054848 -280.76779) (xy 389.054848 -280.815542)
			(xy 389.255 -280.815542)
		)
		(stroke
			(width 0)
			(type solid)
		)
		(fill yes)
		(layer "In11.Cu")
		(net "M_L_CPU0_SB_DQS_DP<1>")
	)
	(gr_poly
		(pts
			(xy 389.255 -280.364184) (xy 389.255 -280.319734) (xy 389.054848 -280.319734) (xy 389.054848 -280.364184)
			(xy 389.154924 -280.46426)
		)
		(stroke
			(width 0)
			(type solid)
		)
		(fill yes)
		(layer "In11.Cu")
		(net "M_L_CPU0_SB_DQ<11>")
	)
	(gr_poly
		(pts
			(xy 389.255 -279.148032) (xy 389.154924 -279.047956) (xy 389.054848 -279.148032) (xy 389.054848 -279.192482)
			(xy 389.255 -279.192482)
		)
		(stroke
			(width 0)
			(type solid)
		)
		(fill yes)
		(layer "In11.Cu")
		(net "M_L_CPU0_SB_DQ<8>")
	)
	(gr_poly
		(pts
			(xy 389.255 -278.744172) (xy 389.255 -278.699722) (xy 389.054848 -278.699722) (xy 389.054848 -278.744172)
			(xy 389.154924 -278.844248)
		)
		(stroke
			(width 0)
			(type solid)
		)
		(fill yes)
		(layer "In11.Cu")
		(net "M_L_CPU0_SB_DQ<7>")
	)
	(gr_poly
		(pts
			(xy 389.255 -277.52802) (xy 389.154924 -277.427944) (xy 389.054848 -277.52802) (xy 389.054848 -277.57247)
			(xy 389.255 -277.57247)
		)
		(stroke
			(width 0)
			(type solid)
		)
		(fill yes)
		(layer "In11.Cu")
		(net "M_L_CPU0_SB_DQ<4>")
	)
	(gr_poly
		(pts
			(xy 389.255 -277.124414) (xy 389.255 -277.076662) (xy 389.054848 -277.076662) (xy 389.054848 -277.124414)
			(xy 389.154924 -277.224236)
		)
		(stroke
			(width 0)
			(type solid)
		)
		(fill yes)
		(layer "In11.Cu")
		(net "M_L_CPU0_SB_DQS_DP<5>")
	)
	(gr_poly
		(pts
			(xy 389.255 -275.907754) (xy 389.154924 -275.807932) (xy 389.054848 -275.907754) (xy 389.054848 -275.955506)
			(xy 389.255 -275.955506)
		)
		(stroke
			(width 0)
			(type solid)
		)
		(fill yes)
		(layer "In11.Cu")
		(net "M_L_CPU0_SB_DQS_DP<0>")
	)
	(gr_poly
		(pts
			(xy 389.255 -275.504148) (xy 389.255 -275.459698) (xy 389.054848 -275.459698) (xy 389.054848 -275.504148)
			(xy 389.154924 -275.604224)
		)
		(stroke
			(width 0)
			(type solid)
		)
		(fill yes)
		(layer "In11.Cu")
		(net "M_L_CPU0_SB_DQ<3>")
	)
	(gr_poly
		(pts
			(xy 389.255 -274.287996) (xy 389.154924 -274.18792) (xy 389.054848 -274.287996) (xy 389.054848 -274.332446)
			(xy 389.255 -274.332446)
		)
		(stroke
			(width 0)
			(type solid)
		)
		(fill yes)
		(layer "In11.Cu")
		(net "M_L_CPU0_SB_DQ<0>")
	)
	(gr_poly
		(pts
			(xy 389.255 -273.884136) (xy 389.255 -273.839686) (xy 389.054848 -273.839686) (xy 389.054848 -273.884136)
			(xy 389.154924 -273.984212)
		)
		(stroke
			(width 0)
			(type solid)
		)
		(fill yes)
		(layer "In11.Cu")
		(net "M_L_CPU0_SB_CB<3>")
	)
	(gr_poly
		(pts
			(xy 389.255 -272.667984) (xy 389.154924 -272.567908) (xy 389.054848 -272.667984) (xy 389.054848 -272.712434)
			(xy 389.255 -272.712434)
		)
		(stroke
			(width 0)
			(type solid)
		)
		(fill yes)
		(layer "In11.Cu")
		(net "M_L_CPU0_SB_CB<0>")
	)
	(gr_poly
		(pts
			(xy 389.255 -272.264378) (xy 389.255 -272.216626) (xy 389.054848 -272.216626) (xy 389.054848 -272.264378)
			(xy 389.154924 -272.3642)
		)
		(stroke
			(width 0)
			(type solid)
		)
		(fill yes)
		(layer "In11.Cu")
		(net "M_L_CPU0_SB_DQS_DP<4>")
	)
	(gr_poly
		(pts
			(xy 389.255 -271.047718) (xy 389.154924 -270.947896) (xy 389.054848 -271.047718) (xy 389.054848 -271.09547)
			(xy 389.255 -271.09547)
		)
		(stroke
			(width 0)
			(type solid)
		)
		(fill yes)
		(layer "In11.Cu")
		(net "M_L_CPU0_SB_DQS_DP<9>")
	)
	(gr_poly
		(pts
			(xy 389.255 -270.644112) (xy 389.255 -270.599662) (xy 389.054848 -270.599662) (xy 389.054848 -270.644112)
			(xy 389.154924 -270.744188)
		)
		(stroke
			(width 0)
			(type solid)
		)
		(fill yes)
		(layer "In11.Cu")
		(net "M_L_CPU0_SB_CB<7>")
	)
	(gr_poly
		(pts
			(xy 389.255 -269.42796) (xy 389.154924 -269.327884) (xy 389.054848 -269.42796) (xy 389.054848 -269.47241)
			(xy 389.255 -269.47241)
		)
		(stroke
			(width 0)
			(type solid)
		)
		(fill yes)
		(layer "In11.Cu")
		(net "M_L_CPU0_SB_CB<4>")
	)
	(gr_poly
		(pts
			(xy 389.255 -267.807948) (xy 389.154924 -267.707872) (xy 389.054848 -267.807948) (xy 389.054848 -267.852398)
			(xy 389.255 -267.852398)
		)
		(stroke
			(width 0)
			(type solid)
		)
		(fill yes)
		(layer "In11.Cu")
		(net "M_L_CPU0_SB_RSP<0>")
	)
	(gr_poly
		(pts
			(xy 389.255 -265.784076) (xy 389.255 -265.739626) (xy 389.054848 -265.739626) (xy 389.054848 -265.784076)
			(xy 389.154924 -265.884152)
		)
		(stroke
			(width 0)
			(type solid)
		)
		(fill yes)
		(layer "In11.Cu")
		(net "M_L_CPU0_SB_CS_N<0>")
	)
	(gr_poly
		(pts
			(xy 389.255 -264.164064) (xy 389.255 -264.119614) (xy 389.054848 -264.119614) (xy 389.054848 -264.164064)
			(xy 389.154924 -264.26414)
		)
		(stroke
			(width 0)
			(type solid)
		)
		(fill yes)
		(layer "In11.Cu")
		(net "M_L_CPU0_SB_CA<5>")
	)
	(gr_poly
		(pts
			(xy 389.255 -262.947912) (xy 389.154924 -262.847836) (xy 389.054848 -262.947912) (xy 389.054848 -262.992362)
			(xy 389.255 -262.992362)
		)
		(stroke
			(width 0)
			(type solid)
		)
		(fill yes)
		(layer "In11.Cu")
		(net "M_L_CPU0_SB_CA<2>")
	)
	(gr_poly
		(pts
			(xy 389.255 -262.544052) (xy 389.255 -262.499602) (xy 389.054848 -262.499602) (xy 389.054848 -262.544052)
			(xy 389.154924 -262.644128)
		)
		(stroke
			(width 0)
			(type solid)
		)
		(fill yes)
		(layer "In11.Cu")
		(net "M_L_CPU0_SB_CA<1>")
	)
	(gr_poly
		(pts
			(xy 389.424926 -256.025904) (xy 389.32485 -255.926082) (xy 389.224774 -256.025904) (xy 389.224774 -256.073656)
			(xy 389.424926 -256.073656)
		)
		(stroke
			(width 0)
			(type solid)
		)
		(fill yes)
		(layer "In11.Cu")
		(net "M_L_CPU0_CLK_DP<0>")
	)
	(gr_poly
		(pts
			(xy 389.424926 -255.622298) (xy 389.424926 -255.577848) (xy 389.224774 -255.577848) (xy 389.224774 -255.622298)
			(xy 389.32485 -255.722374)
		)
		(stroke
			(width 0)
			(type solid)
		)
		(fill yes)
		(layer "In11.Cu")
		(net "M_L_CPU0_SA_PAR")
	)
	(gr_poly
		(pts
			(xy 389.424926 -254.406146) (xy 389.32485 -254.30607) (xy 389.224774 -254.406146) (xy 389.224774 -254.450596)
			(xy 389.424926 -254.450596)
		)
		(stroke
			(width 0)
			(type solid)
		)
		(fill yes)
		(layer "In11.Cu")
		(net "M_L_CPU0_SA_CA<4>")
	)
	(gr_poly
		(pts
			(xy 389.424926 -254.002286) (xy 389.424926 -253.957836) (xy 389.224774 -253.957836) (xy 389.224774 -254.002286)
			(xy 389.32485 -254.102362)
		)
		(stroke
			(width 0)
			(type solid)
		)
		(fill yes)
		(layer "In11.Cu")
		(net "M_L_CPU0_SA_CA<3>")
	)
	(gr_poly
		(pts
			(xy 389.424926 -252.786134) (xy 389.32485 -252.686058) (xy 389.224774 -252.786134) (xy 389.224774 -252.830584)
			(xy 389.424926 -252.830584)
		)
		(stroke
			(width 0)
			(type solid)
		)
		(fill yes)
		(layer "In11.Cu")
		(net "M_L_CPU0_SA_CA<0>")
	)
	(gr_poly
		(pts
			(xy 389.424926 -251.159772) (xy 389.32485 -251.059696) (xy 389.224774 -251.159772) (xy 389.224774 -251.204222)
			(xy 389.424926 -251.204222)
		)
		(stroke
			(width 0)
			(type solid)
		)
		(fill yes)
		(layer "In11.Cu")
		(net "M_L_CPU0_SA_CS_N<0>")
	)
	(gr_poly
		(pts
			(xy 389.424926 -250.762262) (xy 389.424926 -250.717812) (xy 389.224774 -250.717812) (xy 389.224774 -250.762262)
			(xy 389.32485 -250.862338)
		)
		(stroke
			(width 0)
			(type solid)
		)
		(fill yes)
		(layer "In11.Cu")
		(net "M_L_CPU0_RESET_N")
	)
	(gr_poly
		(pts
			(xy 389.424926 -249.14225) (xy 389.424926 -249.0978) (xy 389.224774 -249.0978) (xy 389.224774 -249.14225)
			(xy 389.32485 -249.242326)
		)
		(stroke
			(width 0)
			(type solid)
		)
		(fill yes)
		(layer "In11.Cu")
		(net "M_L_CPU0_SA_CB<7>")
	)
	(gr_poly
		(pts
			(xy 389.424926 -247.926098) (xy 389.32485 -247.826022) (xy 389.224774 -247.926098) (xy 389.224774 -247.970548)
			(xy 389.424926 -247.970548)
		)
		(stroke
			(width 0)
			(type solid)
		)
		(fill yes)
		(layer "In11.Cu")
		(net "M_L_CPU0_SA_CB<4>")
	)
	(gr_poly
		(pts
			(xy 389.424926 -247.522492) (xy 389.424926 -247.47474) (xy 389.224774 -247.47474) (xy 389.224774 -247.522492)
			(xy 389.32485 -247.622314)
		)
		(stroke
			(width 0)
			(type solid)
		)
		(fill yes)
		(layer "In11.Cu")
		(net "M_L_CPU0_SA_DQS_DP<9>")
	)
	(gr_poly
		(pts
			(xy 389.424926 -246.305832) (xy 389.32485 -246.20601) (xy 389.224774 -246.305832) (xy 389.224774 -246.353584)
			(xy 389.424926 -246.353584)
		)
		(stroke
			(width 0)
			(type solid)
		)
		(fill yes)
		(layer "In11.Cu")
		(net "M_L_CPU0_SA_DQS_DP<4>")
	)
	(gr_poly
		(pts
			(xy 389.424926 -245.902226) (xy 389.424926 -245.857776) (xy 389.224774 -245.857776) (xy 389.224774 -245.902226)
			(xy 389.32485 -246.002302)
		)
		(stroke
			(width 0)
			(type solid)
		)
		(fill yes)
		(layer "In11.Cu")
		(net "M_L_CPU0_SA_CB<3>")
	)
	(gr_poly
		(pts
			(xy 389.424926 -244.686074) (xy 389.32485 -244.585998) (xy 389.224774 -244.686074) (xy 389.224774 -244.730524)
			(xy 389.424926 -244.730524)
		)
		(stroke
			(width 0)
			(type solid)
		)
		(fill yes)
		(layer "In11.Cu")
		(net "M_L_CPU0_SA_CB<0>")
	)
	(gr_poly
		(pts
			(xy 389.424926 -244.282214) (xy 389.424926 -244.237764) (xy 389.224774 -244.237764) (xy 389.224774 -244.282214)
			(xy 389.32485 -244.38229)
		)
		(stroke
			(width 0)
			(type solid)
		)
		(fill yes)
		(layer "In11.Cu")
		(net "M_L_CPU0_SA_DQ<31>")
	)
	(gr_poly
		(pts
			(xy 389.424926 -243.066062) (xy 389.32485 -242.965986) (xy 389.224774 -243.066062) (xy 389.224774 -243.110512)
			(xy 389.424926 -243.110512)
		)
		(stroke
			(width 0)
			(type solid)
		)
		(fill yes)
		(layer "In11.Cu")
		(net "M_L_CPU0_SA_DQ<28>")
	)
	(gr_poly
		(pts
			(xy 389.424926 -242.662456) (xy 389.424926 -242.614704) (xy 389.224774 -242.614704) (xy 389.224774 -242.662456)
			(xy 389.32485 -242.762278)
		)
		(stroke
			(width 0)
			(type solid)
		)
		(fill yes)
		(layer "In11.Cu")
		(net "M_L_CPU0_SA_DQS_DP<8>")
	)
	(gr_poly
		(pts
			(xy 389.424926 -241.445796) (xy 389.32485 -241.345974) (xy 389.224774 -241.445796) (xy 389.224774 -241.493548)
			(xy 389.424926 -241.493548)
		)
		(stroke
			(width 0)
			(type solid)
		)
		(fill yes)
		(layer "In11.Cu")
		(net "M_L_CPU0_SA_DQS_DP<3>")
	)
	(gr_poly
		(pts
			(xy 389.424926 -241.04219) (xy 389.424926 -240.99774) (xy 389.224774 -240.99774) (xy 389.224774 -241.04219)
			(xy 389.32485 -241.142266)
		)
		(stroke
			(width 0)
			(type solid)
		)
		(fill yes)
		(layer "In11.Cu")
		(net "M_L_CPU0_SA_DQ<27>")
	)
	(gr_poly
		(pts
			(xy 389.424926 -239.826038) (xy 389.32485 -239.725962) (xy 389.224774 -239.826038) (xy 389.224774 -239.870488)
			(xy 389.424926 -239.870488)
		)
		(stroke
			(width 0)
			(type solid)
		)
		(fill yes)
		(layer "In11.Cu")
		(net "M_L_CPU0_SA_DQ<24>")
	)
	(gr_poly
		(pts
			(xy 389.424926 -239.422178) (xy 389.424926 -239.377728) (xy 389.224774 -239.377728) (xy 389.224774 -239.422178)
			(xy 389.32485 -239.522254)
		)
		(stroke
			(width 0)
			(type solid)
		)
		(fill yes)
		(layer "In11.Cu")
		(net "M_L_CPU0_SA_DQ<23>")
	)
	(gr_poly
		(pts
			(xy 389.424926 -238.206026) (xy 389.32485 -238.10595) (xy 389.224774 -238.206026) (xy 389.224774 -238.250476)
			(xy 389.424926 -238.250476)
		)
		(stroke
			(width 0)
			(type solid)
		)
		(fill yes)
		(layer "In11.Cu")
		(net "M_L_CPU0_SA_DQ<20>")
	)
	(gr_poly
		(pts
			(xy 389.424926 -237.80242) (xy 389.424926 -237.754668) (xy 389.224774 -237.754668) (xy 389.224774 -237.80242)
			(xy 389.32485 -237.902242)
		)
		(stroke
			(width 0)
			(type solid)
		)
		(fill yes)
		(layer "In11.Cu")
		(net "M_L_CPU0_SA_DQS_DP<7>")
	)
	(gr_poly
		(pts
			(xy 389.424926 -236.58576) (xy 389.32485 -236.485938) (xy 389.224774 -236.58576) (xy 389.224774 -236.633512)
			(xy 389.424926 -236.633512)
		)
		(stroke
			(width 0)
			(type solid)
		)
		(fill yes)
		(layer "In11.Cu")
		(net "M_L_CPU0_SA_DQS_DP<2>")
	)
	(gr_poly
		(pts
			(xy 389.424926 -236.182154) (xy 389.424926 -236.137704) (xy 389.224774 -236.137704) (xy 389.224774 -236.182154)
			(xy 389.32485 -236.28223)
		)
		(stroke
			(width 0)
			(type solid)
		)
		(fill yes)
		(layer "In11.Cu")
		(net "M_L_CPU0_SA_DQ<19>")
	)
	(gr_poly
		(pts
			(xy 389.424926 -234.966002) (xy 389.32485 -234.865926) (xy 389.224774 -234.966002) (xy 389.224774 -235.010452)
			(xy 389.424926 -235.010452)
		)
		(stroke
			(width 0)
			(type solid)
		)
		(fill yes)
		(layer "In11.Cu")
		(net "M_L_CPU0_SA_DQ<16>")
	)
	(gr_poly
		(pts
			(xy 389.424926 -234.562142) (xy 389.424926 -234.517692) (xy 389.224774 -234.517692) (xy 389.224774 -234.562142)
			(xy 389.32485 -234.662218)
		)
		(stroke
			(width 0)
			(type solid)
		)
		(fill yes)
		(layer "In11.Cu")
		(net "M_L_CPU0_SA_DQ<15>")
	)
	(gr_poly
		(pts
			(xy 389.424926 -233.34599) (xy 389.32485 -233.245914) (xy 389.224774 -233.34599) (xy 389.224774 -233.39044)
			(xy 389.424926 -233.39044)
		)
		(stroke
			(width 0)
			(type solid)
		)
		(fill yes)
		(layer "In11.Cu")
		(net "M_L_CPU0_SA_DQ<12>")
	)
	(gr_poly
		(pts
			(xy 389.424926 -232.942384) (xy 389.424926 -232.894632) (xy 389.224774 -232.894632) (xy 389.224774 -232.942384)
			(xy 389.32485 -233.042206)
		)
		(stroke
			(width 0)
			(type solid)
		)
		(fill yes)
		(layer "In11.Cu")
		(net "M_L_CPU0_SA_DQS_DP<6>")
	)
	(gr_poly
		(pts
			(xy 389.424926 -231.725724) (xy 389.32485 -231.625902) (xy 389.224774 -231.725724) (xy 389.224774 -231.773476)
			(xy 389.424926 -231.773476)
		)
		(stroke
			(width 0)
			(type solid)
		)
		(fill yes)
		(layer "In11.Cu")
		(net "M_L_CPU0_SA_DQS_DP<1>")
	)
	(gr_poly
		(pts
			(xy 389.424926 -231.322372) (xy 389.424926 -231.277922) (xy 389.224774 -231.277922) (xy 389.224774 -231.322372)
			(xy 389.32485 -231.422448)
		)
		(stroke
			(width 0)
			(type solid)
		)
		(fill yes)
		(layer "In11.Cu")
		(net "M_L_CPU0_SA_DQ<11>")
	)
	(gr_poly
		(pts
			(xy 389.424926 -230.105966) (xy 389.32485 -230.006144) (xy 389.224774 -230.105966) (xy 389.224774 -230.150416)
			(xy 389.424926 -230.150416)
		)
		(stroke
			(width 0)
			(type solid)
		)
		(fill yes)
		(layer "In11.Cu")
		(net "M_L_CPU0_SA_DQ<8>")
	)
	(gr_poly
		(pts
			(xy 389.424926 -229.70236) (xy 389.424926 -229.65791) (xy 389.224774 -229.65791) (xy 389.224774 -229.70236)
			(xy 389.32485 -229.802436)
		)
		(stroke
			(width 0)
			(type solid)
		)
		(fill yes)
		(layer "In11.Cu")
		(net "M_L_CPU0_SA_DQ<7>")
	)
	(gr_poly
		(pts
			(xy 389.424926 -228.486208) (xy 389.32485 -228.386132) (xy 389.224774 -228.486208) (xy 389.224774 -228.530658)
			(xy 389.424926 -228.530658)
		)
		(stroke
			(width 0)
			(type solid)
		)
		(fill yes)
		(layer "In11.Cu")
		(net "M_L_CPU0_SA_DQ<4>")
	)
	(gr_poly
		(pts
			(xy 389.424926 -228.082602) (xy 389.424926 -228.03485) (xy 389.224774 -228.03485) (xy 389.224774 -228.082602)
			(xy 389.32485 -228.182424)
		)
		(stroke
			(width 0)
			(type solid)
		)
		(fill yes)
		(layer "In11.Cu")
		(net "M_L_CPU0_SA_DQS_DP<5>")
	)
	(gr_poly
		(pts
			(xy 389.424926 -226.865942) (xy 389.32485 -226.76612) (xy 389.224774 -226.865942) (xy 389.224774 -226.913694)
			(xy 389.424926 -226.913694)
		)
		(stroke
			(width 0)
			(type solid)
		)
		(fill yes)
		(layer "In11.Cu")
		(net "M_L_CPU0_SA_DQS_DP<0>")
	)
	(gr_poly
		(pts
			(xy 389.424926 -226.462336) (xy 389.424926 -226.417886) (xy 389.224774 -226.417886) (xy 389.224774 -226.462336)
			(xy 389.32485 -226.562412)
		)
		(stroke
			(width 0)
			(type solid)
		)
		(fill yes)
		(layer "In11.Cu")
		(net "M_L_CPU0_SA_DQ<3>")
	)
	(gr_poly
		(pts
			(xy 389.424926 -225.246184) (xy 389.32485 -225.146108) (xy 389.224774 -225.246184) (xy 389.224774 -225.290634)
			(xy 389.424926 -225.290634)
		)
		(stroke
			(width 0)
			(type solid)
		)
		(fill yes)
		(layer "In11.Cu")
		(net "M_L_CPU0_SA_DQ<0>")
	)
	(gr_poly
		(pts
			(xy 389.7249 -292.91788) (xy 389.624824 -292.817804) (xy 389.524748 -292.91788) (xy 389.524748 -292.96233)
			(xy 389.7249 -292.96233)
		)
		(stroke
			(width 0)
			(type solid)
		)
		(fill yes)
		(layer "In11.Cu")
		(net "M_L_CPU0_SB_DQ<29>")
	)
	(gr_poly
		(pts
			(xy 389.7249 -292.51402) (xy 389.7249 -292.46957) (xy 389.524748 -292.46957) (xy 389.524748 -292.51402)
			(xy 389.624824 -292.614096)
		)
		(stroke
			(width 0)
			(type solid)
		)
		(fill yes)
		(layer "In11.Cu")
		(net "M_L_CPU0_SB_DQ<30>")
	)
	(gr_poly
		(pts
			(xy 389.7249 -291.297614) (xy 389.624824 -291.197792) (xy 389.524748 -291.297614) (xy 389.524748 -291.345366)
			(xy 389.7249 -291.345366)
		)
		(stroke
			(width 0)
			(type solid)
		)
		(fill yes)
		(layer "In11.Cu")
		(net "M_L_CPU0_SB_DQS_DN<8>")
	)
	(gr_poly
		(pts
			(xy 389.7249 -290.894262) (xy 389.7249 -290.84651) (xy 389.524748 -290.84651) (xy 389.524748 -290.894262)
			(xy 389.624824 -290.994084)
		)
		(stroke
			(width 0)
			(type solid)
		)
		(fill yes)
		(layer "In11.Cu")
		(net "M_L_CPU0_SB_DQS_DN<3>")
	)
	(gr_poly
		(pts
			(xy 389.7249 -289.677856) (xy 389.624824 -289.57778) (xy 389.524748 -289.677856) (xy 389.524748 -289.722306)
			(xy 389.7249 -289.722306)
		)
		(stroke
			(width 0)
			(type solid)
		)
		(fill yes)
		(layer "In11.Cu")
		(net "M_L_CPU0_SB_DQ<25>")
	)
	(gr_poly
		(pts
			(xy 389.7249 -289.273996) (xy 389.7249 -289.229546) (xy 389.524748 -289.229546) (xy 389.524748 -289.273996)
			(xy 389.624824 -289.374072)
		)
		(stroke
			(width 0)
			(type solid)
		)
		(fill yes)
		(layer "In11.Cu")
		(net "M_L_CPU0_SB_DQ<26>")
	)
	(gr_poly
		(pts
			(xy 389.7249 -288.057844) (xy 389.624824 -287.957768) (xy 389.524748 -288.057844) (xy 389.524748 -288.102294)
			(xy 389.7249 -288.102294)
		)
		(stroke
			(width 0)
			(type solid)
		)
		(fill yes)
		(layer "In11.Cu")
		(net "M_L_CPU0_SB_DQ<21>")
	)
	(gr_poly
		(pts
			(xy 389.7249 -287.654238) (xy 389.7249 -287.609788) (xy 389.524748 -287.609788) (xy 389.524748 -287.654238)
			(xy 389.624824 -287.75406)
		)
		(stroke
			(width 0)
			(type solid)
		)
		(fill yes)
		(layer "In11.Cu")
		(net "M_L_CPU0_SB_DQ<22>")
	)
	(gr_poly
		(pts
			(xy 389.7249 -286.437832) (xy 389.624824 -286.337756) (xy 389.524748 -286.437832) (xy 389.524748 -286.485584)
			(xy 389.7249 -286.485584)
		)
		(stroke
			(width 0)
			(type solid)
		)
		(fill yes)
		(layer "In11.Cu")
		(net "M_L_CPU0_SB_DQS_DN<7>")
	)
	(gr_poly
		(pts
			(xy 389.7249 -286.03448) (xy 389.7249 -285.986728) (xy 389.524748 -285.986728) (xy 389.524748 -286.03448)
			(xy 389.624824 -286.134302)
		)
		(stroke
			(width 0)
			(type solid)
		)
		(fill yes)
		(layer "In11.Cu")
		(net "M_L_CPU0_SB_DQS_DN<2>")
	)
	(gr_poly
		(pts
			(xy 389.7249 -284.818074) (xy 389.624824 -284.717998) (xy 389.524748 -284.818074) (xy 389.524748 -284.862524)
			(xy 389.7249 -284.862524)
		)
		(stroke
			(width 0)
			(type solid)
		)
		(fill yes)
		(layer "In11.Cu")
		(net "M_L_CPU0_SB_DQ<17>")
	)
	(gr_poly
		(pts
			(xy 389.7249 -284.414214) (xy 389.7249 -284.369764) (xy 389.524748 -284.369764) (xy 389.524748 -284.414214)
			(xy 389.624824 -284.51429)
		)
		(stroke
			(width 0)
			(type solid)
		)
		(fill yes)
		(layer "In11.Cu")
		(net "M_L_CPU0_SB_DQ<18>")
	)
	(gr_poly
		(pts
			(xy 389.7249 -283.198062) (xy 389.624824 -283.097986) (xy 389.524748 -283.198062) (xy 389.524748 -283.242512)
			(xy 389.7249 -283.242512)
		)
		(stroke
			(width 0)
			(type solid)
		)
		(fill yes)
		(layer "In11.Cu")
		(net "M_L_CPU0_SB_DQ<13>")
	)
	(gr_poly
		(pts
			(xy 389.7249 -282.794202) (xy 389.7249 -282.749752) (xy 389.524748 -282.749752) (xy 389.524748 -282.794202)
			(xy 389.624824 -282.894278)
		)
		(stroke
			(width 0)
			(type solid)
		)
		(fill yes)
		(layer "In11.Cu")
		(net "M_L_CPU0_SB_DQ<14>")
	)
	(gr_poly
		(pts
			(xy 389.7249 -281.577796) (xy 389.624824 -281.477974) (xy 389.524748 -281.577796) (xy 389.524748 -281.625548)
			(xy 389.7249 -281.625548)
		)
		(stroke
			(width 0)
			(type solid)
		)
		(fill yes)
		(layer "In11.Cu")
		(net "M_L_CPU0_SB_DQS_DN<6>")
	)
	(gr_poly
		(pts
			(xy 389.7249 -281.174444) (xy 389.7249 -281.126692) (xy 389.524748 -281.126692) (xy 389.524748 -281.174444)
			(xy 389.624824 -281.274266)
		)
		(stroke
			(width 0)
			(type solid)
		)
		(fill yes)
		(layer "In11.Cu")
		(net "M_L_CPU0_SB_DQS_DN<1>")
	)
	(gr_poly
		(pts
			(xy 389.7249 -279.958038) (xy 389.624824 -279.857962) (xy 389.524748 -279.958038) (xy 389.524748 -280.002488)
			(xy 389.7249 -280.002488)
		)
		(stroke
			(width 0)
			(type solid)
		)
		(fill yes)
		(layer "In11.Cu")
		(net "M_L_CPU0_SB_DQ<9>")
	)
	(gr_poly
		(pts
			(xy 389.7249 -279.554178) (xy 389.7249 -279.509728) (xy 389.524748 -279.509728) (xy 389.524748 -279.554178)
			(xy 389.624824 -279.654254)
		)
		(stroke
			(width 0)
			(type solid)
		)
		(fill yes)
		(layer "In11.Cu")
		(net "M_L_CPU0_SB_DQ<10>")
	)
	(gr_poly
		(pts
			(xy 389.7249 -278.338026) (xy 389.624824 -278.23795) (xy 389.524748 -278.338026) (xy 389.524748 -278.382476)
			(xy 389.7249 -278.382476)
		)
		(stroke
			(width 0)
			(type solid)
		)
		(fill yes)
		(layer "In11.Cu")
		(net "M_L_CPU0_SB_DQ<5>")
	)
	(gr_poly
		(pts
			(xy 389.7249 -277.934166) (xy 389.7249 -277.889716) (xy 389.524748 -277.889716) (xy 389.524748 -277.934166)
			(xy 389.624824 -278.034242)
		)
		(stroke
			(width 0)
			(type solid)
		)
		(fill yes)
		(layer "In11.Cu")
		(net "M_L_CPU0_SB_DQ<6>")
	)
	(gr_poly
		(pts
			(xy 389.7249 -276.71776) (xy 389.624824 -276.617938) (xy 389.524748 -276.71776) (xy 389.524748 -276.765512)
			(xy 389.7249 -276.765512)
		)
		(stroke
			(width 0)
			(type solid)
		)
		(fill yes)
		(layer "In11.Cu")
		(net "M_L_CPU0_SB_DQS_DN<5>")
	)
	(gr_poly
		(pts
			(xy 389.7249 -276.314408) (xy 389.7249 -276.266656) (xy 389.524748 -276.266656) (xy 389.524748 -276.314408)
			(xy 389.624824 -276.41423)
		)
		(stroke
			(width 0)
			(type solid)
		)
		(fill yes)
		(layer "In11.Cu")
		(net "M_L_CPU0_SB_DQS_DN<0>")
	)
	(gr_poly
		(pts
			(xy 389.7249 -275.098002) (xy 389.624824 -274.997926) (xy 389.524748 -275.098002) (xy 389.524748 -275.142452)
			(xy 389.7249 -275.142452)
		)
		(stroke
			(width 0)
			(type solid)
		)
		(fill yes)
		(layer "In11.Cu")
		(net "M_L_CPU0_SB_DQ<1>")
	)
	(gr_poly
		(pts
			(xy 389.7249 -274.694142) (xy 389.7249 -274.649692) (xy 389.524748 -274.649692) (xy 389.524748 -274.694142)
			(xy 389.624824 -274.794218)
		)
		(stroke
			(width 0)
			(type solid)
		)
		(fill yes)
		(layer "In11.Cu")
		(net "M_L_CPU0_SB_DQ<2>")
	)
	(gr_poly
		(pts
			(xy 389.7249 -273.47799) (xy 389.624824 -273.377914) (xy 389.524748 -273.47799) (xy 389.524748 -273.52244)
			(xy 389.7249 -273.52244)
		)
		(stroke
			(width 0)
			(type solid)
		)
		(fill yes)
		(layer "In11.Cu")
		(net "M_L_CPU0_SB_CB<1>")
	)
	(gr_poly
		(pts
			(xy 389.7249 -273.07413) (xy 389.7249 -273.02968) (xy 389.524748 -273.02968) (xy 389.524748 -273.07413)
			(xy 389.624824 -273.174206)
		)
		(stroke
			(width 0)
			(type solid)
		)
		(fill yes)
		(layer "In11.Cu")
		(net "M_L_CPU0_SB_CB<2>")
	)
	(gr_poly
		(pts
			(xy 389.7249 -271.857724) (xy 389.624824 -271.757902) (xy 389.524748 -271.857724) (xy 389.524748 -271.905476)
			(xy 389.7249 -271.905476)
		)
		(stroke
			(width 0)
			(type solid)
		)
		(fill yes)
		(layer "In11.Cu")
		(net "M_L_CPU0_SB_DQS_DN<4>")
	)
	(gr_poly
		(pts
			(xy 389.7249 -271.454372) (xy 389.7249 -271.40662) (xy 389.524748 -271.40662) (xy 389.524748 -271.454372)
			(xy 389.624824 -271.554194)
		)
		(stroke
			(width 0)
			(type solid)
		)
		(fill yes)
		(layer "In11.Cu")
		(net "M_L_CPU0_SB_DQS_DN<9>")
	)
	(gr_poly
		(pts
			(xy 389.7249 -270.237966) (xy 389.624824 -270.13789) (xy 389.524748 -270.237966) (xy 389.524748 -270.282416)
			(xy 389.7249 -270.282416)
		)
		(stroke
			(width 0)
			(type solid)
		)
		(fill yes)
		(layer "In11.Cu")
		(net "M_L_CPU0_SB_CB<5>")
	)
	(gr_poly
		(pts
			(xy 389.7249 -269.834106) (xy 389.7249 -269.789656) (xy 389.524748 -269.789656) (xy 389.524748 -269.834106)
			(xy 389.624824 -269.934182)
		)
		(stroke
			(width 0)
			(type solid)
		)
		(fill yes)
		(layer "In11.Cu")
		(net "M_L_CPU0_SB_CB<6>")
	)
	(gr_poly
		(pts
			(xy 389.7249 -266.997942) (xy 389.624824 -266.897866) (xy 389.524748 -266.997942) (xy 389.524748 -267.042392)
			(xy 389.7249 -267.042392)
		)
		(stroke
			(width 0)
			(type solid)
		)
		(fill yes)
		(layer "In11.Cu")
		(net "M_L_CPU0_SA_RSP<0>")
	)
	(gr_poly
		(pts
			(xy 389.7249 -266.594082) (xy 389.7249 -266.549632) (xy 389.524748 -266.549632) (xy 389.524748 -266.594082)
			(xy 389.624824 -266.694158)
		)
		(stroke
			(width 0)
			(type solid)
		)
		(fill yes)
		(layer "In11.Cu")
		(net "M_L_CPU0_SB_CS_N<1>")
	)
	(gr_poly
		(pts
			(xy 389.7249 -265.37793) (xy 389.624824 -265.277854) (xy 389.524748 -265.37793) (xy 389.524748 -265.42238)
			(xy 389.7249 -265.42238)
		)
		(stroke
			(width 0)
			(type solid)
		)
		(fill yes)
		(layer "In11.Cu")
		(net "M_L_CPU0_SB_PAR")
	)
	(gr_poly
		(pts
			(xy 389.7249 -263.757918) (xy 389.624824 -263.657842) (xy 389.524748 -263.757918) (xy 389.524748 -263.802368)
			(xy 389.7249 -263.802368)
		)
		(stroke
			(width 0)
			(type solid)
		)
		(fill yes)
		(layer "In11.Cu")
		(net "M_L_CPU0_SB_CA<4>")
	)
	(gr_poly
		(pts
			(xy 389.7249 -263.354058) (xy 389.7249 -263.309608) (xy 389.524748 -263.309608) (xy 389.524748 -263.354058)
			(xy 389.624824 -263.454134)
		)
		(stroke
			(width 0)
			(type solid)
		)
		(fill yes)
		(layer "In11.Cu")
		(net "M_L_CPU0_SB_CA<3>")
	)
	(gr_poly
		(pts
			(xy 389.7249 -262.137906) (xy 389.624824 -262.03783) (xy 389.524748 -262.137906) (xy 389.524748 -262.182356)
			(xy 389.7249 -262.182356)
		)
		(stroke
			(width 0)
			(type solid)
		)
		(fill yes)
		(layer "In11.Cu")
		(net "M_L_CPU0_SB_CA<0>")
	)
	(gr_poly
		(pts
			(xy 389.894826 -256.432558) (xy 389.894826 -256.384806) (xy 389.694674 -256.384806) (xy 389.694674 -256.432558)
			(xy 389.79475 -256.53238)
		)
		(stroke
			(width 0)
			(type solid)
		)
		(fill yes)
		(layer "In11.Cu")
		(net "M_L_CPU0_CLK_DN<0>")
	)
	(gr_poly
		(pts
			(xy 389.894826 -255.216152) (xy 389.79475 -255.116076) (xy 389.694674 -255.216152) (xy 389.694674 -255.260602)
			(xy 389.894826 -255.260602)
		)
		(stroke
			(width 0)
			(type solid)
		)
		(fill yes)
		(layer "In11.Cu")
		(net "M_L_CPU0_SA_CA<6>")
	)
	(gr_poly
		(pts
			(xy 389.894826 -254.812292) (xy 389.894826 -254.767842) (xy 389.694674 -254.767842) (xy 389.694674 -254.812292)
			(xy 389.79475 -254.912368)
		)
		(stroke
			(width 0)
			(type solid)
		)
		(fill yes)
		(layer "In11.Cu")
		(net "M_L_CPU0_SA_CA<5>")
	)
	(gr_poly
		(pts
			(xy 389.894826 -253.59614) (xy 389.79475 -253.496064) (xy 389.694674 -253.59614) (xy 389.694674 -253.64059)
			(xy 389.894826 -253.64059)
		)
		(stroke
			(width 0)
			(type solid)
		)
		(fill yes)
		(layer "In11.Cu")
		(net "M_L_CPU0_SA_CA<2>")
	)
	(gr_poly
		(pts
			(xy 389.894826 -253.19228) (xy 389.894826 -253.14783) (xy 389.694674 -253.14783) (xy 389.694674 -253.19228)
			(xy 389.79475 -253.292356)
		)
		(stroke
			(width 0)
			(type solid)
		)
		(fill yes)
		(layer "In11.Cu")
		(net "M_L_CPU0_SA_CA<1>")
	)
	(gr_poly
		(pts
			(xy 389.894826 -250.356116) (xy 389.79475 -250.25604) (xy 389.694674 -250.356116) (xy 389.694674 -250.400566)
			(xy 389.894826 -250.400566)
		)
		(stroke
			(width 0)
			(type solid)
		)
		(fill yes)
		(layer "In11.Cu")
		(net "M_L_CPU0_ALERT_R_N")
	)
	(gr_poly
		(pts
			(xy 389.894826 -248.736104) (xy 389.79475 -248.636028) (xy 389.694674 -248.736104) (xy 389.694674 -248.780554)
			(xy 389.894826 -248.780554)
		)
		(stroke
			(width 0)
			(type solid)
		)
		(fill yes)
		(layer "In11.Cu")
		(net "M_L_CPU0_SA_CB<5>")
	)
	(gr_poly
		(pts
			(xy 389.894826 -248.332244) (xy 389.894826 -248.287794) (xy 389.694674 -248.287794) (xy 389.694674 -248.332244)
			(xy 389.79475 -248.43232)
		)
		(stroke
			(width 0)
			(type solid)
		)
		(fill yes)
		(layer "In11.Cu")
		(net "M_L_CPU0_SA_CB<6>")
	)
	(gr_poly
		(pts
			(xy 389.894826 -247.115838) (xy 389.79475 -247.016016) (xy 389.694674 -247.115838) (xy 389.694674 -247.16359)
			(xy 389.894826 -247.16359)
		)
		(stroke
			(width 0)
			(type solid)
		)
		(fill yes)
		(layer "In11.Cu")
		(net "M_L_CPU0_SA_DQS_DN<9>")
	)
	(gr_poly
		(pts
			(xy 389.894826 -246.712486) (xy 389.894826 -246.664734) (xy 389.694674 -246.664734) (xy 389.694674 -246.712486)
			(xy 389.79475 -246.812308)
		)
		(stroke
			(width 0)
			(type solid)
		)
		(fill yes)
		(layer "In11.Cu")
		(net "M_L_CPU0_SA_DQS_DN<4>")
	)
	(gr_poly
		(pts
			(xy 389.894826 -245.49608) (xy 389.79475 -245.396004) (xy 389.694674 -245.49608) (xy 389.694674 -245.54053)
			(xy 389.894826 -245.54053)
		)
		(stroke
			(width 0)
			(type solid)
		)
		(fill yes)
		(layer "In11.Cu")
		(net "M_L_CPU0_SA_CB<1>")
	)
	(gr_poly
		(pts
			(xy 389.894826 -245.09222) (xy 389.894826 -245.04777) (xy 389.694674 -245.04777) (xy 389.694674 -245.09222)
			(xy 389.79475 -245.192296)
		)
		(stroke
			(width 0)
			(type solid)
		)
		(fill yes)
		(layer "In11.Cu")
		(net "M_L_CPU0_SA_CB<2>")
	)
	(gr_poly
		(pts
			(xy 389.894826 -243.876068) (xy 389.79475 -243.775992) (xy 389.694674 -243.876068) (xy 389.694674 -243.920518)
			(xy 389.894826 -243.920518)
		)
		(stroke
			(width 0)
			(type solid)
		)
		(fill yes)
		(layer "In11.Cu")
		(net "M_L_CPU0_SA_DQ<29>")
	)
	(gr_poly
		(pts
			(xy 389.894826 -243.472208) (xy 389.894826 -243.427758) (xy 389.694674 -243.427758) (xy 389.694674 -243.472208)
			(xy 389.79475 -243.572284)
		)
		(stroke
			(width 0)
			(type solid)
		)
		(fill yes)
		(layer "In11.Cu")
		(net "M_L_CPU0_SA_DQ<30>")
	)
	(gr_poly
		(pts
			(xy 389.894826 -242.255802) (xy 389.79475 -242.15598) (xy 389.694674 -242.255802) (xy 389.694674 -242.303554)
			(xy 389.894826 -242.303554)
		)
		(stroke
			(width 0)
			(type solid)
		)
		(fill yes)
		(layer "In11.Cu")
		(net "M_L_CPU0_SA_DQS_DN<8>")
	)
	(gr_poly
		(pts
			(xy 389.894826 -241.85245) (xy 389.894826 -241.804698) (xy 389.694674 -241.804698) (xy 389.694674 -241.85245)
			(xy 389.79475 -241.952272)
		)
		(stroke
			(width 0)
			(type solid)
		)
		(fill yes)
		(layer "In11.Cu")
		(net "M_L_CPU0_SA_DQS_DN<3>")
	)
	(gr_poly
		(pts
			(xy 389.894826 -240.636044) (xy 389.79475 -240.535968) (xy 389.694674 -240.636044) (xy 389.694674 -240.680494)
			(xy 389.894826 -240.680494)
		)
		(stroke
			(width 0)
			(type solid)
		)
		(fill yes)
		(layer "In11.Cu")
		(net "M_L_CPU0_SA_DQ<25>")
	)
	(gr_poly
		(pts
			(xy 389.894826 -240.232184) (xy 389.894826 -240.187734) (xy 389.694674 -240.187734) (xy 389.694674 -240.232184)
			(xy 389.79475 -240.33226)
		)
		(stroke
			(width 0)
			(type solid)
		)
		(fill yes)
		(layer "In11.Cu")
		(net "M_L_CPU0_SA_DQ<26>")
	)
	(gr_poly
		(pts
			(xy 389.894826 -239.016032) (xy 389.79475 -238.915956) (xy 389.694674 -239.016032) (xy 389.694674 -239.060482)
			(xy 389.894826 -239.060482)
		)
		(stroke
			(width 0)
			(type solid)
		)
		(fill yes)
		(layer "In11.Cu")
		(net "M_L_CPU0_SA_DQ<21>")
	)
	(gr_poly
		(pts
			(xy 389.894826 -238.612172) (xy 389.894826 -238.567722) (xy 389.694674 -238.567722) (xy 389.694674 -238.612172)
			(xy 389.79475 -238.712248)
		)
		(stroke
			(width 0)
			(type solid)
		)
		(fill yes)
		(layer "In11.Cu")
		(net "M_L_CPU0_SA_DQ<22>")
	)
	(gr_poly
		(pts
			(xy 389.894826 -237.395766) (xy 389.79475 -237.295944) (xy 389.694674 -237.395766) (xy 389.694674 -237.443518)
			(xy 389.894826 -237.443518)
		)
		(stroke
			(width 0)
			(type solid)
		)
		(fill yes)
		(layer "In11.Cu")
		(net "M_L_CPU0_SA_DQS_DN<7>")
	)
	(gr_poly
		(pts
			(xy 389.894826 -236.992414) (xy 389.894826 -236.944662) (xy 389.694674 -236.944662) (xy 389.694674 -236.992414)
			(xy 389.79475 -237.092236)
		)
		(stroke
			(width 0)
			(type solid)
		)
		(fill yes)
		(layer "In11.Cu")
		(net "M_L_CPU0_SA_DQS_DN<2>")
	)
	(gr_poly
		(pts
			(xy 389.894826 -235.776008) (xy 389.79475 -235.675932) (xy 389.694674 -235.776008) (xy 389.694674 -235.820458)
			(xy 389.894826 -235.820458)
		)
		(stroke
			(width 0)
			(type solid)
		)
		(fill yes)
		(layer "In11.Cu")
		(net "M_L_CPU0_SA_DQ<17>")
	)
	(gr_poly
		(pts
			(xy 389.894826 -235.372148) (xy 389.894826 -235.327698) (xy 389.694674 -235.327698) (xy 389.694674 -235.372148)
			(xy 389.79475 -235.472224)
		)
		(stroke
			(width 0)
			(type solid)
		)
		(fill yes)
		(layer "In11.Cu")
		(net "M_L_CPU0_SA_DQ<18>")
	)
	(gr_poly
		(pts
			(xy 389.894826 -234.155996) (xy 389.79475 -234.05592) (xy 389.694674 -234.155996) (xy 389.694674 -234.200446)
			(xy 389.894826 -234.200446)
		)
		(stroke
			(width 0)
			(type solid)
		)
		(fill yes)
		(layer "In11.Cu")
		(net "M_L_CPU0_SA_DQ<13>")
	)
	(gr_poly
		(pts
			(xy 389.894826 -233.752136) (xy 389.894826 -233.707686) (xy 389.694674 -233.707686) (xy 389.694674 -233.752136)
			(xy 389.79475 -233.852212)
		)
		(stroke
			(width 0)
			(type solid)
		)
		(fill yes)
		(layer "In11.Cu")
		(net "M_L_CPU0_SA_DQ<14>")
	)
	(gr_poly
		(pts
			(xy 389.894826 -232.53573) (xy 389.79475 -232.435908) (xy 389.694674 -232.53573) (xy 389.694674 -232.583482)
			(xy 389.894826 -232.583482)
		)
		(stroke
			(width 0)
			(type solid)
		)
		(fill yes)
		(layer "In11.Cu")
		(net "M_L_CPU0_SA_DQS_DN<6>")
	)
	(gr_poly
		(pts
			(xy 389.894826 -232.132378) (xy 389.894826 -232.084626) (xy 389.694674 -232.084626) (xy 389.694674 -232.132378)
			(xy 389.79475 -232.2322)
		)
		(stroke
			(width 0)
			(type solid)
		)
		(fill yes)
		(layer "In11.Cu")
		(net "M_L_CPU0_SA_DQS_DN<1>")
	)
	(gr_poly
		(pts
			(xy 389.894826 -230.915972) (xy 389.79475 -230.815896) (xy 389.694674 -230.915972) (xy 389.694674 -230.960422)
			(xy 389.894826 -230.960422)
		)
		(stroke
			(width 0)
			(type solid)
		)
		(fill yes)
		(layer "In11.Cu")
		(net "M_L_CPU0_SA_DQ<9>")
	)
	(gr_poly
		(pts
			(xy 389.894826 -230.512366) (xy 389.894826 -230.467916) (xy 389.694674 -230.467916) (xy 389.694674 -230.512366)
			(xy 389.79475 -230.612188)
		)
		(stroke
			(width 0)
			(type solid)
		)
		(fill yes)
		(layer "In11.Cu")
		(net "M_L_CPU0_SA_DQ<10>")
	)
	(gr_poly
		(pts
			(xy 389.894826 -229.29596) (xy 389.79475 -229.195884) (xy 389.694674 -229.29596) (xy 389.694674 -229.34041)
			(xy 389.894826 -229.34041)
		)
		(stroke
			(width 0)
			(type solid)
		)
		(fill yes)
		(layer "In11.Cu")
		(net "M_L_CPU0_SA_DQ<5>")
	)
	(gr_poly
		(pts
			(xy 389.894826 -228.892354) (xy 389.894826 -228.847904) (xy 389.694674 -228.847904) (xy 389.694674 -228.892354)
			(xy 389.79475 -228.99243)
		)
		(stroke
			(width 0)
			(type solid)
		)
		(fill yes)
		(layer "In11.Cu")
		(net "M_L_CPU0_SA_DQ<6>")
	)
	(gr_poly
		(pts
			(xy 389.894826 -227.675948) (xy 389.79475 -227.576126) (xy 389.694674 -227.675948) (xy 389.694674 -227.7237)
			(xy 389.894826 -227.7237)
		)
		(stroke
			(width 0)
			(type solid)
		)
		(fill yes)
		(layer "In11.Cu")
		(net "M_L_CPU0_SA_DQS_DN<5>")
	)
	(gr_poly
		(pts
			(xy 389.894826 -227.272596) (xy 389.894826 -227.224844) (xy 389.694674 -227.224844) (xy 389.694674 -227.272596)
			(xy 389.79475 -227.372418)
		)
		(stroke
			(width 0)
			(type solid)
		)
		(fill yes)
		(layer "In11.Cu")
		(net "M_L_CPU0_SA_DQS_DN<0>")
	)
	(gr_poly
		(pts
			(xy 389.894826 -226.05619) (xy 389.79475 -225.956114) (xy 389.694674 -226.05619) (xy 389.694674 -226.10064)
			(xy 389.894826 -226.10064)
		)
		(stroke
			(width 0)
			(type solid)
		)
		(fill yes)
		(layer "In11.Cu")
		(net "M_L_CPU0_SA_DQ<1>")
	)
	(gr_poly
		(pts
			(xy 389.894826 -225.65233) (xy 389.894826 -225.60788) (xy 389.694674 -225.60788) (xy 389.694674 -225.65233)
			(xy 389.79475 -225.752406)
		)
		(stroke
			(width 0)
			(type solid)
		)
		(fill yes)
		(layer "In11.Cu")
		(net "M_L_CPU0_SA_DQ<2>")
	)
	(gr_poly
		(pts
			(xy 389.900922 -251.969778) (xy 389.8011 -251.869702) (xy 389.701024 -251.969778) (xy 389.701024 -252.014228)
			(xy 389.900922 -252.014228)
		)
		(stroke
			(width 0)
			(type solid)
		)
		(fill yes)
		(layer "In11.Cu")
		(net "M_L_CPU0_SA_CS_N<1>")
	)
	(gr_poly
		(pts
			(xy 390.1948 -293.324026) (xy 390.1948 -293.279576) (xy 389.994648 -293.279576) (xy 389.994648 -293.324026)
			(xy 390.094724 -293.424102)
		)
		(stroke
			(width 0)
			(type solid)
		)
		(fill yes)
		(layer "In11.Cu")
		(net "M_L_CPU0_SB_DQ<31>")
	)
	(gr_poly
		(pts
			(xy 390.1948 -292.107874) (xy 390.094724 -292.007798) (xy 389.994648 -292.107874) (xy 389.994648 -292.152324)
			(xy 390.1948 -292.152324)
		)
		(stroke
			(width 0)
			(type solid)
		)
		(fill yes)
		(layer "In11.Cu")
		(net "M_L_CPU0_SB_DQ<28>")
	)
	(gr_poly
		(pts
			(xy 390.1948 -291.704268) (xy 390.1948 -291.656516) (xy 389.994648 -291.656516) (xy 389.994648 -291.704268)
			(xy 390.094724 -291.80409)
		)
		(stroke
			(width 0)
			(type solid)
		)
		(fill yes)
		(layer "In11.Cu")
		(net "M_L_CPU0_SB_DQS_DP<8>")
	)
	(gr_poly
		(pts
			(xy 390.1948 -290.487608) (xy 390.094724 -290.387786) (xy 389.994648 -290.487608) (xy 389.994648 -290.53536)
			(xy 390.1948 -290.53536)
		)
		(stroke
			(width 0)
			(type solid)
		)
		(fill yes)
		(layer "In11.Cu")
		(net "M_L_CPU0_SB_DQS_DP<3>")
	)
	(gr_poly
		(pts
			(xy 390.1948 -290.084002) (xy 390.1948 -290.039552) (xy 389.994648 -290.039552) (xy 389.994648 -290.084002)
			(xy 390.094724 -290.184078)
		)
		(stroke
			(width 0)
			(type solid)
		)
		(fill yes)
		(layer "In11.Cu")
		(net "M_L_CPU0_SB_DQ<27>")
	)
	(gr_poly
		(pts
			(xy 390.1948 -288.86785) (xy 390.094724 -288.767774) (xy 389.994648 -288.86785) (xy 389.994648 -288.9123)
			(xy 390.1948 -288.9123)
		)
		(stroke
			(width 0)
			(type solid)
		)
		(fill yes)
		(layer "In11.Cu")
		(net "M_L_CPU0_SB_DQ<24>")
	)
	(gr_poly
		(pts
			(xy 390.1948 -288.464244) (xy 390.1948 -288.419794) (xy 389.994648 -288.419794) (xy 389.994648 -288.464244)
			(xy 390.094724 -288.56432)
		)
		(stroke
			(width 0)
			(type solid)
		)
		(fill yes)
		(layer "In11.Cu")
		(net "M_L_CPU0_SB_DQ<23>")
	)
	(gr_poly
		(pts
			(xy 390.1948 -287.247838) (xy 390.094724 -287.148016) (xy 389.994648 -287.247838) (xy 389.994648 -287.292288)
			(xy 390.1948 -287.292288)
		)
		(stroke
			(width 0)
			(type solid)
		)
		(fill yes)
		(layer "In11.Cu")
		(net "M_L_CPU0_SB_DQ<20>")
	)
	(gr_poly
		(pts
			(xy 390.1948 -286.844232) (xy 390.1948 -286.79648) (xy 389.994648 -286.79648) (xy 389.994648 -286.844232)
			(xy 390.094724 -286.944308)
		)
		(stroke
			(width 0)
			(type solid)
		)
		(fill yes)
		(layer "In11.Cu")
		(net "M_L_CPU0_SB_DQS_DP<7>")
	)
	(gr_poly
		(pts
			(xy 390.1948 -285.627826) (xy 390.094724 -285.528004) (xy 389.994648 -285.627826) (xy 389.994648 -285.675578)
			(xy 390.1948 -285.675578)
		)
		(stroke
			(width 0)
			(type solid)
		)
		(fill yes)
		(layer "In11.Cu")
		(net "M_L_CPU0_SB_DQS_DP<2>")
	)
	(gr_poly
		(pts
			(xy 390.1948 -285.22422) (xy 390.1948 -285.17977) (xy 389.994648 -285.17977) (xy 389.994648 -285.22422)
			(xy 390.094724 -285.324296)
		)
		(stroke
			(width 0)
			(type solid)
		)
		(fill yes)
		(layer "In11.Cu")
		(net "M_L_CPU0_SB_DQ<19>")
	)
	(gr_poly
		(pts
			(xy 390.1948 -284.008068) (xy 390.094724 -283.907992) (xy 389.994648 -284.008068) (xy 389.994648 -284.052518)
			(xy 390.1948 -284.052518)
		)
		(stroke
			(width 0)
			(type solid)
		)
		(fill yes)
		(layer "In11.Cu")
		(net "M_L_CPU0_SB_DQ<16>")
	)
	(gr_poly
		(pts
			(xy 390.1948 -283.604208) (xy 390.1948 -283.559758) (xy 389.994648 -283.559758) (xy 389.994648 -283.604208)
			(xy 390.094724 -283.704284)
		)
		(stroke
			(width 0)
			(type solid)
		)
		(fill yes)
		(layer "In11.Cu")
		(net "M_L_CPU0_SB_DQ<15>")
	)
	(gr_poly
		(pts
			(xy 390.1948 -282.388056) (xy 390.094724 -282.28798) (xy 389.994648 -282.388056) (xy 389.994648 -282.432506)
			(xy 390.1948 -282.432506)
		)
		(stroke
			(width 0)
			(type solid)
		)
		(fill yes)
		(layer "In11.Cu")
		(net "M_L_CPU0_SB_DQ<12>")
	)
	(gr_poly
		(pts
			(xy 390.1948 -281.98445) (xy 390.1948 -281.936698) (xy 389.994648 -281.936698) (xy 389.994648 -281.98445)
			(xy 390.094724 -282.084272)
		)
		(stroke
			(width 0)
			(type solid)
		)
		(fill yes)
		(layer "In11.Cu")
		(net "M_L_CPU0_SB_DQS_DP<6>")
	)
	(gr_poly
		(pts
			(xy 390.1948 -280.76779) (xy 390.094724 -280.667968) (xy 389.994648 -280.76779) (xy 389.994648 -280.815542)
			(xy 390.1948 -280.815542)
		)
		(stroke
			(width 0)
			(type solid)
		)
		(fill yes)
		(layer "In11.Cu")
		(net "M_L_CPU0_SB_DQS_DP<1>")
	)
	(gr_poly
		(pts
			(xy 390.1948 -280.364184) (xy 390.1948 -280.319734) (xy 389.994648 -280.319734) (xy 389.994648 -280.364184)
			(xy 390.094724 -280.46426)
		)
		(stroke
			(width 0)
			(type solid)
		)
		(fill yes)
		(layer "In11.Cu")
		(net "M_L_CPU0_SB_DQ<11>")
	)
	(gr_poly
		(pts
			(xy 390.1948 -279.148032) (xy 390.094724 -279.047956) (xy 389.994648 -279.148032) (xy 389.994648 -279.192482)
			(xy 390.1948 -279.192482)
		)
		(stroke
			(width 0)
			(type solid)
		)
		(fill yes)
		(layer "In11.Cu")
		(net "M_L_CPU0_SB_DQ<8>")
	)
	(gr_poly
		(pts
			(xy 390.1948 -278.744172) (xy 390.1948 -278.699722) (xy 389.994648 -278.699722) (xy 389.994648 -278.744172)
			(xy 390.094724 -278.844248)
		)
		(stroke
			(width 0)
			(type solid)
		)
		(fill yes)
		(layer "In11.Cu")
		(net "M_L_CPU0_SB_DQ<7>")
	)
	(gr_poly
		(pts
			(xy 390.1948 -277.52802) (xy 390.094724 -277.427944) (xy 389.994648 -277.52802) (xy 389.994648 -277.57247)
			(xy 390.1948 -277.57247)
		)
		(stroke
			(width 0)
			(type solid)
		)
		(fill yes)
		(layer "In11.Cu")
		(net "M_L_CPU0_SB_DQ<4>")
	)
	(gr_poly
		(pts
			(xy 390.1948 -277.124414) (xy 390.1948 -277.076662) (xy 389.994648 -277.076662) (xy 389.994648 -277.124414)
			(xy 390.094724 -277.224236)
		)
		(stroke
			(width 0)
			(type solid)
		)
		(fill yes)
		(layer "In11.Cu")
		(net "M_L_CPU0_SB_DQS_DP<5>")
	)
	(gr_poly
		(pts
			(xy 390.1948 -275.907754) (xy 390.094724 -275.807932) (xy 389.994648 -275.907754) (xy 389.994648 -275.955506)
			(xy 390.1948 -275.955506)
		)
		(stroke
			(width 0)
			(type solid)
		)
		(fill yes)
		(layer "In11.Cu")
		(net "M_L_CPU0_SB_DQS_DP<0>")
	)
	(gr_poly
		(pts
			(xy 390.1948 -275.504148) (xy 390.1948 -275.459698) (xy 389.994648 -275.459698) (xy 389.994648 -275.504148)
			(xy 390.094724 -275.604224)
		)
		(stroke
			(width 0)
			(type solid)
		)
		(fill yes)
		(layer "In11.Cu")
		(net "M_L_CPU0_SB_DQ<3>")
	)
	(gr_poly
		(pts
			(xy 390.1948 -274.287996) (xy 390.094724 -274.18792) (xy 389.994648 -274.287996) (xy 389.994648 -274.332446)
			(xy 390.1948 -274.332446)
		)
		(stroke
			(width 0)
			(type solid)
		)
		(fill yes)
		(layer "In11.Cu")
		(net "M_L_CPU0_SB_DQ<0>")
	)
	(gr_poly
		(pts
			(xy 390.1948 -273.884136) (xy 390.1948 -273.839686) (xy 389.994648 -273.839686) (xy 389.994648 -273.884136)
			(xy 390.094724 -273.984212)
		)
		(stroke
			(width 0)
			(type solid)
		)
		(fill yes)
		(layer "In11.Cu")
		(net "M_L_CPU0_SB_CB<3>")
	)
	(gr_poly
		(pts
			(xy 390.1948 -272.667984) (xy 390.094724 -272.567908) (xy 389.994648 -272.667984) (xy 389.994648 -272.712434)
			(xy 390.1948 -272.712434)
		)
		(stroke
			(width 0)
			(type solid)
		)
		(fill yes)
		(layer "In11.Cu")
		(net "M_L_CPU0_SB_CB<0>")
	)
	(gr_poly
		(pts
			(xy 390.1948 -272.264378) (xy 390.1948 -272.216626) (xy 389.994648 -272.216626) (xy 389.994648 -272.264378)
			(xy 390.094724 -272.3642)
		)
		(stroke
			(width 0)
			(type solid)
		)
		(fill yes)
		(layer "In11.Cu")
		(net "M_L_CPU0_SB_DQS_DP<4>")
	)
	(gr_poly
		(pts
			(xy 390.1948 -271.047718) (xy 390.094724 -270.947896) (xy 389.994648 -271.047718) (xy 389.994648 -271.09547)
			(xy 390.1948 -271.09547)
		)
		(stroke
			(width 0)
			(type solid)
		)
		(fill yes)
		(layer "In11.Cu")
		(net "M_L_CPU0_SB_DQS_DP<9>")
	)
	(gr_poly
		(pts
			(xy 390.1948 -270.644112) (xy 390.1948 -270.599662) (xy 389.994648 -270.599662) (xy 389.994648 -270.644112)
			(xy 390.094724 -270.744188)
		)
		(stroke
			(width 0)
			(type solid)
		)
		(fill yes)
		(layer "In11.Cu")
		(net "M_L_CPU0_SB_CB<7>")
	)
	(gr_poly
		(pts
			(xy 390.1948 -269.42796) (xy 390.094724 -269.327884) (xy 389.994648 -269.42796) (xy 389.994648 -269.47241)
			(xy 390.1948 -269.47241)
		)
		(stroke
			(width 0)
			(type solid)
		)
		(fill yes)
		(layer "In11.Cu")
		(net "M_L_CPU0_SB_CB<4>")
	)
	(gr_poly
		(pts
			(xy 390.1948 -267.807948) (xy 390.094724 -267.707872) (xy 389.994648 -267.807948) (xy 389.994648 -267.852398)
			(xy 390.1948 -267.852398)
		)
		(stroke
			(width 0)
			(type solid)
		)
		(fill yes)
		(layer "In11.Cu")
		(net "M_L_CPU0_SB_RSP<0>")
	)
	(gr_poly
		(pts
			(xy 390.1948 -265.784076) (xy 390.1948 -265.739626) (xy 389.994648 -265.739626) (xy 389.994648 -265.784076)
			(xy 390.094724 -265.884152)
		)
		(stroke
			(width 0)
			(type solid)
		)
		(fill yes)
		(layer "In11.Cu")
		(net "M_L_CPU0_SB_CS_N<0>")
	)
	(gr_poly
		(pts
			(xy 390.1948 -264.164064) (xy 390.1948 -264.119614) (xy 389.994648 -264.119614) (xy 389.994648 -264.164064)
			(xy 390.094724 -264.26414)
		)
		(stroke
			(width 0)
			(type solid)
		)
		(fill yes)
		(layer "In11.Cu")
		(net "M_L_CPU0_SB_CA<5>")
	)
	(gr_poly
		(pts
			(xy 390.1948 -262.947912) (xy 390.094724 -262.847836) (xy 389.994648 -262.947912) (xy 389.994648 -262.992362)
			(xy 390.1948 -262.992362)
		)
		(stroke
			(width 0)
			(type solid)
		)
		(fill yes)
		(layer "In11.Cu")
		(net "M_L_CPU0_SB_CA<2>")
	)
	(gr_poly
		(pts
			(xy 390.1948 -262.544052) (xy 390.1948 -262.499602) (xy 389.994648 -262.499602) (xy 389.994648 -262.544052)
			(xy 390.094724 -262.644128)
		)
		(stroke
			(width 0)
			(type solid)
		)
		(fill yes)
		(layer "In11.Cu")
		(net "M_L_CPU0_SB_CA<1>")
	)
	(gr_poly
		(pts
			(xy 390.200896 -264.561574) (xy 390.101074 -264.461498) (xy 390.000998 -264.561574) (xy 390.000998 -264.606024)
			(xy 390.200896 -264.606024)
		)
		(stroke
			(width 0)
			(type solid)
		)
		(fill yes)
		(layer "In11.Cu")
		(net "M_L_CPU0_SB_CA<6>")
	)
	(gr_poly
		(pts
			(xy 390.283954 -224.695512) (xy 390.245346 -224.67316) (xy 390.108694 -224.709736) (xy 390.145524 -224.846388)
			(xy 390.183878 -224.86874)
		)
		(stroke
			(width 0)
			(type solid)
		)
		(fill yes)
		(layer "In11.Cu")
		(net "M_L_CPU0_SA_DQ<0>")
	)
	(gr_poly
		(pts
			(xy 390.35863 -251.159772) (xy 390.258554 -251.059696) (xy 390.158732 -251.159772) (xy 390.158732 -251.204222)
			(xy 390.35863 -251.204222)
		)
		(stroke
			(width 0)
			(type solid)
		)
		(fill yes)
		(layer "In11.Cu")
		(net "M_L_CPU0_SA_CS_N<0>")
	)
	(gr_poly
		(pts
			(xy 390.36498 -256.025904) (xy 390.264904 -255.926082) (xy 390.164828 -256.025904) (xy 390.164828 -256.073656)
			(xy 390.36498 -256.073656)
		)
		(stroke
			(width 0)
			(type solid)
		)
		(fill yes)
		(layer "In11.Cu")
		(net "M_L_CPU0_CLK_DP<0>")
	)
	(gr_poly
		(pts
			(xy 390.36498 -255.622298) (xy 390.36498 -255.577848) (xy 390.164828 -255.577848) (xy 390.164828 -255.622298)
			(xy 390.264904 -255.722374)
		)
		(stroke
			(width 0)
			(type solid)
		)
		(fill yes)
		(layer "In11.Cu")
		(net "M_L_CPU0_SA_PAR")
	)
	(gr_poly
		(pts
			(xy 390.36498 -254.406146) (xy 390.264904 -254.30607) (xy 390.164828 -254.406146) (xy 390.164828 -254.450596)
			(xy 390.36498 -254.450596)
		)
		(stroke
			(width 0)
			(type solid)
		)
		(fill yes)
		(layer "In11.Cu")
		(net "M_L_CPU0_SA_CA<4>")
	)
	(gr_poly
		(pts
			(xy 390.36498 -254.002286) (xy 390.36498 -253.957836) (xy 390.164828 -253.957836) (xy 390.164828 -254.002286)
			(xy 390.264904 -254.102362)
		)
		(stroke
			(width 0)
			(type solid)
		)
		(fill yes)
		(layer "In11.Cu")
		(net "M_L_CPU0_SA_CA<3>")
	)
	(gr_poly
		(pts
			(xy 390.36498 -252.786134) (xy 390.264904 -252.686058) (xy 390.164828 -252.786134) (xy 390.164828 -252.830584)
			(xy 390.36498 -252.830584)
		)
		(stroke
			(width 0)
			(type solid)
		)
		(fill yes)
		(layer "In11.Cu")
		(net "M_L_CPU0_SA_CA<0>")
	)
	(gr_poly
		(pts
			(xy 390.36498 -250.762262) (xy 390.36498 -250.717812) (xy 390.164828 -250.717812) (xy 390.164828 -250.762262)
			(xy 390.264904 -250.862338)
		)
		(stroke
			(width 0)
			(type solid)
		)
		(fill yes)
		(layer "In11.Cu")
		(net "M_L_CPU0_RESET_N")
	)
	(gr_poly
		(pts
			(xy 390.36498 -249.14225) (xy 390.36498 -249.0978) (xy 390.164828 -249.0978) (xy 390.164828 -249.14225)
			(xy 390.264904 -249.242326)
		)
		(stroke
			(width 0)
			(type solid)
		)
		(fill yes)
		(layer "In11.Cu")
		(net "M_L_CPU0_SA_CB<7>")
	)
	(gr_poly
		(pts
			(xy 390.36498 -247.926098) (xy 390.264904 -247.826022) (xy 390.164828 -247.926098) (xy 390.164828 -247.970548)
			(xy 390.36498 -247.970548)
		)
		(stroke
			(width 0)
			(type solid)
		)
		(fill yes)
		(layer "In11.Cu")
		(net "M_L_CPU0_SA_CB<4>")
	)
	(gr_poly
		(pts
			(xy 390.36498 -247.522492) (xy 390.36498 -247.47474) (xy 390.164828 -247.47474) (xy 390.164828 -247.522492)
			(xy 390.264904 -247.622314)
		)
		(stroke
			(width 0)
			(type solid)
		)
		(fill yes)
		(layer "In11.Cu")
		(net "M_L_CPU0_SA_DQS_DP<9>")
	)
	(gr_poly
		(pts
			(xy 390.36498 -246.305832) (xy 390.264904 -246.20601) (xy 390.164828 -246.305832) (xy 390.164828 -246.353584)
			(xy 390.36498 -246.353584)
		)
		(stroke
			(width 0)
			(type solid)
		)
		(fill yes)
		(layer "In11.Cu")
		(net "M_L_CPU0_SA_DQS_DP<4>")
	)
	(gr_poly
		(pts
			(xy 390.36498 -245.902226) (xy 390.36498 -245.857776) (xy 390.164828 -245.857776) (xy 390.164828 -245.902226)
			(xy 390.264904 -246.002302)
		)
		(stroke
			(width 0)
			(type solid)
		)
		(fill yes)
		(layer "In11.Cu")
		(net "M_L_CPU0_SA_CB<3>")
	)
	(gr_poly
		(pts
			(xy 390.36498 -244.686074) (xy 390.264904 -244.585998) (xy 390.164828 -244.686074) (xy 390.164828 -244.730524)
			(xy 390.36498 -244.730524)
		)
		(stroke
			(width 0)
			(type solid)
		)
		(fill yes)
		(layer "In11.Cu")
		(net "M_L_CPU0_SA_CB<0>")
	)
	(gr_poly
		(pts
			(xy 390.36498 -244.282214) (xy 390.36498 -244.237764) (xy 390.164828 -244.237764) (xy 390.164828 -244.282214)
			(xy 390.264904 -244.38229)
		)
		(stroke
			(width 0)
			(type solid)
		)
		(fill yes)
		(layer "In11.Cu")
		(net "M_L_CPU0_SA_DQ<31>")
	)
	(gr_poly
		(pts
			(xy 390.36498 -243.066062) (xy 390.264904 -242.965986) (xy 390.164828 -243.066062) (xy 390.164828 -243.110512)
			(xy 390.36498 -243.110512)
		)
		(stroke
			(width 0)
			(type solid)
		)
		(fill yes)
		(layer "In11.Cu")
		(net "M_L_CPU0_SA_DQ<28>")
	)
	(gr_poly
		(pts
			(xy 390.36498 -242.662456) (xy 390.36498 -242.614704) (xy 390.164828 -242.614704) (xy 390.164828 -242.662456)
			(xy 390.264904 -242.762278)
		)
		(stroke
			(width 0)
			(type solid)
		)
		(fill yes)
		(layer "In11.Cu")
		(net "M_L_CPU0_SA_DQS_DP<8>")
	)
	(gr_poly
		(pts
			(xy 390.36498 -241.445796) (xy 390.264904 -241.345974) (xy 390.164828 -241.445796) (xy 390.164828 -241.493548)
			(xy 390.36498 -241.493548)
		)
		(stroke
			(width 0)
			(type solid)
		)
		(fill yes)
		(layer "In11.Cu")
		(net "M_L_CPU0_SA_DQS_DP<3>")
	)
	(gr_poly
		(pts
			(xy 390.36498 -241.04219) (xy 390.36498 -240.99774) (xy 390.164828 -240.99774) (xy 390.164828 -241.04219)
			(xy 390.264904 -241.142266)
		)
		(stroke
			(width 0)
			(type solid)
		)
		(fill yes)
		(layer "In11.Cu")
		(net "M_L_CPU0_SA_DQ<27>")
	)
	(gr_poly
		(pts
			(xy 390.36498 -239.826038) (xy 390.264904 -239.725962) (xy 390.164828 -239.826038) (xy 390.164828 -239.870488)
			(xy 390.36498 -239.870488)
		)
		(stroke
			(width 0)
			(type solid)
		)
		(fill yes)
		(layer "In11.Cu")
		(net "M_L_CPU0_SA_DQ<24>")
	)
	(gr_poly
		(pts
			(xy 390.36498 -239.422178) (xy 390.36498 -239.377728) (xy 390.164828 -239.377728) (xy 390.164828 -239.422178)
			(xy 390.264904 -239.522254)
		)
		(stroke
			(width 0)
			(type solid)
		)
		(fill yes)
		(layer "In11.Cu")
		(net "M_L_CPU0_SA_DQ<23>")
	)
	(gr_poly
		(pts
			(xy 390.36498 -238.206026) (xy 390.264904 -238.10595) (xy 390.164828 -238.206026) (xy 390.164828 -238.250476)
			(xy 390.36498 -238.250476)
		)
		(stroke
			(width 0)
			(type solid)
		)
		(fill yes)
		(layer "In11.Cu")
		(net "M_L_CPU0_SA_DQ<20>")
	)
	(gr_poly
		(pts
			(xy 390.36498 -237.80242) (xy 390.36498 -237.754668) (xy 390.164828 -237.754668) (xy 390.164828 -237.80242)
			(xy 390.264904 -237.902242)
		)
		(stroke
			(width 0)
			(type solid)
		)
		(fill yes)
		(layer "In11.Cu")
		(net "M_L_CPU0_SA_DQS_DP<7>")
	)
	(gr_poly
		(pts
			(xy 390.36498 -236.58576) (xy 390.264904 -236.485938) (xy 390.164828 -236.58576) (xy 390.164828 -236.633512)
			(xy 390.36498 -236.633512)
		)
		(stroke
			(width 0)
			(type solid)
		)
		(fill yes)
		(layer "In11.Cu")
		(net "M_L_CPU0_SA_DQS_DP<2>")
	)
	(gr_poly
		(pts
			(xy 390.36498 -236.182154) (xy 390.36498 -236.137704) (xy 390.164828 -236.137704) (xy 390.164828 -236.182154)
			(xy 390.264904 -236.28223)
		)
		(stroke
			(width 0)
			(type solid)
		)
		(fill yes)
		(layer "In11.Cu")
		(net "M_L_CPU0_SA_DQ<19>")
	)
	(gr_poly
		(pts
			(xy 390.36498 -234.966002) (xy 390.264904 -234.865926) (xy 390.164828 -234.966002) (xy 390.164828 -235.010452)
			(xy 390.36498 -235.010452)
		)
		(stroke
			(width 0)
			(type solid)
		)
		(fill yes)
		(layer "In11.Cu")
		(net "M_L_CPU0_SA_DQ<16>")
	)
	(gr_poly
		(pts
			(xy 390.36498 -234.562142) (xy 390.36498 -234.517692) (xy 390.164828 -234.517692) (xy 390.164828 -234.562142)
			(xy 390.264904 -234.662218)
		)
		(stroke
			(width 0)
			(type solid)
		)
		(fill yes)
		(layer "In11.Cu")
		(net "M_L_CPU0_SA_DQ<15>")
	)
	(gr_poly
		(pts
			(xy 390.36498 -233.34599) (xy 390.264904 -233.245914) (xy 390.164828 -233.34599) (xy 390.164828 -233.39044)
			(xy 390.36498 -233.39044)
		)
		(stroke
			(width 0)
			(type solid)
		)
		(fill yes)
		(layer "In11.Cu")
		(net "M_L_CPU0_SA_DQ<12>")
	)
	(gr_poly
		(pts
			(xy 390.36498 -232.942384) (xy 390.36498 -232.894632) (xy 390.164828 -232.894632) (xy 390.164828 -232.942384)
			(xy 390.264904 -233.042206)
		)
		(stroke
			(width 0)
			(type solid)
		)
		(fill yes)
		(layer "In11.Cu")
		(net "M_L_CPU0_SA_DQS_DP<6>")
	)
	(gr_poly
		(pts
			(xy 390.36498 -231.725724) (xy 390.264904 -231.625902) (xy 390.164828 -231.725724) (xy 390.164828 -231.773476)
			(xy 390.36498 -231.773476)
		)
		(stroke
			(width 0)
			(type solid)
		)
		(fill yes)
		(layer "In11.Cu")
		(net "M_L_CPU0_SA_DQS_DP<1>")
	)
	(gr_poly
		(pts
			(xy 390.36498 -231.322372) (xy 390.36498 -231.277922) (xy 390.164828 -231.277922) (xy 390.164828 -231.322372)
			(xy 390.264904 -231.422448)
		)
		(stroke
			(width 0)
			(type solid)
		)
		(fill yes)
		(layer "In11.Cu")
		(net "M_L_CPU0_SA_DQ<11>")
	)
	(gr_poly
		(pts
			(xy 390.36498 -230.105966) (xy 390.264904 -230.006144) (xy 390.164828 -230.105966) (xy 390.164828 -230.150416)
			(xy 390.36498 -230.150416)
		)
		(stroke
			(width 0)
			(type solid)
		)
		(fill yes)
		(layer "In11.Cu")
		(net "M_L_CPU0_SA_DQ<8>")
	)
	(gr_poly
		(pts
			(xy 390.36498 -229.70236) (xy 390.36498 -229.65791) (xy 390.164828 -229.65791) (xy 390.164828 -229.70236)
			(xy 390.264904 -229.802436)
		)
		(stroke
			(width 0)
			(type solid)
		)
		(fill yes)
		(layer "In11.Cu")
		(net "M_L_CPU0_SA_DQ<7>")
	)
	(gr_poly
		(pts
			(xy 390.36498 -228.486208) (xy 390.264904 -228.386132) (xy 390.164828 -228.486208) (xy 390.164828 -228.530658)
			(xy 390.36498 -228.530658)
		)
		(stroke
			(width 0)
			(type solid)
		)
		(fill yes)
		(layer "In11.Cu")
		(net "M_L_CPU0_SA_DQ<4>")
	)
	(gr_poly
		(pts
			(xy 390.36498 -228.082602) (xy 390.36498 -228.03485) (xy 390.164828 -228.03485) (xy 390.164828 -228.082602)
			(xy 390.264904 -228.182424)
		)
		(stroke
			(width 0)
			(type solid)
		)
		(fill yes)
		(layer "In11.Cu")
		(net "M_L_CPU0_SA_DQS_DP<5>")
	)
	(gr_poly
		(pts
			(xy 390.36498 -226.865942) (xy 390.264904 -226.76612) (xy 390.164828 -226.865942) (xy 390.164828 -226.913694)
			(xy 390.36498 -226.913694)
		)
		(stroke
			(width 0)
			(type solid)
		)
		(fill yes)
		(layer "In11.Cu")
		(net "M_L_CPU0_SA_DQS_DP<0>")
	)
	(gr_poly
		(pts
			(xy 390.36498 -226.462336) (xy 390.36498 -226.417886) (xy 390.164828 -226.417886) (xy 390.164828 -226.462336)
			(xy 390.264904 -226.562412)
		)
		(stroke
			(width 0)
			(type solid)
		)
		(fill yes)
		(layer "In11.Cu")
		(net "M_L_CPU0_SA_DQ<3>")
	)
	(gr_poly
		(pts
			(xy 390.420606 -225.378772) (xy 390.38403 -225.24212) (xy 390.345676 -225.219768) (xy 390.2456 -225.392996)
			(xy 390.284208 -225.415348)
		)
		(stroke
			(width 0)
			(type solid)
		)
		(fill yes)
		(layer "In11.Cu")
		(net "M_L_CPU0_SA_DQ<2>")
	)
	(gr_poly
		(pts
			(xy 390.664954 -292.91788) (xy 390.564878 -292.817804) (xy 390.464802 -292.91788) (xy 390.464802 -292.96233)
			(xy 390.664954 -292.96233)
		)
		(stroke
			(width 0)
			(type solid)
		)
		(fill yes)
		(layer "In11.Cu")
		(net "M_L_CPU0_SB_DQ<29>")
	)
	(gr_poly
		(pts
			(xy 390.664954 -292.51402) (xy 390.664954 -292.46957) (xy 390.464802 -292.46957) (xy 390.464802 -292.51402)
			(xy 390.564878 -292.614096)
		)
		(stroke
			(width 0)
			(type solid)
		)
		(fill yes)
		(layer "In11.Cu")
		(net "M_L_CPU0_SB_DQ<30>")
	)
	(gr_poly
		(pts
			(xy 390.664954 -291.297614) (xy 390.564878 -291.197792) (xy 390.464802 -291.297614) (xy 390.464802 -291.345366)
			(xy 390.664954 -291.345366)
		)
		(stroke
			(width 0)
			(type solid)
		)
		(fill yes)
		(layer "In11.Cu")
		(net "M_L_CPU0_SB_DQS_DN<8>")
	)
	(gr_poly
		(pts
			(xy 390.664954 -290.894262) (xy 390.664954 -290.84651) (xy 390.464802 -290.84651) (xy 390.464802 -290.894262)
			(xy 390.564878 -290.994084)
		)
		(stroke
			(width 0)
			(type solid)
		)
		(fill yes)
		(layer "In11.Cu")
		(net "M_L_CPU0_SB_DQS_DN<3>")
	)
	(gr_poly
		(pts
			(xy 390.664954 -289.677856) (xy 390.564878 -289.57778) (xy 390.464802 -289.677856) (xy 390.464802 -289.722306)
			(xy 390.664954 -289.722306)
		)
		(stroke
			(width 0)
			(type solid)
		)
		(fill yes)
		(layer "In11.Cu")
		(net "M_L_CPU0_SB_DQ<25>")
	)
	(gr_poly
		(pts
			(xy 390.664954 -289.273996) (xy 390.664954 -289.229546) (xy 390.464802 -289.229546) (xy 390.464802 -289.273996)
			(xy 390.564878 -289.374072)
		)
		(stroke
			(width 0)
			(type solid)
		)
		(fill yes)
		(layer "In11.Cu")
		(net "M_L_CPU0_SB_DQ<26>")
	)
	(gr_poly
		(pts
			(xy 390.664954 -288.057844) (xy 390.564878 -287.957768) (xy 390.464802 -288.057844) (xy 390.464802 -288.102294)
			(xy 390.664954 -288.102294)
		)
		(stroke
			(width 0)
			(type solid)
		)
		(fill yes)
		(layer "In11.Cu")
		(net "M_L_CPU0_SB_DQ<21>")
	)
	(gr_poly
		(pts
			(xy 390.664954 -287.654238) (xy 390.664954 -287.609788) (xy 390.464802 -287.609788) (xy 390.464802 -287.654238)
			(xy 390.564878 -287.75406)
		)
		(stroke
			(width 0)
			(type solid)
		)
		(fill yes)
		(layer "In11.Cu")
		(net "M_L_CPU0_SB_DQ<22>")
	)
	(gr_poly
		(pts
			(xy 390.664954 -286.437832) (xy 390.564878 -286.337756) (xy 390.464802 -286.437832) (xy 390.464802 -286.485584)
			(xy 390.664954 -286.485584)
		)
		(stroke
			(width 0)
			(type solid)
		)
		(fill yes)
		(layer "In11.Cu")
		(net "M_L_CPU0_SB_DQS_DN<7>")
	)
	(gr_poly
		(pts
			(xy 390.664954 -286.03448) (xy 390.664954 -285.986728) (xy 390.464802 -285.986728) (xy 390.464802 -286.03448)
			(xy 390.564878 -286.134302)
		)
		(stroke
			(width 0)
			(type solid)
		)
		(fill yes)
		(layer "In11.Cu")
		(net "M_L_CPU0_SB_DQS_DN<2>")
	)
	(gr_poly
		(pts
			(xy 390.664954 -284.818074) (xy 390.564878 -284.717998) (xy 390.464802 -284.818074) (xy 390.464802 -284.862524)
			(xy 390.664954 -284.862524)
		)
		(stroke
			(width 0)
			(type solid)
		)
		(fill yes)
		(layer "In11.Cu")
		(net "M_L_CPU0_SB_DQ<17>")
	)
	(gr_poly
		(pts
			(xy 390.664954 -284.414214) (xy 390.664954 -284.369764) (xy 390.464802 -284.369764) (xy 390.464802 -284.414214)
			(xy 390.564878 -284.51429)
		)
		(stroke
			(width 0)
			(type solid)
		)
		(fill yes)
		(layer "In11.Cu")
		(net "M_L_CPU0_SB_DQ<18>")
	)
	(gr_poly
		(pts
			(xy 390.664954 -283.198062) (xy 390.564878 -283.097986) (xy 390.464802 -283.198062) (xy 390.464802 -283.242512)
			(xy 390.664954 -283.242512)
		)
		(stroke
			(width 0)
			(type solid)
		)
		(fill yes)
		(layer "In11.Cu")
		(net "M_L_CPU0_SB_DQ<13>")
	)
	(gr_poly
		(pts
			(xy 390.664954 -282.794202) (xy 390.664954 -282.749752) (xy 390.464802 -282.749752) (xy 390.464802 -282.794202)
			(xy 390.564878 -282.894278)
		)
		(stroke
			(width 0)
			(type solid)
		)
		(fill yes)
		(layer "In11.Cu")
		(net "M_L_CPU0_SB_DQ<14>")
	)
	(gr_poly
		(pts
			(xy 390.664954 -281.577796) (xy 390.564878 -281.477974) (xy 390.464802 -281.577796) (xy 390.464802 -281.625548)
			(xy 390.664954 -281.625548)
		)
		(stroke
			(width 0)
			(type solid)
		)
		(fill yes)
		(layer "In11.Cu")
		(net "M_L_CPU0_SB_DQS_DN<6>")
	)
	(gr_poly
		(pts
			(xy 390.664954 -281.174444) (xy 390.664954 -281.126692) (xy 390.464802 -281.126692) (xy 390.464802 -281.174444)
			(xy 390.564878 -281.274266)
		)
		(stroke
			(width 0)
			(type solid)
		)
		(fill yes)
		(layer "In11.Cu")
		(net "M_L_CPU0_SB_DQS_DN<1>")
	)
	(gr_poly
		(pts
			(xy 390.664954 -279.958038) (xy 390.564878 -279.857962) (xy 390.464802 -279.958038) (xy 390.464802 -280.002488)
			(xy 390.664954 -280.002488)
		)
		(stroke
			(width 0)
			(type solid)
		)
		(fill yes)
		(layer "In11.Cu")
		(net "M_L_CPU0_SB_DQ<9>")
	)
	(gr_poly
		(pts
			(xy 390.664954 -279.554178) (xy 390.664954 -279.509728) (xy 390.464802 -279.509728) (xy 390.464802 -279.554178)
			(xy 390.564878 -279.654254)
		)
		(stroke
			(width 0)
			(type solid)
		)
		(fill yes)
		(layer "In11.Cu")
		(net "M_L_CPU0_SB_DQ<10>")
	)
	(gr_poly
		(pts
			(xy 390.664954 -278.338026) (xy 390.564878 -278.23795) (xy 390.464802 -278.338026) (xy 390.464802 -278.382476)
			(xy 390.664954 -278.382476)
		)
		(stroke
			(width 0)
			(type solid)
		)
		(fill yes)
		(layer "In11.Cu")
		(net "M_L_CPU0_SB_DQ<5>")
	)
	(gr_poly
		(pts
			(xy 390.664954 -277.934166) (xy 390.664954 -277.889716) (xy 390.464802 -277.889716) (xy 390.464802 -277.934166)
			(xy 390.564878 -278.034242)
		)
		(stroke
			(width 0)
			(type solid)
		)
		(fill yes)
		(layer "In11.Cu")
		(net "M_L_CPU0_SB_DQ<6>")
	)
	(gr_poly
		(pts
			(xy 390.664954 -276.71776) (xy 390.564878 -276.617938) (xy 390.464802 -276.71776) (xy 390.464802 -276.765512)
			(xy 390.664954 -276.765512)
		)
		(stroke
			(width 0)
			(type solid)
		)
		(fill yes)
		(layer "In11.Cu")
		(net "M_L_CPU0_SB_DQS_DN<5>")
	)
	(gr_poly
		(pts
			(xy 390.664954 -276.314408) (xy 390.664954 -276.266656) (xy 390.464802 -276.266656) (xy 390.464802 -276.314408)
			(xy 390.564878 -276.41423)
		)
		(stroke
			(width 0)
			(type solid)
		)
		(fill yes)
		(layer "In11.Cu")
		(net "M_L_CPU0_SB_DQS_DN<0>")
	)
	(gr_poly
		(pts
			(xy 390.664954 -275.098002) (xy 390.564878 -274.997926) (xy 390.464802 -275.098002) (xy 390.464802 -275.142452)
			(xy 390.664954 -275.142452)
		)
		(stroke
			(width 0)
			(type solid)
		)
		(fill yes)
		(layer "In11.Cu")
		(net "M_L_CPU0_SB_DQ<1>")
	)
	(gr_poly
		(pts
			(xy 390.664954 -274.694142) (xy 390.664954 -274.649692) (xy 390.464802 -274.649692) (xy 390.464802 -274.694142)
			(xy 390.564878 -274.794218)
		)
		(stroke
			(width 0)
			(type solid)
		)
		(fill yes)
		(layer "In11.Cu")
		(net "M_L_CPU0_SB_DQ<2>")
	)
	(gr_poly
		(pts
			(xy 390.664954 -273.47799) (xy 390.564878 -273.377914) (xy 390.464802 -273.47799) (xy 390.464802 -273.52244)
			(xy 390.664954 -273.52244)
		)
		(stroke
			(width 0)
			(type solid)
		)
		(fill yes)
		(layer "In11.Cu")
		(net "M_L_CPU0_SB_CB<1>")
	)
	(gr_poly
		(pts
			(xy 390.664954 -273.07413) (xy 390.664954 -273.02968) (xy 390.464802 -273.02968) (xy 390.464802 -273.07413)
			(xy 390.564878 -273.174206)
		)
		(stroke
			(width 0)
			(type solid)
		)
		(fill yes)
		(layer "In11.Cu")
		(net "M_L_CPU0_SB_CB<2>")
	)
	(gr_poly
		(pts
			(xy 390.664954 -271.857724) (xy 390.564878 -271.757902) (xy 390.464802 -271.857724) (xy 390.464802 -271.905476)
			(xy 390.664954 -271.905476)
		)
		(stroke
			(width 0)
			(type solid)
		)
		(fill yes)
		(layer "In11.Cu")
		(net "M_L_CPU0_SB_DQS_DN<4>")
	)
	(gr_poly
		(pts
			(xy 390.664954 -271.454372) (xy 390.664954 -271.40662) (xy 390.464802 -271.40662) (xy 390.464802 -271.454372)
			(xy 390.564878 -271.554194)
		)
		(stroke
			(width 0)
			(type solid)
		)
		(fill yes)
		(layer "In11.Cu")
		(net "M_L_CPU0_SB_DQS_DN<9>")
	)
	(gr_poly
		(pts
			(xy 390.664954 -270.237966) (xy 390.564878 -270.13789) (xy 390.464802 -270.237966) (xy 390.464802 -270.282416)
			(xy 390.664954 -270.282416)
		)
		(stroke
			(width 0)
			(type solid)
		)
		(fill yes)
		(layer "In11.Cu")
		(net "M_L_CPU0_SB_CB<5>")
	)
	(gr_poly
		(pts
			(xy 390.664954 -269.834106) (xy 390.664954 -269.789656) (xy 390.464802 -269.789656) (xy 390.464802 -269.834106)
			(xy 390.564878 -269.934182)
		)
		(stroke
			(width 0)
			(type solid)
		)
		(fill yes)
		(layer "In11.Cu")
		(net "M_L_CPU0_SB_CB<6>")
	)
	(gr_poly
		(pts
			(xy 390.664954 -266.997942) (xy 390.564878 -266.897866) (xy 390.464802 -266.997942) (xy 390.464802 -267.042392)
			(xy 390.664954 -267.042392)
		)
		(stroke
			(width 0)
			(type solid)
		)
		(fill yes)
		(layer "In11.Cu")
		(net "M_L_CPU0_SA_RSP<0>")
	)
	(gr_poly
		(pts
			(xy 390.664954 -266.594082) (xy 390.664954 -266.549632) (xy 390.464802 -266.549632) (xy 390.464802 -266.594082)
			(xy 390.564878 -266.694158)
		)
		(stroke
			(width 0)
			(type solid)
		)
		(fill yes)
		(layer "In11.Cu")
		(net "M_L_CPU0_SB_CS_N<1>")
	)
	(gr_poly
		(pts
			(xy 390.664954 -265.37793) (xy 390.564878 -265.277854) (xy 390.464802 -265.37793) (xy 390.464802 -265.42238)
			(xy 390.664954 -265.42238)
		)
		(stroke
			(width 0)
			(type solid)
		)
		(fill yes)
		(layer "In11.Cu")
		(net "M_L_CPU0_SB_PAR")
	)
	(gr_poly
		(pts
			(xy 390.664954 -263.757918) (xy 390.564878 -263.657842) (xy 390.464802 -263.757918) (xy 390.464802 -263.802368)
			(xy 390.664954 -263.802368)
		)
		(stroke
			(width 0)
			(type solid)
		)
		(fill yes)
		(layer "In11.Cu")
		(net "M_L_CPU0_SB_CA<4>")
	)
	(gr_poly
		(pts
			(xy 390.664954 -263.354058) (xy 390.664954 -263.309608) (xy 390.464802 -263.309608) (xy 390.464802 -263.354058)
			(xy 390.564878 -263.454134)
		)
		(stroke
			(width 0)
			(type solid)
		)
		(fill yes)
		(layer "In11.Cu")
		(net "M_L_CPU0_SB_CA<3>")
	)
	(gr_poly
		(pts
			(xy 390.664954 -262.137906) (xy 390.564878 -262.03783) (xy 390.464802 -262.137906) (xy 390.464802 -262.182356)
			(xy 390.664954 -262.182356)
		)
		(stroke
			(width 0)
			(type solid)
		)
		(fill yes)
		(layer "In11.Cu")
		(net "M_L_CPU0_SB_CA<0>")
	)
	(gr_poly
		(pts
			(xy 390.75487 -225.503994) (xy 390.716262 -225.481896) (xy 390.57961 -225.518472) (xy 390.616186 -225.655124)
			(xy 390.654794 -225.677222)
		)
		(stroke
			(width 0)
			(type solid)
		)
		(fill yes)
		(layer "In11.Cu")
		(net "M_L_CPU0_SA_DQ<1>")
	)
	(gr_poly
		(pts
			(xy 390.75487 -223.883982) (xy 390.716262 -223.861884) (xy 390.57961 -223.89846) (xy 390.616186 -224.035112)
			(xy 390.654794 -224.05721)
		)
		(stroke
			(width 0)
			(type solid)
		)
		(fill yes)
		(layer "In11.Cu")
		(net "M_L_CPU0_SA_DQ<0>")
	)
	(gr_poly
		(pts
			(xy 390.83488 -256.432558) (xy 390.83488 -256.384806) (xy 390.634728 -256.384806) (xy 390.634728 -256.432558)
			(xy 390.734804 -256.53238)
		)
		(stroke
			(width 0)
			(type solid)
		)
		(fill yes)
		(layer "In11.Cu")
		(net "M_L_CPU0_CLK_DN<0>")
	)
	(gr_poly
		(pts
			(xy 390.83488 -255.216152) (xy 390.734804 -255.116076) (xy 390.634728 -255.216152) (xy 390.634728 -255.260602)
			(xy 390.83488 -255.260602)
		)
		(stroke
			(width 0)
			(type solid)
		)
		(fill yes)
		(layer "In11.Cu")
		(net "M_L_CPU0_SA_CA<6>")
	)
	(gr_poly
		(pts
			(xy 390.83488 -254.812292) (xy 390.83488 -254.767842) (xy 390.634728 -254.767842) (xy 390.634728 -254.812292)
			(xy 390.734804 -254.912368)
		)
		(stroke
			(width 0)
			(type solid)
		)
		(fill yes)
		(layer "In11.Cu")
		(net "M_L_CPU0_SA_CA<5>")
	)
	(gr_poly
		(pts
			(xy 390.83488 -253.59614) (xy 390.734804 -253.496064) (xy 390.634728 -253.59614) (xy 390.634728 -253.64059)
			(xy 390.83488 -253.64059)
		)
		(stroke
			(width 0)
			(type solid)
		)
		(fill yes)
		(layer "In11.Cu")
		(net "M_L_CPU0_SA_CA<2>")
	)
	(gr_poly
		(pts
			(xy 390.83488 -253.19228) (xy 390.83488 -253.14783) (xy 390.634728 -253.14783) (xy 390.634728 -253.19228)
			(xy 390.734804 -253.292356)
		)
		(stroke
			(width 0)
			(type solid)
		)
		(fill yes)
		(layer "In11.Cu")
		(net "M_L_CPU0_SA_CA<1>")
	)
	(gr_poly
		(pts
			(xy 390.83488 -251.969778) (xy 390.734804 -251.869702) (xy 390.634728 -251.969778) (xy 390.634728 -252.014228)
			(xy 390.83488 -252.014228)
		)
		(stroke
			(width 0)
			(type solid)
		)
		(fill yes)
		(layer "In11.Cu")
		(net "M_L_CPU0_SA_CS_N<1>")
	)
	(gr_poly
		(pts
			(xy 390.83488 -250.356116) (xy 390.734804 -250.25604) (xy 390.634728 -250.356116) (xy 390.634728 -250.400566)
			(xy 390.83488 -250.400566)
		)
		(stroke
			(width 0)
			(type solid)
		)
		(fill yes)
		(layer "In11.Cu")
		(net "M_L_CPU0_ALERT_R_N")
	)
	(gr_poly
		(pts
			(xy 390.83488 -248.736104) (xy 390.734804 -248.636028) (xy 390.634728 -248.736104) (xy 390.634728 -248.780554)
			(xy 390.83488 -248.780554)
		)
		(stroke
			(width 0)
			(type solid)
		)
		(fill yes)
		(layer "In11.Cu")
		(net "M_L_CPU0_SA_CB<5>")
	)
	(gr_poly
		(pts
			(xy 390.83488 -248.332244) (xy 390.83488 -248.287794) (xy 390.634728 -248.287794) (xy 390.634728 -248.332244)
			(xy 390.734804 -248.43232)
		)
		(stroke
			(width 0)
			(type solid)
		)
		(fill yes)
		(layer "In11.Cu")
		(net "M_L_CPU0_SA_CB<6>")
	)
	(gr_poly
		(pts
			(xy 390.83488 -247.115838) (xy 390.734804 -247.016016) (xy 390.634728 -247.115838) (xy 390.634728 -247.16359)
			(xy 390.83488 -247.16359)
		)
		(stroke
			(width 0)
			(type solid)
		)
		(fill yes)
		(layer "In11.Cu")
		(net "M_L_CPU0_SA_DQS_DN<9>")
	)
	(gr_poly
		(pts
			(xy 390.83488 -246.712486) (xy 390.83488 -246.664734) (xy 390.634728 -246.664734) (xy 390.634728 -246.712486)
			(xy 390.734804 -246.812308)
		)
		(stroke
			(width 0)
			(type solid)
		)
		(fill yes)
		(layer "In11.Cu")
		(net "M_L_CPU0_SA_DQS_DN<4>")
	)
	(gr_poly
		(pts
			(xy 390.83488 -245.49608) (xy 390.734804 -245.396004) (xy 390.634728 -245.49608) (xy 390.634728 -245.54053)
			(xy 390.83488 -245.54053)
		)
		(stroke
			(width 0)
			(type solid)
		)
		(fill yes)
		(layer "In11.Cu")
		(net "M_L_CPU0_SA_CB<1>")
	)
	(gr_poly
		(pts
			(xy 390.83488 -245.09222) (xy 390.83488 -245.04777) (xy 390.634728 -245.04777) (xy 390.634728 -245.09222)
			(xy 390.734804 -245.192296)
		)
		(stroke
			(width 0)
			(type solid)
		)
		(fill yes)
		(layer "In11.Cu")
		(net "M_L_CPU0_SA_CB<2>")
	)
	(gr_poly
		(pts
			(xy 390.83488 -243.876068) (xy 390.734804 -243.775992) (xy 390.634728 -243.876068) (xy 390.634728 -243.920518)
			(xy 390.83488 -243.920518)
		)
		(stroke
			(width 0)
			(type solid)
		)
		(fill yes)
		(layer "In11.Cu")
		(net "M_L_CPU0_SA_DQ<29>")
	)
	(gr_poly
		(pts
			(xy 390.83488 -243.472208) (xy 390.83488 -243.427758) (xy 390.634728 -243.427758) (xy 390.634728 -243.472208)
			(xy 390.734804 -243.572284)
		)
		(stroke
			(width 0)
			(type solid)
		)
		(fill yes)
		(layer "In11.Cu")
		(net "M_L_CPU0_SA_DQ<30>")
	)
	(gr_poly
		(pts
			(xy 390.83488 -242.255802) (xy 390.734804 -242.15598) (xy 390.634728 -242.255802) (xy 390.634728 -242.303554)
			(xy 390.83488 -242.303554)
		)
		(stroke
			(width 0)
			(type solid)
		)
		(fill yes)
		(layer "In11.Cu")
		(net "M_L_CPU0_SA_DQS_DN<8>")
	)
	(gr_poly
		(pts
			(xy 390.83488 -241.85245) (xy 390.83488 -241.804698) (xy 390.634728 -241.804698) (xy 390.634728 -241.85245)
			(xy 390.734804 -241.952272)
		)
		(stroke
			(width 0)
			(type solid)
		)
		(fill yes)
		(layer "In11.Cu")
		(net "M_L_CPU0_SA_DQS_DN<3>")
	)
	(gr_poly
		(pts
			(xy 390.83488 -240.636044) (xy 390.734804 -240.535968) (xy 390.634728 -240.636044) (xy 390.634728 -240.680494)
			(xy 390.83488 -240.680494)
		)
		(stroke
			(width 0)
			(type solid)
		)
		(fill yes)
		(layer "In11.Cu")
		(net "M_L_CPU0_SA_DQ<25>")
	)
	(gr_poly
		(pts
			(xy 390.83488 -240.232184) (xy 390.83488 -240.187734) (xy 390.634728 -240.187734) (xy 390.634728 -240.232184)
			(xy 390.734804 -240.33226)
		)
		(stroke
			(width 0)
			(type solid)
		)
		(fill yes)
		(layer "In11.Cu")
		(net "M_L_CPU0_SA_DQ<26>")
	)
	(gr_poly
		(pts
			(xy 390.83488 -239.016032) (xy 390.734804 -238.915956) (xy 390.634728 -239.016032) (xy 390.634728 -239.060482)
			(xy 390.83488 -239.060482)
		)
		(stroke
			(width 0)
			(type solid)
		)
		(fill yes)
		(layer "In11.Cu")
		(net "M_L_CPU0_SA_DQ<21>")
	)
	(gr_poly
		(pts
			(xy 390.83488 -238.612172) (xy 390.83488 -238.567722) (xy 390.634728 -238.567722) (xy 390.634728 -238.612172)
			(xy 390.734804 -238.712248)
		)
		(stroke
			(width 0)
			(type solid)
		)
		(fill yes)
		(layer "In11.Cu")
		(net "M_L_CPU0_SA_DQ<22>")
	)
	(gr_poly
		(pts
			(xy 390.83488 -237.395766) (xy 390.734804 -237.295944) (xy 390.634728 -237.395766) (xy 390.634728 -237.443518)
			(xy 390.83488 -237.443518)
		)
		(stroke
			(width 0)
			(type solid)
		)
		(fill yes)
		(layer "In11.Cu")
		(net "M_L_CPU0_SA_DQS_DN<7>")
	)
	(gr_poly
		(pts
			(xy 390.83488 -236.992414) (xy 390.83488 -236.944662) (xy 390.634728 -236.944662) (xy 390.634728 -236.992414)
			(xy 390.734804 -237.092236)
		)
		(stroke
			(width 0)
			(type solid)
		)
		(fill yes)
		(layer "In11.Cu")
		(net "M_L_CPU0_SA_DQS_DN<2>")
	)
	(gr_poly
		(pts
			(xy 390.83488 -235.776008) (xy 390.734804 -235.675932) (xy 390.634728 -235.776008) (xy 390.634728 -235.820458)
			(xy 390.83488 -235.820458)
		)
		(stroke
			(width 0)
			(type solid)
		)
		(fill yes)
		(layer "In11.Cu")
		(net "M_L_CPU0_SA_DQ<17>")
	)
	(gr_poly
		(pts
			(xy 390.83488 -235.372148) (xy 390.83488 -235.327698) (xy 390.634728 -235.327698) (xy 390.634728 -235.372148)
			(xy 390.734804 -235.472224)
		)
		(stroke
			(width 0)
			(type solid)
		)
		(fill yes)
		(layer "In11.Cu")
		(net "M_L_CPU0_SA_DQ<18>")
	)
	(gr_poly
		(pts
			(xy 390.83488 -234.155996) (xy 390.734804 -234.05592) (xy 390.634728 -234.155996) (xy 390.634728 -234.200446)
			(xy 390.83488 -234.200446)
		)
		(stroke
			(width 0)
			(type solid)
		)
		(fill yes)
		(layer "In11.Cu")
		(net "M_L_CPU0_SA_DQ<13>")
	)
	(gr_poly
		(pts
			(xy 390.83488 -233.752136) (xy 390.83488 -233.707686) (xy 390.634728 -233.707686) (xy 390.634728 -233.752136)
			(xy 390.734804 -233.852212)
		)
		(stroke
			(width 0)
			(type solid)
		)
		(fill yes)
		(layer "In11.Cu")
		(net "M_L_CPU0_SA_DQ<14>")
	)
	(gr_poly
		(pts
			(xy 390.83488 -232.53573) (xy 390.734804 -232.435908) (xy 390.634728 -232.53573) (xy 390.634728 -232.583482)
			(xy 390.83488 -232.583482)
		)
		(stroke
			(width 0)
			(type solid)
		)
		(fill yes)
		(layer "In11.Cu")
		(net "M_L_CPU0_SA_DQS_DN<6>")
	)
	(gr_poly
		(pts
			(xy 390.83488 -232.132378) (xy 390.83488 -232.084626) (xy 390.634728 -232.084626) (xy 390.634728 -232.132378)
			(xy 390.734804 -232.2322)
		)
		(stroke
			(width 0)
			(type solid)
		)
		(fill yes)
		(layer "In11.Cu")
		(net "M_L_CPU0_SA_DQS_DN<1>")
	)
	(gr_poly
		(pts
			(xy 390.83488 -230.915972) (xy 390.734804 -230.815896) (xy 390.634728 -230.915972) (xy 390.634728 -230.960422)
			(xy 390.83488 -230.960422)
		)
		(stroke
			(width 0)
			(type solid)
		)
		(fill yes)
		(layer "In11.Cu")
		(net "M_L_CPU0_SA_DQ<9>")
	)
	(gr_poly
		(pts
			(xy 390.83488 -230.512366) (xy 390.83488 -230.467916) (xy 390.634728 -230.467916) (xy 390.634728 -230.512366)
			(xy 390.734804 -230.612188)
		)
		(stroke
			(width 0)
			(type solid)
		)
		(fill yes)
		(layer "In11.Cu")
		(net "M_L_CPU0_SA_DQ<10>")
	)
	(gr_poly
		(pts
			(xy 390.83488 -229.29596) (xy 390.734804 -229.195884) (xy 390.634728 -229.29596) (xy 390.634728 -229.34041)
			(xy 390.83488 -229.34041)
		)
		(stroke
			(width 0)
			(type solid)
		)
		(fill yes)
		(layer "In11.Cu")
		(net "M_L_CPU0_SA_DQ<5>")
	)
	(gr_poly
		(pts
			(xy 390.83488 -228.892354) (xy 390.83488 -228.847904) (xy 390.634728 -228.847904) (xy 390.634728 -228.892354)
			(xy 390.734804 -228.99243)
		)
		(stroke
			(width 0)
			(type solid)
		)
		(fill yes)
		(layer "In11.Cu")
		(net "M_L_CPU0_SA_DQ<6>")
	)
	(gr_poly
		(pts
			(xy 390.83488 -227.675948) (xy 390.734804 -227.576126) (xy 390.634728 -227.675948) (xy 390.634728 -227.7237)
			(xy 390.83488 -227.7237)
		)
		(stroke
			(width 0)
			(type solid)
		)
		(fill yes)
		(layer "In11.Cu")
		(net "M_L_CPU0_SA_DQS_DN<5>")
	)
	(gr_poly
		(pts
			(xy 390.83488 -227.272596) (xy 390.83488 -227.224844) (xy 390.634728 -227.224844) (xy 390.634728 -227.272596)
			(xy 390.734804 -227.372418)
		)
		(stroke
			(width 0)
			(type solid)
		)
		(fill yes)
		(layer "In11.Cu")
		(net "M_L_CPU0_SA_DQS_DN<0>")
	)
	(gr_poly
		(pts
			(xy 390.889998 -226.190048) (xy 390.853422 -226.053396) (xy 390.814814 -226.031298) (xy 390.714738 -226.204526)
			(xy 390.753346 -226.226624)
		)
		(stroke
			(width 0)
			(type solid)
		)
		(fill yes)
		(layer "In11.Cu")
		(net "M_L_CPU0_SA_DQ<3>")
	)
	(gr_poly
		(pts
			(xy 390.889998 -224.570036) (xy 390.853422 -224.433384) (xy 390.814814 -224.411286) (xy 390.714738 -224.584514)
			(xy 390.753346 -224.606612)
		)
		(stroke
			(width 0)
			(type solid)
		)
		(fill yes)
		(layer "In11.Cu")
		(net "M_L_CPU0_SA_DQ<2>")
	)
	(gr_poly
		(pts
			(xy 391.134854 -293.324026) (xy 391.134854 -293.279576) (xy 390.934702 -293.279576) (xy 390.934702 -293.324026)
			(xy 391.034778 -293.424102)
		)
		(stroke
			(width 0)
			(type solid)
		)
		(fill yes)
		(layer "In11.Cu")
		(net "M_L_CPU0_SB_DQ<31>")
	)
	(gr_poly
		(pts
			(xy 391.134854 -292.107874) (xy 391.034778 -292.007798) (xy 390.934702 -292.107874) (xy 390.934702 -292.152324)
			(xy 391.134854 -292.152324)
		)
		(stroke
			(width 0)
			(type solid)
		)
		(fill yes)
		(layer "In11.Cu")
		(net "M_L_CPU0_SB_DQ<28>")
	)
	(gr_poly
		(pts
			(xy 391.134854 -291.704268) (xy 391.134854 -291.656516) (xy 390.934702 -291.656516) (xy 390.934702 -291.704268)
			(xy 391.034778 -291.80409)
		)
		(stroke
			(width 0)
			(type solid)
		)
		(fill yes)
		(layer "In11.Cu")
		(net "M_L_CPU0_SB_DQS_DP<8>")
	)
	(gr_poly
		(pts
			(xy 391.134854 -290.487608) (xy 391.034778 -290.387786) (xy 390.934702 -290.487608) (xy 390.934702 -290.53536)
			(xy 391.134854 -290.53536)
		)
		(stroke
			(width 0)
			(type solid)
		)
		(fill yes)
		(layer "In11.Cu")
		(net "M_L_CPU0_SB_DQS_DP<3>")
	)
	(gr_poly
		(pts
			(xy 391.134854 -290.084002) (xy 391.134854 -290.039552) (xy 390.934702 -290.039552) (xy 390.934702 -290.084002)
			(xy 391.034778 -290.184078)
		)
		(stroke
			(width 0)
			(type solid)
		)
		(fill yes)
		(layer "In11.Cu")
		(net "M_L_CPU0_SB_DQ<27>")
	)
	(gr_poly
		(pts
			(xy 391.134854 -288.86785) (xy 391.034778 -288.767774) (xy 390.934702 -288.86785) (xy 390.934702 -288.9123)
			(xy 391.134854 -288.9123)
		)
		(stroke
			(width 0)
			(type solid)
		)
		(fill yes)
		(layer "In11.Cu")
		(net "M_L_CPU0_SB_DQ<24>")
	)
	(gr_poly
		(pts
			(xy 391.134854 -288.464244) (xy 391.134854 -288.419794) (xy 390.934702 -288.419794) (xy 390.934702 -288.464244)
			(xy 391.034778 -288.56432)
		)
		(stroke
			(width 0)
			(type solid)
		)
		(fill yes)
		(layer "In11.Cu")
		(net "M_L_CPU0_SB_DQ<23>")
	)
	(gr_poly
		(pts
			(xy 391.134854 -287.247838) (xy 391.034778 -287.148016) (xy 390.934702 -287.247838) (xy 390.934702 -287.292288)
			(xy 391.134854 -287.292288)
		)
		(stroke
			(width 0)
			(type solid)
		)
		(fill yes)
		(layer "In11.Cu")
		(net "M_L_CPU0_SB_DQ<20>")
	)
	(gr_poly
		(pts
			(xy 391.134854 -286.844232) (xy 391.134854 -286.79648) (xy 390.934702 -286.79648) (xy 390.934702 -286.844232)
			(xy 391.034778 -286.944308)
		)
		(stroke
			(width 0)
			(type solid)
		)
		(fill yes)
		(layer "In11.Cu")
		(net "M_L_CPU0_SB_DQS_DP<7>")
	)
	(gr_poly
		(pts
			(xy 391.134854 -285.627826) (xy 391.034778 -285.528004) (xy 390.934702 -285.627826) (xy 390.934702 -285.675578)
			(xy 391.134854 -285.675578)
		)
		(stroke
			(width 0)
			(type solid)
		)
		(fill yes)
		(layer "In11.Cu")
		(net "M_L_CPU0_SB_DQS_DP<2>")
	)
	(gr_poly
		(pts
			(xy 391.134854 -285.22422) (xy 391.134854 -285.17977) (xy 390.934702 -285.17977) (xy 390.934702 -285.22422)
			(xy 391.034778 -285.324296)
		)
		(stroke
			(width 0)
			(type solid)
		)
		(fill yes)
		(layer "In11.Cu")
		(net "M_L_CPU0_SB_DQ<19>")
	)
	(gr_poly
		(pts
			(xy 391.134854 -284.008068) (xy 391.034778 -283.907992) (xy 390.934702 -284.008068) (xy 390.934702 -284.052518)
			(xy 391.134854 -284.052518)
		)
		(stroke
			(width 0)
			(type solid)
		)
		(fill yes)
		(layer "In11.Cu")
		(net "M_L_CPU0_SB_DQ<16>")
	)
	(gr_poly
		(pts
			(xy 391.134854 -283.604208) (xy 391.134854 -283.559758) (xy 390.934702 -283.559758) (xy 390.934702 -283.604208)
			(xy 391.034778 -283.704284)
		)
		(stroke
			(width 0)
			(type solid)
		)
		(fill yes)
		(layer "In11.Cu")
		(net "M_L_CPU0_SB_DQ<15>")
	)
	(gr_poly
		(pts
			(xy 391.134854 -282.388056) (xy 391.034778 -282.28798) (xy 390.934702 -282.388056) (xy 390.934702 -282.432506)
			(xy 391.134854 -282.432506)
		)
		(stroke
			(width 0)
			(type solid)
		)
		(fill yes)
		(layer "In11.Cu")
		(net "M_L_CPU0_SB_DQ<12>")
	)
	(gr_poly
		(pts
			(xy 391.134854 -281.98445) (xy 391.134854 -281.936698) (xy 390.934702 -281.936698) (xy 390.934702 -281.98445)
			(xy 391.034778 -282.084272)
		)
		(stroke
			(width 0)
			(type solid)
		)
		(fill yes)
		(layer "In11.Cu")
		(net "M_L_CPU0_SB_DQS_DP<6>")
	)
	(gr_poly
		(pts
			(xy 391.134854 -280.76779) (xy 391.034778 -280.667968) (xy 390.934702 -280.76779) (xy 390.934702 -280.815542)
			(xy 391.134854 -280.815542)
		)
		(stroke
			(width 0)
			(type solid)
		)
		(fill yes)
		(layer "In11.Cu")
		(net "M_L_CPU0_SB_DQS_DP<1>")
	)
	(gr_poly
		(pts
			(xy 391.134854 -280.364184) (xy 391.134854 -280.319734) (xy 390.934702 -280.319734) (xy 390.934702 -280.364184)
			(xy 391.034778 -280.46426)
		)
		(stroke
			(width 0)
			(type solid)
		)
		(fill yes)
		(layer "In11.Cu")
		(net "M_L_CPU0_SB_DQ<11>")
	)
	(gr_poly
		(pts
			(xy 391.134854 -279.148032) (xy 391.034778 -279.047956) (xy 390.934702 -279.148032) (xy 390.934702 -279.192482)
			(xy 391.134854 -279.192482)
		)
		(stroke
			(width 0)
			(type solid)
		)
		(fill yes)
		(layer "In11.Cu")
		(net "M_L_CPU0_SB_DQ<8>")
	)
	(gr_poly
		(pts
			(xy 391.134854 -278.744172) (xy 391.134854 -278.699722) (xy 390.934702 -278.699722) (xy 390.934702 -278.744172)
			(xy 391.034778 -278.844248)
		)
		(stroke
			(width 0)
			(type solid)
		)
		(fill yes)
		(layer "In11.Cu")
		(net "M_L_CPU0_SB_DQ<7>")
	)
	(gr_poly
		(pts
			(xy 391.134854 -277.52802) (xy 391.034778 -277.427944) (xy 390.934702 -277.52802) (xy 390.934702 -277.57247)
			(xy 391.134854 -277.57247)
		)
		(stroke
			(width 0)
			(type solid)
		)
		(fill yes)
		(layer "In11.Cu")
		(net "M_L_CPU0_SB_DQ<4>")
	)
	(gr_poly
		(pts
			(xy 391.134854 -277.124414) (xy 391.134854 -277.076662) (xy 390.934702 -277.076662) (xy 390.934702 -277.124414)
			(xy 391.034778 -277.224236)
		)
		(stroke
			(width 0)
			(type solid)
		)
		(fill yes)
		(layer "In11.Cu")
		(net "M_L_CPU0_SB_DQS_DP<5>")
	)
	(gr_poly
		(pts
			(xy 391.134854 -275.907754) (xy 391.034778 -275.807932) (xy 390.934702 -275.907754) (xy 390.934702 -275.955506)
			(xy 391.134854 -275.955506)
		)
		(stroke
			(width 0)
			(type solid)
		)
		(fill yes)
		(layer "In11.Cu")
		(net "M_L_CPU0_SB_DQS_DP<0>")
	)
	(gr_poly
		(pts
			(xy 391.134854 -275.504148) (xy 391.134854 -275.459698) (xy 390.934702 -275.459698) (xy 390.934702 -275.504148)
			(xy 391.034778 -275.604224)
		)
		(stroke
			(width 0)
			(type solid)
		)
		(fill yes)
		(layer "In11.Cu")
		(net "M_L_CPU0_SB_DQ<3>")
	)
	(gr_poly
		(pts
			(xy 391.134854 -274.287996) (xy 391.034778 -274.18792) (xy 390.934702 -274.287996) (xy 390.934702 -274.332446)
			(xy 391.134854 -274.332446)
		)
		(stroke
			(width 0)
			(type solid)
		)
		(fill yes)
		(layer "In11.Cu")
		(net "M_L_CPU0_SB_DQ<0>")
	)
	(gr_poly
		(pts
			(xy 391.134854 -273.884136) (xy 391.134854 -273.839686) (xy 390.934702 -273.839686) (xy 390.934702 -273.884136)
			(xy 391.034778 -273.984212)
		)
		(stroke
			(width 0)
			(type solid)
		)
		(fill yes)
		(layer "In11.Cu")
		(net "M_L_CPU0_SB_CB<3>")
	)
	(gr_poly
		(pts
			(xy 391.134854 -272.667984) (xy 391.034778 -272.567908) (xy 390.934702 -272.667984) (xy 390.934702 -272.712434)
			(xy 391.134854 -272.712434)
		)
		(stroke
			(width 0)
			(type solid)
		)
		(fill yes)
		(layer "In11.Cu")
		(net "M_L_CPU0_SB_CB<0>")
	)
	(gr_poly
		(pts
			(xy 391.134854 -272.264378) (xy 391.134854 -272.216626) (xy 390.934702 -272.216626) (xy 390.934702 -272.264378)
			(xy 391.034778 -272.3642)
		)
		(stroke
			(width 0)
			(type solid)
		)
		(fill yes)
		(layer "In11.Cu")
		(net "M_L_CPU0_SB_DQS_DP<4>")
	)
	(gr_poly
		(pts
			(xy 391.134854 -271.047718) (xy 391.034778 -270.947896) (xy 390.934702 -271.047718) (xy 390.934702 -271.09547)
			(xy 391.134854 -271.09547)
		)
		(stroke
			(width 0)
			(type solid)
		)
		(fill yes)
		(layer "In11.Cu")
		(net "M_L_CPU0_SB_DQS_DP<9>")
	)
	(gr_poly
		(pts
			(xy 391.134854 -270.644112) (xy 391.134854 -270.599662) (xy 390.934702 -270.599662) (xy 390.934702 -270.644112)
			(xy 391.034778 -270.744188)
		)
		(stroke
			(width 0)
			(type solid)
		)
		(fill yes)
		(layer "In11.Cu")
		(net "M_L_CPU0_SB_CB<7>")
	)
	(gr_poly
		(pts
			(xy 391.134854 -269.42796) (xy 391.034778 -269.327884) (xy 390.934702 -269.42796) (xy 390.934702 -269.47241)
			(xy 391.134854 -269.47241)
		)
		(stroke
			(width 0)
			(type solid)
		)
		(fill yes)
		(layer "In11.Cu")
		(net "M_L_CPU0_SB_CB<4>")
	)
	(gr_poly
		(pts
			(xy 391.134854 -267.807948) (xy 391.034778 -267.707872) (xy 390.934702 -267.807948) (xy 390.934702 -267.852398)
			(xy 391.134854 -267.852398)
		)
		(stroke
			(width 0)
			(type solid)
		)
		(fill yes)
		(layer "In11.Cu")
		(net "M_L_CPU0_SB_RSP<0>")
	)
	(gr_poly
		(pts
			(xy 391.134854 -265.784076) (xy 391.134854 -265.739626) (xy 390.934702 -265.739626) (xy 390.934702 -265.784076)
			(xy 391.034778 -265.884152)
		)
		(stroke
			(width 0)
			(type solid)
		)
		(fill yes)
		(layer "In11.Cu")
		(net "M_L_CPU0_SB_CS_N<0>")
	)
	(gr_poly
		(pts
			(xy 391.134854 -264.561574) (xy 391.034778 -264.461498) (xy 390.934702 -264.561574) (xy 390.934702 -264.606024)
			(xy 391.134854 -264.606024)
		)
		(stroke
			(width 0)
			(type solid)
		)
		(fill yes)
		(layer "In11.Cu")
		(net "M_L_CPU0_SB_CA<6>")
	)
	(gr_poly
		(pts
			(xy 391.134854 -264.164064) (xy 391.134854 -264.119614) (xy 390.934702 -264.119614) (xy 390.934702 -264.164064)
			(xy 391.034778 -264.26414)
		)
		(stroke
			(width 0)
			(type solid)
		)
		(fill yes)
		(layer "In11.Cu")
		(net "M_L_CPU0_SB_CA<5>")
	)
	(gr_poly
		(pts
			(xy 391.134854 -262.947912) (xy 391.034778 -262.847836) (xy 390.934702 -262.947912) (xy 390.934702 -262.992362)
			(xy 391.134854 -262.992362)
		)
		(stroke
			(width 0)
			(type solid)
		)
		(fill yes)
		(layer "In11.Cu")
		(net "M_L_CPU0_SB_CA<2>")
	)
	(gr_poly
		(pts
			(xy 391.134854 -262.544052) (xy 391.134854 -262.499602) (xy 390.934702 -262.499602) (xy 390.934702 -262.544052)
			(xy 391.034778 -262.644128)
		)
		(stroke
			(width 0)
			(type solid)
		)
		(fill yes)
		(layer "In11.Cu")
		(net "M_L_CPU0_SB_CA<1>")
	)
	(gr_poly
		(pts
			(xy 391.224008 -224.695512) (xy 391.1854 -224.67316) (xy 391.049002 -224.709736) (xy 391.085578 -224.846388)
			(xy 391.123932 -224.86874)
		)
		(stroke
			(width 0)
			(type solid)
		)
		(fill yes)
		(layer "In11.Cu")
		(net "M_L_CPU0_SA_DQ<1>")
	)
	(gr_poly
		(pts
			(xy 391.224008 -223.0755) (xy 391.1854 -223.053148) (xy 391.049002 -223.089724) (xy 391.085578 -223.226376)
			(xy 391.123932 -223.248728)
		)
		(stroke
			(width 0)
			(type solid)
		)
		(fill yes)
		(layer "In11.Cu")
		(net "M_L_CPU0_SA_DQ<0>")
	)
	(gr_poly
		(pts
			(xy 391.226802 -226.316286) (xy 391.185654 -226.292664) (xy 391.049002 -226.32924) (xy 391.085578 -226.465638)
			(xy 391.12698 -226.489514)
		)
		(stroke
			(width 0)
			(type solid)
		)
		(fill yes)
		(layer "In11.Cu")
		(net "M_L_CPU0_SA_DQS_DP<0>")
	)
	(gr_poly
		(pts
			(xy 391.30478 -256.025904) (xy 391.204704 -255.926082) (xy 391.104628 -256.025904) (xy 391.104628 -256.073656)
			(xy 391.30478 -256.073656)
		)
		(stroke
			(width 0)
			(type solid)
		)
		(fill yes)
		(layer "In11.Cu")
		(net "M_L_CPU0_CLK_DP<0>")
	)
	(gr_poly
		(pts
			(xy 391.30478 -255.622298) (xy 391.30478 -255.577848) (xy 391.104628 -255.577848) (xy 391.104628 -255.622298)
			(xy 391.204704 -255.722374)
		)
		(stroke
			(width 0)
			(type solid)
		)
		(fill yes)
		(layer "In11.Cu")
		(net "M_L_CPU0_SA_PAR")
	)
	(gr_poly
		(pts
			(xy 391.30478 -254.406146) (xy 391.204704 -254.30607) (xy 391.104628 -254.406146) (xy 391.104628 -254.450596)
			(xy 391.30478 -254.450596)
		)
		(stroke
			(width 0)
			(type solid)
		)
		(fill yes)
		(layer "In11.Cu")
		(net "M_L_CPU0_SA_CA<4>")
	)
	(gr_poly
		(pts
			(xy 391.30478 -254.002286) (xy 391.30478 -253.957836) (xy 391.104628 -253.957836) (xy 391.104628 -254.002286)
			(xy 391.204704 -254.102362)
		)
		(stroke
			(width 0)
			(type solid)
		)
		(fill yes)
		(layer "In11.Cu")
		(net "M_L_CPU0_SA_CA<3>")
	)
	(gr_poly
		(pts
			(xy 391.30478 -252.786134) (xy 391.204704 -252.686058) (xy 391.104628 -252.786134) (xy 391.104628 -252.830584)
			(xy 391.30478 -252.830584)
		)
		(stroke
			(width 0)
			(type solid)
		)
		(fill yes)
		(layer "In11.Cu")
		(net "M_L_CPU0_SA_CA<0>")
	)
	(gr_poly
		(pts
			(xy 391.30478 -250.762262) (xy 391.30478 -250.717812) (xy 391.104628 -250.717812) (xy 391.104628 -250.762262)
			(xy 391.204704 -250.862338)
		)
		(stroke
			(width 0)
			(type solid)
		)
		(fill yes)
		(layer "In11.Cu")
		(net "M_L_CPU0_RESET_N")
	)
	(gr_poly
		(pts
			(xy 391.30478 -249.14225) (xy 391.30478 -249.0978) (xy 391.104628 -249.0978) (xy 391.104628 -249.14225)
			(xy 391.204704 -249.242326)
		)
		(stroke
			(width 0)
			(type solid)
		)
		(fill yes)
		(layer "In11.Cu")
		(net "M_L_CPU0_SA_CB<7>")
	)
	(gr_poly
		(pts
			(xy 391.30478 -247.926098) (xy 391.204704 -247.826022) (xy 391.104628 -247.926098) (xy 391.104628 -247.970548)
			(xy 391.30478 -247.970548)
		)
		(stroke
			(width 0)
			(type solid)
		)
		(fill yes)
		(layer "In11.Cu")
		(net "M_L_CPU0_SA_CB<4>")
	)
	(gr_poly
		(pts
			(xy 391.30478 -247.522492) (xy 391.30478 -247.47474) (xy 391.104628 -247.47474) (xy 391.104628 -247.522492)
			(xy 391.204704 -247.622314)
		)
		(stroke
			(width 0)
			(type solid)
		)
		(fill yes)
		(layer "In11.Cu")
		(net "M_L_CPU0_SA_DQS_DP<9>")
	)
	(gr_poly
		(pts
			(xy 391.30478 -246.305832) (xy 391.204704 -246.20601) (xy 391.104628 -246.305832) (xy 391.104628 -246.353584)
			(xy 391.30478 -246.353584)
		)
		(stroke
			(width 0)
			(type solid)
		)
		(fill yes)
		(layer "In11.Cu")
		(net "M_L_CPU0_SA_DQS_DP<4>")
	)
	(gr_poly
		(pts
			(xy 391.30478 -245.902226) (xy 391.30478 -245.857776) (xy 391.104628 -245.857776) (xy 391.104628 -245.902226)
			(xy 391.204704 -246.002302)
		)
		(stroke
			(width 0)
			(type solid)
		)
		(fill yes)
		(layer "In11.Cu")
		(net "M_L_CPU0_SA_CB<3>")
	)
	(gr_poly
		(pts
			(xy 391.30478 -244.686074) (xy 391.204704 -244.585998) (xy 391.104628 -244.686074) (xy 391.104628 -244.730524)
			(xy 391.30478 -244.730524)
		)
		(stroke
			(width 0)
			(type solid)
		)
		(fill yes)
		(layer "In11.Cu")
		(net "M_L_CPU0_SA_CB<0>")
	)
	(gr_poly
		(pts
			(xy 391.30478 -244.282214) (xy 391.30478 -244.237764) (xy 391.104628 -244.237764) (xy 391.104628 -244.282214)
			(xy 391.204704 -244.38229)
		)
		(stroke
			(width 0)
			(type solid)
		)
		(fill yes)
		(layer "In11.Cu")
		(net "M_L_CPU0_SA_DQ<31>")
	)
	(gr_poly
		(pts
			(xy 391.30478 -243.066062) (xy 391.204704 -242.965986) (xy 391.104628 -243.066062) (xy 391.104628 -243.110512)
			(xy 391.30478 -243.110512)
		)
		(stroke
			(width 0)
			(type solid)
		)
		(fill yes)
		(layer "In11.Cu")
		(net "M_L_CPU0_SA_DQ<28>")
	)
	(gr_poly
		(pts
			(xy 391.30478 -242.662456) (xy 391.30478 -242.614704) (xy 391.104628 -242.614704) (xy 391.104628 -242.662456)
			(xy 391.204704 -242.762278)
		)
		(stroke
			(width 0)
			(type solid)
		)
		(fill yes)
		(layer "In11.Cu")
		(net "M_L_CPU0_SA_DQS_DP<8>")
	)
	(gr_poly
		(pts
			(xy 391.30478 -241.445796) (xy 391.204704 -241.345974) (xy 391.104628 -241.445796) (xy 391.104628 -241.493548)
			(xy 391.30478 -241.493548)
		)
		(stroke
			(width 0)
			(type solid)
		)
		(fill yes)
		(layer "In11.Cu")
		(net "M_L_CPU0_SA_DQS_DP<3>")
	)
	(gr_poly
		(pts
			(xy 391.30478 -241.04219) (xy 391.30478 -240.99774) (xy 391.104628 -240.99774) (xy 391.104628 -241.04219)
			(xy 391.204704 -241.142266)
		)
		(stroke
			(width 0)
			(type solid)
		)
		(fill yes)
		(layer "In11.Cu")
		(net "M_L_CPU0_SA_DQ<27>")
	)
	(gr_poly
		(pts
			(xy 391.30478 -239.826038) (xy 391.204704 -239.725962) (xy 391.104628 -239.826038) (xy 391.104628 -239.870488)
			(xy 391.30478 -239.870488)
		)
		(stroke
			(width 0)
			(type solid)
		)
		(fill yes)
		(layer "In11.Cu")
		(net "M_L_CPU0_SA_DQ<24>")
	)
	(gr_poly
		(pts
			(xy 391.30478 -239.422178) (xy 391.30478 -239.377728) (xy 391.104628 -239.377728) (xy 391.104628 -239.422178)
			(xy 391.204704 -239.522254)
		)
		(stroke
			(width 0)
			(type solid)
		)
		(fill yes)
		(layer "In11.Cu")
		(net "M_L_CPU0_SA_DQ<23>")
	)
	(gr_poly
		(pts
			(xy 391.30478 -238.206026) (xy 391.204704 -238.10595) (xy 391.104628 -238.206026) (xy 391.104628 -238.250476)
			(xy 391.30478 -238.250476)
		)
		(stroke
			(width 0)
			(type solid)
		)
		(fill yes)
		(layer "In11.Cu")
		(net "M_L_CPU0_SA_DQ<20>")
	)
	(gr_poly
		(pts
			(xy 391.30478 -237.80242) (xy 391.30478 -237.754668) (xy 391.104628 -237.754668) (xy 391.104628 -237.80242)
			(xy 391.204704 -237.902242)
		)
		(stroke
			(width 0)
			(type solid)
		)
		(fill yes)
		(layer "In11.Cu")
		(net "M_L_CPU0_SA_DQS_DP<7>")
	)
	(gr_poly
		(pts
			(xy 391.30478 -236.58576) (xy 391.204704 -236.485938) (xy 391.104628 -236.58576) (xy 391.104628 -236.633512)
			(xy 391.30478 -236.633512)
		)
		(stroke
			(width 0)
			(type solid)
		)
		(fill yes)
		(layer "In11.Cu")
		(net "M_L_CPU0_SA_DQS_DP<2>")
	)
	(gr_poly
		(pts
			(xy 391.30478 -236.182154) (xy 391.30478 -236.137704) (xy 391.104628 -236.137704) (xy 391.104628 -236.182154)
			(xy 391.204704 -236.28223)
		)
		(stroke
			(width 0)
			(type solid)
		)
		(fill yes)
		(layer "In11.Cu")
		(net "M_L_CPU0_SA_DQ<19>")
	)
	(gr_poly
		(pts
			(xy 391.30478 -234.966002) (xy 391.204704 -234.865926) (xy 391.104628 -234.966002) (xy 391.104628 -235.010452)
			(xy 391.30478 -235.010452)
		)
		(stroke
			(width 0)
			(type solid)
		)
		(fill yes)
		(layer "In11.Cu")
		(net "M_L_CPU0_SA_DQ<16>")
	)
	(gr_poly
		(pts
			(xy 391.30478 -234.562142) (xy 391.30478 -234.517692) (xy 391.104628 -234.517692) (xy 391.104628 -234.562142)
			(xy 391.204704 -234.662218)
		)
		(stroke
			(width 0)
			(type solid)
		)
		(fill yes)
		(layer "In11.Cu")
		(net "M_L_CPU0_SA_DQ<15>")
	)
	(gr_poly
		(pts
			(xy 391.30478 -233.34599) (xy 391.204704 -233.245914) (xy 391.104628 -233.34599) (xy 391.104628 -233.39044)
			(xy 391.30478 -233.39044)
		)
		(stroke
			(width 0)
			(type solid)
		)
		(fill yes)
		(layer "In11.Cu")
		(net "M_L_CPU0_SA_DQ<12>")
	)
	(gr_poly
		(pts
			(xy 391.30478 -232.942384) (xy 391.30478 -232.894632) (xy 391.104628 -232.894632) (xy 391.104628 -232.942384)
			(xy 391.204704 -233.042206)
		)
		(stroke
			(width 0)
			(type solid)
		)
		(fill yes)
		(layer "In11.Cu")
		(net "M_L_CPU0_SA_DQS_DP<6>")
	)
	(gr_poly
		(pts
			(xy 391.30478 -231.725724) (xy 391.204704 -231.625902) (xy 391.104628 -231.725724) (xy 391.104628 -231.773476)
			(xy 391.30478 -231.773476)
		)
		(stroke
			(width 0)
			(type solid)
		)
		(fill yes)
		(layer "In11.Cu")
		(net "M_L_CPU0_SA_DQS_DP<1>")
	)
	(gr_poly
		(pts
			(xy 391.30478 -231.322372) (xy 391.30478 -231.277922) (xy 391.104628 -231.277922) (xy 391.104628 -231.322372)
			(xy 391.204704 -231.422448)
		)
		(stroke
			(width 0)
			(type solid)
		)
		(fill yes)
		(layer "In11.Cu")
		(net "M_L_CPU0_SA_DQ<11>")
	)
	(gr_poly
		(pts
			(xy 391.30478 -230.105966) (xy 391.204704 -230.006144) (xy 391.104628 -230.105966) (xy 391.104628 -230.150416)
			(xy 391.30478 -230.150416)
		)
		(stroke
			(width 0)
			(type solid)
		)
		(fill yes)
		(layer "In11.Cu")
		(net "M_L_CPU0_SA_DQ<8>")
	)
	(gr_poly
		(pts
			(xy 391.30478 -229.70236) (xy 391.30478 -229.65791) (xy 391.104628 -229.65791) (xy 391.104628 -229.70236)
			(xy 391.204704 -229.802436)
		)
		(stroke
			(width 0)
			(type solid)
		)
		(fill yes)
		(layer "In11.Cu")
		(net "M_L_CPU0_SA_DQ<7>")
	)
	(gr_poly
		(pts
			(xy 391.30478 -228.486208) (xy 391.204704 -228.386132) (xy 391.104628 -228.486208) (xy 391.104628 -228.530658)
			(xy 391.30478 -228.530658)
		)
		(stroke
			(width 0)
			(type solid)
		)
		(fill yes)
		(layer "In11.Cu")
		(net "M_L_CPU0_SA_DQ<4>")
	)
	(gr_poly
		(pts
			(xy 391.30478 -228.082602) (xy 391.30478 -228.03485) (xy 391.104628 -228.03485) (xy 391.104628 -228.082602)
			(xy 391.204704 -228.182424)
		)
		(stroke
			(width 0)
			(type solid)
		)
		(fill yes)
		(layer "In11.Cu")
		(net "M_L_CPU0_SA_DQS_DP<5>")
	)
	(gr_poly
		(pts
			(xy 391.310876 -251.159772) (xy 391.211054 -251.059696) (xy 391.110978 -251.159772) (xy 391.110978 -251.204222)
			(xy 391.310876 -251.204222)
		)
		(stroke
			(width 0)
			(type solid)
		)
		(fill yes)
		(layer "In11.Cu")
		(net "M_L_CPU0_SA_CS_N<0>")
	)
	(gr_poly
		(pts
			(xy 391.36066 -226.999292) (xy 391.324084 -226.862894) (xy 391.282682 -226.839018) (xy 391.18286 -227.012246)
			(xy 391.224008 -227.035868)
		)
		(stroke
			(width 0)
			(type solid)
		)
		(fill yes)
		(layer "In11.Cu")
		(net "M_L_CPU0_SA_DQS_DN<0>")
	)
	(gr_poly
		(pts
			(xy 391.360914 -225.378772) (xy 391.324084 -225.24212) (xy 391.28573 -225.219768) (xy 391.185654 -225.392996)
			(xy 391.224262 -225.415348)
		)
		(stroke
			(width 0)
			(type solid)
		)
		(fill yes)
		(layer "In11.Cu")
		(net "M_L_CPU0_SA_DQ<3>")
	)
	(gr_poly
		(pts
			(xy 391.360914 -223.75876) (xy 391.324084 -223.622108) (xy 391.28573 -223.599756) (xy 391.185654 -223.772984)
			(xy 391.224262 -223.795336)
		)
		(stroke
			(width 0)
			(type solid)
		)
		(fill yes)
		(layer "In11.Cu")
		(net "M_L_CPU0_SA_DQ<2>")
	)
	(gr_poly
		(pts
			(xy 391.604754 -292.91788) (xy 391.504678 -292.817804) (xy 391.404602 -292.91788) (xy 391.404602 -292.96233)
			(xy 391.604754 -292.96233)
		)
		(stroke
			(width 0)
			(type solid)
		)
		(fill yes)
		(layer "In11.Cu")
		(net "M_L_CPU0_SB_DQ<29>")
	)
	(gr_poly
		(pts
			(xy 391.604754 -292.51402) (xy 391.604754 -292.46957) (xy 391.404602 -292.46957) (xy 391.404602 -292.51402)
			(xy 391.504678 -292.614096)
		)
		(stroke
			(width 0)
			(type solid)
		)
		(fill yes)
		(layer "In11.Cu")
		(net "M_L_CPU0_SB_DQ<30>")
	)
	(gr_poly
		(pts
			(xy 391.604754 -291.297614) (xy 391.504678 -291.197792) (xy 391.404602 -291.297614) (xy 391.404602 -291.345366)
			(xy 391.604754 -291.345366)
		)
		(stroke
			(width 0)
			(type solid)
		)
		(fill yes)
		(layer "In11.Cu")
		(net "M_L_CPU0_SB_DQS_DN<8>")
	)
	(gr_poly
		(pts
			(xy 391.604754 -290.894262) (xy 391.604754 -290.84651) (xy 391.404602 -290.84651) (xy 391.404602 -290.894262)
			(xy 391.504678 -290.994084)
		)
		(stroke
			(width 0)
			(type solid)
		)
		(fill yes)
		(layer "In11.Cu")
		(net "M_L_CPU0_SB_DQS_DN<3>")
	)
	(gr_poly
		(pts
			(xy 391.604754 -289.677856) (xy 391.504678 -289.57778) (xy 391.404602 -289.677856) (xy 391.404602 -289.722306)
			(xy 391.604754 -289.722306)
		)
		(stroke
			(width 0)
			(type solid)
		)
		(fill yes)
		(layer "In11.Cu")
		(net "M_L_CPU0_SB_DQ<25>")
	)
	(gr_poly
		(pts
			(xy 391.604754 -289.273996) (xy 391.604754 -289.229546) (xy 391.404602 -289.229546) (xy 391.404602 -289.273996)
			(xy 391.504678 -289.374072)
		)
		(stroke
			(width 0)
			(type solid)
		)
		(fill yes)
		(layer "In11.Cu")
		(net "M_L_CPU0_SB_DQ<26>")
	)
	(gr_poly
		(pts
			(xy 391.604754 -288.057844) (xy 391.504678 -287.957768) (xy 391.404602 -288.057844) (xy 391.404602 -288.102294)
			(xy 391.604754 -288.102294)
		)
		(stroke
			(width 0)
			(type solid)
		)
		(fill yes)
		(layer "In11.Cu")
		(net "M_L_CPU0_SB_DQ<21>")
	)
	(gr_poly
		(pts
			(xy 391.604754 -287.654238) (xy 391.604754 -287.609788) (xy 391.404602 -287.609788) (xy 391.404602 -287.654238)
			(xy 391.504678 -287.75406)
		)
		(stroke
			(width 0)
			(type solid)
		)
		(fill yes)
		(layer "In11.Cu")
		(net "M_L_CPU0_SB_DQ<22>")
	)
	(gr_poly
		(pts
			(xy 391.604754 -286.437832) (xy 391.504678 -286.337756) (xy 391.404602 -286.437832) (xy 391.404602 -286.485584)
			(xy 391.604754 -286.485584)
		)
		(stroke
			(width 0)
			(type solid)
		)
		(fill yes)
		(layer "In11.Cu")
		(net "M_L_CPU0_SB_DQS_DN<7>")
	)
	(gr_poly
		(pts
			(xy 391.604754 -286.03448) (xy 391.604754 -285.986728) (xy 391.404602 -285.986728) (xy 391.404602 -286.03448)
			(xy 391.504678 -286.134302)
		)
		(stroke
			(width 0)
			(type solid)
		)
		(fill yes)
		(layer "In11.Cu")
		(net "M_L_CPU0_SB_DQS_DN<2>")
	)
	(gr_poly
		(pts
			(xy 391.604754 -284.818074) (xy 391.504678 -284.717998) (xy 391.404602 -284.818074) (xy 391.404602 -284.862524)
			(xy 391.604754 -284.862524)
		)
		(stroke
			(width 0)
			(type solid)
		)
		(fill yes)
		(layer "In11.Cu")
		(net "M_L_CPU0_SB_DQ<17>")
	)
	(gr_poly
		(pts
			(xy 391.604754 -284.414214) (xy 391.604754 -284.369764) (xy 391.404602 -284.369764) (xy 391.404602 -284.414214)
			(xy 391.504678 -284.51429)
		)
		(stroke
			(width 0)
			(type solid)
		)
		(fill yes)
		(layer "In11.Cu")
		(net "M_L_CPU0_SB_DQ<18>")
	)
	(gr_poly
		(pts
			(xy 391.604754 -283.198062) (xy 391.504678 -283.097986) (xy 391.404602 -283.198062) (xy 391.404602 -283.242512)
			(xy 391.604754 -283.242512)
		)
		(stroke
			(width 0)
			(type solid)
		)
		(fill yes)
		(layer "In11.Cu")
		(net "M_L_CPU0_SB_DQ<13>")
	)
	(gr_poly
		(pts
			(xy 391.604754 -282.794202) (xy 391.604754 -282.749752) (xy 391.404602 -282.749752) (xy 391.404602 -282.794202)
			(xy 391.504678 -282.894278)
		)
		(stroke
			(width 0)
			(type solid)
		)
		(fill yes)
		(layer "In11.Cu")
		(net "M_L_CPU0_SB_DQ<14>")
	)
	(gr_poly
		(pts
			(xy 391.604754 -281.577796) (xy 391.504678 -281.477974) (xy 391.404602 -281.577796) (xy 391.404602 -281.625548)
			(xy 391.604754 -281.625548)
		)
		(stroke
			(width 0)
			(type solid)
		)
		(fill yes)
		(layer "In11.Cu")
		(net "M_L_CPU0_SB_DQS_DN<6>")
	)
	(gr_poly
		(pts
			(xy 391.604754 -281.174444) (xy 391.604754 -281.126692) (xy 391.404602 -281.126692) (xy 391.404602 -281.174444)
			(xy 391.504678 -281.274266)
		)
		(stroke
			(width 0)
			(type solid)
		)
		(fill yes)
		(layer "In11.Cu")
		(net "M_L_CPU0_SB_DQS_DN<1>")
	)
	(gr_poly
		(pts
			(xy 391.604754 -279.958038) (xy 391.504678 -279.857962) (xy 391.404602 -279.958038) (xy 391.404602 -280.002488)
			(xy 391.604754 -280.002488)
		)
		(stroke
			(width 0)
			(type solid)
		)
		(fill yes)
		(layer "In11.Cu")
		(net "M_L_CPU0_SB_DQ<9>")
	)
	(gr_poly
		(pts
			(xy 391.604754 -279.554178) (xy 391.604754 -279.509728) (xy 391.404602 -279.509728) (xy 391.404602 -279.554178)
			(xy 391.504678 -279.654254)
		)
		(stroke
			(width 0)
			(type solid)
		)
		(fill yes)
		(layer "In11.Cu")
		(net "M_L_CPU0_SB_DQ<10>")
	)
	(gr_poly
		(pts
			(xy 391.604754 -278.338026) (xy 391.504678 -278.23795) (xy 391.404602 -278.338026) (xy 391.404602 -278.382476)
			(xy 391.604754 -278.382476)
		)
		(stroke
			(width 0)
			(type solid)
		)
		(fill yes)
		(layer "In11.Cu")
		(net "M_L_CPU0_SB_DQ<5>")
	)
	(gr_poly
		(pts
			(xy 391.604754 -277.934166) (xy 391.604754 -277.889716) (xy 391.404602 -277.889716) (xy 391.404602 -277.934166)
			(xy 391.504678 -278.034242)
		)
		(stroke
			(width 0)
			(type solid)
		)
		(fill yes)
		(layer "In11.Cu")
		(net "M_L_CPU0_SB_DQ<6>")
	)
	(gr_poly
		(pts
			(xy 391.604754 -276.71776) (xy 391.504678 -276.617938) (xy 391.404602 -276.71776) (xy 391.404602 -276.765512)
			(xy 391.604754 -276.765512)
		)
		(stroke
			(width 0)
			(type solid)
		)
		(fill yes)
		(layer "In11.Cu")
		(net "M_L_CPU0_SB_DQS_DN<5>")
	)
	(gr_poly
		(pts
			(xy 391.604754 -276.314408) (xy 391.604754 -276.266656) (xy 391.404602 -276.266656) (xy 391.404602 -276.314408)
			(xy 391.504678 -276.41423)
		)
		(stroke
			(width 0)
			(type solid)
		)
		(fill yes)
		(layer "In11.Cu")
		(net "M_L_CPU0_SB_DQS_DN<0>")
	)
	(gr_poly
		(pts
			(xy 391.604754 -275.098002) (xy 391.504678 -274.997926) (xy 391.404602 -275.098002) (xy 391.404602 -275.142452)
			(xy 391.604754 -275.142452)
		)
		(stroke
			(width 0)
			(type solid)
		)
		(fill yes)
		(layer "In11.Cu")
		(net "M_L_CPU0_SB_DQ<1>")
	)
	(gr_poly
		(pts
			(xy 391.604754 -274.694142) (xy 391.604754 -274.649692) (xy 391.404602 -274.649692) (xy 391.404602 -274.694142)
			(xy 391.504678 -274.794218)
		)
		(stroke
			(width 0)
			(type solid)
		)
		(fill yes)
		(layer "In11.Cu")
		(net "M_L_CPU0_SB_DQ<2>")
	)
	(gr_poly
		(pts
			(xy 391.604754 -273.47799) (xy 391.504678 -273.377914) (xy 391.404602 -273.47799) (xy 391.404602 -273.52244)
			(xy 391.604754 -273.52244)
		)
		(stroke
			(width 0)
			(type solid)
		)
		(fill yes)
		(layer "In11.Cu")
		(net "M_L_CPU0_SB_CB<1>")
	)
	(gr_poly
		(pts
			(xy 391.604754 -273.07413) (xy 391.604754 -273.02968) (xy 391.404602 -273.02968) (xy 391.404602 -273.07413)
			(xy 391.504678 -273.174206)
		)
		(stroke
			(width 0)
			(type solid)
		)
		(fill yes)
		(layer "In11.Cu")
		(net "M_L_CPU0_SB_CB<2>")
	)
	(gr_poly
		(pts
			(xy 391.604754 -271.857724) (xy 391.504678 -271.757902) (xy 391.404602 -271.857724) (xy 391.404602 -271.905476)
			(xy 391.604754 -271.905476)
		)
		(stroke
			(width 0)
			(type solid)
		)
		(fill yes)
		(layer "In11.Cu")
		(net "M_L_CPU0_SB_DQS_DN<4>")
	)
	(gr_poly
		(pts
			(xy 391.604754 -271.454372) (xy 391.604754 -271.40662) (xy 391.404602 -271.40662) (xy 391.404602 -271.454372)
			(xy 391.504678 -271.554194)
		)
		(stroke
			(width 0)
			(type solid)
		)
		(fill yes)
		(layer "In11.Cu")
		(net "M_L_CPU0_SB_DQS_DN<9>")
	)
	(gr_poly
		(pts
			(xy 391.604754 -270.237966) (xy 391.504678 -270.13789) (xy 391.404602 -270.237966) (xy 391.404602 -270.282416)
			(xy 391.604754 -270.282416)
		)
		(stroke
			(width 0)
			(type solid)
		)
		(fill yes)
		(layer "In11.Cu")
		(net "M_L_CPU0_SB_CB<5>")
	)
	(gr_poly
		(pts
			(xy 391.604754 -269.834106) (xy 391.604754 -269.789656) (xy 391.404602 -269.789656) (xy 391.404602 -269.834106)
			(xy 391.504678 -269.934182)
		)
		(stroke
			(width 0)
			(type solid)
		)
		(fill yes)
		(layer "In11.Cu")
		(net "M_L_CPU0_SB_CB<6>")
	)
	(gr_poly
		(pts
			(xy 391.604754 -266.997942) (xy 391.504678 -266.897866) (xy 391.404602 -266.997942) (xy 391.404602 -267.042392)
			(xy 391.604754 -267.042392)
		)
		(stroke
			(width 0)
			(type solid)
		)
		(fill yes)
		(layer "In11.Cu")
		(net "M_L_CPU0_SA_RSP<0>")
	)
	(gr_poly
		(pts
			(xy 391.604754 -266.594082) (xy 391.604754 -266.549632) (xy 391.404602 -266.549632) (xy 391.404602 -266.594082)
			(xy 391.504678 -266.694158)
		)
		(stroke
			(width 0)
			(type solid)
		)
		(fill yes)
		(layer "In11.Cu")
		(net "M_L_CPU0_SB_CS_N<1>")
	)
	(gr_poly
		(pts
			(xy 391.604754 -265.37793) (xy 391.504678 -265.277854) (xy 391.404602 -265.37793) (xy 391.404602 -265.42238)
			(xy 391.604754 -265.42238)
		)
		(stroke
			(width 0)
			(type solid)
		)
		(fill yes)
		(layer "In11.Cu")
		(net "M_L_CPU0_SB_PAR")
	)
	(gr_poly
		(pts
			(xy 391.604754 -263.757918) (xy 391.504678 -263.657842) (xy 391.404602 -263.757918) (xy 391.404602 -263.802368)
			(xy 391.604754 -263.802368)
		)
		(stroke
			(width 0)
			(type solid)
		)
		(fill yes)
		(layer "In11.Cu")
		(net "M_L_CPU0_SB_CA<4>")
	)
	(gr_poly
		(pts
			(xy 391.604754 -263.354058) (xy 391.604754 -263.309608) (xy 391.404602 -263.309608) (xy 391.404602 -263.354058)
			(xy 391.504678 -263.454134)
		)
		(stroke
			(width 0)
			(type solid)
		)
		(fill yes)
		(layer "In11.Cu")
		(net "M_L_CPU0_SB_CA<3>")
	)
	(gr_poly
		(pts
			(xy 391.604754 -262.137906) (xy 391.504678 -262.03783) (xy 391.404602 -262.137906) (xy 391.404602 -262.182356)
			(xy 391.604754 -262.182356)
		)
		(stroke
			(width 0)
			(type solid)
		)
		(fill yes)
		(layer "In11.Cu")
		(net "M_L_CPU0_SB_CA<0>")
	)
	(gr_poly
		(pts
			(xy 391.693908 -222.265494) (xy 391.6553 -222.243142) (xy 391.518902 -222.279718) (xy 391.555478 -222.41637)
			(xy 391.593832 -222.438722)
		)
		(stroke
			(width 0)
			(type solid)
		)
		(fill yes)
		(layer "In11.Cu")
		(net "M_L_CPU0_SA_DQ<0>")
	)
	(gr_poly
		(pts
			(xy 391.694162 -223.884744) (xy 391.655808 -223.862392) (xy 391.519156 -223.898968) (xy 391.555732 -224.03562)
			(xy 391.59434 -224.057972)
		)
		(stroke
			(width 0)
			(type solid)
		)
		(fill yes)
		(layer "In11.Cu")
		(net "M_L_CPU0_SA_DQ<1>")
	)
	(gr_poly
		(pts
			(xy 391.696956 -227.126292) (xy 391.655808 -227.10267) (xy 391.519156 -227.139246) (xy 391.555732 -227.275644)
			(xy 391.597134 -227.29952)
		)
		(stroke
			(width 0)
			(type solid)
		)
		(fill yes)
		(layer "In11.Cu")
		(net "M_L_CPU0_SA_DQS_DN<5>")
	)
	(gr_poly
		(pts
			(xy 391.69721 -225.505772) (xy 391.656062 -225.481896) (xy 391.51941 -225.518472) (xy 391.555986 -225.655124)
			(xy 391.597134 -225.679)
		)
		(stroke
			(width 0)
			(type solid)
		)
		(fill yes)
		(layer "In11.Cu")
		(net "M_L_CPU0_SA_DQS_DP<0>")
	)
	(gr_poly
		(pts
			(xy 391.764012 -246.712232) (xy 391.764012 -246.664734) (xy 391.564114 -246.664734) (xy 391.564114 -246.712232)
			(xy 391.66419 -246.812308)
		)
		(stroke
			(width 0)
			(type solid)
		)
		(fill yes)
		(layer "In11.Cu")
		(net "M_L_CPU0_SA_DQS_DN<4>")
	)
	(gr_poly
		(pts
			(xy 391.764012 -241.852196) (xy 391.764012 -241.804698) (xy 391.564114 -241.804698) (xy 391.564114 -241.852196)
			(xy 391.66419 -241.952272)
		)
		(stroke
			(width 0)
			(type solid)
		)
		(fill yes)
		(layer "In11.Cu")
		(net "M_L_CPU0_SA_DQS_DN<3>")
	)
	(gr_poly
		(pts
			(xy 391.764012 -236.99216) (xy 391.764012 -236.944662) (xy 391.564114 -236.944662) (xy 391.564114 -236.99216)
			(xy 391.66419 -237.092236)
		)
		(stroke
			(width 0)
			(type solid)
		)
		(fill yes)
		(layer "In11.Cu")
		(net "M_L_CPU0_SA_DQS_DN<2>")
	)
	(gr_poly
		(pts
			(xy 391.764012 -230.512112) (xy 391.764012 -230.467662) (xy 391.564114 -230.467662) (xy 391.564114 -230.512112)
			(xy 391.66419 -230.612188)
		)
		(stroke
			(width 0)
			(type solid)
		)
		(fill yes)
		(layer "In11.Cu")
		(net "M_L_CPU0_SA_DQ<10>")
	)
	(gr_poly
		(pts
			(xy 391.767568 -254.812292) (xy 391.767568 -254.767842) (xy 391.56767 -254.767842) (xy 391.56767 -254.812292)
			(xy 391.667492 -254.912114)
		)
		(stroke
			(width 0)
			(type solid)
		)
		(fill yes)
		(layer "In11.Cu")
		(net "M_L_CPU0_SA_CA<5>")
	)
	(gr_poly
		(pts
			(xy 391.767568 -253.19228) (xy 391.767568 -253.14783) (xy 391.56767 -253.14783) (xy 391.56767 -253.19228)
			(xy 391.667492 -253.292102)
		)
		(stroke
			(width 0)
			(type solid)
		)
		(fill yes)
		(layer "In11.Cu")
		(net "M_L_CPU0_SA_CA<1>")
	)
	(gr_poly
		(pts
			(xy 391.767568 -248.332244) (xy 391.767568 -248.287794) (xy 391.56767 -248.287794) (xy 391.56767 -248.332244)
			(xy 391.667492 -248.432066)
		)
		(stroke
			(width 0)
			(type solid)
		)
		(fill yes)
		(layer "In11.Cu")
		(net "M_L_CPU0_SA_CB<6>")
	)
	(gr_poly
		(pts
			(xy 391.767568 -245.09222) (xy 391.767568 -245.04777) (xy 391.56767 -245.04777) (xy 391.56767 -245.09222)
			(xy 391.667492 -245.192042)
		)
		(stroke
			(width 0)
			(type solid)
		)
		(fill yes)
		(layer "In11.Cu")
		(net "M_L_CPU0_SA_CB<2>")
	)
	(gr_poly
		(pts
			(xy 391.767568 -243.472208) (xy 391.767568 -243.427758) (xy 391.56767 -243.427758) (xy 391.56767 -243.472208)
			(xy 391.667492 -243.57203)
		)
		(stroke
			(width 0)
			(type solid)
		)
		(fill yes)
		(layer "In11.Cu")
		(net "M_L_CPU0_SA_DQ<30>")
	)
	(gr_poly
		(pts
			(xy 391.767568 -240.232184) (xy 391.767568 -240.187734) (xy 391.56767 -240.187734) (xy 391.56767 -240.232184)
			(xy 391.667492 -240.332006)
		)
		(stroke
			(width 0)
			(type solid)
		)
		(fill yes)
		(layer "In11.Cu")
		(net "M_L_CPU0_SA_DQ<26>")
	)
	(gr_poly
		(pts
			(xy 391.767568 -238.612172) (xy 391.767568 -238.567722) (xy 391.56767 -238.567722) (xy 391.56767 -238.612172)
			(xy 391.667492 -238.711994)
		)
		(stroke
			(width 0)
			(type solid)
		)
		(fill yes)
		(layer "In11.Cu")
		(net "M_L_CPU0_SA_DQ<22>")
	)
	(gr_poly
		(pts
			(xy 391.767568 -235.372148) (xy 391.767568 -235.327698) (xy 391.56767 -235.327698) (xy 391.56767 -235.372148)
			(xy 391.667492 -235.47197)
		)
		(stroke
			(width 0)
			(type solid)
		)
		(fill yes)
		(layer "In11.Cu")
		(net "M_L_CPU0_SA_DQ<18>")
	)
	(gr_poly
		(pts
			(xy 391.767568 -233.752136) (xy 391.767568 -233.707686) (xy 391.56767 -233.707686) (xy 391.56767 -233.752136)
			(xy 391.667492 -233.851958)
		)
		(stroke
			(width 0)
			(type solid)
		)
		(fill yes)
		(layer "In11.Cu")
		(net "M_L_CPU0_SA_DQ<14>")
	)
	(gr_poly
		(pts
			(xy 391.774934 -256.432558) (xy 391.774934 -256.384806) (xy 391.574782 -256.384806) (xy 391.574782 -256.432558)
			(xy 391.674858 -256.53238)
		)
		(stroke
			(width 0)
			(type solid)
		)
		(fill yes)
		(layer "In11.Cu")
		(net "M_L_CPU0_CLK_DN<0>")
	)
	(gr_poly
		(pts
			(xy 391.774934 -251.969524) (xy 391.674858 -251.869702) (xy 391.574782 -251.969524) (xy 391.574782 -252.014228)
			(xy 391.774934 -252.014228)
		)
		(stroke
			(width 0)
			(type solid)
		)
		(fill yes)
		(layer "In11.Cu")
		(net "M_L_CPU0_SA_CS_N<1>")
	)
	(gr_poly
		(pts
			(xy 391.774934 -250.356116) (xy 391.674858 -250.25604) (xy 391.574782 -250.356116) (xy 391.574782 -250.400566)
			(xy 391.774934 -250.400566)
		)
		(stroke
			(width 0)
			(type solid)
		)
		(fill yes)
		(layer "In11.Cu")
		(net "M_L_CPU0_ALERT_R_N")
	)
	(gr_poly
		(pts
			(xy 391.774934 -240.636044) (xy 391.674858 -240.535968) (xy 391.574782 -240.636044) (xy 391.574782 -240.680494)
			(xy 391.774934 -240.680494)
		)
		(stroke
			(width 0)
			(type solid)
		)
		(fill yes)
		(layer "In11.Cu")
		(net "M_L_CPU0_SA_DQ<25>")
	)
	(gr_poly
		(pts
			(xy 391.774934 -232.132378) (xy 391.774934 -232.084626) (xy 391.574782 -232.084626) (xy 391.574782 -232.132378)
			(xy 391.674858 -232.2322)
		)
		(stroke
			(width 0)
			(type solid)
		)
		(fill yes)
		(layer "In11.Cu")
		(net "M_L_CPU0_SA_DQS_DN<1>")
	)
	(gr_poly
		(pts
			(xy 391.78103 -255.216152) (xy 391.680954 -255.116076) (xy 391.580878 -255.216152) (xy 391.580878 -255.260602)
			(xy 391.78103 -255.260602)
		)
		(stroke
			(width 0)
			(type solid)
		)
		(fill yes)
		(layer "In11.Cu")
		(net "M_L_CPU0_SA_CA<6>")
	)
	(gr_poly
		(pts
			(xy 391.78103 -253.59614) (xy 391.680954 -253.496064) (xy 391.580878 -253.59614) (xy 391.580878 -253.64059)
			(xy 391.78103 -253.64059)
		)
		(stroke
			(width 0)
			(type solid)
		)
		(fill yes)
		(layer "In11.Cu")
		(net "M_L_CPU0_SA_CA<2>")
	)
	(gr_poly
		(pts
			(xy 391.78103 -243.876068) (xy 391.680954 -243.775992) (xy 391.580878 -243.876068) (xy 391.580878 -243.920518)
			(xy 391.78103 -243.920518)
		)
		(stroke
			(width 0)
			(type solid)
		)
		(fill yes)
		(layer "In11.Cu")
		(net "M_L_CPU0_SA_DQ<29>")
	)
	(gr_poly
		(pts
			(xy 391.78103 -242.255802) (xy 391.680954 -242.155726) (xy 391.580878 -242.255802) (xy 391.580878 -242.3033)
			(xy 391.78103 -242.3033)
		)
		(stroke
			(width 0)
			(type solid)
		)
		(fill yes)
		(layer "In11.Cu")
		(net "M_L_CPU0_SA_DQS_DN<8>")
	)
	(gr_poly
		(pts
			(xy 391.78103 -239.016032) (xy 391.680954 -238.915956) (xy 391.580878 -239.016032) (xy 391.580878 -239.060482)
			(xy 391.78103 -239.060482)
		)
		(stroke
			(width 0)
			(type solid)
		)
		(fill yes)
		(layer "In11.Cu")
		(net "M_L_CPU0_SA_DQ<21>")
	)
	(gr_poly
		(pts
			(xy 391.78103 -235.776008) (xy 391.680954 -235.675932) (xy 391.580878 -235.776008) (xy 391.580878 -235.820458)
			(xy 391.78103 -235.820458)
		)
		(stroke
			(width 0)
			(type solid)
		)
		(fill yes)
		(layer "In11.Cu")
		(net "M_L_CPU0_SA_DQ<17>")
	)
	(gr_poly
		(pts
			(xy 391.78103 -234.155996) (xy 391.680954 -234.05592) (xy 391.580878 -234.155996) (xy 391.580878 -234.200446)
			(xy 391.78103 -234.200446)
		)
		(stroke
			(width 0)
			(type solid)
		)
		(fill yes)
		(layer "In11.Cu")
		(net "M_L_CPU0_SA_DQ<13>")
	)
	(gr_poly
		(pts
			(xy 391.788904 -248.735596) (xy 391.688828 -248.63552) (xy 391.589006 -248.735596) (xy 391.589006 -248.780046)
			(xy 391.788904 -248.780046)
		)
		(stroke
			(width 0)
			(type solid)
		)
		(fill yes)
		(layer "In11.Cu")
		(net "M_L_CPU0_SA_CB<5>")
	)
	(gr_poly
		(pts
			(xy 391.788904 -247.115584) (xy 391.688828 -247.015508) (xy 391.589006 -247.115584) (xy 391.589006 -247.163082)
			(xy 391.788904 -247.163082)
		)
		(stroke
			(width 0)
			(type solid)
		)
		(fill yes)
		(layer "In11.Cu")
		(net "M_L_CPU0_SA_DQS_DN<9>")
	)
	(gr_poly
		(pts
			(xy 391.788904 -245.495572) (xy 391.688828 -245.395496) (xy 391.589006 -245.495572) (xy 391.589006 -245.540022)
			(xy 391.788904 -245.540022)
		)
		(stroke
			(width 0)
			(type solid)
		)
		(fill yes)
		(layer "In11.Cu")
		(net "M_L_CPU0_SA_CB<1>")
	)
	(gr_poly
		(pts
			(xy 391.788904 -237.395512) (xy 391.688828 -237.295436) (xy 391.589006 -237.395512) (xy 391.589006 -237.44301)
			(xy 391.788904 -237.44301)
		)
		(stroke
			(width 0)
			(type solid)
		)
		(fill yes)
		(layer "In11.Cu")
		(net "M_L_CPU0_SA_DQS_DN<7>")
	)
	(gr_poly
		(pts
			(xy 391.788904 -232.535476) (xy 391.688828 -232.4354) (xy 391.589006 -232.535476) (xy 391.589006 -232.582974)
			(xy 391.788904 -232.582974)
		)
		(stroke
			(width 0)
			(type solid)
		)
		(fill yes)
		(layer "In11.Cu")
		(net "M_L_CPU0_SA_DQS_DN<6>")
	)
	(gr_poly
		(pts
			(xy 391.829798 -224.570036) (xy 391.793222 -224.433384) (xy 391.754614 -224.411286) (xy 391.654538 -224.584514)
			(xy 391.693146 -224.606612)
		)
		(stroke
			(width 0)
			(type solid)
		)
		(fill yes)
		(layer "In11.Cu")
		(net "M_L_CPU0_SA_DQ<3>")
	)
	(gr_poly
		(pts
			(xy 391.83056 -227.809298) (xy 391.793984 -227.6729) (xy 391.752582 -227.649024) (xy 391.65276 -227.822252)
			(xy 391.693908 -227.846128)
		)
		(stroke
			(width 0)
			(type solid)
		)
		(fill yes)
		(layer "In11.Cu")
		(net "M_L_CPU0_SA_DQS_DP<5>")
	)
	(gr_poly
		(pts
			(xy 391.837418 -222.936308) (xy 391.789158 -222.803466) (xy 391.748772 -222.78467) (xy 391.66419 -222.965772)
			(xy 391.704576 -222.984568)
		)
		(stroke
			(width 0)
			(type solid)
		)
		(fill yes)
		(layer "In11.Cu")
		(net "M_L_CPU0_SA_DQ<2>")
	)
	(gr_poly
		(pts
			(xy 391.993882 -293.874698) (xy 391.893806 -293.70147) (xy 391.855452 -293.723822) (xy 391.818622 -293.860474)
			(xy 391.955274 -293.89705)
		)
		(stroke
			(width 0)
			(type solid)
		)
		(fill yes)
		(layer "In11.Cu")
		(net "M_L_CPU0_SB_DQ<31>")
	)
	(gr_poly
		(pts
			(xy 391.993882 -268.877288) (xy 391.955274 -268.854936) (xy 391.818622 -268.891512) (xy 391.855452 -269.028164)
			(xy 391.893806 -269.050516)
		)
		(stroke
			(width 0)
			(type solid)
		)
		(fill yes)
		(layer "In11.Cu")
		(net "M_L_CPU0_SB_CB<4>")
	)
	(gr_poly
		(pts
			(xy 392.063986 -285.62808) (xy 391.964164 -285.528004) (xy 391.864088 -285.62808) (xy 391.864088 -285.675578)
			(xy 392.063986 -285.675578)
		)
		(stroke
			(width 0)
			(type solid)
		)
		(fill yes)
		(layer "In11.Cu")
		(net "M_L_CPU0_SB_DQS_DP<2>")
	)
	(gr_poly
		(pts
			(xy 392.063986 -280.768044) (xy 391.964164 -280.667968) (xy 391.864088 -280.768044) (xy 391.864088 -280.815542)
			(xy 392.063986 -280.815542)
		)
		(stroke
			(width 0)
			(type solid)
		)
		(fill yes)
		(layer "In11.Cu")
		(net "M_L_CPU0_SB_DQS_DP<1>")
	)
	(gr_poly
		(pts
			(xy 392.063986 -275.908008) (xy 391.964164 -275.807932) (xy 391.864088 -275.908008) (xy 391.864088 -275.955506)
			(xy 392.063986 -275.955506)
		)
		(stroke
			(width 0)
			(type solid)
		)
		(fill yes)
		(layer "In11.Cu")
		(net "M_L_CPU0_SB_DQS_DP<0>")
	)
	(gr_poly
		(pts
			(xy 392.063986 -264.561574) (xy 391.96391 -264.461498) (xy 391.863834 -264.561574) (xy 391.863834 -264.606024)
			(xy 392.063986 -264.606024)
		)
		(stroke
			(width 0)
			(type solid)
		)
		(fill yes)
		(layer "In11.Cu")
		(net "M_L_CPU0_SB_CA<6>")
	)
	(gr_poly
		(pts
			(xy 392.067542 -288.86785) (xy 391.967466 -288.768028) (xy 391.867644 -288.86785) (xy 391.867644 -288.9123)
			(xy 392.067542 -288.9123)
		)
		(stroke
			(width 0)
			(type solid)
		)
		(fill yes)
		(layer "In11.Cu")
		(net "M_L_CPU0_SB_DQ<24>")
	)
	(gr_poly
		(pts
			(xy 392.067542 -284.008068) (xy 391.967466 -283.908246) (xy 391.867644 -284.008068) (xy 391.867644 -284.052518)
			(xy 392.067542 -284.052518)
		)
		(stroke
			(width 0)
			(type solid)
		)
		(fill yes)
		(layer "In11.Cu")
		(net "M_L_CPU0_SB_DQ<16>")
	)
	(gr_poly
		(pts
			(xy 392.067542 -282.388056) (xy 391.967466 -282.288234) (xy 391.867644 -282.388056) (xy 391.867644 -282.432506)
			(xy 392.067542 -282.432506)
		)
		(stroke
			(width 0)
			(type solid)
		)
		(fill yes)
		(layer "In11.Cu")
		(net "M_L_CPU0_SB_DQ<12>")
	)
	(gr_poly
		(pts
			(xy 392.067542 -279.148032) (xy 391.967466 -279.04821) (xy 391.867644 -279.148032) (xy 391.867644 -279.192482)
			(xy 392.067542 -279.192482)
		)
		(stroke
			(width 0)
			(type solid)
		)
		(fill yes)
		(layer "In11.Cu")
		(net "M_L_CPU0_SB_DQ<8>")
	)
	(gr_poly
		(pts
			(xy 392.067542 -277.52802) (xy 391.967466 -277.428198) (xy 391.867644 -277.52802) (xy 391.867644 -277.57247)
			(xy 392.067542 -277.57247)
		)
		(stroke
			(width 0)
			(type solid)
		)
		(fill yes)
		(layer "In11.Cu")
		(net "M_L_CPU0_SB_DQ<4>")
	)
	(gr_poly
		(pts
			(xy 392.067542 -274.287996) (xy 391.967466 -274.188174) (xy 391.867644 -274.287996) (xy 391.867644 -274.332446)
			(xy 392.067542 -274.332446)
		)
		(stroke
			(width 0)
			(type solid)
		)
		(fill yes)
		(layer "In11.Cu")
		(net "M_L_CPU0_SB_DQ<0>")
	)
	(gr_poly
		(pts
			(xy 392.067542 -262.947912) (xy 391.967466 -262.84809) (xy 391.867644 -262.947912) (xy 391.867644 -262.992362)
			(xy 392.067542 -262.992362)
		)
		(stroke
			(width 0)
			(type solid)
		)
		(fill yes)
		(layer "In11.Cu")
		(net "M_L_CPU0_SB_CA<2>")
	)
	(gr_poly
		(pts
			(xy 392.068558 -271.047718) (xy 391.968736 -270.947896) (xy 391.86866 -271.047718) (xy 391.86866 -271.09547)
			(xy 392.068558 -271.09547)
		)
		(stroke
			(width 0)
			(type solid)
		)
		(fill yes)
		(layer "In11.Cu")
		(net "M_L_CPU0_SB_DQS_DP<9>")
	)
	(gr_poly
		(pts
			(xy 392.068558 -267.807948) (xy 391.968736 -267.707872) (xy 391.86866 -267.807948) (xy 391.86866 -267.852398)
			(xy 392.068558 -267.852398)
		)
		(stroke
			(width 0)
			(type solid)
		)
		(fill yes)
		(layer "In11.Cu")
		(net "M_L_CPU0_SB_RSP<0>")
	)
	(gr_poly
		(pts
			(xy 392.074908 -288.464244) (xy 392.074908 -288.419794) (xy 391.874756 -288.419794) (xy 391.874756 -288.464244)
			(xy 391.974832 -288.56432)
		)
		(stroke
			(width 0)
			(type solid)
		)
		(fill yes)
		(layer "In11.Cu")
		(net "M_L_CPU0_SB_DQ<23>")
	)
	(gr_poly
		(pts
			(xy 392.074908 -287.247838) (xy 391.974832 -287.148016) (xy 391.874756 -287.247838) (xy 391.874756 -287.292288)
			(xy 392.074908 -287.292288)
		)
		(stroke
			(width 0)
			(type solid)
		)
		(fill yes)
		(layer "In11.Cu")
		(net "M_L_CPU0_SB_DQ<20>")
	)
	(gr_poly
		(pts
			(xy 392.074908 -286.844232) (xy 392.074908 -286.79648) (xy 391.874756 -286.79648) (xy 391.874756 -286.844232)
			(xy 391.974832 -286.944308)
		)
		(stroke
			(width 0)
			(type solid)
		)
		(fill yes)
		(layer "In11.Cu")
		(net "M_L_CPU0_SB_DQS_DP<7>")
	)
	(gr_poly
		(pts
			(xy 392.074908 -281.98445) (xy 392.074908 -281.936698) (xy 391.874756 -281.936698) (xy 391.874756 -281.98445)
			(xy 391.974832 -282.084272)
		)
		(stroke
			(width 0)
			(type solid)
		)
		(fill yes)
		(layer "In11.Cu")
		(net "M_L_CPU0_SB_DQS_DP<6>")
	)
	(gr_poly
		(pts
			(xy 392.074908 -272.667984) (xy 391.974832 -272.567908) (xy 391.874756 -272.667984) (xy 391.874756 -272.712434)
			(xy 392.074908 -272.712434)
		)
		(stroke
			(width 0)
			(type solid)
		)
		(fill yes)
		(layer "In11.Cu")
		(net "M_L_CPU0_SB_CB<0>")
	)
	(gr_poly
		(pts
			(xy 392.074908 -272.264378) (xy 392.074908 -272.216626) (xy 391.874756 -272.216626) (xy 391.874756 -272.264378)
			(xy 391.974832 -272.3642)
		)
		(stroke
			(width 0)
			(type solid)
		)
		(fill yes)
		(layer "In11.Cu")
		(net "M_L_CPU0_SB_DQS_DP<4>")
	)
	(gr_poly
		(pts
			(xy 392.081004 -290.084002) (xy 392.081004 -290.039552) (xy 391.881106 -290.039552) (xy 391.881106 -290.084002)
			(xy 391.980928 -290.184078)
		)
		(stroke
			(width 0)
			(type solid)
		)
		(fill yes)
		(layer "In11.Cu")
		(net "M_L_CPU0_SB_DQ<27>")
	)
	(gr_poly
		(pts
			(xy 392.081004 -280.364184) (xy 392.081004 -280.319734) (xy 391.881106 -280.319734) (xy 391.881106 -280.364184)
			(xy 391.980928 -280.46426)
		)
		(stroke
			(width 0)
			(type solid)
		)
		(fill yes)
		(layer "In11.Cu")
		(net "M_L_CPU0_SB_DQ<11>")
	)
	(gr_poly
		(pts
			(xy 392.081004 -278.744172) (xy 392.081004 -278.699722) (xy 391.881106 -278.699722) (xy 391.881106 -278.744172)
			(xy 391.980928 -278.844248)
		)
		(stroke
			(width 0)
			(type solid)
		)
		(fill yes)
		(layer "In11.Cu")
		(net "M_L_CPU0_SB_DQ<7>")
	)
	(gr_poly
		(pts
			(xy 392.081004 -277.124414) (xy 392.081004 -277.076916) (xy 391.881106 -277.076916) (xy 391.881106 -277.124414)
			(xy 391.980928 -277.22449)
		)
		(stroke
			(width 0)
			(type solid)
		)
		(fill yes)
		(layer "In11.Cu")
		(net "M_L_CPU0_SB_DQS_DP<5>")
	)
	(gr_poly
		(pts
			(xy 392.081004 -275.504148) (xy 392.081004 -275.459698) (xy 391.881106 -275.459698) (xy 391.881106 -275.504148)
			(xy 391.980928 -275.604224)
		)
		(stroke
			(width 0)
			(type solid)
		)
		(fill yes)
		(layer "In11.Cu")
		(net "M_L_CPU0_SB_DQ<3>")
	)
	(gr_poly
		(pts
			(xy 392.081004 -273.884136) (xy 392.081004 -273.839686) (xy 391.881106 -273.839686) (xy 391.881106 -273.884136)
			(xy 391.980928 -273.984212)
		)
		(stroke
			(width 0)
			(type solid)
		)
		(fill yes)
		(layer "In11.Cu")
		(net "M_L_CPU0_SB_CB<3>")
	)
	(gr_poly
		(pts
			(xy 392.081004 -270.644112) (xy 392.081004 -270.599662) (xy 391.881106 -270.599662) (xy 391.881106 -270.644112)
			(xy 391.980928 -270.744188)
		)
		(stroke
			(width 0)
			(type solid)
		)
		(fill yes)
		(layer "In11.Cu")
		(net "M_L_CPU0_SB_CB<7>")
	)
	(gr_poly
		(pts
			(xy 392.088878 -285.224728) (xy 392.088878 -285.180278) (xy 391.88898 -285.180278) (xy 391.88898 -285.224728)
			(xy 391.988802 -285.324804)
		)
		(stroke
			(width 0)
			(type solid)
		)
		(fill yes)
		(layer "In11.Cu")
		(net "M_L_CPU0_SB_DQ<19>")
	)
	(gr_poly
		(pts
			(xy 392.088878 -283.604716) (xy 392.088878 -283.560266) (xy 391.88898 -283.560266) (xy 391.88898 -283.604716)
			(xy 391.988802 -283.704792)
		)
		(stroke
			(width 0)
			(type solid)
		)
		(fill yes)
		(layer "In11.Cu")
		(net "M_L_CPU0_SB_DQ<15>")
	)
	(gr_poly
		(pts
			(xy 392.088878 -265.784584) (xy 392.088878 -265.740134) (xy 391.88898 -265.740134) (xy 391.88898 -265.784584)
			(xy 391.988802 -265.88466)
		)
		(stroke
			(width 0)
			(type solid)
		)
		(fill yes)
		(layer "In11.Cu")
		(net "M_L_CPU0_SB_CS_N<0>")
	)
	(gr_poly
		(pts
			(xy 392.088878 -264.164572) (xy 392.088878 -264.120122) (xy 391.88898 -264.120122) (xy 391.88898 -264.164572)
			(xy 391.988802 -264.264648)
		)
		(stroke
			(width 0)
			(type solid)
		)
		(fill yes)
		(layer "In11.Cu")
		(net "M_L_CPU0_SB_CA<5>")
	)
	(gr_poly
		(pts
			(xy 392.088878 -262.54456) (xy 392.088878 -262.50011) (xy 391.88898 -262.50011) (xy 391.88898 -262.54456)
			(xy 391.988802 -262.644636)
		)
		(stroke
			(width 0)
			(type solid)
		)
		(fill yes)
		(layer "In11.Cu")
		(net "M_L_CPU0_SB_CA<1>")
	)
	(gr_poly
		(pts
			(xy 392.093958 -293.32809) (xy 392.130534 -293.191438) (xy 391.994136 -293.154862) (xy 391.955528 -293.177214)
			(xy 392.055604 -293.350442)
		)
		(stroke
			(width 0)
			(type solid)
		)
		(fill yes)
		(layer "In11.Cu")
		(net "M_L_CPU0_SB_DQ<29>")
	)
	(gr_poly
		(pts
			(xy 392.130534 -269.560548) (xy 392.093958 -269.423896) (xy 392.055604 -269.401544) (xy 391.955528 -269.574772)
			(xy 391.994136 -269.597124)
		)
		(stroke
			(width 0)
			(type solid)
		)
		(fill yes)
		(layer "In11.Cu")
		(net "M_L_CPU0_SB_CB<6>")
	)
	(gr_poly
		(pts
			(xy 392.164316 -223.074738) (xy 392.125962 -223.052386) (xy 391.98931 -223.088962) (xy 392.025886 -223.225614)
			(xy 392.064494 -223.247966)
		)
		(stroke
			(width 0)
			(type solid)
		)
		(fill yes)
		(layer "In11.Cu")
		(net "M_L_CPU0_SA_DQ<1>")
	)
	(gr_poly
		(pts
			(xy 392.16711 -226.316286) (xy 392.125962 -226.292664) (xy 391.98931 -226.32924) (xy 392.025886 -226.465638)
			(xy 392.067288 -226.489514)
		)
		(stroke
			(width 0)
			(type solid)
		)
		(fill yes)
		(layer "In11.Cu")
		(net "M_L_CPU0_SA_DQS_DN<5>")
	)
	(gr_poly
		(pts
			(xy 392.232896 -249.142758) (xy 392.232896 -249.098308) (xy 392.032998 -249.098308) (xy 392.032998 -249.142758)
			(xy 392.133074 -249.242834)
		)
		(stroke
			(width 0)
			(type solid)
		)
		(fill yes)
		(layer "In11.Cu")
		(net "M_L_CPU0_SA_CB<7>")
	)
	(gr_poly
		(pts
			(xy 392.232896 -247.522746) (xy 392.232896 -247.475248) (xy 392.032998 -247.475248) (xy 392.032998 -247.522746)
			(xy 392.133074 -247.622822)
		)
		(stroke
			(width 0)
			(type solid)
		)
		(fill yes)
		(layer "In11.Cu")
		(net "M_L_CPU0_SA_DQS_DP<9>")
	)
	(gr_poly
		(pts
			(xy 392.232896 -245.902734) (xy 392.232896 -245.858284) (xy 392.032998 -245.858284) (xy 392.032998 -245.902734)
			(xy 392.133074 -246.00281)
		)
		(stroke
			(width 0)
			(type solid)
		)
		(fill yes)
		(layer "In11.Cu")
		(net "M_L_CPU0_SA_CB<3>")
	)
	(gr_poly
		(pts
			(xy 392.232896 -237.802674) (xy 392.232896 -237.755176) (xy 392.032998 -237.755176) (xy 392.032998 -237.802674)
			(xy 392.133074 -237.90275)
		)
		(stroke
			(width 0)
			(type solid)
		)
		(fill yes)
		(layer "In11.Cu")
		(net "M_L_CPU0_SA_DQS_DP<7>")
	)
	(gr_poly
		(pts
			(xy 392.232896 -232.942638) (xy 392.232896 -232.89514) (xy 392.032998 -232.89514) (xy 392.032998 -232.942638)
			(xy 392.133074 -233.042714)
		)
		(stroke
			(width 0)
			(type solid)
		)
		(fill yes)
		(layer "In11.Cu")
		(net "M_L_CPU0_SA_DQS_DP<6>")
	)
	(gr_poly
		(pts
			(xy 392.233912 -256.026158) (xy 392.13409 -255.926082) (xy 392.034014 -256.026158) (xy 392.034014 -256.073656)
			(xy 392.233912 -256.073656)
		)
		(stroke
			(width 0)
			(type solid)
		)
		(fill yes)
		(layer "In11.Cu")
		(net "M_L_CPU0_CLK_DP<0>")
	)
	(gr_poly
		(pts
			(xy 392.239246 -255.622298) (xy 392.239246 -255.577848) (xy 392.039094 -255.577848) (xy 392.039094 -255.622298)
			(xy 392.13917 -255.722374)
		)
		(stroke
			(width 0)
			(type solid)
		)
		(fill yes)
		(layer "In11.Cu")
		(net "M_L_CPU0_SA_PAR")
	)
	(gr_poly
		(pts
			(xy 392.239246 -254.002286) (xy 392.239246 -253.957836) (xy 392.039094 -253.957836) (xy 392.039094 -254.002286)
			(xy 392.13917 -254.102362)
		)
		(stroke
			(width 0)
			(type solid)
		)
		(fill yes)
		(layer "In11.Cu")
		(net "M_L_CPU0_SA_CA<3>")
	)
	(gr_poly
		(pts
			(xy 392.239246 -244.282214) (xy 392.239246 -244.237764) (xy 392.039094 -244.237764) (xy 392.039094 -244.282214)
			(xy 392.13917 -244.38229)
		)
		(stroke
			(width 0)
			(type solid)
		)
		(fill yes)
		(layer "In11.Cu")
		(net "M_L_CPU0_SA_DQ<31>")
	)
	(gr_poly
		(pts
			(xy 392.239246 -242.662456) (xy 392.239246 -242.614958) (xy 392.039094 -242.614958) (xy 392.039094 -242.662456)
			(xy 392.13917 -242.762532)
		)
		(stroke
			(width 0)
			(type solid)
		)
		(fill yes)
		(layer "In11.Cu")
		(net "M_L_CPU0_SA_DQS_DP<8>")
	)
	(gr_poly
		(pts
			(xy 392.239246 -239.422178) (xy 392.239246 -239.377728) (xy 392.039094 -239.377728) (xy 392.039094 -239.422178)
			(xy 392.13917 -239.522254)
		)
		(stroke
			(width 0)
			(type solid)
		)
		(fill yes)
		(layer "In11.Cu")
		(net "M_L_CPU0_SA_DQ<23>")
	)
	(gr_poly
		(pts
			(xy 392.239246 -236.182154) (xy 392.239246 -236.137704) (xy 392.039094 -236.137704) (xy 392.039094 -236.182154)
			(xy 392.13917 -236.28223)
		)
		(stroke
			(width 0)
			(type solid)
		)
		(fill yes)
		(layer "In11.Cu")
		(net "M_L_CPU0_SA_DQ<19>")
	)
	(gr_poly
		(pts
			(xy 392.239246 -234.562142) (xy 392.239246 -234.517692) (xy 392.039094 -234.517692) (xy 392.039094 -234.562142)
			(xy 392.13917 -234.662218)
		)
		(stroke
			(width 0)
			(type solid)
		)
		(fill yes)
		(layer "In11.Cu")
		(net "M_L_CPU0_SA_DQ<15>")
	)
	(gr_poly
		(pts
			(xy 392.244834 -250.762262) (xy 392.244834 -250.717812) (xy 392.044682 -250.717812) (xy 392.044682 -250.762262)
			(xy 392.144758 -250.862338)
		)
		(stroke
			(width 0)
			(type solid)
		)
		(fill yes)
		(layer "In11.Cu")
		(net "M_L_CPU0_RESET_N")
	)
	(gr_poly
		(pts
			(xy 392.244834 -241.04219) (xy 392.244834 -240.99774) (xy 392.044682 -240.99774) (xy 392.044682 -241.04219)
			(xy 392.144758 -241.142266)
		)
		(stroke
			(width 0)
			(type solid)
		)
		(fill yes)
		(layer "In11.Cu")
		(net "M_L_CPU0_SA_DQ<27>")
	)
	(gr_poly
		(pts
			(xy 392.245088 -231.725724) (xy 392.145012 -231.625902) (xy 392.044936 -231.725724) (xy 392.044936 -231.773476)
			(xy 392.245088 -231.773476)
		)
		(stroke
			(width 0)
			(type solid)
		)
		(fill yes)
		(layer "In11.Cu")
		(net "M_L_CPU0_SA_DQS_DP<1>")
	)
	(gr_poly
		(pts
			(xy 392.25093 -254.406146) (xy 392.151108 -254.306324) (xy 392.051032 -254.406146) (xy 392.051032 -254.450596)
			(xy 392.25093 -254.450596)
		)
		(stroke
			(width 0)
			(type solid)
		)
		(fill yes)
		(layer "In11.Cu")
		(net "M_L_CPU0_SA_CA<4>")
	)
	(gr_poly
		(pts
			(xy 392.25093 -252.786134) (xy 392.151108 -252.686312) (xy 392.051032 -252.786134) (xy 392.051032 -252.830584)
			(xy 392.25093 -252.830584)
		)
		(stroke
			(width 0)
			(type solid)
		)
		(fill yes)
		(layer "In11.Cu")
		(net "M_L_CPU0_SA_CA<0>")
	)
	(gr_poly
		(pts
			(xy 392.25093 -247.926098) (xy 392.151108 -247.826276) (xy 392.051032 -247.926098) (xy 392.051032 -247.970548)
			(xy 392.25093 -247.970548)
		)
		(stroke
			(width 0)
			(type solid)
		)
		(fill yes)
		(layer "In11.Cu")
		(net "M_L_CPU0_SA_CB<4>")
	)
	(gr_poly
		(pts
			(xy 392.25093 -244.686074) (xy 392.151108 -244.586252) (xy 392.051032 -244.686074) (xy 392.051032 -244.730524)
			(xy 392.25093 -244.730524)
		)
		(stroke
			(width 0)
			(type solid)
		)
		(fill yes)
		(layer "In11.Cu")
		(net "M_L_CPU0_SA_CB<0>")
	)
	(gr_poly
		(pts
			(xy 392.25093 -243.066062) (xy 392.151108 -242.96624) (xy 392.051032 -243.066062) (xy 392.051032 -243.110512)
			(xy 392.25093 -243.110512)
		)
		(stroke
			(width 0)
			(type solid)
		)
		(fill yes)
		(layer "In11.Cu")
		(net "M_L_CPU0_SA_DQ<28>")
	)
	(gr_poly
		(pts
			(xy 392.25093 -239.826038) (xy 392.151108 -239.726216) (xy 392.051032 -239.826038) (xy 392.051032 -239.870488)
			(xy 392.25093 -239.870488)
		)
		(stroke
			(width 0)
			(type solid)
		)
		(fill yes)
		(layer "In11.Cu")
		(net "M_L_CPU0_SA_DQ<24>")
	)
	(gr_poly
		(pts
			(xy 392.25093 -238.206026) (xy 392.151108 -238.106204) (xy 392.051032 -238.206026) (xy 392.051032 -238.250476)
			(xy 392.25093 -238.250476)
		)
		(stroke
			(width 0)
			(type solid)
		)
		(fill yes)
		(layer "In11.Cu")
		(net "M_L_CPU0_SA_DQ<20>")
	)
	(gr_poly
		(pts
			(xy 392.25093 -234.966002) (xy 392.151108 -234.86618) (xy 392.051032 -234.966002) (xy 392.051032 -235.010452)
			(xy 392.25093 -235.010452)
		)
		(stroke
			(width 0)
			(type solid)
		)
		(fill yes)
		(layer "In11.Cu")
		(net "M_L_CPU0_SA_DQ<16>")
	)
	(gr_poly
		(pts
			(xy 392.25093 -233.34599) (xy 392.151108 -233.246168) (xy 392.051032 -233.34599) (xy 392.051032 -233.39044)
			(xy 392.25093 -233.39044)
		)
		(stroke
			(width 0)
			(type solid)
		)
		(fill yes)
		(layer "In11.Cu")
		(net "M_L_CPU0_SA_DQ<12>")
	)
	(gr_poly
		(pts
			(xy 392.254486 -246.306086) (xy 392.15441 -246.20601) (xy 392.054588 -246.306086) (xy 392.054588 -246.353584)
			(xy 392.254486 -246.353584)
		)
		(stroke
			(width 0)
			(type solid)
		)
		(fill yes)
		(layer "In11.Cu")
		(net "M_L_CPU0_SA_DQS_DP<4>")
	)
	(gr_poly
		(pts
			(xy 392.254486 -241.44605) (xy 392.15441 -241.345974) (xy 392.054588 -241.44605) (xy 392.054588 -241.493548)
			(xy 392.254486 -241.493548)
		)
		(stroke
			(width 0)
			(type solid)
		)
		(fill yes)
		(layer "In11.Cu")
		(net "M_L_CPU0_SA_DQS_DP<3>")
	)
	(gr_poly
		(pts
			(xy 392.254486 -236.586014) (xy 392.15441 -236.485938) (xy 392.054588 -236.586014) (xy 392.054588 -236.633512)
			(xy 392.254486 -236.633512)
		)
		(stroke
			(width 0)
			(type solid)
		)
		(fill yes)
		(layer "In11.Cu")
		(net "M_L_CPU0_SA_DQS_DP<2>")
	)
	(gr_poly
		(pts
			(xy 392.257788 -251.159518) (xy 392.157712 -251.059442) (xy 392.05789 -251.159518) (xy 392.05789 -251.203968)
			(xy 392.257788 -251.203968)
		)
		(stroke
			(width 0)
			(type solid)
		)
		(fill yes)
		(layer "In11.Cu")
		(net "M_L_CPU0_SA_CS_N<0>")
	)
	(gr_poly
		(pts
			(xy 392.299698 -222.141542) (xy 392.263122 -222.00489) (xy 392.224514 -221.982538) (xy 392.124438 -222.155766)
			(xy 392.163046 -222.178118)
		)
		(stroke
			(width 0)
			(type solid)
		)
		(fill yes)
		(layer "In11.Cu")
		(net "M_L_CPU0_SA_DQ<2>")
	)
	(gr_poly
		(pts
			(xy 392.300714 -226.999292) (xy 392.264138 -226.862894) (xy 392.222736 -226.839018) (xy 392.122914 -227.012246)
			(xy 392.164062 -227.035868)
		)
		(stroke
			(width 0)
			(type solid)
		)
		(fill yes)
		(layer "In11.Cu")
		(net "M_L_CPU0_SA_DQS_DP<5>")
	)
	(gr_poly
		(pts
			(xy 392.300968 -225.378772) (xy 392.264392 -225.24212) (xy 392.22299 -225.218244) (xy 392.123168 -225.391472)
			(xy 392.164316 -225.415348)
		)
		(stroke
			(width 0)
			(type solid)
		)
		(fill yes)
		(layer "In11.Cu")
		(net "M_L_CPU0_SA_DQS_DN<0>")
	)
	(gr_poly
		(pts
			(xy 392.301222 -223.757998) (xy 392.264392 -223.6216) (xy 392.226038 -223.599248) (xy 392.125962 -223.772476)
			(xy 392.16457 -223.794828)
		)
		(stroke
			(width 0)
			(type solid)
		)
		(fill yes)
		(layer "In11.Cu")
		(net "M_L_CPU0_SA_DQ<3>")
	)
	(gr_poly
		(pts
			(xy 392.463782 -294.684704) (xy 392.363706 -294.511476) (xy 392.325352 -294.533828) (xy 392.288522 -294.67048)
			(xy 392.425174 -294.707056)
		)
		(stroke
			(width 0)
			(type solid)
		)
		(fill yes)
		(layer "In11.Cu")
		(net "M_L_CPU0_SB_DQ<31>")
	)
	(gr_poly
		(pts
			(xy 392.464036 -293.064692) (xy 392.36396 -292.891464) (xy 392.325606 -292.913816) (xy 392.28903 -293.050468)
			(xy 392.425428 -293.087044)
		)
		(stroke
			(width 0)
			(type solid)
		)
		(fill yes)
		(layer "In11.Cu")
		(net "M_L_CPU0_SB_DQ<30>")
	)
	(gr_poly
		(pts
			(xy 392.464036 -269.687294) (xy 392.425428 -269.664942) (xy 392.28903 -269.701518) (xy 392.325606 -269.83817)
			(xy 392.36396 -269.860522)
		)
		(stroke
			(width 0)
			(type solid)
		)
		(fill yes)
		(layer "In11.Cu")
		(net "M_L_CPU0_SB_CB<5>")
	)
	(gr_poly
		(pts
			(xy 392.53287 -284.817566) (xy 392.433048 -284.71749) (xy 392.332972 -284.817566) (xy 392.332972 -284.862016)
			(xy 392.53287 -284.862016)
		)
		(stroke
			(width 0)
			(type solid)
		)
		(fill yes)
		(layer "In11.Cu")
		(net "M_L_CPU0_SB_DQ<17>")
	)
	(gr_poly
		(pts
			(xy 392.53287 -283.197554) (xy 392.433048 -283.097478) (xy 392.332972 -283.197554) (xy 392.332972 -283.242004)
			(xy 392.53287 -283.242004)
		)
		(stroke
			(width 0)
			(type solid)
		)
		(fill yes)
		(layer "In11.Cu")
		(net "M_L_CPU0_SB_DQ<13>")
	)
	(gr_poly
		(pts
			(xy 392.53287 -265.377422) (xy 392.433048 -265.277346) (xy 392.332972 -265.377422) (xy 392.332972 -265.421872)
			(xy 392.53287 -265.421872)
		)
		(stroke
			(width 0)
			(type solid)
		)
		(fill yes)
		(layer "In11.Cu")
		(net "M_L_CPU0_SB_PAR")
	)
	(gr_poly
		(pts
			(xy 392.53287 -263.75741) (xy 392.433048 -263.657334) (xy 392.332972 -263.75741) (xy 392.332972 -263.80186)
			(xy 392.53287 -263.80186)
		)
		(stroke
			(width 0)
			(type solid)
		)
		(fill yes)
		(layer "In11.Cu")
		(net "M_L_CPU0_SB_CA<4>")
	)
	(gr_poly
		(pts
			(xy 392.53287 -262.137398) (xy 392.433048 -262.037322) (xy 392.332972 -262.137398) (xy 392.332972 -262.181848)
			(xy 392.53287 -262.181848)
		)
		(stroke
			(width 0)
			(type solid)
		)
		(fill yes)
		(layer "In11.Cu")
		(net "M_L_CPU0_SB_CA<0>")
	)
	(gr_poly
		(pts
			(xy 392.537442 -273.07413) (xy 392.537442 -273.02968) (xy 392.337544 -273.02968) (xy 392.337544 -273.07413)
			(xy 392.437366 -273.173952)
		)
		(stroke
			(width 0)
			(type solid)
		)
		(fill yes)
		(layer "In11.Cu")
		(net "M_L_CPU0_SB_CB<2>")
	)
	(gr_poly
		(pts
			(xy 392.538458 -271.454118) (xy 392.538458 -271.40662) (xy 392.338306 -271.40662) (xy 392.338306 -271.454118)
			(xy 392.438382 -271.554194)
		)
		(stroke
			(width 0)
			(type solid)
		)
		(fill yes)
		(layer "In11.Cu")
		(net "M_L_CPU0_SB_DQS_DN<9>")
	)
	(gr_poly
		(pts
			(xy 392.538966 -279.958038) (xy 392.439144 -279.857962) (xy 392.339068 -279.958038) (xy 392.339068 -280.002488)
			(xy 392.538966 -280.002488)
		)
		(stroke
			(width 0)
			(type solid)
		)
		(fill yes)
		(layer "In11.Cu")
		(net "M_L_CPU0_SB_DQ<9>")
	)
	(gr_poly
		(pts
			(xy 392.538966 -278.338026) (xy 392.439144 -278.23795) (xy 392.339068 -278.338026) (xy 392.339068 -278.382476)
			(xy 392.538966 -278.382476)
		)
		(stroke
			(width 0)
			(type solid)
		)
		(fill yes)
		(layer "In11.Cu")
		(net "M_L_CPU0_SB_DQ<5>")
	)
	(gr_poly
		(pts
			(xy 392.538966 -276.71776) (xy 392.439144 -276.617684) (xy 392.339068 -276.71776) (xy 392.339068 -276.765258)
			(xy 392.538966 -276.765258)
		)
		(stroke
			(width 0)
			(type solid)
		)
		(fill yes)
		(layer "In11.Cu")
		(net "M_L_CPU0_SB_DQS_DN<5>")
	)
	(gr_poly
		(pts
			(xy 392.538966 -275.098002) (xy 392.439144 -274.997926) (xy 392.339068 -275.098002) (xy 392.339068 -275.142452)
			(xy 392.538966 -275.142452)
		)
		(stroke
			(width 0)
			(type solid)
		)
		(fill yes)
		(layer "In11.Cu")
		(net "M_L_CPU0_SB_DQ<1>")
	)
	(gr_poly
		(pts
			(xy 392.538966 -273.47799) (xy 392.439144 -273.377914) (xy 392.339068 -273.47799) (xy 392.339068 -273.52244)
			(xy 392.538966 -273.52244)
		)
		(stroke
			(width 0)
			(type solid)
		)
		(fill yes)
		(layer "In11.Cu")
		(net "M_L_CPU0_SB_CB<1>")
	)
	(gr_poly
		(pts
			(xy 392.538966 -266.997942) (xy 392.439144 -266.897866) (xy 392.339068 -266.997942) (xy 392.339068 -267.042392)
			(xy 392.538966 -267.042392)
		)
		(stroke
			(width 0)
			(type solid)
		)
		(fill yes)
		(layer "In11.Cu")
		(net "M_L_CPU0_SA_RSP<0>")
	)
	(gr_poly
		(pts
			(xy 392.544808 -271.857724) (xy 392.444732 -271.757902) (xy 392.344656 -271.857724) (xy 392.344656 -271.905476)
			(xy 392.544808 -271.905476)
		)
		(stroke
			(width 0)
			(type solid)
		)
		(fill yes)
		(layer "In11.Cu")
		(net "M_L_CPU0_SB_DQS_DN<4>")
	)
	(gr_poly
		(pts
			(xy 392.544808 -268.617954) (xy 392.444732 -268.517878) (xy 392.344656 -268.617954) (xy 392.344656 -268.662404)
			(xy 392.544808 -268.662404)
		)
		(stroke
			(width 0)
			(type solid)
		)
		(fill yes)
		(layer "In11.Cu")
		(net "M_L_CPU0_SB_CB<4>")
	)
	(gr_poly
		(pts
			(xy 392.550904 -284.414214) (xy 392.550904 -284.369764) (xy 392.351006 -284.369764) (xy 392.351006 -284.414214)
			(xy 392.451082 -284.514036)
		)
		(stroke
			(width 0)
			(type solid)
		)
		(fill yes)
		(layer "In11.Cu")
		(net "M_L_CPU0_SB_DQ<18>")
	)
	(gr_poly
		(pts
			(xy 392.550904 -282.794202) (xy 392.550904 -282.749752) (xy 392.351006 -282.749752) (xy 392.351006 -282.794202)
			(xy 392.451082 -282.894024)
		)
		(stroke
			(width 0)
			(type solid)
		)
		(fill yes)
		(layer "In11.Cu")
		(net "M_L_CPU0_SB_DQ<14>")
	)
	(gr_poly
		(pts
			(xy 392.550904 -279.554178) (xy 392.550904 -279.509728) (xy 392.351006 -279.509728) (xy 392.351006 -279.554178)
			(xy 392.451082 -279.654)
		)
		(stroke
			(width 0)
			(type solid)
		)
		(fill yes)
		(layer "In11.Cu")
		(net "M_L_CPU0_SB_DQ<10>")
	)
	(gr_poly
		(pts
			(xy 392.550904 -277.934166) (xy 392.550904 -277.889716) (xy 392.351006 -277.889716) (xy 392.351006 -277.934166)
			(xy 392.451082 -278.033988)
		)
		(stroke
			(width 0)
			(type solid)
		)
		(fill yes)
		(layer "In11.Cu")
		(net "M_L_CPU0_SB_DQ<6>")
	)
	(gr_poly
		(pts
			(xy 392.550904 -274.694142) (xy 392.550904 -274.649692) (xy 392.351006 -274.649692) (xy 392.351006 -274.694142)
			(xy 392.451082 -274.793964)
		)
		(stroke
			(width 0)
			(type solid)
		)
		(fill yes)
		(layer "In11.Cu")
		(net "M_L_CPU0_SB_DQ<2>")
	)
	(gr_poly
		(pts
			(xy 392.550904 -266.594082) (xy 392.550904 -266.549632) (xy 392.351006 -266.549632) (xy 392.351006 -266.594082)
			(xy 392.451082 -266.693904)
		)
		(stroke
			(width 0)
			(type solid)
		)
		(fill yes)
		(layer "In11.Cu")
		(net "M_L_CPU0_SB_CS_N<1>")
	)
	(gr_poly
		(pts
			(xy 392.550904 -263.354058) (xy 392.550904 -263.309608) (xy 392.351006 -263.309608) (xy 392.351006 -263.354058)
			(xy 392.451082 -263.45388)
		)
		(stroke
			(width 0)
			(type solid)
		)
		(fill yes)
		(layer "In11.Cu")
		(net "M_L_CPU0_SB_CA<3>")
	)
	(gr_poly
		(pts
			(xy 392.55446 -286.034226) (xy 392.55446 -285.986728) (xy 392.354562 -285.986728) (xy 392.354562 -286.034226)
			(xy 392.454384 -286.134302)
		)
		(stroke
			(width 0)
			(type solid)
		)
		(fill yes)
		(layer "In11.Cu")
		(net "M_L_CPU0_SB_DQS_DN<2>")
	)
	(gr_poly
		(pts
			(xy 392.55446 -281.17419) (xy 392.55446 -281.126692) (xy 392.354562 -281.126692) (xy 392.354562 -281.17419)
			(xy 392.454384 -281.274266)
		)
		(stroke
			(width 0)
			(type solid)
		)
		(fill yes)
		(layer "In11.Cu")
		(net "M_L_CPU0_SB_DQS_DN<1>")
	)
	(gr_poly
		(pts
			(xy 392.55446 -276.314154) (xy 392.55446 -276.266656) (xy 392.354562 -276.266656) (xy 392.354562 -276.314154)
			(xy 392.454384 -276.41423)
		)
		(stroke
			(width 0)
			(type solid)
		)
		(fill yes)
		(layer "In11.Cu")
		(net "M_L_CPU0_SB_DQS_DN<0>")
	)
	(gr_poly
		(pts
			(xy 392.563858 -294.138096) (xy 392.600434 -294.001444) (xy 392.464036 -293.964868) (xy 392.425428 -293.98722)
			(xy 392.525504 -294.160448)
		)
		(stroke
			(width 0)
			(type solid)
		)
		(fill yes)
		(layer "In11.Cu")
		(net "M_L_CPU0_SB_DQ<29>")
	)
	(gr_poly
		(pts
			(xy 392.564112 -292.518084) (xy 392.600942 -292.381432) (xy 392.46429 -292.344856) (xy 392.425682 -292.367208)
			(xy 392.525758 -292.540436)
		)
		(stroke
			(width 0)
			(type solid)
		)
		(fill yes)
		(layer "In11.Cu")
		(net "M_L_CPU0_SB_DQ<28>")
	)
	(gr_poly
		(pts
			(xy 392.600942 -270.370554) (xy 392.564112 -270.233902) (xy 392.525758 -270.21155) (xy 392.425682 -270.384778)
			(xy 392.46429 -270.40713)
		)
		(stroke
			(width 0)
			(type solid)
		)
		(fill yes)
		(layer "In11.Cu")
		(net "M_L_CPU0_SB_CB<7>")
	)
	(gr_poly
		(pts
			(xy 392.633962 -222.264732) (xy 392.595608 -222.24238) (xy 392.458956 -222.278956) (xy 392.495532 -222.415608)
			(xy 392.53414 -222.43796)
		)
		(stroke
			(width 0)
			(type solid)
		)
		(fill yes)
		(layer "In11.Cu")
		(net "M_L_CPU0_SA_DQ<1>")
	)
	(gr_poly
		(pts
			(xy 392.636756 -223.886268) (xy 392.595608 -223.862392) (xy 392.458956 -223.899222) (xy 392.495532 -224.03562)
			(xy 392.536934 -224.059496)
		)
		(stroke
			(width 0)
			(type solid)
		)
		(fill yes)
		(layer "In11.Cu")
		(net "M_L_CPU0_SA_DQS_DP<0>")
	)
	(gr_poly
		(pts
			(xy 392.70178 -247.116092) (xy 392.601958 -247.016016) (xy 392.501882 -247.116092) (xy 392.501882 -247.16359)
			(xy 392.70178 -247.16359)
		)
		(stroke
			(width 0)
			(type solid)
		)
		(fill yes)
		(layer "In11.Cu")
		(net "M_L_CPU0_SA_DQS_DN<9>")
	)
	(gr_poly
		(pts
			(xy 392.70178 -237.39602) (xy 392.601958 -237.295944) (xy 392.501882 -237.39602) (xy 392.501882 -237.443518)
			(xy 392.70178 -237.443518)
		)
		(stroke
			(width 0)
			(type solid)
		)
		(fill yes)
		(layer "In11.Cu")
		(net "M_L_CPU0_SA_DQS_DN<7>")
	)
	(gr_poly
		(pts
			(xy 392.70178 -232.535984) (xy 392.601958 -232.435908) (xy 392.501882 -232.535984) (xy 392.501882 -232.583482)
			(xy 392.70178 -232.583482)
		)
		(stroke
			(width 0)
			(type solid)
		)
		(fill yes)
		(layer "In11.Cu")
		(net "M_L_CPU0_SA_DQS_DN<6>")
	)
	(gr_poly
		(pts
			(xy 392.704066 -248.736358) (xy 392.60399 -248.636282) (xy 392.503914 -248.736358) (xy 392.503914 -248.780808)
			(xy 392.704066 -248.780808)
		)
		(stroke
			(width 0)
			(type solid)
		)
		(fill yes)
		(layer "In11.Cu")
		(net "M_L_CPU0_SA_CB<5>")
	)
	(gr_poly
		(pts
			(xy 392.704066 -245.496334) (xy 392.60399 -245.396258) (xy 392.503914 -245.496334) (xy 392.503914 -245.540784)
			(xy 392.704066 -245.540784)
		)
		(stroke
			(width 0)
			(type solid)
		)
		(fill yes)
		(layer "In11.Cu")
		(net "M_L_CPU0_SA_CB<1>")
	)
	(gr_poly
		(pts
			(xy 392.709146 -255.216152) (xy 392.60907 -255.116076) (xy 392.508994 -255.216152) (xy 392.508994 -255.260602)
			(xy 392.709146 -255.260602)
		)
		(stroke
			(width 0)
			(type solid)
		)
		(fill yes)
		(layer "In11.Cu")
		(net "M_L_CPU0_SA_CA<6>")
	)
	(gr_poly
		(pts
			(xy 392.709146 -253.59614) (xy 392.60907 -253.496064) (xy 392.508994 -253.59614) (xy 392.508994 -253.64059)
			(xy 392.709146 -253.64059)
		)
		(stroke
			(width 0)
			(type solid)
		)
		(fill yes)
		(layer "In11.Cu")
		(net "M_L_CPU0_SA_CA<2>")
	)
	(gr_poly
		(pts
			(xy 392.709146 -243.876068) (xy 392.60907 -243.775992) (xy 392.508994 -243.876068) (xy 392.508994 -243.920518)
			(xy 392.709146 -243.920518)
		)
		(stroke
			(width 0)
			(type solid)
		)
		(fill yes)
		(layer "In11.Cu")
		(net "M_L_CPU0_SA_DQ<29>")
	)
	(gr_poly
		(pts
			(xy 392.709146 -242.255802) (xy 392.60907 -242.15598) (xy 392.508994 -242.255802) (xy 392.508994 -242.303554)
			(xy 392.709146 -242.303554)
		)
		(stroke
			(width 0)
			(type solid)
		)
		(fill yes)
		(layer "In11.Cu")
		(net "M_L_CPU0_SA_DQS_DN<8>")
	)
	(gr_poly
		(pts
			(xy 392.709146 -239.016032) (xy 392.60907 -238.915956) (xy 392.508994 -239.016032) (xy 392.508994 -239.060482)
			(xy 392.709146 -239.060482)
		)
		(stroke
			(width 0)
			(type solid)
		)
		(fill yes)
		(layer "In11.Cu")
		(net "M_L_CPU0_SA_DQ<21>")
	)
	(gr_poly
		(pts
			(xy 392.709146 -235.776008) (xy 392.60907 -235.675932) (xy 392.508994 -235.776008) (xy 392.508994 -235.820458)
			(xy 392.709146 -235.820458)
		)
		(stroke
			(width 0)
			(type solid)
		)
		(fill yes)
		(layer "In11.Cu")
		(net "M_L_CPU0_SA_DQ<17>")
	)
	(gr_poly
		(pts
			(xy 392.709146 -234.155996) (xy 392.60907 -234.05592) (xy 392.508994 -234.155996) (xy 392.508994 -234.200446)
			(xy 392.709146 -234.200446)
		)
		(stroke
			(width 0)
			(type solid)
		)
		(fill yes)
		(layer "In11.Cu")
		(net "M_L_CPU0_SA_DQ<13>")
	)
	(gr_poly
		(pts
			(xy 392.709146 -232.132378) (xy 392.709146 -232.084626) (xy 392.508994 -232.084626) (xy 392.508994 -232.132378)
			(xy 392.60907 -232.2322)
		)
		(stroke
			(width 0)
			(type solid)
		)
		(fill yes)
		(layer "In11.Cu")
		(net "M_L_CPU0_SA_DQS_DN<1>")
	)
	(gr_poly
		(pts
			(xy 392.714988 -250.356116) (xy 392.614912 -250.25604) (xy 392.514836 -250.356116) (xy 392.514836 -250.400566)
			(xy 392.714988 -250.400566)
		)
		(stroke
			(width 0)
			(type solid)
		)
		(fill yes)
		(layer "In11.Cu")
		(net "M_L_CPU0_ALERT_R_N")
	)
	(gr_poly
		(pts
			(xy 392.714988 -240.636044) (xy 392.614912 -240.535968) (xy 392.514836 -240.636044) (xy 392.514836 -240.680494)
			(xy 392.714988 -240.680494)
		)
		(stroke
			(width 0)
			(type solid)
		)
		(fill yes)
		(layer "In11.Cu")
		(net "M_L_CPU0_SA_DQ<25>")
	)
	(gr_poly
		(pts
			(xy 392.715242 -251.969778) (xy 392.615166 -251.869702) (xy 392.51509 -251.969778) (xy 392.51509 -252.014228)
			(xy 392.715242 -252.014228)
		)
		(stroke
			(width 0)
			(type solid)
		)
		(fill yes)
		(layer "In11.Cu")
		(net "M_L_CPU0_SA_CS_N<1>")
	)
	(gr_poly
		(pts
			(xy 392.724386 -246.71274) (xy 392.724386 -246.664988) (xy 392.524488 -246.664988) (xy 392.524488 -246.71274)
			(xy 392.62431 -246.812816)
		)
		(stroke
			(width 0)
			(type solid)
		)
		(fill yes)
		(layer "In11.Cu")
		(net "M_L_CPU0_SA_DQS_DN<4>")
	)
	(gr_poly
		(pts
			(xy 392.724386 -241.852704) (xy 392.724386 -241.804952) (xy 392.524488 -241.804952) (xy 392.524488 -241.852704)
			(xy 392.62431 -241.95278)
		)
		(stroke
			(width 0)
			(type solid)
		)
		(fill yes)
		(layer "In11.Cu")
		(net "M_L_CPU0_SA_DQS_DN<3>")
	)
	(gr_poly
		(pts
			(xy 392.724386 -236.992668) (xy 392.724386 -236.944916) (xy 392.524488 -236.944916) (xy 392.524488 -236.992668)
			(xy 392.62431 -237.092744)
		)
		(stroke
			(width 0)
			(type solid)
		)
		(fill yes)
		(layer "In11.Cu")
		(net "M_L_CPU0_SA_DQS_DN<2>")
	)
	(gr_poly
		(pts
			(xy 392.728958 -256.432812) (xy 392.728958 -256.38506) (xy 392.52906 -256.38506) (xy 392.52906 -256.432812)
			(xy 392.628882 -256.532634)
		)
		(stroke
			(width 0)
			(type solid)
		)
		(fill yes)
		(layer "In11.Cu")
		(net "M_L_CPU0_CLK_DN<0>")
	)
	(gr_poly
		(pts
			(xy 392.76909 -222.950786) (xy 392.732514 -222.814134) (xy 392.69416 -222.791782) (xy 392.594084 -222.96501)
			(xy 392.632438 -222.987362)
		)
		(stroke
			(width 0)
			(type solid)
		)
		(fill yes)
		(layer "In11.Cu")
		(net "M_L_CPU0_SA_DQ<3>")
	)
	(gr_poly
		(pts
			(xy 392.770106 -226.190556) (xy 392.733276 -226.054158) (xy 392.692128 -226.030282) (xy 392.592052 -226.20351)
			(xy 392.633454 -226.227386)
		)
		(stroke
			(width 0)
			(type solid)
		)
		(fill yes)
		(layer "In11.Cu")
		(net "M_L_CPU0_SA_DQS_DP<5>")
	)
	(gr_poly
		(pts
			(xy 392.933936 -295.49471) (xy 392.83386 -295.321482) (xy 392.795506 -295.343834) (xy 392.75893 -295.480486)
			(xy 392.895328 -295.517062)
		)
		(stroke
			(width 0)
			(type solid)
		)
		(fill yes)
		(layer "In11.Cu")
		(net "M_L_CPU0_SB_DQ<31>")
	)
	(gr_poly
		(pts
			(xy 392.933936 -293.874698) (xy 392.83386 -293.70147) (xy 392.795506 -293.723822) (xy 392.75893 -293.860474)
			(xy 392.895328 -293.89705)
		)
		(stroke
			(width 0)
			(type solid)
		)
		(fill yes)
		(layer "In11.Cu")
		(net "M_L_CPU0_SB_DQ<30>")
	)
	(gr_poly
		(pts
			(xy 392.93673 -270.498062) (xy 392.895582 -270.47444) (xy 392.75893 -270.511016) (xy 392.795506 -270.647414)
			(xy 392.836908 -270.67129)
		)
		(stroke
			(width 0)
			(type solid)
		)
		(fill yes)
		(layer "In11.Cu")
		(net "M_L_CPU0_SB_DQS_DP<9>")
	)
	(gr_poly
		(pts
			(xy 393.00404 -285.223966) (xy 393.00404 -285.179516) (xy 392.803888 -285.179516) (xy 392.803888 -285.223966)
			(xy 392.903964 -285.324042)
		)
		(stroke
			(width 0)
			(type solid)
		)
		(fill yes)
		(layer "In11.Cu")
		(net "M_L_CPU0_SB_DQ<19>")
	)
	(gr_poly
		(pts
			(xy 393.00404 -283.603954) (xy 393.00404 -283.559504) (xy 392.803888 -283.559504) (xy 392.803888 -283.603954)
			(xy 392.903964 -283.70403)
		)
		(stroke
			(width 0)
			(type solid)
		)
		(fill yes)
		(layer "In11.Cu")
		(net "M_L_CPU0_SB_DQ<15>")
	)
	(gr_poly
		(pts
			(xy 393.00404 -265.783822) (xy 393.00404 -265.739372) (xy 392.803888 -265.739372) (xy 392.803888 -265.783822)
			(xy 392.903964 -265.883898)
		)
		(stroke
			(width 0)
			(type solid)
		)
		(fill yes)
		(layer "In11.Cu")
		(net "M_L_CPU0_SB_CS_N<0>")
	)
	(gr_poly
		(pts
			(xy 393.00404 -264.16381) (xy 393.00404 -264.11936) (xy 392.803888 -264.11936) (xy 392.803888 -264.16381)
			(xy 392.903964 -264.263886)
		)
		(stroke
			(width 0)
			(type solid)
		)
		(fill yes)
		(layer "In11.Cu")
		(net "M_L_CPU0_SB_CA<5>")
	)
	(gr_poly
		(pts
			(xy 393.00404 -262.543798) (xy 393.00404 -262.499348) (xy 392.803888 -262.499348) (xy 392.803888 -262.543798)
			(xy 392.903964 -262.643874)
		)
		(stroke
			(width 0)
			(type solid)
		)
		(fill yes)
		(layer "In11.Cu")
		(net "M_L_CPU0_SB_CA<1>")
	)
	(gr_poly
		(pts
			(xy 393.008866 -267.807948) (xy 392.90879 -267.707872) (xy 392.808714 -267.807948) (xy 392.808714 -267.852398)
			(xy 393.008866 -267.852398)
		)
		(stroke
			(width 0)
			(type solid)
		)
		(fill yes)
		(layer "In11.Cu")
		(net "M_L_CPU0_SB_RSP<0>")
	)
	(gr_poly
		(pts
			(xy 393.009374 -280.364184) (xy 393.009374 -280.319734) (xy 392.809222 -280.319734) (xy 392.809222 -280.364184)
			(xy 392.909298 -280.46426)
		)
		(stroke
			(width 0)
			(type solid)
		)
		(fill yes)
		(layer "In11.Cu")
		(net "M_L_CPU0_SB_DQ<11>")
	)
	(gr_poly
		(pts
			(xy 393.009374 -278.744172) (xy 393.009374 -278.699722) (xy 392.809222 -278.699722) (xy 392.809222 -278.744172)
			(xy 392.909298 -278.844248)
		)
		(stroke
			(width 0)
			(type solid)
		)
		(fill yes)
		(layer "In11.Cu")
		(net "M_L_CPU0_SB_DQ<7>")
	)
	(gr_poly
		(pts
			(xy 393.009374 -277.124414) (xy 393.009374 -277.076662) (xy 392.809222 -277.076662) (xy 392.809222 -277.124414)
			(xy 392.909298 -277.224236)
		)
		(stroke
			(width 0)
			(type solid)
		)
		(fill yes)
		(layer "In11.Cu")
		(net "M_L_CPU0_SB_DQS_DP<5>")
	)
	(gr_poly
		(pts
			(xy 393.009374 -275.504148) (xy 393.009374 -275.459698) (xy 392.809222 -275.459698) (xy 392.809222 -275.504148)
			(xy 392.909298 -275.604224)
		)
		(stroke
			(width 0)
			(type solid)
		)
		(fill yes)
		(layer "In11.Cu")
		(net "M_L_CPU0_SB_DQ<3>")
	)
	(gr_poly
		(pts
			(xy 393.009374 -273.884136) (xy 393.009374 -273.839686) (xy 392.809222 -273.839686) (xy 392.809222 -273.884136)
			(xy 392.909298 -273.984212)
		)
		(stroke
			(width 0)
			(type solid)
		)
		(fill yes)
		(layer "In11.Cu")
		(net "M_L_CPU0_SB_CB<3>")
	)
	(gr_poly
		(pts
			(xy 393.014962 -272.264378) (xy 393.014962 -272.216626) (xy 392.81481 -272.216626) (xy 392.81481 -272.264378)
			(xy 392.914886 -272.3642)
		)
		(stroke
			(width 0)
			(type solid)
		)
		(fill yes)
		(layer "In11.Cu")
		(net "M_L_CPU0_SB_DQS_DP<4>")
	)
	(gr_poly
		(pts
			(xy 393.014962 -269.42796) (xy 392.914886 -269.327884) (xy 392.81481 -269.42796) (xy 392.81481 -269.47241)
			(xy 393.014962 -269.47241)
		)
		(stroke
			(width 0)
			(type solid)
		)
		(fill yes)
		(layer "In11.Cu")
		(net "M_L_CPU0_SB_CB<5>")
	)
	(gr_poly
		(pts
			(xy 393.014962 -269.0241) (xy 393.014962 -268.97965) (xy 392.81481 -268.97965) (xy 392.81481 -269.0241)
			(xy 392.914886 -269.124176)
		)
		(stroke
			(width 0)
			(type solid)
		)
		(fill yes)
		(layer "In11.Cu")
		(net "M_L_CPU0_SB_CB<6>")
	)
	(gr_poly
		(pts
			(xy 393.02436 -285.627572) (xy 392.924284 -285.527496) (xy 392.824462 -285.627572) (xy 392.824462 -285.675324)
			(xy 393.02436 -285.675324)
		)
		(stroke
			(width 0)
			(type solid)
		)
		(fill yes)
		(layer "In11.Cu")
		(net "M_L_CPU0_SB_DQS_DP<2>")
	)
	(gr_poly
		(pts
			(xy 393.02436 -280.767536) (xy 392.924284 -280.66746) (xy 392.824462 -280.767536) (xy 392.824462 -280.815288)
			(xy 393.02436 -280.815288)
		)
		(stroke
			(width 0)
			(type solid)
		)
		(fill yes)
		(layer "In11.Cu")
		(net "M_L_CPU0_SB_DQS_DP<1>")
	)
	(gr_poly
		(pts
			(xy 393.02436 -275.9075) (xy 392.924284 -275.807424) (xy 392.824462 -275.9075) (xy 392.824462 -275.955252)
			(xy 393.02436 -275.955252)
		)
		(stroke
			(width 0)
			(type solid)
		)
		(fill yes)
		(layer "In11.Cu")
		(net "M_L_CPU0_SB_DQS_DP<0>")
	)
	(gr_poly
		(pts
			(xy 393.024614 -264.56132) (xy 392.924538 -264.461244) (xy 392.824462 -264.56132) (xy 392.824462 -264.60577)
			(xy 393.024614 -264.60577)
		)
		(stroke
			(width 0)
			(type solid)
		)
		(fill yes)
		(layer "In11.Cu")
		(net "M_L_CPU0_SB_CA<6>")
	)
	(gr_poly
		(pts
			(xy 393.0269 -272.66773) (xy 392.926824 -272.567908) (xy 392.826748 -272.66773) (xy 392.826748 -272.71218)
			(xy 393.0269 -272.71218)
		)
		(stroke
			(width 0)
			(type solid)
		)
		(fill yes)
		(layer "In11.Cu")
		(net "M_L_CPU0_SB_CB<0>")
	)
	(gr_poly
		(pts
			(xy 393.033758 -294.948102) (xy 393.070334 -294.81145) (xy 392.933936 -294.774874) (xy 392.895328 -294.797226)
			(xy 392.995404 -294.970454)
		)
		(stroke
			(width 0)
			(type solid)
		)
		(fill yes)
		(layer "In11.Cu")
		(net "M_L_CPU0_SB_DQ<29>")
	)
	(gr_poly
		(pts
			(xy 393.034012 -293.32809) (xy 393.070842 -293.191438) (xy 392.93419 -293.154862) (xy 392.895582 -293.177214)
			(xy 392.995658 -293.350442)
		)
		(stroke
			(width 0)
			(type solid)
		)
		(fill yes)
		(layer "In11.Cu")
		(net "M_L_CPU0_SB_DQ<28>")
	)
	(gr_poly
		(pts
			(xy 393.070334 -271.181068) (xy 393.033758 -271.04467) (xy 392.992356 -271.020794) (xy 392.892534 -271.194022)
			(xy 392.933682 -271.217644)
		)
		(stroke
			(width 0)
			(type solid)
		)
		(fill yes)
		(layer "In11.Cu")
		(net "M_L_CPU0_SB_DQS_DN<9>")
	)
	(gr_poly
		(pts
			(xy 393.10691 -224.697036) (xy 393.065762 -224.67316) (xy 392.92911 -224.709736) (xy 392.965686 -224.846388)
			(xy 393.006834 -224.870264)
		)
		(stroke
			(width 0)
			(type solid)
		)
		(fill yes)
		(layer "In11.Cu")
		(net "M_L_CPU0_SA_DQS_DN<5>")
	)
	(gr_poly
		(pts
			(xy 393.107418 -223.0755) (xy 393.06627 -223.051878) (xy 392.929618 -223.088454) (xy 392.966194 -223.225106)
			(xy 393.007342 -223.248728)
		)
		(stroke
			(width 0)
			(type solid)
		)
		(fill yes)
		(layer "In11.Cu")
		(net "M_L_CPU0_SA_DQS_DP<0>")
	)
	(gr_poly
		(pts
			(xy 393.169394 -256.025904) (xy 393.069572 -255.925828) (xy 392.969496 -256.025904) (xy 392.969496 -256.073402)
			(xy 393.169394 -256.073402)
		)
		(stroke
			(width 0)
			(type solid)
		)
		(fill yes)
		(layer "In11.Cu")
		(net "M_L_CPU0_CLK_DP<0>")
	)
	(gr_poly
		(pts
			(xy 393.169394 -241.445796) (xy 393.069572 -241.34572) (xy 392.969496 -241.445796) (xy 392.969496 -241.493294)
			(xy 393.169394 -241.493294)
		)
		(stroke
			(width 0)
			(type solid)
		)
		(fill yes)
		(layer "In11.Cu")
		(net "M_L_CPU0_SA_DQS_DP<3>")
	)
	(gr_poly
		(pts
			(xy 393.17168 -234.965748) (xy 393.071604 -234.865926) (xy 392.971528 -234.965748) (xy 392.971528 -235.010198)
			(xy 393.17168 -235.010198)
		)
		(stroke
			(width 0)
			(type solid)
		)
		(fill yes)
		(layer "In11.Cu")
		(net "M_L_CPU0_SA_DQ<16>")
	)
	(gr_poly
		(pts
			(xy 393.173966 -251.159772) (xy 393.07389 -251.05995) (xy 392.973814 -251.159772) (xy 392.973814 -251.204222)
			(xy 393.173966 -251.204222)
		)
		(stroke
			(width 0)
			(type solid)
		)
		(fill yes)
		(layer "In11.Cu")
		(net "M_L_CPU0_SA_CS_N<0>")
	)
	(gr_poly
		(pts
			(xy 393.184888 -241.04219) (xy 393.184888 -240.99774) (xy 392.984736 -240.99774) (xy 392.984736 -241.04219)
			(xy 393.084812 -241.142266)
		)
		(stroke
			(width 0)
			(type solid)
		)
		(fill yes)
		(layer "In11.Cu")
		(net "M_L_CPU0_SA_DQ<27>")
	)
	(gr_poly
		(pts
			(xy 393.193524 -236.182154) (xy 393.193524 -236.137704) (xy 392.993626 -236.137704) (xy 392.993626 -236.182154)
			(xy 393.093448 -236.28223)
		)
		(stroke
			(width 0)
			(type solid)
		)
		(fill yes)
		(layer "In11.Cu")
		(net "M_L_CPU0_SA_DQ<19>")
	)
	(gr_poly
		(pts
			(xy 393.193524 -234.562142) (xy 393.193524 -234.517692) (xy 392.993626 -234.517692) (xy 392.993626 -234.562142)
			(xy 393.093448 -234.662218)
		)
		(stroke
			(width 0)
			(type solid)
		)
		(fill yes)
		(layer "In11.Cu")
		(net "M_L_CPU0_SA_DQ<15>")
	)
	(gr_poly
		(pts
			(xy 393.206986 -237.802674) (xy 393.206986 -237.755176) (xy 393.006834 -237.755176) (xy 393.006834 -237.802674)
			(xy 393.10691 -237.90275)
		)
		(stroke
			(width 0)
			(type solid)
		)
		(fill yes)
		(layer "In11.Cu")
		(net "M_L_CPU0_SA_DQS_DP<7>")
	)
	(gr_poly
		(pts
			(xy 393.206986 -232.942638) (xy 393.206986 -232.89514) (xy 393.006834 -232.89514) (xy 393.006834 -232.942638)
			(xy 393.10691 -233.042714)
		)
		(stroke
			(width 0)
			(type solid)
		)
		(fill yes)
		(layer "In11.Cu")
		(net "M_L_CPU0_SA_DQS_DP<6>")
	)
	(gr_poly
		(pts
			(xy 393.241784 -225.37801) (xy 393.204954 -225.241612) (xy 393.163806 -225.217736) (xy 393.06373 -225.390964)
			(xy 393.105132 -225.41484)
		)
		(stroke
			(width 0)
			(type solid)
		)
		(fill yes)
		(layer "In11.Cu")
		(net "M_L_CPU0_SA_DQS_DP<5>")
	)
	(gr_poly
		(pts
			(xy 393.403836 -294.684704) (xy 393.30376 -294.511476) (xy 393.265406 -294.533828) (xy 393.22883 -294.67048)
			(xy 393.365228 -294.707056)
		)
		(stroke
			(width 0)
			(type solid)
		)
		(fill yes)
		(layer "In11.Cu")
		(net "M_L_CPU0_SB_DQ<30>")
	)
	(gr_poly
		(pts
			(xy 393.4079 -271.306798) (xy 393.366498 -271.282922) (xy 393.229846 -271.319752) (xy 393.266676 -271.45615)
			(xy 393.307824 -271.480026)
		)
		(stroke
			(width 0)
			(type solid)
		)
		(fill yes)
		(layer "In11.Cu")
		(net "M_L_CPU0_SB_DQS_DN<4>")
	)
	(gr_poly
		(pts
			(xy 393.469368 -276.314408) (xy 393.469368 -276.26691) (xy 393.26947 -276.26691) (xy 393.26947 -276.314408)
			(xy 393.369546 -276.414484)
		)
		(stroke
			(width 0)
			(type solid)
		)
		(fill yes)
		(layer "In11.Cu")
		(net "M_L_CPU0_SB_DQS_DN<0>")
	)
	(gr_poly
		(pts
			(xy 393.471654 -273.074384) (xy 393.471654 -273.029934) (xy 393.271502 -273.029934) (xy 393.271502 -273.074384)
			(xy 393.371578 -273.174206)
		)
		(stroke
			(width 0)
			(type solid)
		)
		(fill yes)
		(layer "In11.Cu")
		(net "M_L_CPU0_SB_CB<2>")
	)
	(gr_poly
		(pts
			(xy 393.503912 -294.138096) (xy 393.540742 -294.001444) (xy 393.40409 -293.964868) (xy 393.365482 -293.98722)
			(xy 393.465558 -294.160448)
		)
		(stroke
			(width 0)
			(type solid)
		)
		(fill yes)
		(layer "In11.Cu")
		(net "M_L_CPU0_SB_DQ<28>")
	)
	(gr_poly
		(pts
			(xy 393.539726 -271.992344) (xy 393.502896 -271.855946) (xy 393.461748 -271.83207) (xy 393.361672 -272.005298)
			(xy 393.403074 -272.029174)
		)
		(stroke
			(width 0)
			(type solid)
		)
		(fill yes)
		(layer "In11.Cu")
		(net "M_L_CPU0_SB_DQS_DP<4>")
	)
	(gr_poly
		(pts
			(xy 393.57681 -223.886268) (xy 393.535662 -223.862392) (xy 393.39901 -223.899222) (xy 393.435586 -224.03562)
			(xy 393.476988 -224.059496)
		)
		(stroke
			(width 0)
			(type solid)
		)
		(fill yes)
		(layer "In11.Cu")
		(net "M_L_CPU0_SA_DQS_DN<5>")
	)
	(gr_poly
		(pts
			(xy 393.655296 -251.969524) (xy 393.55522 -251.869702) (xy 393.455144 -251.969524) (xy 393.455144 -252.014228)
			(xy 393.655296 -252.014228)
		)
		(stroke
			(width 0)
			(type solid)
		)
		(fill yes)
		(layer "In11.Cu")
		(net "M_L_CPU0_SA_CS_N<1>")
	)
	(gr_poly
		(pts
			(xy 393.66063 -235.372148) (xy 393.66063 -235.327698) (xy 393.460732 -235.327698) (xy 393.460732 -235.372148)
			(xy 393.560808 -235.47197)
		)
		(stroke
			(width 0)
			(type solid)
		)
		(fill yes)
		(layer "In11.Cu")
		(net "M_L_CPU0_SA_DQ<18>")
	)
	(gr_poly
		(pts
			(xy 393.8778 -293.875206) (xy 393.777724 -293.701978) (xy 393.736576 -293.725854) (xy 393.699746 -293.862252)
			(xy 393.836398 -293.899082)
		)
		(stroke
			(width 0)
			(type solid)
		)
		(fill yes)
		(layer "In11.Cu")
		(net "M_L_CPU0_SB_DQS_DP<8>")
	)
	(gr_poly
		(pts
			(xy 394.180568 -223.759268) (xy 394.143992 -223.62287) (xy 394.10259 -223.598994) (xy 394.002768 -223.772222)
			(xy 394.043916 -223.795844)
		)
		(stroke
			(width 0)
			(type solid)
		)
		(fill yes)
		(layer "In11.Cu")
		(net "M_L_CPU0_SA_DQS_DP<5>")
	)
	(gr_poly
		(pts
			(xy 394.346684 -294.683942) (xy 394.246862 -294.510714) (xy 394.20546 -294.53459) (xy 394.168884 -294.670988)
			(xy 394.305536 -294.707564)
		)
		(stroke
			(width 0)
			(type solid)
		)
		(fill yes)
		(layer "In11.Cu")
		(net "M_L_CPU0_SB_DQS_DP<8>")
	)
	(gr_poly
		(pts
			(xy 394.443966 -294.137334) (xy 394.480542 -294.000936) (xy 394.34389 -293.96436) (xy 394.302742 -293.987982)
			(xy 394.402564 -294.16121)
		)
		(stroke
			(width 0)
			(type solid)
		)
		(fill yes)
		(layer "In11.Cu")
		(net "M_L_CPU0_SB_DQS_DN<8>")
	)
	(gr_poly
		(pts
			(xy 78.971394 -254.8128) (xy 78.971394 -254.76835) (xy 78.771496 -254.76835) (xy 78.771496 -254.8128)
			(xy 78.871318 -254.912876) (xy 78.871572 -254.912876)
		)
		(stroke
			(width 0)
			(type solid)
		)
		(fill yes)
		(layer "In11.Cu")
		(net "M_F_CPU1_SA_CA<5>")
	)
	(gr_poly
		(pts
			(xy 78.971394 -253.192788) (xy 78.971394 -253.148338) (xy 78.771496 -253.148338) (xy 78.771496 -253.192788)
			(xy 78.871318 -253.292864) (xy 78.871572 -253.292864)
		)
		(stroke
			(width 0)
			(type solid)
		)
		(fill yes)
		(layer "In11.Cu")
		(net "M_F_CPU1_SA_CA<1>")
	)
	(gr_poly
		(pts
			(xy 78.971394 -248.332752) (xy 78.971394 -248.288302) (xy 78.771496 -248.288302) (xy 78.771496 -248.332752)
			(xy 78.871318 -248.432828) (xy 78.871572 -248.432828)
		)
		(stroke
			(width 0)
			(type solid)
		)
		(fill yes)
		(layer "In11.Cu")
		(net "M_F_CPU1_SA_CB<6>")
	)
	(gr_poly
		(pts
			(xy 78.971394 -245.092728) (xy 78.971394 -245.048278) (xy 78.771496 -245.048278) (xy 78.771496 -245.092728)
			(xy 78.871318 -245.192804) (xy 78.871572 -245.192804)
		)
		(stroke
			(width 0)
			(type solid)
		)
		(fill yes)
		(layer "In11.Cu")
		(net "M_F_CPU1_SA_CB<2>")
	)
	(gr_poly
		(pts
			(xy 78.971394 -243.472716) (xy 78.971394 -243.428266) (xy 78.771496 -243.428266) (xy 78.771496 -243.472716)
			(xy 78.871318 -243.572792) (xy 78.871572 -243.572792)
		)
		(stroke
			(width 0)
			(type solid)
		)
		(fill yes)
		(layer "In11.Cu")
		(net "M_F_CPU1_SA_DQ<30>")
	)
	(gr_poly
		(pts
			(xy 78.971394 -240.232692) (xy 78.971394 -240.188242) (xy 78.771496 -240.188242) (xy 78.771496 -240.232692)
			(xy 78.871318 -240.332768) (xy 78.871572 -240.332768)
		)
		(stroke
			(width 0)
			(type solid)
		)
		(fill yes)
		(layer "In11.Cu")
		(net "M_F_CPU1_SA_DQ<26>")
	)
	(gr_poly
		(pts
			(xy 78.971394 -238.61268) (xy 78.971394 -238.56823) (xy 78.771496 -238.56823) (xy 78.771496 -238.61268)
			(xy 78.871318 -238.712756) (xy 78.871572 -238.712756)
		)
		(stroke
			(width 0)
			(type solid)
		)
		(fill yes)
		(layer "In11.Cu")
		(net "M_F_CPU1_SA_DQ<22>")
	)
	(gr_poly
		(pts
			(xy 78.971394 -235.372656) (xy 78.971394 -235.328206) (xy 78.771496 -235.328206) (xy 78.771496 -235.372656)
			(xy 78.871318 -235.472732) (xy 78.871572 -235.472732)
		)
		(stroke
			(width 0)
			(type solid)
		)
		(fill yes)
		(layer "In11.Cu")
		(net "M_F_CPU1_SA_DQ<18>")
	)
	(gr_poly
		(pts
			(xy 78.971394 -233.752644) (xy 78.971394 -233.708194) (xy 78.771496 -233.708194) (xy 78.771496 -233.752644)
			(xy 78.871318 -233.85272) (xy 78.871572 -233.85272)
		)
		(stroke
			(width 0)
			(type solid)
		)
		(fill yes)
		(layer "In11.Cu")
		(net "M_F_CPU1_SA_DQ<14>")
	)
	(gr_poly
		(pts
			(xy 78.991714 -251.572776) (xy 78.991714 -251.528326) (xy 78.791816 -251.528326) (xy 78.791816 -251.572776)
			(xy 78.891638 -251.672852) (xy 78.891892 -251.672852)
		)
		(stroke
			(width 0)
			(type solid)
		)
		(fill yes)
		(layer "In11.Cu")
		(net "M_F_CPU1_SA_CS_N<0>")
	)
	(gr_poly
		(pts
			(xy 79.271368 -288.86785) (xy 79.171546 -288.767774) (xy 79.171292 -288.767774) (xy 79.07147 -288.86785)
			(xy 79.07147 -288.9123) (xy 79.271368 -288.9123)
		)
		(stroke
			(width 0)
			(type solid)
		)
		(fill yes)
		(layer "In11.Cu")
		(net "M_F_CPU1_SB_DQ<24>")
	)
	(gr_poly
		(pts
			(xy 79.271368 -282.388056) (xy 79.171546 -282.28798) (xy 79.171292 -282.28798) (xy 79.07147 -282.388056)
			(xy 79.07147 -282.432506) (xy 79.271368 -282.432506)
		)
		(stroke
			(width 0)
			(type solid)
		)
		(fill yes)
		(layer "In11.Cu")
		(net "M_F_CPU1_SB_DQ<12>")
	)
	(gr_poly
		(pts
			(xy 79.271368 -279.148032) (xy 79.171546 -279.047956) (xy 79.171292 -279.047956) (xy 79.07147 -279.148032)
			(xy 79.07147 -279.192482) (xy 79.271368 -279.192482)
		)
		(stroke
			(width 0)
			(type solid)
		)
		(fill yes)
		(layer "In11.Cu")
		(net "M_F_CPU1_SB_DQ<8>")
	)
	(gr_poly
		(pts
			(xy 79.271368 -277.52802) (xy 79.171546 -277.427944) (xy 79.171292 -277.427944) (xy 79.07147 -277.52802)
			(xy 79.07147 -277.57247) (xy 79.271368 -277.57247)
		)
		(stroke
			(width 0)
			(type solid)
		)
		(fill yes)
		(layer "In11.Cu")
		(net "M_F_CPU1_SB_DQ<4>")
	)
	(gr_poly
		(pts
			(xy 79.271368 -274.287996) (xy 79.171546 -274.18792) (xy 79.171292 -274.18792) (xy 79.07147 -274.287996)
			(xy 79.07147 -274.332446) (xy 79.271368 -274.332446)
		)
		(stroke
			(width 0)
			(type solid)
		)
		(fill yes)
		(layer "In11.Cu")
		(net "M_F_CPU1_SB_DQ<0>")
	)
	(gr_poly
		(pts
			(xy 79.271368 -272.667984) (xy 79.171546 -272.567908) (xy 79.171292 -272.567908) (xy 79.07147 -272.667984)
			(xy 79.07147 -272.712434) (xy 79.271368 -272.712434)
		)
		(stroke
			(width 0)
			(type solid)
		)
		(fill yes)
		(layer "In11.Cu")
		(net "M_F_CPU1_SB_CB<0>")
	)
	(gr_poly
		(pts
			(xy 79.271368 -264.567924) (xy 79.171546 -264.467848) (xy 79.171292 -264.467848) (xy 79.07147 -264.567924)
			(xy 79.07147 -264.612374) (xy 79.271368 -264.612374)
		)
		(stroke
			(width 0)
			(type solid)
		)
		(fill yes)
		(layer "In11.Cu")
		(net "M_F_CPU1_SB_CA<6>")
	)
	(gr_poly
		(pts
			(xy 81.631028 -292.918134) (xy 81.531206 -292.818312) (xy 81.530952 -292.818312) (xy 81.43113 -292.918134)
			(xy 81.43113 -292.962584) (xy 81.631028 -292.962584)
		)
		(stroke
			(width 0)
			(type solid)
		)
		(fill yes)
		(layer "In11.Cu")
		(net "M_F_CPU1_SB_DQ<29>")
	)
	(gr_poly
		(pts
			(xy 143.889222 -226.191064) (xy 143.889476 -226.191064) (xy 143.852646 -226.054412) (xy 143.811498 -226.030536)
			(xy 143.711422 -226.203764) (xy 143.752824 -226.22764)
		)
		(stroke
			(width 0)
			(type solid)
		)
		(fill yes)
		(layer "In11.Cu")
		(net "M_L_CPU1_SA_DQS_DN<0>")
	)
	(gr_poly
		(pts
			(xy 144.227296 -224.69602) (xy 144.185894 -224.672144) (xy 144.049496 -224.70872) (xy 144.049242 -224.70872)
			(xy 144.086072 -224.845372) (xy 144.12722 -224.869248)
		)
		(stroke
			(width 0)
			(type solid)
		)
		(fill yes)
		(layer "In11.Cu")
		(net "M_L_CPU1_SA_DQS_DP<0>")
	)
	(gr_poly
		(pts
			(xy 144.697958 -225.505264) (xy 144.656556 -225.481388) (xy 144.520158 -225.517964) (xy 144.519904 -225.517964)
			(xy 144.556734 -225.654616) (xy 144.597882 -225.678492)
		)
		(stroke
			(width 0)
			(type solid)
		)
		(fill yes)
		(layer "In11.Cu")
		(net "M_L_CPU1_SA_DQS_DN<5>")
	)
	(gr_poly
		(pts
			(xy 144.784318 -254.8128) (xy 144.784318 -254.76835) (xy 144.58442 -254.76835) (xy 144.58442 -254.8128)
			(xy 144.684242 -254.912876) (xy 144.684496 -254.912876)
		)
		(stroke
			(width 0)
			(type solid)
		)
		(fill yes)
		(layer "In11.Cu")
		(net "M_L_CPU1_SA_CA<5>")
	)
	(gr_poly
		(pts
			(xy 144.784318 -253.192788) (xy 144.784318 -253.148338) (xy 144.58442 -253.148338) (xy 144.58442 -253.192788)
			(xy 144.684242 -253.292864) (xy 144.684496 -253.292864)
		)
		(stroke
			(width 0)
			(type solid)
		)
		(fill yes)
		(layer "In11.Cu")
		(net "M_L_CPU1_SA_CA<1>")
	)
	(gr_poly
		(pts
			(xy 144.784318 -248.332752) (xy 144.784318 -248.288302) (xy 144.58442 -248.288302) (xy 144.58442 -248.332752)
			(xy 144.684242 -248.432828) (xy 144.684496 -248.432828)
		)
		(stroke
			(width 0)
			(type solid)
		)
		(fill yes)
		(layer "In11.Cu")
		(net "M_L_CPU1_SA_CB<6>")
	)
	(gr_poly
		(pts
			(xy 144.784318 -245.092728) (xy 144.784318 -245.048278) (xy 144.58442 -245.048278) (xy 144.58442 -245.092728)
			(xy 144.684242 -245.192804) (xy 144.684496 -245.192804)
		)
		(stroke
			(width 0)
			(type solid)
		)
		(fill yes)
		(layer "In11.Cu")
		(net "M_L_CPU1_SA_CB<2>")
	)
	(gr_poly
		(pts
			(xy 144.784318 -243.472716) (xy 144.784318 -243.428266) (xy 144.58442 -243.428266) (xy 144.58442 -243.472716)
			(xy 144.684242 -243.572792) (xy 144.684496 -243.572792)
		)
		(stroke
			(width 0)
			(type solid)
		)
		(fill yes)
		(layer "In11.Cu")
		(net "M_L_CPU1_SA_DQ<30>")
	)
	(gr_poly
		(pts
			(xy 144.784318 -240.232692) (xy 144.784318 -240.188242) (xy 144.58442 -240.188242) (xy 144.58442 -240.232692)
			(xy 144.684242 -240.332768) (xy 144.684496 -240.332768)
		)
		(stroke
			(width 0)
			(type solid)
		)
		(fill yes)
		(layer "In11.Cu")
		(net "M_L_CPU1_SA_DQ<26>")
	)
	(gr_poly
		(pts
			(xy 144.784318 -238.61268) (xy 144.784318 -238.56823) (xy 144.58442 -238.56823) (xy 144.58442 -238.61268)
			(xy 144.684242 -238.712756) (xy 144.684496 -238.712756)
		)
		(stroke
			(width 0)
			(type solid)
		)
		(fill yes)
		(layer "In11.Cu")
		(net "M_L_CPU1_SA_DQ<22>")
	)
	(gr_poly
		(pts
			(xy 144.784318 -235.372656) (xy 144.784318 -235.328206) (xy 144.58442 -235.328206) (xy 144.58442 -235.372656)
			(xy 144.684242 -235.472732) (xy 144.684496 -235.472732)
		)
		(stroke
			(width 0)
			(type solid)
		)
		(fill yes)
		(layer "In11.Cu")
		(net "M_L_CPU1_SA_DQ<18>")
	)
	(gr_poly
		(pts
			(xy 144.784318 -233.752644) (xy 144.784318 -233.708194) (xy 144.58442 -233.708194) (xy 144.58442 -233.752644)
			(xy 144.684242 -233.85272) (xy 144.684496 -233.85272)
		)
		(stroke
			(width 0)
			(type solid)
		)
		(fill yes)
		(layer "In11.Cu")
		(net "M_L_CPU1_SA_DQ<14>")
	)
	(gr_poly
		(pts
			(xy 144.829784 -224.57029) (xy 144.830038 -224.57029) (xy 144.793208 -224.433638) (xy 144.75206 -224.409762)
			(xy 144.651984 -224.58299) (xy 144.693386 -224.606866)
		)
		(stroke
			(width 0)
			(type solid)
		)
		(fill yes)
		(layer "In11.Cu")
		(net "M_L_CPU1_SA_DQS_DN<0>")
	)
	(gr_poly
		(pts
			(xy 145.084292 -284.008068) (xy 144.98447 -283.907992) (xy 144.984216 -283.907992) (xy 144.884394 -284.008068)
			(xy 144.884394 -284.052518) (xy 145.084292 -284.052518)
		)
		(stroke
			(width 0)
			(type solid)
		)
		(fill yes)
		(layer "In11.Cu")
		(net "M_L_CPU1_SB_DQ<16>")
	)
	(gr_poly
		(pts
			(xy 145.084292 -282.388056) (xy 144.98447 -282.28798) (xy 144.984216 -282.28798) (xy 144.884394 -282.388056)
			(xy 144.884394 -282.432506) (xy 145.084292 -282.432506)
		)
		(stroke
			(width 0)
			(type solid)
		)
		(fill yes)
		(layer "In11.Cu")
		(net "M_L_CPU1_SB_DQ<12>")
	)
	(gr_poly
		(pts
			(xy 145.084292 -279.148032) (xy 144.98447 -279.047956) (xy 144.984216 -279.047956) (xy 144.884394 -279.148032)
			(xy 144.884394 -279.192482) (xy 145.084292 -279.192482)
		)
		(stroke
			(width 0)
			(type solid)
		)
		(fill yes)
		(layer "In11.Cu")
		(net "M_L_CPU1_SB_DQ<8>")
	)
	(gr_poly
		(pts
			(xy 145.084292 -277.52802) (xy 144.98447 -277.427944) (xy 144.984216 -277.427944) (xy 144.884394 -277.52802)
			(xy 144.884394 -277.57247) (xy 145.084292 -277.57247)
		)
		(stroke
			(width 0)
			(type solid)
		)
		(fill yes)
		(layer "In11.Cu")
		(net "M_L_CPU1_SB_DQ<4>")
	)
	(gr_poly
		(pts
			(xy 145.084292 -274.287996) (xy 144.98447 -274.18792) (xy 144.984216 -274.18792) (xy 144.884394 -274.287996)
			(xy 144.884394 -274.332446) (xy 145.084292 -274.332446)
		)
		(stroke
			(width 0)
			(type solid)
		)
		(fill yes)
		(layer "In11.Cu")
		(net "M_L_CPU1_SB_DQ<0>")
	)
	(gr_poly
		(pts
			(xy 145.084292 -262.947912) (xy 144.98447 -262.847836) (xy 144.984216 -262.847836) (xy 144.884394 -262.947912)
			(xy 144.884394 -262.992362) (xy 145.084292 -262.992362)
		)
		(stroke
			(width 0)
			(type solid)
		)
		(fill yes)
		(layer "In11.Cu")
		(net "M_L_CPU1_SB_CA<2>")
	)
	(gr_poly
		(pts
			(xy 145.29943 -223.760792) (xy 145.299684 -223.760792) (xy 145.262854 -223.624394) (xy 145.221706 -223.600518)
			(xy 145.12163 -223.773746) (xy 145.163032 -223.797622)
		)
		(stroke
			(width 0)
			(type solid)
		)
		(fill yes)
		(layer "In11.Cu")
		(net "M_L_CPU1_SA_DQS_DN<0>")
	)
	(gr_poly
		(pts
			(xy 145.770092 -224.57029) (xy 145.770346 -224.57029) (xy 145.733516 -224.433638) (xy 145.692368 -224.409762)
			(xy 145.592292 -224.58299) (xy 145.633694 -224.606866)
		)
		(stroke
			(width 0)
			(type solid)
		)
		(fill yes)
		(layer "In11.Cu")
		(net "M_L_CPU1_SA_DQS_DP<5>")
	)
	(gr_poly
		(pts
			(xy 326.911462 -254.812546) (xy 326.911462 -254.768096) (xy 326.711564 -254.768096) (xy 326.711564 -254.812546)
			(xy 326.811386 -254.912622) (xy 326.81164 -254.912622)
		)
		(stroke
			(width 0)
			(type solid)
		)
		(fill yes)
		(layer "In11.Cu")
		(net "M_F_CPU0_SA_CA<5>")
	)
	(gr_poly
		(pts
			(xy 326.911462 -253.192534) (xy 326.911462 -253.148084) (xy 326.711564 -253.148084) (xy 326.711564 -253.192534)
			(xy 326.811386 -253.29261) (xy 326.81164 -253.29261)
		)
		(stroke
			(width 0)
			(type solid)
		)
		(fill yes)
		(layer "In11.Cu")
		(net "M_F_CPU0_SA_CA<1>")
	)
	(gr_poly
		(pts
			(xy 326.911462 -248.332498) (xy 326.911462 -248.288048) (xy 326.711564 -248.288048) (xy 326.711564 -248.332498)
			(xy 326.811386 -248.432574) (xy 326.81164 -248.432574)
		)
		(stroke
			(width 0)
			(type solid)
		)
		(fill yes)
		(layer "In11.Cu")
		(net "M_F_CPU0_SA_CB<6>")
	)
	(gr_poly
		(pts
			(xy 326.911462 -245.092474) (xy 326.911462 -245.048024) (xy 326.711564 -245.048024) (xy 326.711564 -245.092474)
			(xy 326.811386 -245.19255) (xy 326.81164 -245.19255)
		)
		(stroke
			(width 0)
			(type solid)
		)
		(fill yes)
		(layer "In11.Cu")
		(net "M_F_CPU0_SA_CB<2>")
	)
	(gr_poly
		(pts
			(xy 326.911462 -243.472462) (xy 326.911462 -243.428012) (xy 326.711564 -243.428012) (xy 326.711564 -243.472462)
			(xy 326.811386 -243.572538) (xy 326.81164 -243.572538)
		)
		(stroke
			(width 0)
			(type solid)
		)
		(fill yes)
		(layer "In11.Cu")
		(net "M_F_CPU0_SA_DQ<30>")
	)
	(gr_poly
		(pts
			(xy 326.911462 -240.232438) (xy 326.911462 -240.187988) (xy 326.711564 -240.187988) (xy 326.711564 -240.232438)
			(xy 326.811386 -240.332514) (xy 326.81164 -240.332514)
		)
		(stroke
			(width 0)
			(type solid)
		)
		(fill yes)
		(layer "In11.Cu")
		(net "M_F_CPU0_SA_DQ<26>")
	)
	(gr_poly
		(pts
			(xy 326.911462 -238.612426) (xy 326.911462 -238.567976) (xy 326.711564 -238.567976) (xy 326.711564 -238.612426)
			(xy 326.811386 -238.712502) (xy 326.81164 -238.712502)
		)
		(stroke
			(width 0)
			(type solid)
		)
		(fill yes)
		(layer "In11.Cu")
		(net "M_F_CPU0_SA_DQ<22>")
	)
	(gr_poly
		(pts
			(xy 326.911462 -235.372402) (xy 326.911462 -235.327952) (xy 326.711564 -235.327952) (xy 326.711564 -235.372402)
			(xy 326.811386 -235.472478) (xy 326.81164 -235.472478)
		)
		(stroke
			(width 0)
			(type solid)
		)
		(fill yes)
		(layer "In11.Cu")
		(net "M_F_CPU0_SA_DQ<18>")
	)
	(gr_poly
		(pts
			(xy 326.911462 -233.75239) (xy 326.911462 -233.70794) (xy 326.711564 -233.70794) (xy 326.711564 -233.75239)
			(xy 326.811386 -233.852466) (xy 326.81164 -233.852466)
		)
		(stroke
			(width 0)
			(type solid)
		)
		(fill yes)
		(layer "In11.Cu")
		(net "M_F_CPU0_SA_DQ<14>")
	)
	(gr_poly
		(pts
			(xy 326.931782 -251.572522) (xy 326.931782 -251.528072) (xy 326.731884 -251.528072) (xy 326.731884 -251.572522)
			(xy 326.831706 -251.672598) (xy 326.83196 -251.672598)
		)
		(stroke
			(width 0)
			(type solid)
		)
		(fill yes)
		(layer "In11.Cu")
		(net "M_F_CPU0_SA_CS_N<0>")
	)
	(gr_poly
		(pts
			(xy 327.211436 -288.867596) (xy 327.111614 -288.76752) (xy 327.11136 -288.76752) (xy 327.011538 -288.867596)
			(xy 327.011538 -288.912046) (xy 327.211436 -288.912046)
		)
		(stroke
			(width 0)
			(type solid)
		)
		(fill yes)
		(layer "In11.Cu")
		(net "M_F_CPU0_SB_DQ<24>")
	)
	(gr_poly
		(pts
			(xy 327.211436 -282.387802) (xy 327.111614 -282.287726) (xy 327.11136 -282.287726) (xy 327.011538 -282.387802)
			(xy 327.011538 -282.432252) (xy 327.211436 -282.432252)
		)
		(stroke
			(width 0)
			(type solid)
		)
		(fill yes)
		(layer "In11.Cu")
		(net "M_F_CPU0_SB_DQ<12>")
	)
	(gr_poly
		(pts
			(xy 327.211436 -279.147778) (xy 327.111614 -279.047702) (xy 327.11136 -279.047702) (xy 327.011538 -279.147778)
			(xy 327.011538 -279.192228) (xy 327.211436 -279.192228)
		)
		(stroke
			(width 0)
			(type solid)
		)
		(fill yes)
		(layer "In11.Cu")
		(net "M_F_CPU0_SB_DQ<8>")
	)
	(gr_poly
		(pts
			(xy 327.211436 -277.527766) (xy 327.111614 -277.42769) (xy 327.11136 -277.42769) (xy 327.011538 -277.527766)
			(xy 327.011538 -277.572216) (xy 327.211436 -277.572216)
		)
		(stroke
			(width 0)
			(type solid)
		)
		(fill yes)
		(layer "In11.Cu")
		(net "M_F_CPU0_SB_DQ<4>")
	)
	(gr_poly
		(pts
			(xy 327.211436 -274.287742) (xy 327.111614 -274.187666) (xy 327.11136 -274.187666) (xy 327.011538 -274.287742)
			(xy 327.011538 -274.332192) (xy 327.211436 -274.332192)
		)
		(stroke
			(width 0)
			(type solid)
		)
		(fill yes)
		(layer "In11.Cu")
		(net "M_F_CPU0_SB_DQ<0>")
	)
	(gr_poly
		(pts
			(xy 327.211436 -272.66773) (xy 327.111614 -272.567654) (xy 327.11136 -272.567654) (xy 327.011538 -272.66773)
			(xy 327.011538 -272.71218) (xy 327.211436 -272.71218)
		)
		(stroke
			(width 0)
			(type solid)
		)
		(fill yes)
		(layer "In11.Cu")
		(net "M_F_CPU0_SB_CB<0>")
	)
	(gr_poly
		(pts
			(xy 327.211436 -264.56767) (xy 327.111614 -264.467594) (xy 327.11136 -264.467594) (xy 327.011538 -264.56767)
			(xy 327.011538 -264.61212) (xy 327.211436 -264.61212)
		)
		(stroke
			(width 0)
			(type solid)
		)
		(fill yes)
		(layer "In11.Cu")
		(net "M_F_CPU0_SB_CA<6>")
	)
	(gr_poly
		(pts
			(xy 329.571096 -292.91788) (xy 329.471274 -292.818058) (xy 329.47102 -292.818058) (xy 329.371198 -292.91788)
			(xy 329.371198 -292.96233) (xy 329.571096 -292.96233)
		)
		(stroke
			(width 0)
			(type solid)
		)
		(fill yes)
		(layer "In11.Cu")
		(net "M_F_CPU0_SB_DQ<29>")
	)
	(gr_poly
		(pts
			(xy 391.82929 -226.190556) (xy 391.829544 -226.190556) (xy 391.792714 -226.054158) (xy 391.751566 -226.030282)
			(xy 391.65149 -226.20351) (xy 391.692892 -226.227386)
		)
		(stroke
			(width 0)
			(type solid)
		)
		(fill yes)
		(layer "In11.Cu")
		(net "M_L_CPU0_SA_DQS_DN<0>")
	)
	(gr_poly
		(pts
			(xy 392.167364 -224.695766) (xy 392.125962 -224.67189) (xy 391.989564 -224.708466) (xy 391.98931 -224.708466)
			(xy 392.02614 -224.845118) (xy 392.067288 -224.868994)
		)
		(stroke
			(width 0)
			(type solid)
		)
		(fill yes)
		(layer "In11.Cu")
		(net "M_L_CPU0_SA_DQS_DP<0>")
	)
	(gr_poly
		(pts
			(xy 392.638026 -225.50501) (xy 392.596624 -225.481134) (xy 392.460226 -225.517964) (xy 392.459972 -225.517964)
			(xy 392.496802 -225.654362) (xy 392.53795 -225.678238)
		)
		(stroke
			(width 0)
			(type solid)
		)
		(fill yes)
		(layer "In11.Cu")
		(net "M_L_CPU0_SA_DQS_DN<5>")
	)
	(gr_poly
		(pts
			(xy 392.724386 -254.812546) (xy 392.724386 -254.768096) (xy 392.524488 -254.768096) (xy 392.524488 -254.812546)
			(xy 392.62431 -254.912622) (xy 392.624564 -254.912622)
		)
		(stroke
			(width 0)
			(type solid)
		)
		(fill yes)
		(layer "In11.Cu")
		(net "M_L_CPU0_SA_CA<5>")
	)
	(gr_poly
		(pts
			(xy 392.724386 -253.192534) (xy 392.724386 -253.148084) (xy 392.524488 -253.148084) (xy 392.524488 -253.192534)
			(xy 392.62431 -253.29261) (xy 392.624564 -253.29261)
		)
		(stroke
			(width 0)
			(type solid)
		)
		(fill yes)
		(layer "In11.Cu")
		(net "M_L_CPU0_SA_CA<1>")
	)
	(gr_poly
		(pts
			(xy 392.724386 -248.332498) (xy 392.724386 -248.288048) (xy 392.524488 -248.288048) (xy 392.524488 -248.332498)
			(xy 392.62431 -248.432574) (xy 392.624564 -248.432574)
		)
		(stroke
			(width 0)
			(type solid)
		)
		(fill yes)
		(layer "In11.Cu")
		(net "M_L_CPU0_SA_CB<6>")
	)
	(gr_poly
		(pts
			(xy 392.724386 -245.092474) (xy 392.724386 -245.048024) (xy 392.524488 -245.048024) (xy 392.524488 -245.092474)
			(xy 392.62431 -245.19255) (xy 392.624564 -245.19255)
		)
		(stroke
			(width 0)
			(type solid)
		)
		(fill yes)
		(layer "In11.Cu")
		(net "M_L_CPU0_SA_CB<2>")
	)
	(gr_poly
		(pts
			(xy 392.724386 -243.472462) (xy 392.724386 -243.428012) (xy 392.524488 -243.428012) (xy 392.524488 -243.472462)
			(xy 392.62431 -243.572538) (xy 392.624564 -243.572538)
		)
		(stroke
			(width 0)
			(type solid)
		)
		(fill yes)
		(layer "In11.Cu")
		(net "M_L_CPU0_SA_DQ<30>")
	)
	(gr_poly
		(pts
			(xy 392.724386 -240.232438) (xy 392.724386 -240.187988) (xy 392.524488 -240.187988) (xy 392.524488 -240.232438)
			(xy 392.62431 -240.332514) (xy 392.624564 -240.332514)
		)
		(stroke
			(width 0)
			(type solid)
		)
		(fill yes)
		(layer "In11.Cu")
		(net "M_L_CPU0_SA_DQ<26>")
	)
	(gr_poly
		(pts
			(xy 392.724386 -238.612426) (xy 392.724386 -238.567976) (xy 392.524488 -238.567976) (xy 392.524488 -238.612426)
			(xy 392.62431 -238.712502) (xy 392.624564 -238.712502)
		)
		(stroke
			(width 0)
			(type solid)
		)
		(fill yes)
		(layer "In11.Cu")
		(net "M_L_CPU0_SA_DQ<22>")
	)
	(gr_poly
		(pts
			(xy 392.724386 -235.372402) (xy 392.724386 -235.327952) (xy 392.524488 -235.327952) (xy 392.524488 -235.372402)
			(xy 392.62431 -235.472478) (xy 392.624564 -235.472478)
		)
		(stroke
			(width 0)
			(type solid)
		)
		(fill yes)
		(layer "In11.Cu")
		(net "M_L_CPU0_SA_DQ<18>")
	)
	(gr_poly
		(pts
			(xy 392.724386 -233.75239) (xy 392.724386 -233.70794) (xy 392.524488 -233.70794) (xy 392.524488 -233.75239)
			(xy 392.62431 -233.852466) (xy 392.624564 -233.852466)
		)
		(stroke
			(width 0)
			(type solid)
		)
		(fill yes)
		(layer "In11.Cu")
		(net "M_L_CPU0_SA_DQ<14>")
	)
	(gr_poly
		(pts
			(xy 392.769852 -224.570036) (xy 392.770106 -224.570036) (xy 392.733276 -224.433384) (xy 392.692128 -224.409508)
			(xy 392.592052 -224.582736) (xy 392.633454 -224.606612)
		)
		(stroke
			(width 0)
			(type solid)
		)
		(fill yes)
		(layer "In11.Cu")
		(net "M_L_CPU0_SA_DQS_DN<0>")
	)
	(gr_poly
		(pts
			(xy 393.02436 -284.007814) (xy 392.924538 -283.907738) (xy 392.924284 -283.907738) (xy 392.824462 -284.007814)
			(xy 392.824462 -284.052264) (xy 393.02436 -284.052264)
		)
		(stroke
			(width 0)
			(type solid)
		)
		(fill yes)
		(layer "In11.Cu")
		(net "M_L_CPU0_SB_DQ<16>")
	)
	(gr_poly
		(pts
			(xy 393.02436 -282.387802) (xy 392.924538 -282.287726) (xy 392.924284 -282.287726) (xy 392.824462 -282.387802)
			(xy 392.824462 -282.432252) (xy 393.02436 -282.432252)
		)
		(stroke
			(width 0)
			(type solid)
		)
		(fill yes)
		(layer "In11.Cu")
		(net "M_L_CPU0_SB_DQ<12>")
	)
	(gr_poly
		(pts
			(xy 393.02436 -279.147778) (xy 392.924538 -279.047702) (xy 392.924284 -279.047702) (xy 392.824462 -279.147778)
			(xy 392.824462 -279.192228) (xy 393.02436 -279.192228)
		)
		(stroke
			(width 0)
			(type solid)
		)
		(fill yes)
		(layer "In11.Cu")
		(net "M_L_CPU0_SB_DQ<8>")
	)
	(gr_poly
		(pts
			(xy 393.02436 -277.527766) (xy 392.924538 -277.42769) (xy 392.924284 -277.42769) (xy 392.824462 -277.527766)
			(xy 392.824462 -277.572216) (xy 393.02436 -277.572216)
		)
		(stroke
			(width 0)
			(type solid)
		)
		(fill yes)
		(layer "In11.Cu")
		(net "M_L_CPU0_SB_DQ<4>")
	)
	(gr_poly
		(pts
			(xy 393.02436 -274.287742) (xy 392.924538 -274.187666) (xy 392.924284 -274.187666) (xy 392.824462 -274.287742)
			(xy 392.824462 -274.332192) (xy 393.02436 -274.332192)
		)
		(stroke
			(width 0)
			(type solid)
		)
		(fill yes)
		(layer "In11.Cu")
		(net "M_L_CPU0_SB_DQ<0>")
	)
	(gr_poly
		(pts
			(xy 393.02436 -262.947658) (xy 392.924538 -262.847582) (xy 392.924284 -262.847582) (xy 392.824462 -262.947658)
			(xy 392.824462 -262.992108) (xy 393.02436 -262.992108)
		)
		(stroke
			(width 0)
			(type solid)
		)
		(fill yes)
		(layer "In11.Cu")
		(net "M_L_CPU0_SB_CA<2>")
	)
	(gr_poly
		(pts
			(xy 393.239498 -223.760538) (xy 393.239752 -223.760538) (xy 393.202922 -223.62414) (xy 393.161774 -223.600264)
			(xy 393.061698 -223.773492) (xy 393.1031 -223.797368)
		)
		(stroke
			(width 0)
			(type solid)
		)
		(fill yes)
		(layer "In11.Cu")
		(net "M_L_CPU0_SA_DQS_DN<0>")
	)
	(gr_poly
		(pts
			(xy 393.71016 -224.570036) (xy 393.710414 -224.570036) (xy 393.673584 -224.433384) (xy 393.632436 -224.409508)
			(xy 393.53236 -224.582736) (xy 393.573762 -224.606612)
		)
		(stroke
			(width 0)
			(type solid)
		)
		(fill yes)
		(layer "In11.Cu")
		(net "M_L_CPU0_SA_DQS_DP<5>")
	)
	(gr_poly
		(pts
			(xy 404.143972 -318.199008) (xy 404.143972 -316.039246) (xy 403.091142 -314.986416) (xy 394.941552 -314.986416)
			(xy 394.802106 -315.125862) (xy 394.802106 -317.75654) (xy 395.678406 -318.63284) (xy 403.71014 -318.63284)
		)
		(stroke
			(width 0)
			(type solid)
		)
		(fill yes)
		(layer "In11.Cu")
		(net "GND")
	)
	(gr_poly
		(pts
			(xy 446.395602 -425.69511) (xy 446.395602 -422.26611) (xy 446.268602 -422.13911) (xy 442.458602 -422.13911)
			(xy 442.331602 -422.26611) (xy 442.331602 -425.69511) (xy 442.458602 -425.82211) (xy 446.268602 -425.82211)
		)
		(stroke
			(width 0)
			(type solid)
		)
		(fill yes)
		(layer "In11.Cu")
		(net "GND")
	)
	(gr_poly
		(pts
			(xy 32.7152 -366.31753) (xy 32.7152 -362.1024) (xy 32.7152 -361.8992) (xy 32.6898 -361.8738) (xy 28.2956 -361.8738)
			(xy 28.245308 -361.924092) (xy 28.245308 -362.086144) (xy 28.245308 -366.318292) (xy 28.2702 -366.34293)
			(xy 32.6898 -366.34293)
		)
		(stroke
			(width 0)
			(type solid)
		)
		(fill yes)
		(layer "In11.Cu")
		(net "GND")
	)
	(gr_poly
		(pts
			(xy 222.32239 -243.494814) (xy 222.32239 -241.261646) (xy 222.32239 -235.90758) (xy 221.304104 -234.889294)
			(xy 209.644234 -234.889294) (xy 208.823306 -235.710222) (xy 208.823306 -240.67008) (xy 208.823306 -243.593366)
			(xy 209.71002 -244.48008) (xy 221.337124 -244.48008)
		)
		(stroke
			(width 0)
			(type solid)
		)
		(fill yes)
		(layer "In11.Cu")
		(net "P3V3_AUX")
	)
	(gr_poly
		(pts
			(xy 312.3692 -362.88853) (xy 312.3692 -358.6734) (xy 312.3692 -358.4702) (xy 312.3438 -358.4448)
			(xy 307.9496 -358.4448) (xy 307.899308 -358.495092) (xy 307.899308 -358.657144) (xy 307.899308 -362.889292)
			(xy 307.9242 -362.91393) (xy 312.3438 -362.91393)
		)
		(stroke
			(width 0)
			(type solid)
		)
		(fill yes)
		(layer "In11.Cu")
		(net "GND")
	)
	(gr_poly
		(pts
			(xy 8.62076 -102.117144) (xy 8.86968 -101.868224) (xy 8.86968 -97.412302) (xy 8.669782 -97.212404)
			(xy 6.003544 -97.212404) (xy 5.494782 -97.721166) (xy 5.36956 -97.846388) (xy 5.093462 -98.122486)
			(xy 5.093462 -101.841046) (xy 5.36956 -102.117144) (xy 5.494782 -102.242366) (xy 8.495538 -102.242366)
		)
		(stroke
			(width 0)
			(type solid)
		)
		(fill yes)
		(layer "In11.Cu")
		(net "GND")
	)
	(gr_poly
		(pts
			(xy 441.045092 -43.578018) (xy 441.045092 -43.451018) (xy 441.045092 -38.853618) (xy 440.918092 -38.726618)
			(xy 434.288692 -38.726618) (xy 433.780692 -38.726618) (xy 433.628292 -38.879018) (xy 433.628292 -43.001946)
			(xy 433.628292 -43.618658) (xy 433.780692 -43.771058) (xy 438.893458 -43.771058) (xy 440.852052 -43.771058)
		)
		(stroke
			(width 0)
			(type solid)
		)
		(fill yes)
		(layer "In11.Cu")
		(net "P12V_AUX")
	)
	(gr_poly
		(pts
			(xy 155.952952 -319.820798) (xy 155.952952 -316.907418) (xy 155.693364 -316.64783) (xy 151.944832 -316.64783)
			(xy 151.40559 -316.108588) (xy 151.40559 -315.483494) (xy 151.140414 -315.218318) (xy 147.148804 -315.218318)
			(xy 147.023582 -315.34354) (xy 146.703796 -315.663326) (xy 146.703796 -318.473074) (xy 147.209256 -318.978534)
			(xy 147.676362 -318.978534) (xy 148.655278 -319.95745) (xy 151.382476 -319.95745) (xy 151.549608 -319.95745)
			(xy 155.8163 -319.95745)
		)
		(stroke
			(width 0)
			(type solid)
		)
		(fill yes)
		(layer "In11.Cu")
		(net "GND")
	)
	(gr_poly
		(pts
			(arc
				(start 165.676072 -398.209008)
				(mid 165.458648 -398.209008)
				(end 165.676072 -398.209008)
			)
		)
		(stroke
			(width 0)
			(type solid)
		)
		(fill yes)
		(layer "In11.Cu")
		(net "GND")
	)
	(gr_poly
		(pts
			(arc
				(start 165.785546 -361.004104)
				(mid 165.526466 -361.004104)
				(end 165.785546 -361.004104)
			)
		)
		(stroke
			(width 0)
			(type solid)
		)
		(fill yes)
		(layer "In11.Cu")
		(net "GND")
	)
	(gr_poly
		(pts
			(arc
				(start 166.721282 -362.926376)
				(mid 166.462202 -362.926376)
				(end 166.721282 -362.926376)
			)
		)
		(stroke
			(width 0)
			(type solid)
		)
		(fill yes)
		(layer "In11.Cu")
		(net "GND")
	)
	(gr_poly
		(pts
			(arc
				(start 303.367186 -412.84652)
				(mid 303.108106 -412.84652)
				(end 303.367186 -412.84652)
			)
		)
		(stroke
			(width 0)
			(type solid)
		)
		(fill yes)
		(layer "In11.Cu")
		(net "GND")
	)
	(gr_poly
		(pts
			(arc
				(start 303.725834 -413.480504)
				(mid 303.466754 -413.480504)
				(end 303.725834 -413.480504)
			)
		)
		(stroke
			(width 0)
			(type solid)
		)
		(fill yes)
		(layer "In11.Cu")
		(net "GND")
	)
	(gr_poly
		(pts
			(arc
				(start 303.725834 -412.212536)
				(mid 303.466754 -412.212536)
				(end 303.725834 -412.212536)
			)
		)
		(stroke
			(width 0)
			(type solid)
		)
		(fill yes)
		(layer "In11.Cu")
		(net "GND")
	)
	(gr_poly
		(pts
			(arc
				(start 304.898806 -415.38652)
				(mid 304.639726 -415.38652)
				(end 304.898806 -415.38652)
			)
		)
		(stroke
			(width 0)
			(type solid)
		)
		(fill yes)
		(layer "In11.Cu")
		(net "GND")
	)
	(gr_poly
		(pts
			(arc
				(start 304.984658 -413.480504)
				(mid 304.725578 -413.480504)
				(end 304.984658 -413.480504)
			)
		)
		(stroke
			(width 0)
			(type solid)
		)
		(fill yes)
		(layer "In11.Cu")
		(net "GND")
	)
	(gr_poly
		(pts
			(arc
				(start 304.984658 -412.212536)
				(mid 304.725578 -412.212536)
				(end 304.984658 -412.212536)
			)
		)
		(stroke
			(width 0)
			(type solid)
		)
		(fill yes)
		(layer "In11.Cu")
		(net "GND")
	)
	(gr_poly
		(pts
			(arc
				(start 305.257454 -416.020504)
				(mid 304.998374 -416.020504)
				(end 305.257454 -416.020504)
			)
		)
		(stroke
			(width 0)
			(type solid)
		)
		(fill yes)
		(layer "In11.Cu")
		(net "GND")
	)
	(gr_poly
		(pts
			(arc
				(start 305.257454 -414.752536)
				(mid 304.998374 -414.752536)
				(end 305.257454 -414.752536)
			)
		)
		(stroke
			(width 0)
			(type solid)
		)
		(fill yes)
		(layer "In11.Cu")
		(net "GND")
	)
	(gr_poly
		(pts
			(arc
				(start 305.343306 -412.84652)
				(mid 305.084226 -412.84652)
				(end 305.343306 -412.84652)
			)
		)
		(stroke
			(width 0)
			(type solid)
		)
		(fill yes)
		(layer "In11.Cu")
		(net "GND")
	)
	(gr_poly
		(pts
			(arc
				(start 306.430426 -412.84652)
				(mid 306.171346 -412.84652)
				(end 306.430426 -412.84652)
			)
		)
		(stroke
			(width 0)
			(type solid)
		)
		(fill yes)
		(layer "In11.Cu")
		(net "GND")
	)
	(gr_poly
		(pts
			(arc
				(start 306.516278 -416.020504)
				(mid 306.257198 -416.020504)
				(end 306.516278 -416.020504)
			)
		)
		(stroke
			(width 0)
			(type solid)
		)
		(fill yes)
		(layer "In11.Cu")
		(net "GND")
	)
	(gr_poly
		(pts
			(arc
				(start 306.516278 -414.752536)
				(mid 306.257198 -414.752536)
				(end 306.516278 -414.752536)
			)
		)
		(stroke
			(width 0)
			(type solid)
		)
		(fill yes)
		(layer "In11.Cu")
		(net "GND")
	)
	(gr_poly
		(pts
			(arc
				(start 306.789074 -413.480504)
				(mid 306.529994 -413.480504)
				(end 306.789074 -413.480504)
			)
		)
		(stroke
			(width 0)
			(type solid)
		)
		(fill yes)
		(layer "In11.Cu")
		(net "GND")
	)
	(gr_poly
		(pts
			(arc
				(start 306.789074 -412.212536)
				(mid 306.529994 -412.212536)
				(end 306.789074 -412.212536)
			)
		)
		(stroke
			(width 0)
			(type solid)
		)
		(fill yes)
		(layer "In11.Cu")
		(net "GND")
	)
	(gr_poly
		(pts
			(arc
				(start 306.874926 -415.38652)
				(mid 306.615846 -415.38652)
				(end 306.874926 -415.38652)
			)
		)
		(stroke
			(width 0)
			(type solid)
		)
		(fill yes)
		(layer "In11.Cu")
		(net "GND")
	)
	(gr_poly
		(pts
			(arc
				(start 307.962046 -415.38652)
				(mid 307.702966 -415.38652)
				(end 307.962046 -415.38652)
			)
		)
		(stroke
			(width 0)
			(type solid)
		)
		(fill yes)
		(layer "In11.Cu")
		(net "GND")
	)
	(gr_poly
		(pts
			(arc
				(start 308.047898 -413.480504)
				(mid 307.788818 -413.480504)
				(end 308.047898 -413.480504)
			)
		)
		(stroke
			(width 0)
			(type solid)
		)
		(fill yes)
		(layer "In11.Cu")
		(net "GND")
	)
	(gr_poly
		(pts
			(arc
				(start 308.047898 -412.212536)
				(mid 307.788818 -412.212536)
				(end 308.047898 -412.212536)
			)
		)
		(stroke
			(width 0)
			(type solid)
		)
		(fill yes)
		(layer "In11.Cu")
		(net "GND")
	)
	(gr_poly
		(pts
			(arc
				(start 308.320694 -416.020504)
				(mid 308.061614 -416.020504)
				(end 308.320694 -416.020504)
			)
		)
		(stroke
			(width 0)
			(type solid)
		)
		(fill yes)
		(layer "In11.Cu")
		(net "GND")
	)
	(gr_poly
		(pts
			(arc
				(start 308.320694 -414.752536)
				(mid 308.061614 -414.752536)
				(end 308.320694 -414.752536)
			)
		)
		(stroke
			(width 0)
			(type solid)
		)
		(fill yes)
		(layer "In11.Cu")
		(net "GND")
	)
	(gr_poly
		(pts
			(arc
				(start 308.406546 -412.84652)
				(mid 308.147466 -412.84652)
				(end 308.406546 -412.84652)
			)
		)
		(stroke
			(width 0)
			(type solid)
		)
		(fill yes)
		(layer "In11.Cu")
		(net "GND")
	)
	(gr_poly
		(pts
			(arc
				(start 309.493666 -412.84652)
				(mid 309.234586 -412.84652)
				(end 309.493666 -412.84652)
			)
		)
		(stroke
			(width 0)
			(type solid)
		)
		(fill yes)
		(layer "In11.Cu")
		(net "GND")
	)
	(gr_poly
		(pts
			(arc
				(start 309.579518 -416.020504)
				(mid 309.320438 -416.020504)
				(end 309.579518 -416.020504)
			)
		)
		(stroke
			(width 0)
			(type solid)
		)
		(fill yes)
		(layer "In11.Cu")
		(net "GND")
	)
	(gr_poly
		(pts
			(arc
				(start 309.579518 -414.752536)
				(mid 309.320438 -414.752536)
				(end 309.579518 -414.752536)
			)
		)
		(stroke
			(width 0)
			(type solid)
		)
		(fill yes)
		(layer "In11.Cu")
		(net "GND")
	)
	(gr_poly
		(pts
			(arc
				(start 309.852314 -413.480504)
				(mid 309.593234 -413.480504)
				(end 309.852314 -413.480504)
			)
		)
		(stroke
			(width 0)
			(type solid)
		)
		(fill yes)
		(layer "In11.Cu")
		(net "GND")
	)
	(gr_poly
		(pts
			(arc
				(start 309.852314 -412.212536)
				(mid 309.593234 -412.212536)
				(end 309.852314 -412.212536)
			)
		)
		(stroke
			(width 0)
			(type solid)
		)
		(fill yes)
		(layer "In11.Cu")
		(net "GND")
	)
	(gr_poly
		(pts
			(arc
				(start 309.938166 -415.38652)
				(mid 309.679086 -415.38652)
				(end 309.938166 -415.38652)
			)
		)
		(stroke
			(width 0)
			(type solid)
		)
		(fill yes)
		(layer "In11.Cu")
		(net "GND")
	)
	(gr_poly
		(pts
			(arc
				(start 311.025286 -415.38652)
				(mid 310.766206 -415.38652)
				(end 311.025286 -415.38652)
			)
		)
		(stroke
			(width 0)
			(type solid)
		)
		(fill yes)
		(layer "In11.Cu")
		(net "GND")
	)
	(gr_poly
		(pts
			(arc
				(start 311.111138 -413.480504)
				(mid 310.852058 -413.480504)
				(end 311.111138 -413.480504)
			)
		)
		(stroke
			(width 0)
			(type solid)
		)
		(fill yes)
		(layer "In11.Cu")
		(net "GND")
	)
	(gr_poly
		(pts
			(arc
				(start 311.111138 -412.212536)
				(mid 310.852058 -412.212536)
				(end 311.111138 -412.212536)
			)
		)
		(stroke
			(width 0)
			(type solid)
		)
		(fill yes)
		(layer "In11.Cu")
		(net "GND")
	)
	(gr_poly
		(pts
			(arc
				(start 311.383934 -416.020504)
				(mid 311.124854 -416.020504)
				(end 311.383934 -416.020504)
			)
		)
		(stroke
			(width 0)
			(type solid)
		)
		(fill yes)
		(layer "In11.Cu")
		(net "GND")
	)
	(gr_poly
		(pts
			(arc
				(start 311.383934 -414.752536)
				(mid 311.124854 -414.752536)
				(end 311.383934 -414.752536)
			)
		)
		(stroke
			(width 0)
			(type solid)
		)
		(fill yes)
		(layer "In11.Cu")
		(net "GND")
	)
	(gr_poly
		(pts
			(arc
				(start 311.469786 -412.84652)
				(mid 311.210706 -412.84652)
				(end 311.469786 -412.84652)
			)
		)
		(stroke
			(width 0)
			(type solid)
		)
		(fill yes)
		(layer "In11.Cu")
		(net "GND")
	)
	(gr_poly
		(pts
			(arc
				(start 312.556906 -412.84652)
				(mid 312.297826 -412.84652)
				(end 312.556906 -412.84652)
			)
		)
		(stroke
			(width 0)
			(type solid)
		)
		(fill yes)
		(layer "In11.Cu")
		(net "GND")
	)
	(gr_poly
		(pts
			(arc
				(start 312.642758 -416.020504)
				(mid 312.383678 -416.020504)
				(end 312.642758 -416.020504)
			)
		)
		(stroke
			(width 0)
			(type solid)
		)
		(fill yes)
		(layer "In11.Cu")
		(net "GND")
	)
	(gr_poly
		(pts
			(arc
				(start 312.642758 -414.752536)
				(mid 312.383678 -414.752536)
				(end 312.642758 -414.752536)
			)
		)
		(stroke
			(width 0)
			(type solid)
		)
		(fill yes)
		(layer "In11.Cu")
		(net "GND")
	)
	(gr_poly
		(pts
			(arc
				(start 312.915554 -413.480504)
				(mid 312.656474 -413.480504)
				(end 312.915554 -413.480504)
			)
		)
		(stroke
			(width 0)
			(type solid)
		)
		(fill yes)
		(layer "In11.Cu")
		(net "GND")
	)
	(gr_poly
		(pts
			(arc
				(start 312.915554 -412.212536)
				(mid 312.656474 -412.212536)
				(end 312.915554 -412.212536)
			)
		)
		(stroke
			(width 0)
			(type solid)
		)
		(fill yes)
		(layer "In11.Cu")
		(net "GND")
	)
	(gr_poly
		(pts
			(arc
				(start 313.001406 -415.38652)
				(mid 312.742326 -415.38652)
				(end 313.001406 -415.38652)
			)
		)
		(stroke
			(width 0)
			(type solid)
		)
		(fill yes)
		(layer "In11.Cu")
		(net "GND")
	)
	(gr_poly
		(pts
			(arc
				(start 314.088526 -415.38652)
				(mid 313.829446 -415.38652)
				(end 314.088526 -415.38652)
			)
		)
		(stroke
			(width 0)
			(type solid)
		)
		(fill yes)
		(layer "In11.Cu")
		(net "GND")
	)
	(gr_poly
		(pts
			(arc
				(start 314.174378 -413.480504)
				(mid 313.915298 -413.480504)
				(end 314.174378 -413.480504)
			)
		)
		(stroke
			(width 0)
			(type solid)
		)
		(fill yes)
		(layer "In11.Cu")
		(net "GND")
	)
	(gr_poly
		(pts
			(arc
				(start 314.174378 -412.212536)
				(mid 313.915298 -412.212536)
				(end 314.174378 -412.212536)
			)
		)
		(stroke
			(width 0)
			(type solid)
		)
		(fill yes)
		(layer "In11.Cu")
		(net "GND")
	)
	(gr_poly
		(pts
			(arc
				(start 314.447174 -416.020504)
				(mid 314.188094 -416.020504)
				(end 314.447174 -416.020504)
			)
		)
		(stroke
			(width 0)
			(type solid)
		)
		(fill yes)
		(layer "In11.Cu")
		(net "GND")
	)
	(gr_poly
		(pts
			(arc
				(start 314.447174 -414.752536)
				(mid 314.188094 -414.752536)
				(end 314.447174 -414.752536)
			)
		)
		(stroke
			(width 0)
			(type solid)
		)
		(fill yes)
		(layer "In11.Cu")
		(net "GND")
	)
	(gr_poly
		(pts
			(arc
				(start 314.533026 -412.84652)
				(mid 314.273946 -412.84652)
				(end 314.533026 -412.84652)
			)
		)
		(stroke
			(width 0)
			(type solid)
		)
		(fill yes)
		(layer "In11.Cu")
		(net "GND")
	)
	(gr_poly
		(pts
			(arc
				(start 315.620146 -412.84652)
				(mid 315.361066 -412.84652)
				(end 315.620146 -412.84652)
			)
		)
		(stroke
			(width 0)
			(type solid)
		)
		(fill yes)
		(layer "In11.Cu")
		(net "GND")
	)
	(gr_poly
		(pts
			(arc
				(start 315.705998 -416.020504)
				(mid 315.446918 -416.020504)
				(end 315.705998 -416.020504)
			)
		)
		(stroke
			(width 0)
			(type solid)
		)
		(fill yes)
		(layer "In11.Cu")
		(net "GND")
	)
	(gr_poly
		(pts
			(arc
				(start 315.705998 -414.752536)
				(mid 315.446918 -414.752536)
				(end 315.705998 -414.752536)
			)
		)
		(stroke
			(width 0)
			(type solid)
		)
		(fill yes)
		(layer "In11.Cu")
		(net "GND")
	)
	(gr_poly
		(pts
			(arc
				(start 315.978794 -413.480504)
				(mid 315.719714 -413.480504)
				(end 315.978794 -413.480504)
			)
		)
		(stroke
			(width 0)
			(type solid)
		)
		(fill yes)
		(layer "In11.Cu")
		(net "GND")
	)
	(gr_poly
		(pts
			(arc
				(start 315.978794 -412.212536)
				(mid 315.719714 -412.212536)
				(end 315.978794 -412.212536)
			)
		)
		(stroke
			(width 0)
			(type solid)
		)
		(fill yes)
		(layer "In11.Cu")
		(net "GND")
	)
	(gr_poly
		(pts
			(arc
				(start 316.064646 -415.38652)
				(mid 315.805566 -415.38652)
				(end 316.064646 -415.38652)
			)
		)
		(stroke
			(width 0)
			(type solid)
		)
		(fill yes)
		(layer "In11.Cu")
		(net "GND")
	)
	(gr_poly
		(pts
			(arc
				(start 317.151766 -415.38652)
				(mid 316.892686 -415.38652)
				(end 317.151766 -415.38652)
			)
		)
		(stroke
			(width 0)
			(type solid)
		)
		(fill yes)
		(layer "In11.Cu")
		(net "GND")
	)
	(gr_poly
		(pts
			(arc
				(start 317.237618 -413.480504)
				(mid 316.978538 -413.480504)
				(end 317.237618 -413.480504)
			)
		)
		(stroke
			(width 0)
			(type solid)
		)
		(fill yes)
		(layer "In11.Cu")
		(net "GND")
	)
	(gr_poly
		(pts
			(arc
				(start 317.237618 -412.212536)
				(mid 316.978538 -412.212536)
				(end 317.237618 -412.212536)
			)
		)
		(stroke
			(width 0)
			(type solid)
		)
		(fill yes)
		(layer "In11.Cu")
		(net "GND")
	)
	(gr_poly
		(pts
			(arc
				(start 317.510414 -416.020504)
				(mid 317.251334 -416.020504)
				(end 317.510414 -416.020504)
			)
		)
		(stroke
			(width 0)
			(type solid)
		)
		(fill yes)
		(layer "In11.Cu")
		(net "GND")
	)
	(gr_poly
		(pts
			(arc
				(start 317.510414 -414.752536)
				(mid 317.251334 -414.752536)
				(end 317.510414 -414.752536)
			)
		)
		(stroke
			(width 0)
			(type solid)
		)
		(fill yes)
		(layer "In11.Cu")
		(net "GND")
	)
	(gr_poly
		(pts
			(arc
				(start 317.596266 -412.84652)
				(mid 317.337186 -412.84652)
				(end 317.596266 -412.84652)
			)
		)
		(stroke
			(width 0)
			(type solid)
		)
		(fill yes)
		(layer "In11.Cu")
		(net "GND")
	)
	(gr_poly
		(pts
			(arc
				(start 318.683386 -412.84652)
				(mid 318.424306 -412.84652)
				(end 318.683386 -412.84652)
			)
		)
		(stroke
			(width 0)
			(type solid)
		)
		(fill yes)
		(layer "In11.Cu")
		(net "GND")
	)
	(gr_poly
		(pts
			(arc
				(start 318.769238 -416.020504)
				(mid 318.510158 -416.020504)
				(end 318.769238 -416.020504)
			)
		)
		(stroke
			(width 0)
			(type solid)
		)
		(fill yes)
		(layer "In11.Cu")
		(net "GND")
	)
	(gr_poly
		(pts
			(arc
				(start 318.769238 -414.752536)
				(mid 318.510158 -414.752536)
				(end 318.769238 -414.752536)
			)
		)
		(stroke
			(width 0)
			(type solid)
		)
		(fill yes)
		(layer "In11.Cu")
		(net "GND")
	)
	(gr_poly
		(pts
			(arc
				(start 319.042034 -413.480504)
				(mid 318.782954 -413.480504)
				(end 319.042034 -413.480504)
			)
		)
		(stroke
			(width 0)
			(type solid)
		)
		(fill yes)
		(layer "In11.Cu")
		(net "GND")
	)
	(gr_poly
		(pts
			(arc
				(start 319.042034 -412.212536)
				(mid 318.782954 -412.212536)
				(end 319.042034 -412.212536)
			)
		)
		(stroke
			(width 0)
			(type solid)
		)
		(fill yes)
		(layer "In11.Cu")
		(net "GND")
	)
	(gr_poly
		(pts
			(arc
				(start 319.127886 -415.38652)
				(mid 318.868806 -415.38652)
				(end 319.127886 -415.38652)
			)
		)
		(stroke
			(width 0)
			(type solid)
		)
		(fill yes)
		(layer "In11.Cu")
		(net "GND")
	)
	(gr_poly
		(pts
			(arc
				(start 320.215006 -415.38652)
				(mid 319.955926 -415.38652)
				(end 320.215006 -415.38652)
			)
		)
		(stroke
			(width 0)
			(type solid)
		)
		(fill yes)
		(layer "In11.Cu")
		(net "GND")
	)
	(gr_poly
		(pts
			(arc
				(start 320.300858 -413.480504)
				(mid 320.041778 -413.480504)
				(end 320.300858 -413.480504)
			)
		)
		(stroke
			(width 0)
			(type solid)
		)
		(fill yes)
		(layer "In11.Cu")
		(net "GND")
	)
	(gr_poly
		(pts
			(arc
				(start 320.300858 -412.212536)
				(mid 320.041778 -412.212536)
				(end 320.300858 -412.212536)
			)
		)
		(stroke
			(width 0)
			(type solid)
		)
		(fill yes)
		(layer "In11.Cu")
		(net "GND")
	)
	(gr_poly
		(pts
			(arc
				(start 320.573654 -416.020504)
				(mid 320.314574 -416.020504)
				(end 320.573654 -416.020504)
			)
		)
		(stroke
			(width 0)
			(type solid)
		)
		(fill yes)
		(layer "In11.Cu")
		(net "GND")
	)
	(gr_poly
		(pts
			(arc
				(start 320.573654 -414.752536)
				(mid 320.314574 -414.752536)
				(end 320.573654 -414.752536)
			)
		)
		(stroke
			(width 0)
			(type solid)
		)
		(fill yes)
		(layer "In11.Cu")
		(net "GND")
	)
	(gr_poly
		(pts
			(arc
				(start 320.659506 -412.84652)
				(mid 320.400426 -412.84652)
				(end 320.659506 -412.84652)
			)
		)
		(stroke
			(width 0)
			(type solid)
		)
		(fill yes)
		(layer "In11.Cu")
		(net "GND")
	)
	(gr_poly
		(pts
			(arc
				(start 321.746626 -412.84652)
				(mid 321.487546 -412.84652)
				(end 321.746626 -412.84652)
			)
		)
		(stroke
			(width 0)
			(type solid)
		)
		(fill yes)
		(layer "In11.Cu")
		(net "GND")
	)
	(gr_poly
		(pts
			(arc
				(start 321.832478 -416.020504)
				(mid 321.573398 -416.020504)
				(end 321.832478 -416.020504)
			)
		)
		(stroke
			(width 0)
			(type solid)
		)
		(fill yes)
		(layer "In11.Cu")
		(net "GND")
	)
	(gr_poly
		(pts
			(arc
				(start 321.832478 -414.752536)
				(mid 321.573398 -414.752536)
				(end 321.832478 -414.752536)
			)
		)
		(stroke
			(width 0)
			(type solid)
		)
		(fill yes)
		(layer "In11.Cu")
		(net "GND")
	)
	(gr_poly
		(pts
			(arc
				(start 322.105274 -413.480504)
				(mid 321.846194 -413.480504)
				(end 322.105274 -413.480504)
			)
		)
		(stroke
			(width 0)
			(type solid)
		)
		(fill yes)
		(layer "In11.Cu")
		(net "GND")
	)
	(gr_poly
		(pts
			(arc
				(start 322.105274 -412.212536)
				(mid 321.846194 -412.212536)
				(end 322.105274 -412.212536)
			)
		)
		(stroke
			(width 0)
			(type solid)
		)
		(fill yes)
		(layer "In11.Cu")
		(net "GND")
	)
	(gr_poly
		(pts
			(arc
				(start 322.191126 -415.38652)
				(mid 321.932046 -415.38652)
				(end 322.191126 -415.38652)
			)
		)
		(stroke
			(width 0)
			(type solid)
		)
		(fill yes)
		(layer "In11.Cu")
		(net "GND")
	)
	(gr_poly
		(pts
			(arc
				(start 323.278246 -415.38652)
				(mid 323.019166 -415.38652)
				(end 323.278246 -415.38652)
			)
		)
		(stroke
			(width 0)
			(type solid)
		)
		(fill yes)
		(layer "In11.Cu")
		(net "GND")
	)
	(gr_poly
		(pts
			(arc
				(start 323.364098 -413.480504)
				(mid 323.105018 -413.480504)
				(end 323.364098 -413.480504)
			)
		)
		(stroke
			(width 0)
			(type solid)
		)
		(fill yes)
		(layer "In11.Cu")
		(net "GND")
	)
	(gr_poly
		(pts
			(arc
				(start 323.364098 -412.212536)
				(mid 323.105018 -412.212536)
				(end 323.364098 -412.212536)
			)
		)
		(stroke
			(width 0)
			(type solid)
		)
		(fill yes)
		(layer "In11.Cu")
		(net "GND")
	)
	(gr_poly
		(pts
			(arc
				(start 323.636894 -416.020504)
				(mid 323.377814 -416.020504)
				(end 323.636894 -416.020504)
			)
		)
		(stroke
			(width 0)
			(type solid)
		)
		(fill yes)
		(layer "In11.Cu")
		(net "GND")
	)
	(gr_poly
		(pts
			(arc
				(start 323.636894 -414.752536)
				(mid 323.377814 -414.752536)
				(end 323.636894 -414.752536)
			)
		)
		(stroke
			(width 0)
			(type solid)
		)
		(fill yes)
		(layer "In11.Cu")
		(net "GND")
	)
	(gr_poly
		(pts
			(arc
				(start 323.722746 -412.84652)
				(mid 323.463666 -412.84652)
				(end 323.722746 -412.84652)
			)
		)
		(stroke
			(width 0)
			(type solid)
		)
		(fill yes)
		(layer "In11.Cu")
		(net "GND")
	)
	(gr_poly
		(pts
			(arc
				(start 324.809866 -412.84652)
				(mid 324.550786 -412.84652)
				(end 324.809866 -412.84652)
			)
		)
		(stroke
			(width 0)
			(type solid)
		)
		(fill yes)
		(layer "In11.Cu")
		(net "GND")
	)
	(gr_poly
		(pts
			(arc
				(start 324.895718 -416.020504)
				(mid 324.636638 -416.020504)
				(end 324.895718 -416.020504)
			)
		)
		(stroke
			(width 0)
			(type solid)
		)
		(fill yes)
		(layer "In11.Cu")
		(net "GND")
	)
	(gr_poly
		(pts
			(arc
				(start 324.895718 -414.752536)
				(mid 324.636638 -414.752536)
				(end 324.895718 -414.752536)
			)
		)
		(stroke
			(width 0)
			(type solid)
		)
		(fill yes)
		(layer "In11.Cu")
		(net "GND")
	)
	(gr_poly
		(pts
			(arc
				(start 325.168514 -413.480504)
				(mid 324.909434 -413.480504)
				(end 325.168514 -413.480504)
			)
		)
		(stroke
			(width 0)
			(type solid)
		)
		(fill yes)
		(layer "In11.Cu")
		(net "GND")
	)
	(gr_poly
		(pts
			(arc
				(start 325.168514 -412.212536)
				(mid 324.909434 -412.212536)
				(end 325.168514 -412.212536)
			)
		)
		(stroke
			(width 0)
			(type solid)
		)
		(fill yes)
		(layer "In11.Cu")
		(net "GND")
	)
	(gr_poly
		(pts
			(arc
				(start 325.254366 -415.38652)
				(mid 324.995286 -415.38652)
				(end 325.254366 -415.38652)
			)
		)
		(stroke
			(width 0)
			(type solid)
		)
		(fill yes)
		(layer "In11.Cu")
		(net "GND")
	)
	(gr_poly
		(pts
			(arc
				(start 326.341486 -415.38652)
				(mid 326.082406 -415.38652)
				(end 326.341486 -415.38652)
			)
		)
		(stroke
			(width 0)
			(type solid)
		)
		(fill yes)
		(layer "In11.Cu")
		(net "GND")
	)
	(gr_poly
		(pts
			(arc
				(start 326.427338 -413.480504)
				(mid 326.168258 -413.480504)
				(end 326.427338 -413.480504)
			)
		)
		(stroke
			(width 0)
			(type solid)
		)
		(fill yes)
		(layer "In11.Cu")
		(net "GND")
	)
	(gr_poly
		(pts
			(arc
				(start 326.427338 -412.212536)
				(mid 326.168258 -412.212536)
				(end 326.427338 -412.212536)
			)
		)
		(stroke
			(width 0)
			(type solid)
		)
		(fill yes)
		(layer "In11.Cu")
		(net "GND")
	)
	(gr_poly
		(pts
			(arc
				(start 326.700134 -416.020504)
				(mid 326.441054 -416.020504)
				(end 326.700134 -416.020504)
			)
		)
		(stroke
			(width 0)
			(type solid)
		)
		(fill yes)
		(layer "In11.Cu")
		(net "GND")
	)
	(gr_poly
		(pts
			(arc
				(start 326.700134 -414.752536)
				(mid 326.441054 -414.752536)
				(end 326.700134 -414.752536)
			)
		)
		(stroke
			(width 0)
			(type solid)
		)
		(fill yes)
		(layer "In11.Cu")
		(net "GND")
	)
	(gr_poly
		(pts
			(arc
				(start 326.785986 -412.84652)
				(mid 326.526906 -412.84652)
				(end 326.785986 -412.84652)
			)
		)
		(stroke
			(width 0)
			(type solid)
		)
		(fill yes)
		(layer "In11.Cu")
		(net "GND")
	)
	(gr_poly
		(pts
			(arc
				(start 327.873106 -412.84652)
				(mid 327.614026 -412.84652)
				(end 327.873106 -412.84652)
			)
		)
		(stroke
			(width 0)
			(type solid)
		)
		(fill yes)
		(layer "In11.Cu")
		(net "GND")
	)
	(gr_poly
		(pts
			(arc
				(start 327.958958 -416.020504)
				(mid 327.699878 -416.020504)
				(end 327.958958 -416.020504)
			)
		)
		(stroke
			(width 0)
			(type solid)
		)
		(fill yes)
		(layer "In11.Cu")
		(net "GND")
	)
	(gr_poly
		(pts
			(arc
				(start 327.958958 -414.752536)
				(mid 327.699878 -414.752536)
				(end 327.958958 -414.752536)
			)
		)
		(stroke
			(width 0)
			(type solid)
		)
		(fill yes)
		(layer "In11.Cu")
		(net "GND")
	)
	(gr_poly
		(pts
			(arc
				(start 328.231754 -413.480504)
				(mid 327.972674 -413.480504)
				(end 328.231754 -413.480504)
			)
		)
		(stroke
			(width 0)
			(type solid)
		)
		(fill yes)
		(layer "In11.Cu")
		(net "GND")
	)
	(gr_poly
		(pts
			(arc
				(start 328.231754 -412.212536)
				(mid 327.972674 -412.212536)
				(end 328.231754 -412.212536)
			)
		)
		(stroke
			(width 0)
			(type solid)
		)
		(fill yes)
		(layer "In11.Cu")
		(net "GND")
	)
	(gr_poly
		(pts
			(arc
				(start 328.317606 -415.38652)
				(mid 328.058526 -415.38652)
				(end 328.317606 -415.38652)
			)
		)
		(stroke
			(width 0)
			(type solid)
		)
		(fill yes)
		(layer "In11.Cu")
		(net "GND")
	)
	(gr_poly
		(pts
			(arc
				(start 329.404726 -415.38652)
				(mid 329.145646 -415.38652)
				(end 329.404726 -415.38652)
			)
		)
		(stroke
			(width 0)
			(type solid)
		)
		(fill yes)
		(layer "In11.Cu")
		(net "GND")
	)
	(gr_poly
		(pts
			(arc
				(start 329.490578 -413.480504)
				(mid 329.231498 -413.480504)
				(end 329.490578 -413.480504)
			)
		)
		(stroke
			(width 0)
			(type solid)
		)
		(fill yes)
		(layer "In11.Cu")
		(net "GND")
	)
	(gr_poly
		(pts
			(arc
				(start 329.490578 -412.212536)
				(mid 329.231498 -412.212536)
				(end 329.490578 -412.212536)
			)
		)
		(stroke
			(width 0)
			(type solid)
		)
		(fill yes)
		(layer "In11.Cu")
		(net "GND")
	)
	(gr_poly
		(pts
			(arc
				(start 329.763374 -416.020504)
				(mid 329.504294 -416.020504)
				(end 329.763374 -416.020504)
			)
		)
		(stroke
			(width 0)
			(type solid)
		)
		(fill yes)
		(layer "In11.Cu")
		(net "GND")
	)
	(gr_poly
		(pts
			(arc
				(start 329.763374 -414.752536)
				(mid 329.504294 -414.752536)
				(end 329.763374 -414.752536)
			)
		)
		(stroke
			(width 0)
			(type solid)
		)
		(fill yes)
		(layer "In11.Cu")
		(net "GND")
	)
	(gr_poly
		(pts
			(arc
				(start 329.849226 -412.84652)
				(mid 329.590146 -412.84652)
				(end 329.849226 -412.84652)
			)
		)
		(stroke
			(width 0)
			(type solid)
		)
		(fill yes)
		(layer "In11.Cu")
		(net "GND")
	)
	(gr_poly
		(pts
			(arc
				(start 330.936346 -412.84652)
				(mid 330.677266 -412.84652)
				(end 330.936346 -412.84652)
			)
		)
		(stroke
			(width 0)
			(type solid)
		)
		(fill yes)
		(layer "In11.Cu")
		(net "GND")
	)
	(gr_poly
		(pts
			(arc
				(start 331.022198 -416.020504)
				(mid 330.763118 -416.020504)
				(end 331.022198 -416.020504)
			)
		)
		(stroke
			(width 0)
			(type solid)
		)
		(fill yes)
		(layer "In11.Cu")
		(net "GND")
	)
	(gr_poly
		(pts
			(arc
				(start 331.022198 -414.752536)
				(mid 330.763118 -414.752536)
				(end 331.022198 -414.752536)
			)
		)
		(stroke
			(width 0)
			(type solid)
		)
		(fill yes)
		(layer "In11.Cu")
		(net "GND")
	)
	(gr_poly
		(pts
			(arc
				(start 331.294994 -413.480504)
				(mid 331.035914 -413.480504)
				(end 331.294994 -413.480504)
			)
		)
		(stroke
			(width 0)
			(type solid)
		)
		(fill yes)
		(layer "In11.Cu")
		(net "GND")
	)
	(gr_poly
		(pts
			(arc
				(start 331.294994 -412.212536)
				(mid 331.035914 -412.212536)
				(end 331.294994 -412.212536)
			)
		)
		(stroke
			(width 0)
			(type solid)
		)
		(fill yes)
		(layer "In11.Cu")
		(net "GND")
	)
	(gr_poly
		(pts
			(arc
				(start 331.380846 -415.38652)
				(mid 331.121766 -415.38652)
				(end 331.380846 -415.38652)
			)
		)
		(stroke
			(width 0)
			(type solid)
		)
		(fill yes)
		(layer "In11.Cu")
		(net "GND")
	)
	(gr_poly
		(pts
			(arc
				(start 332.467966 -415.38652)
				(mid 332.208886 -415.38652)
				(end 332.467966 -415.38652)
			)
		)
		(stroke
			(width 0)
			(type solid)
		)
		(fill yes)
		(layer "In11.Cu")
		(net "GND")
	)
	(gr_poly
		(pts
			(arc
				(start 332.553818 -413.480504)
				(mid 332.294738 -413.480504)
				(end 332.553818 -413.480504)
			)
		)
		(stroke
			(width 0)
			(type solid)
		)
		(fill yes)
		(layer "In11.Cu")
		(net "GND")
	)
	(gr_poly
		(pts
			(arc
				(start 332.553818 -412.212536)
				(mid 332.294738 -412.212536)
				(end 332.553818 -412.212536)
			)
		)
		(stroke
			(width 0)
			(type solid)
		)
		(fill yes)
		(layer "In11.Cu")
		(net "GND")
	)
	(gr_poly
		(pts
			(arc
				(start 332.826614 -416.020504)
				(mid 332.567534 -416.020504)
				(end 332.826614 -416.020504)
			)
		)
		(stroke
			(width 0)
			(type solid)
		)
		(fill yes)
		(layer "In11.Cu")
		(net "GND")
	)
	(gr_poly
		(pts
			(arc
				(start 332.826614 -414.752536)
				(mid 332.567534 -414.752536)
				(end 332.826614 -414.752536)
			)
		)
		(stroke
			(width 0)
			(type solid)
		)
		(fill yes)
		(layer "In11.Cu")
		(net "GND")
	)
	(gr_poly
		(pts
			(arc
				(start 332.912466 -412.84652)
				(mid 332.653386 -412.84652)
				(end 332.912466 -412.84652)
			)
		)
		(stroke
			(width 0)
			(type solid)
		)
		(fill yes)
		(layer "In11.Cu")
		(net "GND")
	)
	(gr_poly
		(pts
			(arc
				(start 333.999586 -412.84652)
				(mid 333.740506 -412.84652)
				(end 333.999586 -412.84652)
			)
		)
		(stroke
			(width 0)
			(type solid)
		)
		(fill yes)
		(layer "In11.Cu")
		(net "GND")
	)
	(gr_poly
		(pts
			(arc
				(start 334.085438 -416.020504)
				(mid 333.826358 -416.020504)
				(end 334.085438 -416.020504)
			)
		)
		(stroke
			(width 0)
			(type solid)
		)
		(fill yes)
		(layer "In11.Cu")
		(net "GND")
	)
	(gr_poly
		(pts
			(arc
				(start 334.085438 -414.752536)
				(mid 333.826358 -414.752536)
				(end 334.085438 -414.752536)
			)
		)
		(stroke
			(width 0)
			(type solid)
		)
		(fill yes)
		(layer "In11.Cu")
		(net "GND")
	)
	(gr_poly
		(pts
			(arc
				(start 334.358234 -413.480504)
				(mid 334.099154 -413.480504)
				(end 334.358234 -413.480504)
			)
		)
		(stroke
			(width 0)
			(type solid)
		)
		(fill yes)
		(layer "In11.Cu")
		(net "GND")
	)
	(gr_poly
		(pts
			(arc
				(start 334.358234 -412.212536)
				(mid 334.099154 -412.212536)
				(end 334.358234 -412.212536)
			)
		)
		(stroke
			(width 0)
			(type solid)
		)
		(fill yes)
		(layer "In11.Cu")
		(net "GND")
	)
	(gr_poly
		(pts
			(arc
				(start 334.444086 -415.38652)
				(mid 334.185006 -415.38652)
				(end 334.444086 -415.38652)
			)
		)
		(stroke
			(width 0)
			(type solid)
		)
		(fill yes)
		(layer "In11.Cu")
		(net "GND")
	)
	(gr_poly
		(pts
			(arc
				(start 335.531206 -415.38652)
				(mid 335.272126 -415.38652)
				(end 335.531206 -415.38652)
			)
		)
		(stroke
			(width 0)
			(type solid)
		)
		(fill yes)
		(layer "In11.Cu")
		(net "GND")
	)
	(gr_poly
		(pts
			(arc
				(start 335.617058 -413.480504)
				(mid 335.357978 -413.480504)
				(end 335.617058 -413.480504)
			)
		)
		(stroke
			(width 0)
			(type solid)
		)
		(fill yes)
		(layer "In11.Cu")
		(net "GND")
	)
	(gr_poly
		(pts
			(arc
				(start 335.617058 -412.212536)
				(mid 335.357978 -412.212536)
				(end 335.617058 -412.212536)
			)
		)
		(stroke
			(width 0)
			(type solid)
		)
		(fill yes)
		(layer "In11.Cu")
		(net "GND")
	)
	(gr_poly
		(pts
			(arc
				(start 335.889854 -416.020504)
				(mid 335.630774 -416.020504)
				(end 335.889854 -416.020504)
			)
		)
		(stroke
			(width 0)
			(type solid)
		)
		(fill yes)
		(layer "In11.Cu")
		(net "GND")
	)
	(gr_poly
		(pts
			(arc
				(start 335.889854 -414.752536)
				(mid 335.630774 -414.752536)
				(end 335.889854 -414.752536)
			)
		)
		(stroke
			(width 0)
			(type solid)
		)
		(fill yes)
		(layer "In11.Cu")
		(net "GND")
	)
	(gr_poly
		(pts
			(arc
				(start 335.975706 -412.84652)
				(mid 335.716626 -412.84652)
				(end 335.975706 -412.84652)
			)
		)
		(stroke
			(width 0)
			(type solid)
		)
		(fill yes)
		(layer "In11.Cu")
		(net "GND")
	)
	(gr_poly
		(pts
			(arc
				(start 337.062826 -412.84652)
				(mid 336.803746 -412.84652)
				(end 337.062826 -412.84652)
			)
		)
		(stroke
			(width 0)
			(type solid)
		)
		(fill yes)
		(layer "In11.Cu")
		(net "GND")
	)
	(gr_poly
		(pts
			(arc
				(start 337.148678 -416.020504)
				(mid 336.889598 -416.020504)
				(end 337.148678 -416.020504)
			)
		)
		(stroke
			(width 0)
			(type solid)
		)
		(fill yes)
		(layer "In11.Cu")
		(net "GND")
	)
	(gr_poly
		(pts
			(arc
				(start 337.148678 -414.752536)
				(mid 336.889598 -414.752536)
				(end 337.148678 -414.752536)
			)
		)
		(stroke
			(width 0)
			(type solid)
		)
		(fill yes)
		(layer "In11.Cu")
		(net "GND")
	)
	(gr_poly
		(pts
			(arc
				(start 337.421474 -413.480504)
				(mid 337.162394 -413.480504)
				(end 337.421474 -413.480504)
			)
		)
		(stroke
			(width 0)
			(type solid)
		)
		(fill yes)
		(layer "In11.Cu")
		(net "GND")
	)
	(gr_poly
		(pts
			(arc
				(start 337.421474 -412.212536)
				(mid 337.162394 -412.212536)
				(end 337.421474 -412.212536)
			)
		)
		(stroke
			(width 0)
			(type solid)
		)
		(fill yes)
		(layer "In11.Cu")
		(net "GND")
	)
	(gr_poly
		(pts
			(arc
				(start 337.507326 -415.38652)
				(mid 337.248246 -415.38652)
				(end 337.507326 -415.38652)
			)
		)
		(stroke
			(width 0)
			(type solid)
		)
		(fill yes)
		(layer "In11.Cu")
		(net "GND")
	)
	(gr_poly
		(pts
			(arc
				(start 338.594446 -415.38652)
				(mid 338.335366 -415.38652)
				(end 338.594446 -415.38652)
			)
		)
		(stroke
			(width 0)
			(type solid)
		)
		(fill yes)
		(layer "In11.Cu")
		(net "GND")
	)
	(gr_poly
		(pts
			(arc
				(start 338.680298 -413.480504)
				(mid 338.421218 -413.480504)
				(end 338.680298 -413.480504)
			)
		)
		(stroke
			(width 0)
			(type solid)
		)
		(fill yes)
		(layer "In11.Cu")
		(net "GND")
	)
	(gr_poly
		(pts
			(arc
				(start 338.680298 -412.212536)
				(mid 338.421218 -412.212536)
				(end 338.680298 -412.212536)
			)
		)
		(stroke
			(width 0)
			(type solid)
		)
		(fill yes)
		(layer "In11.Cu")
		(net "GND")
	)
	(gr_poly
		(pts
			(arc
				(start 338.953094 -416.020504)
				(mid 338.694014 -416.020504)
				(end 338.953094 -416.020504)
			)
		)
		(stroke
			(width 0)
			(type solid)
		)
		(fill yes)
		(layer "In11.Cu")
		(net "GND")
	)
	(gr_poly
		(pts
			(arc
				(start 338.953094 -414.752536)
				(mid 338.694014 -414.752536)
				(end 338.953094 -414.752536)
			)
		)
		(stroke
			(width 0)
			(type solid)
		)
		(fill yes)
		(layer "In11.Cu")
		(net "GND")
	)
	(gr_poly
		(pts
			(arc
				(start 339.038946 -412.84652)
				(mid 338.779866 -412.84652)
				(end 339.038946 -412.84652)
			)
		)
		(stroke
			(width 0)
			(type solid)
		)
		(fill yes)
		(layer "In11.Cu")
		(net "GND")
	)
	(gr_poly
		(pts
			(arc
				(start 340.126066 -412.84652)
				(mid 339.866986 -412.84652)
				(end 340.126066 -412.84652)
			)
		)
		(stroke
			(width 0)
			(type solid)
		)
		(fill yes)
		(layer "In11.Cu")
		(net "GND")
	)
	(gr_poly
		(pts
			(arc
				(start 340.211918 -416.020504)
				(mid 339.952838 -416.020504)
				(end 340.211918 -416.020504)
			)
		)
		(stroke
			(width 0)
			(type solid)
		)
		(fill yes)
		(layer "In11.Cu")
		(net "GND")
	)
	(gr_poly
		(pts
			(arc
				(start 340.211918 -414.752536)
				(mid 339.952838 -414.752536)
				(end 340.211918 -414.752536)
			)
		)
		(stroke
			(width 0)
			(type solid)
		)
		(fill yes)
		(layer "In11.Cu")
		(net "GND")
	)
	(gr_poly
		(pts
			(arc
				(start 340.484714 -413.480504)
				(mid 340.225634 -413.480504)
				(end 340.484714 -413.480504)
			)
		)
		(stroke
			(width 0)
			(type solid)
		)
		(fill yes)
		(layer "In11.Cu")
		(net "GND")
	)
	(gr_poly
		(pts
			(arc
				(start 340.484714 -412.212536)
				(mid 340.225634 -412.212536)
				(end 340.484714 -412.212536)
			)
		)
		(stroke
			(width 0)
			(type solid)
		)
		(fill yes)
		(layer "In11.Cu")
		(net "GND")
	)
	(gr_poly
		(pts
			(arc
				(start 340.570566 -415.38652)
				(mid 340.311486 -415.38652)
				(end 340.570566 -415.38652)
			)
		)
		(stroke
			(width 0)
			(type solid)
		)
		(fill yes)
		(layer "In11.Cu")
		(net "GND")
	)
	(gr_poly
		(pts
			(arc
				(start 341.657686 -415.38652)
				(mid 341.398606 -415.38652)
				(end 341.657686 -415.38652)
			)
		)
		(stroke
			(width 0)
			(type solid)
		)
		(fill yes)
		(layer "In11.Cu")
		(net "GND")
	)
	(gr_poly
		(pts
			(arc
				(start 341.743538 -413.480504)
				(mid 341.484458 -413.480504)
				(end 341.743538 -413.480504)
			)
		)
		(stroke
			(width 0)
			(type solid)
		)
		(fill yes)
		(layer "In11.Cu")
		(net "GND")
	)
	(gr_poly
		(pts
			(arc
				(start 341.743538 -412.212536)
				(mid 341.484458 -412.212536)
				(end 341.743538 -412.212536)
			)
		)
		(stroke
			(width 0)
			(type solid)
		)
		(fill yes)
		(layer "In11.Cu")
		(net "GND")
	)
	(gr_poly
		(pts
			(arc
				(start 342.016334 -416.020504)
				(mid 341.757254 -416.020504)
				(end 342.016334 -416.020504)
			)
		)
		(stroke
			(width 0)
			(type solid)
		)
		(fill yes)
		(layer "In11.Cu")
		(net "GND")
	)
	(gr_poly
		(pts
			(arc
				(start 342.016334 -414.752536)
				(mid 341.757254 -414.752536)
				(end 342.016334 -414.752536)
			)
		)
		(stroke
			(width 0)
			(type solid)
		)
		(fill yes)
		(layer "In11.Cu")
		(net "GND")
	)
	(gr_poly
		(pts
			(arc
				(start 342.102186 -412.84652)
				(mid 341.843106 -412.84652)
				(end 342.102186 -412.84652)
			)
		)
		(stroke
			(width 0)
			(type solid)
		)
		(fill yes)
		(layer "In11.Cu")
		(net "GND")
	)
	(gr_poly
		(pts
			(arc
				(start 343.189306 -412.84652)
				(mid 342.930226 -412.84652)
				(end 343.189306 -412.84652)
			)
		)
		(stroke
			(width 0)
			(type solid)
		)
		(fill yes)
		(layer "In11.Cu")
		(net "GND")
	)
	(gr_poly
		(pts
			(arc
				(start 343.275158 -416.020504)
				(mid 343.016078 -416.020504)
				(end 343.275158 -416.020504)
			)
		)
		(stroke
			(width 0)
			(type solid)
		)
		(fill yes)
		(layer "In11.Cu")
		(net "GND")
	)
	(gr_poly
		(pts
			(arc
				(start 343.275158 -414.752536)
				(mid 343.016078 -414.752536)
				(end 343.275158 -414.752536)
			)
		)
		(stroke
			(width 0)
			(type solid)
		)
		(fill yes)
		(layer "In11.Cu")
		(net "GND")
	)
	(gr_poly
		(pts
			(arc
				(start 343.547954 -413.480504)
				(mid 343.288874 -413.480504)
				(end 343.547954 -413.480504)
			)
		)
		(stroke
			(width 0)
			(type solid)
		)
		(fill yes)
		(layer "In11.Cu")
		(net "GND")
	)
	(gr_poly
		(pts
			(arc
				(start 343.547954 -412.212536)
				(mid 343.288874 -412.212536)
				(end 343.547954 -412.212536)
			)
		)
		(stroke
			(width 0)
			(type solid)
		)
		(fill yes)
		(layer "In11.Cu")
		(net "GND")
	)
	(gr_poly
		(pts
			(arc
				(start 343.633806 -415.38652)
				(mid 343.374726 -415.38652)
				(end 343.633806 -415.38652)
			)
		)
		(stroke
			(width 0)
			(type solid)
		)
		(fill yes)
		(layer "In11.Cu")
		(net "GND")
	)
	(gr_poly
		(pts
			(arc
				(start 344.720926 -415.38652)
				(mid 344.461846 -415.38652)
				(end 344.720926 -415.38652)
			)
		)
		(stroke
			(width 0)
			(type solid)
		)
		(fill yes)
		(layer "In11.Cu")
		(net "GND")
	)
	(gr_poly
		(pts
			(arc
				(start 344.806778 -413.480504)
				(mid 344.547698 -413.480504)
				(end 344.806778 -413.480504)
			)
		)
		(stroke
			(width 0)
			(type solid)
		)
		(fill yes)
		(layer "In11.Cu")
		(net "GND")
	)
	(gr_poly
		(pts
			(arc
				(start 344.806778 -412.212536)
				(mid 344.547698 -412.212536)
				(end 344.806778 -412.212536)
			)
		)
		(stroke
			(width 0)
			(type solid)
		)
		(fill yes)
		(layer "In11.Cu")
		(net "GND")
	)
	(gr_poly
		(pts
			(arc
				(start 345.079574 -416.020504)
				(mid 344.820494 -416.020504)
				(end 345.079574 -416.020504)
			)
		)
		(stroke
			(width 0)
			(type solid)
		)
		(fill yes)
		(layer "In11.Cu")
		(net "GND")
	)
	(gr_poly
		(pts
			(arc
				(start 345.079574 -414.752536)
				(mid 344.820494 -414.752536)
				(end 345.079574 -414.752536)
			)
		)
		(stroke
			(width 0)
			(type solid)
		)
		(fill yes)
		(layer "In11.Cu")
		(net "GND")
	)
	(gr_poly
		(pts
			(arc
				(start 345.165426 -412.84652)
				(mid 344.906346 -412.84652)
				(end 345.165426 -412.84652)
			)
		)
		(stroke
			(width 0)
			(type solid)
		)
		(fill yes)
		(layer "In11.Cu")
		(net "GND")
	)
	(gr_poly
		(pts
			(arc
				(start 346.252546 -412.84652)
				(mid 345.993466 -412.84652)
				(end 346.252546 -412.84652)
			)
		)
		(stroke
			(width 0)
			(type solid)
		)
		(fill yes)
		(layer "In11.Cu")
		(net "GND")
	)
	(gr_poly
		(pts
			(arc
				(start 346.338398 -416.020504)
				(mid 346.079318 -416.020504)
				(end 346.338398 -416.020504)
			)
		)
		(stroke
			(width 0)
			(type solid)
		)
		(fill yes)
		(layer "In11.Cu")
		(net "GND")
	)
	(gr_poly
		(pts
			(arc
				(start 346.338398 -414.752536)
				(mid 346.079318 -414.752536)
				(end 346.338398 -414.752536)
			)
		)
		(stroke
			(width 0)
			(type solid)
		)
		(fill yes)
		(layer "In11.Cu")
		(net "GND")
	)
	(gr_poly
		(pts
			(arc
				(start 346.611194 -413.480504)
				(mid 346.352114 -413.480504)
				(end 346.611194 -413.480504)
			)
		)
		(stroke
			(width 0)
			(type solid)
		)
		(fill yes)
		(layer "In11.Cu")
		(net "GND")
	)
	(gr_poly
		(pts
			(arc
				(start 346.611194 -412.212536)
				(mid 346.352114 -412.212536)
				(end 346.611194 -412.212536)
			)
		)
		(stroke
			(width 0)
			(type solid)
		)
		(fill yes)
		(layer "In11.Cu")
		(net "GND")
	)
	(gr_poly
		(pts
			(arc
				(start 346.697046 -415.38652)
				(mid 346.437966 -415.38652)
				(end 346.697046 -415.38652)
			)
		)
		(stroke
			(width 0)
			(type solid)
		)
		(fill yes)
		(layer "In11.Cu")
		(net "GND")
	)
	(gr_poly
		(pts
			(arc
				(start 347.784166 -415.38652)
				(mid 347.525086 -415.38652)
				(end 347.784166 -415.38652)
			)
		)
		(stroke
			(width 0)
			(type solid)
		)
		(fill yes)
		(layer "In11.Cu")
		(net "GND")
	)
	(gr_poly
		(pts
			(arc
				(start 347.870018 -413.480504)
				(mid 347.610938 -413.480504)
				(end 347.870018 -413.480504)
			)
		)
		(stroke
			(width 0)
			(type solid)
		)
		(fill yes)
		(layer "In11.Cu")
		(net "GND")
	)
	(gr_poly
		(pts
			(arc
				(start 347.870018 -412.212536)
				(mid 347.610938 -412.212536)
				(end 347.870018 -412.212536)
			)
		)
		(stroke
			(width 0)
			(type solid)
		)
		(fill yes)
		(layer "In11.Cu")
		(net "GND")
	)
	(gr_poly
		(pts
			(arc
				(start 348.142814 -416.020504)
				(mid 347.883734 -416.020504)
				(end 348.142814 -416.020504)
			)
		)
		(stroke
			(width 0)
			(type solid)
		)
		(fill yes)
		(layer "In11.Cu")
		(net "GND")
	)
	(gr_poly
		(pts
			(arc
				(start 348.142814 -414.752536)
				(mid 347.883734 -414.752536)
				(end 348.142814 -414.752536)
			)
		)
		(stroke
			(width 0)
			(type solid)
		)
		(fill yes)
		(layer "In11.Cu")
		(net "GND")
	)
	(gr_poly
		(pts
			(arc
				(start 348.228666 -412.84652)
				(mid 347.969586 -412.84652)
				(end 348.228666 -412.84652)
			)
		)
		(stroke
			(width 0)
			(type solid)
		)
		(fill yes)
		(layer "In11.Cu")
		(net "GND")
	)
	(gr_poly
		(pts
			(arc
				(start 349.31604 -412.84652)
				(mid 349.05696 -412.84652)
				(end 349.31604 -412.84652)
			)
		)
		(stroke
			(width 0)
			(type solid)
		)
		(fill yes)
		(layer "In11.Cu")
		(net "GND")
	)
	(gr_poly
		(pts
			(arc
				(start 349.401638 -416.020504)
				(mid 349.142558 -416.020504)
				(end 349.401638 -416.020504)
			)
		)
		(stroke
			(width 0)
			(type solid)
		)
		(fill yes)
		(layer "In11.Cu")
		(net "GND")
	)
	(gr_poly
		(pts
			(arc
				(start 349.401638 -414.752536)
				(mid 349.142558 -414.752536)
				(end 349.401638 -414.752536)
			)
		)
		(stroke
			(width 0)
			(type solid)
		)
		(fill yes)
		(layer "In11.Cu")
		(net "GND")
	)
	(gr_poly
		(pts
			(arc
				(start 349.674434 -413.480504)
				(mid 349.415354 -413.480504)
				(end 349.674434 -413.480504)
			)
		)
		(stroke
			(width 0)
			(type solid)
		)
		(fill yes)
		(layer "In11.Cu")
		(net "GND")
	)
	(gr_poly
		(pts
			(arc
				(start 349.674434 -412.212536)
				(mid 349.415354 -412.212536)
				(end 349.674434 -412.212536)
			)
		)
		(stroke
			(width 0)
			(type solid)
		)
		(fill yes)
		(layer "In11.Cu")
		(net "GND")
	)
	(gr_poly
		(pts
			(arc
				(start 349.760286 -415.38652)
				(mid 349.501206 -415.38652)
				(end 349.760286 -415.38652)
			)
		)
		(stroke
			(width 0)
			(type solid)
		)
		(fill yes)
		(layer "In11.Cu")
		(net "GND")
	)
	(gr_poly
		(pts
			(arc
				(start 350.847406 -415.38652)
				(mid 350.588326 -415.38652)
				(end 350.847406 -415.38652)
			)
		)
		(stroke
			(width 0)
			(type solid)
		)
		(fill yes)
		(layer "In11.Cu")
		(net "GND")
	)
	(gr_poly
		(pts
			(arc
				(start 350.933258 -413.480504)
				(mid 350.674178 -413.480504)
				(end 350.933258 -413.480504)
			)
		)
		(stroke
			(width 0)
			(type solid)
		)
		(fill yes)
		(layer "In11.Cu")
		(net "GND")
	)
	(gr_poly
		(pts
			(arc
				(start 350.933258 -412.212536)
				(mid 350.674178 -412.212536)
				(end 350.933258 -412.212536)
			)
		)
		(stroke
			(width 0)
			(type solid)
		)
		(fill yes)
		(layer "In11.Cu")
		(net "GND")
	)
	(gr_poly
		(pts
			(arc
				(start 351.206054 -416.020504)
				(mid 350.946974 -416.020504)
				(end 351.206054 -416.020504)
			)
		)
		(stroke
			(width 0)
			(type solid)
		)
		(fill yes)
		(layer "In11.Cu")
		(net "GND")
	)
	(gr_poly
		(pts
			(arc
				(start 351.206054 -414.752536)
				(mid 350.946974 -414.752536)
				(end 351.206054 -414.752536)
			)
		)
		(stroke
			(width 0)
			(type solid)
		)
		(fill yes)
		(layer "In11.Cu")
		(net "GND")
	)
	(gr_poly
		(pts
			(arc
				(start 351.291906 -412.84652)
				(mid 351.032826 -412.84652)
				(end 351.291906 -412.84652)
			)
		)
		(stroke
			(width 0)
			(type solid)
		)
		(fill yes)
		(layer "In11.Cu")
		(net "GND")
	)
	(gr_poly
		(pts
			(arc
				(start 352.464878 -416.020504)
				(mid 352.205798 -416.020504)
				(end 352.464878 -416.020504)
			)
		)
		(stroke
			(width 0)
			(type solid)
		)
		(fill yes)
		(layer "In11.Cu")
		(net "GND")
	)
	(gr_poly
		(pts
			(arc
				(start 352.464878 -414.752536)
				(mid 352.205798 -414.752536)
				(end 352.464878 -414.752536)
			)
		)
		(stroke
			(width 0)
			(type solid)
		)
		(fill yes)
		(layer "In11.Cu")
		(net "GND")
	)
	(gr_poly
		(pts
			(arc
				(start 352.823526 -415.38652)
				(mid 352.564446 -415.38652)
				(end 352.823526 -415.38652)
			)
		)
		(stroke
			(width 0)
			(type solid)
		)
		(fill yes)
		(layer "In11.Cu")
		(net "GND")
	)
	(gr_poly
		(pts
			(xy 229.6795 -435.74208) (xy 229.6795 -422.049194) (xy 234.763056 -416.965638) (xy 272.06448 -416.965638)
			(xy 280.05024 -408.979878)
			(arc
				(start 280.05024 -394.963396)
				(mid 280.046339 -394.943873)
				(end 280.035254 -394.927328)
			)
			(arc
				(start 279.651206 -394.54328)
				(mid 279.634672 -394.532169)
				(end 279.615138 -394.528294)
			)
			(xy 278.21382 -394.528294) (xy 241.711734 -394.528294) (xy 240.424208 -394.528294) (xy 239.91189 -395.040612)
			(xy 239.91189 -404.086822) (xy 239.91189 -405.227536) (xy 239.91189 -405.609298) (xy 234.87634 -410.644848)
			(xy 229.69855 -410.644848) (xy 229.676198 -410.6672) (xy 227.067872 -413.275526) (xy 196.769482 -413.275526)
			(xy 196.26072 -413.784288) (xy 196.26072 -414.072832) (xy 196.26072 -421.757602)
			(arc
				(start 206.039974 -431.536856)
				(mid 206.051085 -431.55339)
				(end 206.05496 -431.572924)
			)
			(xy 206.05496 -435.09946) (xy 207.43418 -436.47868) (xy 228.9429 -436.47868)
		)
		(stroke
			(width 0)
			(type solid)
		)
		(fill yes)
		(layer "In11.Cu")
		(net "P12V_PSU")
	)
	(gr_poly
		(pts
			(arc
				(start 81.154778 -2.750312)
				(mid 81.182917 -2.732466)
				(end 81.193894 -2.701036)
			)
			(arc
				(start 81.193894 -0.5588)
				(mid 81.179015 -0.522879)
				(end 81.143094 -0.508)
			)
			(arc
				(start 13.660882 -0.508)
				(mid 13.624961 -0.522879)
				(end 13.610082 -0.5588)
			)
			(arc
				(start 13.610082 -2.701036)
				(mid 13.621129 -2.732411)
				(end 13.649198 -2.750312)
			)
			(xy 13.762482 -2.77749) (xy 13.794486 -2.762504)
			(arc
				(start 13.80236 -2.746756)
				(mid 13.928356 -2.557713)
				(end 14.095984 -2.404364)
			)
			(xy 14.11732 -2.363216) (xy 14.11732 -1.014984) (xy 80.686656 -1.014984) (xy 80.686656 -2.363216)
			(arc
				(start 80.707992 -2.404364)
				(mid 80.875659 -2.55768)
				(end 81.001616 -2.746756)
			)
			(xy 81.00949 -2.762504) (xy 81.041494 -2.77749)
		)
		(stroke
			(width 0)
			(type solid)
		)
		(fill yes)
		(layer "In11.Cu")
		(net "GND")
	)
	(gr_poly
		(pts
			(arc
				(start 194.154806 -8.03021)
				(mid 194.182945 -8.012364)
				(end 194.193922 -7.980934)
			)
			(arc
				(start 194.193922 -5.838698)
				(mid 194.179043 -5.802777)
				(end 194.143122 -5.787898)
			)
			(arc
				(start 126.66091 -5.787898)
				(mid 126.624989 -5.802777)
				(end 126.61011 -5.838698)
			)
			(arc
				(start 126.61011 -7.980934)
				(mid 126.621157 -8.012309)
				(end 126.649226 -8.03021)
			)
			(xy 126.76251 -8.057388) (xy 126.794514 -8.042402)
			(arc
				(start 126.802388 -8.026654)
				(mid 126.928384 -7.837611)
				(end 127.096012 -7.684262)
			)
			(xy 127.117348 -7.643114) (xy 127.117348 -6.295136) (xy 193.686684 -6.295136) (xy 193.686684 -7.643114)
			(arc
				(start 193.70802 -7.684262)
				(mid 193.875687 -7.837578)
				(end 194.001644 -8.026654)
			)
			(xy 194.009518 -8.042402) (xy 194.041522 -8.057388)
		)
		(stroke
			(width 0)
			(type solid)
		)
		(fill yes)
		(layer "In11.Cu")
		(net "GND")
	)
	(gr_poly
		(pts
			(arc
				(start 455.654918 -2.75082)
				(mid 455.683057 -2.732974)
				(end 455.694034 -2.701544)
			)
			(arc
				(start 455.694034 -0.5588)
				(mid 455.679155 -0.522879)
				(end 455.643234 -0.508)
			)
			(arc
				(start 388.160768 -0.508)
				(mid 388.124847 -0.522879)
				(end 388.109968 -0.5588)
			)
			(arc
				(start 388.109968 -2.701036)
				(mid 388.121015 -2.732411)
				(end 388.149084 -2.750312)
			)
			(xy 388.262368 -2.77749) (xy 388.294372 -2.762504)
			(arc
				(start 388.302246 -2.746756)
				(mid 388.428345 -2.557672)
				(end 388.596124 -2.404364)
			)
			(arc
				(start 388.596124 -2.404364)
				(mid 388.610195 -2.388884)
				(end 388.616952 -2.369058)
			)
			(xy 388.616952 -1.014984) (xy 455.186796 -1.014984) (xy 455.186796 -2.36347)
			(arc
				(start 455.208132 -2.404618)
				(mid 455.3758 -2.558068)
				(end 455.501756 -2.747264)
			)
			(xy 455.50963 -2.763012) (xy 455.54138 -2.777744)
		)
		(stroke
			(width 0)
			(type solid)
		)
		(fill yes)
		(layer "In11.Cu")
		(net "GND")
	)
	(gr_poly
		(pts
			(arc
				(start 7.548626 -137.9601)
				(mid 7.568149 -137.956199)
				(end 7.584694 -137.945114)
			)
			(arc
				(start 7.679944 -137.849864)
				(mid 7.691055 -137.83333)
				(end 7.69493 -137.813796)
			)
			(xy 7.69493 -135.794496) (xy 7.67461 -135.767572)
			(arc
				(start 7.6581 -135.762746)
				(mid 7.381151 -135.39597)
				(end 7.6581 -135.029194)
			)
			(xy 7.67461 -135.024368) (xy 7.69493 -134.997444)
			(arc
				(start 7.69493 -132.962396)
				(mid 7.691029 -132.942873)
				(end 7.679944 -132.926328)
			)
			(arc
				(start 7.584694 -132.831078)
				(mid 7.56816 -132.819967)
				(end 7.548626 -132.816092)
			)
			(arc
				(start 4.00177 -132.816092)
				(mid 3.982247 -132.819993)
				(end 3.965702 -132.831078)
			)
			(arc
				(start 3.870452 -132.926328)
				(mid 3.859341 -132.942862)
				(end 3.855466 -132.962396)
			)
			(arc
				(start 3.855466 -137.813796)
				(mid 3.859367 -137.833319)
				(end 3.870452 -137.849864)
			)
			(arc
				(start 3.965702 -137.945114)
				(mid 3.982236 -137.956225)
				(end 4.00177 -137.9601)
			)
		)
		(stroke
			(width 0)
			(type solid)
		)
		(fill yes)
		(layer "In11.Cu")
		(net "GND")
	)
	(gr_poly
		(pts
			(xy 108.436918 -24.151082) (xy 108.6612 -23.9268) (xy 108.6612 -20.1422) (xy 108.3564 -19.8374) (xy 105.204768 -19.8374)
			(xy 104.6226 -19.8374) (xy 103.8352 -20.6248) (xy 103.8352 -24.54148) (xy 104.799891 -24.54148) (xy 104.803956 -24.485932)
			(xy 104.816066 -24.431567) (xy 104.835963 -24.379546) (xy 104.863222 -24.330975) (xy 104.897262 -24.286892)
			(xy 104.937359 -24.248234) (xy 104.982656 -24.215826) (xy 105.03219 -24.190359) (xy 105.084904 -24.172376)
			(xy 105.139674 -24.162259) (xy 105.195333 -24.160225) (xy 105.250696 -24.166317) (xy 105.304582 -24.180404)
			(xy 105.355842 -24.202188) (xy 105.403385 -24.231202) (xy 105.446196 -24.26683) (xy 105.483363 -24.308311)
			(xy 105.514095 -24.354762) (xy 105.537736 -24.405193) (xy 105.553782 -24.458528) (xy 105.561892 -24.513632)
			(xy 105.5624 -24.54148) (xy 106.273091 -24.54148) (xy 106.277156 -24.485932) (xy 106.289266 -24.431567)
			(xy 106.309163 -24.379546) (xy 106.336422 -24.330975) (xy 106.370462 -24.286892) (xy 106.410559 -24.248234)
			(xy 106.455856 -24.215826) (xy 106.50539 -24.190359) (xy 106.558104 -24.172376) (xy 106.612874 -24.162259)
			(xy 106.668533 -24.160225) (xy 106.723896 -24.166317) (xy 106.777782 -24.180404) (xy 106.829042 -24.202188)
			(xy 106.876585 -24.231202) (xy 106.919396 -24.26683) (xy 106.956563 -24.308311) (xy 106.987295 -24.354762)
			(xy 107.010936 -24.405193) (xy 107.026982 -24.458528) (xy 107.035092 -24.513632) (xy 107.0356 -24.54148)
			(xy 107.035092 -24.569328) (xy 107.026982 -24.624432) (xy 107.010936 -24.677767) (xy 106.987295 -24.728198)
			(xy 106.956563 -24.774649) (xy 106.919396 -24.81613) (xy 106.876585 -24.851758) (xy 106.829042 -24.880772)
			(xy 106.777782 -24.902556) (xy 106.723896 -24.916643) (xy 106.668533 -24.922735) (xy 106.612874 -24.920701)
			(xy 106.558104 -24.910584) (xy 106.50539 -24.892601) (xy 106.455856 -24.867134) (xy 106.410559 -24.834726)
			(xy 106.370462 -24.796068) (xy 106.336422 -24.751985) (xy 106.309163 -24.703414) (xy 106.289266 -24.651393)
			(xy 106.277156 -24.597028) (xy 106.273091 -24.54148) (xy 105.5624 -24.54148) (xy 105.561892 -24.569328)
			(xy 105.553782 -24.624432) (xy 105.537736 -24.677767) (xy 105.514095 -24.728198) (xy 105.483363 -24.774649)
			(xy 105.446196 -24.81613) (xy 105.403385 -24.851758) (xy 105.355842 -24.880772) (xy 105.304582 -24.902556)
			(xy 105.250696 -24.916643) (xy 105.195333 -24.922735) (xy 105.139674 -24.920701) (xy 105.084904 -24.910584)
			(xy 105.03219 -24.892601) (xy 104.982656 -24.867134) (xy 104.937359 -24.834726) (xy 104.897262 -24.796068)
			(xy 104.863222 -24.751985) (xy 104.835963 -24.703414) (xy 104.816066 -24.651393) (xy 104.803956 -24.597028)
			(xy 104.799891 -24.54148) (xy 103.8352 -24.54148) (xy 103.8352 -25.3746) (xy 104.0384 -25.5778) (xy 107.0102 -25.5778)
		)
		(stroke
			(width 0)
			(type solid)
		)
		(fill yes)
		(layer "In11.Cu")
		(net "GND")
	)
	(gr_poly
		(pts
			(arc
				(start 439.789062 -390.995662)
				(mid 439.815053 -391.009668)
				(end 439.844434 -391.006838)
			)
			(xy 439.858912 -391.000742) (xy 439.875676 -390.975596)
			(arc
				(start 439.875676 -388.124192)
				(mid 439.871892 -388.104698)
				(end 439.860944 -388.088124)
			)
			(arc
				(start 438.413144 -386.640324)
				(mid 438.402218 -386.623878)
				(end 438.398412 -386.60451)
			)
			(arc
				(start 438.398412 -377.24715)
				(mid 438.402245 -377.227793)
				(end 438.413144 -377.211336)
			)
			(arc
				(start 438.681114 -376.943112)
				(mid 438.692176 -376.926695)
				(end 438.6961 -376.907298)
			)
			(xy 438.6961 -376.89536)
			(arc
				(start 442.530484 -373.060976)
				(mid 442.547018 -373.049865)
				(end 442.566552 -373.04599)
			)
			(arc
				(start 451.693788 -373.04599)
				(mid 451.713311 -373.042089)
				(end 451.729856 -373.031004)
			)
			(arc
				(start 452.353934 -372.406926)
				(mid 452.365045 -372.390392)
				(end 452.36892 -372.370858)
			)
			(arc
				(start 452.36892 -371.584982)
				(mid 452.365019 -371.565459)
				(end 452.353934 -371.548914)
			)
			(arc
				(start 451.924166 -371.119146)
				(mid 451.907632 -371.108035)
				(end 451.888098 -371.10416)
			)
			(arc
				(start 448.599306 -371.10416)
				(mid 448.574562 -371.110594)
				(end 448.556126 -371.12829)
			)
			(arc
				(start 448.556126 -371.12829)
				(mid 448.123818 -371.368824)
				(end 447.69151 -371.12829)
			)
			(arc
				(start 447.69151 -371.12829)
				(mid 447.673051 -371.110635)
				(end 447.64833 -371.10416)
			)
			(arc
				(start 441.130182 -371.10416)
				(mid 441.110659 -371.108061)
				(end 441.094114 -371.119146)
			)
			(arc
				(start 436.732426 -375.480834)
				(mid 436.721315 -375.497368)
				(end 436.71744 -375.516902)
			)
			(arc
				(start 436.71744 -382.060958)
				(mid 436.720586 -382.078557)
				(end 436.729632 -382.093978)
			)
			(arc
				(start 436.729632 -382.093978)
				(mid 437.496572 -383.393447)
				(end 437.763412 -384.87858)
			)
			(arc
				(start 437.763412 -384.87858)
				(mid 437.496588 -386.363719)
				(end 436.729632 -387.663182)
			)
			(xy 436.72379 -387.67004) (xy 436.71744 -387.687058)
			(arc
				(start 436.71744 -387.902958)
				(mid 436.721341 -387.922481)
				(end 436.732426 -387.939026)
			)
		)
		(stroke
			(width 0)
			(type solid)
		)
		(fill yes)
		(layer "In11.Cu")
		(net "P5V_AUX")
	)
	(gr_poly
		(pts
			(xy 125.505718 -31.1658) (xy 125.515787 -31.165373) (xy 125.534386 -31.157654) (xy 125.541786 -31.150814)
			(xy 125.918214 -30.774386) (xy 125.925609 -30.767532) (xy 125.944208 -30.75979) (xy 125.954282 -30.7594)
			(xy 127.156718 -30.7594) (xy 127.166787 -30.758973) (xy 127.185386 -30.751254) (xy 127.192786 -30.744414)
			(xy 128.026414 -29.910786) (xy 128.033268 -29.903391) (xy 128.04101 -29.884792) (xy 128.0414 -29.874718)
			(xy 128.0414 -28.682696) (xy 128.041074 -28.6738) (xy 128.034999 -28.65708) (xy 128.023555 -28.643459)
			(xy 128.016 -28.638754) (xy 127.927862 -28.5877) (xy 127.900938 -28.5877) (xy 127.889 -28.594558)
			(xy 127.867202 -28.606699) (xy 127.821109 -28.625802) (xy 127.772916 -28.638722) (xy 127.723448 -28.645238)
			(xy 127.6985 -28.645612) (xy 127.671248 -28.645126) (xy 127.6173 -28.63737) (xy 127.565005 -28.622014)
			(xy 127.515427 -28.599373) (xy 127.469576 -28.569906) (xy 127.428386 -28.534214) (xy 127.392694 -28.493024)
			(xy 127.363227 -28.447173) (xy 127.340586 -28.397595) (xy 127.32523 -28.3453) (xy 127.317474 -28.291352)
			(xy 127.317474 -28.236848) (xy 127.32523 -28.1829) (xy 127.340586 -28.130605) (xy 127.363227 -28.081027)
			(xy 127.392694 -28.035176) (xy 127.428386 -27.993986) (xy 127.469576 -27.958294) (xy 127.515427 -27.928827)
			(xy 127.565005 -27.906186) (xy 127.6173 -27.89083) (xy 127.671248 -27.883074) (xy 127.6985 -27.882596)
			(xy 127.723443 -27.883026) (xy 127.772899 -27.889566) (xy 127.821083 -27.902484) (xy 127.867179 -27.92156)
			(xy 127.889 -27.93365) (xy 127.900938 -27.940508) (xy 127.927862 -27.940508) (xy 128.016 -27.889454)
			(xy 128.023493 -27.884675) (xy 128.034908 -27.871071) (xy 128.041 -27.85439) (xy 128.0414 -27.845512)
			(xy 128.0414 -27.072082) (xy 128.040973 -27.062013) (xy 128.033254 -27.043414) (xy 128.026414 -27.036014)
			(xy 127.548386 -26.557986) (xy 127.540991 -26.551132) (xy 127.522392 -26.54339) (xy 127.512318 -26.543)
			(xy 123.490482 -26.543) (xy 123.480413 -26.543427) (xy 123.461814 -26.551146) (xy 123.454414 -26.557986)
			(xy 122.468386 -27.544014) (xy 122.461532 -27.551409) (xy 122.45379 -27.570008) (xy 122.4534 -27.580082)
			(xy 122.4534 -29.530294) (xy 126.789178 -29.530294) (xy 126.793249 -29.474672) (xy 126.805375 -29.420235)
			(xy 126.825298 -29.368144) (xy 126.852594 -29.319509) (xy 126.88668 -29.275366) (xy 126.926829 -29.236657)
			(xy 126.972187 -29.204206) (xy 127.021787 -29.178705) (xy 127.074571 -29.160698) (xy 127.129414 -29.150568)
			(xy 127.185148 -29.148531) (xy 127.240585 -29.154631) (xy 127.294542 -29.168737) (xy 127.345871 -29.190549)
			(xy 127.393477 -29.219603) (xy 127.436345 -29.255278) (xy 127.473562 -29.296815) (xy 127.504335 -29.343328)
			(xy 127.528007 -29.393825) (xy 127.544075 -29.447232) (xy 127.552195 -29.502408) (xy 127.552704 -29.530294)
			(xy 127.552195 -29.55818) (xy 127.544075 -29.613356) (xy 127.528007 -29.666763) (xy 127.504335 -29.71726)
			(xy 127.473562 -29.763773) (xy 127.436345 -29.80531) (xy 127.393477 -29.840985) (xy 127.345871 -29.870039)
			(xy 127.294542 -29.891851) (xy 127.240585 -29.905957) (xy 127.185148 -29.912057) (xy 127.129414 -29.91002)
			(xy 127.074571 -29.89989) (xy 127.021787 -29.881883) (xy 126.972187 -29.856382) (xy 126.926829 -29.823931)
			(xy 126.88668 -29.785222) (xy 126.852594 -29.741079) (xy 126.825298 -29.692444) (xy 126.805375 -29.640353)
			(xy 126.793249 -29.585916) (xy 126.789178 -29.530294) (xy 122.4534 -29.530294) (xy 122.4534 -30.255718)
			(xy 122.453827 -30.265787) (xy 122.461546 -30.284386) (xy 122.468386 -30.291786) (xy 123.327414 -31.150814)
			(xy 123.334809 -31.157668) (xy 123.353408 -31.16541) (xy 123.363482 -31.1658)
		)
		(stroke
			(width 0)
			(type solid)
		)
		(fill yes)
		(layer "In11.Cu")
		(net "GND")
	)
	(gr_poly
		(pts
			(arc
				(start 124.102114 -12.795504)
				(mid 126.234222 -11.912198)
				(end 127.117348 -9.780016)
			)
			(arc
				(start 127.117348 -9.256776)
				(mid 127.111697 -9.233491)
				(end 127.096012 -9.215374)
			)
			(arc
				(start 127.096012 -9.215374)
				(mid 126.928345 -9.062058)
				(end 126.802388 -8.872982)
			)
			(xy 126.794514 -8.857234) (xy 126.76251 -8.842248)
			(arc
				(start 126.649226 -8.869426)
				(mid 126.621087 -8.887272)
				(end 126.61011 -8.918702)
			)
			(arc
				(start 126.61011 -9.780016)
				(mid 125.875535 -11.553437)
				(end 124.102114 -12.288012)
			)
			(arc
				(start 83.70189 -12.288012)
				(mid 81.928469 -11.553437)
				(end 81.193894 -9.780016)
			)
			(arc
				(start 81.193894 -3.638804)
				(mid 81.182847 -3.607429)
				(end 81.154778 -3.589528)
			)
			(xy 81.041494 -3.56235) (xy 81.00949 -3.577336)
			(arc
				(start 81.001616 -3.593084)
				(mid 80.87562 -3.782127)
				(end 80.707992 -3.935476)
			)
			(arc
				(start 80.707992 -3.935476)
				(mid 80.692292 -3.953586)
				(end 80.686656 -3.976878)
			)
			(arc
				(start 80.686656 -9.780524)
				(mid 81.569887 -11.912452)
				(end 83.70189 -12.795504)
			)
		)
		(stroke
			(width 0)
			(type solid)
		)
		(fill yes)
		(layer "In11.Cu")
		(net "GND")
	)
	(gr_poly
		(pts
			(xy 201.178922 -32.19196) (xy 201.18899 -32.191532) (xy 201.207584 -32.183807) (xy 201.21499 -32.176974)
			(xy 202.558904 -30.83306) (xy 202.565744 -30.825659) (xy 202.573463 -30.807061) (xy 202.57389 -30.796992)
			(xy 202.57389 -29.589984) (xy 202.573464 -29.579915) (xy 202.565744 -29.561316) (xy 202.558904 -29.553916)
			(xy 197.780148 -24.77516) (xy 197.773303 -24.767762) (xy 197.765575 -24.749163) (xy 197.765162 -24.739092)
			(xy 197.765162 -16.100552) (xy 197.764729 -16.090486) (xy 197.756998 -16.071898) (xy 197.750176 -16.064484)
			(xy 194.126612 -12.44092) (xy 194.1195 -12.433554) (xy 194.100704 -12.425934) (xy 191.947038 -12.425934)
			(xy 191.936974 -12.426369) (xy 191.918389 -12.434103) (xy 191.91097 -12.44092) (xy 191.253872 -13.098018)
			(xy 191.246506 -13.10513) (xy 191.238886 -13.123926) (xy 191.238886 -14.481556) (xy 191.239319 -14.491622)
			(xy 191.247046 -14.510213) (xy 191.253872 -14.517624) (xy 191.567308 -14.83106) (xy 191.574144 -14.838462)
			(xy 191.581856 -14.85706) (xy 191.582294 -14.867128) (xy 191.582294 -18.150586) (xy 191.582732 -18.160649)
			(xy 191.590468 -18.179232) (xy 191.59728 -18.186654) (xy 192.552066 -19.14144) (xy 195.064632 -19.14144)
			(xy 195.068703 -19.085818) (xy 195.080829 -19.031381) (xy 195.100752 -18.97929) (xy 195.128048 -18.930655)
			(xy 195.162134 -18.886512) (xy 195.202283 -18.847803) (xy 195.247641 -18.815352) (xy 195.297241 -18.789851)
			(xy 195.350025 -18.771844) (xy 195.404868 -18.761714) (xy 195.460602 -18.759677) (xy 195.516039 -18.765777)
			(xy 195.569996 -18.779883) (xy 195.621325 -18.801695) (xy 195.668931 -18.830749) (xy 195.711799 -18.866424)
			(xy 195.749016 -18.907961) (xy 195.779789 -18.954474) (xy 195.803461 -19.004971) (xy 195.819529 -19.058378)
			(xy 195.827649 -19.113554) (xy 195.828158 -19.14144) (xy 195.827649 -19.169326) (xy 195.819529 -19.224502)
			(xy 195.803461 -19.277909) (xy 195.779789 -19.328406) (xy 195.749016 -19.374919) (xy 195.711799 -19.416456)
			(xy 195.668931 -19.452131) (xy 195.621325 -19.481185) (xy 195.569996 -19.502997) (xy 195.516039 -19.517103)
			(xy 195.460602 -19.523203) (xy 195.404868 -19.521166) (xy 195.350025 -19.511036) (xy 195.297241 -19.493029)
			(xy 195.247641 -19.467528) (xy 195.202283 -19.435077) (xy 195.162134 -19.396368) (xy 195.128048 -19.352225)
			(xy 195.100752 -19.30359) (xy 195.080829 -19.251499) (xy 195.068703 -19.197062) (xy 195.064632 -19.14144)
			(xy 192.552066 -19.14144) (xy 193.251582 -19.840956) (xy 193.258421 -19.848357) (xy 193.266138 -19.866955)
			(xy 193.266568 -19.877024) (xy 193.266568 -23.263098) (xy 193.26699 -23.273169) (xy 193.2747 -23.291777)
			(xy 193.281554 -23.299166) (xy 193.738754 -23.75662) (xy 193.765909 -23.784522) (xy 193.814482 -23.845375)
			(xy 193.855939 -23.911283) (xy 193.889757 -23.981417) (xy 193.915511 -24.054896) (xy 193.932878 -24.130796)
			(xy 193.94164 -24.208163) (xy 193.942208 -24.247094) (xy 193.942208 -25.54351) (xy 193.94167 -25.582443)
			(xy 193.932923 -25.659817) (xy 193.915564 -25.735724) (xy 193.88981 -25.809208) (xy 193.855986 -25.879345)
			(xy 193.814517 -25.945251) (xy 193.765927 -26.006096) (xy 193.738754 -26.033984) (xy 193.59753 -26.175462)
			(xy 193.587501 -26.186181) (xy 193.573509 -26.211974) (xy 193.567424 -26.240679) (xy 193.569746 -26.26993)
			(xy 193.580285 -26.297315) (xy 193.598171 -26.320576) (xy 193.609722 -26.32964) (xy 193.643556 -26.354654)
			(xy 193.706842 -26.410111) (xy 193.764608 -26.471297) (xy 193.816338 -26.537665) (xy 193.861568 -26.608621)
			(xy 193.899895 -26.683533) (xy 193.930976 -26.761729) (xy 193.954534 -26.842511) (xy 193.970356 -26.925156)
			(xy 193.978303 -27.008927) (xy 193.978784 -27.051) (xy 193.97826 -27.094536) (xy 193.969766 -27.181192)
			(xy 193.952848 -27.266605) (xy 193.927669 -27.349957) (xy 193.894469 -27.430451) (xy 193.853566 -27.507317)
			(xy 193.805351 -27.579821) (xy 193.750286 -27.647269) (xy 193.688895 -27.709017) (xy 193.621768 -27.764473)
			(xy 193.549545 -27.813107) (xy 193.472917 -27.854455) (xy 193.392617 -27.888121) (xy 193.35115 -27.901392)
			(xy 193.334894 -27.906218) (xy 193.315336 -27.932888) (xy 193.315336 -28.970224) (xy 193.315764 -28.980292)
			(xy 193.323489 -28.998886) (xy 193.330322 -29.006292) (xy 196.501004 -32.176974) (xy 196.508402 -32.183823)
			(xy 196.527 -32.19156) (xy 196.537072 -32.19196)
		)
		(stroke
			(width 0)
			(type solid)
		)
		(fill yes)
		(layer "In11.Cu")
		(net "P12V_SCM")
	)
	(gr_poly
		(pts
			(xy 3.015488 -343.130632)
			(arc
				(start 3.015488 -81.32826)
				(mid 2.785816 -80.174473)
				(end 2.132076 -79.196438)
			)
			(arc
				(start 1.303528 -78.36789)
				(mid 1.090411 -78.048655)
				(end 1.015492 -77.672184)
			)
			(arc
				(start 1.015492 -13.780008)
				(mid 1.303847 -13.083859)
				(end 1.999996 -12.795504)
			)
			(arc
				(start 11.102086 -12.795504)
				(mid 13.234194 -11.912198)
				(end 14.11732 -9.780016)
			)
			(arc
				(start 14.11732 -3.98907)
				(mid 14.115908 -3.977177)
				(end 14.111732 -3.965956)
			)
			(xy 14.098778 -3.94081) (xy 14.091412 -3.932174)
			(arc
				(start 14.086332 -3.928618)
				(mid 13.924474 -3.77767)
				(end 13.80236 -3.593084)
			)
			(xy 13.794232 -3.577082) (xy 13.762482 -3.56235)
			(arc
				(start 13.649198 -3.589274)
				(mid 13.62338 -3.604404)
				(end 13.61059 -3.631438)
			)
			(xy 13.610082 -3.638804)
			(arc
				(start 13.610082 -9.780016)
				(mid 12.875507 -11.553437)
				(end 11.102086 -12.288012)
			)
			(arc
				(start 1.999996 -12.288012)
				(mid 0.944996 -12.725008)
				(end 0.508 -13.780008)
			)
			(arc
				(start 0.508 -77.67193)
				(mid 0.621601 -78.242658)
				(end 0.94488 -78.726538)
			)
			(arc
				(start 1.773428 -79.555086)
				(mid 2.317047 -80.368624)
				(end 2.507996 -81.32826)
			)
			(xy 2.507996 -343.37498) (xy 2.558796 -343.42578) (xy 2.72034 -343.42578)
		)
		(stroke
			(width 0)
			(type solid)
		)
		(fill yes)
		(layer "In11.Cu")
		(net "GND")
	)
	(gr_poly
		(pts
			(arc
				(start 467.792054 -82.82813)
				(mid 467.983012 -81.868498)
				(end 468.526622 -81.054956)
			)
			(arc
				(start 470.85504 -78.726538)
				(mid 471.178373 -78.242681)
				(end 471.29192 -77.67193)
			)
			(arc
				(start 471.29192 -13.780008)
				(mid 470.854924 -12.725008)
				(end 469.799924 -12.288012)
			)
			(arc
				(start 458.20203 -12.288012)
				(mid 456.428609 -11.553437)
				(end 455.694034 -9.780016)
			)
			(xy 455.694034 -3.638296)
			(arc
				(start 455.693526 -3.63093)
				(mid 455.680691 -3.603937)
				(end 455.654918 -3.588766)
			)
			(xy 455.541634 -3.561842) (xy 455.509884 -3.576574) (xy 455.509884 -3.576828) (xy 455.50963 -3.576828)
			(arc
				(start 455.501756 -3.592576)
				(mid 455.377933 -3.779283)
				(end 455.213466 -3.931412)
			)
			(xy 455.212704 -3.93192)
			(arc
				(start 455.208132 -3.935222)
				(mid 455.192432 -3.953332)
				(end 455.186796 -3.976624)
			)
			(arc
				(start 455.186796 -9.780524)
				(mid 456.070027 -11.912452)
				(end 458.20203 -12.795504)
			)
			(arc
				(start 469.799924 -12.795504)
				(mid 470.496073 -13.083859)
				(end 470.784428 -13.780008)
			)
			(arc
				(start 470.784428 -77.672184)
				(mid 470.70959 -78.048688)
				(end 470.496392 -78.36789)
			)
			(arc
				(start 468.167974 -80.696308)
				(mid 467.514407 -81.674395)
				(end 467.284816 -82.82813)
			)
			(arc
				(start 467.284816 -357.040688)
				(mid 467.554494 -357.44994)
				(end 467.792054 -357.878634)
			)
		)
		(stroke
			(width 0)
			(type solid)
		)
		(fill yes)
		(layer "In11.Cu")
		(net "GND")
	)
	(gr_poly
		(pts
			(arc
				(start 2.539238 -156.913326)
				(mid 2.568748 -156.916417)
				(end 2.594864 -156.902404)
			)
			(arc
				(start 3.000502 -156.496766)
				(mid 3.011613 -156.480232)
				(end 3.015488 -156.460698)
			)
			(arc
				(start 3.015488 -81.32826)
				(mid 2.785816 -80.174473)
				(end 2.132076 -79.196438)
			)
			(arc
				(start 1.303528 -78.36789)
				(mid 1.090411 -78.048655)
				(end 1.015492 -77.672184)
			)
			(arc
				(start 1.015492 -13.780008)
				(mid 1.303847 -13.083859)
				(end 1.999996 -12.795504)
			)
			(arc
				(start 11.102086 -12.795504)
				(mid 13.234194 -11.912198)
				(end 14.11732 -9.780016)
			)
			(arc
				(start 14.11732 -3.976878)
				(mid 14.111669 -3.953593)
				(end 14.095984 -3.935476)
			)
			(arc
				(start 14.095984 -3.935476)
				(mid 13.928317 -3.78216)
				(end 13.80236 -3.593084)
			)
			(xy 13.794486 -3.577336) (xy 13.762482 -3.56235)
			(arc
				(start 13.649198 -3.589528)
				(mid 13.621059 -3.607374)
				(end 13.610082 -3.638804)
			)
			(arc
				(start 13.610082 -9.780016)
				(mid 12.875507 -11.553437)
				(end 11.102086 -12.288012)
			)
			(arc
				(start 1.999996 -12.288012)
				(mid 0.944996 -12.725008)
				(end 0.508 -13.780008)
			)
			(arc
				(start 0.508 -77.67193)
				(mid 0.621601 -78.242658)
				(end 0.94488 -78.726538)
			)
			(arc
				(start 1.773428 -79.555086)
				(mid 2.317047 -80.368624)
				(end 2.507996 -81.32826)
			)
			(arc
				(start 2.507996 -156.86659)
				(mid 2.516603 -156.894629)
				(end 2.539238 -156.913326)
			)
		)
		(stroke
			(width 0)
			(type solid)
		)
		(fill yes)
		(layer "In11.Cu")
		(net "GND")
	)
	(gr_poly
		(pts
			(xy 450.556884 -431.661824) (xy 450.566934 -431.661318) (xy 450.585494 -431.653595) (xy 450.592952 -431.646838)
			(xy 453.193912 -429.045878) (xy 453.200765 -429.038483) (xy 453.208505 -429.019883) (xy 453.208898 -429.00981)
			(xy 453.208898 -420.46906) (xy 453.208467 -420.458993) (xy 453.200743 -420.440399) (xy 453.193912 -420.432992)
			(xy 452.62673 -419.86581) (xy 452.619328 -419.858974) (xy 452.60073 -419.851263) (xy 452.590662 -419.850824)
			(xy 450.345048 -419.850824) (xy 450.334983 -419.851257) (xy 450.316394 -419.858988) (xy 450.30898 -419.86581)
			(xy 450.084952 -420.089838) (xy 450.078106 -420.097236) (xy 450.070377 -420.115835) (xy 450.069966 -420.125906)
			(xy 450.069966 -421.099742) (xy 450.070398 -421.109807) (xy 450.078131 -421.128395) (xy 450.084952 -421.13581)
			(xy 450.30898 -421.359838) (xy 450.31638 -421.366678) (xy 450.334979 -421.374393) (xy 450.345048 -421.374824)
			(xy 450.810884 -421.374824) (xy 450.820947 -421.375263) (xy 450.839527 -421.383002) (xy 450.846952 -421.38981)
			(xy 451.352412 -421.89527) (xy 451.359257 -421.902668) (xy 451.36698 -421.921267) (xy 451.367398 -421.931338)
			(xy 451.367398 -425.339002) (xy 451.367718 -425.347519) (xy 451.373296 -425.363613) (xy 451.37832 -425.370498)
			(xy 451.404463 -425.404208) (xy 451.450895 -425.475779) (xy 451.49026 -425.551467) (xy 451.522195 -425.630577)
			(xy 451.546406 -425.712383) (xy 451.562671 -425.796131) (xy 451.570841 -425.881051) (xy 451.57084 -425.966364)
			(xy 451.562669 -426.051285) (xy 451.546402 -426.135033) (xy 451.522189 -426.216837) (xy 451.490253 -426.295947)
			(xy 451.450887 -426.371635) (xy 451.404454 -426.443205) (xy 451.37832 -426.476922) (xy 451.373301 -426.483808)
			(xy 451.367738 -426.499903) (xy 451.367398 -426.508418) (xy 451.367398 -427.195742) (xy 451.366967 -427.205809)
			(xy 451.359242 -427.224402) (xy 451.352412 -427.23181) (xy 448.408298 -430.175924) (xy 448.400903 -430.182778)
			(xy 448.382304 -430.190524) (xy 448.37223 -430.19091) (xy 446.028826 -430.19091) (xy 446.018762 -430.190474)
			(xy 446.000176 -430.182742) (xy 445.992758 -430.175924) (xy 444.725298 -428.908464) (xy 444.717903 -428.901611)
			(xy 444.699304 -428.893867) (xy 444.68923 -428.893478) (xy 441.353702 -428.893478) (xy 441.343632 -428.893055)
			(xy 441.325029 -428.885338) (xy 441.317634 -428.878492) (xy 439.835798 -427.396656) (xy 439.828959 -427.389255)
			(xy 439.821241 -427.370657) (xy 439.820812 -427.360588) (xy 439.820812 -425.650406) (xy 439.82039 -425.640335)
			(xy 439.812679 -425.621728) (xy 439.805826 -425.614338) (xy 438.718452 -424.52671) (xy 438.711051 -424.51987)
			(xy 438.692453 -424.512151) (xy 438.682384 -424.511724) (xy 437.486298 -424.511724) (xy 437.476228 -424.512148)
			(xy 437.457627 -424.519866) (xy 437.45023 -424.52671) (xy 437.115712 -424.861228) (xy 437.108869 -424.868628)
			(xy 437.101143 -424.887226) (xy 437.100726 -424.897296) (xy 437.100726 -425.94911) (xy 437.596024 -425.94911)
			(xy 437.600095 -425.893488) (xy 437.612221 -425.839051) (xy 437.632144 -425.78696) (xy 437.65944 -425.738325)
			(xy 437.693526 -425.694182) (xy 437.733675 -425.655473) (xy 437.779033 -425.623022) (xy 437.828633 -425.597521)
			(xy 437.881417 -425.579514) (xy 437.93626 -425.569384) (xy 437.991994 -425.567347) (xy 438.047431 -425.573447)
			(xy 438.101388 -425.587553) (xy 438.152717 -425.609365) (xy 438.200323 -425.638419) (xy 438.243191 -425.674094)
			(xy 438.280408 -425.715631) (xy 438.311181 -425.762144) (xy 438.334853 -425.812641) (xy 438.350921 -425.866048)
			(xy 438.359041 -425.921224) (xy 438.35955 -425.94911) (xy 438.359041 -425.976996) (xy 438.350921 -426.032172)
			(xy 438.334853 -426.085579) (xy 438.311181 -426.136076) (xy 438.280408 -426.182589) (xy 438.243191 -426.224126)
			(xy 438.200323 -426.259801) (xy 438.152717 -426.288855) (xy 438.101388 -426.310667) (xy 438.047431 -426.324773)
			(xy 437.991994 -426.330873) (xy 437.93626 -426.328836) (xy 437.881417 -426.318706) (xy 437.828633 -426.300699)
			(xy 437.779033 -426.275198) (xy 437.733675 -426.242747) (xy 437.693526 -426.204038) (xy 437.65944 -426.159895)
			(xy 437.632144 -426.11126) (xy 437.612221 -426.059169) (xy 437.600095 -426.004732) (xy 437.596024 -425.94911)
			(xy 437.100726 -425.94911) (xy 437.100726 -427.09211) (xy 437.580784 -427.09211) (xy 437.584855 -427.036488)
			(xy 437.596981 -426.982051) (xy 437.616904 -426.92996) (xy 437.6442 -426.881325) (xy 437.678286 -426.837182)
			(xy 437.718435 -426.798473) (xy 437.763793 -426.766022) (xy 437.813393 -426.740521) (xy 437.866177 -426.722514)
			(xy 437.92102 -426.712384) (xy 437.976754 -426.710347) (xy 438.032191 -426.716447) (xy 438.086148 -426.730553)
			(xy 438.137477 -426.752365) (xy 438.185083 -426.781419) (xy 438.227951 -426.817094) (xy 438.265168 -426.858631)
			(xy 438.295941 -426.905144) (xy 438.319613 -426.955641) (xy 438.335681 -427.009048) (xy 438.343801 -427.064224)
			(xy 438.34431 -427.09211) (xy 438.343801 -427.119996) (xy 438.335681 -427.175172) (xy 438.319613 -427.228579)
			(xy 438.295941 -427.279076) (xy 438.265168 -427.325589) (xy 438.227951 -427.367126) (xy 438.185083 -427.402801)
			(xy 438.137477 -427.431855) (xy 438.086148 -427.453667) (xy 438.032191 -427.467773) (xy 437.976754 -427.473873)
			(xy 437.92102 -427.471836) (xy 437.866177 -427.461706) (xy 437.813393 -427.443699) (xy 437.763793 -427.418198)
			(xy 437.718435 -427.385747) (xy 437.678286 -427.347038) (xy 437.6442 -427.302895) (xy 437.616904 -427.25426)
			(xy 437.596981 -427.202169) (xy 437.584855 -427.147732) (xy 437.580784 -427.09211) (xy 437.100726 -427.09211)
			(xy 437.100726 -427.942502) (xy 437.10115 -427.952572) (xy 437.108868 -427.971173) (xy 437.115712 -427.97857)
			(xy 438.471013 -429.333871) (xy 439.403738 -429.333871) (xy 439.403738 -429.269949) (xy 439.411749 -429.206531)
			(xy 439.427646 -429.144617) (xy 439.451178 -429.085184) (xy 439.481972 -429.029169) (xy 439.519545 -428.977454)
			(xy 439.563302 -428.930857) (xy 439.612555 -428.890112) (xy 439.666526 -428.855861) (xy 439.724365 -428.828644)
			(xy 439.785158 -428.808891) (xy 439.847948 -428.796913) (xy 439.911744 -428.7929) (xy 439.97554 -428.796913)
			(xy 440.03833 -428.808891) (xy 440.099123 -428.828644) (xy 440.156962 -428.855861) (xy 440.210933 -428.890112)
			(xy 440.260186 -428.930857) (xy 440.303943 -428.977454) (xy 440.341516 -429.029169) (xy 440.37231 -429.085184)
			(xy 440.395842 -429.144617) (xy 440.411739 -429.206531) (xy 440.41975 -429.269949) (xy 440.420252 -429.30191)
			(xy 440.41975 -429.333871) (xy 440.411739 -429.397289) (xy 440.395842 -429.459203) (xy 440.37231 -429.518636)
			(xy 440.341516 -429.574651) (xy 440.303943 -429.626366) (xy 440.260186 -429.672963) (xy 440.210933 -429.713708)
			(xy 440.156962 -429.747959) (xy 440.099123 -429.775176) (xy 440.03833 -429.794929) (xy 439.97554 -429.806907)
			(xy 439.911744 -429.810921) (xy 439.847948 -429.806907) (xy 439.785158 -429.794929) (xy 439.724365 -429.775176)
			(xy 439.666526 -429.747959) (xy 439.612555 -429.713708) (xy 439.563302 -429.672963) (xy 439.519545 -429.626366)
			(xy 439.481972 -429.574651) (xy 439.451178 -429.518636) (xy 439.427646 -429.459203) (xy 439.411749 -429.397289)
			(xy 439.403738 -429.333871) (xy 438.471013 -429.333871) (xy 440.78398 -431.646838) (xy 440.79138 -431.653678)
			(xy 440.809979 -431.661393) (xy 440.820048 -431.661824)
		)
		(stroke
			(width 0)
			(type solid)
		)
		(fill yes)
		(layer "In11.Cu")
		(net "P3V3_AUX")
	)
	(gr_poly
		(pts
			(arc
				(start 256.800604 -37.135308)
				(mid 258.932532 -36.252077)
				(end 259.815584 -34.120074)
			)
			(arc
				(start 259.815584 -13.780008)
				(mid 260.103939 -13.083859)
				(end 260.800088 -12.795504)
			)
			(arc
				(start 385.601972 -12.795504)
				(mid 387.734244 -11.912288)
				(end 388.61746 -9.780016)
			)
			(arc
				(start 388.61746 -3.976878)
				(mid 388.611809 -3.953593)
				(end 388.596124 -3.935476)
			)
			(arc
				(start 388.596124 -3.935476)
				(mid 388.428347 -3.782165)
				(end 388.302246 -3.593084)
			)
			(xy 388.294372 -3.577336) (xy 388.262368 -3.56235)
			(arc
				(start 388.149084 -3.589528)
				(mid 388.120945 -3.607374)
				(end 388.109968 -3.638804)
			)
			(arc
				(start 388.109968 -9.780016)
				(mid 387.375393 -11.553437)
				(end 385.601972 -12.288012)
			)
			(arc
				(start 260.800088 -12.288012)
				(mid 259.745088 -12.725008)
				(end 259.308092 -13.780008)
			)
			(arc
				(start 259.308092 -34.120074)
				(mid 258.573517 -35.893495)
				(end 256.800096 -36.62807)
			)
			(arc
				(start 225.300032 -36.62807)
				(mid 223.526611 -35.893495)
				(end 222.792036 -34.120074)
			)
			(arc
				(start 222.792036 -13.780008)
				(mid 222.35504 -12.725008)
				(end 221.30004 -12.288012)
			)
			(arc
				(start 196.701918 -12.288012)
				(mid 194.928497 -11.553437)
				(end 194.193922 -9.780016)
			)
			(arc
				(start 194.193922 -8.918702)
				(mid 194.182875 -8.887327)
				(end 194.154806 -8.869426)
			)
			(xy 194.041522 -8.842248) (xy 194.009518 -8.857234)
			(arc
				(start 194.001644 -8.872982)
				(mid 193.875648 -9.062025)
				(end 193.70802 -9.215374)
			)
			(arc
				(start 193.70802 -9.215374)
				(mid 193.69232 -9.233484)
				(end 193.686684 -9.256776)
			)
			(arc
				(start 193.686684 -9.780524)
				(mid 194.569915 -11.912452)
				(end 196.701918 -12.795504)
			)
			(arc
				(start 221.30004 -12.795504)
				(mid 221.996189 -13.083859)
				(end 222.284544 -13.780008)
			)
			(arc
				(start 222.284544 -34.120074)
				(mid 223.16785 -36.252182)
				(end 225.300032 -37.135308)
			)
		)
		(stroke
			(width 0)
			(type solid)
		)
		(fill yes)
		(layer "In11.Cu")
		(net "GND")
	)
	(gr_poly
		(pts
			(xy 138.62939 -51.2064) (xy 138.640073 -51.205931) (xy 138.659591 -51.197239) (xy 138.673883 -51.181357)
			(xy 138.67765 -51.171348) (xy 138.712702 -51.063652) (xy 138.702542 -51.03241) (xy 138.68908 -51.022504)
			(xy 138.66508 -51.004542) (xy 138.621045 -50.963865) (xy 138.582097 -50.918293) (xy 138.548776 -50.868459)
			(xy 138.521544 -50.815053) (xy 138.500778 -50.758816) (xy 138.486768 -50.700528) (xy 138.479706 -50.640998)
			(xy 138.479276 -50.611024) (xy 138.479778 -50.579063) (xy 138.487789 -50.515645) (xy 138.503686 -50.453731)
			(xy 138.527218 -50.394298) (xy 138.558012 -50.338283) (xy 138.595585 -50.286568) (xy 138.639342 -50.239971)
			(xy 138.688595 -50.199226) (xy 138.742566 -50.164975) (xy 138.800405 -50.137758) (xy 138.861198 -50.118005)
			(xy 138.923988 -50.106027) (xy 138.987784 -50.102014) (xy 139.05158 -50.106027) (xy 139.11437 -50.118005)
			(xy 139.175163 -50.137758) (xy 139.233002 -50.164975) (xy 139.286973 -50.199226) (xy 139.336226 -50.239971)
			(xy 139.379983 -50.286568) (xy 139.417556 -50.338283) (xy 139.44835 -50.394298) (xy 139.471882 -50.453731)
			(xy 139.487779 -50.515645) (xy 139.49579 -50.579063) (xy 139.496292 -50.611024) (xy 139.49586 -50.641)
			(xy 139.488816 -50.700536) (xy 139.474818 -50.758829) (xy 139.454059 -50.815072) (xy 139.426828 -50.868482)
			(xy 139.393503 -50.918317) (xy 139.354547 -50.963887) (xy 139.310501 -51.004557) (xy 139.286488 -51.022504)
			(xy 139.273026 -51.03241) (xy 139.262866 -51.063652) (xy 139.297918 -51.171348) (xy 139.301758 -51.181311)
			(xy 139.316041 -51.197148) (xy 139.335516 -51.205838) (xy 139.346178 -51.2064) (xy 142.244318 -51.2064)
			(xy 142.254387 -51.205973) (xy 142.272986 -51.198254) (xy 142.280386 -51.191414) (xy 142.606014 -50.865786)
			(xy 142.612868 -50.858391) (xy 142.62061 -50.839792) (xy 142.621 -50.829718) (xy 142.621 -39.518082)
			(xy 142.620573 -39.508013) (xy 142.612854 -39.489414) (xy 142.606014 -39.482014) (xy 142.458186 -39.334186)
			(xy 142.450791 -39.327332) (xy 142.432192 -39.31959) (xy 142.422118 -39.3192) (xy 139.822682 -39.3192)
			(xy 139.812613 -39.319627) (xy 139.794014 -39.327346) (xy 139.786614 -39.334186) (xy 139.537186 -39.583614)
			(xy 139.530332 -39.591009) (xy 139.52259 -39.609608) (xy 139.5222 -39.619682) (xy 139.5222 -40.178736)
			(xy 139.522627 -40.188126) (xy 139.529368 -40.205656) (xy 139.541942 -40.219606) (xy 139.55014 -40.224202)
			(xy 139.643866 -40.271446) (xy 139.672568 -40.26916) (xy 139.683998 -40.260524) (xy 139.710327 -40.24173)
			(xy 139.766834 -40.210241) (xy 139.826879 -40.186171) (xy 139.889491 -40.16991) (xy 139.953659 -40.16172)
			(xy 139.986004 -40.16121) (xy 140.017757 -40.161717) (xy 140.080766 -40.169656) (xy 140.142297 -40.185375)
			(xy 140.201394 -40.208627) (xy 140.257139 -40.239052) (xy 140.283184 -40.257222) (xy 140.292328 -40.263201)
			(xy 140.313725 -40.267499) (xy 140.334973 -40.262515) (xy 140.34389 -40.256206) (xy 140.370674 -40.23625)
			(xy 140.428475 -40.202779) (xy 140.490158 -40.177158) (xy 140.554663 -40.159828) (xy 140.620882 -40.151086)
			(xy 140.654278 -40.150542) (xy 140.686238 -40.151022) (xy 140.749655 -40.15903) (xy 140.811567 -40.174924)
			(xy 140.870999 -40.198453) (xy 140.927014 -40.229245) (xy 140.978728 -40.266815) (xy 141.025324 -40.31057)
			(xy 141.06607 -40.359821) (xy 141.10032 -40.41379) (xy 141.127537 -40.471626) (xy 141.14729 -40.532418)
			(xy 141.159268 -40.595206) (xy 141.163282 -40.659) (xy 141.159268 -40.722794) (xy 141.14729 -40.785582)
			(xy 141.127537 -40.846373) (xy 141.10032 -40.90421) (xy 141.06607 -40.958179) (xy 141.025324 -41.00743)
			(xy 140.978728 -41.051185) (xy 140.927014 -41.088755) (xy 140.870999 -41.119547) (xy 140.811567 -41.143076)
			(xy 140.749655 -41.15897) (xy 140.686238 -41.166978) (xy 140.654278 -41.167558) (xy 140.622525 -41.16705)
			(xy 140.559518 -41.159108) (xy 140.497988 -41.143387) (xy 140.438893 -41.120132) (xy 140.383152 -41.089704)
			(xy 140.357098 -41.071546) (xy 140.347953 -41.065574) (xy 140.32656 -41.061286) (xy 140.305319 -41.066272)
			(xy 140.296392 -41.072562) (xy 140.269609 -41.092518) (xy 140.211808 -41.125989) (xy 140.150124 -41.151609)
			(xy 140.085619 -41.168939) (xy 140.0194 -41.177679) (xy 139.986004 -41.178226) (xy 139.953659 -41.177722)
			(xy 139.889491 -41.169525) (xy 139.826879 -41.153263) (xy 139.766833 -41.129197) (xy 139.71032 -41.097716)
			(xy 139.683998 -41.078912) (xy 139.672568 -41.070276) (xy 139.643866 -41.06799) (xy 139.55014 -41.115234)
			(xy 139.541896 -41.119783) (xy 139.529258 -41.133723) (xy 139.522519 -41.151291) (xy 139.5222 -41.1607)
			(xy 139.5222 -41.783) (xy 140.156182 -41.783) (xy 140.160253 -41.727378) (xy 140.172379 -41.672941)
			(xy 140.192302 -41.62085) (xy 140.219598 -41.572215) (xy 140.253684 -41.528072) (xy 140.293833 -41.489363)
			(xy 140.339191 -41.456912) (xy 140.388791 -41.431411) (xy 140.441575 -41.413404) (xy 140.496418 -41.403274)
			(xy 140.552152 -41.401237) (xy 140.607589 -41.407337) (xy 140.661546 -41.421443) (xy 140.712875 -41.443255)
			(xy 140.760481 -41.472309) (xy 140.803349 -41.507984) (xy 140.840566 -41.549521) (xy 140.871339 -41.596034)
			(xy 140.895011 -41.646531) (xy 140.911079 -41.699938) (xy 140.919199 -41.755114) (xy 140.919708 -41.783)
			(xy 140.919199 -41.810886) (xy 140.911079 -41.866062) (xy 140.895011 -41.919469) (xy 140.871339 -41.969966)
			(xy 140.840566 -42.016479) (xy 140.803349 -42.058016) (xy 140.760481 -42.093691) (xy 140.712875 -42.122745)
			(xy 140.661546 -42.144557) (xy 140.607589 -42.158663) (xy 140.552152 -42.164763) (xy 140.496418 -42.162726)
			(xy 140.441575 -42.152596) (xy 140.388791 -42.134589) (xy 140.339191 -42.109088) (xy 140.293833 -42.076637)
			(xy 140.253684 -42.037928) (xy 140.219598 -41.993785) (xy 140.192302 -41.94515) (xy 140.172379 -41.893059)
			(xy 140.160253 -41.838622) (xy 140.156182 -41.783) (xy 139.5222 -41.783) (xy 139.5222 -45.063918)
			(xy 139.521773 -45.073987) (xy 139.514054 -45.092586) (xy 139.507214 -45.099986) (xy 137.911586 -46.695614)
			(xy 137.904732 -46.703009) (xy 137.89699 -46.721608) (xy 137.8966 -46.731682) (xy 137.8966 -48.325)
			(xy 138.478813 -48.325) (xy 138.482827 -48.261208) (xy 138.494804 -48.198423) (xy 138.514555 -48.137633)
			(xy 138.541769 -48.079798) (xy 138.576018 -48.02583) (xy 138.61676 -47.97658) (xy 138.663353 -47.932825)
			(xy 138.715063 -47.895254) (xy 138.771074 -47.86446) (xy 138.830502 -47.840929) (xy 138.892412 -47.825032)
			(xy 138.955825 -47.817019) (xy 138.987784 -47.816516) (xy 139.017999 -47.816957) (xy 139.078002 -47.824143)
			(xy 139.136729 -47.838392) (xy 139.193353 -47.859502) (xy 139.247075 -47.887176) (xy 139.297138 -47.921024)
			(xy 139.32027 -47.940468) (xy 139.327419 -47.946077) (xy 139.344464 -47.952332) (xy 139.353544 -47.95266)
			(xy 139.384024 -47.95266) (xy 139.393106 -47.952334) (xy 139.410157 -47.946088) (xy 139.417298 -47.940468)
			(xy 139.440442 -47.92104) (xy 139.490507 -47.8872) (xy 139.544228 -47.859529) (xy 139.600848 -47.838418)
			(xy 139.659572 -47.824164) (xy 139.71957 -47.816967) (xy 139.749784 -47.816516) (xy 139.781749 -47.816948)
			(xy 139.845174 -47.824959) (xy 139.907095 -47.840855) (xy 139.966535 -47.864388) (xy 140.022557 -47.895185)
			(xy 140.074277 -47.93276) (xy 140.12088 -47.976522) (xy 140.161631 -48.02578) (xy 140.195886 -48.079756)
			(xy 140.223106 -48.137601) (xy 140.242862 -48.198401) (xy 140.254841 -48.261197) (xy 140.258856 -48.325)
			(xy 140.254841 -48.388803) (xy 140.242862 -48.451599) (xy 140.223106 -48.512399) (xy 140.195886 -48.570244)
			(xy 140.161631 -48.62422) (xy 140.12088 -48.673478) (xy 140.074277 -48.71724) (xy 140.022557 -48.754815)
			(xy 139.966535 -48.785612) (xy 139.907095 -48.809145) (xy 139.845174 -48.825041) (xy 139.781749 -48.833052)
			(xy 139.749784 -48.833532) (xy 139.719567 -48.833122) (xy 139.659563 -48.825932) (xy 139.600835 -48.811678)
			(xy 139.544211 -48.790562) (xy 139.490489 -48.762882) (xy 139.440429 -48.729028) (xy 139.417298 -48.70958)
			(xy 139.410163 -48.703951) (xy 139.393107 -48.69771) (xy 139.384024 -48.697388) (xy 139.353544 -48.697388)
			(xy 139.344462 -48.697709) (xy 139.327411 -48.70396) (xy 139.32027 -48.70958) (xy 139.297131 -48.729015)
			(xy 139.247066 -48.762856) (xy 139.193344 -48.790526) (xy 139.136722 -48.811637) (xy 139.077998 -48.825889)
			(xy 139.017998 -48.833083) (xy 138.987784 -48.833532) (xy 138.955825 -48.832981) (xy 138.892412 -48.824968)
			(xy 138.830502 -48.809071) (xy 138.771074 -48.78554) (xy 138.715063 -48.754746) (xy 138.663353 -48.717175)
			(xy 138.61676 -48.67342) (xy 138.576018 -48.62417) (xy 138.541769 -48.570202) (xy 138.514555 -48.512367)
			(xy 138.494804 -48.451577) (xy 138.482827 -48.388792) (xy 138.478813 -48.325) (xy 137.8966 -48.325)
			(xy 137.8966 -49.595024) (xy 138.605766 -49.595024) (xy 138.609837 -49.539402) (xy 138.621963 -49.484965)
			(xy 138.641886 -49.432874) (xy 138.669182 -49.384239) (xy 138.703268 -49.340096) (xy 138.743417 -49.301387)
			(xy 138.788775 -49.268936) (xy 138.838375 -49.243435) (xy 138.891159 -49.225428) (xy 138.946002 -49.215298)
			(xy 139.001736 -49.213261) (xy 139.057173 -49.219361) (xy 139.11113 -49.233467) (xy 139.162459 -49.255279)
			(xy 139.210065 -49.284333) (xy 139.252933 -49.320008) (xy 139.29015 -49.361545) (xy 139.320923 -49.408058)
			(xy 139.344595 -49.458555) (xy 139.360663 -49.511962) (xy 139.368783 -49.567138) (xy 139.369292 -49.595024)
			(xy 139.368783 -49.62291) (xy 139.360663 -49.678086) (xy 139.344595 -49.731493) (xy 139.320923 -49.78199)
			(xy 139.29015 -49.828503) (xy 139.252933 -49.87004) (xy 139.210065 -49.905715) (xy 139.162459 -49.934769)
			(xy 139.11113 -49.956581) (xy 139.057173 -49.970687) (xy 139.001736 -49.976787) (xy 138.946002 -49.97475)
			(xy 138.891159 -49.96462) (xy 138.838375 -49.946613) (xy 138.788775 -49.921112) (xy 138.743417 -49.888661)
			(xy 138.703268 -49.849952) (xy 138.669182 -49.805809) (xy 138.641886 -49.757174) (xy 138.621963 -49.705083)
			(xy 138.609837 -49.650646) (xy 138.605766 -49.595024) (xy 137.8966 -49.595024) (xy 137.8966 -50.778918)
			(xy 137.897027 -50.788987) (xy 137.904746 -50.807586) (xy 137.911586 -50.814986) (xy 138.288014 -51.191414)
			(xy 138.295409 -51.198268) (xy 138.314008 -51.20601) (xy 138.324082 -51.2064)
		)
		(stroke
			(width 0)
			(type solid)
		)
		(fill yes)
		(layer "In11.Cu")
		(net "P5V_AUX")
	)
	(gr_poly
		(pts
			(xy 300.852332 -408.490928) (xy 300.854618 -408.47137) (xy 300.85838 -408.442813) (xy 300.871534 -408.386732)
			(xy 300.890947 -408.332499) (xy 300.916369 -408.280809) (xy 300.947474 -408.232327) (xy 300.965362 -408.20975)
			(xy 300.97056 -408.202786) (xy 300.976393 -408.186428) (xy 300.976792 -408.177746) (xy 300.976792 -408.147774)
			(xy 300.976442 -408.139084) (xy 300.970595 -408.122717) (xy 300.965362 -408.11577) (xy 300.945762 -408.090947)
			(xy 300.912206 -408.037333) (xy 300.885556 -407.979972) (xy 300.866221 -407.91975) (xy 300.854501 -407.857596)
			(xy 300.850577 -407.794469) (xy 300.854509 -407.731342) (xy 300.866236 -407.669189) (xy 300.885578 -407.60897)
			(xy 300.912236 -407.551613) (xy 300.945798 -407.498003) (xy 300.965362 -407.47315) (xy 300.97056 -407.466186)
			(xy 300.976393 -407.449828) (xy 300.976792 -407.441146) (xy 300.976792 -407.411174) (xy 300.976442 -407.402484)
			(xy 300.970595 -407.386117) (xy 300.965362 -407.37917) (xy 300.943831 -407.351835) (xy 300.907651 -407.292398)
			(xy 300.87991 -407.228585) (xy 300.861124 -407.161586) (xy 300.851646 -407.092651) (xy 300.851062 -407.05786)
			(xy 300.851564 -407.025899) (xy 300.859575 -406.962481) (xy 300.875472 -406.900567) (xy 300.899004 -406.841134)
			(xy 300.929798 -406.785119) (xy 300.967371 -406.733404) (xy 301.011128 -406.686807) (xy 301.060381 -406.646062)
			(xy 301.114352 -406.611811) (xy 301.172191 -406.584594) (xy 301.232984 -406.564841) (xy 301.295774 -406.552863)
			(xy 301.35957 -406.54885) (xy 301.423366 -406.552863) (xy 301.486156 -406.564841) (xy 301.546949 -406.584594)
			(xy 301.604788 -406.611811) (xy 301.658759 -406.646062) (xy 301.708012 -406.686807) (xy 301.751769 -406.733404)
			(xy 301.789342 -406.785119) (xy 301.820136 -406.841134) (xy 301.843668 -406.900567) (xy 301.859565 -406.962481)
			(xy 301.867576 -407.025899) (xy 301.868078 -407.05786) (xy 301.867512 -407.092653) (xy 301.858034 -407.16159)
			(xy 301.839249 -407.228592) (xy 301.811509 -407.292409) (xy 301.77533 -407.35185) (xy 301.753778 -407.37917)
			(xy 301.74858 -407.386134) (xy 301.742749 -407.402492) (xy 301.742348 -407.411174) (xy 301.742348 -407.441146)
			(xy 301.742702 -407.449834) (xy 301.748558 -407.466194) (xy 301.753778 -407.47315) (xy 301.774005 -407.498794)
			(xy 301.80841 -407.554311) (xy 301.835416 -407.61378) (xy 301.845472 -407.644854) (xy 301.849536 -407.657554)
			(xy 301.86884 -407.675842) (xy 301.966376 -407.699972) (xy 301.974903 -407.701718) (xy 301.992214 -407.700017)
			(xy 302.007968 -407.692646) (xy 302.014382 -407.686764) (xy 302.739044 -406.962102) (xy 302.746445 -406.955262)
			(xy 302.765043 -406.947544) (xy 302.775112 -406.947116) (xy 327.958958 -406.947116) (xy 327.969024 -406.946683)
			(xy 327.987615 -406.938955) (xy 327.995026 -406.93213) (xy 329.203558 -405.723598) (xy 329.210409 -405.716201)
			(xy 329.218149 -405.697603) (xy 329.218544 -405.68753) (xy 329.218544 -402.970238) (xy 329.218131 -402.960628)
			(xy 329.211082 -402.942748) (xy 329.204828 -402.93544) (xy 329.150218 -402.877528) (xy 329.132692 -402.8694)
			(xy 329.12304 -402.868892) (xy 329.09072 -402.866489) (xy 329.027027 -402.854512) (xy 328.99604 -402.845016)
			(xy 328.986026 -402.842258) (xy 328.965364 -402.84417) (xy 328.947169 -402.854144) (xy 328.940414 -402.862034)
			(xy 328.919704 -402.887869) (xy 328.872677 -402.93448) (xy 328.819998 -402.974594) (xy 328.762558 -403.00753)
			(xy 328.701328 -403.032733) (xy 328.637346 -403.049774) (xy 328.571693 -403.058367) (xy 328.538586 -403.058884)
			(xy 328.506627 -403.058381) (xy 328.443213 -403.050369) (xy 328.381304 -403.034471) (xy 328.321875 -403.01094)
			(xy 328.265864 -402.980147) (xy 328.214154 -402.942576) (xy 328.16756 -402.89882) (xy 328.126818 -402.84957)
			(xy 328.09257 -402.795602) (xy 328.065355 -402.737767) (xy 328.045604 -402.676978) (xy 328.033627 -402.614192)
			(xy 328.029613 -402.5504) (xy 328.033627 -402.486608) (xy 328.045604 -402.423822) (xy 328.065355 -402.363033)
			(xy 328.09257 -402.305198) (xy 328.126818 -402.25123) (xy 328.16756 -402.20198) (xy 328.214154 -402.158224)
			(xy 328.265864 -402.120653) (xy 328.321875 -402.08986) (xy 328.381304 -402.066329) (xy 328.443213 -402.050431)
			(xy 328.506627 -402.042419) (xy 328.538586 -402.041868) (xy 328.578429 -402.042628) (xy 328.657147 -402.055011)
			(xy 328.695304 -402.066506) (xy 328.705314 -402.069257) (xy 328.725961 -402.06733) (xy 328.744132 -402.057338)
			(xy 328.75093 -402.049488) (xy 328.75855 -402.039836) (xy 328.763747 -402.032872) (xy 328.769577 -402.016513)
			(xy 328.76998 -402.007832) (xy 328.76998 -401.97786) (xy 328.769628 -401.969171) (xy 328.763776 -401.952808)
			(xy 328.75855 -401.945856) (xy 328.73702 -401.918521) (xy 328.700843 -401.859083) (xy 328.673104 -401.79527)
			(xy 328.654321 -401.728271) (xy 328.644845 -401.659337) (xy 328.64425 -401.624546) (xy 328.64474 -401.592488)
			(xy 328.652803 -401.528881) (xy 328.668793 -401.466792) (xy 328.692459 -401.407203) (xy 328.723424 -401.35106)
			(xy 328.761198 -401.299253) (xy 328.805182 -401.252603) (xy 328.854678 -401.211849) (xy 328.908903 -401.177637)
			(xy 328.966997 -401.150509) (xy 329.02804 -401.130895) (xy 329.091062 -401.119107) (xy 329.12304 -401.1168)
			(xy 329.132692 -401.116292) (xy 329.150218 -401.108164) (xy 329.204828 -401.050252) (xy 329.211108 -401.042961)
			(xy 329.218151 -401.02507) (xy 329.218544 -401.015454) (xy 329.218544 -399.328132) (xy 329.218107 -399.318069)
			(xy 329.210369 -399.299487) (xy 329.203558 -399.292064) (xy 328.851514 -398.94002) (xy 328.844112 -398.933185)
			(xy 328.825513 -398.925479) (xy 328.815446 -398.925034) (xy 327.88733 -398.925034) (xy 327.877341 -398.925567)
			(xy 327.858904 -398.933277) (xy 327.851516 -398.94002) (xy 324.991222 -401.80006) (xy 324.984872 -401.811236)
			(xy 324.983094 -401.81784) (xy 324.975137 -401.844954) (xy 324.952335 -401.896654) (xy 324.92216 -401.944428)
			(xy 324.88527 -401.98723) (xy 324.842473 -402.024126) (xy 324.794704 -402.054308) (xy 324.743007 -402.077118)
			(xy 324.715886 -402.085048) (xy 324.709282 -402.086826) (xy 324.698106 -402.093176) (xy 324.139814 -402.651468)
			(xy 324.132407 -402.658158) (xy 324.11397 -402.66575) (xy 324.104 -402.6662) (xy 324.046088 -402.6662)
			(xy 324.036102 -402.66674) (xy 324.017673 -402.674456) (xy 324.010274 -402.681186) (xy 323.886576 -402.804884)
			(xy 323.879177 -402.811728) (xy 323.860579 -402.819457) (xy 323.850508 -402.81987) (xy 301.019718 -402.81987)
			(xy 301.009668 -402.820376) (xy 300.991107 -402.828097) (xy 300.98365 -402.834856) (xy 300.448472 -403.370034)
			(xy 300.441614 -403.396196) (xy 300.44517 -403.409404) (xy 300.45349 -403.442112) (xy 300.462412 -403.509009)
			(xy 300.46295 -403.542754) (xy 300.462507 -403.573489) (xy 300.455103 -403.634511) (xy 300.440398 -403.694196)
			(xy 300.418606 -403.751673) (xy 300.390044 -403.806104) (xy 300.35513 -403.856695) (xy 300.314372 -403.90271)
			(xy 300.268365 -403.943475) (xy 300.217779 -403.978398) (xy 300.163353 -404.006969) (xy 300.10588 -404.028772)
			(xy 300.046198 -404.043487) (xy 299.985177 -404.050902) (xy 299.954442 -404.051262) (xy 299.923907 -404.050824)
			(xy 299.863275 -404.043538) (xy 299.803951 -404.029042) (xy 299.746791 -404.007545) (xy 299.719492 -403.993858)
			(xy 299.713904 -403.99081) (xy 299.702474 -403.988016) (xy 299.473874 -403.988016) (xy 299.462444 -403.99081)
			(xy 299.456856 -403.993858) (xy 299.42956 -404.007552) (xy 299.372399 -404.029051) (xy 299.313075 -404.04355)
			(xy 299.252441 -404.05084) (xy 299.221906 -404.051262) (xy 299.19137 -404.050828) (xy 299.130735 -404.043549)
			(xy 299.071408 -404.02906) (xy 299.014244 -404.007568) (xy 298.986956 -403.993858) (xy 298.981368 -403.99081)
			(xy 298.969938 -403.988016) (xy 298.838874 -403.988016) (xy 298.827444 -403.99081) (xy 298.821856 -403.993858)
			(xy 298.79456 -404.007552) (xy 298.737399 -404.029051) (xy 298.678075 -404.04355) (xy 298.617441 -404.05084)
			(xy 298.586906 -404.051262) (xy 298.55637 -404.050828) (xy 298.495735 -404.043549) (xy 298.436408 -404.02906)
			(xy 298.379244 -404.007568) (xy 298.351956 -403.993858) (xy 298.346368 -403.99081) (xy 298.334938 -403.988016)
			(xy 298.203874 -403.988016) (xy 298.192444 -403.99081) (xy 298.186856 -403.993858) (xy 298.15956 -404.007552)
			(xy 298.102399 -404.029051) (xy 298.043075 -404.04355) (xy 297.982441 -404.05084) (xy 297.951906 -404.051262)
			(xy 297.92137 -404.050828) (xy 297.860735 -404.043549) (xy 297.801408 -404.02906) (xy 297.744244 -404.007568)
			(xy 297.716956 -403.993858) (xy 297.711368 -403.99081) (xy 297.699938 -403.988016) (xy 297.568874 -403.988016)
			(xy 297.557444 -403.99081) (xy 297.551856 -403.993858) (xy 297.52456 -404.007552) (xy 297.467399 -404.029051)
			(xy 297.408075 -404.04355) (xy 297.347441 -404.05084) (xy 297.316906 -404.051262) (xy 297.28637 -404.050828)
			(xy 297.225735 -404.043549) (xy 297.166408 -404.02906) (xy 297.109244 -404.007568) (xy 297.081956 -403.993858)
			(xy 297.076368 -403.99081) (xy 297.064938 -403.988016) (xy 296.92981 -403.988016) (xy 296.91838 -403.99081)
			(xy 296.912792 -403.993858) (xy 296.885495 -404.007549) (xy 296.828333 -404.02904) (xy 296.769009 -404.043532)
			(xy 296.708376 -404.050815) (xy 296.677842 -404.051262) (xy 296.647307 -404.050824) (xy 296.586675 -404.043538)
			(xy 296.527351 -404.029042) (xy 296.470191 -404.007545) (xy 296.442892 -403.993858) (xy 296.437304 -403.99081)
			(xy 296.425874 -403.988016) (xy 296.204894 -403.988016) (xy 296.194825 -403.988441) (xy 296.176223 -403.996158)
			(xy 296.168826 -404.003002) (xy 295.950386 -404.221442) (xy 295.943537 -404.228838) (xy 295.935804 -404.247438)
			(xy 295.9354 -404.25751) (xy 295.9354 -404.748492) (xy 304.627278 -404.748492) (xy 304.631349 -404.69287)
			(xy 304.643475 -404.638433) (xy 304.663398 -404.586342) (xy 304.690694 -404.537707) (xy 304.72478 -404.493564)
			(xy 304.764929 -404.454855) (xy 304.810287 -404.422404) (xy 304.859887 -404.396903) (xy 304.912671 -404.378896)
			(xy 304.967514 -404.368766) (xy 305.023248 -404.366729) (xy 305.078685 -404.372829) (xy 305.132642 -404.386935)
			(xy 305.183971 -404.408747) (xy 305.231577 -404.437801) (xy 305.274445 -404.473476) (xy 305.311662 -404.515013)
			(xy 305.342435 -404.561526) (xy 305.366107 -404.612023) (xy 305.382175 -404.66543) (xy 305.390295 -404.720606)
			(xy 305.390804 -404.748492) (xy 305.390295 -404.776378) (xy 305.382175 -404.831554) (xy 305.366107 -404.884961)
			(xy 305.342435 -404.935458) (xy 305.311662 -404.981971) (xy 305.274445 -405.023508) (xy 305.231577 -405.059183)
			(xy 305.183971 -405.088237) (xy 305.132642 -405.110049) (xy 305.078685 -405.124155) (xy 305.023248 -405.130255)
			(xy 304.967514 -405.128218) (xy 304.912671 -405.118088) (xy 304.859887 -405.100081) (xy 304.810287 -405.07458)
			(xy 304.764929 -405.042129) (xy 304.72478 -405.00342) (xy 304.690694 -404.959277) (xy 304.663398 -404.910642)
			(xy 304.643475 -404.858551) (xy 304.631349 -404.804114) (xy 304.627278 -404.748492) (xy 295.9354 -404.748492)
			(xy 295.9354 -407.616152) (xy 295.935833 -407.626218) (xy 295.94356 -407.644809) (xy 295.950386 -407.65222)
			(xy 296.799508 -408.501342) (xy 296.806904 -408.508194) (xy 296.825503 -408.515934) (xy 296.835576 -408.516328)
			(xy 300.82363 -408.516328)
		)
		(stroke
			(width 0)
			(type solid)
		)
		(fill yes)
		(layer "In11.Cu")
		(net "P0V9_CPU0_RT_2D")
	)
	(gr_poly
		(pts
			(xy 251.466858 -52.966112) (xy 251.476924 -52.965679) (xy 251.495514 -52.957951) (xy 251.502926 -52.951126)
			(xy 251.76734 -52.686712) (xy 251.774022 -52.679301) (xy 251.781602 -52.660866) (xy 251.782072 -52.650898)
			(xy 251.782072 -49.98847) (xy 251.781592 -49.978505) (xy 251.77401 -49.960074) (xy 251.76734 -49.952656)
			(xy 249.576336 -47.761652) (xy 249.569493 -47.754253) (xy 249.561771 -47.735654) (xy 249.56135 -47.725584)
			(xy 249.56135 -47.587408) (xy 249.557286 -47.573946) (xy 249.553476 -47.567596) (xy 249.540457 -47.546914)
			(xy 249.516442 -47.504344) (xy 249.50547 -47.482506) (xy 249.502422 -47.476664) (xy 249.49404 -47.467012)
			(xy 249.460004 -47.443644) (xy 249.43562 -47.440596) (xy 249.423682 -47.445168) (xy 249.401804 -47.4532)
			(xy 249.356588 -47.464496) (xy 249.310333 -47.470207) (xy 249.28703 -47.470568) (xy 249.259757 -47.470107)
			(xy 249.205766 -47.462348) (xy 249.153429 -47.446984) (xy 249.103811 -47.424328) (xy 249.057923 -47.39484)
			(xy 249.016699 -47.359122) (xy 248.980978 -47.317901) (xy 248.951487 -47.272015) (xy 248.928827 -47.222399)
			(xy 248.913459 -47.170063) (xy 248.905696 -47.116073) (xy 248.905696 -47.061527) (xy 248.913459 -47.007537)
			(xy 248.928827 -46.955201) (xy 248.951487 -46.905585) (xy 248.980978 -46.859699) (xy 249.016699 -46.818478)
			(xy 249.057923 -46.78276) (xy 249.103811 -46.753272) (xy 249.153429 -46.730616) (xy 249.205766 -46.715252)
			(xy 249.259757 -46.707493) (xy 249.28703 -46.707044) (xy 249.310333 -46.707407) (xy 249.356589 -46.713112)
			(xy 249.401805 -46.724408) (xy 249.423682 -46.732444) (xy 249.43562 -46.737016) (xy 249.460004 -46.733968)
			(xy 249.49404 -46.7106) (xy 249.502422 -46.700948) (xy 249.50547 -46.695106) (xy 249.516443 -46.673269)
			(xy 249.540459 -46.6307) (xy 249.553476 -46.610016) (xy 249.557131 -46.603757) (xy 249.561119 -46.589829)
			(xy 249.56135 -46.582584) (xy 249.56135 -43.868848) (xy 249.559826 -43.863006) (xy 249.551802 -43.828535)
			(xy 249.540608 -43.758645) (xy 249.53501 -43.688085) (xy 249.53468 -43.652694) (xy 249.535023 -43.617304)
			(xy 249.540627 -43.546746) (xy 249.551816 -43.476856) (xy 249.559826 -43.442382) (xy 249.56135 -43.43654)
			(xy 249.56135 -42.6212) (xy 249.561775 -42.611131) (xy 249.569495 -42.592531) (xy 249.576336 -42.585132)
			(xy 250.400058 -41.76141) (xy 250.400566 -41.760902) (xy 250.40714 -41.753518) (xy 250.414572 -41.735219)
			(xy 250.415044 -41.725342) (xy 250.415044 -41.087294) (xy 250.392438 -41.059354) (xy 250.374658 -41.055544)
			(xy 250.332493 -41.04616) (xy 250.250073 -41.020282) (xy 250.17055 -40.986537) (xy 250.094672 -40.945242)
			(xy 250.023155 -40.896785) (xy 249.956673 -40.841624) (xy 249.89585 -40.780278) (xy 249.841261 -40.713325)
			(xy 249.793419 -40.641396) (xy 249.752776 -40.565167) (xy 249.719713 -40.485358) (xy 249.694543 -40.402719)
			(xy 249.677502 -40.318029) (xy 249.668751 -40.232087) (xy 249.66803 -40.188896) (xy 249.66803 -40.178736)
			(xy 249.66041 -40.160448) (xy 249.602244 -40.102536) (xy 249.594838 -40.095841) (xy 249.576402 -40.088237)
			(xy 249.56643 -40.087804) (xy 248.171716 -40.087804) (xy 248.166055 -40.087971) (xy 248.155024 -40.090531)
			(xy 248.149872 -40.092884) (xy 248.121424 -40.106346) (xy 248.114312 -40.114474) (xy 248.114312 -40.114728)
			(xy 248.09608 -40.135136) (xy 248.054782 -40.171041) (xy 248.008785 -40.200688) (xy 247.959029 -40.22347)
			(xy 247.906532 -40.238922) (xy 247.852368 -40.246728) (xy 247.797644 -40.246728) (xy 247.74348 -40.238922)
			(xy 247.690983 -40.22347) (xy 247.641227 -40.200688) (xy 247.59523 -40.171041) (xy 247.553932 -40.135136)
			(xy 247.5357 -40.114728) (xy 247.5357 -40.114474) (xy 247.528588 -40.106346) (xy 247.50014 -40.092884)
			(xy 247.494977 -40.090562) (xy 247.483954 -40.087997) (xy 247.478296 -40.087804) (xy 245.192042 -40.087804)
			(xy 245.181977 -40.088238) (xy 245.163388 -40.095968) (xy 245.155974 -40.10279) (xy 242.268502 -42.990262)
			(xy 242.261665 -42.997664) (xy 242.253953 -43.016262) (xy 242.253516 -43.02633) (xy 242.253516 -43.246802)
			(xy 243.629434 -43.246802) (xy 243.629878 -43.208514) (xy 243.636497 -43.132224) (xy 243.649641 -43.056784)
			(xy 243.669215 -42.982752) (xy 243.681758 -42.946574) (xy 243.6844 -42.938136) (xy 243.684401 -42.920468)
			(xy 243.681758 -42.91203) (xy 243.6692 -42.875856) (xy 243.649604 -42.801826) (xy 243.636453 -42.726385)
			(xy 243.629845 -42.650091) (xy 243.629434 -42.611802) (xy 243.629938 -42.569454) (xy 243.637989 -42.48514)
			(xy 243.654018 -42.401974) (xy 243.677879 -42.320707) (xy 243.709358 -42.242077) (xy 243.748169 -42.166796)
			(xy 243.793959 -42.095544) (xy 243.846315 -42.028968) (xy 243.904763 -41.96767) (xy 243.968773 -41.912205)
			(xy 244.037765 -41.863076) (xy 244.111115 -41.820727) (xy 244.188158 -41.785543) (xy 244.268197 -41.757841)
			(xy 244.350506 -41.737873) (xy 244.434341 -41.72582) (xy 244.518942 -41.72179) (xy 244.603543 -41.72582)
			(xy 244.687378 -41.737873) (xy 244.769687 -41.757841) (xy 244.849726 -41.785543) (xy 244.926769 -41.820727)
			(xy 245.000119 -41.863076) (xy 245.069111 -41.912205) (xy 245.133121 -41.96767) (xy 245.191569 -42.028968)
			(xy 245.243925 -42.095544) (xy 245.289715 -42.166796) (xy 245.328526 -42.242077) (xy 245.360005 -42.320707)
			(xy 245.383866 -42.401974) (xy 245.399895 -42.48514) (xy 245.407946 -42.569454) (xy 245.40845 -42.611802)
			(xy 245.408008 -42.65009) (xy 245.401389 -42.72638) (xy 245.388244 -42.80182) (xy 245.368669 -42.875852)
			(xy 245.356126 -42.91203) (xy 245.353482 -42.920468) (xy 245.353483 -42.938136) (xy 245.356126 -42.946574)
			(xy 245.368685 -42.982748) (xy 245.38828 -43.056777) (xy 245.401431 -43.132219) (xy 245.408039 -43.208512)
			(xy 245.40845 -43.246802) (xy 245.407946 -43.28915) (xy 245.399895 -43.373464) (xy 245.383866 -43.45663)
			(xy 245.360005 -43.537897) (xy 245.328526 -43.616527) (xy 245.289715 -43.691808) (xy 245.243925 -43.76306)
			(xy 245.191569 -43.829636) (xy 245.133121 -43.890934) (xy 245.069111 -43.946399) (xy 245.000119 -43.995528)
			(xy 244.926769 -44.037877) (xy 244.849726 -44.073061) (xy 244.769687 -44.100763) (xy 244.687378 -44.120731)
			(xy 244.603543 -44.132784) (xy 244.518942 -44.136815) (xy 244.434341 -44.132784) (xy 244.350506 -44.120731)
			(xy 244.268197 -44.100763) (xy 244.188158 -44.073061) (xy 244.111115 -44.037877) (xy 244.037765 -43.995528)
			(xy 243.968773 -43.946399) (xy 243.904763 -43.890934) (xy 243.846315 -43.829636) (xy 243.793959 -43.76306)
			(xy 243.748169 -43.691808) (xy 243.709358 -43.616527) (xy 243.677879 -43.537897) (xy 243.654018 -43.45663)
			(xy 243.637989 -43.373464) (xy 243.629938 -43.28915) (xy 243.629434 -43.246802) (xy 242.253516 -43.246802)
			(xy 242.253516 -45.726153) (xy 244.028673 -45.726153) (xy 244.028673 -45.671647) (xy 244.036431 -45.617697)
			(xy 244.051787 -45.5654) (xy 244.07443 -45.515821) (xy 244.103899 -45.469969) (xy 244.139593 -45.428777)
			(xy 244.180786 -45.393085) (xy 244.22664 -45.363619) (xy 244.276221 -45.340979) (xy 244.328519 -45.325626)
			(xy 244.382469 -45.317872) (xy 244.409722 -45.31741) (xy 244.41912 -45.31741) (xy 244.432582 -45.317918)
			(xy 244.45595 -45.305218) (xy 244.51691 -45.208444) (xy 244.51818 -45.182028) (xy 244.512084 -45.169836)
			(xy 244.499055 -45.142926) (xy 244.480598 -45.086061) (xy 244.471261 -45.027009) (xy 244.470682 -44.997116)
			(xy 244.471168 -44.969865) (xy 244.478924 -44.915917) (xy 244.494279 -44.863622) (xy 244.516921 -44.814045)
			(xy 244.546387 -44.768195) (xy 244.582078 -44.727004) (xy 244.623269 -44.691313) (xy 244.669119 -44.661847)
			(xy 244.718696 -44.639205) (xy 244.770991 -44.62385) (xy 244.824939 -44.616094) (xy 244.879441 -44.616094)
			(xy 244.933389 -44.62385) (xy 244.985684 -44.639205) (xy 245.035261 -44.661847) (xy 245.081111 -44.691313)
			(xy 245.122302 -44.727004) (xy 245.157993 -44.768195) (xy 245.187459 -44.814045) (xy 245.210101 -44.863622)
			(xy 245.225456 -44.915917) (xy 245.233212 -44.969865) (xy 245.233698 -44.997116) (xy 245.233189 -45.025048)
			(xy 245.225048 -45.080314) (xy 245.208941 -45.133805) (xy 245.185214 -45.184379) (xy 245.170198 -45.207936)
			(xy 245.164102 -45.21708) (xy 245.160546 -45.23867) (xy 245.186708 -45.33392) (xy 245.200678 -45.350684)
			(xy 245.210838 -45.35551) (xy 245.234703 -45.367543) (xy 245.279101 -45.397298) (xy 245.31891 -45.43296)
			(xy 245.353352 -45.47383) (xy 245.38175 -45.519108) (xy 245.40355 -45.567907) (xy 245.418323 -45.619271)
			(xy 245.425782 -45.672195) (xy 245.42623 -45.698918) (xy 245.425739 -45.726169) (xy 245.417981 -45.780115)
			(xy 245.402624 -45.832408) (xy 245.379983 -45.881984) (xy 245.350517 -45.927833) (xy 245.314826 -45.969023)
			(xy 245.273637 -46.004714) (xy 245.227788 -46.034181) (xy 245.178212 -46.056823) (xy 245.125919 -46.07218)
			(xy 245.071973 -46.079939) (xy 245.044722 -46.080426) (xy 245.017351 -46.079965) (xy 244.963171 -46.072149)
			(xy 244.910667 -46.056659) (xy 244.860921 -46.033816) (xy 244.814955 -46.004089) (xy 244.794024 -45.986446)
			(xy 244.786912 -45.98035) (xy 244.769894 -45.974) (xy 244.68455 -45.974) (xy 244.667532 -45.98035)
			(xy 244.66042 -45.986446) (xy 244.639484 -46.004081) (xy 244.593513 -46.033795) (xy 244.543767 -46.056633)
			(xy 244.491267 -46.072125) (xy 244.437091 -46.079953) (xy 244.409722 -46.080426) (xy 244.382469 -46.079928)
			(xy 244.328519 -46.072174) (xy 244.276221 -46.056821) (xy 244.22664 -46.034181) (xy 244.180786 -46.004715)
			(xy 244.139593 -45.969023) (xy 244.103899 -45.927831) (xy 244.07443 -45.881979) (xy 244.051787 -45.8324)
			(xy 244.036431 -45.780103) (xy 244.028673 -45.726153) (xy 242.253516 -45.726153) (xy 242.253516 -46.74616)
			(xy 242.257326 -46.759368) (xy 242.260882 -46.765464) (xy 242.264384 -46.77157) (xy 242.268251 -46.7851)
			(xy 242.268502 -46.792134) (xy 242.268502 -52.128947) (xy 243.816428 -52.128947) (xy 243.816428 -52.074453)
			(xy 243.824183 -52.020515) (xy 243.839535 -51.968229) (xy 243.862172 -51.918659) (xy 243.891632 -51.872816)
			(xy 243.927316 -51.831632) (xy 243.968498 -51.795945) (xy 244.01434 -51.766482) (xy 244.063908 -51.743843)
			(xy 244.116193 -51.728488) (xy 244.170131 -51.72073) (xy 244.197378 -51.720242) (xy 244.223757 -51.720681)
			(xy 244.276014 -51.727943) (xy 244.326772 -51.742331) (xy 244.375066 -51.763572) (xy 244.419975 -51.79126)
			(xy 244.460644 -51.824869) (xy 244.496297 -51.863757) (xy 244.526255 -51.907184) (xy 244.5385 -51.930554)
			(xy 244.545202 -51.942913) (xy 244.564177 -51.963641) (xy 244.588091 -51.978403) (xy 244.615127 -51.986075)
			(xy 244.643229 -51.986075) (xy 244.670265 -51.978403) (xy 244.694179 -51.963641) (xy 244.713154 -51.942913)
			(xy 244.719856 -51.930554) (xy 244.732095 -51.907182) (xy 244.762059 -51.86376) (xy 244.797716 -51.824876)
			(xy 244.838386 -51.791271) (xy 244.883295 -51.763585) (xy 244.931588 -51.742344) (xy 244.982345 -51.727954)
			(xy 245.034599 -51.720689) (xy 245.060978 -51.720242) (xy 245.088235 -51.720603) (xy 245.142196 -51.728359)
			(xy 245.194503 -51.743715) (xy 245.244093 -51.766359) (xy 245.289955 -51.795831) (xy 245.331155 -51.831529)
			(xy 245.366856 -51.872728) (xy 245.39633 -51.918588) (xy 245.418977 -51.968176) (xy 245.434336 -52.020483)
			(xy 245.442095 -52.074443) (xy 245.442095 -52.128957) (xy 245.434336 -52.182917) (xy 245.418977 -52.235224)
			(xy 245.39633 -52.284812) (xy 245.366856 -52.330672) (xy 245.331155 -52.371871) (xy 245.289955 -52.407569)
			(xy 245.244093 -52.437041) (xy 245.194503 -52.459685) (xy 245.142196 -52.475041) (xy 245.088235 -52.482797)
			(xy 245.060978 -52.483258) (xy 245.0346 -52.482773) (xy 244.982346 -52.475519) (xy 244.931588 -52.461138)
			(xy 244.883295 -52.439904) (xy 244.838386 -52.412222) (xy 244.797716 -52.378619) (xy 244.762062 -52.339736)
			(xy 244.732101 -52.296313) (xy 244.719856 -52.272946) (xy 244.713154 -52.260587) (xy 244.694179 -52.239859)
			(xy 244.670265 -52.225097) (xy 244.643229 -52.217425) (xy 244.615127 -52.217425) (xy 244.588091 -52.225097)
			(xy 244.564177 -52.239859) (xy 244.545202 -52.260587) (xy 244.5385 -52.272946) (xy 244.526294 -52.296336)
			(xy 244.496326 -52.339759) (xy 244.460664 -52.378643) (xy 244.41999 -52.412247) (xy 244.375076 -52.439931)
			(xy 244.326778 -52.461168) (xy 244.276017 -52.475554) (xy 244.223758 -52.482814) (xy 244.197378 -52.483258)
			(xy 244.170131 -52.48267) (xy 244.116193 -52.474912) (xy 244.063908 -52.459557) (xy 244.01434 -52.436918)
			(xy 243.968498 -52.407455) (xy 243.927316 -52.371768) (xy 243.891632 -52.330584) (xy 243.862172 -52.284741)
			(xy 243.839535 -52.235171) (xy 243.824183 -52.182885) (xy 243.816428 -52.128947) (xy 242.268502 -52.128947)
			(xy 242.268502 -52.7177) (xy 242.268925 -52.72777) (xy 242.27664 -52.746374) (xy 242.283488 -52.753768)
			(xy 242.480846 -52.951126) (xy 242.488243 -52.957973) (xy 242.506842 -52.965703) (xy 242.516914 -52.966112)
		)
		(stroke
			(width 0)
			(type solid)
		)
		(fill yes)
		(layer "In11.Cu")
		(net "P12V_E1S_0")
	)
	(gr_poly
		(pts
			(xy 129.468118 -81.31302) (xy 129.477996 -81.312561) (xy 129.496296 -81.30512) (xy 129.503678 -81.298542)
			(xy 129.503932 -81.298288) (xy 129.956814 -80.845406) (xy 129.957322 -80.844898) (xy 129.9639 -80.837516)
			(xy 129.971338 -80.819216) (xy 129.9718 -80.809338) (xy 129.9718 -70.214744) (xy 129.971366 -70.204678)
			(xy 129.963638 -70.186089) (xy 129.956814 -70.178676) (xy 129.631186 -69.853048) (xy 129.624074 -69.845682)
			(xy 129.605278 -69.838062) (xy 114.682778 -69.838062) (xy 114.672711 -69.838491) (xy 114.654118 -69.846218)
			(xy 114.64671 -69.853048) (xy 113.884202 -70.615556) (xy 113.883948 -70.615556) (xy 113.848134 -70.65137)
			(xy 113.840768 -70.658482) (xy 113.833148 -70.677278) (xy 113.833148 -71.348648) (xy 115.0666 -71.348648)
			(xy 115.0666 -71.294152) (xy 115.074355 -71.24021) (xy 115.089708 -71.18792) (xy 115.112346 -71.138348)
			(xy 115.141808 -71.092501) (xy 115.177494 -71.051314) (xy 115.218679 -71.015625) (xy 115.264523 -70.986159)
			(xy 115.314094 -70.963518) (xy 115.366382 -70.948161) (xy 115.420324 -70.940402) (xy 115.447572 -70.939914)
			(xy 115.475973 -70.94045) (xy 115.532143 -70.948907) (xy 115.586435 -70.965607) (xy 115.637647 -70.990182)
			(xy 115.66144 -71.0057) (xy 115.661694 -71.0057) (xy 115.661948 -71.005954) (xy 115.670987 -71.011378)
			(xy 115.691724 -71.015041) (xy 115.70208 -71.013066) (xy 115.774724 -70.995794) (xy 115.784938 -70.992805)
			(xy 115.801862 -70.979936) (xy 115.80749 -70.970902) (xy 115.822018 -70.945803) (xy 115.857558 -70.899975)
			(xy 115.899623 -70.860052) (xy 115.947244 -70.826955) (xy 115.999325 -70.801445) (xy 116.054667 -70.784109)
			(xy 116.111995 -70.775347) (xy 116.140992 -70.774814) (xy 116.168246 -70.775263) (xy 116.222198 -70.783019)
			(xy 116.274498 -70.798375) (xy 116.324079 -70.821019) (xy 116.369933 -70.850488) (xy 116.411127 -70.886183)
			(xy 116.446821 -70.927378) (xy 116.476288 -70.973233) (xy 116.498929 -71.022815) (xy 116.514284 -71.075115)
			(xy 116.522038 -71.129068) (xy 116.5225 -71.156322) (xy 116.522012 -71.183655) (xy 116.514208 -71.237761)
			(xy 116.498762 -71.2902) (xy 116.475991 -71.339898) (xy 116.446362 -71.385838) (xy 116.428774 -71.406766)
			(xy 116.42852 -71.40702) (xy 116.428266 -71.407274) (xy 116.42268 -71.414361) (xy 116.416434 -71.431278)
			(xy 116.416074 -71.440294) (xy 116.416074 -71.50735) (xy 116.41646 -71.516364) (xy 116.422688 -71.533281)
			(xy 116.428266 -71.54037) (xy 116.42852 -71.540624) (xy 116.428774 -71.540878) (xy 116.446366 -71.561805)
			(xy 116.476005 -71.607741) (xy 116.498782 -71.657438) (xy 116.51423 -71.709879) (xy 116.522032 -71.763988)
			(xy 116.5225 -71.791322) (xy 116.522066 -71.817638) (xy 116.51484 -71.869773) (xy 116.500513 -71.920418)
			(xy 116.479359 -71.968613) (xy 116.451779 -72.013441) (xy 116.418297 -72.054051) (xy 116.379549 -72.089671)
			(xy 116.358162 -72.105012) (xy 116.350034 -72.1106) (xy 116.339366 -72.126856) (xy 116.323872 -72.203564)
			(xy 116.32692 -72.222106) (xy 116.332254 -72.230488) (xy 116.345573 -72.253093) (xy 116.366588 -72.301167)
			(xy 116.38081 -72.351669) (xy 116.38797 -72.403644) (xy 116.388388 -72.429878) (xy 116.388388 -72.430386)
			(xy 116.388388 -72.437244) (xy 116.388388 -72.43826) (xy 116.388388 -72.444864) (xy 116.388388 -72.445118)
			(xy 116.388388 -72.445372) (xy 116.387902 -72.472623) (xy 116.380146 -72.526571) (xy 116.368562 -72.566022)
			(xy 119.059704 -72.566022) (xy 119.063775 -72.5104) (xy 119.075901 -72.455963) (xy 119.095824 -72.403872)
			(xy 119.12312 -72.355237) (xy 119.157206 -72.311094) (xy 119.197355 -72.272385) (xy 119.242713 -72.239934)
			(xy 119.292313 -72.214433) (xy 119.345097 -72.196426) (xy 119.39994 -72.186296) (xy 119.455674 -72.184259)
			(xy 119.511111 -72.190359) (xy 119.565068 -72.204465) (xy 119.616397 -72.226277) (xy 119.664003 -72.255331)
			(xy 119.706871 -72.291006) (xy 119.744088 -72.332543) (xy 119.774861 -72.379056) (xy 119.798533 -72.429553)
			(xy 119.814601 -72.48296) (xy 119.822721 -72.538136) (xy 119.82323 -72.566022) (xy 119.822721 -72.593908)
			(xy 119.819349 -72.616822) (xy 122.50877 -72.616822) (xy 122.512843 -72.561163) (xy 122.524978 -72.50669)
			(xy 122.544914 -72.454564) (xy 122.572228 -72.405896) (xy 122.606336 -72.361724) (xy 122.646513 -72.322989)
			(xy 122.691901 -72.290517) (xy 122.741533 -72.264999) (xy 122.794353 -72.24698) (xy 122.849232 -72.236843)
			(xy 122.905003 -72.234805) (xy 122.960477 -72.240908) (xy 123.01447 -72.255024) (xy 123.065833 -72.276851)
			(xy 123.113471 -72.305924) (xy 123.156367 -72.341623) (xy 123.193609 -72.383187) (xy 123.224403 -72.429731)
			(xy 123.248091 -72.480262) (xy 123.264169 -72.533704) (xy 123.272295 -72.588918) (xy 123.272804 -72.616822)
			(xy 123.272295 -72.644726) (xy 123.264169 -72.69994) (xy 123.248091 -72.753382) (xy 123.224403 -72.803913)
			(xy 123.193609 -72.850457) (xy 123.156367 -72.892021) (xy 123.113471 -72.92772) (xy 123.065833 -72.956793)
			(xy 123.01447 -72.97862) (xy 122.960477 -72.992736) (xy 122.905003 -72.998839) (xy 122.849232 -72.996801)
			(xy 122.794353 -72.986664) (xy 122.741533 -72.968645) (xy 122.691901 -72.943127) (xy 122.646513 -72.910655)
			(xy 122.606336 -72.87192) (xy 122.572228 -72.827748) (xy 122.544914 -72.77908) (xy 122.524978 -72.726954)
			(xy 122.512843 -72.672481) (xy 122.50877 -72.616822) (xy 119.819349 -72.616822) (xy 119.814601 -72.649084)
			(xy 119.798533 -72.702491) (xy 119.774861 -72.752988) (xy 119.744088 -72.799501) (xy 119.706871 -72.841038)
			(xy 119.664003 -72.876713) (xy 119.616397 -72.905767) (xy 119.565068 -72.927579) (xy 119.511111 -72.941685)
			(xy 119.455674 -72.947785) (xy 119.39994 -72.945748) (xy 119.345097 -72.935618) (xy 119.292313 -72.917611)
			(xy 119.242713 -72.89211) (xy 119.197355 -72.859659) (xy 119.157206 -72.82095) (xy 119.12312 -72.776807)
			(xy 119.095824 -72.728172) (xy 119.075901 -72.676081) (xy 119.063775 -72.621644) (xy 119.059704 -72.566022)
			(xy 116.368562 -72.566022) (xy 116.364791 -72.578866) (xy 116.342149 -72.628443) (xy 116.312683 -72.674293)
			(xy 116.276992 -72.715484) (xy 116.235801 -72.751175) (xy 116.189951 -72.780641) (xy 116.140374 -72.803283)
			(xy 116.088079 -72.818638) (xy 116.034131 -72.826394) (xy 115.979629 -72.826394) (xy 115.925681 -72.818638)
			(xy 115.873386 -72.803283) (xy 115.823809 -72.780641) (xy 115.777959 -72.751175) (xy 115.736768 -72.715484)
			(xy 115.701077 -72.674293) (xy 115.671611 -72.628443) (xy 115.648969 -72.578866) (xy 115.633614 -72.526571)
			(xy 115.625858 -72.472623) (xy 115.625372 -72.445372) (xy 115.625372 -72.444864) (xy 115.625372 -72.44461)
			(xy 115.625372 -72.43826) (xy 115.625372 -72.437244) (xy 115.625372 -72.430386) (xy 115.625372 -72.429878)
			(xy 115.625875 -72.403323) (xy 115.633284 -72.350731) (xy 115.647915 -72.299674) (xy 115.669485 -72.25114)
			(xy 115.697577 -72.206066) (xy 115.731648 -72.165323) (xy 115.771039 -72.129698) (xy 115.792758 -72.11441)
			(xy 115.80114 -72.108822) (xy 115.812062 -72.092312) (xy 115.82654 -72.0217) (xy 115.823238 -72.00265)
			(xy 115.817904 -71.994268) (xy 115.804068 -71.971359) (xy 115.782222 -71.922503) (xy 115.767414 -71.871074)
			(xy 115.759936 -71.818081) (xy 115.759484 -71.791322) (xy 115.759484 -71.791068) (xy 115.7605 -71.763128)
			(xy 115.761516 -71.749666) (xy 115.75542 -71.73722) (xy 115.752359 -71.731353) (xy 115.743741 -71.721318)
			(xy 115.738402 -71.717408) (xy 115.654074 -71.660258) (xy 115.640104 -71.659242) (xy 115.633609 -71.659083)
			(xy 115.620878 -71.661647) (xy 115.614958 -71.664322) (xy 115.61445 -71.664322) (xy 115.588328 -71.676482)
			(xy 115.533336 -71.693677) (xy 115.476381 -71.702387) (xy 115.447572 -71.70293) (xy 115.420324 -71.702398)
			(xy 115.366382 -71.694639) (xy 115.314094 -71.679282) (xy 115.264523 -71.656641) (xy 115.218679 -71.627175)
			(xy 115.177494 -71.591486) (xy 115.141808 -71.550299) (xy 115.112346 -71.504452) (xy 115.089708 -71.45488)
			(xy 115.074355 -71.40259) (xy 115.0666 -71.348648) (xy 113.833148 -71.348648) (xy 113.833148 -74.038968)
			(xy 120.219214 -74.038968) (xy 120.223285 -73.983346) (xy 120.235411 -73.928909) (xy 120.255334 -73.876818)
			(xy 120.28263 -73.828183) (xy 120.316716 -73.78404) (xy 120.356865 -73.745331) (xy 120.402223 -73.71288)
			(xy 120.451823 -73.687379) (xy 120.504607 -73.669372) (xy 120.55945 -73.659242) (xy 120.615184 -73.657205)
			(xy 120.670621 -73.663305) (xy 120.724578 -73.677411) (xy 120.775907 -73.699223) (xy 120.823513 -73.728277)
			(xy 120.866381 -73.763952) (xy 120.903598 -73.805489) (xy 120.934371 -73.852002) (xy 120.958043 -73.902499)
			(xy 120.974111 -73.955906) (xy 120.982231 -74.011082) (xy 120.982315 -74.01567) (xy 122.273524 -74.01567)
			(xy 122.273524 -73.96113) (xy 122.281286 -73.907144) (xy 122.296652 -73.854812) (xy 122.31931 -73.805201)
			(xy 122.348798 -73.759319) (xy 122.384516 -73.7181) (xy 122.425736 -73.682385) (xy 122.47162 -73.6529)
			(xy 122.521233 -73.630245) (xy 122.573565 -73.614881) (xy 122.627552 -73.607122) (xy 122.654822 -73.60666)
			(xy 122.684158 -73.607172) (xy 122.74214 -73.616146) (xy 122.798063 -73.633895) (xy 122.850608 -73.659999)
			(xy 122.898535 -73.693843) (xy 122.919998 -73.713848) (xy 122.930374 -73.723307) (xy 122.955131 -73.736541)
			(xy 122.982554 -73.742543) (xy 123.010575 -73.740862) (xy 123.037084 -73.731625) (xy 123.060081 -73.715527)
			(xy 123.077834 -73.693782) (xy 123.083828 -73.681082) (xy 123.095317 -73.655801) (xy 123.124497 -73.608556)
			(xy 123.160212 -73.566036) (xy 123.201709 -73.529137) (xy 123.248112 -73.498636) (xy 123.298443 -73.475178)
			(xy 123.35164 -73.459256) (xy 123.406583 -73.451206) (xy 123.434348 -73.450704) (xy 123.461613 -73.451262)
			(xy 123.515586 -73.459028) (xy 123.567905 -73.474396) (xy 123.617505 -73.497053) (xy 123.663376 -73.526538)
			(xy 123.704584 -73.56225) (xy 123.740291 -73.603463) (xy 123.76977 -73.649337) (xy 123.792421 -73.69894)
			(xy 123.807782 -73.751261) (xy 123.815542 -73.805235) (xy 123.815542 -73.859765) (xy 123.807782 -73.913739)
			(xy 123.792421 -73.96606) (xy 123.76977 -74.015663) (xy 123.740291 -74.061537) (xy 123.704584 -74.10275)
			(xy 123.663376 -74.138462) (xy 123.617505 -74.167947) (xy 123.567905 -74.190604) (xy 123.515586 -74.205972)
			(xy 123.461613 -74.213738) (xy 123.434348 -74.214228) (xy 123.405013 -74.213676) (xy 123.347033 -74.204712)
			(xy 123.291111 -74.186973) (xy 123.238565 -74.160878) (xy 123.190637 -74.127042) (xy 123.169172 -74.10704)
			(xy 123.158724 -74.097666) (xy 123.133987 -74.08443) (xy 123.106582 -74.07842) (xy 123.078576 -74.080088)
			(xy 123.052079 -74.08931) (xy 123.029089 -74.10539) (xy 123.011337 -74.127116) (xy 123.005342 -74.139806)
			(xy 122.99387 -74.165096) (xy 122.964689 -74.212341) (xy 122.928972 -74.254862) (xy 122.887473 -74.291762)
			(xy 122.841067 -74.322261) (xy 122.790733 -74.345718) (xy 122.737533 -74.361637) (xy 122.682588 -74.369684)
			(xy 122.654822 -74.370184) (xy 122.627552 -74.369678) (xy 122.573565 -74.361919) (xy 122.521233 -74.346555)
			(xy 122.47162 -74.3239) (xy 122.425736 -74.294415) (xy 122.384516 -74.2587) (xy 122.348798 -74.217481)
			(xy 122.31931 -74.171599) (xy 122.296652 -74.121988) (xy 122.281286 -74.069656) (xy 122.273524 -74.01567)
			(xy 120.982315 -74.01567) (xy 120.98274 -74.038968) (xy 120.982231 -74.066854) (xy 120.974111 -74.12203)
			(xy 120.958043 -74.175437) (xy 120.934371 -74.225934) (xy 120.903598 -74.272447) (xy 120.866381 -74.313984)
			(xy 120.823513 -74.349659) (xy 120.775907 -74.378713) (xy 120.724578 -74.400525) (xy 120.670621 -74.414631)
			(xy 120.615184 -74.420731) (xy 120.55945 -74.418694) (xy 120.504607 -74.408564) (xy 120.451823 -74.390557)
			(xy 120.402223 -74.365056) (xy 120.356865 -74.332605) (xy 120.316716 -74.293896) (xy 120.28263 -74.249753)
			(xy 120.255334 -74.201118) (xy 120.235411 -74.149027) (xy 120.223285 -74.09459) (xy 120.219214 -74.038968)
			(xy 113.833148 -74.038968) (xy 113.833148 -78.016862) (xy 121.734324 -78.016862) (xy 121.738395 -77.96124)
			(xy 121.750521 -77.906803) (xy 121.770444 -77.854712) (xy 121.79774 -77.806077) (xy 121.831826 -77.761934)
			(xy 121.871975 -77.723225) (xy 121.917333 -77.690774) (xy 121.966933 -77.665273) (xy 122.019717 -77.647266)
			(xy 122.07456 -77.637136) (xy 122.130294 -77.635099) (xy 122.174162 -77.639926) (xy 122.569984 -77.639926)
			(xy 122.574055 -77.584304) (xy 122.586181 -77.529867) (xy 122.606104 -77.477776) (xy 122.6334 -77.429141)
			(xy 122.667486 -77.384998) (xy 122.707635 -77.346289) (xy 122.752993 -77.313838) (xy 122.802593 -77.288337)
			(xy 122.855377 -77.27033) (xy 122.91022 -77.2602) (xy 122.965954 -77.258163) (xy 123.021391 -77.264263)
			(xy 123.075348 -77.278369) (xy 123.126677 -77.300181) (xy 123.174283 -77.329235) (xy 123.217151 -77.36491)
			(xy 123.254368 -77.406447) (xy 123.285141 -77.45296) (xy 123.308813 -77.503457) (xy 123.324881 -77.556864)
			(xy 123.333001 -77.61204) (xy 123.33351 -77.639926) (xy 123.333001 -77.667812) (xy 123.324881 -77.722988)
			(xy 123.308813 -77.776395) (xy 123.285141 -77.826892) (xy 123.254368 -77.873405) (xy 123.217151 -77.914942)
			(xy 123.174283 -77.950617) (xy 123.126677 -77.979671) (xy 123.075348 -78.001483) (xy 123.021391 -78.015589)
			(xy 122.965954 -78.021689) (xy 122.91022 -78.019652) (xy 122.855377 -78.009522) (xy 122.802593 -77.991515)
			(xy 122.752993 -77.966014) (xy 122.707635 -77.933563) (xy 122.667486 -77.894854) (xy 122.6334 -77.850711)
			(xy 122.606104 -77.802076) (xy 122.586181 -77.749985) (xy 122.574055 -77.695548) (xy 122.569984 -77.639926)
			(xy 122.174162 -77.639926) (xy 122.185731 -77.641199) (xy 122.239688 -77.655305) (xy 122.291017 -77.677117)
			(xy 122.338623 -77.706171) (xy 122.381491 -77.741846) (xy 122.418708 -77.783383) (xy 122.449481 -77.829896)
			(xy 122.473153 -77.880393) (xy 122.489221 -77.9338) (xy 122.497341 -77.988976) (xy 122.49785 -78.016862)
			(xy 122.497341 -78.044748) (xy 122.489221 -78.099924) (xy 122.473153 -78.153331) (xy 122.449481 -78.203828)
			(xy 122.418708 -78.250341) (xy 122.381491 -78.291878) (xy 122.338623 -78.327553) (xy 122.291017 -78.356607)
			(xy 122.239688 -78.378419) (xy 122.185731 -78.392525) (xy 122.130294 -78.398625) (xy 122.07456 -78.396588)
			(xy 122.019717 -78.386458) (xy 121.966933 -78.368451) (xy 121.917333 -78.34295) (xy 121.871975 -78.310499)
			(xy 121.831826 -78.27179) (xy 121.79774 -78.227647) (xy 121.770444 -78.179012) (xy 121.750521 -78.126921)
			(xy 121.738395 -78.072484) (xy 121.734324 -78.016862) (xy 113.833148 -78.016862) (xy 113.833148 -80.137508)
			(xy 121.321574 -80.137508) (xy 121.325645 -80.081886) (xy 121.337771 -80.027449) (xy 121.357694 -79.975358)
			(xy 121.38499 -79.926723) (xy 121.419076 -79.88258) (xy 121.459225 -79.843871) (xy 121.504583 -79.81142)
			(xy 121.554183 -79.785919) (xy 121.606967 -79.767912) (xy 121.66181 -79.757782) (xy 121.717544 -79.755745)
			(xy 121.772981 -79.761845) (xy 121.826938 -79.775951) (xy 121.878267 -79.797763) (xy 121.925873 -79.826817)
			(xy 121.968741 -79.862492) (xy 122.005958 -79.904029) (xy 122.036731 -79.950542) (xy 122.060403 -80.001039)
			(xy 122.076471 -80.054446) (xy 122.084591 -80.109622) (xy 122.0851 -80.137508) (xy 122.084591 -80.165394)
			(xy 122.076471 -80.22057) (xy 122.060403 -80.273977) (xy 122.036731 -80.324474) (xy 122.005958 -80.370987)
			(xy 121.968741 -80.412524) (xy 121.925873 -80.448199) (xy 121.878267 -80.477253) (xy 121.826938 -80.499065)
			(xy 121.772981 -80.513171) (xy 121.717544 -80.519271) (xy 121.66181 -80.517234) (xy 121.606967 -80.507104)
			(xy 121.554183 -80.489097) (xy 121.504583 -80.463596) (xy 121.459225 -80.431145) (xy 121.419076 -80.392436)
			(xy 121.38499 -80.348293) (xy 121.357694 -80.299658) (xy 121.337771 -80.247567) (xy 121.325645 -80.19313)
			(xy 121.321574 -80.137508) (xy 113.833148 -80.137508) (xy 113.833148 -81.241138) (xy 113.83361 -81.251015)
			(xy 113.841053 -81.269313) (xy 113.847626 -81.276698) (xy 113.84788 -81.276952) (xy 113.868962 -81.298034)
			(xy 113.86947 -81.298542) (xy 113.876851 -81.305123) (xy 113.895151 -81.312569) (xy 113.90503 -81.31302)
		)
		(stroke
			(width 0)
			(type solid)
		)
		(fill yes)
		(layer "In11.Cu")
		(net "GND")
	)
	(gr_poly
		(pts
			(arc
				(start 194.446144 -441.481972)
				(mid 194.482065 -441.467093)
				(end 194.496944 -441.431172)
			)
			(arc
				(start 194.496944 -441.17006)
				(mid 194.792217 -440.457207)
				(end 195.50507 -440.161934)
			)
			(arc
				(start 276.314916 -440.161934)
				(mid 277.027769 -440.457207)
				(end 277.323042 -441.17006)
			)
			(arc
				(start 277.323042 -441.431172)
				(mid 277.337921 -441.467093)
				(end 277.373842 -441.481972)
			)
			(arc
				(start 463.300064 -441.481972)
				(mid 464.355064 -441.044976)
				(end 464.79206 -439.989976)
			)
			(arc
				(start 464.79206 -409.528264)
				(mid 464.983018 -408.568632)
				(end 465.526628 -407.75509)
			)
			(arc
				(start 467.355174 -405.926544)
				(mid 467.678507 -405.442687)
				(end 467.792054 -404.871936)
			)
			(arc
				(start 467.792054 -363.649514)
				(mid 467.554484 -364.078202)
				(end 467.284816 -364.48746)
			)
			(arc
				(start 467.284816 -404.871936)
				(mid 467.209909 -405.248606)
				(end 466.996526 -405.567896)
			)
			(arc
				(start 465.16798 -407.396442)
				(mid 464.51433 -408.374514)
				(end 464.284568 -409.528264)
			)
			(arc
				(start 464.284568 -439.989976)
				(mid 463.996213 -440.686125)
				(end 463.300064 -440.97448)
			)
			(xy 410.910278 -440.97448) (xy 410.906976 -440.97575)
			(arc
				(start 410.903166 -440.976766)
				(mid 410.827611 -440.994391)
				(end 410.750258 -441.000388)
			)
			(arc
				(start 410.74975 -441.000388)
				(mid 410.672393 -440.994416)
				(end 410.596842 -440.976766)
			)
			(xy 410.593032 -440.97575) (xy 410.58973 -440.97448) (xy 406.910286 -440.97448) (xy 406.906984 -440.97575)
			(arc
				(start 406.903174 -440.976766)
				(mid 406.827619 -440.994391)
				(end 406.750266 -441.000388)
			)
			(arc
				(start 406.749758 -441.000388)
				(mid 406.672401 -440.994416)
				(end 406.59685 -440.976766)
			)
			(xy 406.59304 -440.97575) (xy 406.589738 -440.97448) (xy 402.910294 -440.97448) (xy 402.906992 -440.97575)
			(arc
				(start 402.903182 -440.976766)
				(mid 402.827627 -440.994391)
				(end 402.750274 -441.000388)
			)
			(arc
				(start 402.749766 -441.000388)
				(mid 402.672409 -440.994416)
				(end 402.596858 -440.976766)
			)
			(xy 402.593048 -440.97575) (xy 402.589746 -440.97448) (xy 398.910302 -440.97448) (xy 398.904714 -440.976512)
			(xy 398.903444 -440.976766)
			(arc
				(start 398.902936 -440.97702)
				(mid 398.827497 -440.994504)
				(end 398.750282 -441.000388)
			)
			(arc
				(start 398.749774 -441.000388)
				(mid 398.672557 -440.994515)
				(end 398.59712 -440.97702)
			)
			(xy 398.596612 -440.976766) (xy 398.589754 -440.97448) (xy 393.910058 -440.97448) (xy 393.906756 -440.97575)
			(arc
				(start 393.902946 -440.976766)
				(mid 393.827391 -440.994391)
				(end 393.750038 -441.000388)
			)
			(arc
				(start 393.74953 -441.000388)
				(mid 393.672173 -440.994416)
				(end 393.596622 -440.976766)
			)
			(xy 393.592812 -440.97575) (xy 393.58951 -440.97448) (xy 389.910066 -440.97448) (xy 389.906764 -440.97575)
			(arc
				(start 389.902954 -440.976766)
				(mid 389.827399 -440.994391)
				(end 389.750046 -441.000388)
			)
			(arc
				(start 389.749538 -441.000388)
				(mid 389.672181 -440.994416)
				(end 389.59663 -440.976766)
			)
			(xy 389.59282 -440.97575) (xy 389.589518 -440.97448) (xy 385.910074 -440.97448) (xy 385.906772 -440.97575)
			(arc
				(start 385.902962 -440.976766)
				(mid 385.827407 -440.994391)
				(end 385.750054 -441.000388)
			)
			(arc
				(start 385.749546 -441.000388)
				(mid 385.672189 -440.994416)
				(end 385.596638 -440.976766)
			)
			(xy 385.592828 -440.97575) (xy 385.589526 -440.97448) (xy 381.910082 -440.97448) (xy 381.904494 -440.976512)
			(xy 381.903224 -440.976766)
			(arc
				(start 381.902716 -440.97702)
				(mid 381.827277 -440.994504)
				(end 381.750062 -441.000388)
			)
			(arc
				(start 381.749554 -441.000388)
				(mid 381.672337 -440.994515)
				(end 381.5969 -440.97702)
			)
			(xy 381.596392 -440.976766) (xy 381.589534 -440.97448) (xy 343.810082 -440.97448) (xy 343.80678 -440.97575)
			(arc
				(start 343.80297 -440.976766)
				(mid 343.727415 -440.994391)
				(end 343.650062 -441.000388)
			)
			(arc
				(start 343.649554 -441.000388)
				(mid 343.572197 -440.994416)
				(end 343.496646 -440.976766)
			)
			(xy 343.492836 -440.97575) (xy 343.489534 -440.97448) (xy 339.81009 -440.97448) (xy 339.806788 -440.97575)
			(arc
				(start 339.802978 -440.976766)
				(mid 339.727423 -440.994391)
				(end 339.65007 -441.000388)
			)
			(arc
				(start 339.649562 -441.000388)
				(mid 339.572205 -440.994416)
				(end 339.496654 -440.976766)
			)
			(xy 339.492844 -440.97575) (xy 339.489542 -440.97448) (xy 335.810098 -440.97448) (xy 335.806796 -440.97575)
			(arc
				(start 335.802986 -440.976766)
				(mid 335.727431 -440.994391)
				(end 335.650078 -441.000388)
			)
			(arc
				(start 335.64957 -441.000388)
				(mid 335.572213 -440.994416)
				(end 335.496662 -440.976766)
			)
			(xy 335.492852 -440.97575) (xy 335.48955 -440.97448) (xy 331.810106 -440.97448) (xy 331.804518 -440.976512)
			(xy 331.803248 -440.976766)
			(arc
				(start 331.80274 -440.97702)
				(mid 331.727301 -440.994504)
				(end 331.650086 -441.000388)
			)
			(arc
				(start 331.649578 -441.000388)
				(mid 331.572361 -440.994515)
				(end 331.496924 -440.97702)
			)
			(xy 331.496416 -440.976766) (xy 331.489558 -440.97448) (xy 326.810116 -440.97448) (xy 326.806814 -440.97575)
			(arc
				(start 326.803004 -440.976766)
				(mid 326.727449 -440.994391)
				(end 326.650096 -441.000388)
			)
			(arc
				(start 326.649588 -441.000388)
				(mid 326.572231 -440.994416)
				(end 326.49668 -440.976766)
			)
			(xy 326.49287 -440.97575) (xy 326.489568 -440.97448) (xy 322.810124 -440.97448) (xy 322.806822 -440.97575)
			(arc
				(start 322.803012 -440.976766)
				(mid 322.727457 -440.994391)
				(end 322.650104 -441.000388)
			)
			(arc
				(start 322.649596 -441.000388)
				(mid 322.572239 -440.994416)
				(end 322.496688 -440.976766)
			)
			(xy 322.492878 -440.97575) (xy 322.489576 -440.97448) (xy 318.810132 -440.97448) (xy 318.80683 -440.97575)
			(arc
				(start 318.80302 -440.976766)
				(mid 318.727465 -440.994391)
				(end 318.650112 -441.000388)
			)
			(arc
				(start 318.649604 -441.000388)
				(mid 318.572247 -440.994416)
				(end 318.496696 -440.976766)
			)
			(xy 318.492886 -440.97575) (xy 318.489584 -440.97448) (xy 314.81014 -440.97448) (xy 314.804552 -440.976512)
			(xy 314.803282 -440.976766)
			(arc
				(start 314.802774 -440.97702)
				(mid 314.727335 -440.994504)
				(end 314.65012 -441.000388)
			)
			(arc
				(start 314.649612 -441.000388)
				(mid 314.572395 -440.994515)
				(end 314.496958 -440.97702)
			)
			(xy 314.49645 -440.976766) (xy 314.489592 -440.97448)
			(arc
				(start 277.817834 -440.97448)
				(mid 277.314992 -440.031472)
				(end 276.314916 -439.654696)
			)
			(arc
				(start 195.50507 -439.654696)
				(mid 194.504998 -440.031475)
				(end 194.002152 -440.97448)
			)
			(xy 154.910282 -440.97448) (xy 154.90698 -440.97575)
			(arc
				(start 154.90317 -440.976766)
				(mid 154.827615 -440.994391)
				(end 154.750262 -441.000388)
			)
			(arc
				(start 154.749754 -441.000388)
				(mid 154.672397 -440.994416)
				(end 154.596846 -440.976766)
			)
			(xy 154.593036 -440.97575) (xy 154.589734 -440.97448) (xy 150.91029 -440.97448) (xy 150.906988 -440.97575)
			(arc
				(start 150.903178 -440.976766)
				(mid 150.827623 -440.994391)
				(end 150.75027 -441.000388)
			)
			(arc
				(start 150.749762 -441.000388)
				(mid 150.672405 -440.994416)
				(end 150.596854 -440.976766)
			)
			(xy 150.593044 -440.97575) (xy 150.589742 -440.97448) (xy 146.910298 -440.97448) (xy 146.906996 -440.97575)
			(arc
				(start 146.903186 -440.976766)
				(mid 146.827631 -440.994391)
				(end 146.750278 -441.000388)
			)
			(arc
				(start 146.74977 -441.000388)
				(mid 146.672413 -440.994416)
				(end 146.596862 -440.976766)
			)
			(xy 146.593052 -440.97575) (xy 146.58975 -440.97448) (xy 142.910306 -440.97448) (xy 142.904718 -440.976512)
			(xy 142.903448 -440.976766)
			(arc
				(start 142.90294 -440.97702)
				(mid 142.827501 -440.994504)
				(end 142.750286 -441.000388)
			)
			(arc
				(start 142.749778 -441.000388)
				(mid 142.672561 -440.994515)
				(end 142.597124 -440.97702)
			)
			(xy 142.596616 -440.976766) (xy 142.589758 -440.97448) (xy 137.910062 -440.97448) (xy 137.90676 -440.97575)
			(arc
				(start 137.90295 -440.976766)
				(mid 137.827395 -440.994391)
				(end 137.750042 -441.000388)
			)
			(arc
				(start 137.749534 -441.000388)
				(mid 137.672177 -440.994416)
				(end 137.596626 -440.976766)
			)
			(xy 137.592816 -440.97575) (xy 137.589514 -440.97448) (xy 133.91007 -440.97448) (xy 133.906768 -440.97575)
			(arc
				(start 133.902958 -440.976766)
				(mid 133.827403 -440.994391)
				(end 133.75005 -441.000388)
			)
			(arc
				(start 133.749542 -441.000388)
				(mid 133.672185 -440.994416)
				(end 133.596634 -440.976766)
			)
			(xy 133.592824 -440.97575) (xy 133.589522 -440.97448) (xy 129.910078 -440.97448) (xy 129.906776 -440.97575)
			(arc
				(start 129.902966 -440.976766)
				(mid 129.827411 -440.994391)
				(end 129.750058 -441.000388)
			)
			(arc
				(start 129.74955 -441.000388)
				(mid 129.672193 -440.994416)
				(end 129.596642 -440.976766)
			)
			(xy 129.592832 -440.97575) (xy 129.58953 -440.97448) (xy 125.910086 -440.97448) (xy 125.904498 -440.976512)
			(xy 125.903228 -440.976766)
			(arc
				(start 125.90272 -440.97702)
				(mid 125.827281 -440.994504)
				(end 125.750066 -441.000388)
			)
			(arc
				(start 125.749558 -441.000388)
				(mid 125.672341 -440.994515)
				(end 125.596904 -440.97702)
			)
			(xy 125.596396 -440.976766) (xy 125.589538 -440.97448) (xy 87.81034 -440.97448) (xy 87.807038 -440.97575)
			(arc
				(start 87.803228 -440.976766)
				(mid 87.727673 -440.994391)
				(end 87.65032 -441.000388)
			)
			(arc
				(start 87.649812 -441.000388)
				(mid 87.572455 -440.994416)
				(end 87.496904 -440.976766)
			)
			(xy 87.493094 -440.97575) (xy 87.489792 -440.97448) (xy 83.810348 -440.97448) (xy 83.807046 -440.97575)
			(arc
				(start 83.803236 -440.976766)
				(mid 83.727681 -440.994391)
				(end 83.650328 -441.000388)
			)
			(arc
				(start 83.64982 -441.000388)
				(mid 83.572463 -440.994416)
				(end 83.496912 -440.976766)
			)
			(xy 83.493102 -440.97575) (xy 83.4898 -440.97448) (xy 79.810356 -440.97448) (xy 79.807054 -440.97575)
			(arc
				(start 79.803244 -440.976766)
				(mid 79.727689 -440.994391)
				(end 79.650336 -441.000388)
			)
			(arc
				(start 79.649828 -441.000388)
				(mid 79.572471 -440.994416)
				(end 79.49692 -440.976766)
			)
			(xy 79.49311 -440.97575) (xy 79.489808 -440.97448) (xy 75.810364 -440.97448) (xy 75.804776 -440.976512)
			(xy 75.803506 -440.976766)
			(arc
				(start 75.802998 -440.97702)
				(mid 75.727559 -440.994504)
				(end 75.650344 -441.000388)
			)
			(arc
				(start 75.649836 -441.000388)
				(mid 75.572619 -440.994515)
				(end 75.497182 -440.97702)
			)
			(xy 75.496674 -440.976766) (xy 75.489816 -440.97448) (xy 70.81012 -440.97448) (xy 70.806818 -440.97575)
			(arc
				(start 70.803008 -440.976766)
				(mid 70.727453 -440.994391)
				(end 70.6501 -441.000388)
			)
			(arc
				(start 70.649592 -441.000388)
				(mid 70.572235 -440.994416)
				(end 70.496684 -440.976766)
			)
			(xy 70.492874 -440.97575) (xy 70.489572 -440.97448) (xy 66.810128 -440.97448) (xy 66.806826 -440.97575)
			(arc
				(start 66.803016 -440.976766)
				(mid 66.727461 -440.994391)
				(end 66.650108 -441.000388)
			)
			(arc
				(start 66.6496 -441.000388)
				(mid 66.572243 -440.994416)
				(end 66.496692 -440.976766)
			)
			(xy 66.492882 -440.97575) (xy 66.48958 -440.97448) (xy 62.810136 -440.97448) (xy 62.806834 -440.97575)
			(arc
				(start 62.803024 -440.976766)
				(mid 62.727469 -440.994391)
				(end 62.650116 -441.000388)
			)
			(arc
				(start 62.649608 -441.000388)
				(mid 62.572251 -440.994416)
				(end 62.4967 -440.976766)
			)
			(xy 62.49289 -440.97575) (xy 62.489588 -440.97448) (xy 58.810144 -440.97448) (xy 58.803286 -440.976766)
			(arc
				(start 58.802778 -440.97702)
				(mid 58.727339 -440.994504)
				(end 58.650124 -441.000388)
			)
			(arc
				(start 58.649616 -441.000388)
				(mid 58.572399 -440.994515)
				(end 58.496962 -440.97702)
			)
			(xy 58.496454 -440.976766) (xy 58.495184 -440.976512) (xy 58.489596 -440.97448)
			(arc
				(start 8.50011 -440.97448)
				(mid 7.803871 -440.686141)
				(end 7.515352 -439.989976)
			)
			(arc
				(start 7.515352 -409.528518)
				(mid 7.285694 -408.374511)
				(end 6.63194 -407.396188)
			)
			(arc
				(start 3.303778 -404.068026)
				(mid 3.090447 -403.748703)
				(end 3.015488 -403.372066)
			)
			(xy 3.015488 -353.421188) (xy 2.72034 -353.12604) (xy 2.574036 -353.12604) (xy 2.507996 -353.19208)
			(arc
				(start 2.507996 -403.371812)
				(mid 2.621533 -403.942691)
				(end 2.944876 -404.426674)
			)
			(arc
				(start 6.273292 -407.75509)
				(mid 6.817042 -408.568731)
				(end 7.008114 -409.528518)
			)
			(arc
				(start 7.008114 -439.989976)
				(mid 7.44511 -441.044976)
				(end 8.50011 -441.481972)
			)
		)
		(stroke
			(width 0)
			(type solid)
		)
		(fill yes)
		(layer "In11.Cu")
		(net "GND")
	)
	(gr_poly
		(pts
			(xy 440.24677 -419.94074) (xy 440.259343 -419.940013) (xy 440.281449 -419.928011) (xy 440.288934 -419.91788)
			(xy 440.343036 -419.8366) (xy 440.345068 -419.8112) (xy 440.339988 -419.799262) (xy 440.327064 -419.767627)
			(xy 440.308867 -419.701757) (xy 440.299673 -419.634041) (xy 440.299094 -419.599872) (xy 440.299094 -419.59911)
			(xy 440.299596 -419.567149) (xy 440.307607 -419.503731) (xy 440.323504 -419.441817) (xy 440.347036 -419.382384)
			(xy 440.37783 -419.326369) (xy 440.415403 -419.274654) (xy 440.45916 -419.228057) (xy 440.508413 -419.187312)
			(xy 440.562384 -419.153061) (xy 440.620223 -419.125844) (xy 440.681016 -419.106091) (xy 440.743806 -419.094113)
			(xy 440.807602 -419.0901) (xy 440.871398 -419.094113) (xy 440.934188 -419.106091) (xy 440.994981 -419.125844)
			(xy 441.05282 -419.153061) (xy 441.106791 -419.187312) (xy 441.156044 -419.228057) (xy 441.199801 -419.274654)
			(xy 441.237374 -419.326369) (xy 441.268168 -419.382384) (xy 441.2917 -419.441817) (xy 441.307597 -419.503731)
			(xy 441.315608 -419.567149) (xy 441.31611 -419.59911) (xy 441.31611 -419.599872) (xy 441.315522 -419.634039)
			(xy 441.306312 -419.701752) (xy 441.288133 -419.767625) (xy 441.275216 -419.799262) (xy 441.270136 -419.8112)
			(xy 441.272168 -419.8366) (xy 441.32627 -419.91788) (xy 441.333742 -419.928019) (xy 441.35586 -419.940002)
			(xy 441.368434 -419.94074) (xy 442.657738 -419.94074) (xy 442.667715 -419.940305) (xy 442.686185 -419.932768)
			(xy 442.700365 -419.918738) (xy 442.704728 -419.909752) (xy 442.740796 -419.823138) (xy 442.744308 -419.813813)
			(xy 442.744491 -419.793903) (xy 442.737033 -419.775442) (xy 442.730382 -419.76802) (xy 442.707756 -419.744186)
			(xy 442.668196 -419.691709) (xy 442.635726 -419.634572) (xy 442.610885 -419.57373) (xy 442.594088 -419.510195)
			(xy 442.585615 -419.445025) (xy 442.585094 -419.412166) (xy 442.585596 -419.380205) (xy 442.593607 -419.316787)
			(xy 442.609504 -419.254873) (xy 442.633036 -419.19544) (xy 442.66383 -419.139425) (xy 442.701403 -419.08771)
			(xy 442.74516 -419.041113) (xy 442.794413 -419.000368) (xy 442.848384 -418.966117) (xy 442.906223 -418.9389)
			(xy 442.967016 -418.919147) (xy 443.029806 -418.907169) (xy 443.093602 -418.903156) (xy 443.157398 -418.907169)
			(xy 443.220188 -418.919147) (xy 443.280981 -418.9389) (xy 443.33882 -418.966117) (xy 443.392791 -419.000368)
			(xy 443.442044 -419.041113) (xy 443.485801 -419.08771) (xy 443.523374 -419.139425) (xy 443.554168 -419.19544)
			(xy 443.5777 -419.254873) (xy 443.593597 -419.316787) (xy 443.601608 -419.380205) (xy 443.60211 -419.412166)
			(xy 443.601596 -419.445026) (xy 443.593131 -419.510199) (xy 443.57634 -419.573739) (xy 443.5515 -419.634584)
			(xy 443.519027 -419.691722) (xy 443.479462 -419.744199) (xy 443.456822 -419.76802) (xy 443.45024 -419.77548)
			(xy 443.442841 -419.793925) (xy 443.442984 -419.813799) (xy 443.446408 -419.823138) (xy 443.482476 -419.909752)
			(xy 443.486813 -419.91875) (xy 443.501015 -419.932766) (xy 443.519488 -419.94031) (xy 443.529466 -419.94074)
			(xy 444.176658 -419.94074) (xy 444.188284 -419.940173) (xy 444.209192 -419.929998) (xy 444.21679 -419.921182)
			(xy 444.237505 -419.895502) (xy 444.284492 -419.849185) (xy 444.337076 -419.809334) (xy 444.394372 -419.776619)
			(xy 444.455418 -419.75159) (xy 444.519189 -419.734666) (xy 444.584613 -419.726133) (xy 444.650591 -419.726133)
			(xy 444.716015 -419.734666) (xy 444.779786 -419.75159) (xy 444.840832 -419.776619) (xy 444.898128 -419.809334)
			(xy 444.950712 -419.849185) (xy 444.997699 -419.895502) (xy 445.018414 -419.921182) (xy 445.025998 -419.930025)
			(xy 445.046909 -419.940239) (xy 445.058546 -419.94074) (xy 445.446658 -419.94074) (xy 445.458284 -419.940173)
			(xy 445.479192 -419.929998) (xy 445.48679 -419.921182) (xy 445.507505 -419.895502) (xy 445.554492 -419.849185)
			(xy 445.607076 -419.809334) (xy 445.664372 -419.776619) (xy 445.725418 -419.75159) (xy 445.789189 -419.734666)
			(xy 445.854613 -419.726133) (xy 445.920591 -419.726133) (xy 445.986015 -419.734666) (xy 446.049786 -419.75159)
			(xy 446.110832 -419.776619) (xy 446.168128 -419.809334) (xy 446.220712 -419.849185) (xy 446.267699 -419.895502)
			(xy 446.288414 -419.921182) (xy 446.295998 -419.930025) (xy 446.316909 -419.940239) (xy 446.328546 -419.94074)
			(xy 449.612258 -419.94074) (xy 449.622322 -419.940305) (xy 449.640906 -419.932569) (xy 449.648326 -419.925754)
			(xy 449.666614 -419.907466) (xy 449.673465 -419.90007) (xy 449.6812 -419.881471) (xy 449.6816 -419.871398)
			(xy 449.6816 -418.895022) (xy 449.681162 -418.884958) (xy 449.673428 -418.866374) (xy 449.666614 -418.858954)
			(xy 449.447412 -418.639752) (xy 449.438795 -418.631957) (xy 449.416838 -418.624432) (xy 449.405248 -418.625274)
			(xy 449.314316 -418.63645) (xy 449.294758 -418.64915) (xy 449.288662 -418.659056) (xy 449.266779 -418.694416)
			(xy 449.217379 -418.761317) (xy 449.161951 -418.823315) (xy 449.100979 -418.87987) (xy 449.034995 -418.930488)
			(xy 448.964575 -418.974726) (xy 448.890334 -419.0122) (xy 448.81292 -419.042581) (xy 448.733008 -419.065605)
			(xy 448.651296 -419.08107) (xy 448.568497 -419.088842) (xy 448.526916 -419.089332) (xy 448.485813 -419.088858)
			(xy 448.403956 -419.081275) (xy 448.323149 -419.066171) (xy 448.24408 -419.043675) (xy 448.167424 -419.01398)
			(xy 448.093835 -418.977339) (xy 448.02394 -418.934064) (xy 447.958337 -418.884525) (xy 447.897584 -418.829144)
			(xy 447.8422 -418.768394) (xy 447.792658 -418.702793) (xy 447.74938 -418.6329) (xy 447.712736 -418.559313)
			(xy 447.683037 -418.482658) (xy 447.660539 -418.40359) (xy 447.645431 -418.322783) (xy 447.637844 -418.240927)
			(xy 447.637408 -418.199824) (xy 447.637889 -418.158241) (xy 447.645651 -418.075439) (xy 447.661109 -417.993723)
			(xy 447.684127 -417.913807) (xy 447.714506 -417.836389) (xy 447.751979 -417.762145) (xy 447.79622 -417.691723)
			(xy 447.846842 -417.625739) (xy 447.903402 -417.564769) (xy 447.965408 -417.509345) (xy 448.032316 -417.459952)
			(xy 448.067684 -417.438078) (xy 448.07759 -417.431982) (xy 448.09029 -417.412424) (xy 448.101466 -417.321492)
			(xy 448.102363 -417.309896) (xy 448.094824 -417.287922) (xy 448.086988 -417.279328) (xy 447.834766 -417.027106)
			(xy 447.827366 -417.020264) (xy 447.808768 -417.012541) (xy 447.798698 -417.01212) (xy 446.849754 -417.01212)
			(xy 446.840224 -417.012506) (xy 446.822475 -417.019447) (xy 446.808487 -417.03239) (xy 446.804034 -417.040822)
			(xy 446.757806 -417.136834) (xy 446.761108 -417.165282) (xy 446.770252 -417.176966) (xy 446.785916 -417.197314)
			(xy 446.812222 -417.241414) (xy 446.832378 -417.288643) (xy 446.846021 -417.338148) (xy 446.852904 -417.389035)
			(xy 446.85331 -417.41471) (xy 446.852824 -417.441961) (xy 446.845068 -417.495909) (xy 446.829713 -417.548204)
			(xy 446.807071 -417.597781) (xy 446.777605 -417.643631) (xy 446.741914 -417.684822) (xy 446.700723 -417.720513)
			(xy 446.654873 -417.749979) (xy 446.605296 -417.772621) (xy 446.553001 -417.787976) (xy 446.499053 -417.795732)
			(xy 446.444551 -417.795732) (xy 446.390603 -417.787976) (xy 446.338308 -417.772621) (xy 446.288731 -417.749979)
			(xy 446.242881 -417.720513) (xy 446.20169 -417.684822) (xy 446.165999 -417.643631) (xy 446.136533 -417.597781)
			(xy 446.113891 -417.548204) (xy 446.098536 -417.495909) (xy 446.09078 -417.441961) (xy 446.090294 -417.41471)
			(xy 446.090728 -417.388801) (xy 446.097744 -417.337459) (xy 446.111649 -417.28754) (xy 446.132186 -417.239965)
			(xy 446.158977 -417.195609) (xy 446.191528 -417.155289) (xy 446.229239 -417.11975) (xy 446.25006 -417.104322)
			(xy 446.259569 -417.096707) (xy 446.27071 -417.075083) (xy 446.271396 -417.06292) (xy 446.27098 -417.052896)
			(xy 446.263313 -417.034373) (xy 446.24914 -417.020196) (xy 446.23062 -417.012523) (xy 446.220596 -417.01212)
			(xy 446.134744 -417.01212) (xy 446.122935 -417.012731) (xy 446.101778 -417.023232) (xy 446.087475 -417.042029)
			(xy 446.084706 -417.053522) (xy 446.079063 -417.080762) (xy 446.060936 -417.133354) (xy 446.035363 -417.182756)
			(xy 446.002886 -417.22792) (xy 445.964195 -417.267888) (xy 445.920109 -417.301814) (xy 445.871563 -417.328976)
			(xy 445.819587 -417.3488) (xy 445.765283 -417.360865) (xy 445.709802 -417.364916) (xy 445.654321 -417.360865)
			(xy 445.600017 -417.3488) (xy 445.548041 -417.328976) (xy 445.499495 -417.301814) (xy 445.455409 -417.267888)
			(xy 445.416718 -417.22792) (xy 445.384241 -417.182756) (xy 445.358668 -417.133354) (xy 445.340541 -417.080762)
			(xy 445.334898 -417.053522) (xy 445.332126 -417.04202) (xy 445.317863 -417.023178) (xy 445.296678 -417.012708)
			(xy 445.28486 -417.01212) (xy 444.41491 -417.01212) (xy 444.404965 -417.012594) (xy 444.386571 -417.020158)
			(xy 444.372438 -417.034153) (xy 444.364694 -417.052473) (xy 444.36411 -417.062412) (xy 444.3634 -417.089509)
			(xy 444.355264 -417.1431) (xy 444.339625 -417.194999) (xy 444.316798 -417.244163) (xy 444.287242 -417.289601)
			(xy 444.251552 -417.330398) (xy 444.210448 -417.365733) (xy 444.164756 -417.394895) (xy 444.115396 -417.417296)
			(xy 444.063363 -417.432485) (xy 444.009704 -417.440157) (xy 443.9555 -417.440157) (xy 443.901841 -417.432485)
			(xy 443.849808 -417.417296) (xy 443.800448 -417.394895) (xy 443.754756 -417.365733) (xy 443.713652 -417.330398)
			(xy 443.677962 -417.289601) (xy 443.648406 -417.244163) (xy 443.625579 -417.194999) (xy 443.60994 -417.1431)
			(xy 443.601804 -417.089509) (xy 443.601094 -417.062412) (xy 443.60084 -417.04133) (xy 443.571376 -417.01212)
			(xy 442.72962 -417.01212) (xy 442.722254 -417.005008) (xy 441.86602 -417.005008) (xy 441.855956 -417.004571)
			(xy 441.837372 -416.996837) (xy 441.829952 -416.990022) (xy 439.287158 -414.447228) (xy 439.280316 -414.439829)
			(xy 439.272599 -414.42123) (xy 439.272172 -414.41116) (xy 439.272172 -407.284428) (xy 439.27152 -407.272203)
			(xy 439.260374 -407.250448) (xy 439.250836 -407.242772) (xy 439.228266 -407.226176) (xy 439.187786 -407.187451)
			(xy 439.153406 -407.143221) (xy 439.125866 -407.094437) (xy 439.10576 -407.042149) (xy 439.09352 -406.987482)
			(xy 439.08941 -406.931613) (xy 439.093517 -406.875743) (xy 439.105753 -406.821075) (xy 439.125855 -406.768786)
			(xy 439.153392 -406.72) (xy 439.187768 -406.675768) (xy 439.228247 -406.63704) (xy 439.250836 -406.620472)
			(xy 439.260385 -406.612806) (xy 439.271532 -406.591045) (xy 439.272172 -406.578816) (xy 439.272172 -394.21689)
			(xy 439.27175 -394.206872) (xy 439.264077 -394.188364) (xy 439.249905 -394.174201) (xy 439.23139 -394.166542)
			(xy 439.221372 -394.16609) (xy 438.478168 -394.16609) (xy 438.469278 -394.169646) (xy 438.445433 -394.178595)
			(xy 438.395993 -394.19083) (xy 438.370726 -394.19403) (xy 438.361888 -394.195353) (xy 438.345888 -394.20329)
			(xy 438.339484 -394.209524) (xy 438.31891 -394.231368) (xy 438.312538 -394.238693) (xy 438.305375 -394.256719)
			(xy 438.30494 -394.26642) (xy 438.30494 -398.60728) (xy 438.305448 -398.61109) (xy 438.315173 -398.68047)
			(xy 438.32872 -398.819928) (xy 438.335506 -398.959879) (xy 438.335928 -399.029936) (xy 438.335505 -399.099993)
			(xy 438.328719 -399.239944) (xy 438.315175 -399.379402) (xy 438.305448 -399.448782) (xy 438.30494 -399.452592)
			(xy 438.30494 -401.098258) (xy 438.304505 -401.108322) (xy 438.296769 -401.126906) (xy 438.289954 -401.134326)
			(xy 435.815486 -403.608794) (xy 435.808629 -403.616188) (xy 435.800879 -403.634787) (xy 435.8005 -403.644862)
			(xy 435.8005 -405.11476) (xy 436.470804 -405.11476) (xy 436.474875 -405.059138) (xy 436.487001 -405.004701)
			(xy 436.506924 -404.95261) (xy 436.53422 -404.903975) (xy 436.568306 -404.859832) (xy 436.608455 -404.821123)
			(xy 436.653813 -404.788672) (xy 436.703413 -404.763171) (xy 436.756197 -404.745164) (xy 436.81104 -404.735034)
			(xy 436.866774 -404.732997) (xy 436.922211 -404.739097) (xy 436.976168 -404.753203) (xy 437.027497 -404.775015)
			(xy 437.075103 -404.804069) (xy 437.117971 -404.839744) (xy 437.155188 -404.881281) (xy 437.185961 -404.927794)
			(xy 437.209633 -404.978291) (xy 437.225701 -405.031698) (xy 437.233821 -405.086874) (xy 437.23433 -405.11476)
			(xy 437.233821 -405.142646) (xy 437.225701 -405.197822) (xy 437.209633 -405.251229) (xy 437.185961 -405.301726)
			(xy 437.155188 -405.348239) (xy 437.117971 -405.389776) (xy 437.075103 -405.425451) (xy 437.027497 -405.454505)
			(xy 436.976168 -405.476317) (xy 436.922211 -405.490423) (xy 436.866774 -405.496523) (xy 436.81104 -405.494486)
			(xy 436.756197 -405.484356) (xy 436.703413 -405.466349) (xy 436.653813 -405.440848) (xy 436.608455 -405.408397)
			(xy 436.568306 -405.369688) (xy 436.53422 -405.325545) (xy 436.506924 -405.27691) (xy 436.487001 -405.224819)
			(xy 436.474875 -405.170382) (xy 436.470804 -405.11476) (xy 435.8005 -405.11476) (xy 435.8005 -405.130762)
			(xy 435.800908 -405.140008) (xy 435.807468 -405.157298) (xy 435.819719 -405.17115) (xy 435.836077 -405.179775)
			(xy 435.845204 -405.181308) (xy 435.845458 -405.181308) (xy 435.877327 -405.185556) (xy 435.939724 -405.201064)
			(xy 435.999667 -405.224314) (xy 436.056202 -405.254935) (xy 436.108425 -405.292439) (xy 436.155504 -405.336226)
			(xy 436.196687 -405.3856) (xy 436.231318 -405.439771) (xy 436.258844 -405.497876) (xy 436.278825 -405.558987)
			(xy 436.290942 -405.622129) (xy 436.295004 -405.686295) (xy 436.290944 -405.750462) (xy 436.278827 -405.813604)
			(xy 436.258847 -405.874716) (xy 436.231323 -405.932821) (xy 436.196693 -405.986993) (xy 436.155511 -406.036367)
			(xy 436.108432 -406.080155) (xy 436.05621 -406.11766) (xy 435.999676 -406.148282) (xy 435.939733 -406.171533)
			(xy 435.877336 -406.187042) (xy 435.845458 -406.191212) (xy 435.845204 -406.191212) (xy 435.836064 -406.192711)
			(xy 435.819674 -406.201306) (xy 435.807422 -406.215177) (xy 435.800916 -406.232502) (xy 435.8005 -406.241758)
			(xy 435.8005 -409.68676) (xy 436.471314 -409.68676) (xy 436.47185 -409.658127) (xy 436.480414 -409.601505)
			(xy 436.497343 -409.546798) (xy 436.522258 -409.495235) (xy 436.554598 -409.447975) (xy 436.593638 -409.406079)
			(xy 436.6385 -409.370487) (xy 436.663084 -409.355798) (xy 436.670646 -409.351029) (xy 436.682127 -409.337342)
			(xy 436.688187 -409.320536) (xy 436.688484 -409.311602) (xy 436.688484 -409.223718) (xy 436.688193 -409.214785)
			(xy 436.682113 -409.197987) (xy 436.670646 -409.184289) (xy 436.663084 -409.179522) (xy 436.638477 -409.164882)
			(xy 436.593638 -409.129272) (xy 436.554621 -409.087363) (xy 436.522303 -409.040096) (xy 436.497408 -408.988532)
			(xy 436.480496 -408.933827) (xy 436.471945 -408.87721) (xy 436.471948 -408.81995) (xy 436.480505 -408.763334)
			(xy 436.497423 -408.708631) (xy 436.522323 -408.657069) (xy 436.554646 -408.609806) (xy 436.593667 -408.567901)
			(xy 436.63851 -408.532296) (xy 436.663084 -408.517598) (xy 436.670646 -408.512829) (xy 436.682127 -408.499142)
			(xy 436.688187 -408.482336) (xy 436.688484 -408.473402) (xy 436.688484 -408.385518) (xy 436.688193 -408.376585)
			(xy 436.682113 -408.359787) (xy 436.670646 -408.346089) (xy 436.663084 -408.341322) (xy 436.638477 -408.326682)
			(xy 436.593638 -408.291072) (xy 436.554621 -408.249163) (xy 436.522303 -408.201896) (xy 436.497408 -408.150332)
			(xy 436.480496 -408.095627) (xy 436.471945 -408.03901) (xy 436.471948 -407.98175) (xy 436.480505 -407.925134)
			(xy 436.497423 -407.870431) (xy 436.522323 -407.818869) (xy 436.554646 -407.771606) (xy 436.593667 -407.729701)
			(xy 436.63851 -407.694096) (xy 436.663084 -407.679398) (xy 436.670646 -407.674629) (xy 436.682127 -407.660942)
			(xy 436.688187 -407.644136) (xy 436.688484 -407.635202) (xy 436.688484 -407.547318) (xy 436.688193 -407.538385)
			(xy 436.682113 -407.521587) (xy 436.670646 -407.507889) (xy 436.663084 -407.503122) (xy 436.638477 -407.488482)
			(xy 436.593638 -407.452872) (xy 436.554621 -407.410963) (xy 436.522303 -407.363696) (xy 436.497408 -407.312132)
			(xy 436.480496 -407.257427) (xy 436.471945 -407.20081) (xy 436.471948 -407.14355) (xy 436.480505 -407.086934)
			(xy 436.497423 -407.032231) (xy 436.522323 -406.980669) (xy 436.554646 -406.933406) (xy 436.593667 -406.891501)
			(xy 436.63851 -406.855896) (xy 436.663084 -406.841198) (xy 436.670646 -406.836429) (xy 436.682127 -406.822742)
			(xy 436.688187 -406.805936) (xy 436.688484 -406.797002) (xy 436.688484 -406.709118) (xy 436.688193 -406.700185)
			(xy 436.682113 -406.683387) (xy 436.670646 -406.669689) (xy 436.663084 -406.664922) (xy 436.638476 -406.650268)
			(xy 436.593607 -406.614676) (xy 436.554561 -406.572776) (xy 436.522218 -406.52551) (xy 436.497305 -406.473941)
			(xy 436.48038 -406.419226) (xy 436.471824 -406.362596) (xy 436.471314 -406.33396) (xy 436.4718 -406.306709)
			(xy 436.479556 -406.252761) (xy 436.494911 -406.200466) (xy 436.517553 -406.150889) (xy 436.547019 -406.105039)
			(xy 436.58271 -406.063848) (xy 436.623901 -406.028157) (xy 436.669751 -405.998691) (xy 436.719328 -405.976049)
			(xy 436.771623 -405.960694) (xy 436.825571 -405.952938) (xy 436.880073 -405.952938) (xy 436.934021 -405.960694)
			(xy 436.986316 -405.976049) (xy 437.035893 -405.998691) (xy 437.081743 -406.028157) (xy 437.122934 -406.063848)
			(xy 437.158625 -406.105039) (xy 437.188091 -406.150889) (xy 437.210733 -406.200466) (xy 437.226088 -406.252761)
			(xy 437.233844 -406.306709) (xy 437.23433 -406.33396) (xy 437.233838 -406.362595) (xy 437.22527 -406.419221)
			(xy 437.208335 -406.47393) (xy 437.183413 -406.525493) (xy 437.151066 -406.572753) (xy 437.112018 -406.614648)
			(xy 437.067148 -406.650236) (xy 437.04256 -406.664922) (xy 437.034978 -406.669662) (xy 437.023504 -406.683364)
			(xy 437.017453 -406.70018) (xy 437.01716 -406.709118) (xy 437.01716 -406.797002) (xy 437.017463 -406.805933)
			(xy 437.023543 -406.822728) (xy 437.035003 -406.836428) (xy 437.04256 -406.841198) (xy 437.067098 -406.855951)
			(xy 437.111939 -406.891547) (xy 437.150958 -406.933442) (xy 437.183281 -406.980697) (xy 437.20818 -407.032251)
			(xy 437.225098 -407.086946) (xy 437.233654 -407.143554) (xy 437.233657 -407.200806) (xy 437.225107 -407.257415)
			(xy 437.208195 -407.312112) (xy 437.183301 -407.363668) (xy 437.150983 -407.410927) (xy 437.111968 -407.452826)
			(xy 437.067131 -407.488427) (xy 437.04256 -407.503122) (xy 437.034978 -407.507862) (xy 437.023504 -407.521564)
			(xy 437.017453 -407.53838) (xy 437.01716 -407.547318) (xy 437.01716 -407.635202) (xy 437.017463 -407.644133)
			(xy 437.023543 -407.660928) (xy 437.035003 -407.674628) (xy 437.04256 -407.679398) (xy 437.067098 -407.694151)
			(xy 437.111939 -407.729747) (xy 437.150958 -407.771642) (xy 437.183281 -407.818897) (xy 437.20818 -407.870451)
			(xy 437.225098 -407.925146) (xy 437.233654 -407.981754) (xy 437.233657 -408.039006) (xy 437.225107 -408.095615)
			(xy 437.208195 -408.150312) (xy 437.183301 -408.201868) (xy 437.150983 -408.249127) (xy 437.111968 -408.291026)
			(xy 437.067131 -408.326627) (xy 437.04256 -408.341322) (xy 437.034978 -408.346062) (xy 437.023504 -408.359764)
			(xy 437.017453 -408.37658) (xy 437.01716 -408.385518) (xy 437.01716 -408.473402) (xy 437.017463 -408.482333)
			(xy 437.023543 -408.499128) (xy 437.035003 -408.512828) (xy 437.04256 -408.517598) (xy 437.067098 -408.532351)
			(xy 437.111939 -408.567947) (xy 437.150958 -408.609842) (xy 437.183281 -408.657097) (xy 437.20818 -408.708651)
			(xy 437.225098 -408.763346) (xy 437.233654 -408.819954) (xy 437.233657 -408.877206) (xy 437.225107 -408.933815)
			(xy 437.208195 -408.988512) (xy 437.183301 -409.040068) (xy 437.150983 -409.087327) (xy 437.111968 -409.129226)
			(xy 437.067131 -409.164827) (xy 437.04256 -409.179522) (xy 437.034978 -409.184262) (xy 437.023504 -409.197964)
			(xy 437.017453 -409.21478) (xy 437.01716 -409.223718) (xy 437.01716 -409.311602) (xy 437.017463 -409.320533)
			(xy 437.023543 -409.337328) (xy 437.035003 -409.351028) (xy 437.04256 -409.355798) (xy 437.067163 -409.370459)
			(xy 437.112036 -409.406048) (xy 437.151083 -409.447945) (xy 437.183428 -409.49521) (xy 437.208342 -409.546779)
			(xy 437.225267 -409.601494) (xy 437.233821 -409.658124) (xy 437.23433 -409.68676) (xy 437.233844 -409.714011)
			(xy 437.226088 -409.767959) (xy 437.210733 -409.820254) (xy 437.188091 -409.869831) (xy 437.158625 -409.915681)
			(xy 437.122934 -409.956872) (xy 437.081743 -409.992563) (xy 437.035893 -410.022029) (xy 436.986316 -410.044671)
			(xy 436.934021 -410.060026) (xy 436.880073 -410.067782) (xy 436.825571 -410.067782) (xy 436.771623 -410.060026)
			(xy 436.719328 -410.044671) (xy 436.669751 -410.022029) (xy 436.623901 -409.992563) (xy 436.58271 -409.956872)
			(xy 436.547019 -409.915681) (xy 436.517553 -409.869831) (xy 436.494911 -409.820254) (xy 436.479556 -409.767959)
			(xy 436.4718 -409.714011) (xy 436.471314 -409.68676) (xy 435.8005 -409.68676) (xy 435.8005 -417.620958)
			(xy 435.800934 -417.631023) (xy 435.808663 -417.649613) (xy 435.815486 -417.657026) (xy 436.59446 -418.436)
			(xy 437.991833 -418.436) (xy 437.995847 -418.372212) (xy 438.007823 -418.309429) (xy 438.027573 -418.248643)
			(xy 438.054785 -418.190811) (xy 438.089031 -418.136845) (xy 438.129771 -418.087598) (xy 438.176361 -418.043844)
			(xy 438.228068 -418.006274) (xy 438.284076 -417.975481) (xy 438.343501 -417.951951) (xy 438.405407 -417.936053)
			(xy 438.468817 -417.928039) (xy 438.500774 -417.927536) (xy 438.532063 -417.927975) (xy 438.594167 -417.935655)
			(xy 438.654859 -417.950903) (xy 438.713219 -417.973487) (xy 438.768365 -418.003067) (xy 438.819461 -418.039193)
			(xy 438.865735 -418.08132) (xy 438.906486 -418.12881) (xy 438.924192 -418.154612) (xy 438.931728 -418.16475)
			(xy 438.953992 -418.176615) (xy 438.96661 -418.177218) (xy 439.050938 -418.177218) (xy 439.063543 -418.176564)
			(xy 439.085792 -418.164715) (xy 439.093356 -418.154612) (xy 439.111062 -418.128813) (xy 439.151822 -418.081335)
			(xy 439.1981 -418.039219) (xy 439.249198 -418.003102) (xy 439.304342 -417.973529) (xy 439.3627 -417.950948)
			(xy 439.423387 -417.935701) (xy 439.485487 -417.928017) (xy 439.516774 -417.927536) (xy 439.54874 -417.927927)
			(xy 439.612169 -417.935937) (xy 439.674093 -417.951834) (xy 439.733537 -417.975367) (xy 439.789562 -418.006164)
			(xy 439.841286 -418.043741) (xy 439.887892 -418.087505) (xy 439.928645 -418.136765) (xy 439.962902 -418.190744)
			(xy 439.990124 -418.248591) (xy 440.009881 -418.309394) (xy 440.021861 -418.372194) (xy 440.025876 -418.436)
			(xy 440.021861 -418.499806) (xy 440.009881 -418.562606) (xy 439.990124 -418.623409) (xy 439.962902 -418.681256)
			(xy 439.928645 -418.735235) (xy 439.887892 -418.784495) (xy 439.841286 -418.828259) (xy 439.789562 -418.865836)
			(xy 439.733537 -418.896633) (xy 439.674093 -418.920166) (xy 439.612169 -418.936063) (xy 439.54874 -418.944073)
			(xy 439.516774 -418.944552) (xy 439.485486 -418.944082) (xy 439.423383 -418.936407) (xy 439.362692 -418.921164)
			(xy 439.304331 -418.898585) (xy 439.249186 -418.86901) (xy 439.198089 -418.832887) (xy 439.151814 -418.790763)
			(xy 439.111062 -418.743276) (xy 439.093356 -418.717476) (xy 439.085827 -418.70733) (xy 439.063559 -418.695465)
			(xy 439.050938 -418.69487) (xy 438.96661 -418.69487) (xy 438.954002 -418.695498) (xy 438.931754 -418.707366)
			(xy 438.924192 -418.717476) (xy 438.906451 -418.74325) (xy 438.865697 -418.790728) (xy 438.819424 -418.832846)
			(xy 438.768331 -418.868966) (xy 438.713192 -418.898542) (xy 438.654839 -418.921127) (xy 438.594156 -418.936379)
			(xy 438.532059 -418.944068) (xy 438.500774 -418.944552) (xy 438.468817 -418.943961) (xy 438.405407 -418.935947)
			(xy 438.343501 -418.920049) (xy 438.284076 -418.896519) (xy 438.228068 -418.865726) (xy 438.176361 -418.828156)
			(xy 438.129771 -418.784402) (xy 438.089031 -418.735155) (xy 438.054785 -418.681189) (xy 438.027573 -418.623357)
			(xy 438.007823 -418.562571) (xy 437.995847 -418.499788) (xy 437.991833 -418.436) (xy 436.59446 -418.436)
			(xy 438.049416 -419.890956) (xy 438.05602 -419.894512) (xy 438.070512 -419.90235) (xy 438.098234 -419.920157)
			(xy 438.111392 -419.930072) (xy 438.118234 -419.935016) (xy 438.134197 -419.940473) (xy 438.142634 -419.94074)
		)
		(stroke
			(width 0)
			(type solid)
		)
		(fill yes)
		(layer "In11.Cu")
		(net "P5V_AUX")
	)
	(gr_poly
		(pts
			(xy 314.74537 -365.428784) (xy 314.752613 -365.427155) (xy 314.76578 -365.420311) (xy 314.771278 -365.415322)
			(xy 315.204602 -364.981998) (xy 315.207306 -364.979146) (xy 315.211896 -364.972766) (xy 315.213746 -364.969298)
			(xy 315.217048 -364.962948) (xy 315.218572 -364.954566) (xy 315.223318 -364.928656) (xy 315.239004 -364.878369)
			(xy 315.261457 -364.830718) (xy 315.290251 -364.786609) (xy 315.324839 -364.74688) (xy 315.364563 -364.712286)
			(xy 315.408668 -364.683485) (xy 315.456316 -364.661025) (xy 315.5066 -364.645332) (xy 315.532516 -364.640622)
			(xy 315.540898 -364.639098) (xy 315.547248 -364.635796) (xy 315.550721 -364.633955) (xy 315.557097 -364.629358)
			(xy 315.559948 -364.626652) (xy 316.063122 -364.123478) (xy 316.068109 -364.117979) (xy 316.074951 -364.104812)
			(xy 316.076584 -364.09757) (xy 316.0776 -364.087918) (xy 316.0776 -363.535976) (xy 316.0776 -363.533436)
			(xy 316.07666 -363.523347) (xy 316.067901 -363.505094) (xy 316.052744 -363.491672) (xy 316.04331 -363.48797)
			(xy 315.947298 -363.45495) (xy 315.936884 -363.451394) (xy 315.921644 -363.455966) (xy 315.914228 -363.458465)
			(xy 315.9013 -363.467265) (xy 315.896244 -363.473238) (xy 315.89599 -363.473492) (xy 315.877801 -363.495979)
			(xy 315.835785 -363.535724) (xy 315.788252 -363.568671) (xy 315.73629 -363.594065) (xy 315.68109 -363.611325)
			(xy 315.623918 -363.620055) (xy 315.595 -363.620558) (xy 315.567745 -363.620072) (xy 315.51379 -363.612315)
			(xy 315.461489 -363.596957) (xy 315.411905 -363.574313) (xy 315.366049 -363.544843) (xy 315.324853 -363.509147)
			(xy 315.289157 -363.467951) (xy 315.259687 -363.422095) (xy 315.237043 -363.372511) (xy 315.221685 -363.32021)
			(xy 315.213928 -363.266255) (xy 315.213928 -363.211745) (xy 315.221685 -363.15779) (xy 315.237043 -363.105489)
			(xy 315.259687 -363.055905) (xy 315.289157 -363.010049) (xy 315.324853 -362.968853) (xy 315.366049 -362.933157)
			(xy 315.411905 -362.903687) (xy 315.461489 -362.881043) (xy 315.51379 -362.865685) (xy 315.567745 -362.857928)
			(xy 315.595 -362.857542) (xy 315.623916 -362.858076) (xy 315.681086 -362.866804) (xy 315.736285 -362.884059)
			(xy 315.788247 -362.909447) (xy 315.835782 -362.942386) (xy 315.877803 -362.982121) (xy 315.89599 -363.004608)
			(xy 315.896244 -363.004862) (xy 315.901317 -363.010812) (xy 315.914249 -363.019591) (xy 315.921644 -363.022134)
			(xy 315.936884 -363.026706) (xy 315.947298 -363.02315) (xy 316.04331 -362.99013) (xy 316.052724 -362.986413)
			(xy 316.067822 -362.972959) (xy 316.076591 -362.954736) (xy 316.0776 -362.944664) (xy 316.0776 -356.940612)
			(xy 316.0776 -356.93858) (xy 316.077305 -356.933447) (xy 316.074875 -356.92346) (xy 316.072774 -356.918768)
			(xy 316.070965 -356.915159) (xy 316.066372 -356.908522) (xy 316.06363 -356.90556) (xy 316.043056 -356.88397)
			(xy 316.037921 -356.878834) (xy 316.025403 -356.871481) (xy 316.018418 -356.869492) (xy 316.011306 -356.868222)
			(xy 315.983582 -356.864763) (xy 315.929492 -356.850775) (xy 315.878021 -356.829046) (xy 315.830271 -356.80004)
			(xy 315.787264 -356.764378) (xy 315.74992 -356.722823) (xy 315.719038 -356.676264) (xy 315.695279 -356.625698)
			(xy 315.679151 -356.572207) (xy 315.671 -356.516935) (xy 315.671 -356.461065) (xy 315.679151 -356.405793)
			(xy 315.695279 -356.352302) (xy 315.719038 -356.301736) (xy 315.74992 -356.255177) (xy 315.787264 -356.213622)
			(xy 315.830271 -356.17796) (xy 315.878021 -356.148954) (xy 315.929492 -356.127225) (xy 315.983582 -356.113237)
			(xy 316.011306 -356.109778) (xy 316.018418 -356.108508) (xy 316.025384 -356.106477) (xy 316.037885 -356.099121)
			(xy 316.043056 -356.09403) (xy 316.06363 -356.07244) (xy 316.066365 -356.069472) (xy 316.070959 -356.062837)
			(xy 316.072774 -356.059232) (xy 316.074837 -356.054527) (xy 316.077268 -356.044547) (xy 316.0776 -356.03942)
			(xy 316.0776 -354.376482) (xy 316.077436 -354.370471) (xy 316.074619 -354.358786) (xy 316.072012 -354.353368)
			(xy 316.070172 -354.349894) (xy 316.065578 -354.343516) (xy 316.062868 -354.340668) (xy 315.040518 -353.318318)
			(xy 315.035897 -353.313975) (xy 315.024969 -353.307547) (xy 315.018928 -353.305618) (xy 315.01334 -353.30384)
			(xy 315.00064 -353.303586) (xy 314.993782 -353.30511) (xy 314.973104 -353.309491) (xy 314.931097 -353.314206)
			(xy 314.909962 -353.314508) (xy 314.9092 -353.314508) (xy 314.881949 -353.314022) (xy 314.828001 -353.306266)
			(xy 314.775706 -353.290911) (xy 314.726129 -353.268269) (xy 314.680279 -353.238803) (xy 314.639088 -353.203112)
			(xy 314.603397 -353.161921) (xy 314.573931 -353.116071) (xy 314.551289 -353.066494) (xy 314.535934 -353.014199)
			(xy 314.528178 -352.960251) (xy 314.527692 -352.933) (xy 314.5282 -352.912934) (xy 314.528708 -352.902266)
			(xy 314.525152 -352.892868) (xy 314.523296 -352.888041) (xy 314.517911 -352.879215) (xy 314.514484 -352.875342)
			(xy 314.463938 -352.822002) (xy 314.458096 -352.816668) (xy 314.451624 -352.811982) (xy 314.436604 -352.806552)
			(xy 314.428632 -352.806) (xy 314.223908 -352.806) (xy 314.213886 -352.806418) (xy 314.195366 -352.814087)
			(xy 314.181191 -352.828259) (xy 314.17352 -352.846778) (xy 314.173108 -352.8568) (xy 314.173108 -353.2378)
			(xy 314.173015 -353.249357) (xy 314.170977 -353.27238) (xy 314.169044 -353.283774) (xy 314.168536 -353.285806)
			(xy 314.16752 -353.294442) (xy 314.16752 -353.296728) (xy 314.168282 -353.303586) (xy 314.170566 -353.318786)
			(xy 314.172984 -353.34943) (xy 314.173108 -353.3648) (xy 314.172622 -353.392051) (xy 314.164866 -353.445999)
			(xy 314.149511 -353.498294) (xy 314.126869 -353.547871) (xy 314.097403 -353.593721) (xy 314.061712 -353.634912)
			(xy 314.020521 -353.670603) (xy 313.974671 -353.700069) (xy 313.925094 -353.722711) (xy 313.872799 -353.738066)
			(xy 313.818851 -353.745822) (xy 313.764349 -353.745822) (xy 313.710401 -353.738066) (xy 313.658106 -353.722711)
			(xy 313.608529 -353.700069) (xy 313.562679 -353.670603) (xy 313.521488 -353.634912) (xy 313.485797 -353.593721)
			(xy 313.456331 -353.547871) (xy 313.433689 -353.498294) (xy 313.418334 -353.445999) (xy 313.410578 -353.392051)
			(xy 313.410092 -353.3648) (xy 313.41056 -353.337479) (xy 313.418356 -353.283395) (xy 313.433788 -353.230977)
			(xy 313.456541 -353.181297) (xy 313.486149 -353.135371) (xy 313.522007 -353.094139) (xy 313.56338 -353.058445)
			(xy 313.609422 -353.029019) (xy 313.63412 -353.017328) (xy 313.642756 -353.013518) (xy 313.64809 -353.010978)
			(xy 313.656218 -352.998278) (xy 313.659859 -352.99208) (xy 313.663867 -352.978284) (xy 313.664092 -352.9711)
			(xy 313.664092 -352.8568) (xy 313.663672 -352.846779) (xy 313.656002 -352.828264) (xy 313.64183 -352.814093)
			(xy 313.623313 -352.806426) (xy 313.613292 -352.806) (xy 311.683146 -352.806) (xy 311.673155 -352.806529)
			(xy 311.654711 -352.814231) (xy 311.647332 -352.820986) (xy 311.495694 -352.972624) (xy 311.418224 -353.04984)
			(xy 311.411982 -353.057079) (xy 311.404945 -353.074834) (xy 311.404508 -353.084384) (xy 311.404508 -353.3902)
			(xy 311.733182 -353.3902) (xy 311.737253 -353.334578) (xy 311.749379 -353.280141) (xy 311.769302 -353.22805)
			(xy 311.796598 -353.179415) (xy 311.830684 -353.135272) (xy 311.870833 -353.096563) (xy 311.916191 -353.064112)
			(xy 311.965791 -353.038611) (xy 312.018575 -353.020604) (xy 312.073418 -353.010474) (xy 312.129152 -353.008437)
			(xy 312.184589 -353.014537) (xy 312.238546 -353.028643) (xy 312.289875 -353.050455) (xy 312.337481 -353.079509)
			(xy 312.380349 -353.115184) (xy 312.417566 -353.156721) (xy 312.448339 -353.203234) (xy 312.472011 -353.253731)
			(xy 312.488079 -353.307138) (xy 312.496199 -353.362314) (xy 312.496708 -353.3902) (xy 312.496199 -353.418086)
			(xy 312.488079 -353.473262) (xy 312.472011 -353.526669) (xy 312.448339 -353.577166) (xy 312.417566 -353.623679)
			(xy 312.380349 -353.665216) (xy 312.337481 -353.700891) (xy 312.289875 -353.729945) (xy 312.238546 -353.751757)
			(xy 312.184589 -353.765863) (xy 312.129152 -353.771963) (xy 312.073418 -353.769926) (xy 312.018575 -353.759796)
			(xy 311.965791 -353.741789) (xy 311.916191 -353.716288) (xy 311.870833 -353.683837) (xy 311.830684 -353.645128)
			(xy 311.796598 -353.600985) (xy 311.769302 -353.55235) (xy 311.749379 -353.500259) (xy 311.737253 -353.445822)
			(xy 311.733182 -353.3902) (xy 311.404508 -353.3902) (xy 311.404508 -353.746054) (xy 311.403994 -353.769002)
			(xy 311.395714 -353.814144) (xy 311.379468 -353.857069) (xy 311.355784 -353.896382) (xy 311.341008 -353.913948)
			(xy 311.335195 -353.921158) (xy 311.32867 -353.938476) (xy 311.328308 -353.94773) (xy 311.328308 -353.949)
			(xy 311.327822 -353.976251) (xy 311.320066 -354.030199) (xy 311.304711 -354.082494) (xy 311.282069 -354.132071)
			(xy 311.252603 -354.177921) (xy 311.216912 -354.219112) (xy 311.175721 -354.254803) (xy 311.129871 -354.284269)
			(xy 311.080294 -354.306911) (xy 311.027999 -354.322266) (xy 310.974051 -354.330022) (xy 310.9468 -354.330508)
			(xy 310.918594 -354.329993) (xy 310.862797 -354.321676) (xy 310.808832 -354.305237) (xy 310.757875 -354.281034)
			(xy 310.711035 -354.249594) (xy 310.669332 -354.211603) (xy 310.633675 -354.167888) (xy 310.60484 -354.119401)
			(xy 310.583456 -354.067198) (xy 310.576214 -354.039932) (xy 310.57596 -354.038916) (xy 310.57366 -354.030674)
			(xy 310.564443 -354.016268) (xy 310.557926 -354.010722) (xy 310.551068 -354.005388) (xy 310.53532 -353.9998)
			(xy 309.774082 -353.9998) (xy 309.768071 -353.999964) (xy 309.756386 -354.002781) (xy 309.750968 -354.005388)
			(xy 309.747494 -354.007228) (xy 309.741116 -354.011822) (xy 309.738268 -354.014532) (xy 309.589932 -354.162868)
			(xy 309.587225 -354.165718) (xy 309.582628 -354.172095) (xy 309.580788 -354.175568) (xy 309.578208 -354.180996)
			(xy 309.575391 -354.192675) (xy 309.5752 -354.198682) (xy 309.5752 -354.42144) (xy 309.575745 -354.431424)
			(xy 309.583468 -354.449846) (xy 309.590186 -354.457254) (xy 309.615313 -354.4824) (xy 312.977782 -354.4824)
			(xy 312.981853 -354.426778) (xy 312.993979 -354.372341) (xy 313.013902 -354.32025) (xy 313.041198 -354.271615)
			(xy 313.075284 -354.227472) (xy 313.115433 -354.188763) (xy 313.160791 -354.156312) (xy 313.210391 -354.130811)
			(xy 313.263175 -354.112804) (xy 313.318018 -354.102674) (xy 313.373752 -354.100637) (xy 313.429189 -354.106737)
			(xy 313.483146 -354.120843) (xy 313.534475 -354.142655) (xy 313.582081 -354.171709) (xy 313.624949 -354.207384)
			(xy 313.662166 -354.248921) (xy 313.692939 -354.295434) (xy 313.716611 -354.345931) (xy 313.732679 -354.399338)
			(xy 313.740799 -354.454514) (xy 313.740844 -354.457) (xy 314.120782 -354.457) (xy 314.124853 -354.401378)
			(xy 314.136979 -354.346941) (xy 314.156902 -354.29485) (xy 314.184198 -354.246215) (xy 314.218284 -354.202072)
			(xy 314.258433 -354.163363) (xy 314.303791 -354.130912) (xy 314.353391 -354.105411) (xy 314.406175 -354.087404)
			(xy 314.461018 -354.077274) (xy 314.516752 -354.075237) (xy 314.572189 -354.081337) (xy 314.626146 -354.095443)
			(xy 314.677475 -354.117255) (xy 314.725081 -354.146309) (xy 314.767949 -354.181984) (xy 314.805166 -354.223521)
			(xy 314.835939 -354.270034) (xy 314.859611 -354.320531) (xy 314.875679 -354.373938) (xy 314.883799 -354.429114)
			(xy 314.884308 -354.457) (xy 314.883799 -354.484886) (xy 314.875679 -354.540062) (xy 314.859611 -354.593469)
			(xy 314.835939 -354.643966) (xy 314.805166 -354.690479) (xy 314.767949 -354.732016) (xy 314.725081 -354.767691)
			(xy 314.677475 -354.796745) (xy 314.626146 -354.818557) (xy 314.572189 -354.832663) (xy 314.516752 -354.838763)
			(xy 314.461018 -354.836726) (xy 314.406175 -354.826596) (xy 314.353391 -354.808589) (xy 314.303791 -354.783088)
			(xy 314.258433 -354.750637) (xy 314.218284 -354.711928) (xy 314.184198 -354.667785) (xy 314.156902 -354.61915)
			(xy 314.136979 -354.567059) (xy 314.124853 -354.512622) (xy 314.120782 -354.457) (xy 313.740844 -354.457)
			(xy 313.741308 -354.4824) (xy 313.740799 -354.510286) (xy 313.732679 -354.565462) (xy 313.716611 -354.618869)
			(xy 313.692939 -354.669366) (xy 313.662166 -354.715879) (xy 313.624949 -354.757416) (xy 313.582081 -354.793091)
			(xy 313.534475 -354.822145) (xy 313.483146 -354.843957) (xy 313.429189 -354.858063) (xy 313.373752 -354.864163)
			(xy 313.318018 -354.862126) (xy 313.263175 -354.851996) (xy 313.210391 -354.833989) (xy 313.160791 -354.808488)
			(xy 313.115433 -354.776037) (xy 313.075284 -354.737328) (xy 313.041198 -354.693185) (xy 313.013902 -354.64455)
			(xy 312.993979 -354.592459) (xy 312.981853 -354.538022) (xy 312.977782 -354.4824) (xy 309.615313 -354.4824)
			(xy 309.932832 -354.800154) (xy 309.944392 -354.812038) (xy 309.964654 -354.838281) (xy 309.973218 -354.852478)
			(xy 309.97652 -354.85832) (xy 310.055514 -354.937314) (xy 310.062368 -354.944709) (xy 310.07011 -354.963308)
			(xy 310.0705 -354.973382) (xy 310.0705 -355.08692) (xy 310.070564 -355.090526) (xy 310.071587 -355.097664)
			(xy 310.072532 -355.101144) (xy 310.07812 -355.120448) (xy 310.081422 -355.126036) (xy 310.09404 -355.148191)
			(xy 310.113934 -355.195136) (xy 310.127399 -355.244311) (xy 310.134197 -355.294841) (xy 310.134206 -355.345827)
			(xy 310.131206 -355.371146) (xy 310.129505 -355.383077) (xy 310.1248 -355.406716) (xy 310.121808 -355.41839)
			(xy 310.114677 -355.443719) (xy 310.094418 -355.492283) (xy 310.081422 -355.515164) (xy 310.076342 -355.526848)
			(xy 310.072532 -355.540056) (xy 310.0705 -355.554026) (xy 310.0705 -356.005892) (xy 310.070918 -356.015914)
			(xy 310.078587 -356.034434) (xy 310.092759 -356.048609) (xy 310.111278 -356.05628) (xy 310.1213 -356.056692)
			(xy 310.216804 -356.056692) (xy 310.226702 -356.056172) (xy 310.244995 -356.048589) (xy 310.252364 -356.04196)
			(xy 310.99633 -355.297994) (xy 311.407302 -354.886768) (xy 311.425397 -354.869512) (xy 311.466943 -354.841703)
			(xy 311.513114 -354.82253) (xy 311.562138 -354.812729) (xy 311.587134 -354.812092) (xy 312.140854 -354.812092)
			(xy 312.16585 -354.812729) (xy 312.214872 -354.822531) (xy 312.26104 -354.841708) (xy 312.30258 -354.869524)
			(xy 312.320686 -354.886768) (xy 312.424318 -354.990654) (xy 312.612024 -355.17836) (xy 312.619384 -355.184998)
			(xy 312.637685 -355.192561) (xy 312.647584 -355.193092) (xy 314.401454 -355.193092) (xy 314.42645 -355.193729)
			(xy 314.475472 -355.203531) (xy 314.52164 -355.222708) (xy 314.56318 -355.250524) (xy 314.581286 -355.267768)
			(xy 314.644532 -355.331014) (xy 314.758832 -355.445568) (xy 314.773348 -355.460684) (xy 314.797737 -355.494762)
			(xy 314.807346 -355.513386) (xy 314.809632 -355.518212) (xy 314.823094 -355.53523) (xy 314.827158 -355.538532)
			(xy 314.847709 -355.556755) (xy 314.883879 -355.59809) (xy 314.913743 -355.644187) (xy 314.936684 -355.694091)
			(xy 314.952227 -355.746772) (xy 314.960051 -355.801137) (xy 314.960508 -355.8286) (xy 314.960508 -355.83241)
			(xy 314.959764 -355.859484) (xy 314.95157 -355.913019) (xy 314.935888 -355.964858) (xy 314.913032 -356.013959)
			(xy 314.883462 -356.059333) (xy 314.847773 -356.10007) (xy 314.806681 -356.135351) (xy 314.761014 -356.164466)
			(xy 314.711688 -356.18683) (xy 314.659695 -356.201995) (xy 314.60608 -356.209654) (xy 314.579 -356.210108)
			(xy 314.551772 -356.209624) (xy 314.497869 -356.20188) (xy 314.445615 -356.186551) (xy 314.396071 -356.163947)
			(xy 314.350245 -356.134528) (xy 314.309068 -356.098891) (xy 314.273377 -356.057762) (xy 314.243897 -356.011975)
			(xy 314.221227 -355.962462) (xy 314.205828 -355.910228) (xy 314.198013 -355.856336) (xy 314.197492 -355.829108)
			(xy 314.197492 -355.828346) (xy 314.198 -355.808788) (xy 314.198508 -355.79812) (xy 314.194952 -355.788722)
			(xy 314.193073 -355.783964) (xy 314.187697 -355.775261) (xy 314.184284 -355.77145) (xy 314.13196 -355.716332)
			(xy 314.124662 -355.709887) (xy 314.106634 -355.702575) (xy 314.096908 -355.702108) (xy 312.5216 -355.702108)
			(xy 312.51525 -355.701854) (xy 312.50382 -355.7016) (xy 312.493914 -355.705918) (xy 312.488895 -355.708285)
			(xy 312.479931 -355.714824) (xy 312.476134 -355.718872) (xy 312.450226 -355.748336) (xy 312.424318 -355.777546)
			(xy 312.420782 -355.781768) (xy 312.415414 -355.791379) (xy 312.41365 -355.796596) (xy 312.410602 -355.80701)
			(xy 312.41238 -355.81844) (xy 312.416211 -355.846221) (xy 312.420283 -355.902157) (xy 312.420508 -355.9302)
			(xy 312.420031 -355.968942) (xy 312.412175 -356.046027) (xy 312.396546 -356.121918) (xy 312.373303 -356.195834)
			(xy 312.342687 -356.267012) (xy 312.305012 -356.33472) (xy 312.260667 -356.39826) (xy 312.210109 -356.456976)
			(xy 312.153859 -356.510265) (xy 312.092496 -356.557576) (xy 312.059828 -356.578408) (xy 312.059574 -356.578408)
			(xy 312.054423 -356.581901) (xy 312.045818 -356.590888) (xy 312.042556 -356.596188) (xy 312.024014 -356.6287)
			(xy 312.024776 -356.637336) (xy 312.028078 -356.650036) (xy 312.033414 -356.672777) (xy 312.039148 -356.719136)
			(xy 312.039508 -356.742492) (xy 312.039508 -356.743) (xy 312.039022 -356.770251) (xy 312.031266 -356.824199)
			(xy 312.015911 -356.876494) (xy 311.993269 -356.926071) (xy 311.963803 -356.971921) (xy 311.928112 -357.013112)
			(xy 311.886921 -357.048803) (xy 311.841071 -357.078269) (xy 311.791494 -357.100911) (xy 311.739199 -357.116266)
			(xy 311.685251 -357.124022) (xy 311.630749 -357.124022) (xy 311.576801 -357.116266) (xy 311.524506 -357.100911)
			(xy 311.474929 -357.078269) (xy 311.429079 -357.048803) (xy 311.387888 -357.013112) (xy 311.352197 -356.971921)
			(xy 311.322731 -356.926071) (xy 311.300089 -356.876494) (xy 311.284734 -356.824199) (xy 311.276978 -356.770251)
			(xy 311.276492 -356.743) (xy 311.276492 -356.742492) (xy 311.276862 -356.719137) (xy 311.282596 -356.672779)
			(xy 311.287922 -356.650036) (xy 311.291224 -356.637336) (xy 311.291986 -356.6287) (xy 311.273444 -356.596188)
			(xy 311.270214 -356.590862) (xy 311.261608 -356.581864) (xy 311.256426 -356.578408) (xy 311.256172 -356.578408)
			(xy 311.224504 -356.558248) (xy 311.16489 -356.512614) (xy 311.110049 -356.461343) (xy 311.060511 -356.404931)
			(xy 311.016755 -356.343925) (xy 310.979206 -356.278915) (xy 310.96331 -356.244906) (xy 310.96331 -356.244398)
			(xy 310.963056 -356.244144) (xy 310.960396 -356.238887) (xy 310.953081 -356.229656) (xy 310.948578 -356.225856)
			(xy 310.943752 -356.221792) (xy 310.932322 -356.216966) (xy 310.897016 -356.210362) (xy 310.84393 -356.20071)
			(xy 310.831972 -356.1992) (xy 310.808914 -356.206105) (xy 310.799734 -356.213918) (xy 310.621172 -356.392734)
			(xy 310.522874 -356.491032) (xy 310.504778 -356.508286) (xy 310.463232 -356.536091) (xy 310.41706 -356.55526)
			(xy 310.368037 -356.565056) (xy 310.343042 -356.565708) (xy 310.1213 -356.565708) (xy 310.111279 -356.566128)
			(xy 310.092764 -356.573798) (xy 310.078593 -356.58797) (xy 310.070926 -356.606487) (xy 310.0705 -356.616508)
			(xy 310.0705 -357.5304) (xy 310.070988 -357.540408) (xy 310.078648 -357.558899) (xy 310.092801 -357.573052)
			(xy 310.111292 -357.580712) (xy 310.1213 -357.5812) (xy 311.988454 -357.5812) (xy 311.998445 -357.580671)
			(xy 312.016889 -357.572969) (xy 312.024268 -357.566214) (xy 313.046364 -356.544118) (xy 313.04738 -356.543102)
			(xy 313.061896 -356.528261) (xy 313.094868 -356.50304) (xy 313.131504 -356.483518) (xy 313.170827 -356.470215)
			(xy 313.21179 -356.463486) (xy 313.232546 -356.463092) (xy 313.348878 -356.463092) (xy 313.353768 -356.462953)
			(xy 313.363359 -356.46103) (xy 313.367928 -356.459282) (xy 313.39409 -356.448614) (xy 313.394344 -356.44836)
			(xy 313.415952 -356.427467) (xy 313.464523 -356.392062) (xy 313.518043 -356.364709) (xy 313.575189 -356.346084)
			(xy 313.634548 -356.336647) (xy 313.6646 -356.336092) (xy 313.691851 -356.336578) (xy 313.745799 -356.344334)
			(xy 313.798094 -356.359689) (xy 313.847671 -356.382331) (xy 313.893521 -356.411797) (xy 313.934712 -356.447488)
			(xy 313.970403 -356.488679) (xy 313.999869 -356.534529) (xy 314.022511 -356.584106) (xy 314.037866 -356.636401)
			(xy 314.045622 -356.690349) (xy 314.045622 -356.744851) (xy 314.037866 -356.798799) (xy 314.022511 -356.851094)
			(xy 313.999869 -356.900671) (xy 313.970403 -356.946521) (xy 313.934712 -356.987712) (xy 313.893521 -357.023403)
			(xy 313.847671 -357.052869) (xy 313.798094 -357.075511) (xy 313.745799 -357.090866) (xy 313.691851 -357.098622)
			(xy 313.6646 -357.099108) (xy 313.664346 -357.099108) (xy 313.634365 -357.098553) (xy 313.57514 -357.089175)
			(xy 313.518113 -357.070643) (xy 313.46469 -357.043414) (xy 313.416186 -357.00816) (xy 313.394598 -356.987348)
			(xy 313.387232 -356.979982) (xy 313.36869 -356.972108) (xy 313.358784 -356.972108) (xy 313.349151 -356.972575)
			(xy 313.331269 -356.979756) (xy 313.323986 -356.986078) (xy 313.127898 -357.18242) (xy 312.739786 -357.570532)
			(xy 312.732971 -357.577875) (xy 312.725237 -357.596338) (xy 312.7248 -357.606346) (xy 312.7248 -360.402632)
			(xy 313.480448 -360.402632) (xy 313.484519 -360.34701) (xy 313.496645 -360.292573) (xy 313.516568 -360.240482)
			(xy 313.543864 -360.191847) (xy 313.57795 -360.147704) (xy 313.618099 -360.108995) (xy 313.663457 -360.076544)
			(xy 313.713057 -360.051043) (xy 313.765841 -360.033036) (xy 313.820684 -360.022906) (xy 313.876418 -360.020869)
			(xy 313.931855 -360.026969) (xy 313.985812 -360.041075) (xy 314.037141 -360.062887) (xy 314.084747 -360.091941)
			(xy 314.127615 -360.127616) (xy 314.164832 -360.169153) (xy 314.195605 -360.215666) (xy 314.219277 -360.266163)
			(xy 314.226252 -360.289348) (xy 314.38545 -360.289348) (xy 314.389521 -360.233726) (xy 314.401647 -360.179289)
			(xy 314.42157 -360.127198) (xy 314.448866 -360.078563) (xy 314.482952 -360.03442) (xy 314.523101 -359.995711)
			(xy 314.568459 -359.96326) (xy 314.618059 -359.937759) (xy 314.670843 -359.919752) (xy 314.725686 -359.909622)
			(xy 314.78142 -359.907585) (xy 314.836857 -359.913685) (xy 314.890814 -359.927791) (xy 314.942143 -359.949603)
			(xy 314.989749 -359.978657) (xy 315.032617 -360.014332) (xy 315.069834 -360.055869) (xy 315.100607 -360.102382)
			(xy 315.124279 -360.152879) (xy 315.140347 -360.206286) (xy 315.148467 -360.261462) (xy 315.148976 -360.289348)
			(xy 315.148467 -360.317234) (xy 315.140347 -360.37241) (xy 315.124279 -360.425817) (xy 315.100607 -360.476314)
			(xy 315.069834 -360.522827) (xy 315.032617 -360.564364) (xy 314.989749 -360.600039) (xy 314.942143 -360.629093)
			(xy 314.890814 -360.650905) (xy 314.836857 -360.665011) (xy 314.78142 -360.671111) (xy 314.725686 -360.669074)
			(xy 314.670843 -360.658944) (xy 314.618059 -360.640937) (xy 314.568459 -360.615436) (xy 314.523101 -360.582985)
			(xy 314.482952 -360.544276) (xy 314.448866 -360.500133) (xy 314.42157 -360.451498) (xy 314.401647 -360.399407)
			(xy 314.389521 -360.34497) (xy 314.38545 -360.289348) (xy 314.226252 -360.289348) (xy 314.235345 -360.31957)
			(xy 314.243465 -360.374746) (xy 314.243974 -360.402632) (xy 314.243465 -360.430518) (xy 314.235345 -360.485694)
			(xy 314.219277 -360.539101) (xy 314.195605 -360.589598) (xy 314.164832 -360.636111) (xy 314.127615 -360.677648)
			(xy 314.084747 -360.713323) (xy 314.037141 -360.742377) (xy 313.985812 -360.764189) (xy 313.931855 -360.778295)
			(xy 313.876418 -360.784395) (xy 313.820684 -360.782358) (xy 313.765841 -360.772228) (xy 313.713057 -360.754221)
			(xy 313.663457 -360.72872) (xy 313.618099 -360.696269) (xy 313.57795 -360.65756) (xy 313.543864 -360.613417)
			(xy 313.516568 -360.564782) (xy 313.496645 -360.512691) (xy 313.484519 -360.458254) (xy 313.480448 -360.402632)
			(xy 312.7248 -360.402632) (xy 312.7248 -361.279948) (xy 314.255656 -361.279948) (xy 314.259727 -361.224326)
			(xy 314.271853 -361.169889) (xy 314.291776 -361.117798) (xy 314.319072 -361.069163) (xy 314.353158 -361.02502)
			(xy 314.393307 -360.986311) (xy 314.438665 -360.95386) (xy 314.488265 -360.928359) (xy 314.541049 -360.910352)
			(xy 314.595892 -360.900222) (xy 314.651626 -360.898185) (xy 314.707063 -360.904285) (xy 314.76102 -360.918391)
			(xy 314.812349 -360.940203) (xy 314.859955 -360.969257) (xy 314.902823 -361.004932) (xy 314.94004 -361.046469)
			(xy 314.970813 -361.092982) (xy 314.994485 -361.143479) (xy 315.010553 -361.196886) (xy 315.018673 -361.252062)
			(xy 315.019182 -361.279948) (xy 315.018673 -361.307834) (xy 315.010553 -361.36301) (xy 314.994485 -361.416417)
			(xy 314.970813 -361.466914) (xy 314.94004 -361.513427) (xy 314.902823 -361.554964) (xy 314.859955 -361.590639)
			(xy 314.812349 -361.619693) (xy 314.76102 -361.641505) (xy 314.707063 -361.655611) (xy 314.651626 -361.661711)
			(xy 314.595892 -361.659674) (xy 314.541049 -361.649544) (xy 314.488265 -361.631537) (xy 314.438665 -361.606036)
			(xy 314.393307 -361.573585) (xy 314.353158 -361.534876) (xy 314.319072 -361.490733) (xy 314.291776 -361.442098)
			(xy 314.271853 -361.390007) (xy 314.259727 -361.33557) (xy 314.255656 -361.279948) (xy 312.7248 -361.279948)
			(xy 312.7248 -364.976918) (xy 312.725816 -364.98657) (xy 312.727445 -364.993813) (xy 312.734289 -365.00698)
			(xy 312.739278 -365.012478) (xy 313.142122 -365.415322) (xy 313.147621 -365.420309) (xy 313.160788 -365.427151)
			(xy 313.16803 -365.428784) (xy 313.177682 -365.4298) (xy 314.735718 -365.4298)
		)
		(stroke
			(width 0)
			(type solid)
		)
		(fill yes)
		(layer "In11.Cu")
		(net "PVDDCR_CPU1_P0_VCCS")
	)
	(gr_poly
		(pts
			(xy 96.396302 -153.15692) (xy 96.406118 -153.156387) (xy 96.424226 -153.148788) (xy 96.438068 -153.134858)
			(xy 96.445551 -153.116701) (xy 96.446086 -153.106882) (xy 96.446086 -151.20747) (xy 96.445443 -151.19564)
			(xy 96.434704 -151.174559) (xy 96.425512 -151.167084) (xy 96.350328 -151.112474) (xy 96.326706 -151.108664)
			(xy 96.315276 -151.112474) (xy 96.277312 -151.123954) (xy 96.198974 -151.136329) (xy 96.15932 -151.137112)
			(xy 96.158558 -151.137112) (xy 96.127829 -151.136645) (xy 96.066818 -151.129233) (xy 96.007146 -151.114521)
			(xy 95.949682 -151.092723) (xy 95.895265 -151.064159) (xy 95.844687 -151.029244) (xy 95.798686 -150.988487)
			(xy 95.757933 -150.942483) (xy 95.723021 -150.891903) (xy 95.694461 -150.837483) (xy 95.672668 -150.780017)
			(xy 95.65796 -150.720344) (xy 95.650552 -150.659333) (xy 95.65005 -150.628604) (xy 95.65005 -150.62835)
			(xy 95.650599 -150.594232) (xy 95.659727 -150.52661) (xy 95.677827 -150.460819) (xy 95.69069 -150.429214)
			(xy 95.694754 -150.409656) (xy 95.694649 -150.405511) (xy 95.693249 -150.39734) (xy 95.69196 -150.3934)
			(xy 95.682054 -150.364698) (xy 95.65894 -150.337266) (xy 95.632758 -150.322318) (xy 95.583777 -150.287163)
			(xy 95.539297 -150.246463) (xy 95.499942 -150.200788) (xy 95.466265 -150.15078) (xy 95.438738 -150.09714)
			(xy 95.417747 -150.040621) (xy 95.403587 -149.982017) (xy 95.396457 -149.922149) (xy 95.39605 -149.892004)
			(xy 95.396513 -149.861272) (xy 95.403921 -149.800256) (xy 95.418629 -149.740577) (xy 95.440423 -149.683107)
			(xy 95.468986 -149.628682) (xy 95.503899 -149.578097) (xy 95.544656 -149.532088) (xy 95.59066 -149.491328)
			(xy 95.641243 -149.456409) (xy 95.695665 -149.427842) (xy 95.753133 -149.406043) (xy 95.81281 -149.39133)
			(xy 95.873826 -149.383916) (xy 95.904558 -149.383496) (xy 95.939584 -149.384078) (xy 96.008973 -149.393686)
			(xy 96.076388 -149.412726) (xy 96.140551 -149.440838) (xy 96.20025 -149.47749) (xy 96.227646 -149.49932)
			(xy 96.259142 -149.510496) (xy 96.415606 -149.510496) (xy 96.445586 -149.511055) (xy 96.504806 -149.52044)
			(xy 96.561827 -149.538978) (xy 96.615245 -149.566212) (xy 96.639868 -149.584113) (xy 98.811328 -149.584113)
			(xy 98.811328 -149.520191) (xy 98.819339 -149.456773) (xy 98.835236 -149.394859) (xy 98.858768 -149.335426)
			(xy 98.889562 -149.279411) (xy 98.927135 -149.227696) (xy 98.970892 -149.181099) (xy 99.020145 -149.140354)
			(xy 99.074116 -149.106103) (xy 99.131955 -149.078886) (xy 99.192748 -149.059133) (xy 99.255538 -149.047155)
			(xy 99.319334 -149.043142) (xy 99.38313 -149.047155) (xy 99.44592 -149.059133) (xy 99.506713 -149.078886)
			(xy 99.564552 -149.106103) (xy 99.618523 -149.140354) (xy 99.667776 -149.181099) (xy 99.711533 -149.227696)
			(xy 99.749106 -149.279411) (xy 99.7799 -149.335426) (xy 99.803432 -149.394859) (xy 99.819329 -149.456773)
			(xy 99.82734 -149.520191) (xy 99.827842 -149.552152) (xy 99.82734 -149.584113) (xy 99.819329 -149.647531)
			(xy 99.803432 -149.709445) (xy 99.7799 -149.768878) (xy 99.749106 -149.824893) (xy 99.711533 -149.876608)
			(xy 99.667776 -149.923205) (xy 99.618523 -149.96395) (xy 99.564552 -149.998201) (xy 99.506713 -150.025418)
			(xy 99.44592 -150.045171) (xy 99.38313 -150.057149) (xy 99.319334 -150.061163) (xy 99.255538 -150.057149)
			(xy 99.192748 -150.045171) (xy 99.131955 -150.025418) (xy 99.074116 -149.998201) (xy 99.020145 -149.96395)
			(xy 98.970892 -149.923205) (xy 98.927135 -149.876608) (xy 98.889562 -149.824893) (xy 98.858768 -149.768878)
			(xy 98.835236 -149.709445) (xy 98.819339 -149.647531) (xy 98.811328 -149.584113) (xy 96.639868 -149.584113)
			(xy 96.663742 -149.60147) (xy 96.685354 -149.622256) (xy 97.097342 -150.034244) (xy 97.118125 -150.055857)
			(xy 97.153371 -150.10436) (xy 97.180597 -150.157778) (xy 97.199135 -150.214797) (xy 97.208528 -150.274014)
			(xy 97.209102 -150.303992) (xy 97.209102 -151.708866) (xy 97.520504 -151.708866) (xy 97.524575 -151.653244)
			(xy 97.536701 -151.598807) (xy 97.556624 -151.546716) (xy 97.58392 -151.498081) (xy 97.618006 -151.453938)
			(xy 97.658155 -151.415229) (xy 97.703513 -151.382778) (xy 97.753113 -151.357277) (xy 97.805897 -151.33927)
			(xy 97.86074 -151.32914) (xy 97.916474 -151.327103) (xy 97.971911 -151.333203) (xy 98.025868 -151.347309)
			(xy 98.077197 -151.369121) (xy 98.124803 -151.398175) (xy 98.167671 -151.43385) (xy 98.204888 -151.475387)
			(xy 98.235661 -151.5219) (xy 98.259333 -151.572397) (xy 98.275401 -151.625804) (xy 98.281451 -151.666913)
			(xy 99.179628 -151.666913) (xy 99.179628 -151.602991) (xy 99.187639 -151.539573) (xy 99.203536 -151.477659)
			(xy 99.227068 -151.418226) (xy 99.257862 -151.362211) (xy 99.295435 -151.310496) (xy 99.339192 -151.263899)
			(xy 99.388445 -151.223154) (xy 99.442416 -151.188903) (xy 99.500255 -151.161686) (xy 99.561048 -151.141933)
			(xy 99.623838 -151.129955) (xy 99.687634 -151.125942) (xy 99.75143 -151.129955) (xy 99.81422 -151.141933)
			(xy 99.875013 -151.161686) (xy 99.932852 -151.188903) (xy 99.986823 -151.223154) (xy 100.036076 -151.263899)
			(xy 100.079833 -151.310496) (xy 100.117406 -151.362211) (xy 100.1482 -151.418226) (xy 100.171732 -151.477659)
			(xy 100.187629 -151.539573) (xy 100.19564 -151.602991) (xy 100.196142 -151.634952) (xy 100.19564 -151.666913)
			(xy 100.187629 -151.730331) (xy 100.171732 -151.792245) (xy 100.1482 -151.851678) (xy 100.117406 -151.907693)
			(xy 100.079833 -151.959408) (xy 100.036076 -152.006005) (xy 99.986823 -152.04675) (xy 99.932852 -152.081001)
			(xy 99.875013 -152.108218) (xy 99.81422 -152.127971) (xy 99.75143 -152.139949) (xy 99.687634 -152.143963)
			(xy 99.623838 -152.139949) (xy 99.561048 -152.127971) (xy 99.500255 -152.108218) (xy 99.442416 -152.081001)
			(xy 99.388445 -152.04675) (xy 99.339192 -152.006005) (xy 99.295435 -151.959408) (xy 99.257862 -151.907693)
			(xy 99.227068 -151.851678) (xy 99.203536 -151.792245) (xy 99.187639 -151.730331) (xy 99.179628 -151.666913)
			(xy 98.281451 -151.666913) (xy 98.283521 -151.68098) (xy 98.28403 -151.708866) (xy 98.283521 -151.736752)
			(xy 98.275401 -151.791928) (xy 98.259333 -151.845335) (xy 98.235661 -151.895832) (xy 98.204888 -151.942345)
			(xy 98.167671 -151.983882) (xy 98.124803 -152.019557) (xy 98.077197 -152.048611) (xy 98.025868 -152.070423)
			(xy 97.971911 -152.084529) (xy 97.916474 -152.090629) (xy 97.86074 -152.088592) (xy 97.805897 -152.078462)
			(xy 97.753113 -152.060455) (xy 97.703513 -152.034954) (xy 97.658155 -152.002503) (xy 97.618006 -151.963794)
			(xy 97.58392 -151.919651) (xy 97.556624 -151.871016) (xy 97.536701 -151.818925) (xy 97.524575 -151.764488)
			(xy 97.520504 -151.708866) (xy 97.209102 -151.708866) (xy 97.209102 -153.106882) (xy 97.209574 -153.116708)
			(xy 97.21707 -153.134873) (xy 97.230933 -153.1488) (xy 97.249063 -153.15638) (xy 97.258886 -153.15692)
			(xy 101.07803 -153.15692) (xy 101.087871 -153.156392) (xy 101.106045 -153.148817) (xy 101.113336 -153.142188)
			(xy 101.431598 -152.823926) (xy 101.438318 -152.816691) (xy 101.445929 -152.798486) (xy 101.44633 -152.78862)
			(xy 101.44633 -140.977874) (xy 101.445803 -140.968032) (xy 101.43823 -140.949857) (xy 101.431598 -140.942568)
			(xy 101.026468 -140.537438) (xy 101.019226 -140.530734) (xy 101.001022 -140.523155) (xy 100.991162 -140.522706)
			(xy 98.510852 -140.522706) (xy 98.501013 -140.523238) (xy 98.482847 -140.53082) (xy 98.475546 -140.537438)
			(xy 98.310954 -140.70203) (xy 98.304212 -140.709324) (xy 98.296628 -140.727664) (xy 98.296222 -140.73759)
			(xy 98.303588 -140.763752) (xy 98.321515 -140.793949) (xy 98.3498 -140.858226) (xy 98.368968 -140.925785)
			(xy 98.378655 -140.995339) (xy 98.37928 -141.030452) (xy 98.378837 -141.060871) (xy 98.371579 -141.121275)
			(xy 98.357161 -141.180381) (xy 98.335789 -141.237342) (xy 98.307769 -141.291344) (xy 98.273502 -141.341614)
			(xy 98.233478 -141.387434) (xy 98.188269 -141.428147) (xy 98.163634 -141.445996) (xy 98.142552 -141.48689)
			(xy 98.142552 -142.103602) (xy 99.864926 -142.103602) (xy 99.865428 -142.071641) (xy 99.873439 -142.008223)
			(xy 99.889336 -141.946309) (xy 99.912868 -141.886876) (xy 99.943662 -141.830861) (xy 99.981235 -141.779146)
			(xy 100.024992 -141.732549) (xy 100.074245 -141.691804) (xy 100.128216 -141.657553) (xy 100.186055 -141.630336)
			(xy 100.246848 -141.610583) (xy 100.309638 -141.598605) (xy 100.373434 -141.594592) (xy 100.43723 -141.598605)
			(xy 100.50002 -141.610583) (xy 100.560813 -141.630336) (xy 100.618652 -141.657553) (xy 100.672623 -141.691804)
			(xy 100.721876 -141.732549) (xy 100.765633 -141.779146) (xy 100.803206 -141.830861) (xy 100.834 -141.886876)
			(xy 100.857532 -141.946309) (xy 100.873429 -142.008223) (xy 100.88144 -142.071641) (xy 100.881942 -142.103602)
			(xy 100.88151 -142.13345) (xy 100.874533 -142.192735) (xy 100.860665 -142.250797) (xy 100.840095 -142.306836)
			(xy 100.813107 -142.360082) (xy 100.780072 -142.409802) (xy 100.741443 -142.455314) (xy 100.71989 -142.475966)
			(xy 100.710746 -142.484348) (xy 100.702618 -142.5067) (xy 100.71608 -142.611856) (xy 100.729796 -142.631668)
			(xy 100.740464 -142.637256) (xy 100.767115 -142.652028) (xy 100.816968 -142.687071) (xy 100.862276 -142.727819)
			(xy 100.902392 -142.773689) (xy 100.936739 -142.824023) (xy 100.964827 -142.8781) (xy 100.986252 -142.935146)
			(xy 101.000708 -142.994343) (xy 101.007987 -143.054844) (xy 101.008434 -143.085312) (xy 101.007932 -143.117273)
			(xy 100.999921 -143.180691) (xy 100.984024 -143.242605) (xy 100.960492 -143.302038) (xy 100.929698 -143.358053)
			(xy 100.892125 -143.409768) (xy 100.848368 -143.456365) (xy 100.799115 -143.49711) (xy 100.745144 -143.531361)
			(xy 100.687305 -143.558578) (xy 100.626512 -143.578331) (xy 100.563722 -143.590309) (xy 100.499926 -143.594323)
			(xy 100.43613 -143.590309) (xy 100.37334 -143.578331) (xy 100.312547 -143.558578) (xy 100.254708 -143.531361)
			(xy 100.200737 -143.49711) (xy 100.151484 -143.456365) (xy 100.107727 -143.409768) (xy 100.070154 -143.358053)
			(xy 100.03936 -143.302038) (xy 100.015828 -143.242605) (xy 99.999931 -143.180691) (xy 99.99192 -143.117273)
			(xy 99.991418 -143.085312) (xy 99.991872 -143.055465) (xy 99.998847 -142.996181) (xy 100.012712 -142.93812)
			(xy 100.033279 -142.882082) (xy 100.060263 -142.828836) (xy 100.093294 -142.779114) (xy 100.131919 -142.733601)
			(xy 100.15347 -142.712948) (xy 100.162614 -142.704566) (xy 100.170742 -142.682214) (xy 100.15728 -142.577058)
			(xy 100.143564 -142.557246) (xy 100.132896 -142.551658) (xy 100.106265 -142.536851) (xy 100.05641 -142.501815)
			(xy 100.011099 -142.461072) (xy 99.970981 -142.415208) (xy 99.936631 -142.364878) (xy 99.908541 -142.310804)
			(xy 99.887113 -142.253762) (xy 99.872655 -142.194567) (xy 99.865374 -142.134069) (xy 99.864926 -142.103602)
			(xy 98.142552 -142.103602) (xy 98.142552 -145.094706) (xy 99.562412 -145.094706) (xy 99.562869 -145.067535)
			(xy 99.570588 -145.013744) (xy 99.585854 -144.96159) (xy 99.608362 -144.912128) (xy 99.637654 -144.866357)
			(xy 99.673141 -144.825202) (xy 99.714104 -144.789493) (xy 99.759716 -144.759954) (xy 99.809056 -144.737179)
			(xy 99.834954 -144.728946) (xy 99.818014 -144.708213) (xy 99.789507 -144.662895) (xy 99.767614 -144.614037)
			(xy 99.752765 -144.562598) (xy 99.745251 -144.509589) (xy 99.744784 -144.48282) (xy 99.744784 -144.482312)
			(xy 99.745038 -144.472152) (xy 99.741239 -144.452946) (xy 99.737172 -144.414004) (xy 99.73691 -144.394428)
			(xy 99.73745 -144.367161) (xy 99.745208 -144.31318) (xy 99.760568 -144.260854) (xy 99.783219 -144.211245)
			(xy 99.812699 -144.165366) (xy 99.848409 -144.124148) (xy 99.889621 -144.088433) (xy 99.935496 -144.058946)
			(xy 99.985101 -144.036287) (xy 100.037426 -144.020919) (xy 100.091405 -144.013154) (xy 100.118672 -144.012666)
			(xy 100.145135 -144.013149) (xy 100.197548 -144.020498) (xy 100.248447 -144.035005) (xy 100.29686 -144.056392)
			(xy 100.341861 -144.08425) (xy 100.362512 -144.100804) (xy 100.375212 -144.10055) (xy 100.375974 -144.10055)
			(xy 100.403245 -144.101026) (xy 100.457232 -144.108785) (xy 100.509565 -144.124148) (xy 100.559179 -144.146804)
			(xy 100.605063 -144.17629) (xy 100.646284 -144.212006) (xy 100.682002 -144.253225) (xy 100.71149 -144.299109)
			(xy 100.734147 -144.348722) (xy 100.749512 -144.401054) (xy 100.757273 -144.455041) (xy 100.757736 -144.482312)
			(xy 100.757209 -144.510627) (xy 100.748828 -144.566633) (xy 100.732268 -144.620787) (xy 100.707891 -144.671901)
			(xy 100.676232 -144.718855) (xy 100.637985 -144.760617) (xy 100.593989 -144.796273) (xy 100.54521 -144.825039)
			(xy 100.492717 -144.846285) (xy 100.437662 -144.859546) (xy 100.409502 -144.86255) (xy 100.409502 -144.987264)
			(xy 100.448048 -144.989781) (xy 100.524393 -145.00157) (xy 100.599156 -145.021015) (xy 100.67157 -145.047918)
			(xy 100.740893 -145.082004) (xy 100.806416 -145.122922) (xy 100.867467 -145.170254) (xy 100.923421 -145.223515)
			(xy 100.973705 -145.282159) (xy 101.017802 -145.345586) (xy 101.055263 -145.413146) (xy 101.085702 -145.484146)
			(xy 101.108808 -145.557859) (xy 101.124345 -145.633531) (xy 101.132153 -145.710385) (xy 101.13264 -145.74901)
			(xy 101.13215 -145.787668) (xy 101.124328 -145.864588) (xy 101.108765 -145.940321) (xy 101.085619 -146.014091)
			(xy 101.055129 -146.085142) (xy 101.017607 -146.152743) (xy 100.973439 -146.216201) (xy 100.923078 -146.274865)
			(xy 100.867039 -146.328134) (xy 100.8059 -146.375459) (xy 100.740286 -146.416357) (xy 100.670871 -146.450406)
			(xy 100.598368 -146.477259) (xy 100.523519 -146.496638) (xy 100.447095 -146.508346) (xy 100.369878 -146.512262)
			(xy 100.292661 -146.508346) (xy 100.216237 -146.496638) (xy 100.141388 -146.477259) (xy 100.068885 -146.450406)
			(xy 99.99947 -146.416357) (xy 99.933856 -146.375459) (xy 99.872717 -146.328134) (xy 99.816678 -146.274865)
			(xy 99.766317 -146.216201) (xy 99.722149 -146.152743) (xy 99.684627 -146.085142) (xy 99.654137 -146.014091)
			(xy 99.630991 -145.940321) (xy 99.615428 -145.864588) (xy 99.607606 -145.787668) (xy 99.607116 -145.74901)
			(xy 99.607592 -145.711287) (xy 99.615046 -145.636209) (xy 99.629881 -145.562235) (xy 99.651953 -145.490089)
			(xy 99.681046 -145.420476) (xy 99.698556 -145.38706) (xy 99.677651 -145.368793) (xy 99.640775 -145.327297)
			(xy 99.610296 -145.280899) (xy 99.586856 -145.230577) (xy 99.570949 -145.177391) (xy 99.562911 -145.122463)
			(xy 99.562412 -145.094706) (xy 98.142552 -145.094706) (xy 98.142552 -146.715226) (xy 98.142025 -146.725068)
			(xy 98.134455 -146.743245) (xy 98.12782 -146.750532) (xy 97.748344 -147.130008) (xy 97.741109 -147.13673)
			(xy 97.722904 -147.144345) (xy 97.713038 -147.14474) (xy 91.805252 -147.14474) (xy 91.795411 -147.14527)
			(xy 91.777239 -147.152845) (xy 91.769946 -147.159472) (xy 91.56954 -147.359878) (xy 91.562827 -147.367117)
			(xy 91.555228 -147.385321) (xy 91.554808 -147.395184) (xy 91.554808 -148.376132) (xy 91.555277 -148.386735)
			(xy 91.563951 -148.406085) (xy 91.571572 -148.41347) (xy 91.593416 -148.433028) (xy 91.60256 -148.423884)
			(xy 96.169988 -148.423884) (xy 96.200556 -148.405345) (xy 96.265788 -148.376089) (xy 96.334474 -148.356258)
			(xy 96.40526 -148.346245) (xy 96.441006 -148.345652) (xy 96.472969 -148.346154) (xy 96.536392 -148.354167)
			(xy 96.59831 -148.370066) (xy 96.657747 -148.393599) (xy 96.713766 -148.424397) (xy 96.765484 -148.461972)
			(xy 96.802236 -148.496485) (xy 97.816156 -148.496485) (xy 97.816156 -148.432563) (xy 97.824167 -148.369145)
			(xy 97.840064 -148.307231) (xy 97.863596 -148.247798) (xy 97.89439 -148.191783) (xy 97.931963 -148.140068)
			(xy 97.97572 -148.093471) (xy 98.024973 -148.052726) (xy 98.078944 -148.018475) (xy 98.136783 -147.991258)
			(xy 98.197576 -147.971505) (xy 98.260366 -147.959527) (xy 98.324162 -147.955514) (xy 98.387958 -147.959527)
			(xy 98.450748 -147.971505) (xy 98.511541 -147.991258) (xy 98.56938 -148.018475) (xy 98.623351 -148.052726)
			(xy 98.672604 -148.093471) (xy 98.716361 -148.140068) (xy 98.753934 -148.191783) (xy 98.784728 -148.247798)
			(xy 98.80826 -148.307231) (xy 98.824157 -148.369145) (xy 98.832168 -148.432563) (xy 98.83267 -148.464524)
			(xy 98.832168 -148.496485) (xy 98.824157 -148.559903) (xy 98.80826 -148.621817) (xy 98.784728 -148.68125)
			(xy 98.753934 -148.737265) (xy 98.716361 -148.78898) (xy 98.672604 -148.835577) (xy 98.623351 -148.876322)
			(xy 98.56938 -148.910573) (xy 98.511541 -148.93779) (xy 98.450748 -148.957543) (xy 98.387958 -148.969521)
			(xy 98.324162 -148.973535) (xy 98.260366 -148.969521) (xy 98.197576 -148.957543) (xy 98.136783 -148.93779)
			(xy 98.078944 -148.910573) (xy 98.024973 -148.876322) (xy 97.97572 -148.835577) (xy 97.931963 -148.78898)
			(xy 97.89439 -148.737265) (xy 97.863596 -148.68125) (xy 97.840064 -148.621817) (xy 97.824167 -148.559903)
			(xy 97.816156 -148.496485) (xy 96.802236 -148.496485) (xy 96.812084 -148.505733) (xy 96.852832 -148.55499)
			(xy 96.887085 -148.608965) (xy 96.914304 -148.666807) (xy 96.934058 -148.727605) (xy 96.946037 -148.7904)
			(xy 96.950051 -148.8542) (xy 96.946037 -148.918) (xy 96.934058 -148.980795) (xy 96.914304 -149.041593)
			(xy 96.887085 -149.099435) (xy 96.852832 -149.15341) (xy 96.812084 -149.202667) (xy 96.765484 -149.246428)
			(xy 96.713766 -149.284003) (xy 96.657747 -149.314801) (xy 96.59831 -149.338334) (xy 96.536392 -149.354233)
			(xy 96.472969 -149.362246) (xy 96.441006 -149.362668) (xy 96.405981 -149.362083) (xy 96.336594 -149.35247)
			(xy 96.269183 -149.333425) (xy 96.205024 -149.305308) (xy 96.145331 -149.268652) (xy 96.117918 -149.246844)
			(xy 96.086422 -149.235668) (xy 94.283022 -149.235668) (xy 94.273273 -149.236187) (xy 94.255249 -149.243639)
			(xy 94.24797 -149.250146) (xy 94.19082 -149.30755) (xy 94.1832 -149.325584) (xy 94.1832 -149.335744)
			(xy 94.18275 -149.367727) (xy 94.174791 -149.431195) (xy 94.158936 -149.493165) (xy 94.135433 -149.552656)
			(xy 94.104656 -149.60873) (xy 94.067089 -149.660502) (xy 94.023326 -149.707153) (xy 93.974058 -149.747948)
			(xy 93.920063 -149.782242) (xy 93.862193 -149.809493) (xy 93.801362 -149.829271) (xy 93.738531 -149.841265)
			(xy 93.674692 -149.845284) (xy 93.610853 -149.841265) (xy 93.548022 -149.829271) (xy 93.487191 -149.809493)
			(xy 93.429321 -149.782242) (xy 93.375326 -149.747948) (xy 93.326058 -149.707153) (xy 93.282295 -149.660502)
			(xy 93.244728 -149.60873) (xy 93.213951 -149.552656) (xy 93.190448 -149.493165) (xy 93.174593 -149.431195)
			(xy 93.166634 -149.367727) (xy 93.166184 -149.335744) (xy 93.166184 -149.325584) (xy 93.158564 -149.30755)
			(xy 93.101414 -149.250146) (xy 93.094165 -149.243594) (xy 93.076122 -149.23615) (xy 93.066362 -149.235668)
			(xy 92.76588 -149.235668) (xy 91.554808 -150.44674) (xy 91.554808 -151.776684) (xy 92.241624 -151.776684)
			(xy 92.242092 -151.745694) (xy 92.249634 -151.684175) (xy 92.264592 -151.624027) (xy 92.286745 -151.566141)
			(xy 92.315764 -151.511374) (xy 92.35122 -151.460537) (xy 92.392589 -151.414383) (xy 92.439256 -151.373595)
			(xy 92.464636 -151.355806) (xy 92.474514 -151.348432) (xy 92.48611 -151.326715) (xy 92.486734 -151.314404)
			(xy 92.486734 -151.2316) (xy 92.486078 -151.219301) (xy 92.474481 -151.197601) (xy 92.464636 -151.190198)
			(xy 92.439232 -151.172439) (xy 92.392553 -151.131656) (xy 92.351176 -151.085503) (xy 92.315716 -151.034663)
			(xy 92.286697 -150.97989) (xy 92.26455 -150.921996) (xy 92.249604 -150.86184) (xy 92.24208 -150.800313)
			(xy 92.241624 -150.76932) (xy 92.242126 -150.737359) (xy 92.250137 -150.673941) (xy 92.266034 -150.612027)
			(xy 92.289566 -150.552594) (xy 92.32036 -150.496579) (xy 92.357933 -150.444864) (xy 92.40169 -150.398267)
			(xy 92.450943 -150.357522) (xy 92.504914 -150.323271) (xy 92.562753 -150.296054) (xy 92.623546 -150.276301)
			(xy 92.686336 -150.264323) (xy 92.750132 -150.26031) (xy 92.813928 -150.264323) (xy 92.876718 -150.276301)
			(xy 92.937511 -150.296054) (xy 92.99535 -150.323271) (xy 93.049321 -150.357522) (xy 93.098574 -150.398267)
			(xy 93.142331 -150.444864) (xy 93.179904 -150.496579) (xy 93.210698 -150.552594) (xy 93.23423 -150.612027)
			(xy 93.250127 -150.673941) (xy 93.258138 -150.737359) (xy 93.258177 -150.739813) (xy 94.355152 -150.739813)
			(xy 94.355152 -150.675891) (xy 94.363163 -150.612473) (xy 94.37906 -150.550559) (xy 94.402592 -150.491126)
			(xy 94.433386 -150.435111) (xy 94.470959 -150.383396) (xy 94.514716 -150.336799) (xy 94.563969 -150.296054)
			(xy 94.61794 -150.261803) (xy 94.675779 -150.234586) (xy 94.736572 -150.214833) (xy 94.799362 -150.202855)
			(xy 94.863158 -150.198842) (xy 94.926954 -150.202855) (xy 94.989744 -150.214833) (xy 95.050537 -150.234586)
			(xy 95.108376 -150.261803) (xy 95.162347 -150.296054) (xy 95.2116 -150.336799) (xy 95.255357 -150.383396)
			(xy 95.29293 -150.435111) (xy 95.323724 -150.491126) (xy 95.347256 -150.550559) (xy 95.363153 -150.612473)
			(xy 95.371164 -150.675891) (xy 95.371666 -150.707852) (xy 95.371164 -150.739813) (xy 95.363153 -150.803231)
			(xy 95.347256 -150.865145) (xy 95.323724 -150.924578) (xy 95.29293 -150.980593) (xy 95.255357 -151.032308)
			(xy 95.2116 -151.078905) (xy 95.162347 -151.11965) (xy 95.108376 -151.153901) (xy 95.050537 -151.181118)
			(xy 94.989744 -151.200871) (xy 94.926954 -151.212849) (xy 94.863158 -151.216863) (xy 94.799362 -151.212849)
			(xy 94.736572 -151.200871) (xy 94.675779 -151.181118) (xy 94.61794 -151.153901) (xy 94.563969 -151.11965)
			(xy 94.514716 -151.078905) (xy 94.470959 -151.032308) (xy 94.433386 -150.980593) (xy 94.402592 -150.924578)
			(xy 94.37906 -150.865145) (xy 94.363163 -150.803231) (xy 94.355152 -150.739813) (xy 93.258177 -150.739813)
			(xy 93.25864 -150.76932) (xy 93.258147 -150.800309) (xy 93.250606 -150.861826) (xy 93.23565 -150.921973)
			(xy 93.213499 -150.979857) (xy 93.184484 -151.034624) (xy 93.149031 -151.085461) (xy 93.107668 -151.131616)
			(xy 93.061005 -151.172407) (xy 93.035628 -151.190198) (xy 93.025741 -151.197562) (xy 93.014151 -151.219287)
			(xy 93.01353 -151.2316) (xy 93.01353 -151.314404) (xy 93.014198 -151.326701) (xy 93.025788 -151.3484)
			(xy 93.035628 -151.355806) (xy 93.061025 -151.373574) (xy 93.107706 -151.414354) (xy 93.149085 -151.460505)
			(xy 93.184546 -151.511344) (xy 93.213566 -151.566116) (xy 93.235714 -151.624009) (xy 93.25066 -151.684165)
			(xy 93.258184 -151.745692) (xy 93.25864 -151.776684) (xy 93.258138 -151.808645) (xy 93.250127 -151.872063)
			(xy 93.23423 -151.933977) (xy 93.210698 -151.99341) (xy 93.179904 -152.049425) (xy 93.142331 -152.10114)
			(xy 93.098574 -152.147737) (xy 93.049321 -152.188482) (xy 92.99535 -152.222733) (xy 92.937511 -152.24995)
			(xy 92.876718 -152.269703) (xy 92.813928 -152.281681) (xy 92.750132 -152.285695) (xy 92.686336 -152.281681)
			(xy 92.623546 -152.269703) (xy 92.562753 -152.24995) (xy 92.504914 -152.222733) (xy 92.450943 -152.188482)
			(xy 92.40169 -152.147737) (xy 92.357933 -152.10114) (xy 92.32036 -152.049425) (xy 92.289566 -151.99341)
			(xy 92.266034 -151.933977) (xy 92.250137 -151.872063) (xy 92.242126 -151.808645) (xy 92.241624 -151.776684)
			(xy 91.554808 -151.776684) (xy 91.554808 -152.467013) (xy 93.286828 -152.467013) (xy 93.286828 -152.403091)
			(xy 93.294839 -152.339673) (xy 93.310736 -152.277759) (xy 93.334268 -152.218326) (xy 93.365062 -152.162311)
			(xy 93.402635 -152.110596) (xy 93.446392 -152.063999) (xy 93.495645 -152.023254) (xy 93.549616 -151.989003)
			(xy 93.607455 -151.961786) (xy 93.668248 -151.942033) (xy 93.731038 -151.930055) (xy 93.794834 -151.926042)
			(xy 93.85863 -151.930055) (xy 93.92142 -151.942033) (xy 93.982213 -151.961786) (xy 94.040052 -151.989003)
			(xy 94.094023 -152.023254) (xy 94.143276 -152.063999) (xy 94.187033 -152.110596) (xy 94.224606 -152.162311)
			(xy 94.2554 -152.218326) (xy 94.278932 -152.277759) (xy 94.294829 -152.339673) (xy 94.30284 -152.403091)
			(xy 94.303342 -152.435052) (xy 94.30284 -152.467013) (xy 94.294829 -152.530431) (xy 94.278932 -152.592345)
			(xy 94.2554 -152.651778) (xy 94.224606 -152.707793) (xy 94.187033 -152.759508) (xy 94.143276 -152.806105)
			(xy 94.094023 -152.84685) (xy 94.040052 -152.881101) (xy 93.982213 -152.908318) (xy 93.92142 -152.928071)
			(xy 93.85863 -152.940049) (xy 93.794834 -152.944063) (xy 93.731038 -152.940049) (xy 93.668248 -152.928071)
			(xy 93.607455 -152.908318) (xy 93.549616 -152.881101) (xy 93.495645 -152.84685) (xy 93.446392 -152.806105)
			(xy 93.402635 -152.759508) (xy 93.365062 -152.707793) (xy 93.334268 -152.651778) (xy 93.310736 -152.592345)
			(xy 93.294839 -152.530431) (xy 93.286828 -152.467013) (xy 91.554808 -152.467013) (xy 91.554808 -152.731978)
			(xy 91.555285 -152.742203) (xy 91.563417 -152.760964) (xy 91.570556 -152.7683) (xy 91.630754 -152.82545)
			(xy 91.650058 -152.832562) (xy 91.660218 -152.8318) (xy 91.701874 -152.830784) (xy 91.741242 -152.831276)
			(xy 91.819559 -152.839387) (xy 91.896623 -152.855525) (xy 91.971614 -152.879519) (xy 92.043734 -152.911114)
			(xy 92.112213 -152.949971) (xy 92.176324 -152.995679) (xy 92.235383 -153.04775) (xy 92.288761 -153.10563)
			(xy 92.312744 -153.136854) (xy 92.352622 -153.15692)
		)
		(stroke
			(width 0)
			(type solid)
		)
		(fill yes)
		(layer "In11.Cu")
		(net "PVDDCR_CPU0_P1_VCCS")
	)
	(gr_poly
		(pts
			(xy 375.9708 -150.759668) (xy 375.98066 -150.759188) (xy 375.998879 -150.751644) (xy 376.012827 -150.737705)
			(xy 376.020382 -150.719489) (xy 376.020838 -150.70963) (xy 376.020838 -149.797262) (xy 376.020391 -149.787121)
			(xy 376.012546 -149.768416) (xy 375.998088 -149.754191) (xy 375.988834 -149.750018) (xy 375.888504 -149.71014)
			(xy 375.858278 -149.716998) (xy 375.847356 -149.728428) (xy 375.823242 -149.753139) (xy 375.769496 -149.796482)
			(xy 375.710379 -149.832154) (xy 375.64698 -149.859499) (xy 375.580464 -149.878015) (xy 375.512055 -149.887361)
			(xy 375.477532 -149.88794) (xy 375.446799 -149.887478) (xy 375.385781 -149.880073) (xy 375.3261 -149.865367)
			(xy 375.268627 -149.843574) (xy 375.2142 -149.815013) (xy 375.163613 -149.7801) (xy 375.117602 -149.739343)
			(xy 375.07684 -149.693338) (xy 375.04192 -149.642755) (xy 375.013352 -149.588331) (xy 374.991552 -149.530861)
			(xy 374.976839 -149.471182) (xy 374.969426 -149.410165) (xy 374.969024 -149.379432) (xy 374.969458 -149.349159)
			(xy 374.976643 -149.289041) (xy 374.990915 -149.230201) (xy 375.012072 -149.173472) (xy 375.039815 -149.119656)
			(xy 375.073751 -149.069515) (xy 375.1134 -149.023758) (xy 375.158202 -148.983032) (xy 375.182638 -148.965158)
			(xy 375.187718 -148.961602) (xy 375.195084 -148.95322) (xy 375.208292 -148.928582) (xy 375.211021 -148.922996)
			(xy 375.213969 -148.910921) (xy 375.214134 -148.904706) (xy 375.214134 -148.846794) (xy 375.213989 -148.840577)
			(xy 375.211035 -148.828499) (xy 375.208292 -148.822918) (xy 375.195084 -148.79828) (xy 375.187718 -148.789898)
			(xy 375.182638 -148.786342) (xy 375.158229 -148.768432) (xy 375.113424 -148.727714) (xy 375.073771 -148.681963)
			(xy 375.039831 -148.631828) (xy 375.012085 -148.578017) (xy 374.990926 -148.521291) (xy 374.976652 -148.462455)
			(xy 374.969466 -148.40234) (xy 374.969024 -148.372068) (xy 374.96949 -148.341339) (xy 374.976902 -148.280329)
			(xy 374.991613 -148.220658) (xy 375.01341 -148.163195) (xy 375.041975 -148.108778) (xy 375.07689 -148.058202)
			(xy 375.117647 -148.012202) (xy 375.163652 -147.971451) (xy 375.214233 -147.936542) (xy 375.268654 -147.907984)
			(xy 375.326119 -147.886194) (xy 375.385792 -147.87149) (xy 375.446803 -147.864086) (xy 375.477532 -147.86356)
			(xy 375.508742 -147.86403) (xy 375.570695 -147.87166) (xy 375.631248 -147.886815) (xy 375.689492 -147.909265)
			(xy 375.744551 -147.938675) (xy 375.795596 -147.974601) (xy 375.841862 -148.016504) (xy 375.862596 -148.039836)
			(xy 375.869708 -148.048218) (xy 375.890028 -148.057362) (xy 375.987564 -148.056854) (xy 376.00763 -148.047456)
			(xy 376.014742 -148.039074) (xy 376.035488 -148.015413) (xy 376.081866 -147.972878) (xy 376.133138 -147.936391)
			(xy 376.18852 -147.906508) (xy 376.247165 -147.883687) (xy 376.308179 -147.868276) (xy 376.370627 -147.860511)
			(xy 376.402092 -147.860004) (xy 376.432824 -147.860449) (xy 376.49384 -147.867857) (xy 376.553519 -147.882566)
			(xy 376.610989 -147.904361) (xy 376.665413 -147.932925) (xy 376.715997 -147.96784) (xy 376.762004 -148.008599)
			(xy 376.802762 -148.054606) (xy 376.837677 -148.10519) (xy 376.866241 -148.159615) (xy 376.888035 -148.217085)
			(xy 376.902744 -148.276764) (xy 376.910151 -148.33778) (xy 376.9106 -148.368512) (xy 376.910029 -148.402695)
			(xy 376.900833 -148.470442) (xy 376.882636 -148.536343) (xy 376.855766 -148.599209) (xy 376.820709 -148.657903)
			(xy 376.799856 -148.684996) (xy 376.794776 -148.6916) (xy 376.786394 -148.714714) (xy 376.784981 -148.718892)
			(xy 376.783442 -148.727577) (xy 376.783346 -148.731986) (xy 376.783346 -148.779992) (xy 377.483622 -148.779992)
			(xy 377.487693 -148.72437) (xy 377.499819 -148.669933) (xy 377.519742 -148.617842) (xy 377.547038 -148.569207)
			(xy 377.581124 -148.525064) (xy 377.621273 -148.486355) (xy 377.666631 -148.453904) (xy 377.716231 -148.428403)
			(xy 377.769015 -148.410396) (xy 377.823858 -148.400266) (xy 377.879592 -148.398229) (xy 377.935029 -148.404329)
			(xy 377.988986 -148.418435) (xy 378.040315 -148.440247) (xy 378.087921 -148.469301) (xy 378.130789 -148.504976)
			(xy 378.168006 -148.546513) (xy 378.198779 -148.593026) (xy 378.222451 -148.643523) (xy 378.238519 -148.69693)
			(xy 378.246639 -148.752106) (xy 378.247148 -148.779992) (xy 378.246639 -148.807878) (xy 378.238519 -148.863054)
			(xy 378.222451 -148.916461) (xy 378.198779 -148.966958) (xy 378.168006 -149.013471) (xy 378.130789 -149.055008)
			(xy 378.087921 -149.090683) (xy 378.040315 -149.119737) (xy 377.988986 -149.141549) (xy 377.935029 -149.155655)
			(xy 377.879592 -149.161755) (xy 377.823858 -149.159718) (xy 377.769015 -149.149588) (xy 377.716231 -149.131581)
			(xy 377.666631 -149.10608) (xy 377.621273 -149.073629) (xy 377.581124 -149.03492) (xy 377.547038 -148.990777)
			(xy 377.519742 -148.942142) (xy 377.499819 -148.890051) (xy 377.487693 -148.835614) (xy 377.483622 -148.779992)
			(xy 376.783346 -148.779992) (xy 376.783346 -149.311614) (xy 380.247904 -149.311614) (xy 380.251975 -149.255992)
			(xy 380.264101 -149.201555) (xy 380.284024 -149.149464) (xy 380.31132 -149.100829) (xy 380.345406 -149.056686)
			(xy 380.385555 -149.017977) (xy 380.430913 -148.985526) (xy 380.480513 -148.960025) (xy 380.533297 -148.942018)
			(xy 380.58814 -148.931888) (xy 380.643874 -148.929851) (xy 380.699311 -148.935951) (xy 380.753268 -148.950057)
			(xy 380.804597 -148.971869) (xy 380.852203 -149.000923) (xy 380.895071 -149.036598) (xy 380.932288 -149.078135)
			(xy 380.963061 -149.124648) (xy 380.986733 -149.175145) (xy 381.002801 -149.228552) (xy 381.010921 -149.283728)
			(xy 381.01143 -149.311614) (xy 381.010921 -149.3395) (xy 381.002801 -149.394676) (xy 380.986733 -149.448083)
			(xy 380.963061 -149.49858) (xy 380.932288 -149.545093) (xy 380.895071 -149.58663) (xy 380.852203 -149.622305)
			(xy 380.804597 -149.651359) (xy 380.753268 -149.673171) (xy 380.699311 -149.687277) (xy 380.643874 -149.693377)
			(xy 380.58814 -149.69134) (xy 380.533297 -149.68121) (xy 380.480513 -149.663203) (xy 380.430913 -149.637702)
			(xy 380.385555 -149.605251) (xy 380.345406 -149.566542) (xy 380.31132 -149.522399) (xy 380.284024 -149.473764)
			(xy 380.264101 -149.421673) (xy 380.251975 -149.367236) (xy 380.247904 -149.311614) (xy 376.783346 -149.311614)
			(xy 376.783346 -150.344632) (xy 376.783772 -150.354646) (xy 376.791449 -150.373144) (xy 376.805622 -150.387295)
			(xy 376.824132 -150.394944) (xy 376.834146 -150.395432) (xy 381.111506 -150.395432) (xy 381.121575 -150.395857)
			(xy 381.140175 -150.403576) (xy 381.147574 -150.410418) (xy 381.481838 -150.744682) (xy 381.489238 -150.751524)
			(xy 381.507836 -150.759248) (xy 381.517906 -150.759668) (xy 383.80543 -150.759668) (xy 383.81527 -150.759139)
			(xy 383.833439 -150.751558) (xy 383.840736 -150.744936) (xy 384.158998 -150.426674) (xy 384.165711 -150.419436)
			(xy 384.173302 -150.401231) (xy 384.17373 -150.391368) (xy 384.17373 -147.420838) (xy 384.173323 -147.410963)
			(xy 384.165775 -147.392712) (xy 384.151814 -147.378742) (xy 384.133567 -147.371183) (xy 384.123692 -147.3708)
			(xy 381.72517 -147.3708) (xy 381.695188 -147.370247) (xy 381.635962 -147.360872) (xy 381.578933 -147.342343)
			(xy 381.525507 -147.315116) (xy 381.477001 -147.279862) (xy 381.455422 -147.25904) (xy 381.437896 -147.24126)
			(xy 381.422148 -147.23364) (xy 381.413004 -147.232878) (xy 381.381977 -147.229344) (xy 381.321046 -147.215661)
			(xy 381.262248 -147.194623) (xy 381.206467 -147.166548) (xy 381.15454 -147.131858) (xy 381.10725 -147.091073)
			(xy 381.065306 -147.044808) (xy 381.02934 -146.993757) (xy 380.999892 -146.938688) (xy 380.977404 -146.880429)
			(xy 380.962215 -146.819856) (xy 380.954554 -146.75788) (xy 380.954026 -146.726656) (xy 380.954493 -146.695927)
			(xy 380.961906 -146.634919) (xy 380.976618 -146.575249) (xy 380.998416 -146.517787) (xy 381.026981 -146.463372)
			(xy 381.061897 -146.412797) (xy 381.102654 -146.366799) (xy 381.148658 -146.326048) (xy 381.199239 -146.291141)
			(xy 381.253659 -146.262584) (xy 381.311124 -146.240795) (xy 381.370796 -146.226092) (xy 381.431805 -146.218688)
			(xy 381.462534 -146.218148) (xy 381.494644 -146.218641) (xy 381.55835 -146.226735) (xy 381.62053 -146.24279)
			(xy 381.680192 -146.26655) (xy 381.736386 -146.297636) (xy 381.788216 -146.335554) (xy 381.834857 -146.379698)
			(xy 381.875565 -146.429366) (xy 381.909692 -146.483767) (xy 381.936695 -146.542033) (xy 381.946912 -146.572478)
			(xy 381.951992 -146.58848) (xy 381.978662 -146.607784) (xy 382.97104 -146.607784) (xy 382.980197 -146.607348)
			(xy 382.997319 -146.600837) (xy 383.011091 -146.588757) (xy 383.015744 -146.58086) (xy 383.063496 -146.491706)
			(xy 383.062226 -146.46402) (xy 383.054352 -146.452082) (xy 383.038281 -146.427078) (xy 383.011441 -146.37404)
			(xy 382.990976 -146.318233) (xy 382.977164 -146.260418) (xy 382.970195 -146.201387) (xy 382.96977 -146.171666)
			(xy 382.96977 -146.171158) (xy 382.970272 -146.139197) (xy 382.978283 -146.075779) (xy 382.99418 -146.013865)
			(xy 383.017712 -145.954432) (xy 383.048506 -145.898417) (xy 383.086079 -145.846702) (xy 383.129836 -145.800105)
			(xy 383.179089 -145.75936) (xy 383.23306 -145.725109) (xy 383.290899 -145.697892) (xy 383.351692 -145.678139)
			(xy 383.414482 -145.666161) (xy 383.478278 -145.662148) (xy 383.542074 -145.666161) (xy 383.604864 -145.678139)
			(xy 383.665657 -145.697892) (xy 383.723496 -145.725109) (xy 383.777467 -145.75936) (xy 383.82672 -145.800105)
			(xy 383.870477 -145.846702) (xy 383.90805 -145.898417) (xy 383.938844 -145.954432) (xy 383.962376 -146.013865)
			(xy 383.978273 -146.075779) (xy 383.986284 -146.139197) (xy 383.986786 -146.171158) (xy 383.986786 -146.171666)
			(xy 383.986334 -146.201384) (xy 383.979346 -146.26041) (xy 383.965533 -146.318221) (xy 383.945081 -146.374029)
			(xy 383.918269 -146.427076) (xy 383.902204 -146.452082) (xy 383.89433 -146.46402) (xy 383.89306 -146.491706)
			(xy 383.940812 -146.58086) (xy 383.945448 -146.588777) (xy 383.9592 -146.600899) (xy 383.97635 -146.607375)
			(xy 383.985516 -146.607784) (xy 384.123692 -146.607784) (xy 384.133554 -146.607305) (xy 384.151779 -146.599764)
			(xy 384.165733 -146.585824) (xy 384.173295 -146.567607) (xy 384.17373 -146.557746) (xy 384.17373 -138.58113)
			(xy 384.173226 -138.571079) (xy 384.165508 -138.552515) (xy 384.158744 -138.545062) (xy 383.754122 -138.14044)
			(xy 383.746721 -138.133601) (xy 383.728122 -138.125889) (xy 383.718054 -138.125454) (xy 381.238252 -138.125454)
			(xy 381.228412 -138.125985) (xy 381.210241 -138.133561) (xy 381.202946 -138.140186) (xy 381.097028 -138.246104)
			(xy 381.089916 -138.27125) (xy 381.092964 -138.284204) (xy 381.099355 -138.312991) (xy 381.106227 -138.371559)
			(xy 381.10668 -138.401044) (xy 381.10668 -138.401552) (xy 381.106112 -138.435484) (xy 381.097071 -138.502742)
			(xy 381.079157 -138.568198) (xy 381.052689 -138.630687) (xy 381.018137 -138.689096) (xy 380.976118 -138.742386)
			(xy 380.927379 -138.789608) (xy 380.900432 -138.810238) (xy 380.895606 -138.813794) (xy 380.88824 -138.82243)
			(xy 380.87554 -138.846814) (xy 380.87293 -138.8523) (xy 380.870097 -138.864109) (xy 380.869952 -138.870182)
			(xy 380.869952 -139.714986) (xy 382.423668 -139.714986) (xy 382.427739 -139.659364) (xy 382.439865 -139.604927)
			(xy 382.459788 -139.552836) (xy 382.487084 -139.504201) (xy 382.52117 -139.460058) (xy 382.561319 -139.421349)
			(xy 382.606677 -139.388898) (xy 382.656277 -139.363397) (xy 382.709061 -139.34539) (xy 382.763904 -139.33526)
			(xy 382.819638 -139.333223) (xy 382.875075 -139.339323) (xy 382.929032 -139.353429) (xy 382.980361 -139.375241)
			(xy 383.027967 -139.404295) (xy 383.070835 -139.43997) (xy 383.108052 -139.481507) (xy 383.138825 -139.52802)
			(xy 383.162497 -139.578517) (xy 383.178565 -139.631924) (xy 383.186685 -139.6871) (xy 383.187194 -139.714986)
			(xy 383.186685 -139.742872) (xy 383.178565 -139.798048) (xy 383.162497 -139.851455) (xy 383.138825 -139.901952)
			(xy 383.108052 -139.948465) (xy 383.070835 -139.990002) (xy 383.027967 -140.025677) (xy 382.980361 -140.054731)
			(xy 382.929032 -140.076543) (xy 382.875075 -140.090649) (xy 382.819638 -140.096749) (xy 382.763904 -140.094712)
			(xy 382.709061 -140.084582) (xy 382.656277 -140.066575) (xy 382.606677 -140.041074) (xy 382.561319 -140.008623)
			(xy 382.52117 -139.969914) (xy 382.487084 -139.925771) (xy 382.459788 -139.877136) (xy 382.439865 -139.825045)
			(xy 382.427739 -139.770608) (xy 382.423668 -139.714986) (xy 380.869952 -139.714986) (xy 380.869952 -140.810488)
			(xy 382.559558 -140.810488) (xy 382.563629 -140.754866) (xy 382.575755 -140.700429) (xy 382.595678 -140.648338)
			(xy 382.622974 -140.599703) (xy 382.65706 -140.55556) (xy 382.697209 -140.516851) (xy 382.742567 -140.4844)
			(xy 382.792167 -140.458899) (xy 382.844951 -140.440892) (xy 382.899794 -140.430762) (xy 382.955528 -140.428725)
			(xy 383.010965 -140.434825) (xy 383.064922 -140.448931) (xy 383.116251 -140.470743) (xy 383.163857 -140.499797)
			(xy 383.206725 -140.535472) (xy 383.243942 -140.577009) (xy 383.274715 -140.623522) (xy 383.298387 -140.674019)
			(xy 383.314455 -140.727426) (xy 383.322575 -140.782602) (xy 383.323084 -140.810488) (xy 383.322575 -140.838374)
			(xy 383.314455 -140.89355) (xy 383.298387 -140.946957) (xy 383.274715 -140.997454) (xy 383.243942 -141.043967)
			(xy 383.206725 -141.085504) (xy 383.163857 -141.121179) (xy 383.116251 -141.150233) (xy 383.064922 -141.172045)
			(xy 383.010965 -141.186151) (xy 382.955528 -141.192251) (xy 382.899794 -141.190214) (xy 382.844951 -141.180084)
			(xy 382.792167 -141.162077) (xy 382.742567 -141.136576) (xy 382.697209 -141.104125) (xy 382.65706 -141.065416)
			(xy 382.622974 -141.021273) (xy 382.595678 -140.972638) (xy 382.575755 -140.920547) (xy 382.563629 -140.86611)
			(xy 382.559558 -140.810488) (xy 380.869952 -140.810488) (xy 380.869952 -143.346678) (xy 382.134364 -143.346678)
			(xy 382.13483 -143.307591) (xy 382.142831 -143.229827) (xy 382.158748 -143.15329) (xy 382.182413 -143.078783)
			(xy 382.213578 -143.007089) (xy 382.251915 -142.93896) (xy 382.274064 -142.90675) (xy 382.279266 -142.898713)
			(xy 382.283812 -142.880131) (xy 382.281202 -142.86118) (xy 382.276858 -142.852648) (xy 382.26525 -142.831191)
			(xy 382.24701 -142.785943) (xy 382.234685 -142.73874) (xy 382.228474 -142.690351) (xy 382.22809 -142.665958)
			(xy 382.228539 -142.638706) (xy 382.236301 -142.584757) (xy 382.251661 -142.532462) (xy 382.274307 -142.482884)
			(xy 382.303778 -142.437034) (xy 382.339473 -142.395845) (xy 382.380666 -142.360154) (xy 382.426519 -142.330688)
			(xy 382.476099 -142.308047) (xy 382.528396 -142.292692) (xy 382.582346 -142.284936) (xy 382.609598 -142.28445)
			(xy 382.626108 -142.284704) (xy 382.637792 -142.285212) (xy 382.659128 -142.276068) (xy 382.726438 -142.19682)
			(xy 382.73228 -142.174214) (xy 382.72974 -142.16253) (xy 382.726046 -142.143376) (xy 382.7221 -142.104565)
			(xy 382.721866 -142.08506) (xy 382.722421 -142.057812) (xy 382.730182 -142.003871) (xy 382.745541 -141.951584)
			(xy 382.768185 -141.902015) (xy 382.797652 -141.856172) (xy 382.833344 -141.81499) (xy 382.874533 -141.779307)
			(xy 382.920381 -141.749848) (xy 382.969955 -141.727215) (xy 383.022245 -141.711866) (xy 383.076187 -141.704116)
			(xy 383.130683 -141.704121) (xy 383.184624 -141.711881) (xy 383.236912 -141.727239) (xy 383.286481 -141.749882)
			(xy 383.332324 -141.779349) (xy 383.373506 -141.81504) (xy 383.40919 -141.856229) (xy 383.438649 -141.902077)
			(xy 383.461284 -141.95165) (xy 383.476633 -142.00394) (xy 383.484384 -142.057882) (xy 383.48438 -142.112379)
			(xy 383.47662 -142.16632) (xy 383.461262 -142.218607) (xy 383.43862 -142.268177) (xy 383.409153 -142.31402)
			(xy 383.373463 -142.355203) (xy 383.332275 -142.390887) (xy 383.286427 -142.420347) (xy 383.236854 -142.442982)
			(xy 383.184564 -142.458332) (xy 383.130622 -142.466084) (xy 383.103374 -142.466568) (xy 383.089865 -142.466457)
			(xy 383.062916 -142.464549) (xy 383.049526 -142.462758) (xy 383.041042 -142.461867) (xy 383.024311 -142.465154)
			(xy 383.00959 -142.473758) (xy 383.003806 -142.48003) (xy 382.983486 -142.503906) (xy 382.978173 -142.510613)
			(xy 382.971977 -142.526554) (xy 382.971368 -142.543645) (xy 382.97358 -142.551912) (xy 382.975358 -142.557754)
			(xy 382.978492 -142.566832) (xy 382.990298 -142.581956) (xy 383.006837 -142.591682) (xy 383.016252 -142.593568)
			(xy 383.054197 -142.600121) (xy 383.128651 -142.619779) (xy 383.200744 -142.646841) (xy 383.269742 -142.681034)
			(xy 383.334942 -142.722006) (xy 383.39568 -142.769343) (xy 383.451338 -142.822561) (xy 383.501347 -142.881117)
			(xy 383.545199 -142.944417) (xy 383.582447 -143.011814) (xy 383.612712 -143.082623) (xy 383.635685 -143.156122)
			(xy 383.651132 -143.231562) (xy 383.658897 -143.308175) (xy 383.65938 -143.346678) (xy 383.658891 -143.385323)
			(xy 383.651071 -143.462217) (xy 383.635513 -143.537925) (xy 383.612375 -143.611671) (xy 383.581895 -143.682698)
			(xy 383.544386 -143.750276) (xy 383.500232 -143.813714) (xy 383.449887 -143.872358) (xy 383.393868 -143.925609)
			(xy 383.332749 -143.972919) (xy 383.267156 -144.013803) (xy 383.197765 -144.047841) (xy 383.125285 -144.074684)
			(xy 383.050462 -144.094057) (xy 382.974063 -144.105761) (xy 382.896872 -144.109676) (xy 382.819681 -144.105761)
			(xy 382.743282 -144.094057) (xy 382.668459 -144.074684) (xy 382.595979 -144.047841) (xy 382.526588 -144.013803)
			(xy 382.460995 -143.972919) (xy 382.399876 -143.925609) (xy 382.343857 -143.872358) (xy 382.293512 -143.813714)
			(xy 382.249358 -143.750276) (xy 382.211849 -143.682698) (xy 382.181369 -143.611671) (xy 382.158231 -143.537925)
			(xy 382.142673 -143.462217) (xy 382.134853 -143.385323) (xy 382.134364 -143.346678) (xy 380.869952 -143.346678)
			(xy 380.869952 -144.317974) (xy 380.869416 -144.327812) (xy 380.861834 -144.345977) (xy 380.85522 -144.35328)
			(xy 380.475744 -144.732756) (xy 380.468507 -144.739473) (xy 380.450303 -144.747081) (xy 380.440438 -144.747488)
			(xy 374.532652 -144.747488) (xy 374.522812 -144.748019) (xy 374.504644 -144.7556) (xy 374.497346 -144.76222)
			(xy 374.29694 -144.962626) (xy 374.290234 -144.969867) (xy 374.282653 -144.988072) (xy 374.282208 -144.997932)
			(xy 374.282208 -145.028158) (xy 381.31826 -145.028158) (xy 381.322331 -144.972536) (xy 381.334457 -144.918099)
			(xy 381.35438 -144.866008) (xy 381.381676 -144.817373) (xy 381.415762 -144.77323) (xy 381.455911 -144.734521)
			(xy 381.501269 -144.70207) (xy 381.550869 -144.676569) (xy 381.603653 -144.658562) (xy 381.658496 -144.648432)
			(xy 381.71423 -144.646395) (xy 381.769667 -144.652495) (xy 381.823624 -144.666601) (xy 381.874953 -144.688413)
			(xy 381.922559 -144.717467) (xy 381.965427 -144.753142) (xy 382.002644 -144.794679) (xy 382.033417 -144.841192)
			(xy 382.057089 -144.891689) (xy 382.073157 -144.945096) (xy 382.081277 -145.000272) (xy 382.081786 -145.028158)
			(xy 382.081277 -145.056044) (xy 382.073157 -145.11122) (xy 382.057089 -145.164627) (xy 382.033417 -145.215124)
			(xy 382.002644 -145.261637) (xy 381.965427 -145.303174) (xy 381.922559 -145.338849) (xy 381.874953 -145.367903)
			(xy 381.823624 -145.389715) (xy 381.769667 -145.403821) (xy 381.71423 -145.409921) (xy 381.658496 -145.407884)
			(xy 381.603653 -145.397754) (xy 381.550869 -145.379747) (xy 381.501269 -145.354246) (xy 381.455911 -145.321795)
			(xy 381.415762 -145.283086) (xy 381.381676 -145.238943) (xy 381.35438 -145.190308) (xy 381.334457 -145.138217)
			(xy 381.322331 -145.08378) (xy 381.31826 -145.028158) (xy 374.282208 -145.028158) (xy 374.282208 -145.037302)
			(xy 374.282628 -145.047322) (xy 374.290299 -145.065837) (xy 374.304471 -145.080007) (xy 374.322987 -145.087674)
			(xy 374.333008 -145.088102) (xy 374.339104 -145.088102) (xy 374.344692 -145.086578) (xy 374.366526 -145.081689)
			(xy 374.410965 -145.076467) (xy 374.433338 -145.076164) (xy 378.69241 -145.076164) (xy 378.72239 -145.076723)
			(xy 378.78161 -145.086108) (xy 378.838633 -145.104645) (xy 378.892051 -145.131877) (xy 378.94055 -145.167134)
			(xy 378.962158 -145.187924) (xy 379.430534 -145.6563) (xy 379.43155 -145.657316) (xy 379.449909 -145.675368)
			(xy 379.482094 -145.715556) (xy 379.508575 -145.759711) (xy 379.528869 -145.807031) (xy 379.542606 -145.856652)
			(xy 379.549537 -145.90767) (xy 379.549914 -145.933414) (xy 379.549914 -146.093688) (xy 379.550005 -146.098098)
			(xy 379.551544 -146.106783) (xy 379.552962 -146.11096) (xy 379.561344 -146.134074) (xy 379.566424 -146.140678)
			(xy 379.587233 -146.167758) (xy 379.622182 -146.226433) (xy 379.648976 -146.289252) (xy 379.667132 -146.355088)
			(xy 379.676326 -146.422761) (xy 379.676914 -146.456908) (xy 379.676412 -146.488869) (xy 379.668401 -146.552287)
			(xy 379.652504 -146.614201) (xy 379.628972 -146.673634) (xy 379.598178 -146.729649) (xy 379.560605 -146.781364)
			(xy 379.516848 -146.827961) (xy 379.467595 -146.868706) (xy 379.413624 -146.902957) (xy 379.355785 -146.930174)
			(xy 379.294992 -146.949927) (xy 379.232202 -146.961905) (xy 379.168406 -146.965919) (xy 379.10461 -146.961905)
			(xy 379.04182 -146.949927) (xy 378.981027 -146.930174) (xy 378.923188 -146.902957) (xy 378.869217 -146.868706)
			(xy 378.819964 -146.827961) (xy 378.776207 -146.781364) (xy 378.738634 -146.729649) (xy 378.70784 -146.673634)
			(xy 378.684308 -146.614201) (xy 378.668411 -146.552287) (xy 378.6604 -146.488869) (xy 378.659898 -146.456908)
			(xy 378.660464 -146.422759) (xy 378.669635 -146.355078) (xy 378.687787 -146.289235) (xy 378.714592 -146.226416)
			(xy 378.749568 -146.167752) (xy 378.770388 -146.140678) (xy 378.775468 -146.134074) (xy 378.779024 -146.124676)
			(xy 378.781853 -146.11549) (xy 378.781207 -146.096295) (xy 378.773593 -146.078662) (xy 378.767086 -146.07159)
			(xy 378.549408 -145.854166) (xy 378.542013 -145.847311) (xy 378.523414 -145.839563) (xy 378.51334 -145.83918)
			(xy 374.6119 -145.83918) (xy 374.602065 -145.839721) (xy 374.583909 -145.847313) (xy 374.576594 -145.853912)
			(xy 374.29694 -146.133312) (xy 374.290232 -146.140552) (xy 374.282646 -146.158757) (xy 374.282208 -146.168618)
			(xy 374.282208 -146.955002) (xy 374.282705 -146.964997) (xy 374.290342 -146.983473) (xy 374.304429 -146.997658)
			(xy 374.31345 -147.001992) (xy 374.327928 -147.008088) (xy 374.3579 -147.001992) (xy 375.212102 -146.147536)
			(xy 375.233717 -146.126757) (xy 375.282222 -146.091521) (xy 375.335641 -146.064304) (xy 375.392659 -146.045776)
			(xy 375.451874 -146.036393) (xy 375.48185 -146.035776) (xy 377.715272 -146.035776) (xy 377.745253 -146.036332)
			(xy 377.804476 -146.045712) (xy 377.861502 -146.064245) (xy 377.914924 -146.091475) (xy 377.963427 -146.12673)
			(xy 377.98502 -146.147536) (xy 378.359162 -146.521678) (xy 378.376499 -146.539629) (xy 378.406848 -146.579248)
			(xy 378.431782 -146.62248) (xy 378.441712 -146.645376) (xy 378.576078 -146.969988) (xy 378.602494 -146.987006)
			(xy 378.618496 -146.986498) (xy 378.631958 -146.986244) (xy 378.662692 -146.986705) (xy 378.723712 -146.994109)
			(xy 378.783394 -147.008814) (xy 378.840869 -147.030606) (xy 378.895298 -147.059167) (xy 378.945888 -147.09408)
			(xy 378.9919 -147.134836) (xy 379.032665 -147.180841) (xy 379.067587 -147.231425) (xy 379.096157 -147.285849)
			(xy 379.117959 -147.34332) (xy 379.132675 -147.403) (xy 379.140089 -147.464018) (xy 379.140466 -147.494752)
			(xy 379.139882 -147.528043) (xy 379.131125 -147.594049) (xy 379.113846 -147.658351) (xy 379.101604 -147.689316)
			(xy 379.099572 -147.693888) (xy 379.097286 -147.705318) (xy 379.096181 -147.711937) (xy 379.09709 -147.72532)
			(xy 379.099064 -147.731734) (xy 379.105414 -147.749768) (xy 379.107038 -147.754113) (xy 379.111638 -147.762166)
			(xy 379.114558 -147.76577) (xy 379.131322 -147.785836) (xy 379.139196 -147.790408) (xy 379.167868 -147.807482)
			(xy 379.22089 -147.848003) (xy 379.268158 -147.89511) (xy 379.308858 -147.947995) (xy 379.342291 -148.005748)
			(xy 379.367884 -148.067378) (xy 379.385197 -148.131827) (xy 379.393931 -148.197986) (xy 379.394466 -148.231352)
			(xy 379.393964 -148.263313) (xy 379.385953 -148.326731) (xy 379.370056 -148.388645) (xy 379.346524 -148.448078)
			(xy 379.31573 -148.504093) (xy 379.278157 -148.555808) (xy 379.2344 -148.602405) (xy 379.185147 -148.64315)
			(xy 379.131176 -148.677401) (xy 379.073337 -148.704618) (xy 379.012544 -148.724371) (xy 378.949754 -148.736349)
			(xy 378.885958 -148.740363) (xy 378.822162 -148.736349) (xy 378.759372 -148.724371) (xy 378.698579 -148.704618)
			(xy 378.64074 -148.677401) (xy 378.586769 -148.64315) (xy 378.537516 -148.602405) (xy 378.493759 -148.555808)
			(xy 378.456186 -148.504093) (xy 378.425392 -148.448078) (xy 378.40186 -148.388645) (xy 378.385963 -148.326731)
			(xy 378.377952 -148.263313) (xy 378.37745 -148.231352) (xy 378.378033 -148.198061) (xy 378.38679 -148.132055)
			(xy 378.40407 -148.067752) (xy 378.416312 -148.036788) (xy 378.418344 -148.032216) (xy 378.42063 -148.020786)
			(xy 378.421736 -148.014167) (xy 378.420828 -148.000783) (xy 378.418852 -147.99437) (xy 378.412502 -147.976336)
			(xy 378.410876 -147.971993) (xy 378.40627 -147.963944) (xy 378.403358 -147.960334) (xy 378.386594 -147.940268)
			(xy 378.37872 -147.935696) (xy 378.352987 -147.920416) (xy 378.304943 -147.884726) (xy 378.261414 -147.843652)
			(xy 378.222999 -147.797758) (xy 378.190228 -147.747677) (xy 378.176536 -147.721066) (xy 378.172726 -147.713446)
			(xy 378.031502 -147.572476) (xy 378.014164 -147.554525) (xy 377.983813 -147.514908) (xy 377.958876 -147.471677)
			(xy 377.948952 -147.448778) (xy 377.769882 -147.016978) (xy 377.767877 -147.012412) (xy 377.762384 -147.004093)
			(xy 377.75896 -147.000468) (xy 377.57227 -146.813778) (xy 377.564874 -146.806928) (xy 377.546275 -146.799192)
			(xy 377.536202 -146.798792) (xy 375.660412 -146.798792) (xy 375.650576 -146.799331) (xy 375.632418 -146.806921)
			(xy 375.625106 -146.813524) (xy 375.020078 -147.418552) (xy 376.64212 -147.418552) (xy 376.646191 -147.36293)
			(xy 376.658317 -147.308493) (xy 376.67824 -147.256402) (xy 376.705536 -147.207767) (xy 376.739622 -147.163624)
			(xy 376.779771 -147.124915) (xy 376.825129 -147.092464) (xy 376.874729 -147.066963) (xy 376.927513 -147.048956)
			(xy 376.982356 -147.038826) (xy 377.03809 -147.036789) (xy 377.093527 -147.042889) (xy 377.147484 -147.056995)
			(xy 377.198813 -147.078807) (xy 377.246419 -147.107861) (xy 377.289287 -147.143536) (xy 377.326504 -147.185073)
			(xy 377.357277 -147.231586) (xy 377.380949 -147.282083) (xy 377.397017 -147.33549) (xy 377.405137 -147.390666)
			(xy 377.405646 -147.418552) (xy 377.405137 -147.446438) (xy 377.397017 -147.501614) (xy 377.380949 -147.555021)
			(xy 377.357277 -147.605518) (xy 377.326504 -147.652031) (xy 377.289287 -147.693568) (xy 377.246419 -147.729243)
			(xy 377.198813 -147.758297) (xy 377.147484 -147.780109) (xy 377.093527 -147.794215) (xy 377.03809 -147.800315)
			(xy 376.982356 -147.798278) (xy 376.927513 -147.788148) (xy 376.874729 -147.770141) (xy 376.825129 -147.74464)
			(xy 376.779771 -147.712189) (xy 376.739622 -147.67348) (xy 376.705536 -147.629337) (xy 376.67824 -147.580702)
			(xy 376.658317 -147.528611) (xy 376.646191 -147.474174) (xy 376.64212 -147.418552) (xy 375.020078 -147.418552)
			(xy 374.633998 -147.804632) (xy 374.627287 -147.811871) (xy 374.619699 -147.830076) (xy 374.619266 -147.839938)
			(xy 374.619266 -148.688552) (xy 374.618712 -148.718534) (xy 374.609335 -148.77776) (xy 374.590806 -148.834788)
			(xy 374.56358 -148.888215) (xy 374.528329 -148.936722) (xy 374.507506 -148.9583) (xy 374.29694 -149.168612)
			(xy 374.290232 -149.175852) (xy 374.282646 -149.194057) (xy 374.282208 -149.203918) (xy 374.282208 -150.467822)
			(xy 374.282635 -150.47789) (xy 374.290356 -150.496488) (xy 374.297194 -150.50389) (xy 374.537986 -150.744682)
			(xy 374.545388 -150.751517) (xy 374.563987 -150.759223) (xy 374.574054 -150.759668)
		)
		(stroke
			(width 0)
			(type solid)
		)
		(fill yes)
		(layer "In11.Cu")
		(net "PVDDCR_CPU0_P0_VCCS")
	)
	(gr_poly
		(pts
			(xy 34.68751 -367.12144) (xy 34.691574 -367.104422) (xy 34.701282 -367.066523) (xy 34.727416 -366.992779)
			(xy 34.760958 -366.922095) (xy 34.801556 -366.855215) (xy 34.848784 -366.792839) (xy 34.902146 -366.735623)
			(xy 34.961082 -366.684167) (xy 35.024974 -366.639011) (xy 35.093151 -366.60063) (xy 35.164897 -366.569426)
			(xy 35.23946 -366.545726) (xy 35.316056 -366.52978) (xy 35.393881 -366.521754) (xy 35.433 -366.521238)
			(xy 35.472123 -366.52173) (xy 35.549959 -366.52973) (xy 35.626566 -366.545657) (xy 35.70114 -366.569344)
			(xy 35.772898 -366.600541) (xy 35.841085 -366.638921) (xy 35.904984 -366.684079) (xy 35.963923 -366.735543)
			(xy 36.017285 -366.79277) (xy 36.064507 -366.85516) (xy 36.105094 -366.922056) (xy 36.138618 -366.992756)
			(xy 36.164728 -367.066517) (xy 36.174426 -367.104422) (xy 36.17849 -367.12144) (xy 36.206176 -367.143284)
			(xy 36.870386 -367.143284) (xy 36.880449 -367.142845) (xy 36.899029 -367.135107) (xy 36.906454 -367.128298)
			(xy 37.229542 -366.80521) (xy 37.236396 -366.797815) (xy 37.244144 -366.779216) (xy 37.244528 -366.769142)
			(xy 37.244528 -366.153446) (xy 37.225478 -366.126776) (xy 37.209984 -366.121696) (xy 37.185124 -366.112789)
			(xy 37.137929 -366.089094) (xy 37.094447 -366.059128) (xy 37.055504 -366.02346) (xy 37.021844 -365.98277)
			(xy 36.994106 -365.937832) (xy 36.972819 -365.889504) (xy 36.95839 -365.838706) (xy 36.951091 -365.786404)
			(xy 36.95065 -365.76) (xy 36.95109 -365.733591) (xy 36.958356 -365.681274) (xy 36.972763 -365.630459)
			(xy 36.994037 -365.582114) (xy 37.02177 -365.537162) (xy 37.055434 -365.496461) (xy 37.094386 -365.460789)
			(xy 37.137883 -365.430826) (xy 37.185095 -365.407143) (xy 37.209984 -365.398304) (xy 37.225478 -365.393224)
			(xy 37.244528 -365.366554) (xy 37.244528 -362.399072) (xy 37.244957 -362.389005) (xy 37.252682 -362.37041)
			(xy 37.259514 -362.363004) (xy 37.55898 -362.063538) (xy 37.566346 -362.046774) (xy 37.566854 -362.037122)
			(xy 37.569447 -361.99725) (xy 37.581943 -361.918328) (xy 37.602621 -361.841144) (xy 37.631254 -361.766545)
			(xy 37.667529 -361.695348) (xy 37.711047 -361.628333) (xy 37.761333 -361.566234) (xy 37.817834 -361.509733)
			(xy 37.879933 -361.459447) (xy 37.946948 -361.415929) (xy 38.018145 -361.379654) (xy 38.092744 -361.351021)
			(xy 38.169928 -361.330343) (xy 38.24885 -361.317847) (xy 38.288722 -361.315254) (xy 38.298374 -361.314746)
			(xy 38.315138 -361.30738) (xy 38.843204 -360.779314) (xy 38.850036 -360.771911) (xy 38.857739 -360.753312)
			(xy 38.85819 -360.743246) (xy 38.85819 -358.131872) (xy 38.857761 -358.121804) (xy 38.850039 -358.103208)
			(xy 38.843204 -358.095804) (xy 37.505386 -356.757986) (xy 37.498274 -356.75062) (xy 37.479478 -356.743)
			(xy 32.431482 -356.743) (xy 32.421413 -356.742573) (xy 32.402814 -356.734854) (xy 32.395414 -356.728014)
			(xy 31.870904 -356.203504) (xy 31.840424 -356.197916) (xy 31.825946 -356.204012) (xy 31.80184 -356.214017)
			(xy 31.751595 -356.228134) (xy 31.699895 -356.23528) (xy 31.6738 -356.235762) (xy 31.646531 -356.235276)
			(xy 31.592547 -356.227514) (xy 31.540217 -356.212149) (xy 31.490607 -356.189492) (xy 31.444726 -356.160006)
			(xy 31.403509 -356.124291) (xy 31.367794 -356.083074) (xy 31.338308 -356.037193) (xy 31.315651 -355.987583)
			(xy 31.300286 -355.935253) (xy 31.292524 -355.881269) (xy 31.292038 -355.854) (xy 31.292479 -355.827902)
			(xy 31.299623 -355.776197) (xy 31.31375 -355.725948) (xy 31.323788 -355.701854) (xy 31.329884 -355.687376)
			(xy 31.324296 -355.656896) (xy 31.165546 -355.498146) (xy 31.158134 -355.491462) (xy 31.139701 -355.483865)
			(xy 31.119763 -355.483865) (xy 31.10133 -355.491462) (xy 31.093918 -355.498146) (xy 30.039564 -356.5525)
			(xy 30.618428 -356.5525) (xy 30.622501 -356.496841) (xy 30.634636 -356.442368) (xy 30.654572 -356.390242)
			(xy 30.681886 -356.341574) (xy 30.715994 -356.297402) (xy 30.756171 -356.258667) (xy 30.801559 -356.226195)
			(xy 30.851191 -356.200677) (xy 30.904011 -356.182658) (xy 30.95889 -356.172521) (xy 31.014661 -356.170483)
			(xy 31.070135 -356.176586) (xy 31.124128 -356.190702) (xy 31.175491 -356.212529) (xy 31.223129 -356.241602)
			(xy 31.266025 -356.277301) (xy 31.303267 -356.318865) (xy 31.334061 -356.365409) (xy 31.357749 -356.41594)
			(xy 31.373827 -356.469382) (xy 31.381953 -356.524596) (xy 31.382462 -356.5525) (xy 31.381953 -356.580404)
			(xy 31.373827 -356.635618) (xy 31.357749 -356.68906) (xy 31.334061 -356.739591) (xy 31.303267 -356.786135)
			(xy 31.266025 -356.827699) (xy 31.223129 -356.863398) (xy 31.175491 -356.892471) (xy 31.124128 -356.914298)
			(xy 31.070135 -356.928414) (xy 31.014661 -356.934517) (xy 30.95889 -356.932479) (xy 30.904011 -356.922342)
			(xy 30.851191 -356.904323) (xy 30.801559 -356.878805) (xy 30.756171 -356.846333) (xy 30.715994 -356.807598)
			(xy 30.681886 -356.763426) (xy 30.654572 -356.714758) (xy 30.634636 -356.662632) (xy 30.622501 -356.608159)
			(xy 30.618428 -356.5525) (xy 30.039564 -356.5525) (xy 29.745432 -356.846632) (xy 29.741368 -356.850442)
			(xy 29.741114 -356.85095) (xy 29.685742 -356.906068) (xy 29.678395 -356.912873) (xy 29.659932 -356.920589)
			(xy 29.649928 -356.921054) (xy 29.576776 -356.921054) (xy 29.57576 -356.921054) (xy 29.5656 -356.921308)
			(xy 28.625292 -356.921308) (xy 28.615132 -356.921054) (xy 28.614116 -356.921054) (xy 28.541472 -356.921054)
			(xy 28.531488 -356.92051) (xy 28.513068 -356.912784) (xy 28.505658 -356.906068) (xy 28.456382 -356.856792)
			(xy 28.455366 -356.85603) (xy 28.445714 -356.846886) (xy 28.382468 -356.78364) (xy 28.378853 -356.780203)
			(xy 28.370538 -356.774694) (xy 28.365958 -356.772718) (xy 28.357068 -356.768908) (xy 28.3464 -356.769162)
			(xy 28.319131 -356.768676) (xy 28.265147 -356.760914) (xy 28.212817 -356.745549) (xy 28.163207 -356.722892)
			(xy 28.117326 -356.693406) (xy 28.076109 -356.657691) (xy 28.040394 -356.616474) (xy 28.010908 -356.570593)
			(xy 27.988251 -356.520983) (xy 27.972886 -356.468653) (xy 27.965124 -356.414669) (xy 27.965124 -356.360131)
			(xy 27.972886 -356.306147) (xy 27.988251 -356.253817) (xy 28.010908 -356.204207) (xy 28.040394 -356.158326)
			(xy 28.076109 -356.117109) (xy 28.117326 -356.081394) (xy 28.163207 -356.051908) (xy 28.212817 -356.029251)
			(xy 28.265147 -356.013886) (xy 28.319131 -356.006124) (xy 28.3464 -356.005638) (xy 28.375257 -356.00616)
			(xy 28.432315 -356.014834) (xy 28.487416 -356.032001) (xy 28.539304 -356.057268) (xy 28.586797 -356.090059)
			(xy 28.628811 -356.129627) (xy 28.664389 -356.17507) (xy 28.692719 -356.225352) (xy 28.713156 -356.279326)
			(xy 28.725233 -356.335761) (xy 28.7274 -356.36454) (xy 28.72867 -356.384606) (xy 28.758134 -356.412292)
			(xy 29.449268 -356.412292) (xy 29.468064 -356.404672) (xy 29.475176 -356.397306) (xy 30.734254 -355.138482)
			(xy 30.740933 -355.131071) (xy 30.748521 -355.112642) (xy 30.748512 -355.092713) (xy 30.740908 -355.074291)
			(xy 30.734254 -355.066854) (xy 30.266386 -354.598986) (xy 30.259274 -354.59162) (xy 30.240478 -354.584)
			(xy 30.149292 -354.584) (xy 30.139305 -354.584539) (xy 30.120875 -354.592254) (xy 30.113478 -354.598986)
			(xy 29.228542 -355.483668) (xy 29.221195 -355.490473) (xy 29.202732 -355.498189) (xy 29.192728 -355.498654)
			(xy 29.135578 -355.498654) (xy 29.125594 -355.499197) (xy 29.107172 -355.506922) (xy 29.099764 -355.51364)
			(xy 29.078123 -355.534586) (xy 29.02947 -355.570081) (xy 28.975849 -355.597501) (xy 28.918591 -355.616167)
			(xy 28.859112 -355.625618) (xy 28.829 -355.626162) (xy 28.801363 -355.625672) (xy 28.746668 -355.617701)
			(xy 28.693694 -355.601925) (xy 28.643548 -355.578675) (xy 28.59728 -355.548436) (xy 28.555856 -355.511841)
			(xy 28.537662 -355.491034) (xy 28.53007 -355.482902) (xy 28.509912 -355.473552) (xy 28.4988 -355.473)
			(xy 27.732482 -355.473) (xy 27.722413 -355.473427) (xy 27.703814 -355.481146) (xy 27.696414 -355.487986)
			(xy 26.964386 -356.220014) (xy 26.95702 -356.227126) (xy 26.9494 -356.245922) (xy 26.9494 -357.48595)
			(xy 27.558238 -357.48595) (xy 27.558724 -357.458681) (xy 27.566486 -357.404697) (xy 27.581851 -357.352367)
			(xy 27.604508 -357.302757) (xy 27.633994 -357.256876) (xy 27.669709 -357.215659) (xy 27.710926 -357.179944)
			(xy 27.756807 -357.150458) (xy 27.806417 -357.127801) (xy 27.858747 -357.112436) (xy 27.912731 -357.104674)
			(xy 27.967269 -357.104674) (xy 28.021253 -357.112436) (xy 28.073583 -357.127801) (xy 28.123193 -357.150458)
			(xy 28.169074 -357.179944) (xy 28.210291 -357.215659) (xy 28.246006 -357.256876) (xy 28.275492 -357.302757)
			(xy 28.298149 -357.352367) (xy 28.313514 -357.404697) (xy 28.321276 -357.458681) (xy 28.321762 -357.48595)
			(xy 28.321211 -357.515458) (xy 28.312142 -357.573774) (xy 28.294198 -357.629996) (xy 28.280497 -357.6574)
			(xy 30.275528 -357.6574) (xy 30.279601 -357.601741) (xy 30.291736 -357.547268) (xy 30.311672 -357.495142)
			(xy 30.338986 -357.446474) (xy 30.373094 -357.402302) (xy 30.413271 -357.363567) (xy 30.458659 -357.331095)
			(xy 30.508291 -357.305577) (xy 30.561111 -357.287558) (xy 30.61599 -357.277421) (xy 30.671761 -357.275383)
			(xy 30.727235 -357.281486) (xy 30.781228 -357.295602) (xy 30.832591 -357.317429) (xy 30.880229 -357.346502)
			(xy 30.923125 -357.382201) (xy 30.960367 -357.423765) (xy 30.991161 -357.470309) (xy 31.014849 -357.52084)
			(xy 31.030927 -357.574282) (xy 31.039053 -357.629496) (xy 31.039562 -357.6574) (xy 33.856928 -357.6574)
			(xy 33.861001 -357.601741) (xy 33.873136 -357.547268) (xy 33.893072 -357.495142) (xy 33.920386 -357.446474)
			(xy 33.954494 -357.402302) (xy 33.994671 -357.363567) (xy 34.040059 -357.331095) (xy 34.089691 -357.305577)
			(xy 34.142511 -357.287558) (xy 34.19739 -357.277421) (xy 34.253161 -357.275383) (xy 34.308635 -357.281486)
			(xy 34.362628 -357.295602) (xy 34.413991 -357.317429) (xy 34.461629 -357.346502) (xy 34.504525 -357.382201)
			(xy 34.541767 -357.423765) (xy 34.572561 -357.470309) (xy 34.596249 -357.52084) (xy 34.612327 -357.574282)
			(xy 34.620453 -357.629496) (xy 34.620962 -357.6574) (xy 34.620453 -357.685304) (xy 34.612327 -357.740518)
			(xy 34.596249 -357.79396) (xy 34.572561 -357.844491) (xy 34.541767 -357.891035) (xy 34.504525 -357.932599)
			(xy 34.461629 -357.968298) (xy 34.413991 -357.997371) (xy 34.362628 -358.019198) (xy 34.308635 -358.033314)
			(xy 34.253161 -358.039417) (xy 34.19739 -358.037379) (xy 34.142511 -358.027242) (xy 34.089691 -358.009223)
			(xy 34.040059 -357.983705) (xy 33.994671 -357.951233) (xy 33.954494 -357.912498) (xy 33.920386 -357.868326)
			(xy 33.893072 -357.819658) (xy 33.873136 -357.767532) (xy 33.861001 -357.713059) (xy 33.856928 -357.6574)
			(xy 31.039562 -357.6574) (xy 31.039053 -357.685304) (xy 31.030927 -357.740518) (xy 31.014849 -357.79396)
			(xy 30.991161 -357.844491) (xy 30.960367 -357.891035) (xy 30.923125 -357.932599) (xy 30.880229 -357.968298)
			(xy 30.832591 -357.997371) (xy 30.781228 -358.019198) (xy 30.727235 -358.033314) (xy 30.671761 -358.039417)
			(xy 30.61599 -358.037379) (xy 30.561111 -358.027242) (xy 30.508291 -358.009223) (xy 30.458659 -357.983705)
			(xy 30.413271 -357.951233) (xy 30.373094 -357.912498) (xy 30.338986 -357.868326) (xy 30.311672 -357.819658)
			(xy 30.291736 -357.767532) (xy 30.279601 -357.713059) (xy 30.275528 -357.6574) (xy 28.280497 -357.6574)
			(xy 28.267806 -357.682782) (xy 28.233598 -357.730873) (xy 28.192389 -357.773119) (xy 28.169108 -357.791258)
			(xy 28.165552 -357.794052) (xy 28.154946 -357.804187) (xy 28.139628 -357.829194) (xy 28.132045 -357.857523)
			(xy 28.132823 -357.886839) (xy 28.141897 -357.914726) (xy 28.15852 -357.938886) (xy 28.169616 -357.948484)
			(xy 28.173172 -357.951024) (xy 28.194965 -357.966288) (xy 28.234443 -358.00196) (xy 28.268584 -358.042769)
			(xy 28.296727 -358.087924) (xy 28.318325 -358.13655) (xy 28.332961 -358.187705) (xy 28.340351 -358.240396)
			(xy 28.340812 -358.267) (xy 29.259528 -358.267) (xy 29.263601 -358.211341) (xy 29.275736 -358.156868)
			(xy 29.295672 -358.104742) (xy 29.322986 -358.056074) (xy 29.357094 -358.011902) (xy 29.397271 -357.973167)
			(xy 29.442659 -357.940695) (xy 29.492291 -357.915177) (xy 29.545111 -357.897158) (xy 29.59999 -357.887021)
			(xy 29.655761 -357.884983) (xy 29.711235 -357.891086) (xy 29.765228 -357.905202) (xy 29.816591 -357.927029)
			(xy 29.864229 -357.956102) (xy 29.907125 -357.991801) (xy 29.944367 -358.033365) (xy 29.975161 -358.079909)
			(xy 29.998849 -358.13044) (xy 30.014927 -358.183882) (xy 30.023053 -358.239096) (xy 30.023562 -358.267)
			(xy 30.023053 -358.294904) (xy 30.014927 -358.350118) (xy 29.998849 -358.40356) (xy 29.975161 -358.454091)
			(xy 29.944367 -358.500635) (xy 29.907125 -358.542199) (xy 29.864229 -358.577898) (xy 29.816591 -358.606971)
			(xy 29.765228 -358.628798) (xy 29.711235 -358.642914) (xy 29.655761 -358.649017) (xy 29.59999 -358.646979)
			(xy 29.545111 -358.636842) (xy 29.492291 -358.618823) (xy 29.442659 -358.593305) (xy 29.397271 -358.560833)
			(xy 29.357094 -358.522098) (xy 29.322986 -358.477926) (xy 29.295672 -358.429258) (xy 29.275736 -358.377132)
			(xy 29.263601 -358.322659) (xy 29.259528 -358.267) (xy 28.340812 -358.267) (xy 28.340326 -358.294269)
			(xy 28.332564 -358.348253) (xy 28.317199 -358.400583) (xy 28.294542 -358.450193) (xy 28.265056 -358.496074)
			(xy 28.229341 -358.537291) (xy 28.188124 -358.573006) (xy 28.142243 -358.602492) (xy 28.092633 -358.625149)
			(xy 28.040303 -358.640514) (xy 27.986319 -358.648276) (xy 27.931781 -358.648276) (xy 27.877797 -358.640514)
			(xy 27.825467 -358.625149) (xy 27.775857 -358.602492) (xy 27.729976 -358.573006) (xy 27.688759 -358.537291)
			(xy 27.653044 -358.496074) (xy 27.623558 -358.450193) (xy 27.600901 -358.400583) (xy 27.585536 -358.348253)
			(xy 27.577774 -358.294269) (xy 27.577288 -358.267) (xy 27.577856 -358.237492) (xy 27.586918 -358.179177)
			(xy 27.604858 -358.122954) (xy 27.631246 -358.070167) (xy 27.665453 -358.022076) (xy 27.706661 -357.97983)
			(xy 27.729942 -357.961692) (xy 27.733498 -357.958898) (xy 27.744046 -357.94871) (xy 27.759359 -357.923716)
			(xy 27.766944 -357.895403) (xy 27.766176 -357.866101) (xy 27.757119 -357.838224) (xy 27.740519 -357.814066)
			(xy 27.729434 -357.804466) (xy 27.725878 -357.801926) (xy 27.70412 -357.786615) (xy 27.664638 -357.750953)
			(xy 27.630493 -357.710152) (xy 27.602345 -357.665005) (xy 27.580741 -357.616386) (xy 27.566099 -357.565238)
			(xy 27.558703 -357.512551) (xy 27.558238 -357.48595) (xy 26.9494 -357.48595) (xy 26.9494 -358.372918)
			(xy 26.949827 -358.382987) (xy 26.957546 -358.401586) (xy 26.964386 -358.408986) (xy 27.823414 -359.268014)
			(xy 27.830809 -359.274868) (xy 27.849408 -359.28261) (xy 27.859482 -359.283) (xy 29.388054 -359.283)
			(xy 29.391925 -359.282953) (xy 29.39958 -359.281806) (xy 29.403294 -359.280714) (xy 29.424122 -359.27411)
			(xy 29.430218 -359.270046) (xy 29.453837 -359.254911) (xy 29.504572 -359.230982) (xy 29.558263 -359.214732)
			(xy 29.613752 -359.206511) (xy 29.6418 -359.206038) (xy 29.669847 -359.206533) (xy 29.725336 -359.214744)
			(xy 29.779027 -359.230988) (xy 29.829761 -359.254916) (xy 29.853382 -359.270046) (xy 29.859478 -359.27411)
			(xy 29.880306 -359.280714) (xy 29.884026 -359.281778) (xy 29.891678 -359.28292) (xy 29.895546 -359.283)
			(xy 31.1404 -359.283) (xy 31.150579 -359.282494) (xy 31.169309 -359.274501) (xy 31.176722 -359.267506)
			(xy 31.227268 -359.21569) (xy 31.230841 -359.211856) (xy 31.236474 -359.20302) (xy 31.238444 -359.198164)
			(xy 31.242 -359.18902) (xy 31.241238 -359.156) (xy 31.241728 -359.117342) (xy 31.24955 -359.040422)
			(xy 31.265113 -358.964689) (xy 31.288259 -358.890919) (xy 31.318749 -358.819868) (xy 31.356271 -358.752267)
			(xy 31.400439 -358.688809) (xy 31.4508 -358.630145) (xy 31.506839 -358.576876) (xy 31.567978 -358.529551)
			(xy 31.633592 -358.488653) (xy 31.703007 -358.454604) (xy 31.77551 -358.427751) (xy 31.850359 -358.408372)
			(xy 31.926783 -358.396664) (xy 32.004 -358.392748) (xy 32.081217 -358.396664) (xy 32.157641 -358.408372)
			(xy 32.23249 -358.427751) (xy 32.304993 -358.454604) (xy 32.374408 -358.488653) (xy 32.440022 -358.529551)
			(xy 32.501161 -358.576876) (xy 32.5572 -358.630145) (xy 32.607561 -358.688809) (xy 32.651729 -358.752267)
			(xy 32.689251 -358.819868) (xy 32.719741 -358.890919) (xy 32.742887 -358.964689) (xy 32.75845 -359.040422)
			(xy 32.766272 -359.117342) (xy 32.766762 -359.156) (xy 32.766508 -359.17886) (xy 32.766448 -359.183922)
			(xy 32.768107 -359.193905) (xy 32.76981 -359.198672) (xy 32.773366 -359.20807) (xy 32.831532 -359.26776)
			(xy 32.838958 -359.274706) (xy 32.857695 -359.282558) (xy 32.867854 -359.283) (xy 33.071054 -359.283)
			(xy 33.081081 -359.283412) (xy 33.099614 -359.291073) (xy 33.113801 -359.305247) (xy 33.121479 -359.323773)
			(xy 33.121854 -359.3338) (xy 33.121854 -360.374946) (xy 33.122349 -360.384951) (xy 33.130015 -360.403435)
			(xy 33.144165 -360.417585) (xy 33.162649 -360.425251) (xy 33.172654 -360.425746) (xy 34.544762 -360.425746)
			(xy 34.554751 -360.425214) (xy 34.573188 -360.417504) (xy 34.580576 -360.41076) (xy 35.678618 -359.312972)
			(xy 35.686238 -359.294176) (xy 35.686238 -359.284016) (xy 35.686632 -359.256698) (xy 35.694277 -359.202601)
			(xy 35.709555 -359.150146) (xy 35.732154 -359.100405) (xy 35.761614 -359.054393) (xy 35.797332 -359.013051)
			(xy 35.838579 -358.977224) (xy 35.884512 -358.947642) (xy 35.934192 -358.924909) (xy 35.986606 -358.909492)
			(xy 36.040683 -358.901703) (xy 36.068 -358.901238) (xy 36.096121 -358.901737) (xy 36.151756 -358.90998)
			(xy 36.205582 -358.926288) (xy 36.256437 -358.950309) (xy 36.303222 -358.981525) (xy 36.344926 -359.01926)
			(xy 36.363148 -359.040684) (xy 36.373338 -359.052255) (xy 36.399106 -359.06916) (xy 36.428743 -359.077609)
			(xy 36.459552 -359.076831) (xy 36.488725 -359.066898) (xy 36.513607 -359.048714) (xy 36.523168 -359.03662)
			(xy 36.541318 -359.013097) (xy 36.583672 -358.971433) (xy 36.631966 -358.936828) (xy 36.685034 -358.910117)
			(xy 36.741598 -358.891943) (xy 36.800294 -358.882745) (xy 36.83 -358.882188) (xy 36.857298 -358.882653)
			(xy 36.911336 -358.89043) (xy 36.963716 -358.905823) (xy 37.01337 -358.928521) (xy 37.059284 -358.95806)
			(xy 37.100523 -358.993837) (xy 37.136245 -359.035123) (xy 37.165723 -359.081077) (xy 37.188354 -359.13076)
			(xy 37.203678 -359.183161) (xy 37.211383 -359.23721) (xy 37.21131 -359.291805) (xy 37.203462 -359.345833)
			(xy 37.187998 -359.398193) (xy 37.165234 -359.447816) (xy 37.135635 -359.493691) (xy 37.099803 -359.534882)
			(xy 37.058469 -359.570549) (xy 37.012476 -359.599966) (xy 36.962763 -359.622531) (xy 36.910342 -359.637786)
			(xy 36.856283 -359.645418) (xy 36.828984 -359.645712) (xy 36.818824 -359.645712) (xy 36.800028 -359.653332)
			(xy 35.153092 -361.300268) (xy 35.145748 -361.307081) (xy 35.127285 -361.314815) (xy 35.117278 -361.315254)
			(xy 33.172654 -361.315254) (xy 33.162649 -361.315749) (xy 33.144165 -361.323415) (xy 33.130015 -361.337565)
			(xy 33.122349 -361.356049) (xy 33.121854 -361.366054) (xy 33.121854 -363.728) (xy 33.780732 -363.728)
			(xy 33.784777 -363.64952) (xy 33.79687 -363.571872) (xy 33.816883 -363.495879) (xy 33.844604 -363.422346)
			(xy 33.879739 -363.352054) (xy 33.921915 -363.285746) (xy 33.970685 -363.224127) (xy 34.025532 -363.167848)
			(xy 34.085875 -363.117508) (xy 34.151075 -363.073639) (xy 34.220439 -363.036706) (xy 34.293234 -363.007101)
			(xy 34.368687 -362.985138) (xy 34.445998 -362.971049) (xy 34.524347 -362.964985) (xy 34.602906 -362.967008)
			(xy 34.680839 -362.977098) (xy 34.757323 -362.995148) (xy 34.831545 -363.020966) (xy 34.902718 -363.054279)
			(xy 34.967202 -363.093) (xy 35.558728 -363.093) (xy 35.562801 -363.037341) (xy 35.574936 -362.982868)
			(xy 35.594872 -362.930742) (xy 35.622186 -362.882074) (xy 35.656294 -362.837902) (xy 35.696471 -362.799167)
			(xy 35.741859 -362.766695) (xy 35.791491 -362.741177) (xy 35.844311 -362.723158) (xy 35.89919 -362.713021)
			(xy 35.954961 -362.710983) (xy 36.010435 -362.717086) (xy 36.064428 -362.731202) (xy 36.115791 -362.753029)
			(xy 36.163429 -362.782102) (xy 36.206325 -362.817801) (xy 36.243567 -362.859365) (xy 36.274361 -362.905909)
			(xy 36.298049 -362.95644) (xy 36.314127 -363.009882) (xy 36.322253 -363.065096) (xy 36.322762 -363.093)
			(xy 36.322253 -363.120904) (xy 36.314127 -363.176118) (xy 36.298049 -363.22956) (xy 36.274361 -363.280091)
			(xy 36.243567 -363.326635) (xy 36.206325 -363.368199) (xy 36.163429 -363.403898) (xy 36.115791 -363.432971)
			(xy 36.064428 -363.454798) (xy 36.010435 -363.468914) (xy 35.954961 -363.475017) (xy 35.89919 -363.472979)
			(xy 35.844311 -363.462842) (xy 35.791491 -363.444823) (xy 35.741859 -363.419305) (xy 35.696471 -363.386833)
			(xy 35.656294 -363.348098) (xy 35.622186 -363.303926) (xy 35.594872 -363.255258) (xy 35.574936 -363.203132)
			(xy 35.562801 -363.148659) (xy 35.558728 -363.093) (xy 34.967202 -363.093) (xy 34.97009 -363.094734)
			(xy 35.032945 -363.141901) (xy 35.090616 -363.195281) (xy 35.142494 -363.254308) (xy 35.188027 -363.318357)
			(xy 35.226734 -363.386747) (xy 35.258203 -363.458755) (xy 35.282102 -363.533618) (xy 35.298176 -363.61054)
			(xy 35.306256 -363.688708) (xy 35.306762 -363.728) (xy 35.306256 -363.767292) (xy 35.298176 -363.84546)
			(xy 35.282102 -363.922382) (xy 35.258203 -363.997245) (xy 35.226734 -364.069253) (xy 35.204238 -364.109)
			(xy 35.559238 -364.109) (xy 35.559724 -364.081731) (xy 35.567486 -364.027747) (xy 35.582851 -363.975417)
			(xy 35.605508 -363.925807) (xy 35.634994 -363.879926) (xy 35.670709 -363.838709) (xy 35.711926 -363.802994)
			(xy 35.757807 -363.773508) (xy 35.807417 -363.750851) (xy 35.859747 -363.735486) (xy 35.913731 -363.727724)
			(xy 35.968269 -363.727724) (xy 36.022253 -363.735486) (xy 36.074583 -363.750851) (xy 36.124193 -363.773508)
			(xy 36.170074 -363.802994) (xy 36.211291 -363.838709) (xy 36.247006 -363.879926) (xy 36.276492 -363.925807)
			(xy 36.299149 -363.975417) (xy 36.314514 -364.027747) (xy 36.322276 -364.081731) (xy 36.322762 -364.109)
			(xy 36.322243 -364.137749) (xy 36.313602 -364.194593) (xy 36.296529 -364.249498) (xy 36.271411 -364.301219)
			(xy 36.238818 -364.348587) (xy 36.199487 -364.390528) (xy 36.17722 -364.40872) (xy 36.165465 -364.418722)
			(xy 36.148007 -364.444152) (xy 36.138934 -364.473633) (xy 36.139073 -364.504479) (xy 36.148412 -364.533877)
			(xy 36.166099 -364.559148) (xy 36.177982 -364.568994) (xy 36.200665 -364.587155) (xy 36.240727 -364.629243)
			(xy 36.273947 -364.676917) (xy 36.299557 -364.729075) (xy 36.316967 -364.784512) (xy 36.325774 -364.841947)
			(xy 36.326318 -364.871) (xy 36.325832 -364.898269) (xy 36.31807 -364.952253) (xy 36.302705 -365.004583)
			(xy 36.280048 -365.054193) (xy 36.250562 -365.100074) (xy 36.214847 -365.141291) (xy 36.17363 -365.177006)
			(xy 36.127749 -365.206492) (xy 36.078139 -365.229149) (xy 36.025809 -365.244514) (xy 35.971825 -365.252276)
			(xy 35.917287 -365.252276) (xy 35.863303 -365.244514) (xy 35.810973 -365.229149) (xy 35.761363 -365.206492)
			(xy 35.715482 -365.177006) (xy 35.674265 -365.141291) (xy 35.63855 -365.100074) (xy 35.609064 -365.054193)
			(xy 35.586407 -365.004583) (xy 35.571042 -364.952253) (xy 35.56328 -364.898269) (xy 35.562794 -364.871)
			(xy 35.563291 -364.84225) (xy 35.571935 -364.785404) (xy 35.58901 -364.730498) (xy 35.614132 -364.678776)
			(xy 35.64673 -364.631409) (xy 35.686066 -364.58947) (xy 35.708336 -364.57128) (xy 35.720085 -364.561274)
			(xy 35.737534 -364.535843) (xy 35.746601 -364.506365) (xy 35.746462 -364.475524) (xy 35.737129 -364.446128)
			(xy 35.719452 -364.420855) (xy 35.707574 -364.411006) (xy 35.684902 -364.392831) (xy 35.644838 -364.350747)
			(xy 35.611615 -364.303077) (xy 35.586001 -364.250922) (xy 35.56859 -364.195487) (xy 35.559782 -364.138053)
			(xy 35.559238 -364.109) (xy 35.204238 -364.109) (xy 35.188027 -364.137643) (xy 35.142494 -364.201692)
			(xy 35.090616 -364.260719) (xy 35.032945 -364.314099) (xy 34.97009 -364.361266) (xy 34.902718 -364.401721)
			(xy 34.831545 -364.435034) (xy 34.757323 -364.460852) (xy 34.680839 -364.478902) (xy 34.602906 -364.488992)
			(xy 34.524347 -364.491015) (xy 34.445998 -364.484951) (xy 34.368687 -364.470862) (xy 34.293234 -364.448899)
			(xy 34.220439 -364.419294) (xy 34.151075 -364.382361) (xy 34.085875 -364.338492) (xy 34.025532 -364.288152)
			(xy 33.970685 -364.231873) (xy 33.921915 -364.170254) (xy 33.879739 -364.103946) (xy 33.844604 -364.033654)
			(xy 33.816883 -363.960121) (xy 33.79687 -363.884128) (xy 33.784777 -363.80648) (xy 33.780732 -363.728)
			(xy 33.121854 -363.728) (xy 33.121854 -365.883698) (xy 34.67303 -365.883698) (xy 34.677103 -365.828039)
			(xy 34.689238 -365.773566) (xy 34.709174 -365.72144) (xy 34.736488 -365.672772) (xy 34.770596 -365.6286)
			(xy 34.810773 -365.589865) (xy 34.856161 -365.557393) (xy 34.905793 -365.531875) (xy 34.958613 -365.513856)
			(xy 35.013492 -365.503719) (xy 35.069263 -365.501681) (xy 35.124737 -365.507784) (xy 35.17873 -365.5219)
			(xy 35.230093 -365.543727) (xy 35.277731 -365.5728) (xy 35.320627 -365.608499) (xy 35.357869 -365.650063)
			(xy 35.388663 -365.696607) (xy 35.412351 -365.747138) (xy 35.416221 -365.76) (xy 36.06114 -365.76)
			(xy 36.065213 -365.704341) (xy 36.077348 -365.649868) (xy 36.097284 -365.597742) (xy 36.124598 -365.549074)
			(xy 36.158706 -365.504902) (xy 36.198883 -365.466167) (xy 36.244271 -365.433695) (xy 36.293903 -365.408177)
			(xy 36.346723 -365.390158) (xy 36.401602 -365.380021) (xy 36.457373 -365.377983) (xy 36.512847 -365.384086)
			(xy 36.56684 -365.398202) (xy 36.618203 -365.420029) (xy 36.665841 -365.449102) (xy 36.708737 -365.484801)
			(xy 36.745979 -365.526365) (xy 36.776773 -365.572909) (xy 36.800461 -365.62344) (xy 36.816539 -365.676882)
			(xy 36.824665 -365.732096) (xy 36.825174 -365.76) (xy 36.824665 -365.787904) (xy 36.816539 -365.843118)
			(xy 36.800461 -365.89656) (xy 36.776773 -365.947091) (xy 36.745979 -365.993635) (xy 36.708737 -366.035199)
			(xy 36.665841 -366.070898) (xy 36.618203 -366.099971) (xy 36.56684 -366.121798) (xy 36.512847 -366.135914)
			(xy 36.457373 -366.142017) (xy 36.401602 -366.139979) (xy 36.346723 -366.129842) (xy 36.293903 -366.111823)
			(xy 36.244271 -366.086305) (xy 36.198883 -366.053833) (xy 36.158706 -366.015098) (xy 36.124598 -365.970926)
			(xy 36.097284 -365.922258) (xy 36.077348 -365.870132) (xy 36.065213 -365.815659) (xy 36.06114 -365.76)
			(xy 35.416221 -365.76) (xy 35.428429 -365.80058) (xy 35.436555 -365.855794) (xy 35.437064 -365.883698)
			(xy 35.436555 -365.911602) (xy 35.428429 -365.966816) (xy 35.412351 -366.020258) (xy 35.388663 -366.070789)
			(xy 35.357869 -366.117333) (xy 35.320627 -366.158897) (xy 35.277731 -366.194596) (xy 35.230093 -366.223669)
			(xy 35.17873 -366.245496) (xy 35.124737 -366.259612) (xy 35.069263 -366.265715) (xy 35.013492 -366.263677)
			(xy 34.958613 -366.25354) (xy 34.905793 -366.235521) (xy 34.856161 -366.210003) (xy 34.810773 -366.177531)
			(xy 34.770596 -366.138796) (xy 34.736488 -366.094624) (xy 34.709174 -366.045956) (xy 34.689238 -365.99383)
			(xy 34.677103 -365.939357) (xy 34.67303 -365.883698) (xy 33.121854 -365.883698) (xy 33.121854 -366.718596)
			(xy 33.122278 -366.728665) (xy 33.129997 -366.747266) (xy 33.13684 -366.754664) (xy 33.510474 -367.128298)
			(xy 33.517877 -367.135133) (xy 33.536475 -367.142841) (xy 33.546542 -367.143284) (xy 34.659824 -367.143284)
		)
		(stroke
			(width 0)
			(type solid)
		)
		(fill yes)
		(layer "In11.Cu")
		(net "PVDDCR_CPU1_P1_VCCS")
	)
	(gr_poly
		(pts
			(xy 210.600798 -148.58238) (xy 210.610322 -148.581986) (xy 210.628057 -148.575033) (xy 210.64203 -148.562087)
			(xy 210.646518 -148.553678) (xy 210.692746 -148.45792) (xy 210.689698 -148.429218) (xy 210.6803 -148.417534)
			(xy 210.659508 -148.390449) (xy 210.624595 -148.331769) (xy 210.597843 -148.268946) (xy 210.579732 -148.203111)
			(xy 210.570587 -148.135445) (xy 210.570064 -148.101304) (xy 210.570566 -148.069343) (xy 210.578577 -148.005925)
			(xy 210.594474 -147.944011) (xy 210.618006 -147.884578) (xy 210.6488 -147.828563) (xy 210.686373 -147.776848)
			(xy 210.73013 -147.730251) (xy 210.779383 -147.689506) (xy 210.833354 -147.655255) (xy 210.891193 -147.628038)
			(xy 210.951986 -147.608285) (xy 211.014776 -147.596307) (xy 211.078572 -147.592294) (xy 211.142368 -147.596307)
			(xy 211.205158 -147.608285) (xy 211.265951 -147.628038) (xy 211.32379 -147.655255) (xy 211.377761 -147.689506)
			(xy 211.427014 -147.730251) (xy 211.470771 -147.776848) (xy 211.508344 -147.828563) (xy 211.539138 -147.884578)
			(xy 211.56267 -147.944011) (xy 211.578567 -148.005925) (xy 211.586578 -148.069343) (xy 211.58708 -148.101304)
			(xy 211.586529 -148.135444) (xy 211.577394 -148.203109) (xy 211.55929 -148.268945) (xy 211.532542 -148.331767)
			(xy 211.497631 -148.390447) (xy 211.476844 -148.417534) (xy 211.467446 -148.429218) (xy 211.464398 -148.45792)
			(xy 211.510626 -148.553678) (xy 211.51513 -148.562074) (xy 211.529103 -148.575007) (xy 211.546827 -148.581962)
			(xy 211.556346 -148.58238) (xy 212.866478 -148.58238) (xy 212.876541 -148.581942) (xy 212.895123 -148.574206)
			(xy 212.902546 -148.567394) (xy 214.343234 -147.126706) (xy 214.350089 -147.119311) (xy 214.357836 -147.100712)
			(xy 214.35822 -147.090638) (xy 214.35822 -142.165578) (xy 214.357723 -142.155139) (xy 214.349401 -142.135993)
			(xy 214.334115 -142.121775) (xy 214.324438 -142.117826) (xy 214.21852 -142.080488) (xy 214.187786 -142.089124)
			(xy 214.177626 -142.101824) (xy 214.156881 -142.126762) (xy 214.110093 -142.171693) (xy 214.057972 -142.210309)
			(xy 214.001362 -142.241984) (xy 213.941184 -142.266203) (xy 213.878415 -142.282572) (xy 213.814074 -142.290827)
			(xy 213.78164 -142.291308) (xy 213.750927 -142.290847) (xy 213.689948 -142.283452) (xy 213.630303 -142.268765)
			(xy 213.572863 -142.247) (xy 213.518462 -142.218474) (xy 213.467895 -142.183602) (xy 213.421896 -142.142892)
			(xy 213.381137 -142.096937) (xy 213.34621 -142.046407) (xy 213.317625 -141.992037) (xy 213.295798 -141.93462)
			(xy 213.281047 -141.874992) (xy 213.273586 -141.814021) (xy 213.273132 -141.783308) (xy 213.273132 -141.772386)
			(xy 213.26475 -141.753082) (xy 213.193884 -141.688058) (xy 213.174072 -141.6812) (xy 213.16315 -141.681962)
			(xy 213.121494 -141.68374) (xy 213.089951 -141.683264) (xy 213.027348 -141.67546) (xy 212.966192 -141.659972)
			(xy 212.907422 -141.637038) (xy 212.851939 -141.607012) (xy 212.800597 -141.570352) (xy 212.754183 -141.527624)
			(xy 212.713411 -141.479483) (xy 212.678907 -141.426668) (xy 212.651201 -141.369991) (xy 212.630719 -141.310322)
			(xy 212.617774 -141.248577) (xy 212.612566 -141.185706) (xy 212.615175 -141.122673) (xy 212.62556 -141.060447)
			(xy 212.643563 -140.999984) (xy 212.668907 -140.942211) (xy 212.701202 -140.888017) (xy 212.739952 -140.838235)
			(xy 212.784563 -140.793627) (xy 212.834349 -140.75488) (xy 212.888545 -140.722589) (xy 212.946319 -140.69725)
			(xy 213.006784 -140.679252) (xy 213.069011 -140.668871) (xy 213.132044 -140.666267) (xy 213.194915 -140.671479)
			(xy 213.256658 -140.684429) (xy 213.316326 -140.704916) (xy 213.373001 -140.732626) (xy 213.425813 -140.767134)
			(xy 213.473951 -140.80791) (xy 213.516676 -140.854326) (xy 213.553332 -140.905671) (xy 213.583354 -140.961156)
			(xy 213.606284 -141.019929) (xy 213.621767 -141.081086) (xy 213.629566 -141.143689) (xy 213.630002 -141.175232)
			(xy 213.62924 -141.204442) (xy 213.629163 -141.215757) (xy 213.637606 -141.236717) (xy 213.645496 -141.244828)
			(xy 213.687152 -141.283182) (xy 213.69655 -141.281404) (xy 213.705948 -141.27988) (xy 213.721696 -141.270482)
			(xy 213.775798 -141.202156) (xy 213.781386 -141.18463) (xy 213.780878 -141.174978) (xy 213.779862 -141.143482)
			(xy 213.780353 -141.11129) (xy 213.788472 -141.047421) (xy 213.804591 -140.985088) (xy 213.828452 -140.92529)
			(xy 213.859673 -140.868983) (xy 213.897754 -140.817069) (xy 213.942085 -140.770379) (xy 213.991957 -140.729661)
			(xy 214.046571 -140.695566) (xy 214.105054 -140.66864) (xy 214.166468 -140.649314) (xy 214.229831 -140.637897)
			(xy 214.261954 -140.635736) (xy 214.27186 -140.635228) (xy 214.289386 -140.6271) (xy 214.34425 -140.569188)
			(xy 214.350634 -140.561868) (xy 214.357823 -140.543841) (xy 214.35822 -140.534136) (xy 214.35822 -138.63828)
			(xy 214.357768 -138.62903) (xy 214.351126 -138.611757) (xy 214.338814 -138.597942) (xy 214.330788 -138.593322)
			(xy 214.301948 -138.577833) (xy 214.248141 -138.540545) (xy 214.199562 -138.496662) (xy 214.157014 -138.446909)
			(xy 214.1212 -138.39211) (xy 214.092713 -138.333168) (xy 214.072023 -138.271059) (xy 214.059471 -138.206809)
			(xy 214.055266 -138.14148) (xy 214.059476 -138.076151) (xy 214.072033 -138.011902) (xy 214.092728 -137.949794)
			(xy 214.12122 -137.890855) (xy 214.157038 -137.836058) (xy 214.19959 -137.786309) (xy 214.248173 -137.74243)
			(xy 214.301983 -137.705146) (xy 214.330788 -137.68959) (xy 214.338831 -137.684985) (xy 214.351183 -137.671187)
			(xy 214.3578 -137.653891) (xy 214.35822 -137.644632) (xy 214.35822 -137.05332) (xy 214.358658 -137.043257)
			(xy 214.366395 -137.024675) (xy 214.373206 -137.017252) (xy 214.794338 -136.59612) (xy 214.800532 -136.589377)
			(xy 214.808079 -136.572711) (xy 214.80907 -136.563608) (xy 214.810086 -136.550146) (xy 214.763096 -136.451848)
			(xy 214.757254 -136.44245) (xy 214.754007 -136.438476) (xy 214.746194 -136.431826) (xy 214.74176 -136.429242)
			(xy 214.734394 -136.425432) (xy 214.719154 -136.422384) (xy 214.71128 -136.423146) (xy 214.696979 -136.424686)
			(xy 214.668259 -136.42634) (xy 214.653876 -136.426448) (xy 214.622332 -136.425971) (xy 214.55973 -136.418164)
			(xy 214.498573 -136.402674) (xy 214.439803 -136.379739) (xy 214.384321 -136.349709) (xy 214.332979 -136.313048)
			(xy 214.286566 -136.270318) (xy 214.245795 -136.222175) (xy 214.211293 -136.169358) (xy 214.183588 -136.112679)
			(xy 214.163107 -136.053009) (xy 214.150164 -135.991263) (xy 214.144958 -135.928391) (xy 214.147568 -135.865358)
			(xy 214.157956 -135.803131) (xy 214.175961 -135.742668) (xy 214.201306 -135.684895) (xy 214.233603 -135.630702)
			(xy 214.272355 -135.580919) (xy 214.316967 -135.536313) (xy 214.366755 -135.497567) (xy 214.420952 -135.465277)
			(xy 214.478728 -135.439939) (xy 214.539194 -135.421941) (xy 214.601422 -135.411562) (xy 214.664455 -135.408959)
			(xy 214.727327 -135.414173) (xy 214.789071 -135.427124) (xy 214.848738 -135.447612) (xy 214.905414 -135.475324)
			(xy 214.958226 -135.509834) (xy 215.006364 -135.550611) (xy 215.049089 -135.597029) (xy 215.085743 -135.648375)
			(xy 215.115765 -135.703861) (xy 215.138694 -135.762634) (xy 215.154176 -135.823793) (xy 215.161975 -135.886396)
			(xy 215.162384 -135.91794) (xy 215.162268 -135.932323) (xy 215.160617 -135.961042) (xy 215.159082 -135.975344)
			(xy 215.15832 -135.983218) (xy 215.161114 -135.998458) (xy 215.165178 -136.00557) (xy 215.167757 -136.010062)
			(xy 215.174414 -136.017994) (xy 215.178386 -136.021318) (xy 215.187784 -136.02716) (xy 215.27389 -136.068308)
			(xy 215.279946 -136.070961) (xy 215.292937 -136.073399) (xy 215.299544 -136.073134) (xy 215.308653 -136.07216)
			(xy 215.325333 -136.064622) (xy 215.332056 -136.058402) (xy 215.468454 -135.922004) (xy 215.475855 -135.915166)
			(xy 215.494453 -135.90745) (xy 215.504522 -135.907018) (xy 234.432602 -135.907018) (xy 234.440984 -135.906256)
			(xy 234.448591 -135.904746) (xy 234.462433 -135.897768) (xy 234.468162 -135.89254) (xy 235.594144 -134.766558)
			(xy 235.60099 -134.75916) (xy 235.608718 -134.740561) (xy 235.60913 -134.73049) (xy 235.60913 -127.392176)
			(xy 235.60151 -127.37338) (xy 235.594144 -127.366268) (xy 235.280454 -127.052578) (xy 235.273057 -127.04573)
			(xy 235.254458 -127.038) (xy 235.244386 -127.037592) (xy 222.73387 -127.037592) (xy 222.723802 -127.03802)
			(xy 222.705205 -127.045741) (xy 222.697802 -127.052578) (xy 221.421749 -128.328631) (xy 228.940354 -128.328631)
			(xy 228.940354 -128.264709) (xy 228.948365 -128.201291) (xy 228.964262 -128.139377) (xy 228.987794 -128.079944)
			(xy 229.018588 -128.023929) (xy 229.056161 -127.972214) (xy 229.099918 -127.925617) (xy 229.149171 -127.884872)
			(xy 229.203142 -127.850621) (xy 229.260981 -127.823404) (xy 229.321774 -127.803651) (xy 229.384564 -127.791673)
			(xy 229.44836 -127.78766) (xy 229.512156 -127.791673) (xy 229.574946 -127.803651) (xy 229.635739 -127.823404)
			(xy 229.693578 -127.850621) (xy 229.747549 -127.884872) (xy 229.796802 -127.925617) (xy 229.840559 -127.972214)
			(xy 229.878132 -128.023929) (xy 229.908926 -128.079944) (xy 229.932458 -128.139377) (xy 229.948355 -128.201291)
			(xy 229.956366 -128.264709) (xy 229.956868 -128.29667) (xy 229.956366 -128.328631) (xy 229.948355 -128.392049)
			(xy 229.932458 -128.453963) (xy 229.908926 -128.513396) (xy 229.878132 -128.569411) (xy 229.840559 -128.621126)
			(xy 229.796802 -128.667723) (xy 229.747549 -128.708468) (xy 229.693578 -128.742719) (xy 229.635739 -128.769936)
			(xy 229.574946 -128.789689) (xy 229.512156 -128.801667) (xy 229.44836 -128.805681) (xy 229.384564 -128.801667)
			(xy 229.321774 -128.789689) (xy 229.260981 -128.769936) (xy 229.203142 -128.742719) (xy 229.149171 -128.708468)
			(xy 229.099918 -128.667723) (xy 229.056161 -128.621126) (xy 229.018588 -128.569411) (xy 228.987794 -128.513396)
			(xy 228.964262 -128.453963) (xy 228.948365 -128.392049) (xy 228.940354 -128.328631) (xy 221.421749 -128.328631)
			(xy 219.567506 -130.182874) (xy 219.560109 -130.189724) (xy 219.541511 -130.197465) (xy 219.531438 -130.19786)
			(xy 213.38921 -130.19786) (xy 213.379397 -130.198304) (xy 213.361198 -130.205651) (xy 213.347075 -130.21928)
			(xy 213.342728 -130.228086) (xy 213.29904 -130.327146) (xy 213.303866 -130.35661) (xy 213.31428 -130.36804)
			(xy 213.335101 -130.391514) (xy 213.371406 -130.442692) (xy 213.401135 -130.49795) (xy 213.423836 -130.556448)
			(xy 213.439162 -130.617295) (xy 213.446882 -130.679566) (xy 213.447376 -130.71094) (xy 213.446874 -130.742901)
			(xy 213.438863 -130.806319) (xy 213.422966 -130.868233) (xy 213.399434 -130.927666) (xy 213.36864 -130.983681)
			(xy 213.331067 -131.035396) (xy 213.28731 -131.081993) (xy 213.2824 -131.086055) (xy 218.099126 -131.086055)
			(xy 218.099126 -131.022133) (xy 218.107137 -130.958715) (xy 218.123034 -130.896801) (xy 218.146566 -130.837368)
			(xy 218.17736 -130.781353) (xy 218.214933 -130.729638) (xy 218.25869 -130.683041) (xy 218.307943 -130.642296)
			(xy 218.361914 -130.608045) (xy 218.419753 -130.580828) (xy 218.480546 -130.561075) (xy 218.543336 -130.549097)
			(xy 218.607132 -130.545084) (xy 218.670928 -130.549097) (xy 218.733718 -130.561075) (xy 218.794511 -130.580828)
			(xy 218.85235 -130.608045) (xy 218.906321 -130.642296) (xy 218.955574 -130.683041) (xy 218.999331 -130.729638)
			(xy 219.036904 -130.781353) (xy 219.067698 -130.837368) (xy 219.09123 -130.896801) (xy 219.107127 -130.958715)
			(xy 219.115138 -131.022133) (xy 219.11564 -131.054094) (xy 219.115138 -131.086055) (xy 219.107127 -131.149473)
			(xy 219.09123 -131.211387) (xy 219.067698 -131.27082) (xy 219.036904 -131.326835) (xy 218.999331 -131.37855)
			(xy 218.955574 -131.425147) (xy 218.906321 -131.465892) (xy 218.85235 -131.500143) (xy 218.794511 -131.52736)
			(xy 218.733718 -131.547113) (xy 218.670928 -131.559091) (xy 218.607132 -131.563105) (xy 218.543336 -131.559091)
			(xy 218.480546 -131.547113) (xy 218.419753 -131.52736) (xy 218.361914 -131.500143) (xy 218.307943 -131.465892)
			(xy 218.25869 -131.425147) (xy 218.214933 -131.37855) (xy 218.17736 -131.326835) (xy 218.146566 -131.27082)
			(xy 218.123034 -131.211387) (xy 218.107137 -131.149473) (xy 218.099126 -131.086055) (xy 213.2824 -131.086055)
			(xy 213.238057 -131.122738) (xy 213.184086 -131.156989) (xy 213.126247 -131.184206) (xy 213.065454 -131.203959)
			(xy 213.002664 -131.215937) (xy 212.938868 -131.219951) (xy 212.875072 -131.215937) (xy 212.812282 -131.203959)
			(xy 212.751489 -131.184206) (xy 212.69365 -131.156989) (xy 212.639679 -131.122738) (xy 212.590426 -131.081993)
			(xy 212.546669 -131.035396) (xy 212.509096 -130.983681) (xy 212.478302 -130.927666) (xy 212.45477 -130.868233)
			(xy 212.438873 -130.806319) (xy 212.430862 -130.742901) (xy 212.43036 -130.71094) (xy 212.430823 -130.679564)
			(xy 212.438544 -130.61729) (xy 212.453872 -130.55644) (xy 212.476575 -130.49794) (xy 212.506308 -130.442679)
			(xy 212.542617 -130.3915) (xy 212.563456 -130.36804) (xy 212.57387 -130.35661) (xy 212.578696 -130.327146)
			(xy 212.535008 -130.228086) (xy 212.530629 -130.219295) (xy 212.516532 -130.205646) (xy 212.498338 -130.198297)
			(xy 212.488526 -130.19786) (xy 212.217762 -130.19786) (xy 212.207696 -130.198292) (xy 212.189107 -130.206022)
			(xy 212.181694 -130.212846) (xy 212.025992 -130.368548) (xy 212.021928 -130.403854) (xy 212.031326 -130.41884)
			(xy 212.052824 -130.454181) (xy 212.089914 -130.528126) (xy 212.119977 -130.605196) (xy 212.142753 -130.684724)
			(xy 212.158046 -130.766024) (xy 212.165723 -130.848393) (xy 212.1662 -130.889756) (xy 212.165742 -130.93086)
			(xy 212.15816 -131.012719) (xy 212.143058 -131.093528) (xy 212.120564 -131.172599) (xy 212.090869 -131.249258)
			(xy 212.054228 -131.322849) (xy 212.010953 -131.392746) (xy 211.961413 -131.458351) (xy 211.90603 -131.519105)
			(xy 211.845278 -131.57449) (xy 211.779675 -131.624032) (xy 211.709781 -131.66731) (xy 211.636191 -131.703955)
			(xy 211.559534 -131.733652) (xy 211.480463 -131.75615) (xy 211.399654 -131.771255) (xy 211.317796 -131.77884)
			(xy 211.276692 -131.779264) (xy 211.235329 -131.778791) (xy 211.152961 -131.77111) (xy 211.071662 -131.755815)
			(xy 210.992134 -131.733037) (xy 210.915064 -131.702974) (xy 210.841118 -131.665885) (xy 210.805776 -131.64439)
			(xy 210.79577 -131.63888) (xy 210.773098 -131.63636) (xy 210.75157 -131.643905) (xy 210.743038 -131.651502)
			(xy 210.355477 -132.039063) (xy 216.874592 -132.039063) (xy 216.874592 -131.975141) (xy 216.882603 -131.911723)
			(xy 216.8985 -131.849809) (xy 216.922032 -131.790376) (xy 216.952826 -131.734361) (xy 216.990399 -131.682646)
			(xy 217.034156 -131.636049) (xy 217.083409 -131.595304) (xy 217.13738 -131.561053) (xy 217.195219 -131.533836)
			(xy 217.256012 -131.514083) (xy 217.318802 -131.502105) (xy 217.382598 -131.498092) (xy 217.446394 -131.502105)
			(xy 217.509184 -131.514083) (xy 217.569977 -131.533836) (xy 217.627816 -131.561053) (xy 217.681787 -131.595304)
			(xy 217.73104 -131.636049) (xy 217.774797 -131.682646) (xy 217.81237 -131.734361) (xy 217.843164 -131.790376)
			(xy 217.866696 -131.849809) (xy 217.882593 -131.911723) (xy 217.890604 -131.975141) (xy 217.891106 -132.007102)
			(xy 217.890604 -132.039063) (xy 217.882593 -132.102481) (xy 217.866696 -132.164395) (xy 217.843164 -132.223828)
			(xy 217.81237 -132.279843) (xy 217.774797 -132.331558) (xy 217.73104 -132.378155) (xy 217.681787 -132.4189)
			(xy 217.627816 -132.453151) (xy 217.569977 -132.480368) (xy 217.509184 -132.500121) (xy 217.446394 -132.512099)
			(xy 217.382598 -132.516113) (xy 217.318802 -132.512099) (xy 217.256012 -132.500121) (xy 217.195219 -132.480368)
			(xy 217.13738 -132.453151) (xy 217.083409 -132.4189) (xy 217.034156 -132.378155) (xy 216.990399 -132.331558)
			(xy 216.952826 -132.279843) (xy 216.922032 -132.223828) (xy 216.8985 -132.164395) (xy 216.882603 -132.102481)
			(xy 216.874592 -132.039063) (xy 210.355477 -132.039063) (xy 210.190334 -132.204206) (xy 210.183485 -132.211603)
			(xy 210.175747 -132.230202) (xy 210.175348 -132.240274) (xy 210.175348 -134.366254) (xy 210.174914 -134.376319)
			(xy 210.16718 -134.394904) (xy 210.160362 -134.402322) (xy 210.160362 -134.655052) (xy 214.279986 -134.655052)
			(xy 214.284057 -134.59943) (xy 214.296183 -134.544993) (xy 214.316106 -134.492902) (xy 214.343402 -134.444267)
			(xy 214.377488 -134.400124) (xy 214.417637 -134.361415) (xy 214.462995 -134.328964) (xy 214.512595 -134.303463)
			(xy 214.565379 -134.285456) (xy 214.620222 -134.275326) (xy 214.675956 -134.273289) (xy 214.731393 -134.279389)
			(xy 214.78535 -134.293495) (xy 214.836679 -134.315307) (xy 214.884285 -134.344361) (xy 214.927153 -134.380036)
			(xy 214.96437 -134.421573) (xy 214.995143 -134.468086) (xy 215.018815 -134.518583) (xy 215.034883 -134.57199)
			(xy 215.043003 -134.627166) (xy 215.043512 -134.655052) (xy 215.295986 -134.655052) (xy 215.300057 -134.59943)
			(xy 215.312183 -134.544993) (xy 215.332106 -134.492902) (xy 215.359402 -134.444267) (xy 215.393488 -134.400124)
			(xy 215.433637 -134.361415) (xy 215.478995 -134.328964) (xy 215.528595 -134.303463) (xy 215.581379 -134.285456)
			(xy 215.636222 -134.275326) (xy 215.691956 -134.273289) (xy 215.747393 -134.279389) (xy 215.80135 -134.293495)
			(xy 215.852679 -134.315307) (xy 215.900285 -134.344361) (xy 215.943153 -134.380036) (xy 215.98037 -134.421573)
			(xy 216.011143 -134.468086) (xy 216.034815 -134.518583) (xy 216.050883 -134.57199) (xy 216.059003 -134.627166)
			(xy 216.059512 -134.655052) (xy 216.059003 -134.682938) (xy 216.050883 -134.738114) (xy 216.034815 -134.791521)
			(xy 216.011143 -134.842018) (xy 215.98037 -134.888531) (xy 215.943153 -134.930068) (xy 215.900285 -134.965743)
			(xy 215.852679 -134.994797) (xy 215.80135 -135.016609) (xy 215.747393 -135.030715) (xy 215.691956 -135.036815)
			(xy 215.636222 -135.034778) (xy 215.581379 -135.024648) (xy 215.528595 -135.006641) (xy 215.478995 -134.98114)
			(xy 215.433637 -134.948689) (xy 215.393488 -134.90998) (xy 215.359402 -134.865837) (xy 215.332106 -134.817202)
			(xy 215.312183 -134.765111) (xy 215.300057 -134.710674) (xy 215.295986 -134.655052) (xy 215.043512 -134.655052)
			(xy 215.043003 -134.682938) (xy 215.034883 -134.738114) (xy 215.018815 -134.791521) (xy 214.995143 -134.842018)
			(xy 214.96437 -134.888531) (xy 214.927153 -134.930068) (xy 214.884285 -134.965743) (xy 214.836679 -134.994797)
			(xy 214.78535 -135.016609) (xy 214.731393 -135.030715) (xy 214.675956 -135.036815) (xy 214.620222 -135.034778)
			(xy 214.565379 -135.024648) (xy 214.512595 -135.006641) (xy 214.462995 -134.98114) (xy 214.417637 -134.948689)
			(xy 214.377488 -134.90998) (xy 214.343402 -134.865837) (xy 214.316106 -134.817202) (xy 214.296183 -134.765111)
			(xy 214.284057 -134.710674) (xy 214.279986 -134.655052) (xy 210.160362 -134.655052) (xy 210.160362 -135.933434)
			(xy 210.159932 -135.943501) (xy 210.152205 -135.962093) (xy 210.145376 -135.969502) (xy 208.03743 -138.077448)
			(xy 209.56219 -138.077448) (xy 209.566261 -138.021826) (xy 209.578387 -137.967389) (xy 209.59831 -137.915298)
			(xy 209.625606 -137.866663) (xy 209.659692 -137.82252) (xy 209.699841 -137.783811) (xy 209.745199 -137.75136)
			(xy 209.794799 -137.725859) (xy 209.847583 -137.707852) (xy 209.902426 -137.697722) (xy 209.95816 -137.695685)
			(xy 210.013597 -137.701785) (xy 210.067554 -137.715891) (xy 210.118883 -137.737703) (xy 210.166489 -137.766757)
			(xy 210.209357 -137.802432) (xy 210.246574 -137.843969) (xy 210.277347 -137.890482) (xy 210.301019 -137.940979)
			(xy 210.317087 -137.994386) (xy 210.325207 -138.049562) (xy 210.325716 -138.077448) (xy 210.325207 -138.105334)
			(xy 210.317087 -138.16051) (xy 210.301019 -138.213917) (xy 210.277347 -138.264414) (xy 210.246574 -138.310927)
			(xy 210.209357 -138.352464) (xy 210.166489 -138.388139) (xy 210.118883 -138.417193) (xy 210.067554 -138.439005)
			(xy 210.013597 -138.453111) (xy 209.95816 -138.459211) (xy 209.902426 -138.457174) (xy 209.847583 -138.447044)
			(xy 209.794799 -138.429037) (xy 209.745199 -138.403536) (xy 209.699841 -138.371085) (xy 209.659692 -138.332376)
			(xy 209.625606 -138.288233) (xy 209.59831 -138.239598) (xy 209.578387 -138.187507) (xy 209.566261 -138.13307)
			(xy 209.56219 -138.077448) (xy 208.03743 -138.077448) (xy 206.193678 -139.9212) (xy 207.224602 -139.9212)
			(xy 207.228617 -139.857402) (xy 207.240595 -139.79461) (xy 207.26035 -139.733815) (xy 207.287569 -139.675976)
			(xy 207.321823 -139.622004) (xy 207.362572 -139.572751) (xy 207.409173 -139.528994) (xy 207.46089 -139.491423)
			(xy 207.516909 -139.460631) (xy 207.576346 -139.437103) (xy 207.638263 -139.421211) (xy 207.701684 -139.413204)
			(xy 207.733646 -139.412726) (xy 207.767822 -139.413247) (xy 207.835557 -139.42241) (xy 207.901454 -139.440563)
			(xy 207.964325 -139.46738) (xy 208.023037 -139.502377) (xy 208.05013 -139.523216) (xy 208.059547 -139.529938)
			(xy 208.082144 -139.534824) (xy 208.104612 -139.529378) (xy 208.113884 -139.522454) (xy 208.141342 -139.500606)
			(xy 208.201109 -139.463841) (xy 208.265365 -139.435648) (xy 208.332888 -139.416562) (xy 208.402395 -139.406947)
			(xy 208.43748 -139.406376) (xy 208.4702 -139.406847) (xy 208.535101 -139.415228) (xy 208.598391 -139.431866)
			(xy 208.659023 -139.456487) (xy 208.715995 -139.488683) (xy 208.768365 -139.527923) (xy 208.815268 -139.573558)
			(xy 208.855928 -139.624833) (xy 208.889673 -139.680901) (xy 208.915946 -139.740835) (xy 208.934313 -139.803645)
			(xy 208.939892 -139.83589) (xy 208.941924 -139.848844) (xy 208.957926 -139.869672) (xy 209.061304 -139.913868)
			(xy 209.087466 -139.911074) (xy 209.098388 -139.903454) (xy 209.124047 -139.88616) (xy 209.178745 -139.857228)
			(xy 209.236548 -139.835146) (xy 209.296604 -139.820239) (xy 209.358025 -139.812728) (xy 209.388964 -139.812268)
			(xy 209.419035 -139.812738) (xy 209.478755 -139.819865) (xy 209.50809 -139.826492) (xy 209.517742 -139.828778)
			(xy 209.536792 -139.825984) (xy 209.61477 -139.780518) (xy 209.626708 -139.765278) (xy 209.629502 -139.755626)
			(xy 209.639076 -139.724205) (xy 209.665162 -139.663923) (xy 209.698795 -139.607501) (xy 209.739413 -139.555881)
			(xy 209.78634 -139.50992) (xy 209.838795 -139.470385) (xy 209.895904 -139.437935) (xy 209.956716 -139.413108)
			(xy 210.020219 -139.396319) (xy 210.085356 -139.387848) (xy 210.118198 -139.387326) (xy 210.148931 -139.38774)
			(xy 210.20995 -139.395149) (xy 210.26963 -139.409859) (xy 210.327103 -139.431656) (xy 210.381528 -139.460222)
			(xy 210.432114 -139.49514) (xy 210.478121 -139.535902) (xy 210.518879 -139.581912) (xy 210.553794 -139.632499)
			(xy 210.582357 -139.686927) (xy 210.60415 -139.7444) (xy 210.618857 -139.804082) (xy 210.626262 -139.865101)
			(xy 210.626706 -139.895834) (xy 210.626104 -139.929528) (xy 210.617174 -139.996322) (xy 210.5995 -140.061351)
			(xy 210.573393 -140.123476) (xy 210.53931 -140.18161) (xy 210.51901 -140.208508) (xy 210.512406 -140.217144)
			(xy 210.507326 -140.237718) (xy 210.523582 -140.332968) (xy 210.535266 -140.350748) (xy 210.54441 -140.35659)
			(xy 210.570859 -140.374198) (xy 210.619592 -140.414969) (xy 210.662869 -140.461491) (xy 210.700016 -140.513041)
			(xy 210.730454 -140.568816) (xy 210.75371 -140.627946) (xy 210.769421 -140.689513) (xy 210.777342 -140.752556)
			(xy 210.777836 -140.784326) (xy 210.777368 -140.815056) (xy 210.769957 -140.876069) (xy 210.755247 -140.935744)
			(xy 210.733451 -140.99321) (xy 210.704888 -141.04763) (xy 210.669973 -141.098211) (xy 210.629217 -141.144216)
			(xy 210.583213 -141.184972) (xy 210.532632 -141.219887) (xy 210.478212 -141.24845) (xy 210.420745 -141.270246)
			(xy 210.361071 -141.284957) (xy 210.300058 -141.292368) (xy 210.269328 -141.292834) (xy 210.236085 -141.292246)
			(xy 210.170167 -141.28356) (xy 210.105943 -141.266359) (xy 210.044509 -141.240935) (xy 209.986911 -141.207722)
			(xy 209.934132 -141.167288) (xy 209.887072 -141.12032) (xy 209.846534 -141.067621) (xy 209.813208 -141.010089)
			(xy 209.787664 -140.948704) (xy 209.770336 -140.884514) (xy 209.765392 -140.851636) (xy 209.763614 -140.83919)
			(xy 209.749644 -140.819124) (xy 209.65414 -140.769086) (xy 209.629756 -140.768832) (xy 209.61858 -140.77442)
			(xy 209.591809 -140.787493) (xy 209.53587 -140.808003) (xy 209.477922 -140.821848) (xy 209.418754 -140.82884)
			(xy 209.388964 -140.829284) (xy 209.356244 -140.828806) (xy 209.291341 -140.82043) (xy 209.22805 -140.803795)
			(xy 209.167417 -140.779177) (xy 209.110443 -140.746982) (xy 209.058072 -140.707743) (xy 209.011168 -140.662108)
			(xy 208.970508 -140.610832) (xy 208.936764 -140.554763) (xy 208.910493 -140.494827) (xy 208.892129 -140.432015)
			(xy 208.886552 -140.39977) (xy 208.88452 -140.386816) (xy 208.868518 -140.365988) (xy 208.76514 -140.321792)
			(xy 208.738978 -140.324586) (xy 208.728056 -140.332206) (xy 208.702409 -140.349519) (xy 208.647708 -140.378448)
			(xy 208.589902 -140.400527) (xy 208.529843 -140.41543) (xy 208.46842 -140.422935) (xy 208.43748 -140.423392)
			(xy 208.403305 -140.422852) (xy 208.335571 -140.413694) (xy 208.269674 -140.395545) (xy 208.206803 -140.368732)
			(xy 208.148089 -140.333739) (xy 208.120996 -140.312902) (xy 208.111565 -140.306202) (xy 208.088977 -140.301307)
			(xy 208.066514 -140.306744) (xy 208.057242 -140.313664) (xy 208.029777 -140.335503) (xy 207.970012 -140.372269)
			(xy 207.905758 -140.400463) (xy 207.838236 -140.419551) (xy 207.76873 -140.429169) (xy 207.733646 -140.429742)
			(xy 207.701684 -140.429196) (xy 207.638263 -140.421189) (xy 207.576346 -140.405297) (xy 207.516909 -140.381769)
			(xy 207.46089 -140.350977) (xy 207.409173 -140.313406) (xy 207.362572 -140.269649) (xy 207.321823 -140.220396)
			(xy 207.287569 -140.166424) (xy 207.26035 -140.108585) (xy 207.240595 -140.04779) (xy 207.228617 -139.984998)
			(xy 207.224602 -139.9212) (xy 206.193678 -139.9212) (xy 205.466188 -140.64869) (xy 205.458822 -140.655802)
			(xy 205.451202 -140.674598) (xy 205.451202 -141.784789) (xy 206.3722 -141.784789) (xy 206.3722 -141.720867)
			(xy 206.380211 -141.657449) (xy 206.396108 -141.595535) (xy 206.41964 -141.536102) (xy 206.450434 -141.480087)
			(xy 206.488007 -141.428372) (xy 206.531764 -141.381775) (xy 206.581017 -141.34103) (xy 206.634988 -141.306779)
			(xy 206.692827 -141.279562) (xy 206.75362 -141.259809) (xy 206.81641 -141.247831) (xy 206.880206 -141.243818)
			(xy 206.944002 -141.247831) (xy 207.006792 -141.259809) (xy 207.067585 -141.279562) (xy 207.125424 -141.306779)
			(xy 207.179395 -141.34103) (xy 207.228648 -141.381775) (xy 207.272405 -141.428372) (xy 207.309978 -141.480087)
			(xy 207.340772 -141.536102) (xy 207.364304 -141.595535) (xy 207.380201 -141.657449) (xy 207.388212 -141.720867)
			(xy 207.388714 -141.752828) (xy 207.388212 -141.784789) (xy 207.380201 -141.848207) (xy 207.364304 -141.910121)
			(xy 207.340772 -141.969554) (xy 207.309978 -142.025569) (xy 207.272405 -142.077284) (xy 207.228648 -142.123881)
			(xy 207.179395 -142.164626) (xy 207.125424 -142.198877) (xy 207.067585 -142.226094) (xy 207.006792 -142.245847)
			(xy 206.944002 -142.257825) (xy 206.880206 -142.261839) (xy 206.81641 -142.257825) (xy 206.75362 -142.245847)
			(xy 206.692827 -142.226094) (xy 206.634988 -142.198877) (xy 206.581017 -142.164626) (xy 206.531764 -142.123881)
			(xy 206.488007 -142.077284) (xy 206.450434 -142.025569) (xy 206.41964 -141.969554) (xy 206.396108 -141.910121)
			(xy 206.380211 -141.848207) (xy 206.3722 -141.784789) (xy 205.451202 -141.784789) (xy 205.451202 -142.490952)
			(xy 208.85734 -142.490952) (xy 208.861411 -142.43533) (xy 208.873537 -142.380893) (xy 208.89346 -142.328802)
			(xy 208.920756 -142.280167) (xy 208.954842 -142.236024) (xy 208.994991 -142.197315) (xy 209.040349 -142.164864)
			(xy 209.089949 -142.139363) (xy 209.142733 -142.121356) (xy 209.197576 -142.111226) (xy 209.25331 -142.109189)
			(xy 209.308747 -142.115289) (xy 209.362704 -142.129395) (xy 209.414033 -142.151207) (xy 209.461639 -142.180261)
			(xy 209.504507 -142.215936) (xy 209.541724 -142.257473) (xy 209.572497 -142.303986) (xy 209.596169 -142.354483)
			(xy 209.612237 -142.40789) (xy 209.620357 -142.463066) (xy 209.620866 -142.490952) (xy 209.620357 -142.518838)
			(xy 209.612237 -142.574014) (xy 209.596169 -142.627421) (xy 209.572497 -142.677918) (xy 209.541724 -142.724431)
			(xy 209.504507 -142.765968) (xy 209.461639 -142.801643) (xy 209.414033 -142.830697) (xy 209.362704 -142.852509)
			(xy 209.308747 -142.866615) (xy 209.25331 -142.872715) (xy 209.197576 -142.870678) (xy 209.142733 -142.860548)
			(xy 209.089949 -142.842541) (xy 209.040349 -142.81704) (xy 208.994991 -142.784589) (xy 208.954842 -142.74588)
			(xy 208.920756 -142.701737) (xy 208.89346 -142.653102) (xy 208.873537 -142.601011) (xy 208.861411 -142.546574)
			(xy 208.85734 -142.490952) (xy 205.451202 -142.490952) (xy 205.451202 -147.438548) (xy 208.711796 -147.438548)
			(xy 208.711796 -147.353852) (xy 208.719847 -147.269538) (xy 208.735876 -147.186372) (xy 208.759737 -147.105105)
			(xy 208.791216 -147.026475) (xy 208.830027 -146.951194) (xy 208.875817 -146.879942) (xy 208.928173 -146.813366)
			(xy 208.986621 -146.752068) (xy 209.050631 -146.696603) (xy 209.119623 -146.647474) (xy 209.192973 -146.605125)
			(xy 209.270016 -146.569941) (xy 209.350055 -146.542239) (xy 209.432364 -146.522271) (xy 209.516199 -146.510218)
			(xy 209.6008 -146.506188) (xy 209.685401 -146.510218) (xy 209.769236 -146.522271) (xy 209.851545 -146.542239)
			(xy 209.931584 -146.569941) (xy 210.008627 -146.605125) (xy 210.081977 -146.647474) (xy 210.150969 -146.696603)
			(xy 210.214979 -146.752068) (xy 210.273427 -146.813366) (xy 210.325783 -146.879942) (xy 210.371573 -146.951194)
			(xy 210.410384 -147.026475) (xy 210.441863 -147.105105) (xy 210.465724 -147.186372) (xy 210.481753 -147.269538)
			(xy 210.489804 -147.353852) (xy 210.489951 -147.366185) (xy 211.71382 -147.366185) (xy 211.71382 -147.302263)
			(xy 211.721831 -147.238845) (xy 211.737728 -147.176931) (xy 211.76126 -147.117498) (xy 211.792054 -147.061483)
			(xy 211.829627 -147.009768) (xy 211.873384 -146.963171) (xy 211.922637 -146.922426) (xy 211.976608 -146.888175)
			(xy 212.034447 -146.860958) (xy 212.09524 -146.841205) (xy 212.15803 -146.829227) (xy 212.221826 -146.825214)
			(xy 212.285622 -146.829227) (xy 212.348412 -146.841205) (xy 212.409205 -146.860958) (xy 212.467044 -146.888175)
			(xy 212.521015 -146.922426) (xy 212.570268 -146.963171) (xy 212.614025 -147.009768) (xy 212.651598 -147.061483)
			(xy 212.682392 -147.117498) (xy 212.705924 -147.176931) (xy 212.721821 -147.238845) (xy 212.729832 -147.302263)
			(xy 212.730334 -147.334224) (xy 212.729832 -147.366185) (xy 212.721821 -147.429603) (xy 212.705924 -147.491517)
			(xy 212.682392 -147.55095) (xy 212.651598 -147.606965) (xy 212.614025 -147.65868) (xy 212.570268 -147.705277)
			(xy 212.521015 -147.746022) (xy 212.467044 -147.780273) (xy 212.409205 -147.80749) (xy 212.348412 -147.827243)
			(xy 212.285622 -147.839221) (xy 212.221826 -147.843235) (xy 212.15803 -147.839221) (xy 212.09524 -147.827243)
			(xy 212.034447 -147.80749) (xy 211.976608 -147.780273) (xy 211.922637 -147.746022) (xy 211.873384 -147.705277)
			(xy 211.829627 -147.65868) (xy 211.792054 -147.606965) (xy 211.76126 -147.55095) (xy 211.737728 -147.491517)
			(xy 211.721831 -147.429603) (xy 211.71382 -147.366185) (xy 210.489951 -147.366185) (xy 210.490308 -147.3962)
			(xy 210.489804 -147.438548) (xy 210.481753 -147.522862) (xy 210.465724 -147.606028) (xy 210.441863 -147.687295)
			(xy 210.410384 -147.765925) (xy 210.371573 -147.841206) (xy 210.325783 -147.912458) (xy 210.273427 -147.979034)
			(xy 210.214979 -148.040332) (xy 210.150969 -148.095797) (xy 210.081977 -148.144926) (xy 210.008627 -148.187275)
			(xy 209.931584 -148.222459) (xy 209.851545 -148.250161) (xy 209.769236 -148.270129) (xy 209.685401 -148.282182)
			(xy 209.6008 -148.286213) (xy 209.516199 -148.282182) (xy 209.432364 -148.270129) (xy 209.350055 -148.250161)
			(xy 209.270016 -148.222459) (xy 209.192973 -148.187275) (xy 209.119623 -148.144926) (xy 209.050631 -148.095797)
			(xy 208.986621 -148.040332) (xy 208.928173 -147.979034) (xy 208.875817 -147.912458) (xy 208.830027 -147.841206)
			(xy 208.791216 -147.765925) (xy 208.759737 -147.687295) (xy 208.735876 -147.606028) (xy 208.719847 -147.522862)
			(xy 208.711796 -147.438548) (xy 205.451202 -147.438548) (xy 205.451202 -147.74418) (xy 205.451673 -147.754052)
			(xy 205.459133 -147.772335) (xy 205.46568 -147.77974) (xy 205.465934 -147.779994) (xy 206.085694 -148.399754)
			(xy 206.086202 -148.400262) (xy 206.093586 -148.406836) (xy 206.111885 -148.414267) (xy 206.121762 -148.41474)
			(xy 207.805782 -148.41474) (xy 207.815845 -148.415179) (xy 207.834424 -148.422919) (xy 207.84185 -148.429726)
			(xy 207.979518 -148.567394) (xy 207.986917 -148.574238) (xy 208.005515 -148.581967) (xy 208.015586 -148.58238)
		)
		(stroke
			(width 0)
			(type solid)
		)
		(fill yes)
		(layer "In11.Cu")
		(net "P5V_AUX")
	)
	(gr_poly
		(pts
			(xy 213.512908 -330.840588) (xy 213.523327 -330.840075) (xy 213.542454 -330.8318) (xy 213.549992 -330.824586)
			(xy 213.607904 -330.762864) (xy 213.615016 -330.743052) (xy 213.614254 -330.732384) (xy 213.613492 -330.708)
			(xy 213.613978 -330.680749) (xy 213.621734 -330.626801) (xy 213.637089 -330.574506) (xy 213.659731 -330.524929)
			(xy 213.689197 -330.479079) (xy 213.724888 -330.437888) (xy 213.766079 -330.402197) (xy 213.811929 -330.372731)
			(xy 213.861506 -330.350089) (xy 213.913801 -330.334734) (xy 213.967749 -330.326978) (xy 214.022251 -330.326978)
			(xy 214.076199 -330.334734) (xy 214.128494 -330.350089) (xy 214.178071 -330.372731) (xy 214.223921 -330.402197)
			(xy 214.265112 -330.437888) (xy 214.300803 -330.479079) (xy 214.330269 -330.524929) (xy 214.352911 -330.574506)
			(xy 214.368266 -330.626801) (xy 214.376022 -330.680749) (xy 214.376508 -330.708) (xy 214.375746 -330.732384)
			(xy 214.374984 -330.743052) (xy 214.382096 -330.762864) (xy 214.440008 -330.824586) (xy 214.447506 -330.831856)
			(xy 214.466659 -330.840127) (xy 214.477092 -330.840588) (xy 214.57539 -330.840588) (xy 214.585461 -330.840166)
			(xy 214.604067 -330.832453) (xy 214.611458 -330.825602) (xy 219.257626 -326.179434) (xy 219.26447 -326.172035)
			(xy 219.272192 -326.153436) (xy 219.272612 -326.143366) (xy 219.272612 -307.060854) (xy 219.273044 -307.050788)
			(xy 219.280771 -307.032197) (xy 219.287598 -307.024786) (xy 220.52153 -305.790854) (xy 220.528928 -305.784007)
			(xy 220.547526 -305.776275) (xy 220.557598 -305.775868) (xy 257.796792 -305.775868) (xy 257.806864 -305.776289)
			(xy 257.825473 -305.783998) (xy 257.83286 -305.790854) (xy 258.72948 -306.687474) (xy 258.736317 -306.694876)
			(xy 258.744027 -306.713474) (xy 258.744466 -306.723542) (xy 258.744466 -326.648826) (xy 258.744896 -326.658893)
			(xy 258.752624 -326.677484) (xy 258.759452 -326.684894) (xy 259.247386 -327.172828) (xy 259.28828 -327.17359)
			(xy 259.30352 -327.159366) (xy 259.324857 -327.140054) (xy 259.372254 -327.107415) (xy 259.424014 -327.082262)
			(xy 259.478964 -327.065166) (xy 259.535858 -327.056514) (xy 259.564632 -327.055988) (xy 259.591882 -327.056476)
			(xy 259.645826 -327.064236) (xy 259.698117 -327.079594) (xy 259.747691 -327.102237) (xy 259.793538 -327.131704)
			(xy 259.834724 -327.167395) (xy 259.870413 -327.208585) (xy 259.899877 -327.254434) (xy 259.922516 -327.304009)
			(xy 259.93787 -327.356301) (xy 259.945626 -327.410246) (xy 259.94614 -327.437496) (xy 259.945617 -327.466271)
			(xy 259.936972 -327.523167) (xy 259.919878 -327.578119) (xy 259.894723 -327.62988) (xy 259.862078 -327.677274)
			(xy 259.842762 -327.698608) (xy 259.828538 -327.713848) (xy 259.8293 -327.754742) (xy 260.119876 -328.045318)
			(xy 260.127275 -328.052161) (xy 260.145874 -328.059881) (xy 260.155944 -328.060304) (xy 264.873994 -328.060304)
			(xy 264.884065 -328.059882) (xy 264.902671 -328.05217) (xy 264.910062 -328.045318) (xy 265.301222 -327.654158)
			(xy 265.30807 -327.646761) (xy 265.315802 -327.628162) (xy 265.316208 -327.61809) (xy 265.316208 -321.299078)
			(xy 265.315781 -321.289009) (xy 265.308062 -321.27041) (xy 265.301222 -321.26301) (xy 263.982962 -319.94475)
			(xy 263.976117 -319.937352) (xy 263.968391 -319.918753) (xy 263.967976 -319.908682) (xy 263.967976 -318.445896)
			(xy 263.9673 -318.433254) (xy 263.955302 -318.410997) (xy 263.945116 -318.403478) (xy 263.863582 -318.34963)
			(xy 263.838182 -318.347344) (xy 263.826244 -318.352424) (xy 263.794383 -318.36551) (xy 263.728016 -318.383942)
			(xy 263.659769 -318.393245) (xy 263.62533 -318.393826) (xy 263.593365 -318.393347) (xy 263.52994 -318.385338)
			(xy 263.468018 -318.369442) (xy 263.408577 -318.345911) (xy 263.352554 -318.315115) (xy 263.300833 -318.27754)
			(xy 263.254229 -318.233779) (xy 263.213477 -318.184522) (xy 263.179221 -318.130545) (xy 263.152 -318.0727)
			(xy 263.132244 -318.0119) (xy 263.120265 -317.949103) (xy 263.11625 -317.8853) (xy 263.120265 -317.821497)
			(xy 263.132244 -317.7587) (xy 263.152 -317.6979) (xy 263.179221 -317.640055) (xy 263.213477 -317.586078)
			(xy 263.254229 -317.536821) (xy 263.300833 -317.49306) (xy 263.352554 -317.455485) (xy 263.408577 -317.424689)
			(xy 263.468018 -317.401158) (xy 263.52994 -317.385262) (xy 263.593365 -317.377253) (xy 263.62533 -317.37681)
			(xy 263.659769 -317.377385) (xy 263.728016 -317.386693) (xy 263.79438 -317.405133) (xy 263.826244 -317.418212)
			(xy 263.838182 -317.423292) (xy 263.863582 -317.421006) (xy 263.945116 -317.367158) (xy 263.955313 -317.359646)
			(xy 263.967329 -317.337387) (xy 263.967976 -317.32474) (xy 263.967976 -299.64634) (xy 263.967541 -299.636275)
			(xy 263.959809 -299.617689) (xy 263.95299 -299.610272) (xy 259.517896 -295.175178) (xy 259.510501 -295.168324)
			(xy 259.491902 -295.160579) (xy 259.481828 -295.160192) (xy 210.78444 -295.160192) (xy 210.774374 -295.160626)
			(xy 210.755785 -295.168354) (xy 210.748372 -295.175178) (xy 207.871822 -298.051728) (xy 207.864978 -298.059127)
			(xy 207.85725 -298.077725) (xy 207.856836 -298.087796) (xy 207.856836 -313.595977) (xy 209.83168 -313.595977)
			(xy 209.83168 -313.532055) (xy 209.839691 -313.468637) (xy 209.855588 -313.406723) (xy 209.87912 -313.34729)
			(xy 209.909914 -313.291275) (xy 209.947487 -313.23956) (xy 209.991244 -313.192963) (xy 210.040497 -313.152218)
			(xy 210.094468 -313.117967) (xy 210.152307 -313.09075) (xy 210.2131 -313.070997) (xy 210.27589 -313.059019)
			(xy 210.339686 -313.055006) (xy 210.403482 -313.059019) (xy 210.466272 -313.070997) (xy 210.527065 -313.09075)
			(xy 210.584904 -313.117967) (xy 210.638875 -313.152218) (xy 210.688128 -313.192963) (xy 210.731885 -313.23956)
			(xy 210.769458 -313.291275) (xy 210.800252 -313.34729) (xy 210.823784 -313.406723) (xy 210.839681 -313.468637)
			(xy 210.847692 -313.532055) (xy 210.848194 -313.564016) (xy 210.847692 -313.595977) (xy 210.839681 -313.659395)
			(xy 210.823784 -313.721309) (xy 210.800252 -313.780742) (xy 210.769458 -313.836757) (xy 210.731885 -313.888472)
			(xy 210.688128 -313.935069) (xy 210.638875 -313.975814) (xy 210.584904 -314.010065) (xy 210.527065 -314.037282)
			(xy 210.466272 -314.057035) (xy 210.403482 -314.069013) (xy 210.339686 -314.073027) (xy 210.27589 -314.069013)
			(xy 210.2131 -314.057035) (xy 210.152307 -314.037282) (xy 210.094468 -314.010065) (xy 210.040497 -313.975814)
			(xy 209.991244 -313.935069) (xy 209.947487 -313.888472) (xy 209.909914 -313.836757) (xy 209.87912 -313.780742)
			(xy 209.855588 -313.721309) (xy 209.839691 -313.659395) (xy 209.83168 -313.595977) (xy 207.856836 -313.595977)
			(xy 207.856836 -317.35268) (xy 208.900268 -317.35268) (xy 208.900802 -317.319503) (xy 208.909435 -317.253712)
			(xy 208.926552 -317.189603) (xy 208.951862 -317.128265) (xy 208.984934 -317.070739) (xy 209.025208 -317.018004)
			(xy 209.071999 -316.970956) (xy 209.124512 -316.930392) (xy 209.181854 -316.897004) (xy 209.243052 -316.871357)
			(xy 209.307066 -316.853887) (xy 209.372808 -316.844893) (xy 209.405982 -316.844172) (xy 209.419533 -316.84373)
			(xy 209.445656 -316.836498) (xy 209.468955 -316.822647) (xy 209.487788 -316.803152) (xy 209.500826 -316.779388)
			(xy 209.507151 -316.753031) (xy 209.506316 -316.725938) (xy 209.502756 -316.712854) (xy 209.492328 -316.676529)
			(xy 209.481111 -316.601795) (xy 209.480404 -316.56401) (xy 209.480906 -316.532049) (xy 209.488917 -316.468631)
			(xy 209.504814 -316.406717) (xy 209.528346 -316.347284) (xy 209.55914 -316.291269) (xy 209.596713 -316.239554)
			(xy 209.64047 -316.192957) (xy 209.689723 -316.152212) (xy 209.743694 -316.117961) (xy 209.801533 -316.090744)
			(xy 209.862326 -316.070991) (xy 209.925116 -316.059013) (xy 209.988912 -316.055) (xy 210.052708 -316.059013)
			(xy 210.115498 -316.070991) (xy 210.176291 -316.090744) (xy 210.23413 -316.117961) (xy 210.288101 -316.152212)
			(xy 210.337354 -316.192957) (xy 210.381111 -316.239554) (xy 210.418684 -316.291269) (xy 210.449478 -316.347284)
			(xy 210.47301 -316.406717) (xy 210.488907 -316.468631) (xy 210.496918 -316.532049) (xy 210.49742 -316.56401)
			(xy 210.496888 -316.597188) (xy 210.488256 -316.662979) (xy 210.47114 -316.727089) (xy 210.445831 -316.788428)
			(xy 210.412758 -316.845954) (xy 210.372484 -316.898689) (xy 210.325693 -316.945738) (xy 210.27318 -316.986301)
			(xy 210.215837 -317.01969) (xy 210.154638 -317.045336) (xy 210.090623 -317.062805) (xy 210.02488 -317.071798)
			(xy 209.991706 -317.072518) (xy 209.978155 -317.072963) (xy 209.952034 -317.080197) (xy 209.928737 -317.094049)
			(xy 209.909905 -317.113543) (xy 209.896867 -317.137305) (xy 209.890541 -317.163661) (xy 209.891374 -317.190752)
			(xy 209.894932 -317.203836) (xy 209.905357 -317.240161) (xy 209.916576 -317.314895) (xy 209.917284 -317.35268)
			(xy 209.916782 -317.384641) (xy 209.908771 -317.448059) (xy 209.892874 -317.509973) (xy 209.869342 -317.569406)
			(xy 209.838548 -317.625421) (xy 209.800975 -317.677136) (xy 209.757218 -317.723733) (xy 209.707965 -317.764478)
			(xy 209.653994 -317.798729) (xy 209.596155 -317.825946) (xy 209.535362 -317.845699) (xy 209.472572 -317.857677)
			(xy 209.408776 -317.861691) (xy 209.34498 -317.857677) (xy 209.28219 -317.845699) (xy 209.221397 -317.825946)
			(xy 209.163558 -317.798729) (xy 209.109587 -317.764478) (xy 209.060334 -317.723733) (xy 209.016577 -317.677136)
			(xy 208.979004 -317.625421) (xy 208.94821 -317.569406) (xy 208.924678 -317.509973) (xy 208.908781 -317.448059)
			(xy 208.90077 -317.384641) (xy 208.900268 -317.35268) (xy 207.856836 -317.35268) (xy 207.856836 -317.964523)
			(xy 210.908132 -317.964523) (xy 210.908132 -317.900601) (xy 210.916143 -317.837183) (xy 210.93204 -317.775269)
			(xy 210.955572 -317.715836) (xy 210.986366 -317.659821) (xy 211.023939 -317.608106) (xy 211.067696 -317.561509)
			(xy 211.116949 -317.520764) (xy 211.17092 -317.486513) (xy 211.228759 -317.459296) (xy 211.289552 -317.439543)
			(xy 211.352342 -317.427565) (xy 211.416138 -317.423552) (xy 211.479934 -317.427565) (xy 211.542724 -317.439543)
			(xy 211.603517 -317.459296) (xy 211.661356 -317.486513) (xy 211.715327 -317.520764) (xy 211.76458 -317.561509)
			(xy 211.808337 -317.608106) (xy 211.84591 -317.659821) (xy 211.876704 -317.715836) (xy 211.900236 -317.775269)
			(xy 211.916133 -317.837183) (xy 211.924144 -317.900601) (xy 211.924646 -317.932562) (xy 211.924144 -317.964523)
			(xy 211.916133 -318.027941) (xy 211.900236 -318.089855) (xy 211.876704 -318.149288) (xy 211.84591 -318.205303)
			(xy 211.808337 -318.257018) (xy 211.76458 -318.303615) (xy 211.715327 -318.34436) (xy 211.661356 -318.378611)
			(xy 211.603517 -318.405828) (xy 211.542724 -318.425581) (xy 211.479934 -318.437559) (xy 211.416138 -318.441573)
			(xy 211.352342 -318.437559) (xy 211.289552 -318.425581) (xy 211.228759 -318.405828) (xy 211.17092 -318.378611)
			(xy 211.116949 -318.34436) (xy 211.067696 -318.303615) (xy 211.023939 -318.257018) (xy 210.986366 -318.205303)
			(xy 210.955572 -318.149288) (xy 210.93204 -318.089855) (xy 210.916143 -318.027941) (xy 210.908132 -317.964523)
			(xy 207.856836 -317.964523) (xy 207.856836 -319.361058) (xy 207.856401 -319.371122) (xy 207.848664 -319.389705)
			(xy 207.84185 -319.397126) (xy 206.860648 -320.378328) (xy 206.85325 -320.385174) (xy 206.834651 -320.392901)
			(xy 206.82458 -320.393314) (xy 199.410574 -320.393314) (xy 199.400506 -320.393742) (xy 199.38191 -320.401465)
			(xy 199.374506 -320.4083) (xy 198.81469 -320.968116) (xy 198.807836 -320.975511) (xy 198.800093 -320.99411)
			(xy 198.799704 -321.004184) (xy 198.799704 -321.627447) (xy 208.342509 -321.627447) (xy 208.350528 -321.499984)
			(xy 208.366535 -321.373276) (xy 208.390466 -321.247824) (xy 208.422227 -321.124121) (xy 208.461692 -321.002657)
			(xy 208.508707 -320.88391) (xy 208.563085 -320.76835) (xy 208.624611 -320.656432) (xy 208.693044 -320.548599)
			(xy 208.768112 -320.445274) (xy 208.84952 -320.346868) (xy 208.936946 -320.253767) (xy 209.030045 -320.16634)
			(xy 209.128451 -320.08493) (xy 209.231774 -320.00986) (xy 209.339606 -319.941426) (xy 209.451523 -319.879898)
			(xy 209.567083 -319.825519) (xy 209.685828 -319.778503) (xy 209.807292 -319.739035) (xy 209.930994 -319.707272)
			(xy 210.056447 -319.68334) (xy 210.183154 -319.667331) (xy 210.310617 -319.65931) (xy 210.438332 -319.659309)
			(xy 210.565795 -319.667326) (xy 210.692503 -319.683332) (xy 210.817956 -319.707261) (xy 210.941659 -319.739021)
			(xy 211.063124 -319.778485) (xy 211.181871 -319.825499) (xy 211.297432 -319.879875) (xy 211.40935 -319.941401)
			(xy 211.517184 -320.009832) (xy 211.620509 -320.084899) (xy 211.718917 -320.166306) (xy 211.812018 -320.253731)
			(xy 211.899447 -320.34683) (xy 211.980857 -320.445234) (xy 212.055928 -320.548557) (xy 212.124363 -320.656389)
			(xy 212.185892 -320.768305) (xy 212.240273 -320.883864) (xy 212.28729 -321.002609) (xy 212.326759 -321.124072)
			(xy 212.358523 -321.247774) (xy 212.382457 -321.373226) (xy 212.398467 -321.499934) (xy 212.406489 -321.627397)
			(xy 212.406992 -321.691254) (xy 212.406491 -321.756943) (xy 212.404432 -321.788747) (xy 213.931494 -321.788747)
			(xy 213.931494 -321.724825) (xy 213.939505 -321.661407) (xy 213.955402 -321.599493) (xy 213.978934 -321.54006)
			(xy 214.009728 -321.484045) (xy 214.047301 -321.43233) (xy 214.091058 -321.385733) (xy 214.140311 -321.344988)
			(xy 214.194282 -321.310737) (xy 214.252121 -321.28352) (xy 214.312914 -321.263767) (xy 214.375704 -321.251789)
			(xy 214.4395 -321.247776) (xy 214.503296 -321.251789) (xy 214.566086 -321.263767) (xy 214.626879 -321.28352)
			(xy 214.684718 -321.310737) (xy 214.738689 -321.344988) (xy 214.787942 -321.385733) (xy 214.831699 -321.43233)
			(xy 214.869272 -321.484045) (xy 214.900066 -321.54006) (xy 214.923598 -321.599493) (xy 214.939495 -321.661407)
			(xy 214.947506 -321.724825) (xy 214.948008 -321.756786) (xy 214.947506 -321.788747) (xy 214.939495 -321.852165)
			(xy 214.923598 -321.914079) (xy 214.900066 -321.973512) (xy 214.869272 -322.029527) (xy 214.831699 -322.081242)
			(xy 214.787942 -322.127839) (xy 214.738689 -322.168584) (xy 214.684718 -322.202835) (xy 214.626879 -322.230052)
			(xy 214.566086 -322.249805) (xy 214.503296 -322.261783) (xy 214.4395 -322.265797) (xy 214.375704 -322.261783)
			(xy 214.312914 -322.249805) (xy 214.252121 -322.230052) (xy 214.194282 -322.202835) (xy 214.140311 -322.168584)
			(xy 214.091058 -322.127839) (xy 214.047301 -322.081242) (xy 214.009728 -322.029527) (xy 213.978934 -321.973512)
			(xy 213.955402 -321.914079) (xy 213.939505 -321.852165) (xy 213.931494 -321.788747) (xy 212.404432 -321.788747)
			(xy 212.398003 -321.888047) (xy 212.381067 -322.018329) (xy 212.355752 -322.147246) (xy 212.322166 -322.274258)
			(xy 212.280447 -322.398837) (xy 212.23077 -322.520461) (xy 212.228375 -322.52539) (xy 214.686132 -322.52539)
			(xy 214.690203 -322.469768) (xy 214.702329 -322.415331) (xy 214.722252 -322.36324) (xy 214.749548 -322.314605)
			(xy 214.783634 -322.270462) (xy 214.823783 -322.231753) (xy 214.869141 -322.199302) (xy 214.918741 -322.173801)
			(xy 214.971525 -322.155794) (xy 215.026368 -322.145664) (xy 215.082102 -322.143627) (xy 215.137539 -322.149727)
			(xy 215.191496 -322.163833) (xy 215.242825 -322.185645) (xy 215.290431 -322.214699) (xy 215.333299 -322.250374)
			(xy 215.370516 -322.291911) (xy 215.401289 -322.338424) (xy 215.424961 -322.388921) (xy 215.441029 -322.442328)
			(xy 215.449149 -322.497504) (xy 215.449658 -322.52539) (xy 215.449149 -322.553276) (xy 215.441029 -322.608452)
			(xy 215.424961 -322.661859) (xy 215.401289 -322.712356) (xy 215.370516 -322.758869) (xy 215.333299 -322.800406)
			(xy 215.290431 -322.836081) (xy 215.242825 -322.865135) (xy 215.191496 -322.886947) (xy 215.137539 -322.901053)
			(xy 215.082102 -322.907153) (xy 215.026368 -322.905116) (xy 214.971525 -322.894986) (xy 214.918741 -322.876979)
			(xy 214.869141 -322.851478) (xy 214.823783 -322.819027) (xy 214.783634 -322.780318) (xy 214.749548 -322.736175)
			(xy 214.722252 -322.68754) (xy 214.702329 -322.635449) (xy 214.690203 -322.581012) (xy 214.686132 -322.52539)
			(xy 212.228375 -322.52539) (xy 212.173343 -322.638624) (xy 212.108405 -322.752831) (xy 212.036227 -322.862606)
			(xy 211.957111 -322.967491) (xy 211.871387 -323.067049) (xy 211.779412 -323.160862) (xy 211.730844 -323.205094)
			(xy 211.722462 -323.21246) (xy 211.713572 -323.23278) (xy 211.716112 -323.332602) (xy 211.726018 -323.352668)
			(xy 211.734654 -323.35978) (xy 211.759493 -323.380518) (xy 211.804247 -323.427254) (xy 211.842705 -323.479294)
			(xy 211.874246 -323.535795) (xy 211.89836 -323.595842) (xy 211.914655 -323.658465) (xy 211.922869 -323.72265)
			(xy 211.923376 -323.755004) (xy 211.92281 -323.789504) (xy 211.913479 -323.85787) (xy 211.894988 -323.924346)
			(xy 211.867678 -323.987711) (xy 211.832051 -324.046802) (xy 211.810854 -324.074028) (xy 211.804232 -324.082981)
			(xy 211.798811 -324.104558) (xy 211.803014 -324.126406) (xy 211.809076 -324.13575) (xy 211.82742 -324.161901)
			(xy 211.85819 -324.217879) (xy 211.881704 -324.277271) (xy 211.897591 -324.339142) (xy 211.9056 -324.402515)
			(xy 211.906104 -324.434454) (xy 211.905602 -324.466415) (xy 211.897591 -324.529833) (xy 211.881694 -324.591747)
			(xy 211.858162 -324.65118) (xy 211.827368 -324.707195) (xy 211.789795 -324.75891) (xy 211.746038 -324.805507)
			(xy 211.696785 -324.846252) (xy 211.642814 -324.880503) (xy 211.584975 -324.90772) (xy 211.524182 -324.927473)
			(xy 211.461392 -324.939451) (xy 211.397596 -324.943465) (xy 211.3338 -324.939451) (xy 211.27101 -324.927473)
			(xy 211.210217 -324.90772) (xy 211.152378 -324.880503) (xy 211.098407 -324.846252) (xy 211.049154 -324.805507)
			(xy 211.005397 -324.75891) (xy 210.967824 -324.707195) (xy 210.93703 -324.65118) (xy 210.913498 -324.591747)
			(xy 210.897601 -324.529833) (xy 210.88959 -324.466415) (xy 210.889088 -324.434454) (xy 210.889695 -324.399956)
			(xy 210.899017 -324.331591) (xy 210.917499 -324.265116) (xy 210.944799 -324.20175) (xy 210.980418 -324.142658)
			(xy 211.00161 -324.11543) (xy 211.008183 -324.106446) (xy 211.013624 -324.084887) (xy 211.009441 -324.06305)
			(xy 211.003388 -324.053708) (xy 210.98628 -324.029395) (xy 210.957194 -323.977542) (xy 210.934357 -323.922651)
			(xy 210.918079 -323.865471) (xy 210.908582 -323.806782) (xy 210.906868 -323.777102) (xy 210.90636 -323.765672)
			(xy 210.8962 -323.746114) (xy 210.81746 -323.684646) (xy 210.79587 -323.679566) (xy 210.784948 -323.681852)
			(xy 210.717359 -323.695196) (xy 210.580841 -323.713826) (xy 210.443375 -323.723176) (xy 210.374484 -323.723762)
			(xy 210.310627 -323.72329) (xy 210.183164 -323.71527) (xy 210.056456 -323.699262) (xy 209.931003 -323.67533)
			(xy 209.807301 -323.643567) (xy 209.685837 -323.604101) (xy 209.567091 -323.557085) (xy 209.451532 -323.502706)
			(xy 209.339614 -323.441178) (xy 209.231781 -323.372745) (xy 209.128458 -323.297676) (xy 209.030052 -323.216267)
			(xy 208.936953 -323.128839) (xy 208.849526 -323.035739) (xy 208.768118 -322.937333) (xy 208.693049 -322.834009)
			(xy 208.624616 -322.726176) (xy 208.563089 -322.614258) (xy 208.508711 -322.498698) (xy 208.461696 -322.379952)
			(xy 208.422229 -322.258488) (xy 208.390468 -322.134786) (xy 208.366536 -322.009333) (xy 208.350529 -321.882625)
			(xy 208.34251 -321.755162) (xy 208.342509 -321.627447) (xy 198.799704 -321.627447) (xy 198.799704 -324.5353)
			(xy 202.330084 -324.5353) (xy 202.334076 -324.446414) (xy 202.346019 -324.358244) (xy 202.365818 -324.271499)
			(xy 202.393312 -324.186879) (xy 202.428281 -324.105063) (xy 202.470443 -324.026711) (xy 202.519458 -323.952454)
			(xy 202.574932 -323.882889) (xy 202.636419 -323.818577) (xy 202.703423 -323.760036) (xy 202.775404 -323.707736)
			(xy 202.851784 -323.662099) (xy 202.931947 -323.623492) (xy 203.015248 -323.592226) (xy 203.101016 -323.568553)
			(xy 203.188561 -323.552663) (xy 203.277178 -323.544684) (xy 203.321666 -323.544184) (xy 205.074266 -323.544184)
			(xy 205.118756 -323.544683) (xy 205.207377 -323.552656) (xy 205.294926 -323.568541) (xy 205.3807 -323.592211)
			(xy 205.464006 -323.623473) (xy 205.544174 -323.662078) (xy 205.620559 -323.707714) (xy 205.692546 -323.760013)
			(xy 205.759555 -323.818554) (xy 205.821046 -323.882867) (xy 205.876525 -323.952433) (xy 205.925544 -324.026692)
			(xy 205.967709 -324.105046) (xy 206.002681 -324.186865) (xy 206.030178 -324.271489) (xy 206.049978 -324.358237)
			(xy 206.061922 -324.44641) (xy 206.065914 -324.5353) (xy 206.061922 -324.62419) (xy 206.049978 -324.712363)
			(xy 206.030178 -324.799111) (xy 206.002681 -324.883735) (xy 205.967709 -324.965554) (xy 205.925544 -325.043908)
			(xy 205.876525 -325.118167) (xy 205.821046 -325.187733) (xy 205.759555 -325.252046) (xy 205.692546 -325.310587)
			(xy 205.620559 -325.362886) (xy 205.544174 -325.408522) (xy 205.464006 -325.447127) (xy 205.439573 -325.456296)
			(xy 211.848698 -325.456296) (xy 211.852769 -325.400674) (xy 211.864895 -325.346237) (xy 211.884818 -325.294146)
			(xy 211.912114 -325.245511) (xy 211.9462 -325.201368) (xy 211.986349 -325.162659) (xy 212.031707 -325.130208)
			(xy 212.081307 -325.104707) (xy 212.134091 -325.0867) (xy 212.188934 -325.07657) (xy 212.244668 -325.074533)
			(xy 212.300105 -325.080633) (xy 212.354062 -325.094739) (xy 212.405391 -325.116551) (xy 212.452997 -325.145605)
			(xy 212.495865 -325.18128) (xy 212.533082 -325.222817) (xy 212.563855 -325.26933) (xy 212.587527 -325.319827)
			(xy 212.603595 -325.373234) (xy 212.611715 -325.42841) (xy 212.612224 -325.456296) (xy 212.611715 -325.484182)
			(xy 212.603595 -325.539358) (xy 212.587527 -325.592765) (xy 212.563855 -325.643262) (xy 212.533082 -325.689775)
			(xy 212.495865 -325.731312) (xy 212.452997 -325.766987) (xy 212.405391 -325.796041) (xy 212.354062 -325.817853)
			(xy 212.300105 -325.831959) (xy 212.244668 -325.838059) (xy 212.188934 -325.836022) (xy 212.134091 -325.825892)
			(xy 212.081307 -325.807885) (xy 212.031707 -325.782384) (xy 211.986349 -325.749933) (xy 211.9462 -325.711224)
			(xy 211.912114 -325.667081) (xy 211.884818 -325.618446) (xy 211.864895 -325.566355) (xy 211.852769 -325.511918)
			(xy 211.848698 -325.456296) (xy 205.439573 -325.456296) (xy 205.3807 -325.478389) (xy 205.294926 -325.502059)
			(xy 205.207377 -325.517944) (xy 205.118756 -325.525917) (xy 205.074266 -325.5264) (xy 203.321666 -325.5264)
			(xy 203.277178 -325.525916) (xy 203.188561 -325.517937) (xy 203.101016 -325.502047) (xy 203.015248 -325.478374)
			(xy 202.931947 -325.447108) (xy 202.851784 -325.408501) (xy 202.775404 -325.362864) (xy 202.703423 -325.310564)
			(xy 202.636419 -325.252023) (xy 202.574932 -325.187711) (xy 202.519458 -325.118146) (xy 202.470443 -325.043889)
			(xy 202.428281 -324.965537) (xy 202.393312 -324.883721) (xy 202.365818 -324.799101) (xy 202.346019 -324.712356)
			(xy 202.334076 -324.624186) (xy 202.330084 -324.5353) (xy 198.799704 -324.5353) (xy 198.799704 -325.280274)
			(xy 198.799267 -325.290338) (xy 198.791534 -325.308924) (xy 198.784718 -325.316342) (xy 197.591172 -326.509888)
			(xy 211.88121 -326.509888) (xy 211.885281 -326.454266) (xy 211.897407 -326.399829) (xy 211.91733 -326.347738)
			(xy 211.944626 -326.299103) (xy 211.978712 -326.25496) (xy 212.018861 -326.216251) (xy 212.064219 -326.1838)
			(xy 212.113819 -326.158299) (xy 212.166603 -326.140292) (xy 212.221446 -326.130162) (xy 212.27718 -326.128125)
			(xy 212.332617 -326.134225) (xy 212.386574 -326.148331) (xy 212.437903 -326.170143) (xy 212.485509 -326.199197)
			(xy 212.497471 -326.209152) (xy 217.917266 -326.209152) (xy 217.921337 -326.15353) (xy 217.933463 -326.099093)
			(xy 217.953386 -326.047002) (xy 217.980682 -325.998367) (xy 218.014768 -325.954224) (xy 218.054917 -325.915515)
			(xy 218.100275 -325.883064) (xy 218.149875 -325.857563) (xy 218.202659 -325.839556) (xy 218.257502 -325.829426)
			(xy 218.313236 -325.827389) (xy 218.368673 -325.833489) (xy 218.42263 -325.847595) (xy 218.473959 -325.869407)
			(xy 218.521565 -325.898461) (xy 218.564433 -325.934136) (xy 218.60165 -325.975673) (xy 218.632423 -326.022186)
			(xy 218.656095 -326.072683) (xy 218.672163 -326.12609) (xy 218.680283 -326.181266) (xy 218.680792 -326.209152)
			(xy 218.680283 -326.237038) (xy 218.672163 -326.292214) (xy 218.656095 -326.345621) (xy 218.632423 -326.396118)
			(xy 218.60165 -326.442631) (xy 218.564433 -326.484168) (xy 218.521565 -326.519843) (xy 218.473959 -326.548897)
			(xy 218.42263 -326.570709) (xy 218.368673 -326.584815) (xy 218.313236 -326.590915) (xy 218.257502 -326.588878)
			(xy 218.202659 -326.578748) (xy 218.149875 -326.560741) (xy 218.100275 -326.53524) (xy 218.054917 -326.502789)
			(xy 218.014768 -326.46408) (xy 217.980682 -326.419937) (xy 217.953386 -326.371302) (xy 217.933463 -326.319211)
			(xy 217.921337 -326.264774) (xy 217.917266 -326.209152) (xy 212.497471 -326.209152) (xy 212.528377 -326.234872)
			(xy 212.565594 -326.276409) (xy 212.596367 -326.322922) (xy 212.620039 -326.373419) (xy 212.636107 -326.426826)
			(xy 212.644227 -326.482002) (xy 212.644736 -326.509888) (xy 212.644227 -326.537774) (xy 212.636107 -326.59295)
			(xy 212.620039 -326.646357) (xy 212.596367 -326.696854) (xy 212.565594 -326.743367) (xy 212.528377 -326.784904)
			(xy 212.485509 -326.820579) (xy 212.437903 -326.849633) (xy 212.386574 -326.871445) (xy 212.332617 -326.885551)
			(xy 212.27718 -326.891651) (xy 212.221446 -326.889614) (xy 212.166603 -326.879484) (xy 212.113819 -326.861477)
			(xy 212.064219 -326.835976) (xy 212.018861 -326.803525) (xy 211.978712 -326.764816) (xy 211.944626 -326.720673)
			(xy 211.91733 -326.672038) (xy 211.897407 -326.619947) (xy 211.885281 -326.56551) (xy 211.88121 -326.509888)
			(xy 197.591172 -326.509888) (xy 197.005956 -327.095104) (xy 214.324946 -327.095104) (xy 214.325448 -327.063143)
			(xy 214.333459 -326.999725) (xy 214.349356 -326.937811) (xy 214.372888 -326.878378) (xy 214.403682 -326.822363)
			(xy 214.441255 -326.770648) (xy 214.485012 -326.724051) (xy 214.534265 -326.683306) (xy 214.588236 -326.649055)
			(xy 214.646075 -326.621838) (xy 214.706868 -326.602085) (xy 214.769658 -326.590107) (xy 214.833454 -326.586094)
			(xy 214.89725 -326.590107) (xy 214.96004 -326.602085) (xy 215.020833 -326.621838) (xy 215.078672 -326.649055)
			(xy 215.132643 -326.683306) (xy 215.181896 -326.724051) (xy 215.225653 -326.770648) (xy 215.263226 -326.822363)
			(xy 215.29402 -326.878378) (xy 215.317552 -326.937811) (xy 215.333449 -326.999725) (xy 215.34146 -327.063143)
			(xy 215.341962 -327.095104) (xy 215.341444 -327.127483) (xy 215.333232 -327.191717) (xy 215.316929 -327.254389)
			(xy 215.292799 -327.314482) (xy 215.261232 -327.371024) (xy 215.242394 -327.397364) (xy 215.235282 -327.407016)
			(xy 215.231218 -327.430892) (xy 215.262206 -327.531984) (xy 215.278716 -327.54951) (xy 215.290146 -327.553574)
			(xy 215.319508 -327.564421) (xy 215.37551 -327.592386) (xy 215.427654 -327.627015) (xy 215.475153 -327.667785)
			(xy 215.517286 -327.714078) (xy 215.553417 -327.765194) (xy 215.582999 -327.820359) (xy 215.605583 -327.878739)
			(xy 215.620829 -327.93945) (xy 215.628506 -328.001574) (xy 215.628982 -328.032872) (xy 215.62848 -328.064833)
			(xy 215.620469 -328.128251) (xy 215.604572 -328.190165) (xy 215.58104 -328.249598) (xy 215.550246 -328.305613)
			(xy 215.512673 -328.357328) (xy 215.468916 -328.403925) (xy 215.419663 -328.44467) (xy 215.365692 -328.478921)
			(xy 215.307853 -328.506138) (xy 215.24706 -328.525891) (xy 215.18427 -328.537869) (xy 215.120474 -328.541883)
			(xy 215.056678 -328.537869) (xy 214.993888 -328.525891) (xy 214.933095 -328.506138) (xy 214.875256 -328.478921)
			(xy 214.821285 -328.44467) (xy 214.772032 -328.403925) (xy 214.728275 -328.357328) (xy 214.690702 -328.305613)
			(xy 214.659908 -328.249598) (xy 214.636376 -328.190165) (xy 214.620479 -328.128251) (xy 214.612468 -328.064833)
			(xy 214.611966 -328.032872) (xy 214.612485 -328.000493) (xy 214.620699 -327.93626) (xy 214.637002 -327.873589)
			(xy 214.661132 -327.813495) (xy 214.692697 -327.756952) (xy 214.711534 -327.730612) (xy 214.718646 -327.72096)
			(xy 214.72271 -327.697084) (xy 214.691722 -327.595992) (xy 214.675212 -327.578466) (xy 214.663782 -327.574402)
			(xy 214.634418 -327.56356) (xy 214.578415 -327.535596) (xy 214.526269 -327.500967) (xy 214.478769 -327.460197)
			(xy 214.436635 -327.413904) (xy 214.400504 -327.362787) (xy 214.370923 -327.307621) (xy 214.348339 -327.24924)
			(xy 214.333095 -327.188527) (xy 214.325421 -327.126403) (xy 214.324946 -327.095104) (xy 197.005956 -327.095104)
			(xy 196.813932 -327.287128) (xy 196.807086 -327.294526) (xy 196.799357 -327.313125) (xy 196.798946 -327.323196)
			(xy 196.798946 -328.00417) (xy 212.132162 -328.00417) (xy 212.136233 -327.948548) (xy 212.148359 -327.894111)
			(xy 212.168282 -327.84202) (xy 212.195578 -327.793385) (xy 212.229664 -327.749242) (xy 212.269813 -327.710533)
			(xy 212.315171 -327.678082) (xy 212.364771 -327.652581) (xy 212.417555 -327.634574) (xy 212.472398 -327.624444)
			(xy 212.528132 -327.622407) (xy 212.583569 -327.628507) (xy 212.637526 -327.642613) (xy 212.688855 -327.664425)
			(xy 212.736461 -327.693479) (xy 212.779329 -327.729154) (xy 212.816546 -327.770691) (xy 212.847319 -327.817204)
			(xy 212.870991 -327.867701) (xy 212.887059 -327.921108) (xy 212.895179 -327.976284) (xy 212.895688 -328.00417)
			(xy 212.895179 -328.032056) (xy 212.887059 -328.087232) (xy 212.870991 -328.140639) (xy 212.847319 -328.191136)
			(xy 212.816546 -328.237649) (xy 212.779329 -328.279186) (xy 212.736461 -328.314861) (xy 212.688855 -328.343915)
			(xy 212.637526 -328.365727) (xy 212.583569 -328.379833) (xy 212.528132 -328.385933) (xy 212.472398 -328.383896)
			(xy 212.417555 -328.373766) (xy 212.364771 -328.355759) (xy 212.315171 -328.330258) (xy 212.269813 -328.297807)
			(xy 212.229664 -328.259098) (xy 212.195578 -328.214955) (xy 212.168282 -328.16632) (xy 212.148359 -328.114229)
			(xy 212.136233 -328.059792) (xy 212.132162 -328.00417) (xy 196.798946 -328.00417) (xy 196.798946 -329.014582)
			(xy 212.11108 -329.014582) (xy 212.115151 -328.95896) (xy 212.127277 -328.904523) (xy 212.1472 -328.852432)
			(xy 212.174496 -328.803797) (xy 212.208582 -328.759654) (xy 212.248731 -328.720945) (xy 212.294089 -328.688494)
			(xy 212.343689 -328.662993) (xy 212.396473 -328.644986) (xy 212.451316 -328.634856) (xy 212.50705 -328.632819)
			(xy 212.562487 -328.638919) (xy 212.616444 -328.653025) (xy 212.667773 -328.674837) (xy 212.715379 -328.703891)
			(xy 212.758247 -328.739566) (xy 212.795464 -328.781103) (xy 212.826237 -328.827616) (xy 212.849909 -328.878113)
			(xy 212.865977 -328.93152) (xy 212.874097 -328.986696) (xy 212.874606 -329.014582) (xy 212.874097 -329.042468)
			(xy 212.865977 -329.097644) (xy 212.849909 -329.151051) (xy 212.826237 -329.201548) (xy 212.819894 -329.211135)
			(xy 214.603324 -329.211135) (xy 214.603324 -329.147213) (xy 214.611335 -329.083795) (xy 214.627232 -329.021881)
			(xy 214.650764 -328.962448) (xy 214.681558 -328.906433) (xy 214.719131 -328.854718) (xy 214.762888 -328.808121)
			(xy 214.812141 -328.767376) (xy 214.866112 -328.733125) (xy 214.923951 -328.705908) (xy 214.984744 -328.686155)
			(xy 215.047534 -328.674177) (xy 215.11133 -328.670164) (xy 215.175126 -328.674177) (xy 215.237916 -328.686155)
			(xy 215.298709 -328.705908) (xy 215.356548 -328.733125) (xy 215.410519 -328.767376) (xy 215.459772 -328.808121)
			(xy 215.503529 -328.854718) (xy 215.541102 -328.906433) (xy 215.571896 -328.962448) (xy 215.595428 -329.021881)
			(xy 215.611325 -329.083795) (xy 215.619336 -329.147213) (xy 215.619838 -329.179174) (xy 215.619336 -329.211135)
			(xy 215.611325 -329.274553) (xy 215.595428 -329.336467) (xy 215.571896 -329.3959) (xy 215.541102 -329.451915)
			(xy 215.503529 -329.50363) (xy 215.459772 -329.550227) (xy 215.410519 -329.590972) (xy 215.356548 -329.625223)
			(xy 215.298709 -329.65244) (xy 215.237916 -329.672193) (xy 215.175126 -329.684171) (xy 215.11133 -329.688185)
			(xy 215.047534 -329.684171) (xy 214.984744 -329.672193) (xy 214.923951 -329.65244) (xy 214.866112 -329.625223)
			(xy 214.812141 -329.590972) (xy 214.762888 -329.550227) (xy 214.719131 -329.50363) (xy 214.681558 -329.451915)
			(xy 214.650764 -329.3959) (xy 214.627232 -329.336467) (xy 214.611335 -329.274553) (xy 214.603324 -329.211135)
			(xy 212.819894 -329.211135) (xy 212.795464 -329.248061) (xy 212.758247 -329.289598) (xy 212.715379 -329.325273)
			(xy 212.667773 -329.354327) (xy 212.616444 -329.376139) (xy 212.562487 -329.390245) (xy 212.50705 -329.396345)
			(xy 212.451316 -329.394308) (xy 212.396473 -329.384178) (xy 212.343689 -329.366171) (xy 212.294089 -329.34067)
			(xy 212.248731 -329.308219) (xy 212.208582 -329.26951) (xy 212.174496 -329.225367) (xy 212.1472 -329.176732)
			(xy 212.127277 -329.124641) (xy 212.115151 -329.070204) (xy 212.11108 -329.014582) (xy 196.798946 -329.014582)
			(xy 196.798946 -330.587858) (xy 196.799381 -330.597922) (xy 196.807115 -330.616507) (xy 196.813932 -330.623926)
			(xy 197.015608 -330.825602) (xy 197.023007 -330.832447) (xy 197.041605 -330.840178) (xy 197.051676 -330.840588)
		)
		(stroke
			(width 0)
			(type solid)
		)
		(fill yes)
		(layer "In11.Cu")
		(net "PVDD_33_S5")
	)
	(gr_poly
		(pts
			(xy 155.509976 -83.59902) (xy 155.520002 -83.598605) (xy 155.53853 -83.59094) (xy 155.552715 -83.576767)
			(xy 155.560396 -83.558246) (xy 155.560776 -83.54822) (xy 155.560776 -72.174862) (xy 155.560281 -72.164861)
			(xy 155.552614 -72.146386) (xy 155.538461 -72.132251) (xy 155.519977 -72.124607) (xy 155.509976 -72.124062)
			(xy 136.780778 -72.124062) (xy 136.770711 -72.124491) (xy 136.752118 -72.132218) (xy 136.74471 -72.139048)
			(xy 135.982202 -72.901556) (xy 135.981948 -72.901556) (xy 135.946134 -72.93737) (xy 135.938768 -72.944482)
			(xy 135.931148 -72.963278) (xy 135.931148 -73.594722) (xy 137.237724 -73.594722) (xy 137.238176 -73.567468)
			(xy 137.245931 -73.513515) (xy 137.261286 -73.461215) (xy 137.283928 -73.411633) (xy 137.313397 -73.365778)
			(xy 137.349092 -73.324584) (xy 137.390286 -73.288891) (xy 137.436142 -73.259423) (xy 137.485725 -73.236782)
			(xy 137.538025 -73.221429) (xy 137.591978 -73.213675) (xy 137.619232 -73.213214) (xy 137.61974 -73.213214)
			(xy 137.650646 -73.213857) (xy 137.71164 -73.223883) (xy 137.770224 -73.243602) (xy 137.824867 -73.272499)
			(xy 137.849864 -73.290684) (xy 137.858754 -73.297288) (xy 137.880344 -73.302114) (xy 137.977118 -73.281032)
			(xy 137.994898 -73.267824) (xy 138.000232 -73.257918) (xy 138.014686 -73.232456) (xy 138.050123 -73.185852)
			(xy 138.092266 -73.14521) (xy 138.140124 -73.111485) (xy 138.192573 -73.08547) (xy 138.248382 -73.067774)
			(xy 138.306239 -73.058814) (xy 138.335512 -73.058274) (xy 138.362763 -73.058767) (xy 138.416709 -73.066524)
			(xy 138.469003 -73.08188) (xy 138.518579 -73.104521) (xy 138.564428 -73.133987) (xy 138.605618 -73.169678)
			(xy 138.641309 -73.210867) (xy 138.670776 -73.256716) (xy 138.693418 -73.306292) (xy 138.708774 -73.358585)
			(xy 138.716533 -73.412531) (xy 138.71702 -73.439782) (xy 138.716562 -73.467116) (xy 138.70875 -73.521223)
			(xy 138.693297 -73.573662) (xy 138.673732 -73.616352) (xy 152.964589 -73.616352) (xy 152.964589 -73.561848)
			(xy 152.972347 -73.507898) (xy 152.987704 -73.455601) (xy 153.010347 -73.406023) (xy 153.039816 -73.360172)
			(xy 153.075511 -73.318982) (xy 153.116705 -73.283291) (xy 153.16256 -73.253827) (xy 153.212141 -73.231189)
			(xy 153.264439 -73.215838) (xy 153.31839 -73.208086) (xy 153.345642 -73.207626) (xy 153.373352 -73.208112)
			(xy 153.428187 -73.216142) (xy 153.481282 -73.232025) (xy 153.531518 -73.255427) (xy 153.577837 -73.285856)
			(xy 153.59888 -73.303892) (xy 153.605992 -73.309988) (xy 153.614628 -73.31329) (xy 153.618978 -73.314824)
			(xy 153.62805 -73.316489) (xy 153.632662 -73.316592) (xy 153.699972 -73.316592) (xy 153.704585 -73.316497)
			(xy 153.713658 -73.314834) (xy 153.718006 -73.31329) (xy 153.726642 -73.309988) (xy 153.733754 -73.303892)
			(xy 153.754797 -73.285858) (xy 153.801117 -73.255432) (xy 153.851353 -73.232034) (xy 153.904448 -73.216156)
			(xy 153.959283 -73.208132) (xy 154.014701 -73.208132) (xy 154.069536 -73.216156) (xy 154.122631 -73.232034)
			(xy 154.172867 -73.255432) (xy 154.219187 -73.285858) (xy 154.24023 -73.303892) (xy 154.247342 -73.309988)
			(xy 154.255978 -73.31329) (xy 154.260324 -73.314837) (xy 154.269399 -73.316493) (xy 154.274012 -73.316592)
			(xy 154.341322 -73.316592) (xy 154.345934 -73.316483) (xy 154.355008 -73.314829) (xy 154.359356 -73.31329)
			(xy 154.367992 -73.309988) (xy 154.375104 -73.303892) (xy 154.396136 -73.285844) (xy 154.442457 -73.255416)
			(xy 154.492696 -73.232017) (xy 154.545794 -73.21614) (xy 154.600632 -73.20812) (xy 154.628342 -73.207626)
			(xy 154.655594 -73.208047) (xy 154.709542 -73.215809) (xy 154.761836 -73.231169) (xy 154.811412 -73.253814)
			(xy 154.857262 -73.283285) (xy 154.898451 -73.318979) (xy 154.934141 -73.360172) (xy 154.963606 -73.406024)
			(xy 154.986246 -73.455603) (xy 155.0016 -73.507899) (xy 155.009356 -73.561848) (xy 155.009356 -73.616352)
			(xy 155.0016 -73.670301) (xy 154.986246 -73.722597) (xy 154.963606 -73.772176) (xy 154.934141 -73.818028)
			(xy 154.898451 -73.859221) (xy 154.857262 -73.894915) (xy 154.811412 -73.924386) (xy 154.761836 -73.947031)
			(xy 154.709542 -73.962391) (xy 154.655594 -73.970153) (xy 154.628342 -73.970642) (xy 154.600633 -73.970148)
			(xy 154.545799 -73.962118) (xy 154.492704 -73.946236) (xy 154.442468 -73.922835) (xy 154.396148 -73.89241)
			(xy 154.375104 -73.874376) (xy 154.367992 -73.86828) (xy 154.359356 -73.864978) (xy 154.355007 -73.863438)
			(xy 154.345934 -73.861777) (xy 154.341322 -73.861676) (xy 154.274012 -73.861676) (xy 154.269399 -73.861763)
			(xy 154.260325 -73.863431) (xy 154.255978 -73.864978) (xy 154.247342 -73.86828) (xy 154.24023 -73.874376)
			(xy 154.219187 -73.89241) (xy 154.172867 -73.922836) (xy 154.122631 -73.946234) (xy 154.069536 -73.962112)
			(xy 154.014701 -73.970136) (xy 153.959283 -73.970136) (xy 153.904448 -73.962112) (xy 153.851353 -73.946234)
			(xy 153.801117 -73.922836) (xy 153.754797 -73.89241) (xy 153.733754 -73.874376) (xy 153.726642 -73.86828)
			(xy 153.718006 -73.864978) (xy 153.713662 -73.863425) (xy 153.704585 -73.861772) (xy 153.699972 -73.861676)
			(xy 153.632662 -73.861676) (xy 153.62805 -73.861776) (xy 153.618976 -73.863435) (xy 153.614628 -73.864978)
			(xy 153.605992 -73.86828) (xy 153.59888 -73.874376) (xy 153.577849 -73.892427) (xy 153.531529 -73.922855)
			(xy 153.481289 -73.946254) (xy 153.428191 -73.96213) (xy 153.373353 -73.970148) (xy 153.345642 -73.970642)
			(xy 153.31839 -73.970114) (xy 153.264439 -73.962362) (xy 153.212141 -73.947011) (xy 153.16256 -73.924373)
			(xy 153.116705 -73.894909) (xy 153.075511 -73.859218) (xy 153.039816 -73.818028) (xy 153.010347 -73.772177)
			(xy 152.987704 -73.722599) (xy 152.972347 -73.670302) (xy 152.964589 -73.616352) (xy 138.673732 -73.616352)
			(xy 138.67052 -73.62336) (xy 138.640884 -73.669299) (xy 138.623294 -73.690226) (xy 138.62304 -73.69048)
			(xy 138.622786 -73.690734) (xy 138.617219 -73.697834) (xy 138.610961 -73.714741) (xy 138.610594 -73.723754)
			(xy 138.610594 -73.79081) (xy 138.610948 -73.799827) (xy 138.617198 -73.816744) (xy 138.622786 -73.82383)
			(xy 138.62304 -73.824084) (xy 138.623294 -73.824338) (xy 138.64087 -73.845277) (xy 138.670511 -73.89121)
			(xy 138.693291 -73.940905) (xy 138.708742 -73.993342) (xy 138.716549 -74.047449) (xy 138.71702 -74.074782)
			(xy 138.716585 -74.101067) (xy 138.709381 -74.153142) (xy 138.695094 -74.203734) (xy 138.673994 -74.251885)
			(xy 138.646482 -74.296681) (xy 138.613077 -74.337274) (xy 138.574415 -74.372896) (xy 138.531227 -74.40287)
			(xy 138.507978 -74.415142) (xy 138.498834 -74.419714) (xy 138.48588 -74.4347) (xy 138.459972 -74.511916)
			(xy 138.457274 -74.521299) (xy 138.458457 -74.540769) (xy 138.462258 -74.549762) (xy 138.462512 -74.550524)
			(xy 138.462766 -74.550778) (xy 138.475042 -74.577044) (xy 138.492374 -74.632369) (xy 138.501112 -74.689683)
			(xy 138.501628 -74.718672) (xy 138.501142 -74.745923) (xy 138.493386 -74.799871) (xy 138.478073 -74.852022)
			(xy 141.157704 -74.852022) (xy 141.161775 -74.7964) (xy 141.173901 -74.741963) (xy 141.193824 -74.689872)
			(xy 141.22112 -74.641237) (xy 141.255206 -74.597094) (xy 141.295355 -74.558385) (xy 141.340713 -74.525934)
			(xy 141.390313 -74.500433) (xy 141.443097 -74.482426) (xy 141.49794 -74.472296) (xy 141.553674 -74.470259)
			(xy 141.609111 -74.476359) (xy 141.663068 -74.490465) (xy 141.714397 -74.512277) (xy 141.762003 -74.541331)
			(xy 141.804871 -74.577006) (xy 141.842088 -74.618543) (xy 141.872861 -74.665056) (xy 141.896533 -74.715553)
			(xy 141.912601 -74.76896) (xy 141.920721 -74.824136) (xy 141.92123 -74.852022) (xy 141.920721 -74.879908)
			(xy 141.917349 -74.902822) (xy 144.60677 -74.902822) (xy 144.610843 -74.847163) (xy 144.622978 -74.79269)
			(xy 144.642914 -74.740564) (xy 144.670228 -74.691896) (xy 144.704336 -74.647724) (xy 144.744513 -74.608989)
			(xy 144.789901 -74.576517) (xy 144.839533 -74.550999) (xy 144.892353 -74.53298) (xy 144.947232 -74.522843)
			(xy 145.003003 -74.520805) (xy 145.058477 -74.526908) (xy 145.11247 -74.541024) (xy 145.163833 -74.562851)
			(xy 145.211471 -74.591924) (xy 145.254367 -74.627623) (xy 145.291609 -74.669187) (xy 145.322403 -74.715731)
			(xy 145.346091 -74.766262) (xy 145.362169 -74.819704) (xy 145.370295 -74.874918) (xy 145.370804 -74.902822)
			(xy 145.370295 -74.930726) (xy 145.362169 -74.98594) (xy 145.346091 -75.039382) (xy 145.322403 -75.089913)
			(xy 145.291609 -75.136457) (xy 145.254367 -75.178021) (xy 145.211471 -75.21372) (xy 145.163833 -75.242793)
			(xy 145.11247 -75.26462) (xy 145.058477 -75.278736) (xy 145.003003 -75.284839) (xy 144.947232 -75.282801)
			(xy 144.892353 -75.272664) (xy 144.839533 -75.254645) (xy 144.789901 -75.229127) (xy 144.744513 -75.196655)
			(xy 144.704336 -75.15792) (xy 144.670228 -75.113748) (xy 144.642914 -75.06508) (xy 144.622978 -75.012954)
			(xy 144.610843 -74.958481) (xy 144.60677 -74.902822) (xy 141.917349 -74.902822) (xy 141.912601 -74.935084)
			(xy 141.896533 -74.988491) (xy 141.872861 -75.038988) (xy 141.842088 -75.085501) (xy 141.804871 -75.127038)
			(xy 141.762003 -75.162713) (xy 141.714397 -75.191767) (xy 141.663068 -75.213579) (xy 141.609111 -75.227685)
			(xy 141.553674 -75.233785) (xy 141.49794 -75.231748) (xy 141.443097 -75.221618) (xy 141.390313 -75.203611)
			(xy 141.340713 -75.17811) (xy 141.295355 -75.145659) (xy 141.255206 -75.10695) (xy 141.22112 -75.062807)
			(xy 141.193824 -75.014172) (xy 141.173901 -74.962081) (xy 141.161775 -74.907644) (xy 141.157704 -74.852022)
			(xy 138.478073 -74.852022) (xy 138.478031 -74.852166) (xy 138.455389 -74.901743) (xy 138.425923 -74.947593)
			(xy 138.390232 -74.988784) (xy 138.349041 -75.024475) (xy 138.303191 -75.053941) (xy 138.253614 -75.076583)
			(xy 138.201319 -75.091938) (xy 138.147371 -75.099694) (xy 138.092869 -75.099694) (xy 138.038921 -75.091938)
			(xy 137.986626 -75.076583) (xy 137.937049 -75.053941) (xy 137.891199 -75.024475) (xy 137.850008 -74.988784)
			(xy 137.814317 -74.947593) (xy 137.784851 -74.901743) (xy 137.762209 -74.852166) (xy 137.746854 -74.799871)
			(xy 137.739098 -74.745923) (xy 137.738612 -74.718672) (xy 137.739074 -74.692387) (xy 137.746271 -74.640313)
			(xy 137.760553 -74.589721) (xy 137.781648 -74.54157) (xy 137.809157 -74.496773) (xy 137.842558 -74.456179)
			(xy 137.881219 -74.420557) (xy 137.924406 -74.390584) (xy 137.947654 -74.378312) (xy 137.956798 -74.37374)
			(xy 137.969752 -74.358754) (xy 137.99566 -74.281538) (xy 137.998326 -74.272149) (xy 137.997163 -74.252685)
			(xy 137.993374 -74.243692) (xy 137.99312 -74.24293) (xy 137.992866 -74.242676) (xy 137.98061 -74.216401)
			(xy 137.963271 -74.16108) (xy 137.954524 -74.10377) (xy 137.954004 -74.074782) (xy 137.954004 -74.07402)
			(xy 137.954108 -74.062561) (xy 137.955504 -74.039686) (xy 137.956798 -74.0283) (xy 137.957475 -74.018943)
			(xy 137.952948 -74.000757) (xy 137.942222 -73.98539) (xy 137.9347 -73.979786) (xy 137.847324 -73.921366)
			(xy 137.818622 -73.920096) (xy 137.806176 -73.927208) (xy 137.784693 -73.93885) (xy 137.73939 -73.957162)
			(xy 137.692124 -73.969554) (xy 137.643664 -73.975822) (xy 137.619232 -73.97623) (xy 137.591981 -73.975715)
			(xy 137.538033 -73.967963) (xy 137.485737 -73.952612) (xy 137.436159 -73.929975) (xy 137.390307 -73.900512)
			(xy 137.349114 -73.864824) (xy 137.31342 -73.823637) (xy 137.283951 -73.777789) (xy 137.261307 -73.728213)
			(xy 137.245949 -73.67592) (xy 137.238189 -73.621973) (xy 137.237724 -73.594722) (xy 135.931148 -73.594722)
			(xy 135.931148 -76.324968) (xy 142.31696 -76.324968) (xy 142.321033 -76.269309) (xy 142.333168 -76.214836)
			(xy 142.353104 -76.16271) (xy 142.380418 -76.114042) (xy 142.414526 -76.06987) (xy 142.454703 -76.031135)
			(xy 142.500091 -75.998663) (xy 142.549723 -75.973145) (xy 142.602543 -75.955126) (xy 142.657422 -75.944989)
			(xy 142.713193 -75.942951) (xy 142.768667 -75.949054) (xy 142.82266 -75.96317) (xy 142.874023 -75.984997)
			(xy 142.921661 -76.01407) (xy 142.964557 -76.049769) (xy 143.001799 -76.091333) (xy 143.032593 -76.137877)
			(xy 143.056281 -76.188408) (xy 143.072359 -76.24185) (xy 143.080485 -76.297064) (xy 143.080569 -76.30167)
			(xy 144.371524 -76.30167) (xy 144.371524 -76.24713) (xy 144.379286 -76.193144) (xy 144.394652 -76.140812)
			(xy 144.41731 -76.091201) (xy 144.446798 -76.045319) (xy 144.482516 -76.0041) (xy 144.523736 -75.968385)
			(xy 144.56962 -75.9389) (xy 144.619233 -75.916245) (xy 144.671565 -75.900881) (xy 144.725552 -75.893122)
			(xy 144.752822 -75.89266) (xy 144.782801 -75.893196) (xy 144.842031 -75.902508) (xy 144.899073 -75.920975)
			(xy 144.92605 -75.934062) (xy 144.938048 -75.939701) (xy 144.963973 -75.945206) (xy 144.99044 -75.94384)
			(xy 145.015661 -75.935697) (xy 145.037929 -75.921327) (xy 145.05574 -75.901701) (xy 145.062194 -75.89012)
			(xy 145.074617 -75.867141) (xy 145.104715 -75.824448) (xy 145.140348 -75.786252) (xy 145.180853 -75.753268)
			(xy 145.225473 -75.726108) (xy 145.273377 -75.70528) (xy 145.323672 -75.691173) (xy 145.37542 -75.684048)
			(xy 145.401538 -75.683618) (xy 145.428804 -75.684147) (xy 145.482781 -75.691913) (xy 145.535103 -75.70728)
			(xy 145.580805 -75.728156) (xy 152.583545 -75.728156) (xy 152.583545 -75.673644) (xy 152.591303 -75.619688)
			(xy 152.606662 -75.567386) (xy 152.629308 -75.517801) (xy 152.658781 -75.471945) (xy 152.69448 -75.43075)
			(xy 152.735679 -75.395056) (xy 152.781538 -75.365588) (xy 152.831125 -75.342947) (xy 152.883429 -75.327594)
			(xy 152.937386 -75.319842) (xy 152.964642 -75.319382) (xy 152.992351 -75.319879) (xy 153.047186 -75.327908)
			(xy 153.10028 -75.343789) (xy 153.150516 -75.367189) (xy 153.196836 -75.397614) (xy 153.21788 -75.415648)
			(xy 153.224992 -75.421744) (xy 153.233628 -75.425046) (xy 153.237978 -75.426583) (xy 153.24705 -75.428246)
			(xy 153.251662 -75.428348) (xy 153.318972 -75.428348) (xy 153.323585 -75.428255) (xy 153.332659 -75.426591)
			(xy 153.337006 -75.425046) (xy 153.345642 -75.421744) (xy 153.352754 -75.415648) (xy 153.373797 -75.397614)
			(xy 153.420117 -75.367188) (xy 153.470353 -75.34379) (xy 153.523448 -75.327912) (xy 153.578283 -75.319888)
			(xy 153.633701 -75.319888) (xy 153.688536 -75.327912) (xy 153.741631 -75.34379) (xy 153.791867 -75.367188)
			(xy 153.838187 -75.397614) (xy 153.85923 -75.415648) (xy 153.866342 -75.421744) (xy 153.874978 -75.425046)
			(xy 153.879323 -75.426595) (xy 153.888399 -75.42825) (xy 153.893012 -75.428348) (xy 153.960322 -75.428348)
			(xy 153.964934 -75.428242) (xy 153.974008 -75.426586) (xy 153.978356 -75.425046) (xy 153.986992 -75.421744)
			(xy 153.994104 -75.415648) (xy 154.015147 -75.397614) (xy 154.061467 -75.367188) (xy 154.111703 -75.34379)
			(xy 154.164798 -75.327912) (xy 154.219633 -75.319888) (xy 154.275051 -75.319888) (xy 154.329886 -75.327912)
			(xy 154.382981 -75.34379) (xy 154.433217 -75.367188) (xy 154.479537 -75.397614) (xy 154.50058 -75.415648)
			(xy 154.507692 -75.421744) (xy 154.516328 -75.425046) (xy 154.520678 -75.426583) (xy 154.52975 -75.428246)
			(xy 154.534362 -75.428348) (xy 154.601672 -75.428348) (xy 154.606285 -75.428255) (xy 154.615359 -75.426591)
			(xy 154.619706 -75.425046) (xy 154.628342 -75.421744) (xy 154.635454 -75.415648) (xy 154.6565 -75.397616)
			(xy 154.702817 -75.367187) (xy 154.753053 -75.343786) (xy 154.806148 -75.327905) (xy 154.860983 -75.31988)
			(xy 154.888692 -75.319382) (xy 154.915945 -75.319865) (xy 154.969895 -75.327621) (xy 155.022192 -75.342976)
			(xy 155.071772 -75.365617) (xy 155.117625 -75.395084) (xy 155.158818 -75.430777) (xy 155.194511 -75.471969)
			(xy 155.223979 -75.517821) (xy 155.246622 -75.5674) (xy 155.261978 -75.619697) (xy 155.269735 -75.673647)
			(xy 155.269735 -75.728153) (xy 155.261978 -75.782103) (xy 155.246622 -75.8344) (xy 155.223979 -75.883979)
			(xy 155.194511 -75.929831) (xy 155.158818 -75.971023) (xy 155.117625 -76.006716) (xy 155.071772 -76.036183)
			(xy 155.022192 -76.058824) (xy 154.969895 -76.074179) (xy 154.915945 -76.081935) (xy 154.888692 -76.082398)
			(xy 154.860983 -76.081886) (xy 154.806149 -76.073862) (xy 154.753055 -76.057984) (xy 154.702818 -76.034588)
			(xy 154.656498 -76.004165) (xy 154.635454 -75.986132) (xy 154.628342 -75.980036) (xy 154.619706 -75.976734)
			(xy 154.615361 -75.975184) (xy 154.606285 -75.973529) (xy 154.601672 -75.973432) (xy 154.534362 -75.973432)
			(xy 154.52975 -75.973535) (xy 154.520676 -75.975193) (xy 154.516328 -75.976734) (xy 154.507692 -75.980036)
			(xy 154.50058 -75.986132) (xy 154.479537 -76.004166) (xy 154.433217 -76.034592) (xy 154.382981 -76.05799)
			(xy 154.329886 -76.073868) (xy 154.275051 -76.081892) (xy 154.219633 -76.081892) (xy 154.164798 -76.073868)
			(xy 154.111703 -76.05799) (xy 154.061467 -76.034592) (xy 154.015147 -76.004166) (xy 153.994104 -75.986132)
			(xy 153.986992 -75.980036) (xy 153.978356 -75.976734) (xy 153.974007 -75.975196) (xy 153.964934 -75.973534)
			(xy 153.960322 -75.973432) (xy 153.893012 -75.973432) (xy 153.888399 -75.973522) (xy 153.879325 -75.975188)
			(xy 153.874978 -75.976734) (xy 153.866342 -75.980036) (xy 153.85923 -75.986132) (xy 153.838187 -76.004166)
			(xy 153.791867 -76.034592) (xy 153.741631 -76.05799) (xy 153.688536 -76.073868) (xy 153.633701 -76.081892)
			(xy 153.578283 -76.081892) (xy 153.523448 -76.073868) (xy 153.470353 -76.05799) (xy 153.420117 -76.034592)
			(xy 153.373797 -76.004166) (xy 153.352754 -75.986132) (xy 153.345642 -75.980036) (xy 153.337006 -75.976734)
			(xy 153.332661 -75.975184) (xy 153.323585 -75.973529) (xy 153.318972 -75.973432) (xy 153.251662 -75.973432)
			(xy 153.24705 -75.973535) (xy 153.237976 -75.975193) (xy 153.233628 -75.976734) (xy 153.224992 -75.980036)
			(xy 153.21788 -75.986132) (xy 153.196857 -76.004192) (xy 153.150533 -76.034617) (xy 153.100292 -76.058013)
			(xy 153.047192 -76.073888) (xy 152.992353 -76.081905) (xy 152.964642 -76.082398) (xy 152.937386 -76.081958)
			(xy 152.883429 -76.074206) (xy 152.831125 -76.058853) (xy 152.781538 -76.036212) (xy 152.735679 -76.006744)
			(xy 152.69448 -75.97105) (xy 152.658781 -75.929855) (xy 152.629308 -75.883999) (xy 152.606662 -75.834414)
			(xy 152.591303 -75.782112) (xy 152.583545 -75.728156) (xy 145.580805 -75.728156) (xy 145.584706 -75.729938)
			(xy 145.63058 -75.759423) (xy 145.671791 -75.795136) (xy 145.7075 -75.836351) (xy 145.736981 -75.882228)
			(xy 145.759633 -75.931833) (xy 145.774995 -75.984156) (xy 145.782756 -76.038134) (xy 145.782756 -76.092666)
			(xy 145.774995 -76.146644) (xy 145.759633 -76.198967) (xy 145.736981 -76.248572) (xy 145.7075 -76.294449)
			(xy 145.671791 -76.335664) (xy 145.63058 -76.371377) (xy 145.584706 -76.400862) (xy 145.535103 -76.42352)
			(xy 145.482781 -76.438887) (xy 145.428804 -76.446653) (xy 145.401538 -76.447142) (xy 145.371558 -76.44662)
			(xy 145.312328 -76.437303) (xy 145.255287 -76.418829) (xy 145.22831 -76.40574) (xy 145.216283 -76.400168)
			(xy 145.19037 -76.394653) (xy 145.163911 -76.396006) (xy 145.138697 -76.404136) (xy 145.116431 -76.418493)
			(xy 145.098621 -76.438107) (xy 145.092166 -76.449682) (xy 145.079773 -76.472678) (xy 145.049671 -76.515372)
			(xy 145.014034 -76.553567) (xy 144.973525 -76.586551) (xy 144.9289 -76.613708) (xy 144.880992 -76.634533)
			(xy 144.830693 -76.648637) (xy 144.778941 -76.655756) (xy 144.752822 -76.656184) (xy 144.725552 -76.655678)
			(xy 144.671565 -76.647919) (xy 144.619233 -76.632555) (xy 144.56962 -76.6099) (xy 144.523736 -76.580415)
			(xy 144.482516 -76.5447) (xy 144.446798 -76.503481) (xy 144.41731 -76.457599) (xy 144.394652 -76.407988)
			(xy 144.379286 -76.355656) (xy 144.371524 -76.30167) (xy 143.080569 -76.30167) (xy 143.080994 -76.324968)
			(xy 143.080485 -76.352872) (xy 143.072359 -76.408086) (xy 143.056281 -76.461528) (xy 143.032593 -76.512059)
			(xy 143.001799 -76.558603) (xy 142.964557 -76.600167) (xy 142.921661 -76.635866) (xy 142.874023 -76.664939)
			(xy 142.82266 -76.686766) (xy 142.768667 -76.700882) (xy 142.713193 -76.706985) (xy 142.657422 -76.704947)
			(xy 142.602543 -76.69481) (xy 142.549723 -76.676791) (xy 142.500091 -76.651273) (xy 142.454703 -76.618801)
			(xy 142.414526 -76.580066) (xy 142.380418 -76.535894) (xy 142.353104 -76.487226) (xy 142.333168 -76.4351)
			(xy 142.321033 -76.380627) (xy 142.31696 -76.324968) (xy 135.931148 -76.324968) (xy 135.931148 -80.302862)
			(xy 143.832324 -80.302862) (xy 143.836395 -80.24724) (xy 143.848521 -80.192803) (xy 143.868444 -80.140712)
			(xy 143.89574 -80.092077) (xy 143.929826 -80.047934) (xy 143.969975 -80.009225) (xy 144.015333 -79.976774)
			(xy 144.064933 -79.951273) (xy 144.117717 -79.933266) (xy 144.17256 -79.923136) (xy 144.228294 -79.921099)
			(xy 144.272162 -79.925926) (xy 144.667984 -79.925926) (xy 144.672055 -79.870304) (xy 144.684181 -79.815867)
			(xy 144.704104 -79.763776) (xy 144.7314 -79.715141) (xy 144.765486 -79.670998) (xy 144.805635 -79.632289)
			(xy 144.850993 -79.599838) (xy 144.900593 -79.574337) (xy 144.953377 -79.55633) (xy 145.00822 -79.5462)
			(xy 145.063954 -79.544163) (xy 145.119391 -79.550263) (xy 145.173348 -79.564369) (xy 145.224677 -79.586181)
			(xy 145.272283 -79.615235) (xy 145.315151 -79.65091) (xy 145.352368 -79.692447) (xy 145.383141 -79.73896)
			(xy 145.406813 -79.789457) (xy 145.416018 -79.820053) (xy 152.583585 -79.820053) (xy 152.583585 -79.765547)
			(xy 152.591343 -79.711597) (xy 152.6067 -79.6593) (xy 152.629344 -79.609721) (xy 152.658813 -79.563869)
			(xy 152.694509 -79.522679) (xy 152.735703 -79.486988) (xy 152.781558 -79.457523) (xy 152.831139 -79.434885)
			(xy 152.883438 -79.419534) (xy 152.937389 -79.411782) (xy 152.964642 -79.411322) (xy 152.992352 -79.411809)
			(xy 153.047187 -79.419838) (xy 153.100282 -79.435722) (xy 153.150518 -79.459124) (xy 153.196837 -79.489553)
			(xy 153.21788 -79.507588) (xy 153.224992 -79.513684) (xy 153.233628 -79.516986) (xy 153.237978 -79.51852)
			(xy 153.24705 -79.520185) (xy 153.251662 -79.520288) (xy 153.318972 -79.520288) (xy 153.323585 -79.520193)
			(xy 153.332658 -79.51853) (xy 153.337006 -79.516986) (xy 153.345642 -79.513684) (xy 153.352754 -79.507588)
			(xy 153.373797 -79.489554) (xy 153.420117 -79.459128) (xy 153.470353 -79.43573) (xy 153.523448 -79.419852)
			(xy 153.578283 -79.411828) (xy 153.633701 -79.411828) (xy 153.688536 -79.419852) (xy 153.741631 -79.43573)
			(xy 153.791867 -79.459128) (xy 153.838187 -79.489554) (xy 153.85923 -79.507588) (xy 153.866342 -79.513684)
			(xy 153.874978 -79.516986) (xy 153.879324 -79.518533) (xy 153.888399 -79.520189) (xy 153.893012 -79.520288)
			(xy 153.960322 -79.520288) (xy 153.964934 -79.52018) (xy 153.974008 -79.518525) (xy 153.978356 -79.516986)
			(xy 153.986992 -79.513684) (xy 153.994104 -79.507588) (xy 154.015147 -79.489554) (xy 154.061467 -79.459128)
			(xy 154.111703 -79.43573) (xy 154.164798 -79.419852) (xy 154.219633 -79.411828) (xy 154.275051 -79.411828)
			(xy 154.329886 -79.419852) (xy 154.382981 -79.43573) (xy 154.433217 -79.459128) (xy 154.479537 -79.489554)
			(xy 154.50058 -79.507588) (xy 154.507692 -79.513684) (xy 154.516328 -79.516986) (xy 154.520678 -79.51852)
			(xy 154.52975 -79.520185) (xy 154.534362 -79.520288) (xy 154.601672 -79.520288) (xy 154.606285 -79.520193)
			(xy 154.615358 -79.51853) (xy 154.619706 -79.516986) (xy 154.628342 -79.513684) (xy 154.635454 -79.507588)
			(xy 154.656505 -79.489562) (xy 154.702821 -79.459131) (xy 154.753055 -79.435728) (xy 154.806149 -79.419846)
			(xy 154.860983 -79.41182) (xy 154.888692 -79.411322) (xy 154.915947 -79.411724) (xy 154.969903 -79.419481)
			(xy 155.022206 -79.434838) (xy 155.071792 -79.457481) (xy 155.117649 -79.486952) (xy 155.158846 -79.522648)
			(xy 155.194544 -79.563844) (xy 155.224015 -79.609701) (xy 155.24666 -79.659286) (xy 155.262017 -79.711589)
			(xy 155.269775 -79.765545) (xy 155.269775 -79.820055) (xy 155.262017 -79.874011) (xy 155.24666 -79.926314)
			(xy 155.224015 -79.975899) (xy 155.194544 -80.021756) (xy 155.158846 -80.062952) (xy 155.117649 -80.098648)
			(xy 155.071792 -80.128119) (xy 155.022206 -80.150762) (xy 154.969903 -80.166119) (xy 154.915947 -80.173876)
			(xy 154.888692 -80.174338) (xy 154.860984 -80.173816) (xy 154.806151 -80.165793) (xy 154.753057 -80.149917)
			(xy 154.70282 -80.126523) (xy 154.656499 -80.096103) (xy 154.635454 -80.078072) (xy 154.628342 -80.071976)
			(xy 154.619706 -80.068674) (xy 154.615362 -80.067121) (xy 154.606285 -80.065468) (xy 154.601672 -80.065372)
			(xy 154.534362 -80.065372) (xy 154.52975 -80.065472) (xy 154.520676 -80.067132) (xy 154.516328 -80.068674)
			(xy 154.507692 -80.071976) (xy 154.50058 -80.078072) (xy 154.479537 -80.096106) (xy 154.433217 -80.126532)
			(xy 154.382981 -80.14993) (xy 154.329886 -80.165808) (xy 154.275051 -80.173832) (xy 154.219633 -80.173832)
			(xy 154.164798 -80.165808) (xy 154.111703 -80.14993) (xy 154.061467 -80.126532) (xy 154.015147 -80.096106)
			(xy 153.994104 -80.078072) (xy 153.986992 -80.071976) (xy 153.978356 -80.068674) (xy 153.974008 -80.067134)
			(xy 153.964934 -80.065473) (xy 153.960322 -80.065372) (xy 153.893012 -80.065372) (xy 153.888399 -80.065459)
			(xy 153.879325 -80.067127) (xy 153.874978 -80.068674) (xy 153.866342 -80.071976) (xy 153.85923 -80.078072)
			(xy 153.838187 -80.096106) (xy 153.791867 -80.126532) (xy 153.741631 -80.14993) (xy 153.688536 -80.165808)
			(xy 153.633701 -80.173832) (xy 153.578283 -80.173832) (xy 153.523448 -80.165808) (xy 153.470353 -80.14993)
			(xy 153.420117 -80.126532) (xy 153.373797 -80.096106) (xy 153.352754 -80.078072) (xy 153.345642 -80.071976)
			(xy 153.337006 -80.068674) (xy 153.332662 -80.067121) (xy 153.323585 -80.065468) (xy 153.318972 -80.065372)
			(xy 153.251662 -80.065372) (xy 153.24705 -80.065472) (xy 153.237976 -80.067132) (xy 153.233628 -80.068674)
			(xy 153.224992 -80.071976) (xy 153.21788 -80.078072) (xy 153.196849 -80.096122) (xy 153.150528 -80.126551)
			(xy 153.100289 -80.14995) (xy 153.047191 -80.165826) (xy 152.992353 -80.173844) (xy 152.964642 -80.174338)
			(xy 152.937389 -80.173818) (xy 152.883438 -80.166066) (xy 152.831139 -80.150715) (xy 152.781558 -80.128077)
			(xy 152.735703 -80.098612) (xy 152.694509 -80.062921) (xy 152.658813 -80.021731) (xy 152.629344 -79.975879)
			(xy 152.6067 -79.9263) (xy 152.591343 -79.874003) (xy 152.583585 -79.820053) (xy 145.416018 -79.820053)
			(xy 145.422881 -79.842864) (xy 145.431001 -79.89804) (xy 145.43151 -79.925926) (xy 145.431001 -79.953812)
			(xy 145.422881 -80.008988) (xy 145.406813 -80.062395) (xy 145.383141 -80.112892) (xy 145.352368 -80.159405)
			(xy 145.315151 -80.200942) (xy 145.272283 -80.236617) (xy 145.224677 -80.265671) (xy 145.173348 -80.287483)
			(xy 145.119391 -80.301589) (xy 145.063954 -80.307689) (xy 145.00822 -80.305652) (xy 144.953377 -80.295522)
			(xy 144.900593 -80.277515) (xy 144.850993 -80.252014) (xy 144.805635 -80.219563) (xy 144.765486 -80.180854)
			(xy 144.7314 -80.136711) (xy 144.704104 -80.088076) (xy 144.684181 -80.035985) (xy 144.672055 -79.981548)
			(xy 144.667984 -79.925926) (xy 144.272162 -79.925926) (xy 144.283731 -79.927199) (xy 144.337688 -79.941305)
			(xy 144.389017 -79.963117) (xy 144.436623 -79.992171) (xy 144.479491 -80.027846) (xy 144.516708 -80.069383)
			(xy 144.547481 -80.115896) (xy 144.571153 -80.166393) (xy 144.587221 -80.2198) (xy 144.595341 -80.274976)
			(xy 144.59585 -80.302862) (xy 144.595341 -80.330748) (xy 144.587221 -80.385924) (xy 144.571153 -80.439331)
			(xy 144.547481 -80.489828) (xy 144.516708 -80.536341) (xy 144.479491 -80.577878) (xy 144.436623 -80.613553)
			(xy 144.389017 -80.642607) (xy 144.337688 -80.664419) (xy 144.283731 -80.678525) (xy 144.228294 -80.684625)
			(xy 144.17256 -80.682588) (xy 144.117717 -80.672458) (xy 144.064933 -80.654451) (xy 144.015333 -80.62895)
			(xy 143.969975 -80.596499) (xy 143.929826 -80.55779) (xy 143.89574 -80.513647) (xy 143.868444 -80.465012)
			(xy 143.848521 -80.412921) (xy 143.836395 -80.358484) (xy 143.832324 -80.302862) (xy 135.931148 -80.302862)
			(xy 135.931148 -81.866055) (xy 152.583555 -81.866055) (xy 152.583555 -81.811545) (xy 152.591314 -81.757591)
			(xy 152.606672 -81.705289) (xy 152.629317 -81.655707) (xy 152.658789 -81.609851) (xy 152.694487 -81.568658)
			(xy 152.735685 -81.532964) (xy 152.781543 -81.503497) (xy 152.831129 -81.480857) (xy 152.883432 -81.465505)
			(xy 152.937387 -81.457752) (xy 152.964642 -81.457292) (xy 152.992351 -81.457787) (xy 153.047186 -81.465815)
			(xy 153.10028 -81.481697) (xy 153.150517 -81.505098) (xy 153.196836 -81.535524) (xy 153.21788 -81.553558)
			(xy 153.224992 -81.559654) (xy 153.233628 -81.562956) (xy 153.237979 -81.564489) (xy 153.24705 -81.566155)
			(xy 153.251662 -81.566258) (xy 153.318972 -81.566258) (xy 153.323585 -81.566165) (xy 153.332658 -81.5645)
			(xy 153.337006 -81.562956) (xy 153.345642 -81.559654) (xy 153.352754 -81.553558) (xy 153.373797 -81.535524)
			(xy 153.420117 -81.505098) (xy 153.470353 -81.4817) (xy 153.523448 -81.465822) (xy 153.578283 -81.457798)
			(xy 153.633701 -81.457798) (xy 153.688536 -81.465822) (xy 153.741631 -81.4817) (xy 153.791867 -81.505098)
			(xy 153.838187 -81.535524) (xy 153.85923 -81.553558) (xy 153.866342 -81.559654) (xy 153.874978 -81.562956)
			(xy 153.879325 -81.564502) (xy 153.8884 -81.566159) (xy 153.893012 -81.566258) (xy 153.960322 -81.566258)
			(xy 153.964934 -81.566151) (xy 153.974008 -81.564496) (xy 153.978356 -81.562956) (xy 153.986992 -81.559654)
			(xy 153.994104 -81.553558) (xy 154.015147 -81.535524) (xy 154.061467 -81.505098) (xy 154.111703 -81.4817)
			(xy 154.164798 -81.465822) (xy 154.219633 -81.457798) (xy 154.275051 -81.457798) (xy 154.329886 -81.465822)
			(xy 154.382981 -81.4817) (xy 154.433217 -81.505098) (xy 154.479537 -81.535524) (xy 154.50058 -81.553558)
			(xy 154.507692 -81.559654) (xy 154.516328 -81.562956) (xy 154.520679 -81.564489) (xy 154.52975 -81.566155)
			(xy 154.534362 -81.566258) (xy 154.601672 -81.566258) (xy 154.606285 -81.566165) (xy 154.615358 -81.5645)
			(xy 154.619706 -81.562956) (xy 154.628342 -81.559654) (xy 154.635454 -81.553558) (xy 154.656501 -81.535528)
			(xy 154.702818 -81.505098) (xy 154.753054 -81.481697) (xy 154.806148 -81.465815) (xy 154.860983 -81.45779)
			(xy 154.888692 -81.457292) (xy 154.915945 -81.457755) (xy 154.969897 -81.465511) (xy 155.022196 -81.480866)
			(xy 155.071777 -81.503508) (xy 155.117631 -81.532976) (xy 155.158825 -81.56867) (xy 155.194519 -81.609863)
			(xy 155.223988 -81.655716) (xy 155.246631 -81.705297) (xy 155.261987 -81.757595) (xy 155.269745 -81.811547)
			(xy 155.269745 -81.866053) (xy 155.261987 -81.920005) (xy 155.246631 -81.972303) (xy 155.223988 -82.021884)
			(xy 155.194519 -82.067737) (xy 155.158825 -82.10893) (xy 155.117631 -82.144624) (xy 155.071777 -82.174092)
			(xy 155.022196 -82.196734) (xy 154.969897 -82.212089) (xy 154.915945 -82.219845) (xy 154.888692 -82.220308)
			(xy 154.860983 -82.219793) (xy 154.80615 -82.21177) (xy 154.753055 -82.195892) (xy 154.702819 -82.172496)
			(xy 154.656498 -82.142074) (xy 154.635454 -82.124042) (xy 154.628342 -82.117946) (xy 154.619706 -82.114644)
			(xy 154.615361 -82.113094) (xy 154.606285 -82.111439) (xy 154.601672 -82.111342) (xy 154.534362 -82.111342)
			(xy 154.52975 -82.111444) (xy 154.520676 -82.113102) (xy 154.516328 -82.114644) (xy 154.507692 -82.117946)
			(xy 154.50058 -82.124042) (xy 154.479537 -82.142076) (xy 154.433217 -82.172502) (xy 154.382981 -82.1959)
			(xy 154.329886 -82.211778) (xy 154.275051 -82.219802) (xy 154.219633 -82.219802) (xy 154.164798 -82.211778)
			(xy 154.111703 -82.1959) (xy 154.061467 -82.172502) (xy 154.015147 -82.142076) (xy 153.994104 -82.124042)
			(xy 153.986992 -82.117946) (xy 153.978356 -82.114644) (xy 153.974007 -82.113107) (xy 153.964934 -82.111444)
			(xy 153.960322 -82.111342) (xy 153.893012 -82.111342) (xy 153.888399 -82.111431) (xy 153.879325 -82.113098)
			(xy 153.874978 -82.114644) (xy 153.866342 -82.117946) (xy 153.85923 -82.124042) (xy 153.838187 -82.142076)
			(xy 153.791867 -82.172502) (xy 153.741631 -82.1959) (xy 153.688536 -82.211778) (xy 153.633701 -82.219802)
			(xy 153.578283 -82.219802) (xy 153.523448 -82.211778) (xy 153.470353 -82.1959) (xy 153.420117 -82.172502)
			(xy 153.373797 -82.142076) (xy 153.352754 -82.124042) (xy 153.345642 -82.117946) (xy 153.337006 -82.114644)
			(xy 153.332661 -82.113094) (xy 153.323585 -82.111439) (xy 153.318972 -82.111342) (xy 153.251662 -82.111342)
			(xy 153.24705 -82.111444) (xy 153.237976 -82.113102) (xy 153.233628 -82.114644) (xy 153.224992 -82.117946)
			(xy 153.21788 -82.124042) (xy 153.196859 -82.142103) (xy 153.150534 -82.172528) (xy 153.100292 -82.195924)
			(xy 153.047192 -82.211798) (xy 152.992353 -82.219815) (xy 152.964642 -82.220308) (xy 152.937387 -82.219848)
			(xy 152.883432 -82.212095) (xy 152.831129 -82.196743) (xy 152.781543 -82.174103) (xy 152.735685 -82.144636)
			(xy 152.694487 -82.108942) (xy 152.658789 -82.067749) (xy 152.629317 -82.021893) (xy 152.606672 -81.972311)
			(xy 152.591314 -81.920009) (xy 152.583555 -81.866055) (xy 135.931148 -81.866055) (xy 135.931148 -82.423508)
			(xy 143.419574 -82.423508) (xy 143.423645 -82.367886) (xy 143.435771 -82.313449) (xy 143.455694 -82.261358)
			(xy 143.48299 -82.212723) (xy 143.517076 -82.16858) (xy 143.557225 -82.129871) (xy 143.602583 -82.09742)
			(xy 143.652183 -82.071919) (xy 143.704967 -82.053912) (xy 143.75981 -82.043782) (xy 143.815544 -82.041745)
			(xy 143.870981 -82.047845) (xy 143.924938 -82.061951) (xy 143.976267 -82.083763) (xy 144.023873 -82.112817)
			(xy 144.066741 -82.148492) (xy 144.103958 -82.190029) (xy 144.134731 -82.236542) (xy 144.158403 -82.287039)
			(xy 144.174471 -82.340446) (xy 144.182591 -82.395622) (xy 144.1831 -82.423508) (xy 144.182591 -82.451394)
			(xy 144.174471 -82.50657) (xy 144.158403 -82.559977) (xy 144.134731 -82.610474) (xy 144.103958 -82.656987)
			(xy 144.066741 -82.698524) (xy 144.023873 -82.734199) (xy 143.976267 -82.763253) (xy 143.924938 -82.785065)
			(xy 143.870981 -82.799171) (xy 143.815544 -82.805271) (xy 143.75981 -82.803234) (xy 143.704967 -82.793104)
			(xy 143.652183 -82.775097) (xy 143.602583 -82.749596) (xy 143.557225 -82.717145) (xy 143.517076 -82.678436)
			(xy 143.48299 -82.634293) (xy 143.455694 -82.585658) (xy 143.435771 -82.533567) (xy 143.423645 -82.47913)
			(xy 143.419574 -82.423508) (xy 135.931148 -82.423508) (xy 135.931148 -83.527138) (xy 135.931579 -83.537204)
			(xy 135.939309 -83.555794) (xy 135.946134 -83.563206) (xy 135.966962 -83.584034) (xy 135.974361 -83.590878)
			(xy 135.99296 -83.5986) (xy 136.00303 -83.59902)
		)
		(stroke
			(width 0)
			(type solid)
		)
		(fill yes)
		(layer "In11.Cu")
		(net "GND")
	)
	(gr_poly
		(pts
			(xy 446.470786 -26.371296) (xy 446.481118 -26.370806) (xy 446.500118 -26.362675) (xy 446.507616 -26.355548)
			(xy 446.535548 -26.326762) (xy 446.595784 -26.273789) (xy 446.660545 -26.226456) (xy 446.729306 -26.185148)
			(xy 446.801508 -26.150199) (xy 446.876564 -26.121895) (xy 446.953863 -26.100465) (xy 447.032778 -26.086082)
			(xy 447.112668 -26.078866) (xy 447.152776 -26.078434) (xy 447.192548 -26.078877) (xy 447.271776 -26.08598)
			(xy 447.350053 -26.100122) (xy 447.426757 -26.12119) (xy 447.501276 -26.149016) (xy 447.537332 -26.16581)
			(xy 447.547833 -26.170142) (xy 447.570519 -26.170142) (xy 447.58102 -26.16581) (xy 447.617074 -26.149011)
			(xy 447.691588 -26.121165) (xy 447.768292 -26.100089) (xy 447.846572 -26.085952) (xy 447.925803 -26.078868)
			(xy 447.965576 -26.078434) (xy 448.005684 -26.078875) (xy 448.085574 -26.086095) (xy 448.16449 -26.100477)
			(xy 448.24179 -26.121905) (xy 448.316848 -26.150205) (xy 448.389053 -26.185147) (xy 448.457819 -26.226448)
			(xy 448.522588 -26.273772) (xy 448.582833 -26.326734) (xy 448.610736 -26.355548) (xy 448.618214 -26.362703)
			(xy 448.637227 -26.370826) (xy 448.647566 -26.371296) (xy 450.726302 -26.371296) (xy 450.734684 -26.370534)
			(xy 450.742291 -26.369023) (xy 450.756131 -26.362043) (xy 450.761862 -26.356818) (xy 451.312026 -25.806654)
			(xy 451.319676 -25.798023) (xy 451.327202 -25.776256) (xy 451.326504 -25.764744) (xy 451.315328 -25.673304)
			(xy 451.302628 -25.654) (xy 451.292468 -25.647904) (xy 451.256988 -25.62605) (xy 451.189851 -25.576679)
			(xy 451.127627 -25.521243) (xy 451.070863 -25.46023) (xy 451.020055 -25.394173) (xy 450.97565 -25.323654)
			(xy 450.938037 -25.249289) (xy 450.907546 -25.171731) (xy 450.884445 -25.091662) (xy 450.868935 -25.009782)
			(xy 450.861153 -24.92681) (xy 450.860668 -24.885142) (xy 450.861126 -24.844037) (xy 450.868708 -24.762178)
			(xy 450.88381 -24.681367) (xy 450.906304 -24.602295) (xy 450.935999 -24.525636) (xy 450.97264 -24.452043)
			(xy 451.015915 -24.382145) (xy 451.065454 -24.316539) (xy 451.120836 -24.255783) (xy 451.181588 -24.200397)
			(xy 451.247191 -24.150852) (xy 451.317085 -24.107572) (xy 451.390675 -24.070925) (xy 451.467333 -24.041225)
			(xy 451.546403 -24.018725) (xy 451.627213 -24.003617) (xy 451.709071 -23.996029) (xy 451.750176 -23.995634)
			(xy 451.791842 -23.996124) (xy 451.874807 -24.003923) (xy 451.95668 -24.019447) (xy 452.036742 -24.042559)
			(xy 452.114292 -24.073056) (xy 452.188651 -24.110671) (xy 452.259166 -24.155075) (xy 452.32522 -24.205878)
			(xy 452.386234 -24.262636) (xy 452.441673 -24.32485) (xy 452.491051 -24.391976) (xy 452.512938 -24.427434)
			(xy 452.519034 -24.437594) (xy 452.538338 -24.450294) (xy 452.629778 -24.46147) (xy 452.641308 -24.462313)
			(xy 452.663136 -24.454771) (xy 452.671688 -24.446992) (xy 453.59828 -23.5204) (xy 453.605128 -23.513002)
			(xy 453.612866 -23.494404) (xy 453.613266 -23.484332) (xy 453.613266 -23.328884) (xy 453.612675 -23.317689)
			(xy 453.603182 -23.297409) (xy 453.594978 -23.289768) (xy 453.526398 -23.232618) (xy 453.504808 -23.226776)
			(xy 453.493632 -23.228808) (xy 453.477007 -23.231571) (xy 453.443429 -23.234496) (xy 453.426576 -23.23465)
			(xy 453.400403 -23.234198) (xy 453.348551 -23.227005) (xy 453.298168 -23.212798) (xy 453.250198 -23.191844)
			(xy 453.205538 -23.164535) (xy 453.165026 -23.131383) (xy 453.146922 -23.112476) (xy 453.140187 -23.105886)
			(xy 453.123247 -23.097674) (xy 453.113902 -23.096474) (xy 453.083168 -23.093934) (xy 453.073416 -23.093492)
			(xy 453.054737 -23.099109) (xy 453.046846 -23.104856) (xy 453.012962 -23.131534) (xy 452.940908 -23.178932)
			(xy 452.864604 -23.21913) (xy 452.784766 -23.251753) (xy 452.702145 -23.276494) (xy 452.617517 -23.293119)
			(xy 452.531677 -23.301474) (xy 452.488554 -23.30196) (xy 452.443439 -23.301422) (xy 452.353669 -23.292311)
			(xy 452.265286 -23.274147) (xy 452.179199 -23.247117) (xy 452.137526 -23.229824) (xy 452.128382 -23.22576)
			(xy 452.109078 -23.225252) (xy 452.025004 -23.256494) (xy 452.010526 -23.269194) (xy 452.006208 -23.278084)
			(xy 451.99406 -23.301688) (xy 451.964212 -23.345586) (xy 451.928569 -23.384925) (xy 451.887817 -23.418944)
			(xy 451.842745 -23.446988) (xy 451.794221 -23.468515) (xy 451.743181 -23.483109) (xy 451.690612 -23.490489)
			(xy 451.66407 -23.490936) (xy 451.635527 -23.490401) (xy 451.57908 -23.481894) (xy 451.524529 -23.465073)
			(xy 451.473093 -23.440315) (xy 451.425918 -23.408171) (xy 451.384057 -23.369359) (xy 451.348444 -23.324744)
			(xy 451.319875 -23.275323) (xy 451.298985 -23.222197) (xy 451.286242 -23.166553) (xy 451.283578 -23.13813)
			(xy 451.282562 -23.123398) (xy 451.264782 -23.099776) (xy 451.150736 -23.05685) (xy 451.12178 -23.062946)
			(xy 451.111112 -23.07336) (xy 451.079972 -23.103177) (xy 451.01285 -23.157295) (xy 450.940806 -23.204663)
			(xy 450.864515 -23.244835) (xy 450.784693 -23.277434) (xy 450.702092 -23.302154) (xy 450.617485 -23.318762)
			(xy 450.531669 -23.327104) (xy 450.488558 -23.327614) (xy 450.446633 -23.327129) (xy 450.363155 -23.319234)
			(xy 450.28079 -23.303518) (xy 450.20027 -23.280121) (xy 450.122309 -23.24925) (xy 450.0476 -23.211179)
			(xy 449.976804 -23.166247) (xy 449.910551 -23.114852) (xy 449.849429 -23.057449) (xy 449.793981 -22.99455)
			(xy 449.744697 -22.926712) (xy 449.702016 -22.854536) (xy 449.666317 -22.778665) (xy 449.637917 -22.69977)
			(xy 449.617067 -22.618554) (xy 449.603953 -22.535735) (xy 449.598691 -22.45205) (xy 449.601327 -22.368241)
			(xy 449.611839 -22.285052) (xy 449.630133 -22.203221) (xy 449.656047 -22.123475) (xy 449.689351 -22.046522)
			(xy 449.729748 -21.973045) (xy 449.776881 -21.903695) (xy 449.830331 -21.839088) (xy 449.889624 -21.779799)
			(xy 449.954233 -21.726352) (xy 450.023586 -21.679223) (xy 450.097065 -21.638829) (xy 450.17402 -21.60553)
			(xy 450.253767 -21.579621) (xy 450.335599 -21.561331) (xy 450.418789 -21.550824) (xy 450.502598 -21.548192)
			(xy 450.586283 -21.553458) (xy 450.669101 -21.566577) (xy 450.750316 -21.587431) (xy 450.829209 -21.615836)
			(xy 450.905079 -21.651539) (xy 450.977252 -21.694223) (xy 451.045088 -21.743511) (xy 451.107984 -21.798963)
			(xy 451.165383 -21.860088) (xy 451.216775 -21.926343) (xy 451.261703 -21.997141) (xy 451.29977 -22.071853)
			(xy 451.330636 -22.149816) (xy 451.354029 -22.230337) (xy 451.36974 -22.312702) (xy 451.377631 -22.396181)
			(xy 451.378066 -22.438106) (xy 451.37773 -22.474063) (xy 451.371961 -22.545743) (xy 451.360422 -22.616724)
			(xy 451.352158 -22.65172) (xy 451.348602 -22.665944) (xy 451.358 -22.694138) (xy 451.452742 -22.770592)
			(xy 451.482206 -22.77364) (xy 451.495668 -22.767036) (xy 451.509957 -22.760186) (xy 451.53946 -22.748613)
			(xy 451.554596 -22.743922) (xy 451.563994 -22.741128) (xy 451.579234 -22.72919) (xy 451.623938 -22.651466)
			(xy 451.626478 -22.632162) (xy 451.624192 -22.62251) (xy 451.616175 -22.588081) (xy 451.604987 -22.518275)
			(xy 451.599381 -22.447801) (xy 451.599046 -22.412452) (xy 451.599523 -22.37135) (xy 451.607111 -22.289497)
			(xy 451.62222 -22.208694) (xy 451.644719 -22.129629) (xy 451.674416 -22.052977) (xy 451.711059 -21.979393)
			(xy 451.754335 -21.909502) (xy 451.803875 -21.843903) (xy 451.859255 -21.783154) (xy 451.920004 -21.727773)
			(xy 451.985604 -21.678234) (xy 452.055494 -21.634958) (xy 452.129079 -21.598315) (xy 452.205731 -21.568618)
			(xy 452.284796 -21.546119) (xy 452.365599 -21.531011) (xy 452.447452 -21.523423) (xy 452.488554 -21.522944)
			(xy 452.530721 -21.523441) (xy 452.614678 -21.531426) (xy 452.697501 -21.54732) (xy 452.77845 -21.57098)
			(xy 452.856796 -21.602193) (xy 452.931837 -21.640679) (xy 453.0029 -21.686094) (xy 453.036432 -21.711666)
			(xy 453.047862 -21.720556) (xy 453.076564 -21.723604) (xy 453.185022 -21.671026) (xy 453.200516 -21.646642)
			(xy 453.200516 -21.63191) (xy 453.201132 -21.591024) (xy 453.208938 -21.509621) (xy 453.224183 -21.429278)
			(xy 453.246737 -21.350674) (xy 453.276411 -21.274471) (xy 453.312952 -21.201313) (xy 453.33412 -21.166328)
			(xy 453.339089 -21.157401) (xy 453.342232 -21.137229) (xy 453.340216 -21.127212) (xy 453.331958 -21.092259)
			(xy 453.320433 -21.021361) (xy 453.314662 -20.949766) (xy 453.314308 -20.913852) (xy 453.314858 -20.868757)
			(xy 453.323979 -20.779031) (xy 453.342134 -20.690688) (xy 453.369136 -20.604636) (xy 453.404707 -20.521758)
			(xy 453.448482 -20.442905) (xy 453.47382 -20.405598) (xy 453.479324 -20.396853) (xy 453.483492 -20.376635)
			(xy 453.479352 -20.356411) (xy 453.47382 -20.347686) (xy 453.456103 -20.321716) (xy 453.423943 -20.26769)
			(xy 453.409558 -20.239736) (xy 453.405236 -20.231907) (xy 453.392218 -20.219663) (xy 453.37579 -20.212624)
			(xy 453.366886 -20.211796) (xy 453.324895 -20.208911) (xy 453.241685 -20.196204) (xy 453.160048 -20.175693)
			(xy 453.080714 -20.147562) (xy 453.004391 -20.112062) (xy 452.931764 -20.069511) (xy 452.863481 -20.02029)
			(xy 452.800154 -19.964838) (xy 452.742348 -19.903651) (xy 452.69058 -19.837277) (xy 452.645315 -19.76631)
			(xy 452.606956 -19.691384) (xy 452.575846 -19.61317) (xy 452.552264 -19.532366) (xy 452.536422 -19.449696)
			(xy 452.528459 -19.365899) (xy 452.527924 -19.323812) (xy 452.528384 -19.282709) (xy 452.535968 -19.200854)
			(xy 452.551072 -19.120047) (xy 452.573569 -19.040979) (xy 452.603265 -18.964325) (xy 452.639907 -18.890737)
			(xy 452.683183 -18.820844) (xy 452.732724 -18.755243) (xy 452.788106 -18.694492) (xy 452.848858 -18.639111)
			(xy 452.914461 -18.589572) (xy 452.984354 -18.546298) (xy 453.057943 -18.509657) (xy 453.134598 -18.479962)
			(xy 453.213667 -18.457468) (xy 453.294473 -18.442365) (xy 453.376329 -18.434783) (xy 453.417432 -18.434304)
			(xy 453.442699 -18.434512) (xy 453.493148 -18.437436) (xy 453.51827 -18.440146) (xy 453.530096 -18.44089)
			(xy 453.552336 -18.432799) (xy 453.560942 -18.424652) (xy 453.59701 -18.388838) (xy 453.604352 -18.381369)
			(xy 453.612763 -18.362214) (xy 453.613266 -18.351754) (xy 453.613266 -16.74368) (xy 453.605646 -16.724884)
			(xy 453.59828 -16.717772) (xy 451.023228 -14.14272) (xy 451.015826 -14.135883) (xy 450.997228 -14.128171)
			(xy 450.98716 -14.127734) (xy 450.23405 -14.127734) (xy 450.224308 -14.12817) (xy 450.206241 -14.135464)
			(xy 450.192231 -14.149005) (xy 450.187822 -14.157706) (xy 450.169896 -14.196284) (xy 450.127702 -14.270158)
			(xy 450.078646 -14.339665) (xy 450.023177 -14.404169) (xy 449.961801 -14.463082) (xy 449.89508 -14.515863)
			(xy 449.823623 -14.562032) (xy 449.748084 -14.601166) (xy 449.669153 -14.632907) (xy 449.587551 -14.656966)
			(xy 449.504025 -14.673122) (xy 449.419337 -14.681227) (xy 449.3768 -14.681708) (xy 449.332888 -14.681174)
			(xy 449.245491 -14.672516) (xy 449.159371 -14.655293) (xy 449.075366 -14.629673) (xy 448.994292 -14.595906)
			(xy 448.916938 -14.554318) (xy 448.844055 -14.505316) (xy 448.809872 -14.477746) (xy 448.802736 -14.472372)
			(xy 448.785909 -14.466416) (xy 448.76806 -14.466562) (xy 448.75958 -14.469364) (xy 448.718601 -14.48434)
			(xy 448.634373 -14.507113) (xy 448.591432 -14.51483) (xy 448.5823 -14.516879) (xy 448.566278 -14.526518)
			(xy 448.56019 -14.533626) (xy 448.54114 -14.557502) (xy 448.535886 -14.564833) (xy 448.530424 -14.58201)
			(xy 448.530472 -14.59103) (xy 448.530726 -14.607032) (xy 448.53024 -14.634301) (xy 448.522478 -14.688285)
			(xy 448.507113 -14.740615) (xy 448.484456 -14.790225) (xy 448.45497 -14.836106) (xy 448.419255 -14.877323)
			(xy 448.378038 -14.913038) (xy 448.332157 -14.942524) (xy 448.282547 -14.965181) (xy 448.230217 -14.980546)
			(xy 448.176233 -14.988308) (xy 448.121695 -14.988308) (xy 448.067711 -14.980546) (xy 448.015381 -14.965181)
			(xy 447.965771 -14.942524) (xy 447.91989 -14.913038) (xy 447.878673 -14.877323) (xy 447.842958 -14.836106)
			(xy 447.813472 -14.790225) (xy 447.790815 -14.740615) (xy 447.77545 -14.688285) (xy 447.767688 -14.634301)
			(xy 447.767202 -14.607032) (xy 447.767669 -14.579671) (xy 447.775475 -14.525509) (xy 447.790931 -14.473016)
			(xy 447.813722 -14.423266) (xy 447.828162 -14.400022) (xy 447.828162 -14.399768) (xy 447.83273 -14.391955)
			(xy 447.836596 -14.374285) (xy 447.834105 -14.35637) (xy 447.830194 -14.348206) (xy 447.787522 -14.270228)
			(xy 447.782869 -14.262404) (xy 447.769177 -14.250428) (xy 447.752165 -14.243986) (xy 447.743072 -14.243558)
			(xy 447.323464 -14.243558) (xy 447.313558 -14.244574) (xy 447.313304 -14.244574) (xy 447.301679 -14.247561)
			(xy 447.282873 -14.262422) (xy 447.277236 -14.273022) (xy 447.232532 -14.370304) (xy 447.236596 -14.399514)
			(xy 447.245994 -14.410944) (xy 447.263037 -14.431722) (xy 447.291741 -14.477154) (xy 447.313803 -14.526157)
			(xy 447.328789 -14.577765) (xy 447.336404 -14.630963) (xy 447.336926 -14.657832) (xy 447.33644 -14.685101)
			(xy 447.328678 -14.739085) (xy 447.313313 -14.791415) (xy 447.290656 -14.841025) (xy 447.26117 -14.886906)
			(xy 447.225455 -14.928123) (xy 447.184238 -14.963838) (xy 447.138357 -14.993324) (xy 447.088747 -15.015981)
			(xy 447.036417 -15.031346) (xy 446.982433 -15.039108) (xy 446.927895 -15.039108) (xy 446.873911 -15.031346)
			(xy 446.821581 -15.015981) (xy 446.771971 -14.993324) (xy 446.72609 -14.963838) (xy 446.684873 -14.928123)
			(xy 446.649158 -14.886906) (xy 446.619672 -14.841025) (xy 446.597015 -14.791415) (xy 446.58165 -14.739085)
			(xy 446.573888 -14.685101) (xy 446.573402 -14.657832) (xy 446.573868 -14.630956) (xy 446.581435 -14.577739)
			(xy 446.596408 -14.526114) (xy 446.618491 -14.477107) (xy 446.647244 -14.431691) (xy 446.664334 -14.410944)
			(xy 446.673732 -14.399514) (xy 446.677796 -14.370304) (xy 446.633092 -14.273022) (xy 446.62745 -14.262432)
			(xy 446.608638 -14.247586) (xy 446.597024 -14.244574) (xy 446.591944 -14.243558) (xy 442.381894 -14.243558)
			(xy 442.3537 -14.266926) (xy 442.350144 -14.285214) (xy 442.341899 -14.326975) (xy 442.318461 -14.408814)
			(xy 442.287311 -14.488039) (xy 442.248734 -14.563926) (xy 442.203083 -14.635779) (xy 442.150774 -14.702941)
			(xy 442.092288 -14.764799) (xy 442.02816 -14.820784) (xy 441.958975 -14.870387) (xy 441.885367 -14.913152)
			(xy 441.80801 -14.948688) (xy 441.727611 -14.97667) (xy 441.644907 -14.996842) (xy 441.560654 -15.00902)
			(xy 441.475622 -15.013092) (xy 441.39059 -15.00902) (xy 441.306337 -14.996842) (xy 441.223633 -14.97667)
			(xy 441.143234 -14.948688) (xy 441.065877 -14.913152) (xy 440.992269 -14.870387) (xy 440.923084 -14.820784)
			(xy 440.858956 -14.764799) (xy 440.80047 -14.702941) (xy 440.748161 -14.635779) (xy 440.70251 -14.563926)
			(xy 440.663933 -14.488039) (xy 440.632783 -14.408814) (xy 440.609345 -14.326975) (xy 440.6011 -14.285214)
			(xy 440.597544 -14.266926) (xy 440.56935 -14.243558) (xy 440.489086 -14.243558) (xy 440.479018 -14.243985)
			(xy 440.460423 -14.25171) (xy 440.453018 -14.258544) (xy 439.693812 -15.01775) (xy 439.686417 -15.024604)
			(xy 439.667818 -15.03235) (xy 439.657744 -15.032736) (xy 438.433718 -15.032736) (xy 438.423655 -15.033175)
			(xy 438.405076 -15.040914) (xy 438.39765 -15.047722) (xy 438.027572 -15.4178) (xy 438.020206 -15.424912)
			(xy 438.012586 -15.443708) (xy 438.012586 -16.328136) (xy 438.173876 -16.328136) (xy 438.174345 -16.300766)
			(xy 438.182159 -16.246586) (xy 438.197646 -16.194082) (xy 438.220488 -16.144335) (xy 438.250214 -16.098369)
			(xy 438.267856 -16.077438) (xy 438.273952 -16.070326) (xy 438.280302 -16.053308) (xy 438.280302 -15.967964)
			(xy 438.273952 -15.950946) (xy 438.267856 -15.943834) (xy 438.250212 -15.922906) (xy 438.220502 -15.876931)
			(xy 438.197668 -15.827183) (xy 438.182178 -15.774681) (xy 438.17435 -15.720505) (xy 438.173876 -15.693136)
			(xy 438.174362 -15.665885) (xy 438.182118 -15.611937) (xy 438.197473 -15.559642) (xy 438.220115 -15.510065)
			(xy 438.249581 -15.464215) (xy 438.285272 -15.423024) (xy 438.326463 -15.387333) (xy 438.372313 -15.357867)
			(xy 438.42189 -15.335225) (xy 438.474185 -15.31987) (xy 438.528133 -15.312114) (xy 438.582635 -15.312114)
			(xy 438.636583 -15.31987) (xy 438.688878 -15.335225) (xy 438.738455 -15.357867) (xy 438.784305 -15.387333)
			(xy 438.825496 -15.423024) (xy 438.861187 -15.464215) (xy 438.890653 -15.510065) (xy 438.913295 -15.559642)
			(xy 438.92865 -15.611937) (xy 438.936406 -15.665885) (xy 438.936892 -15.693136) (xy 438.936449 -15.720507)
			(xy 438.928626 -15.774687) (xy 438.913132 -15.827191) (xy 438.890285 -15.876937) (xy 438.860555 -15.922903)
			(xy 438.842912 -15.943834) (xy 438.836816 -15.950946) (xy 438.830466 -15.967964) (xy 438.830466 -16.053308)
			(xy 438.836816 -16.070326) (xy 438.842912 -16.077438) (xy 438.860537 -16.098381) (xy 438.890251 -16.144351)
			(xy 438.913089 -16.194096) (xy 438.928584 -16.246594) (xy 438.936416 -16.300768) (xy 438.936892 -16.328136)
			(xy 438.936406 -16.355387) (xy 438.92865 -16.409335) (xy 438.913295 -16.46163) (xy 438.890653 -16.511207)
			(xy 438.861187 -16.557057) (xy 438.825496 -16.598248) (xy 438.784305 -16.633939) (xy 438.738455 -16.663405)
			(xy 438.688878 -16.686047) (xy 438.636583 -16.701402) (xy 438.582635 -16.709158) (xy 438.528133 -16.709158)
			(xy 438.474185 -16.701402) (xy 438.42189 -16.686047) (xy 438.372313 -16.663405) (xy 438.326463 -16.633939)
			(xy 438.285272 -16.598248) (xy 438.249581 -16.557057) (xy 438.220115 -16.511207) (xy 438.197473 -16.46163)
			(xy 438.182118 -16.409335) (xy 438.174362 -16.355387) (xy 438.173876 -16.328136) (xy 438.012586 -16.328136)
			(xy 438.012586 -16.754856) (xy 438.012884 -16.762728) (xy 438.017672 -16.777727) (xy 438.021984 -16.78432)
			(xy 438.037543 -16.806399) (xy 438.066267 -16.85215) (xy 438.079388 -16.87576) (xy 438.084214 -16.884904)
			(xy 438.093612 -16.89227) (xy 438.102879 -16.898895) (xy 438.125042 -16.904024) (xy 438.136284 -16.902176)
			(xy 438.137046 -16.902176) (xy 438.157965 -16.897668) (xy 438.200485 -16.892826) (xy 438.221882 -16.892524)
			(xy 438.222644 -16.892524) (xy 438.249891 -16.893013) (xy 438.303829 -16.900774) (xy 438.356114 -16.916132)
			(xy 438.405682 -16.938773) (xy 438.451523 -16.968238) (xy 438.492704 -17.003927) (xy 438.528388 -17.045113)
			(xy 438.557848 -17.090957) (xy 438.580484 -17.140527) (xy 438.595835 -17.192814) (xy 438.60359 -17.246753)
			(xy 438.60359 -17.301247) (xy 438.595835 -17.355186) (xy 438.580484 -17.407473) (xy 438.557848 -17.457043)
			(xy 438.528388 -17.502887) (xy 438.492704 -17.544073) (xy 438.451523 -17.579762) (xy 438.405682 -17.609227)
			(xy 438.356114 -17.631868) (xy 438.303829 -17.647226) (xy 438.249891 -17.654987) (xy 438.222644 -17.65554)
			(xy 438.221882 -17.65554) (xy 438.205866 -17.655385) (xy 438.173947 -17.652711) (xy 438.158128 -17.650206)
			(xy 438.147115 -17.64887) (xy 438.125719 -17.654636) (xy 438.108729 -17.668861) (xy 438.103518 -17.678654)
			(xy 438.08594 -17.715083) (xy 438.04511 -17.784914) (xy 438.021984 -17.8181) (xy 438.017652 -17.824684)
			(xy 438.01286 -17.839688) (xy 438.012586 -17.847564) (xy 438.012586 -19.21256) (xy 440.97321 -19.21256)
			(xy 440.973709 -19.185191) (xy 440.981518 -19.131013) (xy 440.997 -19.07851) (xy 441.019834 -19.028763)
			(xy 441.049552 -18.982795) (xy 441.06719 -18.961862) (xy 441.073286 -18.95475) (xy 441.079636 -18.937732)
			(xy 441.079636 -18.852388) (xy 441.073286 -18.83537) (xy 441.06719 -18.828258) (xy 441.049563 -18.807316)
			(xy 441.01985 -18.761346) (xy 440.997012 -18.711601) (xy 440.981518 -18.659102) (xy 440.973686 -18.604928)
			(xy 440.97321 -18.57756) (xy 440.973696 -18.550309) (xy 440.981452 -18.496361) (xy 440.996807 -18.444066)
			(xy 441.019449 -18.394489) (xy 441.048915 -18.348639) (xy 441.084606 -18.307448) (xy 441.125797 -18.271757)
			(xy 441.171647 -18.242291) (xy 441.221224 -18.219649) (xy 441.273519 -18.204294) (xy 441.327467 -18.196538)
			(xy 441.381969 -18.196538) (xy 441.435917 -18.204294) (xy 441.488212 -18.219649) (xy 441.537789 -18.242291)
			(xy 441.583639 -18.271757) (xy 441.62483 -18.307448) (xy 441.660521 -18.348639) (xy 441.689987 -18.394489)
			(xy 441.712629 -18.444066) (xy 441.714312 -18.449798) (xy 445.622934 -18.449798) (xy 445.623464 -18.407497)
			(xy 445.631504 -18.323278) (xy 445.647501 -18.240202) (xy 445.67131 -18.159019) (xy 445.702718 -18.080463)
			(xy 445.74144 -18.005243) (xy 445.787127 -17.934037) (xy 445.839365 -17.867489) (xy 445.897685 -17.8062)
			(xy 445.961558 -17.750723) (xy 446.030408 -17.701559) (xy 446.103615 -17.659151) (xy 446.141856 -17.641062)
			(xy 446.150289 -17.636862) (xy 446.163463 -17.623409) (xy 446.16751 -17.6149) (xy 446.179448 -17.586706)
			(xy 446.182664 -17.578162) (xy 446.183442 -17.559935) (xy 446.180972 -17.551146) (xy 446.172351 -17.522576)
			(xy 446.163032 -17.463634) (xy 446.16243 -17.433798) (xy 446.162916 -17.406547) (xy 446.170672 -17.352599)
			(xy 446.186027 -17.300304) (xy 446.208669 -17.250727) (xy 446.238135 -17.204877) (xy 446.273826 -17.163686)
			(xy 446.315017 -17.127995) (xy 446.360867 -17.098529) (xy 446.410444 -17.075887) (xy 446.462739 -17.060532)
			(xy 446.516687 -17.052776) (xy 446.571189 -17.052776) (xy 446.625137 -17.060532) (xy 446.677432 -17.075887)
			(xy 446.727009 -17.098529) (xy 446.772859 -17.127995) (xy 446.81405 -17.163686) (xy 446.849741 -17.204877)
			(xy 446.879207 -17.250727) (xy 446.901849 -17.300304) (xy 446.917204 -17.352599) (xy 446.92496 -17.406547)
			(xy 446.925446 -17.433798) (xy 446.925094 -17.457641) (xy 446.919171 -17.504959) (xy 446.907403 -17.55117)
			(xy 446.89903 -17.573498) (xy 446.896011 -17.582106) (xy 446.89562 -17.600329) (xy 446.898268 -17.609058)
			(xy 446.908428 -17.63776) (xy 446.911978 -17.646502) (xy 446.92422 -17.660835) (xy 446.932304 -17.6657)
			(xy 446.970503 -17.686808) (xy 447.043045 -17.735339) (xy 447.110485 -17.790741) (xy 447.172173 -17.852483)
			(xy 447.227518 -17.91997) (xy 447.275986 -17.992554) (xy 447.317111 -18.069536) (xy 447.350499 -18.150176)
			(xy 447.375827 -18.233699) (xy 447.392852 -18.319301) (xy 447.401411 -18.406159) (xy 447.40195 -18.449798)
			(xy 447.401446 -18.492146) (xy 447.393395 -18.57646) (xy 447.377366 -18.659626) (xy 447.353505 -18.740893)
			(xy 447.322026 -18.819523) (xy 447.283215 -18.894804) (xy 447.237425 -18.966056) (xy 447.185069 -19.032632)
			(xy 447.126621 -19.09393) (xy 447.062611 -19.149395) (xy 446.993619 -19.198524) (xy 446.920269 -19.240873)
			(xy 446.843226 -19.276057) (xy 446.763187 -19.303759) (xy 446.680878 -19.323727) (xy 446.597043 -19.33578)
			(xy 446.512442 -19.339811) (xy 446.427841 -19.33578) (xy 446.344006 -19.323727) (xy 446.261697 -19.303759)
			(xy 446.181658 -19.276057) (xy 446.104615 -19.240873) (xy 446.031265 -19.198524) (xy 445.962273 -19.149395)
			(xy 445.898263 -19.09393) (xy 445.839815 -19.032632) (xy 445.787459 -18.966056) (xy 445.741669 -18.894804)
			(xy 445.702858 -18.819523) (xy 445.671379 -18.740893) (xy 445.647518 -18.659626) (xy 445.631489 -18.57646)
			(xy 445.623438 -18.492146) (xy 445.622934 -18.449798) (xy 441.714312 -18.449798) (xy 441.727984 -18.496361)
			(xy 441.73574 -18.550309) (xy 441.736226 -18.57756) (xy 441.735755 -18.60493) (xy 441.727941 -18.65911)
			(xy 441.712454 -18.711614) (xy 441.689613 -18.761361) (xy 441.659888 -18.807327) (xy 441.642246 -18.828258)
			(xy 441.63615 -18.83537) (xy 441.6298 -18.852388) (xy 441.6298 -18.937732) (xy 441.63615 -18.95475)
			(xy 441.642246 -18.961862) (xy 441.659872 -18.982805) (xy 441.689588 -19.028774) (xy 441.712427 -19.078518)
			(xy 441.727921 -19.131017) (xy 441.735751 -19.185191) (xy 441.736226 -19.21256) (xy 441.73574 -19.239811)
			(xy 441.727984 -19.293759) (xy 441.712629 -19.346054) (xy 441.689987 -19.395631) (xy 441.660521 -19.441481)
			(xy 441.62483 -19.482672) (xy 441.583639 -19.518363) (xy 441.537789 -19.547829) (xy 441.488212 -19.570471)
			(xy 441.435917 -19.585826) (xy 441.381969 -19.593582) (xy 441.327467 -19.593582) (xy 441.273519 -19.585826)
			(xy 441.221224 -19.570471) (xy 441.171647 -19.547829) (xy 441.125797 -19.518363) (xy 441.084606 -19.482672)
			(xy 441.048915 -19.441481) (xy 441.019449 -19.395631) (xy 440.996807 -19.346054) (xy 440.981452 -19.293759)
			(xy 440.973696 -19.239811) (xy 440.97321 -19.21256) (xy 438.012586 -19.21256) (xy 438.012586 -20.73656)
			(xy 440.97321 -20.73656) (xy 440.973709 -20.709191) (xy 440.981518 -20.655013) (xy 440.997 -20.60251)
			(xy 441.019834 -20.552763) (xy 441.049552 -20.506795) (xy 441.06719 -20.485862) (xy 441.073286 -20.47875)
			(xy 441.079636 -20.461732) (xy 441.079636 -20.376388) (xy 441.073286 -20.35937) (xy 441.06719 -20.352258)
			(xy 441.049563 -20.331316) (xy 441.01985 -20.285346) (xy 440.997012 -20.235601) (xy 440.981518 -20.183102)
			(xy 440.973686 -20.128928) (xy 440.97321 -20.10156) (xy 440.973696 -20.074309) (xy 440.981452 -20.020361)
			(xy 440.996807 -19.968066) (xy 441.019449 -19.918489) (xy 441.048915 -19.872639) (xy 441.084606 -19.831448)
			(xy 441.125797 -19.795757) (xy 441.171647 -19.766291) (xy 441.221224 -19.743649) (xy 441.273519 -19.728294)
			(xy 441.327467 -19.720538) (xy 441.381969 -19.720538) (xy 441.435917 -19.728294) (xy 441.488212 -19.743649)
			(xy 441.537789 -19.766291) (xy 441.583639 -19.795757) (xy 441.62483 -19.831448) (xy 441.660521 -19.872639)
			(xy 441.689987 -19.918489) (xy 441.712629 -19.968066) (xy 441.727984 -20.020361) (xy 441.73574 -20.074309)
			(xy 441.736226 -20.10156) (xy 441.735755 -20.12893) (xy 441.727941 -20.18311) (xy 441.712454 -20.235614)
			(xy 441.703681 -20.254722) (xy 446.285618 -20.254722) (xy 446.289689 -20.1991) (xy 446.301815 -20.144663)
			(xy 446.321738 -20.092572) (xy 446.349034 -20.043937) (xy 446.38312 -19.999794) (xy 446.423269 -19.961085)
			(xy 446.468627 -19.928634) (xy 446.518227 -19.903133) (xy 446.571011 -19.885126) (xy 446.625854 -19.874996)
			(xy 446.681588 -19.872959) (xy 446.737025 -19.879059) (xy 446.790982 -19.893165) (xy 446.842311 -19.914977)
			(xy 446.889917 -19.944031) (xy 446.932785 -19.979706) (xy 446.970002 -20.021243) (xy 447.000775 -20.067756)
			(xy 447.024447 -20.118253) (xy 447.040515 -20.17166) (xy 447.048635 -20.226836) (xy 447.049144 -20.254722)
			(xy 447.048635 -20.282608) (xy 447.040515 -20.337784) (xy 447.024447 -20.391191) (xy 447.005072 -20.432522)
			(xy 447.937128 -20.432522) (xy 447.937613 -20.405439) (xy 447.945246 -20.351813) (xy 447.960391 -20.299807)
			(xy 447.982742 -20.250467) (xy 448.01185 -20.204787) (xy 448.047129 -20.163684) (xy 448.087869 -20.127988)
			(xy 448.13325 -20.098415) (xy 448.182359 -20.075562) (xy 448.208146 -20.06727) (xy 448.219068 -20.063968)
			(xy 448.235832 -20.048982) (xy 448.275202 -19.956272) (xy 448.27444 -19.93392) (xy 448.269106 -19.92376)
			(xy 448.250322 -19.886049) (xy 448.219172 -19.807764) (xy 448.195571 -19.726882) (xy 448.17973 -19.64413)
			(xy 448.171792 -19.56025) (xy 448.171316 -19.518122) (xy 448.171744 -19.476362) (xy 448.179588 -19.393211)
			(xy 448.195191 -19.311162) (xy 448.218416 -19.230936) (xy 448.249057 -19.15324) (xy 448.286846 -19.078758)
			(xy 448.331448 -19.008145) (xy 448.382473 -18.942023) (xy 448.43947 -18.880975) (xy 448.501938 -18.825537)
			(xy 448.569327 -18.776199) (xy 448.641044 -18.733393) (xy 448.716457 -18.697498) (xy 448.755516 -18.682716)
			(xy 448.763756 -18.679388) (xy 448.777379 -18.667992) (xy 448.78629 -18.652628) (xy 448.789419 -18.635144)
			(xy 448.788282 -18.626328) (xy 448.782214 -18.58884) (xy 448.775726 -18.513171) (xy 448.775328 -18.475198)
			(xy 448.77575 -18.434094) (xy 448.783336 -18.352236) (xy 448.798442 -18.271427) (xy 448.82094 -18.192357)
			(xy 448.850638 -18.1157) (xy 448.887283 -18.042111) (xy 448.930561 -17.972216) (xy 448.980104 -17.906614)
			(xy 449.035489 -17.845862) (xy 449.096243 -17.79048) (xy 449.161848 -17.74094) (xy 449.231744 -17.697664)
			(xy 449.305335 -17.661023) (xy 449.381993 -17.631328) (xy 449.461064 -17.608834) (xy 449.541874 -17.593731)
			(xy 449.623732 -17.586149) (xy 449.664836 -17.58569) (xy 449.706215 -17.586191) (xy 449.788614 -17.59389)
			(xy 449.869941 -17.609209) (xy 449.949494 -17.632015) (xy 450.026586 -17.662111) (xy 450.100548 -17.699237)
			(xy 450.170743 -17.743072) (xy 450.236563 -17.793237) (xy 450.29744 -17.849298) (xy 450.352846 -17.910772)
			(xy 450.402304 -17.977125) (xy 450.445385 -18.047785) (xy 450.481717 -18.122141) (xy 450.510986 -18.19955)
			(xy 450.532939 -18.279343) (xy 450.540628 -18.320004) (xy 450.543168 -18.334228) (xy 450.562218 -18.355564)
			(xy 450.676264 -18.390362) (xy 450.70395 -18.38325) (xy 450.713856 -18.372836) (xy 450.731887 -18.354686)
			(xy 450.771988 -18.322913) (xy 450.815976 -18.296786) (xy 450.863061 -18.276771) (xy 450.912398 -18.263229)
			(xy 450.963103 -18.256402) (xy 450.988684 -18.255996) (xy 451.015938 -18.25645) (xy 451.069891 -18.264205)
			(xy 451.122191 -18.27956) (xy 451.171774 -18.302202) (xy 451.21763 -18.33167) (xy 451.258825 -18.367364)
			(xy 451.29452 -18.408558) (xy 451.32399 -18.454412) (xy 451.346634 -18.503994) (xy 451.361991 -18.556293)
			(xy 451.369749 -18.610246) (xy 451.369749 -18.664754) (xy 451.361991 -18.718707) (xy 451.346634 -18.771006)
			(xy 451.32399 -18.820588) (xy 451.29452 -18.866442) (xy 451.258825 -18.907636) (xy 451.21763 -18.94333)
			(xy 451.171774 -18.972798) (xy 451.122191 -18.99544) (xy 451.069891 -19.010795) (xy 451.015938 -19.01855)
			(xy 450.988684 -19.019012) (xy 450.960115 -19.018478) (xy 450.903615 -19.009975) (xy 450.849017 -18.993132)
			(xy 450.797545 -18.968326) (xy 450.750354 -18.936115) (xy 450.708501 -18.897218) (xy 450.672924 -18.852509)
			(xy 450.65823 -18.828004) (xy 450.650864 -18.815558) (xy 450.625718 -18.801842) (xy 450.506592 -18.807938)
			(xy 450.483224 -18.824194) (xy 450.477382 -18.837402) (xy 450.458738 -18.877865) (xy 450.414508 -18.955209)
			(xy 450.362763 -19.027739) (xy 450.304022 -19.09473) (xy 450.238874 -19.155508) (xy 450.167972 -19.209465)
			(xy 450.092029 -19.256058) (xy 450.011806 -19.29482) (xy 449.970144 -19.310604) (xy 449.961952 -19.314034)
			(xy 449.948328 -19.325396) (xy 449.939404 -19.340727) (xy 449.936254 -19.358185) (xy 449.937378 -19.366992)
			(xy 449.943448 -19.404479) (xy 449.949935 -19.480149) (xy 449.950332 -19.518122) (xy 449.949794 -19.560947)
			(xy 449.941575 -19.646201) (xy 449.925195 -19.730269) (xy 449.900806 -19.812373) (xy 449.868636 -19.891751)
			(xy 449.828981 -19.967667) (xy 449.782209 -20.039418) (xy 449.728754 -20.106339) (xy 449.669111 -20.167809)
			(xy 449.603833 -20.223259) (xy 449.533526 -20.272174) (xy 449.496434 -20.293584) (xy 449.486741 -20.29966)
			(xy 449.473594 -20.318348) (xy 449.469859 -20.34089) (xy 449.472558 -20.352004) (xy 449.479572 -20.377919)
			(xy 449.48709 -20.431078) (xy 449.487544 -20.457922) (xy 449.487027 -20.486356) (xy 449.478608 -20.542596)
			(xy 449.47078 -20.569936) (xy 449.468401 -20.578822) (xy 449.469497 -20.597172) (xy 449.477019 -20.613945)
			(xy 449.483226 -20.620736) (xy 449.513551 -20.651948) (xy 449.568612 -20.719344) (xy 449.616825 -20.791797)
			(xy 449.657727 -20.868615) (xy 449.690927 -20.949061) (xy 449.716108 -21.032367) (xy 449.733028 -21.117735)
			(xy 449.741526 -21.204348) (xy 449.742052 -21.247862) (xy 449.741548 -21.29021) (xy 449.733497 -21.374524)
			(xy 449.717468 -21.45769) (xy 449.693607 -21.538957) (xy 449.662128 -21.617587) (xy 449.623317 -21.692868)
			(xy 449.577527 -21.76412) (xy 449.525171 -21.830696) (xy 449.466723 -21.891994) (xy 449.402713 -21.947459)
			(xy 449.333721 -21.996588) (xy 449.260371 -22.038937) (xy 449.183328 -22.074121) (xy 449.103289 -22.101823)
			(xy 449.02098 -22.121791) (xy 448.937145 -22.133844) (xy 448.852544 -22.137875) (xy 448.767943 -22.133844)
			(xy 448.684108 -22.121791) (xy 448.601799 -22.101823) (xy 448.52176 -22.074121) (xy 448.444717 -22.038937)
			(xy 448.371367 -21.996588) (xy 448.302375 -21.947459) (xy 448.238365 -21.891994) (xy 448.179917 -21.830696)
			(xy 448.127561 -21.76412) (xy 448.081771 -21.692868) (xy 448.04296 -21.617587) (xy 448.011481 -21.538957)
			(xy 447.98762 -21.45769) (xy 447.971591 -21.374524) (xy 447.96354 -21.29021) (xy 447.963036 -21.247862)
			(xy 447.963596 -21.201892) (xy 447.973081 -21.110442) (xy 447.991946 -21.020458) (xy 448.019989 -20.932899)
			(xy 448.056911 -20.848699) (xy 448.079114 -20.808442) (xy 448.083099 -20.800629) (xy 448.086084 -20.783358)
			(xy 448.084956 -20.77466) (xy 448.079876 -20.74545) (xy 448.078056 -20.7372) (xy 448.06989 -20.722424)
			(xy 448.063874 -20.716494) (xy 448.044309 -20.698314) (xy 448.009915 -20.657458) (xy 447.981555 -20.612204)
			(xy 447.959785 -20.563436) (xy 447.945029 -20.512109) (xy 447.937577 -20.459225) (xy 447.937128 -20.432522)
			(xy 447.005072 -20.432522) (xy 447.000775 -20.441688) (xy 446.970002 -20.488201) (xy 446.932785 -20.529738)
			(xy 446.889917 -20.565413) (xy 446.842311 -20.594467) (xy 446.790982 -20.616279) (xy 446.737025 -20.630385)
			(xy 446.681588 -20.636485) (xy 446.625854 -20.634448) (xy 446.571011 -20.624318) (xy 446.518227 -20.606311)
			(xy 446.468627 -20.58081) (xy 446.423269 -20.548359) (xy 446.38312 -20.50965) (xy 446.349034 -20.465507)
			(xy 446.321738 -20.416872) (xy 446.301815 -20.364781) (xy 446.289689 -20.310344) (xy 446.285618 -20.254722)
			(xy 441.703681 -20.254722) (xy 441.689613 -20.285361) (xy 441.659888 -20.331327) (xy 441.642246 -20.352258)
			(xy 441.63615 -20.35937) (xy 441.6298 -20.376388) (xy 441.6298 -20.461732) (xy 441.63615 -20.47875)
			(xy 441.642246 -20.485862) (xy 441.659872 -20.506805) (xy 441.689588 -20.552774) (xy 441.712427 -20.602518)
			(xy 441.727921 -20.655017) (xy 441.735751 -20.709191) (xy 441.736226 -20.73656) (xy 441.73574 -20.763811)
			(xy 441.727984 -20.817759) (xy 441.712629 -20.870054) (xy 441.689987 -20.919631) (xy 441.660521 -20.965481)
			(xy 441.62483 -21.006672) (xy 441.583639 -21.042363) (xy 441.537789 -21.071829) (xy 441.488212 -21.094471)
			(xy 441.435917 -21.109826) (xy 441.381969 -21.117582) (xy 441.327467 -21.117582) (xy 441.273519 -21.109826)
			(xy 441.221224 -21.094471) (xy 441.171647 -21.071829) (xy 441.125797 -21.042363) (xy 441.084606 -21.006672)
			(xy 441.048915 -20.965481) (xy 441.019449 -20.919631) (xy 440.996807 -20.870054) (xy 440.981452 -20.817759)
			(xy 440.973696 -20.763811) (xy 440.97321 -20.73656) (xy 438.012586 -20.73656) (xy 438.012586 -21.247862)
			(xy 446.286888 -21.247862) (xy 446.290959 -21.19224) (xy 446.303085 -21.137803) (xy 446.323008 -21.085712)
			(xy 446.350304 -21.037077) (xy 446.38439 -20.992934) (xy 446.424539 -20.954225) (xy 446.469897 -20.921774)
			(xy 446.519497 -20.896273) (xy 446.572281 -20.878266) (xy 446.627124 -20.868136) (xy 446.682858 -20.866099)
			(xy 446.738295 -20.872199) (xy 446.792252 -20.886305) (xy 446.843581 -20.908117) (xy 446.891187 -20.937171)
			(xy 446.934055 -20.972846) (xy 446.971272 -21.014383) (xy 447.002045 -21.060896) (xy 447.025717 -21.111393)
			(xy 447.041785 -21.1648) (xy 447.049905 -21.219976) (xy 447.050414 -21.247862) (xy 447.049905 -21.275748)
			(xy 447.041785 -21.330924) (xy 447.025717 -21.384331) (xy 447.002045 -21.434828) (xy 446.971272 -21.481341)
			(xy 446.934055 -21.522878) (xy 446.891187 -21.558553) (xy 446.843581 -21.587607) (xy 446.792252 -21.609419)
			(xy 446.738295 -21.623525) (xy 446.682858 -21.629625) (xy 446.627124 -21.627588) (xy 446.572281 -21.617458)
			(xy 446.519497 -21.599451) (xy 446.469897 -21.57395) (xy 446.424539 -21.541499) (xy 446.38439 -21.50279)
			(xy 446.350304 -21.458647) (xy 446.323008 -21.410012) (xy 446.303085 -21.357921) (xy 446.290959 -21.303484)
			(xy 446.286888 -21.247862) (xy 438.012586 -21.247862) (xy 438.012586 -22.136862) (xy 446.287398 -22.136862)
			(xy 446.287842 -22.10961) (xy 446.295604 -22.05566) (xy 446.310965 -22.003364) (xy 446.333611 -21.953786)
			(xy 446.363081 -21.907936) (xy 446.398777 -21.866746) (xy 446.439971 -21.831055) (xy 446.485825 -21.801589)
			(xy 446.535405 -21.778949) (xy 446.587703 -21.763595) (xy 446.641653 -21.755839) (xy 446.668906 -21.755354)
			(xy 446.6965 -21.755882) (xy 446.75111 -21.763847) (xy 446.804003 -21.779595) (xy 446.854077 -21.802798)
			(xy 446.900285 -21.832972) (xy 446.941665 -21.869488) (xy 446.977354 -21.911583) (xy 447.006607 -21.95838)
			(xy 447.018156 -21.983446) (xy 447.022313 -21.991779) (xy 447.035482 -22.004929) (xy 447.04381 -22.0091)
			(xy 447.07175 -22.0218) (xy 447.080736 -22.025401) (xy 447.100058 -22.02632) (xy 447.109342 -22.023578)
			(xy 447.144444 -22.011855) (xy 447.216166 -21.99359) (xy 447.289157 -21.981341) (xy 447.362912 -21.975191)
			(xy 447.399918 -21.97481) (xy 447.441842 -21.975294) (xy 447.525318 -21.983187) (xy 447.607681 -21.9989)
			(xy 447.688199 -22.022294) (xy 447.766159 -22.053162) (xy 447.840868 -22.09123) (xy 447.911662 -22.136159)
			(xy 447.977915 -22.187551) (xy 448.039037 -22.24495) (xy 448.094486 -22.307846) (xy 448.14377 -22.375681)
			(xy 448.186451 -22.447854) (xy 448.222151 -22.523722) (xy 448.250553 -22.602614) (xy 448.271404 -22.683828)
			(xy 448.284521 -22.766644) (xy 448.289785 -22.850327) (xy 448.287151 -22.934134) (xy 448.276641 -23.017321)
			(xy 448.25835 -23.099149) (xy 448.232439 -23.178894) (xy 448.199138 -23.255846) (xy 448.158744 -23.329322)
			(xy 448.111614 -23.398672) (xy 448.058167 -23.463278) (xy 447.998878 -23.522567) (xy 447.934272 -23.576014)
			(xy 447.864922 -23.623144) (xy 447.791446 -23.663538) (xy 447.714494 -23.696839) (xy 447.634749 -23.72275)
			(xy 447.552921 -23.741041) (xy 447.469734 -23.751551) (xy 447.385927 -23.754185) (xy 447.302244 -23.748921)
			(xy 447.219428 -23.735804) (xy 447.138214 -23.714953) (xy 447.059322 -23.686551) (xy 446.983454 -23.650851)
			(xy 446.911281 -23.60817) (xy 446.843446 -23.558886) (xy 446.78055 -23.503437) (xy 446.723151 -23.442315)
			(xy 446.671759 -23.376062) (xy 446.62683 -23.305268) (xy 446.588762 -23.230559) (xy 446.557894 -23.152599)
			(xy 446.5345 -23.072081) (xy 446.518787 -22.989718) (xy 446.510894 -22.906242) (xy 446.51041 -22.864318)
			(xy 446.511084 -22.815684) (xy 446.521725 -22.719) (xy 446.542849 -22.624054) (xy 446.557908 -22.577806)
			(xy 446.560613 -22.568504) (xy 446.559556 -22.549176) (xy 446.555876 -22.540214) (xy 446.542922 -22.512274)
			(xy 446.538643 -22.504008) (xy 446.525365 -22.490985) (xy 446.517014 -22.486874) (xy 446.491816 -22.475349)
			(xy 446.444717 -22.446166) (xy 446.402334 -22.410478) (xy 446.365558 -22.369035) (xy 446.335162 -22.32271)
			(xy 446.311786 -22.272476) (xy 446.29592 -22.219389) (xy 446.287898 -22.164565) (xy 446.287398 -22.136862)
			(xy 438.012586 -22.136862) (xy 438.012586 -22.839172) (xy 438.013041 -22.849012) (xy 438.020466 -22.867237)
			(xy 438.034227 -22.881305) (xy 438.043066 -22.885654) (xy 438.082344 -22.903263) (xy 438.157619 -22.94502)
			(xy 438.228509 -22.993854) (xy 438.29435 -23.049307) (xy 438.354527 -23.110861) (xy 438.408476 -23.17794)
			(xy 438.455694 -23.249916) (xy 438.495738 -23.326117) (xy 438.528234 -23.40583) (xy 438.552879 -23.488309)
			(xy 438.569441 -23.572782) (xy 438.569958 -23.5781) (xy 441.09303 -23.5781) (xy 441.09706 -23.493493)
			(xy 441.109115 -23.409651) (xy 441.129085 -23.327336) (xy 441.156789 -23.247291) (xy 441.191976 -23.170243)
			(xy 441.234328 -23.096888) (xy 441.283461 -23.027891) (xy 441.338931 -22.963876) (xy 441.400234 -22.905425)
			(xy 441.466816 -22.853065) (xy 441.538073 -22.807272) (xy 441.613361 -22.76846) (xy 441.691997 -22.73698)
			(xy 441.77327 -22.713117) (xy 441.856442 -22.697088) (xy 441.940762 -22.689038) (xy 441.983114 -22.68855)
			(xy 442.025557 -22.689042) (xy 442.110058 -22.69713) (xy 442.193403 -22.713231) (xy 442.274836 -22.737198)
			(xy 442.353615 -22.768813) (xy 442.391546 -22.787864) (xy 442.40271 -22.792845) (xy 442.427118 -22.792845)
			(xy 442.438282 -22.787864) (xy 442.476212 -22.768812) (xy 442.554991 -22.737195) (xy 442.636424 -22.713228)
			(xy 442.71977 -22.697128) (xy 442.804271 -22.689042) (xy 442.846714 -22.68855) (xy 442.88906 -22.689138)
			(xy 442.973369 -22.69719) (xy 443.05653 -22.713219) (xy 443.137791 -22.737081) (xy 443.216416 -22.768559)
			(xy 443.291693 -22.807368) (xy 443.36294 -22.853156) (xy 443.429513 -22.90551) (xy 443.490807 -22.963955)
			(xy 443.546268 -23.027961) (xy 443.595394 -23.09695) (xy 443.637739 -23.170296) (xy 443.672921 -23.247335)
			(xy 443.700621 -23.327369) (xy 443.720588 -23.409674) (xy 443.732641 -23.493504) (xy 443.736671 -23.5781)
			(xy 443.732641 -23.662696) (xy 443.720588 -23.746526) (xy 443.709328 -23.792942) (xy 448.243958 -23.792942)
			(xy 448.248029 -23.73732) (xy 448.260155 -23.682883) (xy 448.280078 -23.630792) (xy 448.307374 -23.582157)
			(xy 448.34146 -23.538014) (xy 448.381609 -23.499305) (xy 448.426967 -23.466854) (xy 448.476567 -23.441353)
			(xy 448.529351 -23.423346) (xy 448.584194 -23.413216) (xy 448.639928 -23.411179) (xy 448.695365 -23.417279)
			(xy 448.749322 -23.431385) (xy 448.800651 -23.453197) (xy 448.848257 -23.482251) (xy 448.891125 -23.517926)
			(xy 448.928342 -23.559463) (xy 448.959115 -23.605976) (xy 448.982787 -23.656473) (xy 448.998855 -23.70988)
			(xy 449.006975 -23.765056) (xy 449.007484 -23.792942) (xy 449.006975 -23.820828) (xy 448.998855 -23.876004)
			(xy 448.982787 -23.929411) (xy 448.959115 -23.979908) (xy 448.928342 -24.026421) (xy 448.891125 -24.067958)
			(xy 448.848257 -24.103633) (xy 448.800651 -24.132687) (xy 448.749322 -24.154499) (xy 448.695365 -24.168605)
			(xy 448.639928 -24.174705) (xy 448.584194 -24.172668) (xy 448.529351 -24.162538) (xy 448.476567 -24.144531)
			(xy 448.426967 -24.11903) (xy 448.381609 -24.086579) (xy 448.34146 -24.04787) (xy 448.307374 -24.003727)
			(xy 448.280078 -23.955092) (xy 448.260155 -23.903001) (xy 448.248029 -23.848564) (xy 448.243958 -23.792942)
			(xy 443.709328 -23.792942) (xy 443.700621 -23.828831) (xy 443.672921 -23.908865) (xy 443.637739 -23.985904)
			(xy 443.595394 -24.05925) (xy 443.546268 -24.128239) (xy 443.490807 -24.192245) (xy 443.429513 -24.25069)
			(xy 443.36294 -24.303044) (xy 443.291693 -24.348832) (xy 443.216416 -24.387641) (xy 443.137791 -24.419119)
			(xy 443.05653 -24.442981) (xy 442.973369 -24.45901) (xy 442.88906 -24.467062) (xy 442.846714 -24.467566)
			(xy 442.804271 -24.467061) (xy 442.719771 -24.458976) (xy 442.636426 -24.442878) (xy 442.554993 -24.418914)
			(xy 442.476213 -24.387301) (xy 442.438282 -24.368252) (xy 442.427118 -24.363271) (xy 442.40271 -24.363271)
			(xy 442.391546 -24.368252) (xy 442.353611 -24.387295) (xy 442.274834 -24.418913) (xy 442.193402 -24.442882)
			(xy 442.110057 -24.458984) (xy 442.025557 -24.467073) (xy 441.983114 -24.467566) (xy 441.940762 -24.467162)
			(xy 441.856442 -24.459112) (xy 441.77327 -24.443083) (xy 441.691997 -24.41922) (xy 441.613361 -24.38774)
			(xy 441.538073 -24.348928) (xy 441.466816 -24.303135) (xy 441.400234 -24.250775) (xy 441.338931 -24.192324)
			(xy 441.283461 -24.128309) (xy 441.234328 -24.059312) (xy 441.191976 -23.985957) (xy 441.156789 -23.908909)
			(xy 441.129085 -23.828864) (xy 441.109115 -23.746549) (xy 441.09706 -23.662707) (xy 441.09303 -23.5781)
			(xy 438.569958 -23.5781) (xy 438.577765 -23.658461) (xy 438.578244 -23.701502) (xy 438.577728 -23.744324)
			(xy 438.569486 -23.829572) (xy 438.553088 -23.913633) (xy 438.528685 -23.995728) (xy 438.496504 -24.075097)
			(xy 438.456844 -24.151005) (xy 438.41007 -24.22275) (xy 438.356616 -24.289666) (xy 438.296978 -24.351135)
			(xy 438.231707 -24.406586) (xy 438.161409 -24.455507) (xy 438.124346 -24.476964) (xy 438.113932 -24.482806)
			(xy 438.100724 -24.502364) (xy 438.088024 -24.594566) (xy 438.087036 -24.606346) (xy 438.094575 -24.628723)
			(xy 438.102502 -24.637492) (xy 438.954672 -25.489662) (xy 445.226438 -25.489662) (xy 445.230509 -25.43404)
			(xy 445.242635 -25.379603) (xy 445.262558 -25.327512) (xy 445.289854 -25.278877) (xy 445.32394 -25.234734)
			(xy 445.364089 -25.196025) (xy 445.409447 -25.163574) (xy 445.459047 -25.138073) (xy 445.511831 -25.120066)
			(xy 445.566674 -25.109936) (xy 445.622408 -25.107899) (xy 445.677845 -25.113999) (xy 445.731802 -25.128105)
			(xy 445.783131 -25.149917) (xy 445.830737 -25.178971) (xy 445.873605 -25.214646) (xy 445.910822 -25.256183)
			(xy 445.941595 -25.302696) (xy 445.965267 -25.353193) (xy 445.981335 -25.4066) (xy 445.989455 -25.461776)
			(xy 445.989964 -25.489662) (xy 445.989455 -25.517548) (xy 445.981335 -25.572724) (xy 445.965267 -25.626131)
			(xy 445.941595 -25.676628) (xy 445.910822 -25.723141) (xy 445.873605 -25.764678) (xy 445.830737 -25.800353)
			(xy 445.783131 -25.829407) (xy 445.731802 -25.851219) (xy 445.677845 -25.865325) (xy 445.622408 -25.871425)
			(xy 445.566674 -25.869388) (xy 445.511831 -25.859258) (xy 445.459047 -25.841251) (xy 445.409447 -25.81575)
			(xy 445.364089 -25.783299) (xy 445.32394 -25.74459) (xy 445.289854 -25.700447) (xy 445.262558 -25.651812)
			(xy 445.242635 -25.599721) (xy 445.230509 -25.545284) (xy 445.226438 -25.489662) (xy 438.954672 -25.489662)
			(xy 439.82132 -26.35631) (xy 439.828715 -26.363163) (xy 439.847314 -26.370905) (xy 439.857388 -26.371296)
		)
		(stroke
			(width 0)
			(type solid)
		)
		(fill yes)
		(layer "In11.Cu")
		(net "P12V_OCP_SFF")
	)
	(gr_poly
		(pts
			(xy 261.0612 -294.728138) (xy 261.071269 -294.727713) (xy 261.089867 -294.719992) (xy 261.097268 -294.713152)
			(xy 261.997698 -293.812722) (xy 262.004532 -293.805319) (xy 262.012238 -293.786721) (xy 262.012684 -293.776654)
			(xy 262.012684 -256.099056) (xy 262.012252 -256.08899) (xy 262.004525 -256.070398) (xy 261.997698 -256.062988)
			(xy 259.903214 -253.968504) (xy 259.895811 -253.961671) (xy 259.877213 -253.953967) (xy 259.867146 -253.953518)
			(xy 210.428078 -253.953518) (xy 210.41801 -253.953946) (xy 210.399413 -253.961668) (xy 210.39201 -253.968504)
			(xy 209.022696 -255.337818) (xy 209.015853 -255.345218) (xy 209.008126 -255.363816) (xy 209.00771 -255.373886)
			(xy 209.00771 -263.481566) (xy 254.402842 -263.481566) (xy 254.406913 -263.425944) (xy 254.419039 -263.371507)
			(xy 254.438962 -263.319416) (xy 254.466258 -263.270781) (xy 254.500344 -263.226638) (xy 254.540493 -263.187929)
			(xy 254.585851 -263.155478) (xy 254.635451 -263.129977) (xy 254.688235 -263.11197) (xy 254.743078 -263.10184)
			(xy 254.798812 -263.099803) (xy 254.854249 -263.105903) (xy 254.908206 -263.120009) (xy 254.959535 -263.141821)
			(xy 255.007141 -263.170875) (xy 255.050009 -263.20655) (xy 255.087226 -263.248087) (xy 255.117999 -263.2946)
			(xy 255.141671 -263.345097) (xy 255.157739 -263.398504) (xy 255.165859 -263.45368) (xy 255.166368 -263.481566)
			(xy 255.165859 -263.509452) (xy 255.157739 -263.564628) (xy 255.141671 -263.618035) (xy 255.117999 -263.668532)
			(xy 255.087226 -263.715045) (xy 255.050009 -263.756582) (xy 255.007141 -263.792257) (xy 254.959535 -263.821311)
			(xy 254.908206 -263.843123) (xy 254.854249 -263.857229) (xy 254.798812 -263.863329) (xy 254.743078 -263.861292)
			(xy 254.688235 -263.851162) (xy 254.635451 -263.833155) (xy 254.585851 -263.807654) (xy 254.540493 -263.775203)
			(xy 254.500344 -263.736494) (xy 254.466258 -263.692351) (xy 254.438962 -263.643716) (xy 254.419039 -263.591625)
			(xy 254.406913 -263.537188) (xy 254.402842 -263.481566) (xy 209.00771 -263.481566) (xy 209.00771 -269.770955)
			(xy 221.508737 -269.770955) (xy 221.508737 -269.716445) (xy 221.516495 -269.662489) (xy 221.531853 -269.610186)
			(xy 221.554499 -269.560602) (xy 221.583971 -269.514745) (xy 221.619669 -269.473549) (xy 221.660867 -269.437854)
			(xy 221.706726 -269.408385) (xy 221.756312 -269.385743) (xy 221.808616 -269.370389) (xy 221.862573 -269.362635)
			(xy 221.889828 -269.362174) (xy 221.918744 -269.362716) (xy 221.975916 -269.371436) (xy 222.031115 -269.388688)
			(xy 222.083078 -269.414075) (xy 222.130612 -269.447016) (xy 222.172628 -269.486755) (xy 222.190818 -269.50924)
			(xy 222.19837 -269.518012) (xy 222.219136 -269.528188) (xy 222.230696 -269.528798) (xy 222.31096 -269.528798)
			(xy 222.322525 -269.528205) (xy 222.343296 -269.518027) (xy 222.350838 -269.50924) (xy 222.367591 -269.488457)
			(xy 222.405945 -269.451327) (xy 222.449099 -269.419905) (xy 222.496213 -269.394806) (xy 222.546365 -269.37652)
			(xy 222.598576 -269.365403) (xy 222.651828 -269.361673) (xy 222.70508 -269.365403) (xy 222.757291 -269.37652)
			(xy 222.807443 -269.394806) (xy 222.854557 -269.419905) (xy 222.897711 -269.451327) (xy 222.936065 -269.488457)
			(xy 222.952818 -269.50924) (xy 222.96037 -269.518012) (xy 222.981136 -269.528188) (xy 222.992696 -269.528798)
			(xy 223.07296 -269.528798) (xy 223.084525 -269.528205) (xy 223.105296 -269.518027) (xy 223.112838 -269.50924)
			(xy 223.129591 -269.488457) (xy 223.167945 -269.451327) (xy 223.211099 -269.419905) (xy 223.258213 -269.394806)
			(xy 223.308365 -269.37652) (xy 223.360576 -269.365403) (xy 223.413828 -269.361673) (xy 223.46708 -269.365403)
			(xy 223.519291 -269.37652) (xy 223.569443 -269.394806) (xy 223.616557 -269.419905) (xy 223.659711 -269.451327)
			(xy 223.698065 -269.488457) (xy 223.714818 -269.50924) (xy 223.72237 -269.518012) (xy 223.743136 -269.528188)
			(xy 223.754696 -269.528798) (xy 223.83496 -269.528798) (xy 223.846525 -269.528205) (xy 223.867296 -269.518027)
			(xy 223.874838 -269.50924) (xy 223.893018 -269.486747) (xy 223.935039 -269.44701) (xy 223.982575 -269.414071)
			(xy 224.034539 -269.388684) (xy 224.089739 -269.371431) (xy 224.146911 -269.362706) (xy 224.175828 -269.362174)
			(xy 224.203077 -269.362698) (xy 224.257019 -269.370458) (xy 224.309308 -269.385814) (xy 224.358879 -269.408456)
			(xy 224.404724 -269.437922) (xy 224.445908 -269.473611) (xy 224.481595 -269.514799) (xy 224.511057 -269.560646)
			(xy 224.533695 -269.610219) (xy 224.549048 -269.662509) (xy 224.556804 -269.716451) (xy 224.556804 -269.770949)
			(xy 224.549048 -269.824891) (xy 224.533695 -269.877181) (xy 224.511057 -269.926754) (xy 224.481595 -269.972601)
			(xy 224.445908 -270.013789) (xy 224.404724 -270.049478) (xy 224.358879 -270.078944) (xy 224.309308 -270.101586)
			(xy 224.257019 -270.116942) (xy 224.203077 -270.124702) (xy 224.175828 -270.12519) (xy 224.146912 -270.124655)
			(xy 224.089741 -270.11593) (xy 224.034542 -270.098676) (xy 223.982581 -270.073287) (xy 223.935046 -270.040346)
			(xy 223.893029 -270.000608) (xy 223.874838 -269.978124) (xy 223.867268 -269.969371) (xy 223.846515 -269.959186)
			(xy 223.83496 -269.958566) (xy 223.754696 -269.958566) (xy 223.743124 -269.959111) (xy 223.722352 -269.969321)
			(xy 223.714818 -269.978124) (xy 223.698065 -269.998907) (xy 223.659711 -270.036037) (xy 223.616557 -270.067459)
			(xy 223.569443 -270.092558) (xy 223.519291 -270.110844) (xy 223.46708 -270.121961) (xy 223.413828 -270.125691)
			(xy 223.360576 -270.121961) (xy 223.308365 -270.110844) (xy 223.258213 -270.092558) (xy 223.211099 -270.067459)
			(xy 223.167945 -270.036037) (xy 223.129591 -269.998907) (xy 223.112838 -269.978124) (xy 223.105268 -269.969371)
			(xy 223.084515 -269.959186) (xy 223.07296 -269.958566) (xy 222.992696 -269.958566) (xy 222.981124 -269.959111)
			(xy 222.960352 -269.969321) (xy 222.952818 -269.978124) (xy 222.936065 -269.998907) (xy 222.897711 -270.036037)
			(xy 222.854557 -270.067459) (xy 222.807443 -270.092558) (xy 222.757291 -270.110844) (xy 222.70508 -270.121961)
			(xy 222.651828 -270.125691) (xy 222.598576 -270.121961) (xy 222.546365 -270.110844) (xy 222.496213 -270.092558)
			(xy 222.449099 -270.067459) (xy 222.405945 -270.036037) (xy 222.367591 -269.998907) (xy 222.350838 -269.978124)
			(xy 222.343268 -269.969371) (xy 222.322515 -269.959186) (xy 222.31096 -269.958566) (xy 222.230696 -269.958566)
			(xy 222.219124 -269.959111) (xy 222.198352 -269.969321) (xy 222.190818 -269.978124) (xy 222.172623 -270.000604)
			(xy 222.130603 -270.040338) (xy 222.083069 -270.073277) (xy 222.031109 -270.098666) (xy 221.975912 -270.115923)
			(xy 221.918744 -270.124654) (xy 221.889828 -270.12519) (xy 221.862573 -270.124765) (xy 221.808616 -270.117011)
			(xy 221.756312 -270.101657) (xy 221.706726 -270.079015) (xy 221.660867 -270.049546) (xy 221.619669 -270.013851)
			(xy 221.583971 -269.972655) (xy 221.554499 -269.926798) (xy 221.531853 -269.877214) (xy 221.516495 -269.824911)
			(xy 221.508737 -269.770955) (xy 209.00771 -269.770955) (xy 209.00771 -271.407389) (xy 221.507795 -271.407389)
			(xy 221.511527 -271.354135) (xy 221.522646 -271.301921) (xy 221.540936 -271.251767) (xy 221.566039 -271.204652)
			(xy 221.597465 -271.161497) (xy 221.6346 -271.123145) (xy 221.655386 -271.106392) (xy 221.664145 -271.098827)
			(xy 221.674331 -271.078071) (xy 221.674944 -271.066514) (xy 221.674944 -270.98625) (xy 221.674365 -270.974683)
			(xy 221.664178 -270.95391) (xy 221.655386 -270.946372) (xy 221.632886 -270.9282) (xy 221.593153 -270.886176)
			(xy 221.560216 -270.838637) (xy 221.534831 -270.786672) (xy 221.517578 -270.731471) (xy 221.508853 -270.674299)
			(xy 221.50832 -270.645382) (xy 221.508738 -270.618127) (xy 221.516498 -270.564173) (xy 221.531858 -270.511873)
			(xy 221.554505 -270.462291) (xy 221.583977 -270.416436) (xy 221.619676 -270.375243) (xy 221.660873 -270.33955)
			(xy 221.706731 -270.310083) (xy 221.756316 -270.287442) (xy 221.808618 -270.272089) (xy 221.862573 -270.264335)
			(xy 221.889828 -270.263874) (xy 221.918744 -270.264416) (xy 221.975916 -270.273136) (xy 222.031115 -270.290388)
			(xy 222.083078 -270.315775) (xy 222.130612 -270.348716) (xy 222.172628 -270.388455) (xy 222.190818 -270.41094)
			(xy 222.19837 -270.419712) (xy 222.219136 -270.429888) (xy 222.230696 -270.430498) (xy 222.31096 -270.430498)
			(xy 222.322525 -270.429905) (xy 222.343296 -270.419727) (xy 222.350838 -270.41094) (xy 222.369018 -270.388447)
			(xy 222.411039 -270.34871) (xy 222.458575 -270.315771) (xy 222.510539 -270.290384) (xy 222.565739 -270.273131)
			(xy 222.622911 -270.264406) (xy 222.651828 -270.263874) (xy 222.679079 -270.264352) (xy 222.733026 -270.272112)
			(xy 222.78532 -270.287469) (xy 222.834896 -270.310112) (xy 222.880746 -270.33958) (xy 222.921935 -270.375272)
			(xy 222.957626 -270.416463) (xy 222.987092 -270.462313) (xy 223.009734 -270.511889) (xy 223.025091 -270.564184)
			(xy 223.032849 -270.618131) (xy 223.033336 -270.645382) (xy 223.032829 -270.6743) (xy 223.024101 -270.731472)
			(xy 223.006843 -270.786673) (xy 222.981449 -270.838635) (xy 222.948502 -270.886168) (xy 222.908757 -270.928183)
			(xy 222.88627 -270.946372) (xy 222.87752 -270.953945) (xy 222.867331 -270.974696) (xy 222.866712 -270.98625)
			(xy 222.866712 -271.066514) (xy 222.86727 -271.078084) (xy 222.877473 -271.098855) (xy 222.88627 -271.106392)
			(xy 222.907034 -271.123167) (xy 222.944161 -271.161519) (xy 222.975581 -271.204672) (xy 223.000678 -271.251783)
			(xy 223.018964 -271.301932) (xy 223.03008 -271.354141) (xy 223.033811 -271.407389) (xy 223.030083 -271.460638)
			(xy 223.01897 -271.512847) (xy 223.000687 -271.562997) (xy 222.975592 -271.610109) (xy 222.944176 -271.653264)
			(xy 222.90705 -271.691618) (xy 222.88627 -271.708372) (xy 222.87752 -271.715945) (xy 222.867331 -271.736696)
			(xy 222.866712 -271.74825) (xy 222.866712 -271.828514) (xy 222.86727 -271.840084) (xy 222.877473 -271.860855)
			(xy 222.88627 -271.868392) (xy 222.908743 -271.886595) (xy 222.948481 -271.928611) (xy 222.981422 -271.976144)
			(xy 223.006812 -272.028103) (xy 223.02407 -272.083298) (xy 223.0328 -272.140467) (xy 223.033336 -272.169382)
			(xy 223.032805 -272.196631) (xy 223.025052 -272.250576) (xy 223.0097 -272.302868) (xy 222.987063 -272.352443)
			(xy 222.957602 -272.398293) (xy 222.921915 -272.439482) (xy 222.880729 -272.475174) (xy 222.84236 -272.499836)
			(xy 231.378258 -272.499836) (xy 231.382272 -272.294152) (xy 231.394308 -272.088782) (xy 231.414347 -271.884038)
			(xy 231.44236 -271.680231) (xy 231.478303 -271.477672) (xy 231.522122 -271.27667) (xy 231.573749 -271.077531)
			(xy 231.633107 -270.880558) (xy 231.700105 -270.68605) (xy 231.774641 -270.494305) (xy 231.856601 -270.305614)
			(xy 231.945861 -270.120264) (xy 232.042284 -269.938538) (xy 232.145725 -269.760712) (xy 232.256024 -269.587058)
			(xy 232.373015 -269.417839) (xy 232.496519 -269.253313) (xy 232.626348 -269.093732) (xy 232.762305 -268.939337)
			(xy 232.904182 -268.790365) (xy 233.051763 -268.647041) (xy 233.204824 -268.509585) (xy 233.363131 -268.378205)
			(xy 233.526444 -268.253102) (xy 233.694513 -268.134465) (xy 233.867083 -268.022477) (xy 234.043891 -267.917306)
			(xy 234.224668 -267.819115) (xy 234.409138 -267.728051) (xy 234.59702 -267.644254) (xy 234.78803 -267.567851)
			(xy 234.981874 -267.498958) (xy 235.178259 -267.437681) (xy 235.376885 -267.384113) (xy 235.57745 -267.338336)
			(xy 235.779648 -267.300418) (xy 235.983172 -267.270419) (xy 236.187711 -267.248382) (xy 236.392954 -267.234343)
			(xy 236.598589 -267.228323) (xy 236.804302 -267.23033) (xy 237.00978 -267.240362) (xy 237.21471 -267.258403)
			(xy 237.41878 -267.284426) (xy 237.62168 -267.318391) (xy 237.8231 -267.360246) (xy 238.022733 -267.409928)
			(xy 238.220276 -267.467362) (xy 238.415428 -267.532459) (xy 238.607892 -267.60512) (xy 238.797374 -267.685236)
			(xy 238.983585 -267.772683) (xy 239.166244 -267.867329) (xy 239.34507 -267.969029) (xy 239.519792 -268.077629)
			(xy 239.690145 -268.192964) (xy 239.855867 -268.314857) (xy 240.016708 -268.443123) (xy 240.172421 -268.577566)
			(xy 240.322771 -268.717983) (xy 240.467528 -268.864159) (xy 240.606471 -269.015871) (xy 240.739389 -269.172889)
			(xy 240.86608 -269.334974) (xy 240.98635 -269.501877) (xy 241.072241 -269.631446) (xy 249.332814 -269.631446)
			(xy 249.332814 -269.576954) (xy 249.340569 -269.523015) (xy 249.35592 -269.47073) (xy 249.378555 -269.421161)
			(xy 249.408014 -269.375317) (xy 249.443696 -269.334132) (xy 249.484877 -269.298444) (xy 249.530717 -269.268979)
			(xy 249.580283 -269.246337) (xy 249.632567 -269.230979) (xy 249.686504 -269.223218) (xy 249.71375 -269.222728)
			(xy 249.742666 -269.223272) (xy 249.799837 -269.231994) (xy 249.855035 -269.249246) (xy 249.906997 -269.274633)
			(xy 249.954532 -269.307573) (xy 249.99655 -269.34731) (xy 250.01474 -269.369794) (xy 250.02229 -269.378569)
			(xy 250.043058 -269.388745) (xy 250.054618 -269.389352) (xy 250.134882 -269.389352) (xy 250.146451 -269.388788)
			(xy 250.167223 -269.37859) (xy 250.17476 -269.369794) (xy 250.191513 -269.349011) (xy 250.229867 -269.311881)
			(xy 250.273021 -269.280459) (xy 250.320135 -269.25536) (xy 250.370287 -269.237074) (xy 250.422498 -269.225957)
			(xy 250.47575 -269.222227) (xy 250.529002 -269.225957) (xy 250.581213 -269.237074) (xy 250.631365 -269.25536)
			(xy 250.678479 -269.280459) (xy 250.721633 -269.311881) (xy 250.759987 -269.349011) (xy 250.77674 -269.369794)
			(xy 250.78429 -269.378569) (xy 250.805058 -269.388745) (xy 250.816618 -269.389352) (xy 250.896882 -269.389352)
			(xy 250.908451 -269.388788) (xy 250.929223 -269.37859) (xy 250.93676 -269.369794) (xy 250.953513 -269.349011)
			(xy 250.991867 -269.311881) (xy 251.035021 -269.280459) (xy 251.082135 -269.25536) (xy 251.132287 -269.237074)
			(xy 251.184498 -269.225957) (xy 251.23775 -269.222227) (xy 251.291002 -269.225957) (xy 251.343213 -269.237074)
			(xy 251.393365 -269.25536) (xy 251.440479 -269.280459) (xy 251.483633 -269.311881) (xy 251.521987 -269.349011)
			(xy 251.53874 -269.369794) (xy 251.54629 -269.378569) (xy 251.567058 -269.388745) (xy 251.578618 -269.389352)
			(xy 251.658882 -269.389352) (xy 251.670451 -269.388788) (xy 251.691223 -269.37859) (xy 251.69876 -269.369794)
			(xy 251.716972 -269.347328) (xy 251.758988 -269.307592) (xy 251.806518 -269.274651) (xy 251.858475 -269.24926)
			(xy 251.913669 -269.232) (xy 251.970835 -269.223266) (xy 251.99975 -269.222728) (xy 252.027008 -269.223116)
			(xy 252.080969 -269.230867) (xy 252.133278 -269.246221) (xy 252.182869 -269.268862) (xy 252.228733 -269.298332)
			(xy 252.269936 -269.334029) (xy 252.305638 -269.375227) (xy 252.335114 -269.421087) (xy 252.357762 -269.470675)
			(xy 252.373122 -269.522982) (xy 252.380881 -269.576942) (xy 252.380881 -269.631458) (xy 252.373122 -269.685418)
			(xy 252.357762 -269.737725) (xy 252.335114 -269.787313) (xy 252.305638 -269.833173) (xy 252.269936 -269.874371)
			(xy 252.228733 -269.910068) (xy 252.182869 -269.939538) (xy 252.133278 -269.962179) (xy 252.080969 -269.977533)
			(xy 252.027008 -269.985284) (xy 251.99975 -269.985744) (xy 251.970833 -269.985211) (xy 251.913662 -269.976488)
			(xy 251.858462 -269.959235) (xy 251.8065 -269.933846) (xy 251.758966 -269.900904) (xy 251.71695 -269.861163)
			(xy 251.69876 -269.838678) (xy 251.691215 -269.829899) (xy 251.670443 -269.819726) (xy 251.658882 -269.81912)
			(xy 251.578618 -269.81912) (xy 251.56705 -269.819694) (xy 251.546279 -269.829885) (xy 251.53874 -269.838678)
			(xy 251.521987 -269.859461) (xy 251.483633 -269.896591) (xy 251.440479 -269.928013) (xy 251.393365 -269.953112)
			(xy 251.343213 -269.971398) (xy 251.291002 -269.982515) (xy 251.23775 -269.986245) (xy 251.184498 -269.982515)
			(xy 251.132287 -269.971398) (xy 251.082135 -269.953112) (xy 251.035021 -269.928013) (xy 250.991867 -269.896591)
			(xy 250.953513 -269.859461) (xy 250.93676 -269.838678) (xy 250.929215 -269.829899) (xy 250.908443 -269.819726)
			(xy 250.896882 -269.81912) (xy 250.816618 -269.81912) (xy 250.80505 -269.819694) (xy 250.784279 -269.829885)
			(xy 250.77674 -269.838678) (xy 250.759987 -269.859461) (xy 250.721633 -269.896591) (xy 250.678479 -269.928013)
			(xy 250.631365 -269.953112) (xy 250.581213 -269.971398) (xy 250.529002 -269.982515) (xy 250.47575 -269.986245)
			(xy 250.422498 -269.982515) (xy 250.370287 -269.971398) (xy 250.320135 -269.953112) (xy 250.273021 -269.928013)
			(xy 250.229867 -269.896591) (xy 250.191513 -269.859461) (xy 250.17476 -269.838678) (xy 250.167215 -269.829899)
			(xy 250.146443 -269.819726) (xy 250.134882 -269.81912) (xy 250.054618 -269.81912) (xy 250.04305 -269.819694)
			(xy 250.022279 -269.829885) (xy 250.01474 -269.838678) (xy 249.996521 -269.861138) (xy 249.954508 -269.900875)
			(xy 249.906979 -269.933818) (xy 249.855023 -269.959211) (xy 249.79983 -269.976472) (xy 249.742664 -269.985206)
			(xy 249.71375 -269.985744) (xy 249.686504 -269.985182) (xy 249.632567 -269.977421) (xy 249.580283 -269.962063)
			(xy 249.530717 -269.939421) (xy 249.484877 -269.909956) (xy 249.443697 -269.874268) (xy 249.408014 -269.833083)
			(xy 249.378555 -269.787239) (xy 249.35592 -269.73767) (xy 249.340569 -269.685385) (xy 249.332814 -269.631446)
			(xy 241.072241 -269.631446) (xy 241.100017 -269.673347) (xy 241.206907 -269.84912) (xy 241.306858 -270.02893)
			(xy 241.399717 -270.212503) (xy 241.485344 -270.399559) (xy 241.563606 -270.589814) (xy 241.634387 -270.782977)
			(xy 241.697577 -270.978755) (xy 241.75308 -271.176849) (xy 241.774804 -271.267922) (xy 250.855751 -271.267922)
			(xy 250.859478 -271.214673) (xy 250.870593 -271.162463) (xy 250.888877 -271.112313) (xy 250.913975 -271.065201)
			(xy 250.945396 -271.022049) (xy 250.982526 -270.983698) (xy 251.003308 -270.966946) (xy 251.012046 -270.959361)
			(xy 251.022242 -270.93862) (xy 251.022866 -270.927068) (xy 251.022866 -270.846804) (xy 251.022305 -270.835235)
			(xy 251.012105 -270.814463) (xy 251.003308 -270.806926) (xy 250.980839 -270.788718) (xy 250.941102 -270.746702)
			(xy 250.908161 -270.699171) (xy 250.88277 -270.647213) (xy 250.865511 -270.592018) (xy 250.856779 -270.534851)
			(xy 250.856242 -270.505936) (xy 250.856689 -270.478682) (xy 250.864442 -270.424728) (xy 250.879796 -270.372426)
			(xy 250.902438 -270.322843) (xy 250.931907 -270.276987) (xy 250.967603 -270.235793) (xy 251.008799 -270.200099)
			(xy 251.054655 -270.170632) (xy 251.10424 -270.147991) (xy 251.156541 -270.132639) (xy 251.210496 -270.124888)
			(xy 251.23775 -270.124428) (xy 251.266666 -270.124972) (xy 251.323837 -270.133694) (xy 251.379035 -270.150946)
			(xy 251.430997 -270.176333) (xy 251.478532 -270.209273) (xy 251.52055 -270.24901) (xy 251.53874 -270.271494)
			(xy 251.54629 -270.280269) (xy 251.567058 -270.290445) (xy 251.578618 -270.291052) (xy 251.658882 -270.291052)
			(xy 251.670451 -270.290488) (xy 251.691223 -270.28029) (xy 251.69876 -270.271494) (xy 251.716972 -270.249028)
			(xy 251.758988 -270.209292) (xy 251.806518 -270.176351) (xy 251.858475 -270.15096) (xy 251.913669 -270.1337)
			(xy 251.970835 -270.124966) (xy 251.99975 -270.124428) (xy 252.027003 -270.124902) (xy 252.080956 -270.132653)
			(xy 252.133256 -270.148005) (xy 252.182838 -270.170644) (xy 252.228693 -270.20011) (xy 252.269887 -270.235803)
			(xy 252.305582 -270.276996) (xy 252.335049 -270.32285) (xy 252.357691 -270.372431) (xy 252.373044 -270.424731)
			(xy 252.380797 -270.478683) (xy 252.381258 -270.505936) (xy 252.38071 -270.534852) (xy 252.371989 -270.592023)
			(xy 252.354738 -270.647221) (xy 252.329352 -270.699184) (xy 252.296413 -270.746718) (xy 252.256676 -270.788736)
			(xy 252.234192 -270.806926) (xy 252.225422 -270.81448) (xy 252.215243 -270.835245) (xy 252.214634 -270.846804)
			(xy 252.214634 -270.927068) (xy 252.215211 -270.938635) (xy 252.2254 -270.959407) (xy 252.234192 -270.966946)
			(xy 252.255013 -270.983656) (xy 252.292148 -271.022012) (xy 252.323574 -271.065171) (xy 252.348675 -271.112289)
			(xy 252.366962 -271.162447) (xy 252.378078 -271.214665) (xy 252.381806 -271.267922) (xy 252.378072 -271.321179)
			(xy 252.36695 -271.373395) (xy 252.348657 -271.423551) (xy 252.32355 -271.470667) (xy 252.29212 -271.513822)
			(xy 252.25498 -271.552174) (xy 252.234192 -271.568926) (xy 252.225422 -271.57648) (xy 252.215243 -271.597245)
			(xy 252.214634 -271.608804) (xy 252.214634 -271.689068) (xy 252.215211 -271.700635) (xy 252.2254 -271.721407)
			(xy 252.234192 -271.728946) (xy 252.256648 -271.74717) (xy 252.296385 -271.789182) (xy 252.329328 -271.83671)
			(xy 252.354721 -271.888665) (xy 252.371983 -271.943857) (xy 252.380719 -272.001022) (xy 252.381258 -272.029936)
			(xy 252.380878 -272.057192) (xy 252.373115 -272.111149) (xy 252.357752 -272.163451) (xy 252.335102 -272.213035)
			(xy 252.305625 -272.25889) (xy 252.269923 -272.300084) (xy 252.228721 -272.335777) (xy 252.182859 -272.365243)
			(xy 252.13327 -272.387882) (xy 252.080964 -272.403234) (xy 252.027006 -272.410985) (xy 251.99975 -272.411444)
			(xy 251.970833 -272.410911) (xy 251.913662 -272.402188) (xy 251.858462 -272.384935) (xy 251.8065 -272.359546)
			(xy 251.758966 -272.326604) (xy 251.71695 -272.286863) (xy 251.69876 -272.264378) (xy 251.691215 -272.255599)
			(xy 251.670443 -272.245426) (xy 251.658882 -272.24482) (xy 251.578618 -272.24482) (xy 251.56705 -272.245394)
			(xy 251.546279 -272.255585) (xy 251.53874 -272.264378) (xy 251.520521 -272.286838) (xy 251.478508 -272.326575)
			(xy 251.430979 -272.359518) (xy 251.379023 -272.384911) (xy 251.32383 -272.402172) (xy 251.266664 -272.410906)
			(xy 251.23775 -272.411444) (xy 251.2105 -272.410898) (xy 251.156554 -272.403149) (xy 251.10426 -272.387801)
			(xy 251.054682 -272.365167) (xy 251.008831 -272.335708) (xy 250.967638 -272.300023) (xy 250.931944 -272.258838)
			(xy 250.902474 -272.212993) (xy 250.879829 -272.163421) (xy 250.864469 -272.11113) (xy 250.856708 -272.057186)
			(xy 250.856242 -272.029936) (xy 250.85677 -272.001019) (xy 250.865495 -271.943848) (xy 250.88275 -271.888648)
			(xy 250.90814 -271.836686) (xy 250.941082 -271.789152) (xy 250.980823 -271.747136) (xy 251.003308 -271.728946)
			(xy 251.012046 -271.721361) (xy 251.022242 -271.70062) (xy 251.022866 -271.689068) (xy 251.022866 -271.608804)
			(xy 251.022305 -271.597235) (xy 251.012105 -271.576463) (xy 251.003308 -271.568926) (xy 250.982558 -271.552131)
			(xy 250.945424 -271.513785) (xy 250.913999 -271.470636) (xy 250.888895 -271.423528) (xy 250.870605 -271.37338)
			(xy 250.859485 -271.321171) (xy 250.855751 -271.267922) (xy 241.774804 -271.267922) (xy 241.800812 -271.376958)
			(xy 241.840701 -271.578776) (xy 241.872685 -271.781998) (xy 241.896715 -271.986312) (xy 241.912756 -272.191408)
			(xy 241.920782 -272.396975) (xy 241.921284 -272.499836) (xy 241.920782 -272.602697) (xy 241.912756 -272.808264)
			(xy 241.900979 -272.958846) (xy 249.332814 -272.958846) (xy 249.332814 -272.904354) (xy 249.340569 -272.850415)
			(xy 249.35592 -272.79813) (xy 249.378555 -272.748561) (xy 249.408014 -272.702717) (xy 249.443696 -272.661532)
			(xy 249.484877 -272.625844) (xy 249.530717 -272.596379) (xy 249.580283 -272.573737) (xy 249.632567 -272.558379)
			(xy 249.686504 -272.550618) (xy 249.71375 -272.550128) (xy 249.742666 -272.550672) (xy 249.799837 -272.559394)
			(xy 249.855035 -272.576646) (xy 249.906997 -272.602033) (xy 249.954532 -272.634973) (xy 249.99655 -272.67471)
			(xy 250.01474 -272.697194) (xy 250.02229 -272.705969) (xy 250.043058 -272.716145) (xy 250.054618 -272.716752)
			(xy 250.134882 -272.716752) (xy 250.146451 -272.716188) (xy 250.167223 -272.70599) (xy 250.17476 -272.697194)
			(xy 250.191513 -272.676411) (xy 250.229867 -272.639281) (xy 250.273021 -272.607859) (xy 250.320135 -272.58276)
			(xy 250.370287 -272.564474) (xy 250.422498 -272.553357) (xy 250.47575 -272.549627) (xy 250.529002 -272.553357)
			(xy 250.581213 -272.564474) (xy 250.631365 -272.58276) (xy 250.678479 -272.607859) (xy 250.721633 -272.639281)
			(xy 250.759987 -272.676411) (xy 250.77674 -272.697194) (xy 250.78429 -272.705969) (xy 250.805058 -272.716145)
			(xy 250.816618 -272.716752) (xy 250.896882 -272.716752) (xy 250.908451 -272.716188) (xy 250.929223 -272.70599)
			(xy 250.93676 -272.697194) (xy 250.953513 -272.676411) (xy 250.991867 -272.639281) (xy 251.035021 -272.607859)
			(xy 251.082135 -272.58276) (xy 251.132287 -272.564474) (xy 251.184498 -272.553357) (xy 251.23775 -272.549627)
			(xy 251.291002 -272.553357) (xy 251.343213 -272.564474) (xy 251.393365 -272.58276) (xy 251.440479 -272.607859)
			(xy 251.483633 -272.639281) (xy 251.521987 -272.676411) (xy 251.53874 -272.697194) (xy 251.54629 -272.705969)
			(xy 251.567058 -272.716145) (xy 251.578618 -272.716752) (xy 251.658882 -272.716752) (xy 251.670451 -272.716188)
			(xy 251.691223 -272.70599) (xy 251.69876 -272.697194) (xy 251.716972 -272.674728) (xy 251.758988 -272.634992)
			(xy 251.806518 -272.602051) (xy 251.858475 -272.57666) (xy 251.913669 -272.5594) (xy 251.970835 -272.550666)
			(xy 251.99975 -272.550128) (xy 252.027008 -272.550516) (xy 252.080969 -272.558267) (xy 252.133278 -272.573621)
			(xy 252.182869 -272.596262) (xy 252.228733 -272.625732) (xy 252.269936 -272.661429) (xy 252.305638 -272.702627)
			(xy 252.335114 -272.748487) (xy 252.357762 -272.798075) (xy 252.373122 -272.850382) (xy 252.380881 -272.904342)
			(xy 252.380881 -272.958858) (xy 252.373122 -273.012818) (xy 252.357762 -273.065125) (xy 252.335114 -273.114713)
			(xy 252.305638 -273.160573) (xy 252.269936 -273.201771) (xy 252.228733 -273.237468) (xy 252.182869 -273.266938)
			(xy 252.133278 -273.289579) (xy 252.080969 -273.304933) (xy 252.027008 -273.312684) (xy 251.99975 -273.313144)
			(xy 251.970833 -273.312611) (xy 251.913662 -273.303888) (xy 251.858462 -273.286635) (xy 251.8065 -273.261246)
			(xy 251.758966 -273.228304) (xy 251.71695 -273.188563) (xy 251.69876 -273.166078) (xy 251.691215 -273.157299)
			(xy 251.670443 -273.147126) (xy 251.658882 -273.14652) (xy 251.578618 -273.14652) (xy 251.56705 -273.147094)
			(xy 251.546279 -273.157285) (xy 251.53874 -273.166078) (xy 251.521987 -273.186861) (xy 251.483633 -273.223991)
			(xy 251.440479 -273.255413) (xy 251.393365 -273.280512) (xy 251.343213 -273.298798) (xy 251.291002 -273.309915)
			(xy 251.23775 -273.313645) (xy 251.184498 -273.309915) (xy 251.132287 -273.298798) (xy 251.082135 -273.280512)
			(xy 251.035021 -273.255413) (xy 250.991867 -273.223991) (xy 250.953513 -273.186861) (xy 250.93676 -273.166078)
			(xy 250.929215 -273.157299) (xy 250.908443 -273.147126) (xy 250.896882 -273.14652) (xy 250.816618 -273.14652)
			(xy 250.80505 -273.147094) (xy 250.784279 -273.157285) (xy 250.77674 -273.166078) (xy 250.759987 -273.186861)
			(xy 250.721633 -273.223991) (xy 250.678479 -273.255413) (xy 250.631365 -273.280512) (xy 250.581213 -273.298798)
			(xy 250.529002 -273.309915) (xy 250.47575 -273.313645) (xy 250.422498 -273.309915) (xy 250.370287 -273.298798)
			(xy 250.320135 -273.280512) (xy 250.273021 -273.255413) (xy 250.229867 -273.223991) (xy 250.191513 -273.186861)
			(xy 250.17476 -273.166078) (xy 250.167215 -273.157299) (xy 250.146443 -273.147126) (xy 250.134882 -273.14652)
			(xy 250.054618 -273.14652) (xy 250.04305 -273.147094) (xy 250.022279 -273.157285) (xy 250.01474 -273.166078)
			(xy 249.996521 -273.188538) (xy 249.954508 -273.228275) (xy 249.906979 -273.261218) (xy 249.855023 -273.286611)
			(xy 249.79983 -273.303872) (xy 249.742664 -273.312606) (xy 249.71375 -273.313144) (xy 249.686504 -273.312582)
			(xy 249.632567 -273.304821) (xy 249.580283 -273.289463) (xy 249.530717 -273.266821) (xy 249.484877 -273.237356)
			(xy 249.443697 -273.201668) (xy 249.408014 -273.160483) (xy 249.378555 -273.114639) (xy 249.35592 -273.06507)
			(xy 249.340569 -273.012785) (xy 249.332814 -272.958846) (xy 241.900979 -272.958846) (xy 241.896715 -273.01336)
			(xy 241.872685 -273.217674) (xy 241.840701 -273.420896) (xy 241.800812 -273.622714) (xy 241.75308 -273.822823)
			(xy 241.697577 -274.020917) (xy 241.634387 -274.216695) (xy 241.563606 -274.409858) (xy 241.485344 -274.600113)
			(xy 241.399717 -274.787169) (xy 241.306858 -274.970742) (xy 241.206907 -275.150552) (xy 241.100017 -275.326325)
			(xy 240.98635 -275.497795) (xy 240.86608 -275.664698) (xy 240.739389 -275.826783) (xy 240.606471 -275.983801)
			(xy 240.467528 -276.135513) (xy 240.322771 -276.281689) (xy 240.172421 -276.422106) (xy 240.016708 -276.556549)
			(xy 239.855867 -276.684815) (xy 239.690145 -276.806708) (xy 239.519792 -276.922043) (xy 239.34507 -277.030643)
			(xy 239.166244 -277.132343) (xy 238.983585 -277.226989) (xy 238.797374 -277.314436) (xy 238.607892 -277.394552)
			(xy 238.415428 -277.467213) (xy 238.220276 -277.53231) (xy 238.022733 -277.589744) (xy 237.8231 -277.639426)
			(xy 237.62168 -277.681281) (xy 237.41878 -277.715246) (xy 237.21471 -277.741269) (xy 237.00978 -277.75931)
			(xy 236.804302 -277.769342) (xy 236.598589 -277.771349) (xy 236.392954 -277.765329) (xy 236.187711 -277.75129)
			(xy 235.983172 -277.729253) (xy 235.779648 -277.699254) (xy 235.57745 -277.661336) (xy 235.376885 -277.615559)
			(xy 235.178259 -277.561991) (xy 234.981874 -277.500714) (xy 234.78803 -277.431821) (xy 234.59702 -277.355418)
			(xy 234.409138 -277.271621) (xy 234.224668 -277.180557) (xy 234.043891 -277.082366) (xy 233.867083 -276.977195)
			(xy 233.694513 -276.865207) (xy 233.526444 -276.74657) (xy 233.363131 -276.621467) (xy 233.204824 -276.490087)
			(xy 233.051763 -276.352631) (xy 232.904182 -276.209307) (xy 232.762305 -276.060335) (xy 232.626348 -275.90594)
			(xy 232.496519 -275.746359) (xy 232.373015 -275.581833) (xy 232.256024 -275.412614) (xy 232.145725 -275.23896)
			(xy 232.042284 -275.061134) (xy 231.945861 -274.879408) (xy 231.856601 -274.694058) (xy 231.774641 -274.505367)
			(xy 231.700105 -274.313622) (xy 231.633107 -274.119114) (xy 231.573749 -273.922141) (xy 231.522122 -273.723002)
			(xy 231.478303 -273.522) (xy 231.44236 -273.319441) (xy 231.414347 -273.115634) (xy 231.394308 -272.91089)
			(xy 231.382272 -272.70552) (xy 231.378258 -272.499836) (xy 222.84236 -272.499836) (xy 222.834884 -272.504641)
			(xy 222.785311 -272.527284) (xy 222.733021 -272.542642) (xy 222.679077 -272.550402) (xy 222.651828 -272.55089)
			(xy 222.622912 -272.550355) (xy 222.565741 -272.54163) (xy 222.510542 -272.524376) (xy 222.458581 -272.498987)
			(xy 222.411046 -272.466046) (xy 222.369029 -272.426308) (xy 222.350838 -272.403824) (xy 222.343268 -272.395071)
			(xy 222.322515 -272.384886) (xy 222.31096 -272.384266) (xy 222.230696 -272.384266) (xy 222.219124 -272.384811)
			(xy 222.198352 -272.395021) (xy 222.190818 -272.403824) (xy 222.172623 -272.426304) (xy 222.130603 -272.466038)
			(xy 222.083069 -272.498977) (xy 222.031109 -272.524366) (xy 221.975912 -272.541623) (xy 221.918744 -272.550354)
			(xy 221.889828 -272.55089) (xy 221.862575 -272.550419) (xy 221.808623 -272.542665) (xy 221.756325 -272.527312)
			(xy 221.706743 -272.504671) (xy 221.660889 -272.475204) (xy 221.619696 -272.439511) (xy 221.584002 -272.398319)
			(xy 221.554534 -272.352465) (xy 221.531892 -272.302885) (xy 221.516537 -272.250586) (xy 221.508782 -272.196635)
			(xy 221.50832 -272.169382) (xy 221.508889 -272.140467) (xy 221.517607 -272.083298) (xy 221.534854 -272.0281)
			(xy 221.560236 -271.976137) (xy 221.593171 -271.928602) (xy 221.632904 -271.886583) (xy 221.655386 -271.868392)
			(xy 221.664145 -271.860827) (xy 221.674331 -271.840071) (xy 221.674944 -271.828514) (xy 221.674944 -271.74825)
			(xy 221.674365 -271.736683) (xy 221.664178 -271.71591) (xy 221.655386 -271.708372) (xy 221.634584 -271.691641)
			(xy 221.597451 -271.653286) (xy 221.566027 -271.610129) (xy 221.540927 -271.563013) (xy 221.52264 -271.512858)
			(xy 221.511524 -271.460643) (xy 221.507795 -271.407389) (xy 209.00771 -271.407389) (xy 209.00771 -273.098355)
			(xy 221.508737 -273.098355) (xy 221.508737 -273.043845) (xy 221.516495 -272.989889) (xy 221.531853 -272.937586)
			(xy 221.554499 -272.888002) (xy 221.583971 -272.842145) (xy 221.619669 -272.800949) (xy 221.660867 -272.765254)
			(xy 221.706726 -272.735785) (xy 221.756312 -272.713143) (xy 221.808616 -272.697789) (xy 221.862573 -272.690035)
			(xy 221.889828 -272.689574) (xy 221.918744 -272.690116) (xy 221.975916 -272.698836) (xy 222.031115 -272.716088)
			(xy 222.083078 -272.741475) (xy 222.130612 -272.774416) (xy 222.172628 -272.814155) (xy 222.190818 -272.83664)
			(xy 222.19837 -272.845412) (xy 222.219136 -272.855588) (xy 222.230696 -272.856198) (xy 222.31096 -272.856198)
			(xy 222.322525 -272.855605) (xy 222.343296 -272.845427) (xy 222.350838 -272.83664) (xy 222.367591 -272.815857)
			(xy 222.405945 -272.778727) (xy 222.449099 -272.747305) (xy 222.496213 -272.722206) (xy 222.546365 -272.70392)
			(xy 222.598576 -272.692803) (xy 222.651828 -272.689073) (xy 222.70508 -272.692803) (xy 222.757291 -272.70392)
			(xy 222.807443 -272.722206) (xy 222.854557 -272.747305) (xy 222.897711 -272.778727) (xy 222.936065 -272.815857)
			(xy 222.952818 -272.83664) (xy 222.96037 -272.845412) (xy 222.981136 -272.855588) (xy 222.992696 -272.856198)
			(xy 223.07296 -272.856198) (xy 223.084525 -272.855605) (xy 223.105296 -272.845427) (xy 223.112838 -272.83664)
			(xy 223.129591 -272.815857) (xy 223.167945 -272.778727) (xy 223.211099 -272.747305) (xy 223.258213 -272.722206)
			(xy 223.308365 -272.70392) (xy 223.360576 -272.692803) (xy 223.413828 -272.689073) (xy 223.46708 -272.692803)
			(xy 223.519291 -272.70392) (xy 223.569443 -272.722206) (xy 223.616557 -272.747305) (xy 223.659711 -272.778727)
			(xy 223.698065 -272.815857) (xy 223.714818 -272.83664) (xy 223.72237 -272.845412) (xy 223.743136 -272.855588)
			(xy 223.754696 -272.856198) (xy 223.83496 -272.856198) (xy 223.846525 -272.855605) (xy 223.867296 -272.845427)
			(xy 223.874838 -272.83664) (xy 223.893018 -272.814147) (xy 223.935039 -272.77441) (xy 223.982575 -272.741471)
			(xy 224.034539 -272.716084) (xy 224.089739 -272.698831) (xy 224.146911 -272.690106) (xy 224.175828 -272.689574)
			(xy 224.203077 -272.690098) (xy 224.257019 -272.697858) (xy 224.309308 -272.713214) (xy 224.358879 -272.735856)
			(xy 224.404724 -272.765322) (xy 224.445908 -272.801011) (xy 224.481595 -272.842199) (xy 224.511057 -272.888046)
			(xy 224.533695 -272.937619) (xy 224.549048 -272.989909) (xy 224.556804 -273.043851) (xy 224.556804 -273.098349)
			(xy 224.549048 -273.152291) (xy 224.533695 -273.204581) (xy 224.511057 -273.254154) (xy 224.481595 -273.300001)
			(xy 224.445908 -273.341189) (xy 224.404724 -273.376878) (xy 224.358879 -273.406344) (xy 224.309308 -273.428986)
			(xy 224.257019 -273.444342) (xy 224.203077 -273.452102) (xy 224.175828 -273.45259) (xy 224.146912 -273.452055)
			(xy 224.089741 -273.44333) (xy 224.034542 -273.426076) (xy 223.982581 -273.400687) (xy 223.935046 -273.367746)
			(xy 223.893029 -273.328008) (xy 223.874838 -273.305524) (xy 223.867268 -273.296771) (xy 223.846515 -273.286586)
			(xy 223.83496 -273.285966) (xy 223.754696 -273.285966) (xy 223.743124 -273.286511) (xy 223.722352 -273.296721)
			(xy 223.714818 -273.305524) (xy 223.698065 -273.326307) (xy 223.659711 -273.363437) (xy 223.616557 -273.394859)
			(xy 223.569443 -273.419958) (xy 223.519291 -273.438244) (xy 223.46708 -273.449361) (xy 223.413828 -273.453091)
			(xy 223.360576 -273.449361) (xy 223.308365 -273.438244) (xy 223.258213 -273.419958) (xy 223.211099 -273.394859)
			(xy 223.167945 -273.363437) (xy 223.129591 -273.326307) (xy 223.112838 -273.305524) (xy 223.105268 -273.296771)
			(xy 223.084515 -273.286586) (xy 223.07296 -273.285966) (xy 222.992696 -273.285966) (xy 222.981124 -273.286511)
			(xy 222.960352 -273.296721) (xy 222.952818 -273.305524) (xy 222.936065 -273.326307) (xy 222.897711 -273.363437)
			(xy 222.854557 -273.394859) (xy 222.807443 -273.419958) (xy 222.757291 -273.438244) (xy 222.70508 -273.449361)
			(xy 222.651828 -273.453091) (xy 222.598576 -273.449361) (xy 222.546365 -273.438244) (xy 222.496213 -273.419958)
			(xy 222.449099 -273.394859) (xy 222.405945 -273.363437) (xy 222.367591 -273.326307) (xy 222.350838 -273.305524)
			(xy 222.343268 -273.296771) (xy 222.322515 -273.286586) (xy 222.31096 -273.285966) (xy 222.230696 -273.285966)
			(xy 222.219124 -273.286511) (xy 222.198352 -273.296721) (xy 222.190818 -273.305524) (xy 222.172623 -273.328004)
			(xy 222.130603 -273.367738) (xy 222.083069 -273.400677) (xy 222.031109 -273.426066) (xy 221.975912 -273.443323)
			(xy 221.918744 -273.452054) (xy 221.889828 -273.45259) (xy 221.862573 -273.452165) (xy 221.808616 -273.444411)
			(xy 221.756312 -273.429057) (xy 221.706726 -273.406415) (xy 221.660867 -273.376946) (xy 221.619669 -273.341251)
			(xy 221.583971 -273.300055) (xy 221.554499 -273.254198) (xy 221.531853 -273.204614) (xy 221.516495 -273.152311)
			(xy 221.508737 -273.098355) (xy 209.00771 -273.098355) (xy 209.00771 -288.15538) (xy 225.493324 -288.15538)
			(xy 225.497395 -288.099758) (xy 225.509521 -288.045321) (xy 225.529444 -287.99323) (xy 225.55674 -287.944595)
			(xy 225.590826 -287.900452) (xy 225.630975 -287.861743) (xy 225.676333 -287.829292) (xy 225.725933 -287.803791)
			(xy 225.778717 -287.785784) (xy 225.83356 -287.775654) (xy 225.889294 -287.773617) (xy 225.944731 -287.779717)
			(xy 225.998688 -287.793823) (xy 226.050017 -287.815635) (xy 226.097623 -287.844689) (xy 226.140491 -287.880364)
			(xy 226.177708 -287.921901) (xy 226.208481 -287.968414) (xy 226.232153 -288.018911) (xy 226.248221 -288.072318)
			(xy 226.255698 -288.123122) (xy 237.653574 -288.123122) (xy 237.657645 -288.0675) (xy 237.669771 -288.013063)
			(xy 237.689694 -287.960972) (xy 237.71699 -287.912337) (xy 237.751076 -287.868194) (xy 237.791225 -287.829485)
			(xy 237.836583 -287.797034) (xy 237.886183 -287.771533) (xy 237.938967 -287.753526) (xy 237.99381 -287.743396)
			(xy 238.049544 -287.741359) (xy 238.104981 -287.747459) (xy 238.158938 -287.761565) (xy 238.210267 -287.783377)
			(xy 238.257873 -287.812431) (xy 238.300741 -287.848106) (xy 238.337958 -287.889643) (xy 238.368731 -287.936156)
			(xy 238.392403 -287.986653) (xy 238.408471 -288.04006) (xy 238.416591 -288.095236) (xy 238.4171 -288.123122)
			(xy 238.416591 -288.151008) (xy 238.408471 -288.206184) (xy 238.392403 -288.259591) (xy 238.368731 -288.310088)
			(xy 238.337958 -288.356601) (xy 238.300741 -288.398138) (xy 238.257873 -288.433813) (xy 238.210267 -288.462867)
			(xy 238.158938 -288.484679) (xy 238.104981 -288.498785) (xy 238.049544 -288.504885) (xy 237.99381 -288.502848)
			(xy 237.938967 -288.492718) (xy 237.886183 -288.474711) (xy 237.836583 -288.44921) (xy 237.791225 -288.416759)
			(xy 237.751076 -288.37805) (xy 237.71699 -288.333907) (xy 237.689694 -288.285272) (xy 237.669771 -288.233181)
			(xy 237.657645 -288.178744) (xy 237.653574 -288.123122) (xy 226.255698 -288.123122) (xy 226.256341 -288.127494)
			(xy 226.25685 -288.15538) (xy 226.256341 -288.183266) (xy 226.248221 -288.238442) (xy 226.232153 -288.291849)
			(xy 226.208481 -288.342346) (xy 226.177708 -288.388859) (xy 226.140491 -288.430396) (xy 226.097623 -288.466071)
			(xy 226.050017 -288.495125) (xy 225.998688 -288.516937) (xy 225.944731 -288.531043) (xy 225.889294 -288.537143)
			(xy 225.83356 -288.535106) (xy 225.778717 -288.524976) (xy 225.725933 -288.506969) (xy 225.676333 -288.481468)
			(xy 225.630975 -288.449017) (xy 225.590826 -288.410308) (xy 225.55674 -288.366165) (xy 225.529444 -288.31753)
			(xy 225.509521 -288.265439) (xy 225.497395 -288.211002) (xy 225.493324 -288.15538) (xy 209.00771 -288.15538)
			(xy 209.00771 -288.939732) (xy 228.82352 -288.939732) (xy 228.824006 -288.912481) (xy 228.831762 -288.858533)
			(xy 228.847117 -288.806238) (xy 228.869759 -288.756661) (xy 228.899225 -288.710811) (xy 228.934916 -288.66962)
			(xy 228.976107 -288.633929) (xy 229.021957 -288.604463) (xy 229.071534 -288.581821) (xy 229.123829 -288.566466)
			(xy 229.177777 -288.55871) (xy 229.232279 -288.55871) (xy 229.286227 -288.566466) (xy 229.338522 -288.581821)
			(xy 229.388099 -288.604463) (xy 229.433949 -288.633929) (xy 229.47514 -288.66962) (xy 229.510831 -288.710811)
			(xy 229.540297 -288.756661) (xy 229.562939 -288.806238) (xy 229.578294 -288.858533) (xy 229.58605 -288.912481)
			(xy 229.586536 -288.939732) (xy 240.76787 -288.939732) (xy 240.768356 -288.912481) (xy 240.776112 -288.858533)
			(xy 240.791467 -288.806238) (xy 240.814109 -288.756661) (xy 240.843575 -288.710811) (xy 240.879266 -288.66962)
			(xy 240.920457 -288.633929) (xy 240.966307 -288.604463) (xy 241.015884 -288.581821) (xy 241.068179 -288.566466)
			(xy 241.122127 -288.55871) (xy 241.176629 -288.55871) (xy 241.230577 -288.566466) (xy 241.282872 -288.581821)
			(xy 241.332449 -288.604463) (xy 241.378299 -288.633929) (xy 241.41949 -288.66962) (xy 241.455181 -288.710811)
			(xy 241.484647 -288.756661) (xy 241.507289 -288.806238) (xy 241.522644 -288.858533) (xy 241.5304 -288.912481)
			(xy 241.530886 -288.939732) (xy 241.530366 -288.967593) (xy 241.522273 -289.022725) (xy 241.506249 -289.076094)
			(xy 241.482635 -289.126566) (xy 241.451932 -289.173067) (xy 241.414794 -289.214609) (xy 241.393726 -289.232848)
			(xy 241.384582 -289.240468) (xy 241.37493 -289.26155) (xy 241.378486 -289.365436) (xy 241.389408 -289.38601)
			(xy 241.39906 -289.393122) (xy 241.41961 -289.408545) (xy 241.456743 -289.444058) (xy 241.488774 -289.484233)
			(xy 241.515123 -289.528344) (xy 241.535312 -289.575593) (xy 241.548976 -289.625124) (xy 241.555869 -289.676041)
			(xy 241.556286 -289.701732) (xy 241.5558 -289.728983) (xy 241.548044 -289.782931) (xy 241.532689 -289.835226)
			(xy 241.510047 -289.884803) (xy 241.480581 -289.930653) (xy 241.44489 -289.971844) (xy 241.403699 -290.007535)
			(xy 241.357849 -290.037001) (xy 241.308272 -290.059643) (xy 241.255977 -290.074998) (xy 241.202029 -290.082754)
			(xy 241.147527 -290.082754) (xy 241.093579 -290.074998) (xy 241.041284 -290.059643) (xy 240.991707 -290.037001)
			(xy 240.945857 -290.007535) (xy 240.904666 -289.971844) (xy 240.868975 -289.930653) (xy 240.839509 -289.884803)
			(xy 240.816867 -289.835226) (xy 240.801512 -289.782931) (xy 240.793756 -289.728983) (xy 240.79327 -289.701732)
			(xy 240.793781 -289.67387) (xy 240.801878 -289.618739) (xy 240.817905 -289.565371) (xy 240.841521 -289.514899)
			(xy 240.872224 -289.468398) (xy 240.909363 -289.426856) (xy 240.93043 -289.408616) (xy 240.939574 -289.400996)
			(xy 240.949226 -289.379914) (xy 240.94567 -289.276028) (xy 240.934748 -289.255454) (xy 240.925096 -289.248342)
			(xy 240.904589 -289.232864) (xy 240.867451 -289.197363) (xy 240.835415 -289.157198) (xy 240.809061 -289.113096)
			(xy 240.788864 -289.065855) (xy 240.775192 -289.016331) (xy 240.768292 -288.96542) (xy 240.76787 -288.939732)
			(xy 229.586536 -288.939732) (xy 229.585998 -288.967593) (xy 229.577906 -289.022723) (xy 229.561885 -289.076091)
			(xy 229.538274 -289.126562) (xy 229.507575 -289.173063) (xy 229.470441 -289.214608) (xy 229.449376 -289.232848)
			(xy 229.440232 -289.240468) (xy 229.43058 -289.26155) (xy 229.434136 -289.365436) (xy 229.445058 -289.38601)
			(xy 229.45471 -289.393122) (xy 229.475249 -289.408559) (xy 229.512385 -289.444068) (xy 229.544418 -289.48424)
			(xy 229.570769 -289.528349) (xy 229.59096 -289.575596) (xy 229.604625 -289.625126) (xy 229.611519 -289.676042)
			(xy 229.611936 -289.701732) (xy 229.61145 -289.728983) (xy 229.603694 -289.782931) (xy 229.588339 -289.835226)
			(xy 229.565697 -289.884803) (xy 229.536231 -289.930653) (xy 229.50054 -289.971844) (xy 229.459349 -290.007535)
			(xy 229.413499 -290.037001) (xy 229.363922 -290.059643) (xy 229.311627 -290.074998) (xy 229.257679 -290.082754)
			(xy 229.203177 -290.082754) (xy 229.149229 -290.074998) (xy 229.096934 -290.059643) (xy 229.047357 -290.037001)
			(xy 229.001507 -290.007535) (xy 228.960316 -289.971844) (xy 228.924625 -289.930653) (xy 228.895159 -289.884803)
			(xy 228.872517 -289.835226) (xy 228.857162 -289.782931) (xy 228.849406 -289.728983) (xy 228.84892 -289.701732)
			(xy 228.849448 -289.673871) (xy 228.857544 -289.618741) (xy 228.873569 -289.565374) (xy 228.897182 -289.514903)
			(xy 228.927881 -289.468402) (xy 228.965015 -289.426857) (xy 228.98608 -289.408616) (xy 228.995224 -289.400996)
			(xy 229.004876 -289.379914) (xy 229.00132 -289.276028) (xy 228.990398 -289.255454) (xy 228.980746 -289.248342)
			(xy 228.960228 -289.232879) (xy 228.923093 -289.197373) (xy 228.891059 -289.157205) (xy 228.864707 -289.1131)
			(xy 228.844512 -289.065858) (xy 228.830842 -289.016333) (xy 228.823942 -288.965421) (xy 228.82352 -288.939732)
			(xy 209.00771 -288.939732) (xy 209.00771 -290.844732) (xy 236.659418 -290.844732) (xy 236.663489 -290.78911)
			(xy 236.675615 -290.734673) (xy 236.695538 -290.682582) (xy 236.722834 -290.633947) (xy 236.75692 -290.589804)
			(xy 236.797069 -290.551095) (xy 236.842427 -290.518644) (xy 236.892027 -290.493143) (xy 236.944811 -290.475136)
			(xy 236.999654 -290.465006) (xy 237.055388 -290.462969) (xy 237.110825 -290.469069) (xy 237.164782 -290.483175)
			(xy 237.216111 -290.504987) (xy 237.263717 -290.534041) (xy 237.306585 -290.569716) (xy 237.343802 -290.611253)
			(xy 237.374575 -290.657766) (xy 237.398247 -290.708263) (xy 237.414315 -290.76167) (xy 237.422435 -290.816846)
			(xy 237.422944 -290.844732) (xy 237.422435 -290.872618) (xy 237.414315 -290.927794) (xy 237.398247 -290.981201)
			(xy 237.374575 -291.031698) (xy 237.343802 -291.078211) (xy 237.306585 -291.119748) (xy 237.263717 -291.155423)
			(xy 237.216111 -291.184477) (xy 237.164782 -291.206289) (xy 237.110825 -291.220395) (xy 237.055388 -291.226495)
			(xy 236.999654 -291.224458) (xy 236.944811 -291.214328) (xy 236.892027 -291.196321) (xy 236.842427 -291.17082)
			(xy 236.797069 -291.138369) (xy 236.75692 -291.09966) (xy 236.722834 -291.055517) (xy 236.695538 -291.006882)
			(xy 236.675615 -290.954791) (xy 236.663489 -290.900354) (xy 236.659418 -290.844732) (xy 209.00771 -290.844732)
			(xy 209.00771 -291.614098) (xy 237.461804 -291.614098) (xy 237.465875 -291.558476) (xy 237.478001 -291.504039)
			(xy 237.497924 -291.451948) (xy 237.52522 -291.403313) (xy 237.559306 -291.35917) (xy 237.599455 -291.320461)
			(xy 237.644813 -291.28801) (xy 237.694413 -291.262509) (xy 237.747197 -291.244502) (xy 237.80204 -291.234372)
			(xy 237.857774 -291.232335) (xy 237.913211 -291.238435) (xy 237.967168 -291.252541) (xy 238.018497 -291.274353)
			(xy 238.066103 -291.303407) (xy 238.108971 -291.339082) (xy 238.146188 -291.380619) (xy 238.176961 -291.427132)
			(xy 238.200633 -291.477629) (xy 238.216701 -291.531036) (xy 238.224821 -291.586212) (xy 238.22533 -291.614098)
			(xy 238.224821 -291.641984) (xy 238.216701 -291.69716) (xy 238.200633 -291.750567) (xy 238.176961 -291.801064)
			(xy 238.146188 -291.847577) (xy 238.108971 -291.889114) (xy 238.066103 -291.924789) (xy 238.018497 -291.953843)
			(xy 237.967168 -291.975655) (xy 237.913211 -291.989761) (xy 237.857774 -291.995861) (xy 237.80204 -291.993824)
			(xy 237.747197 -291.983694) (xy 237.694413 -291.965687) (xy 237.644813 -291.940186) (xy 237.599455 -291.907735)
			(xy 237.559306 -291.869026) (xy 237.52522 -291.824883) (xy 237.497924 -291.776248) (xy 237.478001 -291.724157)
			(xy 237.465875 -291.66972) (xy 237.461804 -291.614098) (xy 209.00771 -291.614098) (xy 209.00771 -292.025578)
			(xy 226.184966 -292.025578) (xy 226.189037 -291.969956) (xy 226.201163 -291.915519) (xy 226.221086 -291.863428)
			(xy 226.248382 -291.814793) (xy 226.282468 -291.77065) (xy 226.322617 -291.731941) (xy 226.367975 -291.69949)
			(xy 226.417575 -291.673989) (xy 226.470359 -291.655982) (xy 226.525202 -291.645852) (xy 226.580936 -291.643815)
			(xy 226.636373 -291.649915) (xy 226.69033 -291.664021) (xy 226.741659 -291.685833) (xy 226.789265 -291.714887)
			(xy 226.832133 -291.750562) (xy 226.86935 -291.792099) (xy 226.900123 -291.838612) (xy 226.923795 -291.889109)
			(xy 226.939863 -291.942516) (xy 226.947983 -291.997692) (xy 226.948492 -292.025578) (xy 226.947983 -292.053464)
			(xy 226.939863 -292.10864) (xy 226.923795 -292.162047) (xy 226.900123 -292.212544) (xy 226.86935 -292.259057)
			(xy 226.836853 -292.295326) (xy 228.289102 -292.295326) (xy 228.293173 -292.239704) (xy 228.305299 -292.185267)
			(xy 228.325222 -292.133176) (xy 228.352518 -292.084541) (xy 228.386604 -292.040398) (xy 228.426753 -292.001689)
			(xy 228.472111 -291.969238) (xy 228.521711 -291.943737) (xy 228.574495 -291.92573) (xy 228.629338 -291.9156)
			(xy 228.685072 -291.913563) (xy 228.740509 -291.919663) (xy 228.794466 -291.933769) (xy 228.845795 -291.955581)
			(xy 228.893401 -291.984635) (xy 228.936269 -292.02031) (xy 228.973486 -292.061847) (xy 229.004259 -292.10836)
			(xy 229.027931 -292.158857) (xy 229.043999 -292.212264) (xy 229.052119 -292.26744) (xy 229.052628 -292.295326)
			(xy 240.233452 -292.295326) (xy 240.237523 -292.239704) (xy 240.249649 -292.185267) (xy 240.269572 -292.133176)
			(xy 240.296868 -292.084541) (xy 240.330954 -292.040398) (xy 240.371103 -292.001689) (xy 240.416461 -291.969238)
			(xy 240.466061 -291.943737) (xy 240.518845 -291.92573) (xy 240.573688 -291.9156) (xy 240.629422 -291.913563)
			(xy 240.684859 -291.919663) (xy 240.738816 -291.933769) (xy 240.790145 -291.955581) (xy 240.837751 -291.984635)
			(xy 240.880619 -292.02031) (xy 240.917836 -292.061847) (xy 240.948609 -292.10836) (xy 240.972281 -292.158857)
			(xy 240.988349 -292.212264) (xy 240.996469 -292.26744) (xy 240.996978 -292.295326) (xy 240.996469 -292.323212)
			(xy 240.988349 -292.378388) (xy 240.972281 -292.431795) (xy 240.948609 -292.482292) (xy 240.917836 -292.528805)
			(xy 240.880619 -292.570342) (xy 240.837751 -292.606017) (xy 240.790145 -292.635071) (xy 240.738816 -292.656883)
			(xy 240.684859 -292.670989) (xy 240.629422 -292.677089) (xy 240.573688 -292.675052) (xy 240.518845 -292.664922)
			(xy 240.466061 -292.646915) (xy 240.416461 -292.621414) (xy 240.371103 -292.588963) (xy 240.330954 -292.550254)
			(xy 240.296868 -292.506111) (xy 240.269572 -292.457476) (xy 240.249649 -292.405385) (xy 240.237523 -292.350948)
			(xy 240.233452 -292.295326) (xy 229.052628 -292.295326) (xy 229.052119 -292.323212) (xy 229.043999 -292.378388)
			(xy 229.027931 -292.431795) (xy 229.004259 -292.482292) (xy 228.973486 -292.528805) (xy 228.936269 -292.570342)
			(xy 228.893401 -292.606017) (xy 228.845795 -292.635071) (xy 228.794466 -292.656883) (xy 228.740509 -292.670989)
			(xy 228.685072 -292.677089) (xy 228.629338 -292.675052) (xy 228.574495 -292.664922) (xy 228.521711 -292.646915)
			(xy 228.472111 -292.621414) (xy 228.426753 -292.588963) (xy 228.386604 -292.550254) (xy 228.352518 -292.506111)
			(xy 228.325222 -292.457476) (xy 228.305299 -292.405385) (xy 228.293173 -292.350948) (xy 228.289102 -292.295326)
			(xy 226.836853 -292.295326) (xy 226.832133 -292.300594) (xy 226.789265 -292.336269) (xy 226.741659 -292.365323)
			(xy 226.69033 -292.387135) (xy 226.636373 -292.401241) (xy 226.580936 -292.407341) (xy 226.525202 -292.405304)
			(xy 226.470359 -292.395174) (xy 226.417575 -292.377167) (xy 226.367975 -292.351666) (xy 226.322617 -292.319215)
			(xy 226.282468 -292.280506) (xy 226.248382 -292.236363) (xy 226.221086 -292.187728) (xy 226.201163 -292.135637)
			(xy 226.189037 -292.0812) (xy 226.184966 -292.025578) (xy 209.00771 -292.025578) (xy 209.00771 -293.537132)
			(xy 233.241848 -293.537132) (xy 233.245919 -293.48151) (xy 233.258045 -293.427073) (xy 233.277968 -293.374982)
			(xy 233.305264 -293.326347) (xy 233.33935 -293.282204) (xy 233.379499 -293.243495) (xy 233.424857 -293.211044)
			(xy 233.474457 -293.185543) (xy 233.527241 -293.167536) (xy 233.582084 -293.157406) (xy 233.637818 -293.155369)
			(xy 233.693255 -293.161469) (xy 233.747212 -293.175575) (xy 233.798541 -293.197387) (xy 233.846147 -293.226441)
			(xy 233.889015 -293.262116) (xy 233.926232 -293.303653) (xy 233.957005 -293.350166) (xy 233.980677 -293.400663)
			(xy 233.996745 -293.45407) (xy 234.004865 -293.509246) (xy 234.005374 -293.537132) (xy 245.186198 -293.537132)
			(xy 245.190269 -293.48151) (xy 245.202395 -293.427073) (xy 245.222318 -293.374982) (xy 245.249614 -293.326347)
			(xy 245.2837 -293.282204) (xy 245.323849 -293.243495) (xy 245.369207 -293.211044) (xy 245.418807 -293.185543)
			(xy 245.471591 -293.167536) (xy 245.526434 -293.157406) (xy 245.582168 -293.155369) (xy 245.637605 -293.161469)
			(xy 245.691562 -293.175575) (xy 245.742891 -293.197387) (xy 245.790497 -293.226441) (xy 245.833365 -293.262116)
			(xy 245.870582 -293.303653) (xy 245.901355 -293.350166) (xy 245.925027 -293.400663) (xy 245.941095 -293.45407)
			(xy 245.949215 -293.509246) (xy 245.949724 -293.537132) (xy 245.949215 -293.565018) (xy 245.941095 -293.620194)
			(xy 245.925027 -293.673601) (xy 245.901355 -293.724098) (xy 245.870582 -293.770611) (xy 245.833365 -293.812148)
			(xy 245.790497 -293.847823) (xy 245.742891 -293.876877) (xy 245.691562 -293.898689) (xy 245.637605 -293.912795)
			(xy 245.582168 -293.918895) (xy 245.526434 -293.916858) (xy 245.471591 -293.906728) (xy 245.418807 -293.888721)
			(xy 245.369207 -293.86322) (xy 245.323849 -293.830769) (xy 245.2837 -293.79206) (xy 245.249614 -293.747917)
			(xy 245.222318 -293.699282) (xy 245.202395 -293.647191) (xy 245.190269 -293.592754) (xy 245.186198 -293.537132)
			(xy 234.005374 -293.537132) (xy 234.004865 -293.565018) (xy 233.996745 -293.620194) (xy 233.980677 -293.673601)
			(xy 233.957005 -293.724098) (xy 233.926232 -293.770611) (xy 233.889015 -293.812148) (xy 233.846147 -293.847823)
			(xy 233.798541 -293.876877) (xy 233.747212 -293.898689) (xy 233.693255 -293.912795) (xy 233.637818 -293.918895)
			(xy 233.582084 -293.916858) (xy 233.527241 -293.906728) (xy 233.474457 -293.888721) (xy 233.424857 -293.86322)
			(xy 233.379499 -293.830769) (xy 233.33935 -293.79206) (xy 233.305264 -293.747917) (xy 233.277968 -293.699282)
			(xy 233.258045 -293.647191) (xy 233.245919 -293.592754) (xy 233.241848 -293.537132) (xy 209.00771 -293.537132)
			(xy 209.00771 -294.13962) (xy 209.008137 -294.149688) (xy 209.015858 -294.168287) (xy 209.022696 -294.175688)
			(xy 209.56016 -294.713152) (xy 209.567559 -294.719994) (xy 209.586158 -294.727714) (xy 209.596228 -294.728138)
		)
		(stroke
			(width 0)
			(type solid)
		)
		(fill yes)
		(layer "In11.Cu")
		(net "GND")
	)
	(gr_poly
		(pts
			(xy 430.913286 -112.658398) (xy 430.928257 -112.657827) (xy 430.956892 -112.649064) (xy 430.981756 -112.632376)
			(xy 431.000714 -112.609196) (xy 431.012138 -112.581515) (xy 431.015046 -112.551712) (xy 431.009187 -112.522345)
			(xy 430.995067 -112.495938) (xy 430.984914 -112.484916) (xy 429.821086 -111.321342) (xy 429.80864 -111.314484)
			(xy 429.801274 -111.31296) (xy 429.773262 -111.306342) (xy 429.719489 -111.28582) (xy 429.66941 -111.257451)
			(xy 429.624161 -111.22188) (xy 429.58477 -111.179915) (xy 429.552131 -111.132508) (xy 429.526985 -111.080735)
			(xy 429.509903 -111.025772) (xy 429.501272 -110.968866) (xy 429.500792 -110.940088) (xy 429.501279 -110.912837)
			(xy 429.509037 -110.858891) (xy 429.524393 -110.806598) (xy 429.547035 -110.757022) (xy 429.576501 -110.711173)
			(xy 429.612193 -110.669984) (xy 429.653383 -110.634294) (xy 429.699232 -110.604829) (xy 429.748809 -110.582188)
			(xy 429.801103 -110.566834) (xy 429.855049 -110.559078) (xy 429.8823 -110.55858) (xy 429.911071 -110.559111)
			(xy 429.967958 -110.567764) (xy 430.022901 -110.584861) (xy 430.074654 -110.610012) (xy 430.122045 -110.642648)
			(xy 430.163999 -110.682029) (xy 430.199565 -110.727263) (xy 430.227937 -110.777323) (xy 430.248471 -110.831076)
			(xy 430.255172 -110.859062) (xy 430.256696 -110.866428) (xy 430.263554 -110.878874) (xy 432.028092 -112.643412)
			(xy 432.035486 -112.650269) (xy 432.054085 -112.65802) (xy 432.06416 -112.658398) (xy 446.916302 -112.658398)
			(xy 446.926372 -112.657974) (xy 446.944976 -112.650259) (xy 446.95237 -112.643412) (xy 450.614542 -108.98124)
			(xy 450.621385 -108.973841) (xy 450.629107 -108.955242) (xy 450.629528 -108.945172) (xy 450.629528 -92.768928)
			(xy 450.621908 -92.750132) (xy 450.614542 -92.74302) (xy 448.10045 -90.228928) (xy 448.09305 -90.222087)
			(xy 448.074452 -90.214366) (xy 448.064382 -90.213942) (xy 417.129468 -90.213942) (xy 417.119401 -90.214372)
			(xy 417.100809 -90.2221) (xy 417.0934 -90.228928) (xy 416.051492 -91.270836) (xy 437.855358 -91.270836)
			(xy 437.859429 -91.215214) (xy 437.871555 -91.160777) (xy 437.891478 -91.108686) (xy 437.918774 -91.060051)
			(xy 437.95286 -91.015908) (xy 437.993009 -90.977199) (xy 438.038367 -90.944748) (xy 438.087967 -90.919247)
			(xy 438.140751 -90.90124) (xy 438.195594 -90.89111) (xy 438.251328 -90.889073) (xy 438.306765 -90.895173)
			(xy 438.360722 -90.909279) (xy 438.412051 -90.931091) (xy 438.459657 -90.960145) (xy 438.502525 -90.99582)
			(xy 438.539742 -91.037357) (xy 438.570515 -91.08387) (xy 438.594187 -91.134367) (xy 438.610255 -91.187774)
			(xy 438.618375 -91.24295) (xy 438.618884 -91.270836) (xy 438.618375 -91.298722) (xy 438.610255 -91.353898)
			(xy 438.594187 -91.407305) (xy 438.570515 -91.457802) (xy 438.539742 -91.504315) (xy 438.502525 -91.545852)
			(xy 438.459657 -91.581527) (xy 438.412051 -91.610581) (xy 438.360722 -91.632393) (xy 438.306765 -91.646499)
			(xy 438.251328 -91.652599) (xy 438.195594 -91.650562) (xy 438.140751 -91.640432) (xy 438.087967 -91.622425)
			(xy 438.038367 -91.596924) (xy 437.993009 -91.564473) (xy 437.95286 -91.525764) (xy 437.918774 -91.481621)
			(xy 437.891478 -91.432986) (xy 437.871555 -91.380895) (xy 437.859429 -91.326458) (xy 437.855358 -91.270836)
			(xy 416.051492 -91.270836) (xy 414.854136 -92.468192) (xy 445.845182 -92.468192) (xy 445.849253 -92.41257)
			(xy 445.861379 -92.358133) (xy 445.881302 -92.306042) (xy 445.908598 -92.257407) (xy 445.942684 -92.213264)
			(xy 445.982833 -92.174555) (xy 446.028191 -92.142104) (xy 446.077791 -92.116603) (xy 446.130575 -92.098596)
			(xy 446.185418 -92.088466) (xy 446.241152 -92.086429) (xy 446.296589 -92.092529) (xy 446.350546 -92.106635)
			(xy 446.401875 -92.128447) (xy 446.449481 -92.157501) (xy 446.492349 -92.193176) (xy 446.529566 -92.234713)
			(xy 446.560339 -92.281226) (xy 446.584011 -92.331723) (xy 446.600079 -92.38513) (xy 446.608199 -92.440306)
			(xy 446.608708 -92.468192) (xy 446.608199 -92.496078) (xy 446.600079 -92.551254) (xy 446.584011 -92.604661)
			(xy 446.560339 -92.655158) (xy 446.529566 -92.701671) (xy 446.492349 -92.743208) (xy 446.449481 -92.778883)
			(xy 446.401875 -92.807937) (xy 446.350546 -92.829749) (xy 446.296589 -92.843855) (xy 446.241152 -92.849955)
			(xy 446.185418 -92.847918) (xy 446.130575 -92.837788) (xy 446.077791 -92.819781) (xy 446.028191 -92.79428)
			(xy 445.982833 -92.761829) (xy 445.942684 -92.72312) (xy 445.908598 -92.678977) (xy 445.881302 -92.630342)
			(xy 445.861379 -92.578251) (xy 445.849253 -92.523814) (xy 445.845182 -92.468192) (xy 414.854136 -92.468192)
			(xy 414.014158 -93.30817) (xy 414.006792 -93.315282) (xy 413.999172 -93.334078) (xy 413.999172 -93.484192)
			(xy 445.845182 -93.484192) (xy 445.849253 -93.42857) (xy 445.861379 -93.374133) (xy 445.881302 -93.322042)
			(xy 445.908598 -93.273407) (xy 445.942684 -93.229264) (xy 445.982833 -93.190555) (xy 446.028191 -93.158104)
			(xy 446.077791 -93.132603) (xy 446.130575 -93.114596) (xy 446.185418 -93.104466) (xy 446.241152 -93.102429)
			(xy 446.296589 -93.108529) (xy 446.350546 -93.122635) (xy 446.401875 -93.144447) (xy 446.449481 -93.173501)
			(xy 446.492349 -93.209176) (xy 446.529566 -93.250713) (xy 446.560339 -93.297226) (xy 446.584011 -93.347723)
			(xy 446.600079 -93.40113) (xy 446.608199 -93.456306) (xy 446.608708 -93.484192) (xy 446.608199 -93.512078)
			(xy 446.600079 -93.567254) (xy 446.584011 -93.620661) (xy 446.560339 -93.671158) (xy 446.529566 -93.717671)
			(xy 446.492349 -93.759208) (xy 446.449481 -93.794883) (xy 446.401875 -93.823937) (xy 446.350546 -93.845749)
			(xy 446.296589 -93.859855) (xy 446.241152 -93.865955) (xy 446.185418 -93.863918) (xy 446.130575 -93.853788)
			(xy 446.077791 -93.835781) (xy 446.028191 -93.81028) (xy 445.982833 -93.777829) (xy 445.942684 -93.73912)
			(xy 445.908598 -93.694977) (xy 445.881302 -93.646342) (xy 445.861379 -93.594251) (xy 445.849253 -93.539814)
			(xy 445.845182 -93.484192) (xy 413.999172 -93.484192) (xy 413.999172 -93.891608) (xy 430.965862 -93.891608)
			(xy 430.969933 -93.835986) (xy 430.982059 -93.781549) (xy 431.001982 -93.729458) (xy 431.029278 -93.680823)
			(xy 431.063364 -93.63668) (xy 431.103513 -93.597971) (xy 431.148871 -93.56552) (xy 431.198471 -93.540019)
			(xy 431.251255 -93.522012) (xy 431.306098 -93.511882) (xy 431.361832 -93.509845) (xy 431.417269 -93.515945)
			(xy 431.471226 -93.530051) (xy 431.522555 -93.551863) (xy 431.570161 -93.580917) (xy 431.613029 -93.616592)
			(xy 431.650246 -93.658129) (xy 431.681019 -93.704642) (xy 431.704691 -93.755139) (xy 431.720759 -93.808546)
			(xy 431.728879 -93.863722) (xy 431.729388 -93.891608) (xy 431.728879 -93.919494) (xy 431.720759 -93.97467)
			(xy 431.704691 -94.028077) (xy 431.681019 -94.078574) (xy 431.650246 -94.125087) (xy 431.613029 -94.166624)
			(xy 431.570161 -94.202299) (xy 431.522555 -94.231353) (xy 431.471226 -94.253165) (xy 431.417269 -94.267271)
			(xy 431.361832 -94.273371) (xy 431.306098 -94.271334) (xy 431.251255 -94.261204) (xy 431.198471 -94.243197)
			(xy 431.148871 -94.217696) (xy 431.103513 -94.185245) (xy 431.063364 -94.146536) (xy 431.029278 -94.102393)
			(xy 431.001982 -94.053758) (xy 430.982059 -94.001667) (xy 430.969933 -93.94723) (xy 430.965862 -93.891608)
			(xy 413.999172 -93.891608) (xy 413.999172 -94.275148) (xy 436.294782 -94.275148) (xy 436.298853 -94.219526)
			(xy 436.310979 -94.165089) (xy 436.330902 -94.112998) (xy 436.358198 -94.064363) (xy 436.392284 -94.02022)
			(xy 436.432433 -93.981511) (xy 436.477791 -93.94906) (xy 436.527391 -93.923559) (xy 436.580175 -93.905552)
			(xy 436.635018 -93.895422) (xy 436.690752 -93.893385) (xy 436.746189 -93.899485) (xy 436.800146 -93.913591)
			(xy 436.851475 -93.935403) (xy 436.899081 -93.964457) (xy 436.941949 -94.000132) (xy 436.979166 -94.041669)
			(xy 437.009939 -94.088182) (xy 437.033611 -94.138679) (xy 437.049679 -94.192086) (xy 437.057799 -94.247262)
			(xy 437.058308 -94.275148) (xy 437.057799 -94.303034) (xy 437.049679 -94.35821) (xy 437.033611 -94.411617)
			(xy 437.009939 -94.462114) (xy 436.979166 -94.508627) (xy 436.941949 -94.550164) (xy 436.899081 -94.585839)
			(xy 436.871277 -94.602808) (xy 445.878964 -94.602808) (xy 445.883035 -94.547186) (xy 445.895161 -94.492749)
			(xy 445.915084 -94.440658) (xy 445.94238 -94.392023) (xy 445.976466 -94.34788) (xy 446.016615 -94.309171)
			(xy 446.061973 -94.27672) (xy 446.111573 -94.251219) (xy 446.164357 -94.233212) (xy 446.2192 -94.223082)
			(xy 446.274934 -94.221045) (xy 446.330371 -94.227145) (xy 446.384328 -94.241251) (xy 446.435657 -94.263063)
			(xy 446.483263 -94.292117) (xy 446.526131 -94.327792) (xy 446.563348 -94.369329) (xy 446.594121 -94.415842)
			(xy 446.617793 -94.466339) (xy 446.633861 -94.519746) (xy 446.641981 -94.574922) (xy 446.64249 -94.602808)
			(xy 449.269102 -94.602808) (xy 449.273173 -94.547186) (xy 449.285299 -94.492749) (xy 449.305222 -94.440658)
			(xy 449.332518 -94.392023) (xy 449.366604 -94.34788) (xy 449.406753 -94.309171) (xy 449.452111 -94.27672)
			(xy 449.501711 -94.251219) (xy 449.554495 -94.233212) (xy 449.609338 -94.223082) (xy 449.665072 -94.221045)
			(xy 449.720509 -94.227145) (xy 449.774466 -94.241251) (xy 449.825795 -94.263063) (xy 449.873401 -94.292117)
			(xy 449.916269 -94.327792) (xy 449.953486 -94.369329) (xy 449.984259 -94.415842) (xy 450.007931 -94.466339)
			(xy 450.023999 -94.519746) (xy 450.032119 -94.574922) (xy 450.032628 -94.602808) (xy 450.032119 -94.630694)
			(xy 450.023999 -94.68587) (xy 450.007931 -94.739277) (xy 449.984259 -94.789774) (xy 449.953486 -94.836287)
			(xy 449.916269 -94.877824) (xy 449.873401 -94.913499) (xy 449.825795 -94.942553) (xy 449.774466 -94.964365)
			(xy 449.720509 -94.978471) (xy 449.665072 -94.984571) (xy 449.609338 -94.982534) (xy 449.554495 -94.972404)
			(xy 449.501711 -94.954397) (xy 449.452111 -94.928896) (xy 449.406753 -94.896445) (xy 449.366604 -94.857736)
			(xy 449.332518 -94.813593) (xy 449.305222 -94.764958) (xy 449.285299 -94.712867) (xy 449.273173 -94.65843)
			(xy 449.269102 -94.602808) (xy 446.64249 -94.602808) (xy 446.641981 -94.630694) (xy 446.633861 -94.68587)
			(xy 446.617793 -94.739277) (xy 446.594121 -94.789774) (xy 446.563348 -94.836287) (xy 446.526131 -94.877824)
			(xy 446.483263 -94.913499) (xy 446.435657 -94.942553) (xy 446.384328 -94.964365) (xy 446.330371 -94.978471)
			(xy 446.274934 -94.984571) (xy 446.2192 -94.982534) (xy 446.164357 -94.972404) (xy 446.111573 -94.954397)
			(xy 446.061973 -94.928896) (xy 446.016615 -94.896445) (xy 445.976466 -94.857736) (xy 445.94238 -94.813593)
			(xy 445.915084 -94.764958) (xy 445.895161 -94.712867) (xy 445.883035 -94.65843) (xy 445.878964 -94.602808)
			(xy 436.871277 -94.602808) (xy 436.851475 -94.614893) (xy 436.800146 -94.636705) (xy 436.746189 -94.650811)
			(xy 436.690752 -94.656911) (xy 436.635018 -94.654874) (xy 436.580175 -94.644744) (xy 436.527391 -94.626737)
			(xy 436.477791 -94.601236) (xy 436.432433 -94.568785) (xy 436.392284 -94.530076) (xy 436.358198 -94.485933)
			(xy 436.330902 -94.437298) (xy 436.310979 -94.385207) (xy 436.298853 -94.33077) (xy 436.294782 -94.275148)
			(xy 413.999172 -94.275148) (xy 413.999172 -95.957898) (xy 438.606182 -95.957898) (xy 438.610253 -95.902276)
			(xy 438.622379 -95.847839) (xy 438.642302 -95.795748) (xy 438.669598 -95.747113) (xy 438.703684 -95.70297)
			(xy 438.743833 -95.664261) (xy 438.789191 -95.63181) (xy 438.838791 -95.606309) (xy 438.891575 -95.588302)
			(xy 438.946418 -95.578172) (xy 439.002152 -95.576135) (xy 439.057589 -95.582235) (xy 439.111546 -95.596341)
			(xy 439.162875 -95.618153) (xy 439.210481 -95.647207) (xy 439.253349 -95.682882) (xy 439.290566 -95.724419)
			(xy 439.321339 -95.770932) (xy 439.345011 -95.821429) (xy 439.360469 -95.872808) (xy 442.723522 -95.872808)
			(xy 442.727593 -95.817186) (xy 442.739719 -95.762749) (xy 442.759642 -95.710658) (xy 442.786938 -95.662023)
			(xy 442.821024 -95.61788) (xy 442.861173 -95.579171) (xy 442.906531 -95.54672) (xy 442.956131 -95.521219)
			(xy 443.008915 -95.503212) (xy 443.063758 -95.493082) (xy 443.119492 -95.491045) (xy 443.174929 -95.497145)
			(xy 443.228886 -95.511251) (xy 443.280215 -95.533063) (xy 443.327821 -95.562117) (xy 443.370689 -95.597792)
			(xy 443.407906 -95.639329) (xy 443.438679 -95.685842) (xy 443.462351 -95.736339) (xy 443.478419 -95.789746)
			(xy 443.486539 -95.844922) (xy 443.487048 -95.872808) (xy 449.253862 -95.872808) (xy 449.257933 -95.817186)
			(xy 449.270059 -95.762749) (xy 449.289982 -95.710658) (xy 449.317278 -95.662023) (xy 449.351364 -95.61788)
			(xy 449.391513 -95.579171) (xy 449.436871 -95.54672) (xy 449.486471 -95.521219) (xy 449.539255 -95.503212)
			(xy 449.594098 -95.493082) (xy 449.649832 -95.491045) (xy 449.705269 -95.497145) (xy 449.759226 -95.511251)
			(xy 449.810555 -95.533063) (xy 449.858161 -95.562117) (xy 449.901029 -95.597792) (xy 449.938246 -95.639329)
			(xy 449.969019 -95.685842) (xy 449.992691 -95.736339) (xy 450.008759 -95.789746) (xy 450.016879 -95.844922)
			(xy 450.017388 -95.872808) (xy 450.016879 -95.900694) (xy 450.008759 -95.95587) (xy 449.992691 -96.009277)
			(xy 449.969019 -96.059774) (xy 449.938246 -96.106287) (xy 449.901029 -96.147824) (xy 449.858161 -96.183499)
			(xy 449.810555 -96.212553) (xy 449.759226 -96.234365) (xy 449.705269 -96.248471) (xy 449.649832 -96.254571)
			(xy 449.594098 -96.252534) (xy 449.539255 -96.242404) (xy 449.486471 -96.224397) (xy 449.436871 -96.198896)
			(xy 449.391513 -96.166445) (xy 449.351364 -96.127736) (xy 449.317278 -96.083593) (xy 449.289982 -96.034958)
			(xy 449.270059 -95.982867) (xy 449.257933 -95.92843) (xy 449.253862 -95.872808) (xy 443.487048 -95.872808)
			(xy 443.486539 -95.900694) (xy 443.478419 -95.95587) (xy 443.462351 -96.009277) (xy 443.438679 -96.059774)
			(xy 443.407906 -96.106287) (xy 443.370689 -96.147824) (xy 443.327821 -96.183499) (xy 443.280215 -96.212553)
			(xy 443.228886 -96.234365) (xy 443.174929 -96.248471) (xy 443.119492 -96.254571) (xy 443.063758 -96.252534)
			(xy 443.008915 -96.242404) (xy 442.956131 -96.224397) (xy 442.906531 -96.198896) (xy 442.861173 -96.166445)
			(xy 442.821024 -96.127736) (xy 442.786938 -96.083593) (xy 442.759642 -96.034958) (xy 442.739719 -95.982867)
			(xy 442.727593 -95.92843) (xy 442.723522 -95.872808) (xy 439.360469 -95.872808) (xy 439.361079 -95.874836)
			(xy 439.369199 -95.930012) (xy 439.369708 -95.957898) (xy 439.369199 -95.985784) (xy 439.361079 -96.04096)
			(xy 439.345011 -96.094367) (xy 439.321339 -96.144864) (xy 439.290566 -96.191377) (xy 439.253349 -96.232914)
			(xy 439.210481 -96.268589) (xy 439.162875 -96.297643) (xy 439.111546 -96.319455) (xy 439.057589 -96.333561)
			(xy 439.002152 -96.339661) (xy 438.946418 -96.337624) (xy 438.891575 -96.327494) (xy 438.838791 -96.309487)
			(xy 438.789191 -96.283986) (xy 438.743833 -96.251535) (xy 438.703684 -96.212826) (xy 438.669598 -96.168683)
			(xy 438.642302 -96.120048) (xy 438.622379 -96.067957) (xy 438.610253 -96.01352) (xy 438.606182 -95.957898)
			(xy 413.999172 -95.957898) (xy 413.999172 -96.812608) (xy 434.902862 -96.812608) (xy 434.906933 -96.756986)
			(xy 434.919059 -96.702549) (xy 434.938982 -96.650458) (xy 434.966278 -96.601823) (xy 435.000364 -96.55768)
			(xy 435.040513 -96.518971) (xy 435.085871 -96.48652) (xy 435.135471 -96.461019) (xy 435.188255 -96.443012)
			(xy 435.243098 -96.432882) (xy 435.298832 -96.430845) (xy 435.354269 -96.436945) (xy 435.408226 -96.451051)
			(xy 435.459555 -96.472863) (xy 435.507161 -96.501917) (xy 435.550029 -96.537592) (xy 435.587246 -96.579129)
			(xy 435.618019 -96.625642) (xy 435.641691 -96.676139) (xy 435.657759 -96.729546) (xy 435.665879 -96.784722)
			(xy 435.666388 -96.812608) (xy 435.791862 -96.812608) (xy 435.795933 -96.756986) (xy 435.808059 -96.702549)
			(xy 435.827982 -96.650458) (xy 435.855278 -96.601823) (xy 435.889364 -96.55768) (xy 435.929513 -96.518971)
			(xy 435.974871 -96.48652) (xy 436.024471 -96.461019) (xy 436.077255 -96.443012) (xy 436.132098 -96.432882)
			(xy 436.187832 -96.430845) (xy 436.243269 -96.436945) (xy 436.297226 -96.451051) (xy 436.348555 -96.472863)
			(xy 436.396161 -96.501917) (xy 436.439029 -96.537592) (xy 436.476246 -96.579129) (xy 436.507019 -96.625642)
			(xy 436.530691 -96.676139) (xy 436.546759 -96.729546) (xy 436.554879 -96.784722) (xy 436.555388 -96.812608)
			(xy 436.554879 -96.840494) (xy 436.546759 -96.89567) (xy 436.530691 -96.949077) (xy 436.507019 -96.999574)
			(xy 436.476246 -97.046087) (xy 436.439029 -97.087624) (xy 436.396161 -97.123299) (xy 436.348555 -97.152353)
			(xy 436.297226 -97.174165) (xy 436.243269 -97.188271) (xy 436.187832 -97.194371) (xy 436.132098 -97.192334)
			(xy 436.077255 -97.182204) (xy 436.024471 -97.164197) (xy 435.974871 -97.138696) (xy 435.929513 -97.106245)
			(xy 435.889364 -97.067536) (xy 435.855278 -97.023393) (xy 435.827982 -96.974758) (xy 435.808059 -96.922667)
			(xy 435.795933 -96.86823) (xy 435.791862 -96.812608) (xy 435.666388 -96.812608) (xy 435.665879 -96.840494)
			(xy 435.657759 -96.89567) (xy 435.641691 -96.949077) (xy 435.618019 -96.999574) (xy 435.587246 -97.046087)
			(xy 435.550029 -97.087624) (xy 435.507161 -97.123299) (xy 435.459555 -97.152353) (xy 435.408226 -97.174165)
			(xy 435.354269 -97.188271) (xy 435.298832 -97.194371) (xy 435.243098 -97.192334) (xy 435.188255 -97.182204)
			(xy 435.135471 -97.164197) (xy 435.085871 -97.138696) (xy 435.040513 -97.106245) (xy 435.000364 -97.067536)
			(xy 434.966278 -97.023393) (xy 434.938982 -96.974758) (xy 434.919059 -96.922667) (xy 434.906933 -96.86823)
			(xy 434.902862 -96.812608) (xy 413.999172 -96.812608) (xy 413.999172 -97.254568) (xy 442.690502 -97.254568)
			(xy 442.694573 -97.198946) (xy 442.706699 -97.144509) (xy 442.726622 -97.092418) (xy 442.753918 -97.043783)
			(xy 442.788004 -96.99964) (xy 442.828153 -96.960931) (xy 442.873511 -96.92848) (xy 442.923111 -96.902979)
			(xy 442.975895 -96.884972) (xy 443.030738 -96.874842) (xy 443.086472 -96.872805) (xy 443.141909 -96.878905)
			(xy 443.195866 -96.893011) (xy 443.247195 -96.914823) (xy 443.294801 -96.943877) (xy 443.337669 -96.979552)
			(xy 443.374886 -97.021089) (xy 443.405659 -97.067602) (xy 443.429331 -97.118099) (xy 443.445399 -97.171506)
			(xy 443.453519 -97.226682) (xy 443.454028 -97.254568) (xy 443.45375 -97.269808) (xy 449.253862 -97.269808)
			(xy 449.257933 -97.214186) (xy 449.270059 -97.159749) (xy 449.289982 -97.107658) (xy 449.317278 -97.059023)
			(xy 449.351364 -97.01488) (xy 449.391513 -96.976171) (xy 449.436871 -96.94372) (xy 449.486471 -96.918219)
			(xy 449.539255 -96.900212) (xy 449.594098 -96.890082) (xy 449.649832 -96.888045) (xy 449.705269 -96.894145)
			(xy 449.759226 -96.908251) (xy 449.810555 -96.930063) (xy 449.858161 -96.959117) (xy 449.901029 -96.994792)
			(xy 449.938246 -97.036329) (xy 449.969019 -97.082842) (xy 449.992691 -97.133339) (xy 450.008759 -97.186746)
			(xy 450.016879 -97.241922) (xy 450.017388 -97.269808) (xy 450.016879 -97.297694) (xy 450.008759 -97.35287)
			(xy 449.992691 -97.406277) (xy 449.969019 -97.456774) (xy 449.938246 -97.503287) (xy 449.901029 -97.544824)
			(xy 449.858161 -97.580499) (xy 449.810555 -97.609553) (xy 449.759226 -97.631365) (xy 449.705269 -97.645471)
			(xy 449.649832 -97.651571) (xy 449.594098 -97.649534) (xy 449.539255 -97.639404) (xy 449.486471 -97.621397)
			(xy 449.436871 -97.595896) (xy 449.391513 -97.563445) (xy 449.351364 -97.524736) (xy 449.317278 -97.480593)
			(xy 449.289982 -97.431958) (xy 449.270059 -97.379867) (xy 449.257933 -97.32543) (xy 449.253862 -97.269808)
			(xy 443.45375 -97.269808) (xy 443.453519 -97.282454) (xy 443.445399 -97.33763) (xy 443.429331 -97.391037)
			(xy 443.405659 -97.441534) (xy 443.374886 -97.488047) (xy 443.337669 -97.529584) (xy 443.294801 -97.565259)
			(xy 443.247195 -97.594313) (xy 443.195866 -97.616125) (xy 443.141909 -97.630231) (xy 443.086472 -97.636331)
			(xy 443.030738 -97.634294) (xy 442.975895 -97.624164) (xy 442.923111 -97.606157) (xy 442.873511 -97.580656)
			(xy 442.828153 -97.548205) (xy 442.788004 -97.509496) (xy 442.753918 -97.465353) (xy 442.726622 -97.416718)
			(xy 442.706699 -97.364627) (xy 442.694573 -97.31019) (xy 442.690502 -97.254568) (xy 413.999172 -97.254568)
			(xy 413.999172 -97.701608) (xy 434.902862 -97.701608) (xy 434.906933 -97.645986) (xy 434.919059 -97.591549)
			(xy 434.938982 -97.539458) (xy 434.966278 -97.490823) (xy 435.000364 -97.44668) (xy 435.040513 -97.407971)
			(xy 435.085871 -97.37552) (xy 435.135471 -97.350019) (xy 435.188255 -97.332012) (xy 435.243098 -97.321882)
			(xy 435.298832 -97.319845) (xy 435.354269 -97.325945) (xy 435.408226 -97.340051) (xy 435.459555 -97.361863)
			(xy 435.507161 -97.390917) (xy 435.550029 -97.426592) (xy 435.587246 -97.468129) (xy 435.618019 -97.514642)
			(xy 435.641691 -97.565139) (xy 435.657759 -97.618546) (xy 435.665879 -97.673722) (xy 435.666388 -97.701608)
			(xy 435.791862 -97.701608) (xy 435.795933 -97.645986) (xy 435.808059 -97.591549) (xy 435.827982 -97.539458)
			(xy 435.855278 -97.490823) (xy 435.889364 -97.44668) (xy 435.929513 -97.407971) (xy 435.974871 -97.37552)
			(xy 436.024471 -97.350019) (xy 436.077255 -97.332012) (xy 436.132098 -97.321882) (xy 436.187832 -97.319845)
			(xy 436.243269 -97.325945) (xy 436.297226 -97.340051) (xy 436.348555 -97.361863) (xy 436.396161 -97.390917)
			(xy 436.439029 -97.426592) (xy 436.476246 -97.468129) (xy 436.507019 -97.514642) (xy 436.530691 -97.565139)
			(xy 436.546759 -97.618546) (xy 436.554879 -97.673722) (xy 436.555388 -97.701608) (xy 436.554879 -97.729494)
			(xy 436.546759 -97.78467) (xy 436.530691 -97.838077) (xy 436.507019 -97.888574) (xy 436.476246 -97.935087)
			(xy 436.439029 -97.976624) (xy 436.396161 -98.012299) (xy 436.348555 -98.041353) (xy 436.297226 -98.063165)
			(xy 436.243269 -98.077271) (xy 436.187832 -98.083371) (xy 436.132098 -98.081334) (xy 436.077255 -98.071204)
			(xy 436.024471 -98.053197) (xy 435.974871 -98.027696) (xy 435.929513 -97.995245) (xy 435.889364 -97.956536)
			(xy 435.855278 -97.912393) (xy 435.827982 -97.863758) (xy 435.808059 -97.811667) (xy 435.795933 -97.75723)
			(xy 435.791862 -97.701608) (xy 435.666388 -97.701608) (xy 435.665879 -97.729494) (xy 435.657759 -97.78467)
			(xy 435.641691 -97.838077) (xy 435.618019 -97.888574) (xy 435.587246 -97.935087) (xy 435.550029 -97.976624)
			(xy 435.507161 -98.012299) (xy 435.459555 -98.041353) (xy 435.408226 -98.063165) (xy 435.354269 -98.077271)
			(xy 435.298832 -98.083371) (xy 435.243098 -98.081334) (xy 435.188255 -98.071204) (xy 435.135471 -98.053197)
			(xy 435.085871 -98.027696) (xy 435.040513 -97.995245) (xy 435.000364 -97.956536) (xy 434.966278 -97.912393)
			(xy 434.938982 -97.863758) (xy 434.919059 -97.811667) (xy 434.906933 -97.75723) (xy 434.902862 -97.701608)
			(xy 413.999172 -97.701608) (xy 413.999172 -98.590608) (xy 434.902862 -98.590608) (xy 434.906933 -98.534986)
			(xy 434.919059 -98.480549) (xy 434.938982 -98.428458) (xy 434.966278 -98.379823) (xy 435.000364 -98.33568)
			(xy 435.040513 -98.296971) (xy 435.085871 -98.26452) (xy 435.135471 -98.239019) (xy 435.188255 -98.221012)
			(xy 435.243098 -98.210882) (xy 435.298832 -98.208845) (xy 435.354269 -98.214945) (xy 435.408226 -98.229051)
			(xy 435.459555 -98.250863) (xy 435.507161 -98.279917) (xy 435.550029 -98.315592) (xy 435.587246 -98.357129)
			(xy 435.618019 -98.403642) (xy 435.641691 -98.454139) (xy 435.657759 -98.507546) (xy 435.665879 -98.562722)
			(xy 435.666388 -98.590608) (xy 435.791862 -98.590608) (xy 435.795933 -98.534986) (xy 435.808059 -98.480549)
			(xy 435.827982 -98.428458) (xy 435.855278 -98.379823) (xy 435.889364 -98.33568) (xy 435.929513 -98.296971)
			(xy 435.974871 -98.26452) (xy 436.024471 -98.239019) (xy 436.077255 -98.221012) (xy 436.132098 -98.210882)
			(xy 436.187832 -98.208845) (xy 436.243269 -98.214945) (xy 436.297226 -98.229051) (xy 436.348555 -98.250863)
			(xy 436.396161 -98.279917) (xy 436.439029 -98.315592) (xy 436.476246 -98.357129) (xy 436.507019 -98.403642)
			(xy 436.530691 -98.454139) (xy 436.546759 -98.507546) (xy 436.554879 -98.562722) (xy 436.555388 -98.590608)
			(xy 436.554879 -98.618494) (xy 436.546759 -98.67367) (xy 436.530691 -98.727077) (xy 436.507019 -98.777574)
			(xy 436.476246 -98.824087) (xy 436.439029 -98.865624) (xy 436.396161 -98.901299) (xy 436.348555 -98.930353)
			(xy 436.297226 -98.952165) (xy 436.243269 -98.966271) (xy 436.187832 -98.972371) (xy 436.132098 -98.970334)
			(xy 436.077255 -98.960204) (xy 436.024471 -98.942197) (xy 435.974871 -98.916696) (xy 435.929513 -98.884245)
			(xy 435.889364 -98.845536) (xy 435.855278 -98.801393) (xy 435.827982 -98.752758) (xy 435.808059 -98.700667)
			(xy 435.795933 -98.64623) (xy 435.791862 -98.590608) (xy 435.666388 -98.590608) (xy 435.665879 -98.618494)
			(xy 435.657759 -98.67367) (xy 435.641691 -98.727077) (xy 435.618019 -98.777574) (xy 435.587246 -98.824087)
			(xy 435.550029 -98.865624) (xy 435.507161 -98.901299) (xy 435.459555 -98.930353) (xy 435.408226 -98.952165)
			(xy 435.354269 -98.966271) (xy 435.298832 -98.972371) (xy 435.243098 -98.970334) (xy 435.188255 -98.960204)
			(xy 435.135471 -98.942197) (xy 435.085871 -98.916696) (xy 435.040513 -98.884245) (xy 435.000364 -98.845536)
			(xy 434.966278 -98.801393) (xy 434.938982 -98.752758) (xy 434.919059 -98.700667) (xy 434.906933 -98.64623)
			(xy 434.902862 -98.590608) (xy 413.999172 -98.590608) (xy 413.999172 -99.459542) (xy 413.999691 -99.4745)
			(xy 414.008345 -99.503135) (xy 414.024927 -99.528033) (xy 414.048013 -99.547057) (xy 414.075621 -99.558574)
			(xy 414.105383 -99.561594) (xy 414.134742 -99.555859) (xy 414.16118 -99.541861) (xy 414.172146 -99.531678)
			(xy 414.193747 -99.511112) (xy 414.242148 -99.476263) (xy 414.295376 -99.44936) (xy 414.352139 -99.431058)
			(xy 414.411057 -99.4218) (xy 414.440878 -99.421188) (xy 414.468146 -99.42165) (xy 414.522129 -99.429408)
			(xy 414.574457 -99.444771) (xy 414.624067 -99.467424) (xy 414.643027 -99.479608) (xy 434.902862 -99.479608)
			(xy 434.906933 -99.423986) (xy 434.919059 -99.369549) (xy 434.938982 -99.317458) (xy 434.966278 -99.268823)
			(xy 435.000364 -99.22468) (xy 435.040513 -99.185971) (xy 435.085871 -99.15352) (xy 435.135471 -99.128019)
			(xy 435.188255 -99.110012) (xy 435.243098 -99.099882) (xy 435.298832 -99.097845) (xy 435.354269 -99.103945)
			(xy 435.408226 -99.118051) (xy 435.459555 -99.139863) (xy 435.507161 -99.168917) (xy 435.550029 -99.204592)
			(xy 435.587246 -99.246129) (xy 435.618019 -99.292642) (xy 435.641691 -99.343139) (xy 435.657759 -99.396546)
			(xy 435.665879 -99.451722) (xy 435.666388 -99.479608) (xy 435.791862 -99.479608) (xy 435.795933 -99.423986)
			(xy 435.808059 -99.369549) (xy 435.827982 -99.317458) (xy 435.855278 -99.268823) (xy 435.889364 -99.22468)
			(xy 435.929513 -99.185971) (xy 435.974871 -99.15352) (xy 436.024471 -99.128019) (xy 436.077255 -99.110012)
			(xy 436.132098 -99.099882) (xy 436.187832 -99.097845) (xy 436.243269 -99.103945) (xy 436.297226 -99.118051)
			(xy 436.348555 -99.139863) (xy 436.396161 -99.168917) (xy 436.439029 -99.204592) (xy 436.476246 -99.246129)
			(xy 436.507019 -99.292642) (xy 436.530691 -99.343139) (xy 436.546759 -99.396546) (xy 436.554879 -99.451722)
			(xy 436.555388 -99.479608) (xy 436.554879 -99.507494) (xy 436.546759 -99.56267) (xy 436.530691 -99.616077)
			(xy 436.507019 -99.666574) (xy 436.476246 -99.713087) (xy 436.439029 -99.754624) (xy 436.396161 -99.790299)
			(xy 436.348555 -99.819353) (xy 436.297226 -99.841165) (xy 436.243269 -99.855271) (xy 436.187832 -99.861371)
			(xy 436.132098 -99.859334) (xy 436.077255 -99.849204) (xy 436.024471 -99.831197) (xy 435.974871 -99.805696)
			(xy 435.929513 -99.773245) (xy 435.889364 -99.734536) (xy 435.855278 -99.690393) (xy 435.827982 -99.641758)
			(xy 435.808059 -99.589667) (xy 435.795933 -99.53523) (xy 435.791862 -99.479608) (xy 435.666388 -99.479608)
			(xy 435.665879 -99.507494) (xy 435.657759 -99.56267) (xy 435.641691 -99.616077) (xy 435.618019 -99.666574)
			(xy 435.587246 -99.713087) (xy 435.550029 -99.754624) (xy 435.507161 -99.790299) (xy 435.459555 -99.819353)
			(xy 435.408226 -99.841165) (xy 435.354269 -99.855271) (xy 435.298832 -99.861371) (xy 435.243098 -99.859334)
			(xy 435.188255 -99.849204) (xy 435.135471 -99.831197) (xy 435.085871 -99.805696) (xy 435.040513 -99.773245)
			(xy 435.000364 -99.734536) (xy 434.966278 -99.690393) (xy 434.938982 -99.641758) (xy 434.919059 -99.589667)
			(xy 434.906933 -99.53523) (xy 434.902862 -99.479608) (xy 414.643027 -99.479608) (xy 414.669947 -99.496907)
			(xy 414.711164 -99.53262) (xy 414.746879 -99.573835) (xy 414.776365 -99.619714) (xy 414.799022 -99.669322)
			(xy 414.814387 -99.72165) (xy 414.822149 -99.775632) (xy 414.822149 -99.830168) (xy 414.814387 -99.88415)
			(xy 414.799022 -99.936478) (xy 414.776365 -99.986086) (xy 414.746879 -100.031965) (xy 414.711164 -100.07318)
			(xy 414.669947 -100.108893) (xy 414.624067 -100.138376) (xy 414.574457 -100.161029) (xy 414.522129 -100.176392)
			(xy 414.468146 -100.18415) (xy 414.440878 -100.184712) (xy 414.411056 -100.184138) (xy 414.352137 -100.174867)
			(xy 414.295374 -100.156555) (xy 414.242146 -100.129645) (xy 414.193745 -100.094792) (xy 414.172146 -100.074222)
			(xy 414.161144 -100.064085) (xy 414.134704 -100.050119) (xy 414.105353 -100.044402) (xy 414.075604 -100.047425)
			(xy 414.048004 -100.058929) (xy 414.024914 -100.077928) (xy 414.008311 -100.102797) (xy 413.999617 -100.131408)
			(xy 413.999172 -100.146358) (xy 413.999172 -102.63945) (xy 429.495968 -102.63945) (xy 429.495968 -102.58495)
			(xy 429.503724 -102.531003) (xy 429.519077 -102.47871) (xy 429.541717 -102.429134) (xy 429.57118 -102.383284)
			(xy 429.606869 -102.342093) (xy 429.648057 -102.306401) (xy 429.693904 -102.276933) (xy 429.743478 -102.254289)
			(xy 429.79577 -102.238931) (xy 429.849716 -102.23117) (xy 429.876966 -102.230682) (xy 429.903569 -102.231164)
			(xy 429.95626 -102.238541) (xy 430.007415 -102.25317) (xy 430.056039 -102.274767) (xy 430.10119 -102.302914)
			(xy 430.14199 -102.337062) (xy 430.177648 -102.376551) (xy 430.192942 -102.398322) (xy 430.200507 -102.408301)
			(xy 430.222601 -102.420025) (xy 430.235106 -102.420674) (xy 430.318926 -102.420674) (xy 430.331447 -102.420083)
			(xy 430.353565 -102.408348) (xy 430.36109 -102.398322) (xy 430.376374 -102.376544) (xy 430.412042 -102.337065)
			(xy 430.452848 -102.302923) (xy 430.498 -102.274779) (xy 430.546623 -102.253178) (xy 430.597775 -102.238539)
			(xy 430.650463 -102.231145) (xy 430.677066 -102.230682) (xy 430.704318 -102.231187) (xy 430.758266 -102.238939)
			(xy 430.810563 -102.25429) (xy 430.860142 -102.276928) (xy 430.905995 -102.306392) (xy 430.947188 -102.342081)
			(xy 430.982882 -102.38327) (xy 431.012351 -102.429119) (xy 431.034994 -102.478696) (xy 431.050352 -102.53099)
			(xy 431.05811 -102.584938) (xy 431.058574 -102.61219) (xy 431.058169 -102.636998) (xy 431.057848 -102.639451)
			(xy 431.370468 -102.639451) (xy 431.370468 -102.584949) (xy 431.378224 -102.531001) (xy 431.393579 -102.478706)
			(xy 431.41622 -102.429128) (xy 431.445685 -102.383277) (xy 431.481376 -102.342086) (xy 431.522566 -102.306394)
			(xy 431.568416 -102.276926) (xy 431.617993 -102.254284) (xy 431.670287 -102.238927) (xy 431.724235 -102.231169)
			(xy 431.751486 -102.230682) (xy 431.780451 -102.231233) (xy 431.837715 -102.240002) (xy 431.892995 -102.257325)
			(xy 431.945022 -102.282805) (xy 431.9926 -102.315856) (xy 432.034635 -102.355719) (xy 432.070163 -102.401477)
			(xy 432.084734 -102.426516) (xy 432.091827 -102.43826) (xy 432.111094 -102.457777) (xy 432.134864 -102.471456)
			(xy 432.161419 -102.478308) (xy 432.18884 -102.477839) (xy 432.215144 -102.470082) (xy 432.238432 -102.455598)
			(xy 432.248056 -102.44582) (xy 432.25085 -102.442772) (xy 432.269067 -102.42035) (xy 432.311055 -102.380675)
			(xy 432.358547 -102.347787) (xy 432.410457 -102.322438) (xy 432.465595 -102.305209) (xy 432.522702 -102.296494)
			(xy 432.551586 -102.29596) (xy 432.578859 -102.296379) (xy 432.632851 -102.30414) (xy 432.685188 -102.319505)
			(xy 432.734806 -102.342164) (xy 432.780694 -102.371653) (xy 432.821918 -102.407372) (xy 432.857639 -102.448595)
			(xy 432.88713 -102.494482) (xy 432.90979 -102.544099) (xy 432.925157 -102.596436) (xy 432.93292 -102.650427)
			(xy 432.93292 -102.704973) (xy 432.925157 -102.758964) (xy 432.90979 -102.811301) (xy 432.88713 -102.860918)
			(xy 432.857639 -102.906805) (xy 432.821918 -102.948028) (xy 432.780694 -102.983747) (xy 432.734806 -103.013236)
			(xy 432.685188 -103.035895) (xy 432.632851 -103.05126) (xy 432.578859 -103.059021) (xy 432.551586 -103.059484)
			(xy 432.522284 -103.058914) (xy 432.464367 -103.049963) (xy 432.408501 -103.03226) (xy 432.355999 -103.00622)
			(xy 432.308099 -102.972457) (xy 432.265926 -102.931764) (xy 432.230473 -102.8851) (xy 432.216052 -102.859586)
			(xy 432.213004 -102.855014) (xy 432.204927 -102.84415) (xy 432.184206 -102.826746) (xy 432.159635 -102.815409)
			(xy 432.132947 -102.810938) (xy 432.106023 -102.813648) (xy 432.080761 -102.823347) (xy 432.058942 -102.839353)
			(xy 432.05019 -102.84968) (xy 432.031993 -102.871752) (xy 431.990086 -102.91069) (xy 431.94284 -102.942941)
			(xy 431.891311 -102.967782) (xy 431.836652 -102.984658) (xy 431.780088 -102.99319) (xy 431.751486 -102.993698)
			(xy 431.724235 -102.993231) (xy 431.670287 -102.985473) (xy 431.617993 -102.970116) (xy 431.568416 -102.947474)
			(xy 431.522566 -102.918006) (xy 431.481376 -102.882314) (xy 431.445685 -102.841123) (xy 431.41622 -102.795272)
			(xy 431.393579 -102.745694) (xy 431.378224 -102.693399) (xy 431.370468 -102.639451) (xy 431.057848 -102.639451)
			(xy 431.051732 -102.686194) (xy 431.038953 -102.734135) (xy 431.029872 -102.757224) (xy 431.025918 -102.768534)
			(xy 431.027765 -102.792387) (xy 431.033428 -102.802944) (xy 431.075592 -102.872794) (xy 431.08088 -102.880666)
			(xy 431.095852 -102.892271) (xy 431.104802 -102.8954) (xy 431.114454 -102.897178) (xy 431.142478 -102.90029)
			(xy 431.197232 -102.913751) (xy 431.249408 -102.935124) (xy 431.29787 -102.963943) (xy 431.341562 -102.999582)
			(xy 431.379534 -103.041264) (xy 431.410956 -103.08808) (xy 431.435146 -103.139011) (xy 431.451576 -103.192948)
			(xy 431.459889 -103.248716) (xy 431.460402 -103.276908) (xy 431.459916 -103.304159) (xy 431.45216 -103.358107)
			(xy 431.436805 -103.410402) (xy 431.414163 -103.459979) (xy 431.384697 -103.505829) (xy 431.349006 -103.54702)
			(xy 431.307815 -103.582711) (xy 431.261965 -103.612177) (xy 431.212388 -103.634819) (xy 431.160093 -103.650174)
			(xy 431.106145 -103.65793) (xy 431.051643 -103.65793) (xy 430.997695 -103.650174) (xy 430.9454 -103.634819)
			(xy 430.895823 -103.612177) (xy 430.849973 -103.582711) (xy 430.808782 -103.54702) (xy 430.773091 -103.505829)
			(xy 430.743625 -103.459979) (xy 430.720983 -103.410402) (xy 430.705628 -103.358107) (xy 430.697872 -103.304159)
			(xy 430.697386 -103.276908) (xy 430.697793 -103.2521) (xy 430.704229 -103.202905) (xy 430.717007 -103.154963)
			(xy 430.726088 -103.131874) (xy 430.730048 -103.120565) (xy 430.728199 -103.09671) (xy 430.722532 -103.086154)
			(xy 430.680368 -103.016304) (xy 430.675096 -103.008421) (xy 430.660113 -102.996822) (xy 430.651158 -102.993698)
			(xy 430.641506 -102.99192) (xy 430.613609 -102.988818) (xy 430.559087 -102.975477) (xy 430.50711 -102.95429)
			(xy 430.458798 -102.925714) (xy 430.415195 -102.890368) (xy 430.377243 -102.849014) (xy 430.36109 -102.826058)
			(xy 430.353562 -102.816044) (xy 430.33144 -102.80434) (xy 430.318926 -102.803706) (xy 430.235106 -102.803706)
			(xy 430.222589 -102.804325) (xy 430.200471 -102.816041) (xy 430.192942 -102.826058) (xy 430.177632 -102.847817)
			(xy 430.141968 -102.887297) (xy 430.101167 -102.921441) (xy 430.05602 -102.949588) (xy 430.007401 -102.971192)
			(xy 429.956253 -102.985835) (xy 429.903567 -102.993232) (xy 429.876966 -102.993698) (xy 429.849716 -102.99323)
			(xy 429.79577 -102.985469) (xy 429.743478 -102.970111) (xy 429.693904 -102.947467) (xy 429.648057 -102.917999)
			(xy 429.606869 -102.882307) (xy 429.57118 -102.841116) (xy 429.541717 -102.795266) (xy 429.519077 -102.74569)
			(xy 429.503724 -102.693397) (xy 429.495968 -102.63945) (xy 413.999172 -102.63945) (xy 413.999172 -104.501188)
			(xy 418.034978 -104.501188) (xy 418.035425 -104.473783) (xy 418.043285 -104.419539) (xy 418.058829 -104.366979)
			(xy 418.081735 -104.317184) (xy 418.111532 -104.271181) (xy 418.129212 -104.250236) (xy 418.135308 -104.243124)
			(xy 418.141658 -104.22636) (xy 418.141658 -104.141016) (xy 418.135308 -104.124252) (xy 418.129212 -104.11714)
			(xy 418.111533 -104.096198) (xy 418.081766 -104.050181) (xy 418.058879 -104.000384) (xy 418.043341 -103.947827)
			(xy 418.03547 -103.89359) (xy 418.034978 -103.866188) (xy 418.03539 -103.838915) (xy 418.043155 -103.784924)
			(xy 418.058525 -103.732588) (xy 418.081187 -103.682972) (xy 418.11068 -103.637087) (xy 418.146402 -103.595866)
			(xy 418.187628 -103.560148) (xy 418.233518 -103.530662) (xy 418.283137 -103.508007) (xy 418.335475 -103.492644)
			(xy 418.389467 -103.484887) (xy 418.41674 -103.484426) (xy 418.44235 -103.484812) (xy 418.493109 -103.491676)
			(xy 418.542494 -103.505264) (xy 418.589621 -103.52533) (xy 418.633642 -103.551516) (xy 418.673769 -103.58335)
			(xy 418.691822 -103.60152) (xy 418.698934 -103.608886) (xy 418.717476 -103.61676) (xy 418.809932 -103.61803)
			(xy 418.828728 -103.61041) (xy 418.836094 -103.603044) (xy 418.857657 -103.582363) (xy 418.906069 -103.547352)
			(xy 418.959348 -103.520319) (xy 419.016191 -103.501925) (xy 419.075207 -103.49262) (xy 419.10508 -103.492046)
			(xy 419.132351 -103.49252) (xy 419.186338 -103.50028) (xy 419.238671 -103.515644) (xy 419.288284 -103.5383)
			(xy 419.334169 -103.567786) (xy 419.375389 -103.603502) (xy 419.411107 -103.644722) (xy 419.440595 -103.690605)
			(xy 419.463252 -103.740218) (xy 419.478618 -103.79255) (xy 419.486379 -103.846537) (xy 419.486842 -103.873808)
			(xy 419.486388 -103.901213) (xy 419.478528 -103.955456) (xy 419.462986 -104.008016) (xy 419.440082 -104.057811)
			(xy 419.410287 -104.103815) (xy 419.392608 -104.12476) (xy 419.386512 -104.131872) (xy 419.380162 -104.148636)
			(xy 419.380162 -104.23398) (xy 419.386512 -104.250744) (xy 419.392608 -104.257856) (xy 419.410288 -104.278797)
			(xy 419.440054 -104.324814) (xy 419.462941 -104.374612) (xy 419.478479 -104.427169) (xy 419.48635 -104.481406)
			(xy 419.486842 -104.508808) (xy 419.486406 -104.53608) (xy 419.478642 -104.590069) (xy 419.463274 -104.642403)
			(xy 419.440614 -104.692018) (xy 419.411124 -104.737903) (xy 419.375403 -104.779123) (xy 419.33418 -104.81484)
			(xy 419.288293 -104.844327) (xy 419.238677 -104.866984) (xy 419.186342 -104.882348) (xy 419.132352 -104.890108)
			(xy 419.10508 -104.89057) (xy 419.079471 -104.890143) (xy 419.028716 -104.883282) (xy 418.979332 -104.869701)
			(xy 418.932206 -104.849642) (xy 418.888183 -104.823466) (xy 418.848053 -104.791641) (xy 418.829998 -104.773476)
			(xy 418.822886 -104.76611) (xy 418.804344 -104.758236) (xy 418.711888 -104.756966) (xy 418.693092 -104.764586)
			(xy 418.685726 -104.771952) (xy 418.664153 -104.792622) (xy 418.615744 -104.827635) (xy 418.562467 -104.85467)
			(xy 418.505626 -104.873067) (xy 418.446612 -104.882374) (xy 418.41674 -104.88295) (xy 418.389469 -104.882461)
			(xy 418.335483 -104.874704) (xy 418.28315 -104.859342) (xy 418.233536 -104.836689) (xy 418.187652 -104.807204)
			(xy 418.146431 -104.771489) (xy 418.110713 -104.730271) (xy 418.081225 -104.684389) (xy 418.058567 -104.634776)
			(xy 418.043202 -104.582445) (xy 418.035441 -104.528459) (xy 418.034978 -104.501188) (xy 413.999172 -104.501188)
			(xy 413.999172 -105.827322) (xy 429.906682 -105.827322) (xy 429.910753 -105.7717) (xy 429.922879 -105.717263)
			(xy 429.942802 -105.665172) (xy 429.970098 -105.616537) (xy 430.004184 -105.572394) (xy 430.044333 -105.533685)
			(xy 430.089691 -105.501234) (xy 430.139291 -105.475733) (xy 430.192075 -105.457726) (xy 430.246918 -105.447596)
			(xy 430.302652 -105.445559) (xy 430.358089 -105.451659) (xy 430.412046 -105.465765) (xy 430.463375 -105.487577)
			(xy 430.510981 -105.516631) (xy 430.553849 -105.552306) (xy 430.591066 -105.593843) (xy 430.614291 -105.628948)
			(xy 433.069238 -105.628948) (xy 433.06973 -105.601545) (xy 433.077581 -105.547303) (xy 433.093114 -105.494744)
			(xy 433.11601 -105.444948) (xy 433.145797 -105.398943) (xy 433.163472 -105.377996) (xy 433.169568 -105.370884)
			(xy 433.175918 -105.353866) (xy 433.175918 -105.26903) (xy 433.169568 -105.252012) (xy 433.163472 -105.2449)
			(xy 433.145815 -105.22394) (xy 433.116046 -105.177928) (xy 433.093155 -105.128135) (xy 433.077612 -105.075583)
			(xy 433.069734 -105.021349) (xy 433.069238 -104.993948) (xy 433.069745 -104.965754) (xy 433.078059 -104.909981)
			(xy 433.094485 -104.856037) (xy 433.118665 -104.805096) (xy 433.150074 -104.758264) (xy 433.188028 -104.71656)
			(xy 433.231702 -104.680891) (xy 433.280147 -104.652032) (xy 433.332309 -104.630611) (xy 433.35956 -104.623362)
			(xy 433.370482 -104.620568) (xy 433.388008 -104.606344) (xy 433.43195 -104.516428) (xy 433.432458 -104.494076)
			(xy 433.427886 -104.483662) (xy 433.417298 -104.458996) (xy 433.402381 -104.407434) (xy 433.394831 -104.35429)
			(xy 433.394358 -104.327452) (xy 433.394844 -104.300183) (xy 433.402606 -104.246199) (xy 433.417971 -104.193869)
			(xy 433.440628 -104.144259) (xy 433.470114 -104.098378) (xy 433.505829 -104.057161) (xy 433.547046 -104.021446)
			(xy 433.592927 -103.99196) (xy 433.642537 -103.969303) (xy 433.694867 -103.953938) (xy 433.748851 -103.946176)
			(xy 433.803389 -103.946176) (xy 433.857373 -103.953938) (xy 433.909703 -103.969303) (xy 433.959313 -103.99196)
			(xy 434.005194 -104.021446) (xy 434.046411 -104.057161) (xy 434.082126 -104.098378) (xy 434.111612 -104.144259)
			(xy 434.134269 -104.193869) (xy 434.149634 -104.246199) (xy 434.157396 -104.300183) (xy 434.157882 -104.327452)
			(xy 434.157416 -104.354803) (xy 434.149569 -104.408941) (xy 434.134072 -104.461404) (xy 434.123084 -104.486456)
			(xy 434.118512 -104.496616) (xy 434.118512 -104.518968) (xy 434.160422 -104.608884) (xy 434.177186 -104.623108)
			(xy 434.188108 -104.626156) (xy 434.214567 -104.633967) (xy 434.265052 -104.656214) (xy 434.311807 -104.685498)
			(xy 434.353859 -104.721208) (xy 434.390332 -104.762601) (xy 434.420464 -104.808815) (xy 434.443629 -104.858885)
			(xy 434.459343 -104.911768) (xy 434.467279 -104.966363) (xy 434.467762 -104.993948) (xy 434.467268 -105.021351)
			(xy 434.459417 -105.075593) (xy 434.443884 -105.128152) (xy 434.420989 -105.177947) (xy 434.391203 -105.223953)
			(xy 434.373528 -105.2449) (xy 434.367432 -105.252012) (xy 434.361082 -105.26903) (xy 434.361082 -105.353866)
			(xy 434.367432 -105.370884) (xy 434.373528 -105.377996) (xy 434.391183 -105.398957) (xy 434.420952 -105.444969)
			(xy 434.443843 -105.494762) (xy 434.459387 -105.547314) (xy 434.467265 -105.601547) (xy 434.467762 -105.628948)
			(xy 434.46732 -105.656219) (xy 434.459552 -105.710204) (xy 434.444181 -105.762534) (xy 434.421519 -105.812144)
			(xy 434.392028 -105.858025) (xy 434.356308 -105.899242) (xy 434.315087 -105.934957) (xy 434.269202 -105.964442)
			(xy 434.219589 -105.987097) (xy 434.167257 -106.002462) (xy 434.113271 -106.010224) (xy 434.086 -106.01071)
			(xy 434.058595 -106.010259) (xy 434.004351 -106.0024) (xy 433.951791 -105.986858) (xy 433.901996 -105.963953)
			(xy 433.855993 -105.934156) (xy 433.835048 -105.916476) (xy 433.827936 -105.91038) (xy 433.810918 -105.90403)
			(xy 433.726082 -105.90403) (xy 433.709064 -105.91038) (xy 433.701952 -105.916476) (xy 433.681004 -105.934147)
			(xy 433.634989 -105.963916) (xy 433.585193 -105.986805) (xy 433.532638 -106.002345) (xy 433.478402 -106.010217)
			(xy 433.451 -106.01071) (xy 433.423733 -106.010176) (xy 433.369753 -106.002415) (xy 433.317428 -105.987052)
			(xy 433.267821 -105.9644) (xy 433.221942 -105.934918) (xy 433.180726 -105.899208) (xy 433.145011 -105.857996)
			(xy 433.115523 -105.812121) (xy 433.092864 -105.762517) (xy 433.077495 -105.710194) (xy 433.069728 -105.656215)
			(xy 433.069238 -105.628948) (xy 430.614291 -105.628948) (xy 430.621839 -105.640356) (xy 430.645511 -105.690853)
			(xy 430.661579 -105.74426) (xy 430.669699 -105.799436) (xy 430.670208 -105.827322) (xy 430.669699 -105.855208)
			(xy 430.661579 -105.910384) (xy 430.645511 -105.963791) (xy 430.621839 -106.014288) (xy 430.591066 -106.060801)
			(xy 430.553849 -106.102338) (xy 430.510981 -106.138013) (xy 430.463375 -106.167067) (xy 430.412046 -106.188879)
			(xy 430.358089 -106.202985) (xy 430.302652 -106.209085) (xy 430.246918 -106.207048) (xy 430.192075 -106.196918)
			(xy 430.139291 -106.178911) (xy 430.089691 -106.15341) (xy 430.044333 -106.120959) (xy 430.004184 -106.08225)
			(xy 429.970098 -106.038107) (xy 429.942802 -105.989472) (xy 429.922879 -105.937381) (xy 429.910753 -105.882944)
			(xy 429.906682 -105.827322) (xy 413.999172 -105.827322) (xy 413.999172 -107.15117) (xy 428.930814 -107.15117)
			(xy 428.934885 -107.095548) (xy 428.947011 -107.041111) (xy 428.966934 -106.98902) (xy 428.99423 -106.940385)
			(xy 429.028316 -106.896242) (xy 429.068465 -106.857533) (xy 429.113823 -106.825082) (xy 429.163423 -106.799581)
			(xy 429.216207 -106.781574) (xy 429.27105 -106.771444) (xy 429.326784 -106.769407) (xy 429.368344 -106.77398)
			(xy 433.340254 -106.77398) (xy 433.344325 -106.718358) (xy 433.356451 -106.663921) (xy 433.376374 -106.61183)
			(xy 433.40367 -106.563195) (xy 433.437756 -106.519052) (xy 433.477905 -106.480343) (xy 433.523263 -106.447892)
			(xy 433.572863 -106.422391) (xy 433.625647 -106.404384) (xy 433.68049 -106.394254) (xy 433.736224 -106.392217)
			(xy 433.791661 -106.398317) (xy 433.845618 -106.412423) (xy 433.896947 -106.434235) (xy 433.944553 -106.463289)
			(xy 433.987421 -106.498964) (xy 434.024638 -106.540501) (xy 434.055411 -106.587014) (xy 434.079083 -106.637511)
			(xy 434.095151 -106.690918) (xy 434.103271 -106.746094) (xy 434.10378 -106.77398) (xy 434.103271 -106.801866)
			(xy 434.095151 -106.857042) (xy 434.079083 -106.910449) (xy 434.055411 -106.960946) (xy 434.024638 -107.007459)
			(xy 433.987421 -107.048996) (xy 433.944553 -107.084671) (xy 433.896947 -107.113725) (xy 433.845618 -107.135537)
			(xy 433.791661 -107.149643) (xy 433.736224 -107.155743) (xy 433.68049 -107.153706) (xy 433.625647 -107.143576)
			(xy 433.572863 -107.125569) (xy 433.523263 -107.100068) (xy 433.477905 -107.067617) (xy 433.437756 -107.028908)
			(xy 433.40367 -106.984765) (xy 433.376374 -106.93613) (xy 433.356451 -106.884039) (xy 433.344325 -106.829602)
			(xy 433.340254 -106.77398) (xy 429.368344 -106.77398) (xy 429.382221 -106.775507) (xy 429.436178 -106.789613)
			(xy 429.487507 -106.811425) (xy 429.535113 -106.840479) (xy 429.577981 -106.876154) (xy 429.615198 -106.917691)
			(xy 429.645971 -106.964204) (xy 429.669643 -107.014701) (xy 429.685711 -107.068108) (xy 429.693831 -107.123284)
			(xy 429.69434 -107.15117) (xy 429.693831 -107.179056) (xy 429.685711 -107.234232) (xy 429.677688 -107.260898)
			(xy 430.263552 -107.260898) (xy 430.267623 -107.205276) (xy 430.279749 -107.150839) (xy 430.299672 -107.098748)
			(xy 430.326968 -107.050113) (xy 430.361054 -107.00597) (xy 430.401203 -106.967261) (xy 430.446561 -106.93481)
			(xy 430.496161 -106.909309) (xy 430.548945 -106.891302) (xy 430.603788 -106.881172) (xy 430.659522 -106.879135)
			(xy 430.714959 -106.885235) (xy 430.768916 -106.899341) (xy 430.820245 -106.921153) (xy 430.867851 -106.950207)
			(xy 430.910719 -106.985882) (xy 430.947936 -107.027419) (xy 430.978709 -107.073932) (xy 431.002381 -107.124429)
			(xy 431.018449 -107.177836) (xy 431.026569 -107.233012) (xy 431.027078 -107.260898) (xy 431.026569 -107.288784)
			(xy 431.018449 -107.34396) (xy 431.002381 -107.397367) (xy 430.978709 -107.447864) (xy 430.947936 -107.494377)
			(xy 430.910719 -107.535914) (xy 430.867851 -107.571589) (xy 430.820245 -107.600643) (xy 430.768916 -107.622455)
			(xy 430.714959 -107.636561) (xy 430.659522 -107.642661) (xy 430.603788 -107.640624) (xy 430.548945 -107.630494)
			(xy 430.496161 -107.612487) (xy 430.446561 -107.586986) (xy 430.401203 -107.554535) (xy 430.361054 -107.515826)
			(xy 430.326968 -107.471683) (xy 430.299672 -107.423048) (xy 430.279749 -107.370957) (xy 430.267623 -107.31652)
			(xy 430.263552 -107.260898) (xy 429.677688 -107.260898) (xy 429.669643 -107.287639) (xy 429.645971 -107.338136)
			(xy 429.615198 -107.384649) (xy 429.577981 -107.426186) (xy 429.535113 -107.461861) (xy 429.487507 -107.490915)
			(xy 429.436178 -107.512727) (xy 429.382221 -107.526833) (xy 429.326784 -107.532933) (xy 429.27105 -107.530896)
			(xy 429.216207 -107.520766) (xy 429.163423 -107.502759) (xy 429.113823 -107.477258) (xy 429.068465 -107.444807)
			(xy 429.028316 -107.406098) (xy 428.99423 -107.361955) (xy 428.966934 -107.31332) (xy 428.947011 -107.261229)
			(xy 428.934885 -107.206792) (xy 428.930814 -107.15117) (xy 413.999172 -107.15117) (xy 413.999172 -107.645708)
			(xy 431.703478 -107.645708) (xy 431.707549 -107.590086) (xy 431.719675 -107.535649) (xy 431.739598 -107.483558)
			(xy 431.766894 -107.434923) (xy 431.80098 -107.39078) (xy 431.841129 -107.352071) (xy 431.886487 -107.31962)
			(xy 431.936087 -107.294119) (xy 431.988871 -107.276112) (xy 432.043714 -107.265982) (xy 432.099448 -107.263945)
			(xy 432.154885 -107.270045) (xy 432.208842 -107.284151) (xy 432.260171 -107.305963) (xy 432.307777 -107.335017)
			(xy 432.350645 -107.370692) (xy 432.387862 -107.412229) (xy 432.418635 -107.458742) (xy 432.442307 -107.509239)
			(xy 432.458375 -107.562646) (xy 432.466495 -107.617822) (xy 432.467004 -107.645708) (xy 432.466495 -107.673594)
			(xy 432.458375 -107.72877) (xy 432.442307 -107.782177) (xy 432.418635 -107.832674) (xy 432.387862 -107.879187)
			(xy 432.350645 -107.920724) (xy 432.307777 -107.956399) (xy 432.260171 -107.985453) (xy 432.208842 -108.007265)
			(xy 432.154885 -108.021371) (xy 432.099448 -108.027471) (xy 432.043714 -108.025434) (xy 431.988871 -108.015304)
			(xy 431.936087 -107.997297) (xy 431.886487 -107.971796) (xy 431.841129 -107.939345) (xy 431.80098 -107.900636)
			(xy 431.766894 -107.856493) (xy 431.739598 -107.807858) (xy 431.719675 -107.755767) (xy 431.707549 -107.70133)
			(xy 431.703478 -107.645708) (xy 413.999172 -107.645708) (xy 413.999172 -109.66323) (xy 433.334158 -109.66323)
			(xy 433.338229 -109.607608) (xy 433.350355 -109.553171) (xy 433.370278 -109.50108) (xy 433.397574 -109.452445)
			(xy 433.43166 -109.408302) (xy 433.471809 -109.369593) (xy 433.517167 -109.337142) (xy 433.566767 -109.311641)
			(xy 433.619551 -109.293634) (xy 433.674394 -109.283504) (xy 433.730128 -109.281467) (xy 433.785565 -109.287567)
			(xy 433.839522 -109.301673) (xy 433.890851 -109.323485) (xy 433.938457 -109.352539) (xy 433.981325 -109.388214)
			(xy 434.018542 -109.429751) (xy 434.049315 -109.476264) (xy 434.072987 -109.526761) (xy 434.089055 -109.580168)
			(xy 434.097175 -109.635344) (xy 434.097684 -109.66323) (xy 434.097175 -109.691116) (xy 434.089055 -109.746292)
			(xy 434.072987 -109.799699) (xy 434.049315 -109.850196) (xy 434.018542 -109.896709) (xy 433.981325 -109.938246)
			(xy 433.938457 -109.973921) (xy 433.890851 -110.002975) (xy 433.839522 -110.024787) (xy 433.785565 -110.038893)
			(xy 433.730128 -110.044993) (xy 433.674394 -110.042956) (xy 433.619551 -110.032826) (xy 433.566767 -110.014819)
			(xy 433.517167 -109.989318) (xy 433.471809 -109.956867) (xy 433.43166 -109.918158) (xy 433.397574 -109.874015)
			(xy 433.370278 -109.82538) (xy 433.350355 -109.773289) (xy 433.338229 -109.718852) (xy 433.334158 -109.66323)
			(xy 413.999172 -109.66323) (xy 413.999172 -110.4265) (xy 418.726618 -110.4265) (xy 418.730691 -110.370841)
			(xy 418.742826 -110.316368) (xy 418.762762 -110.264242) (xy 418.790076 -110.215574) (xy 418.824184 -110.171402)
			(xy 418.864361 -110.132667) (xy 418.909749 -110.100195) (xy 418.959381 -110.074677) (xy 419.012201 -110.056658)
			(xy 419.06708 -110.046521) (xy 419.122851 -110.044483) (xy 419.178325 -110.050586) (xy 419.232318 -110.064702)
			(xy 419.283681 -110.086529) (xy 419.331319 -110.115602) (xy 419.374215 -110.151301) (xy 419.411457 -110.192865)
			(xy 419.442251 -110.239409) (xy 419.461728 -110.280958) (xy 419.761668 -110.280958) (xy 419.765741 -110.225299)
			(xy 419.777876 -110.170826) (xy 419.797812 -110.1187) (xy 419.825126 -110.070032) (xy 419.859234 -110.02586)
			(xy 419.899411 -109.987125) (xy 419.944799 -109.954653) (xy 419.994431 -109.929135) (xy 420.047251 -109.911116)
			(xy 420.10213 -109.900979) (xy 420.157901 -109.898941) (xy 420.213375 -109.905044) (xy 420.267368 -109.91916)
			(xy 420.318731 -109.940987) (xy 420.366369 -109.97006) (xy 420.409265 -110.005759) (xy 420.446507 -110.047323)
			(xy 420.477301 -110.093867) (xy 420.500989 -110.144398) (xy 420.517067 -110.19784) (xy 420.525193 -110.253054)
			(xy 420.525702 -110.280958) (xy 420.525193 -110.308862) (xy 420.517067 -110.364076) (xy 420.516932 -110.364524)
			(xy 420.634158 -110.364524) (xy 420.638231 -110.308865) (xy 420.650366 -110.254392) (xy 420.670302 -110.202266)
			(xy 420.697616 -110.153598) (xy 420.731724 -110.109426) (xy 420.771901 -110.070691) (xy 420.817289 -110.038219)
			(xy 420.866921 -110.012701) (xy 420.919741 -109.994682) (xy 420.97462 -109.984545) (xy 421.030391 -109.982507)
			(xy 421.085865 -109.98861) (xy 421.139858 -110.002726) (xy 421.191221 -110.024553) (xy 421.238859 -110.053626)
			(xy 421.281755 -110.089325) (xy 421.318997 -110.130889) (xy 421.349791 -110.177433) (xy 421.373479 -110.227964)
			(xy 421.388123 -110.27664) (xy 428.913542 -110.27664) (xy 428.917613 -110.221018) (xy 428.929739 -110.166581)
			(xy 428.949662 -110.11449) (xy 428.976958 -110.065855) (xy 429.011044 -110.021712) (xy 429.051193 -109.983003)
			(xy 429.096551 -109.950552) (xy 429.146151 -109.925051) (xy 429.198935 -109.907044) (xy 429.253778 -109.896914)
			(xy 429.309512 -109.894877) (xy 429.364949 -109.900977) (xy 429.418906 -109.915083) (xy 429.470235 -109.936895)
			(xy 429.517841 -109.965949) (xy 429.560709 -110.001624) (xy 429.597926 -110.043161) (xy 429.628699 -110.089674)
			(xy 429.652371 -110.140171) (xy 429.668439 -110.193578) (xy 429.676559 -110.248754) (xy 429.677068 -110.27664)
			(xy 429.676559 -110.304526) (xy 429.668439 -110.359702) (xy 429.652371 -110.413109) (xy 429.628699 -110.463606)
			(xy 429.597926 -110.510119) (xy 429.560709 -110.551656) (xy 429.517841 -110.587331) (xy 429.470235 -110.616385)
			(xy 429.418906 -110.638197) (xy 429.364949 -110.652303) (xy 429.309512 -110.658403) (xy 429.253778 -110.656366)
			(xy 429.198935 -110.646236) (xy 429.146151 -110.628229) (xy 429.096551 -110.602728) (xy 429.051193 -110.570277)
			(xy 429.011044 -110.531568) (xy 428.976958 -110.487425) (xy 428.949662 -110.43879) (xy 428.929739 -110.386699)
			(xy 428.917613 -110.332262) (xy 428.913542 -110.27664) (xy 421.388123 -110.27664) (xy 421.389557 -110.281406)
			(xy 421.397683 -110.33662) (xy 421.398192 -110.364524) (xy 421.397683 -110.392428) (xy 421.389557 -110.447642)
			(xy 421.373479 -110.501084) (xy 421.349791 -110.551615) (xy 421.318997 -110.598159) (xy 421.281755 -110.639723)
			(xy 421.238859 -110.675422) (xy 421.191221 -110.704495) (xy 421.139858 -110.726322) (xy 421.085865 -110.740438)
			(xy 421.030391 -110.746541) (xy 420.97462 -110.744503) (xy 420.919741 -110.734366) (xy 420.866921 -110.716347)
			(xy 420.817289 -110.690829) (xy 420.771901 -110.658357) (xy 420.731724 -110.619622) (xy 420.697616 -110.57545)
			(xy 420.670302 -110.526782) (xy 420.650366 -110.474656) (xy 420.638231 -110.420183) (xy 420.634158 -110.364524)
			(xy 420.516932 -110.364524) (xy 420.500989 -110.417518) (xy 420.477301 -110.468049) (xy 420.446507 -110.514593)
			(xy 420.409265 -110.556157) (xy 420.366369 -110.591856) (xy 420.318731 -110.620929) (xy 420.267368 -110.642756)
			(xy 420.213375 -110.656872) (xy 420.157901 -110.662975) (xy 420.10213 -110.660937) (xy 420.047251 -110.6508)
			(xy 419.994431 -110.632781) (xy 419.944799 -110.607263) (xy 419.899411 -110.574791) (xy 419.859234 -110.536056)
			(xy 419.825126 -110.491884) (xy 419.797812 -110.443216) (xy 419.777876 -110.39109) (xy 419.765741 -110.336617)
			(xy 419.761668 -110.280958) (xy 419.461728 -110.280958) (xy 419.465939 -110.28994) (xy 419.482017 -110.343382)
			(xy 419.490143 -110.398596) (xy 419.490652 -110.4265) (xy 419.490143 -110.454404) (xy 419.482017 -110.509618)
			(xy 419.465939 -110.56306) (xy 419.442251 -110.613591) (xy 419.411457 -110.660135) (xy 419.374215 -110.701699)
			(xy 419.331319 -110.737398) (xy 419.283681 -110.766471) (xy 419.232318 -110.788298) (xy 419.178325 -110.802414)
			(xy 419.122851 -110.808517) (xy 419.06708 -110.806479) (xy 419.012201 -110.796342) (xy 418.959381 -110.778323)
			(xy 418.909749 -110.752805) (xy 418.864361 -110.720333) (xy 418.824184 -110.681598) (xy 418.790076 -110.637426)
			(xy 418.762762 -110.588758) (xy 418.742826 -110.536632) (xy 418.730691 -110.482159) (xy 418.726618 -110.4265)
			(xy 413.999172 -110.4265) (xy 413.999172 -111.131096) (xy 413.999594 -111.141167) (xy 414.007304 -111.159775)
			(xy 414.014158 -111.167164) (xy 415.490406 -112.643412) (xy 415.497801 -112.650267) (xy 415.5164 -112.658013)
			(xy 415.526474 -112.658398)
		)
		(stroke
			(width 0)
			(type solid)
		)
		(fill yes)
		(layer "In11.Cu")
		(net "GND")
	)
	(gr_poly
		(pts
			(xy 133.379718 -81.3308) (xy 133.389787 -81.330373) (xy 133.408386 -81.322654) (xy 133.415786 -81.315814)
			(xy 133.766814 -80.964786) (xy 133.773668 -80.957391) (xy 133.78141 -80.938792) (xy 133.7818 -80.928718)
			(xy 133.7818 -65.654682) (xy 133.781373 -65.644613) (xy 133.773654 -65.626014) (xy 133.766814 -65.618614)
			(xy 132.450586 -64.302386) (xy 132.443732 -64.294991) (xy 132.43599 -64.276392) (xy 132.4356 -64.266318)
			(xy 132.4356 -53.009546) (xy 132.43512 -52.999281) (xy 132.427059 -52.980397) (xy 132.412246 -52.96618)
			(xy 132.402834 -52.962048) (xy 132.299202 -52.922678) (xy 132.268722 -52.930044) (xy 132.258054 -52.941982)
			(xy 132.239886 -52.96174) (xy 132.19896 -52.996468) (xy 132.153568 -53.025114) (xy 132.104608 -53.047111)
			(xy 132.053047 -53.062025) (xy 131.999903 -53.069561) (xy 131.973066 -53.069998) (xy 131.945817 -53.069509)
			(xy 131.891875 -53.061749) (xy 131.839585 -53.046392) (xy 131.790014 -53.023749) (xy 131.744169 -52.994283)
			(xy 131.702984 -52.958592) (xy 131.667297 -52.917404) (xy 131.637835 -52.871556) (xy 131.615197 -52.821983)
			(xy 131.599844 -52.769692) (xy 131.592088 -52.715749) (xy 131.592088 -52.661251) (xy 131.599844 -52.607308)
			(xy 131.615197 -52.555017) (xy 131.637835 -52.505444) (xy 131.667297 -52.459596) (xy 131.702984 -52.418408)
			(xy 131.744169 -52.382717) (xy 131.790014 -52.353251) (xy 131.839585 -52.330608) (xy 131.891875 -52.315251)
			(xy 131.945817 -52.307491) (xy 131.973066 -52.306982) (xy 131.999904 -52.307437) (xy 132.053049 -52.314962)
			(xy 132.104614 -52.329867) (xy 132.153578 -52.351857) (xy 132.198973 -52.380499) (xy 132.239902 -52.415225)
			(xy 132.258054 -52.434998) (xy 132.268722 -52.446936) (xy 132.299202 -52.454302) (xy 132.402834 -52.414932)
			(xy 132.412275 -52.410848) (xy 132.427099 -52.396613) (xy 132.435162 -52.377709) (xy 132.4356 -52.367434)
			(xy 132.4356 -51.227482) (xy 132.436027 -51.217413) (xy 132.443746 -51.198814) (xy 132.450586 -51.191414)
			(xy 138.719814 -44.922186) (xy 138.726668 -44.914791) (xy 138.73441 -44.896192) (xy 138.7348 -44.886118)
			(xy 138.7348 -36.597082) (xy 138.734373 -36.587013) (xy 138.726654 -36.568414) (xy 138.719814 -36.561014)
			(xy 137.987786 -35.828986) (xy 137.980391 -35.822132) (xy 137.961792 -35.81439) (xy 137.951718 -35.814)
			(xy 136.292082 -35.814) (xy 136.282013 -35.814427) (xy 136.263414 -35.822146) (xy 136.256014 -35.828986)
			(xy 135.828786 -36.256214) (xy 135.821932 -36.263609) (xy 135.81419 -36.282208) (xy 135.8138 -36.292282)
			(xy 135.8138 -39.374318) (xy 135.813373 -39.384387) (xy 135.805654 -39.402986) (xy 135.798814 -39.410386)
			(xy 135.168386 -40.040814) (xy 135.160991 -40.047668) (xy 135.142392 -40.05541) (xy 135.132318 -40.0558)
			(xy 130.678682 -40.0558) (xy 130.668613 -40.056227) (xy 130.650014 -40.063946) (xy 130.642614 -40.070786)
			(xy 130.570986 -40.142414) (xy 130.563591 -40.149268) (xy 130.544992 -40.15701) (xy 130.534918 -40.1574)
			(xy 129.916682 -40.1574) (xy 129.906613 -40.156973) (xy 129.888014 -40.149254) (xy 129.880614 -40.142414)
			(xy 128.919986 -39.181786) (xy 128.913132 -39.174391) (xy 128.90539 -39.155792) (xy 128.905 -39.145718)
			(xy 128.905 -34.615882) (xy 128.904573 -34.605813) (xy 128.896854 -34.587214) (xy 128.890014 -34.579814)
			(xy 128.564386 -34.254186) (xy 128.556991 -34.247332) (xy 128.538392 -34.23959) (xy 128.528318 -34.2392)
			(xy 127.706882 -34.2392) (xy 127.696813 -34.239627) (xy 127.678214 -34.247346) (xy 127.670814 -34.254186)
			(xy 125.756924 -36.168076) (xy 125.753429 -36.171684) (xy 125.747798 -36.18) (xy 125.745748 -36.184586)
			(xy 125.495304 -36.78936) (xy 125.480161 -36.824691) (xy 125.443928 -36.892488) (xy 125.401228 -36.956411)
			(xy 125.352472 -37.015843) (xy 125.325632 -37.04336) (xy 124.830586 -37.538406) (xy 124.823731 -37.545801)
			(xy 124.815985 -37.5644) (xy 124.8156 -37.574474) (xy 124.8156 -38.07333) (xy 127.420876 -38.07333)
			(xy 127.424947 -38.017708) (xy 127.437073 -37.963271) (xy 127.456996 -37.91118) (xy 127.484292 -37.862545)
			(xy 127.518378 -37.818402) (xy 127.558527 -37.779693) (xy 127.603885 -37.747242) (xy 127.653485 -37.721741)
			(xy 127.706269 -37.703734) (xy 127.761112 -37.693604) (xy 127.816846 -37.691567) (xy 127.872283 -37.697667)
			(xy 127.92624 -37.711773) (xy 127.977569 -37.733585) (xy 128.025175 -37.762639) (xy 128.068043 -37.798314)
			(xy 128.10526 -37.839851) (xy 128.136033 -37.886364) (xy 128.159705 -37.936861) (xy 128.175773 -37.990268)
			(xy 128.183893 -38.045444) (xy 128.184402 -38.07333) (xy 128.183893 -38.101216) (xy 128.175773 -38.156392)
			(xy 128.159705 -38.209799) (xy 128.136033 -38.260296) (xy 128.10526 -38.306809) (xy 128.068043 -38.348346)
			(xy 128.025175 -38.384021) (xy 127.977569 -38.413075) (xy 127.92624 -38.434887) (xy 127.872283 -38.448993)
			(xy 127.816846 -38.455093) (xy 127.761112 -38.453056) (xy 127.706269 -38.442926) (xy 127.653485 -38.424919)
			(xy 127.603885 -38.399418) (xy 127.558527 -38.366967) (xy 127.518378 -38.328258) (xy 127.484292 -38.284115)
			(xy 127.456996 -38.23548) (xy 127.437073 -38.183389) (xy 127.424947 -38.128952) (xy 127.420876 -38.07333)
			(xy 124.8156 -38.07333) (xy 124.8156 -40.464994) (xy 124.815949 -40.473725) (xy 124.821827 -40.490166)
			(xy 124.832926 -40.503644) (xy 124.840238 -40.508428) (xy 124.92609 -40.560244) (xy 124.952506 -40.561006)
			(xy 124.964444 -40.55491) (xy 124.989549 -40.542253) (xy 125.042599 -40.523634) (xy 125.070108 -40.517826)
			(xy 125.080014 -40.515794) (xy 125.096524 -40.505126) (xy 125.14834 -40.429942) (xy 125.152658 -40.410638)
			(xy 125.15088 -40.400732) (xy 125.148244 -40.384478) (xy 125.145445 -40.351666) (xy 125.145292 -40.3352)
			(xy 125.145778 -40.307949) (xy 125.153534 -40.254001) (xy 125.168889 -40.201706) (xy 125.191531 -40.152129)
			(xy 125.220997 -40.106279) (xy 125.256688 -40.065088) (xy 125.297879 -40.029397) (xy 125.343729 -39.999931)
			(xy 125.393306 -39.977289) (xy 125.445601 -39.961934) (xy 125.499549 -39.954178) (xy 125.554051 -39.954178)
			(xy 125.607999 -39.961934) (xy 125.660294 -39.977289) (xy 125.709871 -39.999931) (xy 125.755721 -40.029397)
			(xy 125.796912 -40.065088) (xy 125.832603 -40.106279) (xy 125.862069 -40.152129) (xy 125.884711 -40.201706)
			(xy 125.900066 -40.254001) (xy 125.907822 -40.307949) (xy 125.908308 -40.3352) (xy 125.908172 -40.348068)
			(xy 125.90639 -40.373744) (xy 125.904752 -40.386508) (xy 125.903482 -40.395906) (xy 125.9078 -40.41394)
			(xy 125.956314 -40.485822) (xy 125.971554 -40.49649) (xy 125.980698 -40.498776) (xy 126.010305 -40.506674)
			(xy 126.067519 -40.528615) (xy 126.121682 -40.557273) (xy 126.172008 -40.592233) (xy 126.217768 -40.632987)
			(xy 126.258298 -40.678945) (xy 126.293012 -40.729441) (xy 126.321406 -40.783743) (xy 126.343068 -40.841063)
			(xy 126.357684 -40.900572) (xy 126.365043 -40.961405) (xy 126.365508 -40.992044) (xy 126.365041 -41.022773)
			(xy 126.357628 -41.083783) (xy 126.342916 -41.143455) (xy 126.321119 -41.200918) (xy 126.292554 -41.255335)
			(xy 126.257639 -41.305913) (xy 126.216882 -41.351913) (xy 126.170878 -41.392666) (xy 126.120298 -41.427577)
			(xy 126.065878 -41.456137) (xy 126.008413 -41.477929) (xy 125.94874 -41.492636) (xy 125.887729 -41.500044)
			(xy 125.857 -41.500552) (xy 125.825668 -41.500065) (xy 125.763479 -41.492356) (xy 125.702708 -41.477067)
			(xy 125.644274 -41.454429) (xy 125.589064 -41.424787) (xy 125.537912 -41.388587) (xy 125.491594 -41.346379)
			(xy 125.450811 -41.298802) (xy 125.433074 -41.272968) (xy 125.427994 -41.265348) (xy 125.413516 -41.25468)
			(xy 125.331474 -41.23182) (xy 125.31344 -41.233344) (xy 125.305058 -41.237408) (xy 125.279443 -41.248959)
			(xy 125.225668 -41.265256) (xy 125.170085 -41.273492) (xy 125.14199 -41.273984) (xy 125.111188 -41.273371)
			(xy 125.050391 -41.263433) (xy 124.991977 -41.243865) (xy 124.964444 -41.230042) (xy 124.952506 -41.223946)
			(xy 124.92609 -41.224708) (xy 124.840238 -41.276524) (xy 124.832963 -41.28134) (xy 124.821924 -41.294836)
			(xy 124.816025 -41.311242) (xy 124.8156 -41.319958) (xy 124.8156 -42.516195) (xy 131.38521 -42.516195)
			(xy 131.390417 -42.453331) (xy 131.40336 -42.391594) (xy 131.42384 -42.331931) (xy 131.451542 -42.27526)
			(xy 131.486041 -42.222451) (xy 131.526808 -42.174314) (xy 131.573215 -42.13159) (xy 131.62455 -42.094933)
			(xy 131.680026 -42.064908) (xy 131.738789 -42.041975) (xy 131.799938 -42.026487) (xy 131.862532 -42.018681)
			(xy 131.894072 -42.018204) (xy 131.919717 -42.018552) (xy 131.970741 -42.023769) (xy 131.995926 -42.028618)
			(xy 132.006086 -42.03065) (xy 132.025898 -42.026586) (xy 132.103114 -41.97477) (xy 132.11429 -41.958006)
			(xy 132.116068 -41.947846) (xy 132.12141 -41.921977) (xy 132.138297 -41.871925) (xy 132.161927 -41.824681)
			(xy 132.191846 -41.781148) (xy 132.227484 -41.742158) (xy 132.268159 -41.708456) (xy 132.313094 -41.680686)
			(xy 132.36143 -41.65938) (xy 132.412242 -41.644944) (xy 132.46456 -41.637654) (xy 132.490972 -41.637204)
			(xy 132.518225 -41.637681) (xy 132.572176 -41.645435) (xy 132.624474 -41.660788) (xy 132.674055 -41.683428)
			(xy 132.719909 -41.712894) (xy 132.761102 -41.748587) (xy 132.775075 -41.764712) (xy 135.11225 -41.764712)
			(xy 135.116321 -41.70909) (xy 135.128447 -41.654653) (xy 135.14837 -41.602562) (xy 135.175666 -41.553927)
			(xy 135.209752 -41.509784) (xy 135.249901 -41.471075) (xy 135.295259 -41.438624) (xy 135.344859 -41.413123)
			(xy 135.397643 -41.395116) (xy 135.452486 -41.384986) (xy 135.50822 -41.382949) (xy 135.563657 -41.389049)
			(xy 135.617614 -41.403155) (xy 135.668943 -41.424967) (xy 135.716549 -41.454021) (xy 135.759417 -41.489696)
			(xy 135.796634 -41.531233) (xy 135.827407 -41.577746) (xy 135.851079 -41.628243) (xy 135.867147 -41.68165)
			(xy 135.875267 -41.736826) (xy 135.875776 -41.764712) (xy 135.875267 -41.792598) (xy 135.867147 -41.847774)
			(xy 135.851079 -41.901181) (xy 135.827407 -41.951678) (xy 135.796634 -41.998191) (xy 135.759417 -42.039728)
			(xy 135.716549 -42.075403) (xy 135.668943 -42.104457) (xy 135.617614 -42.126269) (xy 135.563657 -42.140375)
			(xy 135.50822 -42.146475) (xy 135.452486 -42.144438) (xy 135.397643 -42.134308) (xy 135.344859 -42.116301)
			(xy 135.295259 -42.0908) (xy 135.249901 -42.058349) (xy 135.209752 -42.01964) (xy 135.175666 -41.975497)
			(xy 135.14837 -41.926862) (xy 135.128447 -41.874771) (xy 135.116321 -41.820334) (xy 135.11225 -41.764712)
			(xy 132.775075 -41.764712) (xy 132.796796 -41.789778) (xy 132.826264 -41.835631) (xy 132.848906 -41.885211)
			(xy 132.864262 -41.937509) (xy 132.872017 -41.991459) (xy 132.87248 -42.018712) (xy 132.872044 -42.045514)
			(xy 132.864561 -42.098593) (xy 132.849715 -42.1501) (xy 132.827799 -42.199019) (xy 132.799246 -42.244385)
			(xy 132.764619 -42.285304) (xy 132.724601 -42.320968) (xy 132.679981 -42.350674) (xy 132.631639 -42.373836)
			(xy 132.58053 -42.389996) (xy 132.52766 -42.398837) (xy 132.500878 -42.399966) (xy 132.490718 -42.400474)
			(xy 132.472176 -42.408602) (xy 132.408676 -42.476674) (xy 132.401818 -42.49547) (xy 132.402072 -42.505884)
			(xy 132.40258 -42.526712) (xy 132.40212 -42.558252) (xy 132.394316 -42.620847) (xy 132.37883 -42.681996)
			(xy 132.355899 -42.74076) (xy 132.325875 -42.796236) (xy 132.28922 -42.847573) (xy 132.246497 -42.893981)
			(xy 132.198362 -42.934749) (xy 132.145554 -42.96925) (xy 132.088883 -42.996954) (xy 132.029222 -43.017436)
			(xy 131.967485 -43.030381) (xy 131.904621 -43.03559) (xy 131.841595 -43.032983) (xy 131.779376 -43.022601)
			(xy 131.718918 -43.004603) (xy 131.661152 -42.979264) (xy 131.606962 -42.946976) (xy 131.557183 -42.908232)
			(xy 131.512579 -42.863629) (xy 131.473834 -42.813851) (xy 131.441543 -42.759663) (xy 131.416203 -42.701897)
			(xy 131.398203 -42.64144) (xy 131.387818 -42.579221) (xy 131.38521 -42.516195) (xy 124.8156 -42.516195)
			(xy 124.8156 -42.97426) (xy 130.011422 -42.97426) (xy 130.015493 -42.918638) (xy 130.027619 -42.864201)
			(xy 130.047542 -42.81211) (xy 130.074838 -42.763475) (xy 130.108924 -42.719332) (xy 130.149073 -42.680623)
			(xy 130.194431 -42.648172) (xy 130.244031 -42.622671) (xy 130.296815 -42.604664) (xy 130.351658 -42.594534)
			(xy 130.407392 -42.592497) (xy 130.462829 -42.598597) (xy 130.516786 -42.612703) (xy 130.568115 -42.634515)
			(xy 130.615721 -42.663569) (xy 130.658589 -42.699244) (xy 130.695806 -42.740781) (xy 130.726579 -42.787294)
			(xy 130.750251 -42.837791) (xy 130.766319 -42.891198) (xy 130.774439 -42.946374) (xy 130.774948 -42.97426)
			(xy 130.774439 -43.002146) (xy 130.766319 -43.057322) (xy 130.750251 -43.110729) (xy 130.726579 -43.161226)
			(xy 130.695806 -43.207739) (xy 130.658589 -43.249276) (xy 130.615721 -43.284951) (xy 130.568115 -43.314005)
			(xy 130.516786 -43.335817) (xy 130.462829 -43.349923) (xy 130.407392 -43.356023) (xy 130.351658 -43.353986)
			(xy 130.296815 -43.343856) (xy 130.244031 -43.325849) (xy 130.194431 -43.300348) (xy 130.149073 -43.267897)
			(xy 130.108924 -43.229188) (xy 130.074838 -43.185045) (xy 130.047542 -43.13641) (xy 130.027619 -43.084319)
			(xy 130.015493 -43.029882) (xy 130.011422 -42.97426) (xy 124.8156 -42.97426) (xy 124.8156 -47.153025)
			(xy 125.280922 -47.153025) (xy 125.280922 -47.089103) (xy 125.288933 -47.025685) (xy 125.30483 -46.963771)
			(xy 125.328362 -46.904338) (xy 125.359156 -46.848323) (xy 125.396729 -46.796608) (xy 125.440486 -46.750011)
			(xy 125.489739 -46.709266) (xy 125.54371 -46.675015) (xy 125.601549 -46.647798) (xy 125.662342 -46.628045)
			(xy 125.725132 -46.616067) (xy 125.788928 -46.612054) (xy 125.852724 -46.616067) (xy 125.915514 -46.628045)
			(xy 125.976307 -46.647798) (xy 126.034146 -46.675015) (xy 126.088117 -46.709266) (xy 126.13737 -46.750011)
			(xy 126.181127 -46.796608) (xy 126.2187 -46.848323) (xy 126.249494 -46.904338) (xy 126.273026 -46.963771)
			(xy 126.288923 -47.025685) (xy 126.296934 -47.089103) (xy 126.297436 -47.121064) (xy 126.296934 -47.153025)
			(xy 127.382772 -47.153025) (xy 127.382772 -47.089103) (xy 127.390783 -47.025685) (xy 127.40668 -46.963771)
			(xy 127.430212 -46.904338) (xy 127.461006 -46.848323) (xy 127.498579 -46.796608) (xy 127.542336 -46.750011)
			(xy 127.591589 -46.709266) (xy 127.64556 -46.675015) (xy 127.703399 -46.647798) (xy 127.764192 -46.628045)
			(xy 127.826982 -46.616067) (xy 127.890778 -46.612054) (xy 127.954574 -46.616067) (xy 128.017364 -46.628045)
			(xy 128.078157 -46.647798) (xy 128.135996 -46.675015) (xy 128.189967 -46.709266) (xy 128.23922 -46.750011)
			(xy 128.282977 -46.796608) (xy 128.32055 -46.848323) (xy 128.351344 -46.904338) (xy 128.374876 -46.963771)
			(xy 128.390773 -47.025685) (xy 128.398784 -47.089103) (xy 128.399286 -47.121064) (xy 128.398784 -47.153025)
			(xy 128.390773 -47.216443) (xy 128.374876 -47.278357) (xy 128.351344 -47.33779) (xy 128.32055 -47.393805)
			(xy 128.282977 -47.44552) (xy 128.23922 -47.492117) (xy 128.189967 -47.532862) (xy 128.135996 -47.567113)
			(xy 128.078157 -47.59433) (xy 128.017364 -47.614083) (xy 127.954574 -47.626061) (xy 127.890778 -47.630075)
			(xy 127.826982 -47.626061) (xy 127.764192 -47.614083) (xy 127.703399 -47.59433) (xy 127.64556 -47.567113)
			(xy 127.591589 -47.532862) (xy 127.542336 -47.492117) (xy 127.498579 -47.44552) (xy 127.461006 -47.393805)
			(xy 127.430212 -47.33779) (xy 127.40668 -47.278357) (xy 127.390783 -47.216443) (xy 127.382772 -47.153025)
			(xy 126.296934 -47.153025) (xy 126.288923 -47.216443) (xy 126.273026 -47.278357) (xy 126.249494 -47.33779)
			(xy 126.2187 -47.393805) (xy 126.181127 -47.44552) (xy 126.13737 -47.492117) (xy 126.088117 -47.532862)
			(xy 126.034146 -47.567113) (xy 125.976307 -47.59433) (xy 125.915514 -47.614083) (xy 125.852724 -47.626061)
			(xy 125.788928 -47.630075) (xy 125.725132 -47.626061) (xy 125.662342 -47.614083) (xy 125.601549 -47.59433)
			(xy 125.54371 -47.567113) (xy 125.489739 -47.532862) (xy 125.440486 -47.492117) (xy 125.396729 -47.44552)
			(xy 125.359156 -47.393805) (xy 125.328362 -47.33779) (xy 125.30483 -47.278357) (xy 125.288933 -47.216443)
			(xy 125.280922 -47.153025) (xy 124.8156 -47.153025) (xy 124.8156 -48.137064) (xy 125.40691 -48.137064)
			(xy 125.410981 -48.081442) (xy 125.423107 -48.027005) (xy 125.44303 -47.974914) (xy 125.470326 -47.926279)
			(xy 125.504412 -47.882136) (xy 125.544561 -47.843427) (xy 125.589919 -47.810976) (xy 125.639519 -47.785475)
			(xy 125.692303 -47.767468) (xy 125.747146 -47.757338) (xy 125.80288 -47.755301) (xy 125.858317 -47.761401)
			(xy 125.912274 -47.775507) (xy 125.963603 -47.797319) (xy 126.011209 -47.826373) (xy 126.054077 -47.862048)
			(xy 126.091294 -47.903585) (xy 126.122067 -47.950098) (xy 126.145739 -48.000595) (xy 126.161807 -48.054002)
			(xy 126.169927 -48.109178) (xy 126.170436 -48.137064) (xy 126.169927 -48.16495) (xy 126.161807 -48.220126)
			(xy 126.145739 -48.273533) (xy 126.122067 -48.32403) (xy 126.091294 -48.370543) (xy 126.054077 -48.41208)
			(xy 126.011209 -48.447755) (xy 125.963603 -48.476809) (xy 125.912274 -48.498621) (xy 125.858317 -48.512727)
			(xy 125.80288 -48.518827) (xy 125.747146 -48.51679) (xy 125.692303 -48.50666) (xy 125.639519 -48.488653)
			(xy 125.589919 -48.463152) (xy 125.544561 -48.430701) (xy 125.504412 -48.391992) (xy 125.470326 -48.347849)
			(xy 125.44303 -48.299214) (xy 125.423107 -48.247123) (xy 125.410981 -48.192686) (xy 125.40691 -48.137064)
			(xy 124.8156 -48.137064) (xy 124.8156 -49.185025) (xy 125.280922 -49.185025) (xy 125.280922 -49.121103)
			(xy 125.288933 -49.057685) (xy 125.30483 -48.995771) (xy 125.328362 -48.936338) (xy 125.359156 -48.880323)
			(xy 125.396729 -48.828608) (xy 125.440486 -48.782011) (xy 125.489739 -48.741266) (xy 125.54371 -48.707015)
			(xy 125.601549 -48.679798) (xy 125.662342 -48.660045) (xy 125.725132 -48.648067) (xy 125.788928 -48.644054)
			(xy 125.852724 -48.648067) (xy 125.915514 -48.660045) (xy 125.976307 -48.679798) (xy 126.034146 -48.707015)
			(xy 126.068606 -48.728884) (xy 131.365496 -48.728884) (xy 131.369567 -48.673262) (xy 131.381693 -48.618825)
			(xy 131.401616 -48.566734) (xy 131.428912 -48.518099) (xy 131.462998 -48.473956) (xy 131.503147 -48.435247)
			(xy 131.548505 -48.402796) (xy 131.598105 -48.377295) (xy 131.650889 -48.359288) (xy 131.705732 -48.349158)
			(xy 131.761466 -48.347121) (xy 131.816903 -48.353221) (xy 131.87086 -48.367327) (xy 131.922189 -48.389139)
			(xy 131.969795 -48.418193) (xy 132.012663 -48.453868) (xy 132.04988 -48.495405) (xy 132.080653 -48.541918)
			(xy 132.104325 -48.592415) (xy 132.120393 -48.645822) (xy 132.128513 -48.700998) (xy 132.129022 -48.728884)
			(xy 132.128513 -48.75677) (xy 132.120393 -48.811946) (xy 132.104325 -48.865353) (xy 132.080653 -48.91585)
			(xy 132.04988 -48.962363) (xy 132.012663 -49.0039) (xy 131.969795 -49.039575) (xy 131.922189 -49.068629)
			(xy 131.87086 -49.090441) (xy 131.816903 -49.104547) (xy 131.761466 -49.110647) (xy 131.705732 -49.10861)
			(xy 131.650889 -49.09848) (xy 131.598105 -49.080473) (xy 131.548505 -49.054972) (xy 131.503147 -49.022521)
			(xy 131.462998 -48.983812) (xy 131.428912 -48.939669) (xy 131.401616 -48.891034) (xy 131.381693 -48.838943)
			(xy 131.369567 -48.784506) (xy 131.365496 -48.728884) (xy 126.068606 -48.728884) (xy 126.088117 -48.741266)
			(xy 126.13737 -48.782011) (xy 126.181127 -48.828608) (xy 126.2187 -48.880323) (xy 126.249494 -48.936338)
			(xy 126.273026 -48.995771) (xy 126.288923 -49.057685) (xy 126.296934 -49.121103) (xy 126.297436 -49.153064)
			(xy 126.296934 -49.185025) (xy 126.288923 -49.248443) (xy 126.273026 -49.310357) (xy 126.249494 -49.36979)
			(xy 126.2187 -49.425805) (xy 126.181127 -49.47752) (xy 126.13737 -49.524117) (xy 126.088117 -49.564862)
			(xy 126.034146 -49.599113) (xy 125.976307 -49.62633) (xy 125.915514 -49.646083) (xy 125.852724 -49.658061)
			(xy 125.788928 -49.662075) (xy 125.725132 -49.658061) (xy 125.662342 -49.646083) (xy 125.601549 -49.62633)
			(xy 125.54371 -49.599113) (xy 125.489739 -49.564862) (xy 125.440486 -49.524117) (xy 125.396729 -49.47752)
			(xy 125.359156 -49.425805) (xy 125.328362 -49.36979) (xy 125.30483 -49.310357) (xy 125.288933 -49.248443)
			(xy 125.280922 -49.185025) (xy 124.8156 -49.185025) (xy 124.8156 -50.169064) (xy 125.40691 -50.169064)
			(xy 125.410981 -50.113442) (xy 125.423107 -50.059005) (xy 125.44303 -50.006914) (xy 125.470326 -49.958279)
			(xy 125.504412 -49.914136) (xy 125.544561 -49.875427) (xy 125.589919 -49.842976) (xy 125.639519 -49.817475)
			(xy 125.692303 -49.799468) (xy 125.747146 -49.789338) (xy 125.80288 -49.787301) (xy 125.858317 -49.793401)
			(xy 125.912274 -49.807507) (xy 125.963603 -49.829319) (xy 126.011209 -49.858373) (xy 126.054077 -49.894048)
			(xy 126.091294 -49.935585) (xy 126.122067 -49.982098) (xy 126.145739 -50.032595) (xy 126.161807 -50.086002)
			(xy 126.169927 -50.141178) (xy 126.170436 -50.169064) (xy 126.169927 -50.19695) (xy 126.161807 -50.252126)
			(xy 126.145739 -50.305533) (xy 126.122067 -50.35603) (xy 126.091294 -50.402543) (xy 126.054077 -50.44408)
			(xy 126.011209 -50.479755) (xy 126.002133 -50.485294) (xy 127.813816 -50.485294) (xy 127.814316 -50.457628)
			(xy 127.822317 -50.402878) (xy 127.838135 -50.349856) (xy 127.86144 -50.299672) (xy 127.891743 -50.253376)
			(xy 127.928411 -50.211939) (xy 127.970674 -50.176227) (xy 127.993902 -50.16119) (xy 127.985807 -50.139193)
			(xy 127.974397 -50.093729) (xy 127.968625 -50.047212) (xy 127.968248 -50.023776) (xy 127.968734 -49.996507)
			(xy 127.976496 -49.942523) (xy 127.991861 -49.890193) (xy 128.014518 -49.840583) (xy 128.044004 -49.794702)
			(xy 128.079719 -49.753485) (xy 128.120936 -49.71777) (xy 128.166817 -49.688284) (xy 128.216427 -49.665627)
			(xy 128.268757 -49.650262) (xy 128.322741 -49.6425) (xy 128.377279 -49.6425) (xy 128.431263 -49.650262)
			(xy 128.483593 -49.665627) (xy 128.533203 -49.688284) (xy 128.579084 -49.71777) (xy 128.620301 -49.753485)
			(xy 128.656016 -49.794702) (xy 128.668237 -49.813718) (xy 131.596636 -49.813718) (xy 131.600707 -49.758096)
			(xy 131.612833 -49.703659) (xy 131.632756 -49.651568) (xy 131.660052 -49.602933) (xy 131.694138 -49.55879)
			(xy 131.734287 -49.520081) (xy 131.779645 -49.48763) (xy 131.829245 -49.462129) (xy 131.882029 -49.444122)
			(xy 131.936872 -49.433992) (xy 131.992606 -49.431955) (xy 132.048043 -49.438055) (xy 132.102 -49.452161)
			(xy 132.153329 -49.473973) (xy 132.200935 -49.503027) (xy 132.243803 -49.538702) (xy 132.28102 -49.580239)
			(xy 132.311793 -49.626752) (xy 132.335465 -49.677249) (xy 132.351533 -49.730656) (xy 132.359653 -49.785832)
			(xy 132.360162 -49.813718) (xy 132.359653 -49.841604) (xy 132.351533 -49.89678) (xy 132.335465 -49.950187)
			(xy 132.311793 -50.000684) (xy 132.28102 -50.047197) (xy 132.243803 -50.088734) (xy 132.200935 -50.124409)
			(xy 132.153329 -50.153463) (xy 132.102 -50.175275) (xy 132.048043 -50.189381) (xy 131.992606 -50.195481)
			(xy 131.936872 -50.193444) (xy 131.882029 -50.183314) (xy 131.829245 -50.165307) (xy 131.779645 -50.139806)
			(xy 131.734287 -50.107355) (xy 131.694138 -50.068646) (xy 131.660052 -50.024503) (xy 131.632756 -49.975868)
			(xy 131.612833 -49.923777) (xy 131.600707 -49.86934) (xy 131.596636 -49.813718) (xy 128.668237 -49.813718)
			(xy 128.685502 -49.840583) (xy 128.708159 -49.890193) (xy 128.723524 -49.942523) (xy 128.731286 -49.996507)
			(xy 128.731772 -50.023776) (xy 128.731272 -50.051471) (xy 128.723283 -50.106282) (xy 128.707455 -50.159362)
			(xy 128.684119 -50.209596) (xy 128.653768 -50.25593) (xy 128.617037 -50.29739) (xy 128.574699 -50.333104)
			(xy 128.551432 -50.348134) (xy 128.559482 -50.370095) (xy 128.570801 -50.41548) (xy 128.576491 -50.461907)
			(xy 128.576832 -50.485294) (xy 128.576346 -50.512545) (xy 128.56859 -50.566493) (xy 128.553235 -50.618788)
			(xy 128.530593 -50.668365) (xy 128.526635 -50.674524) (xy 128.710434 -50.674524) (xy 128.714505 -50.618902)
			(xy 128.726631 -50.564465) (xy 128.746554 -50.512374) (xy 128.77385 -50.463739) (xy 128.807936 -50.419596)
			(xy 128.848085 -50.380887) (xy 128.893443 -50.348436) (xy 128.943043 -50.322935) (xy 128.995827 -50.304928)
			(xy 129.05067 -50.294798) (xy 129.106404 -50.292761) (xy 129.161841 -50.298861) (xy 129.215798 -50.312967)
			(xy 129.267127 -50.334779) (xy 129.314733 -50.363833) (xy 129.357601 -50.399508) (xy 129.394818 -50.441045)
			(xy 129.425591 -50.487558) (xy 129.449263 -50.538055) (xy 129.465331 -50.591462) (xy 129.473451 -50.646638)
			(xy 129.47396 -50.674524) (xy 129.473635 -50.692304) (xy 129.607816 -50.692304) (xy 129.611887 -50.636682)
			(xy 129.624013 -50.582245) (xy 129.643936 -50.530154) (xy 129.671232 -50.481519) (xy 129.705318 -50.437376)
			(xy 129.745467 -50.398667) (xy 129.790825 -50.366216) (xy 129.840425 -50.340715) (xy 129.893209 -50.322708)
			(xy 129.948052 -50.312578) (xy 130.003786 -50.310541) (xy 130.059223 -50.316641) (xy 130.11318 -50.330747)
			(xy 130.164509 -50.352559) (xy 130.212115 -50.381613) (xy 130.254983 -50.417288) (xy 130.2922 -50.458825)
			(xy 130.322973 -50.505338) (xy 130.346645 -50.555835) (xy 130.362713 -50.609242) (xy 130.370833 -50.664418)
			(xy 130.371342 -50.692304) (xy 130.370833 -50.72019) (xy 130.362713 -50.775366) (xy 130.346645 -50.828773)
			(xy 130.322973 -50.87927) (xy 130.299965 -50.914046) (xy 131.015738 -50.914046) (xy 131.019809 -50.858424)
			(xy 131.031935 -50.803987) (xy 131.051858 -50.751896) (xy 131.079154 -50.703261) (xy 131.11324 -50.659118)
			(xy 131.153389 -50.620409) (xy 131.198747 -50.587958) (xy 131.248347 -50.562457) (xy 131.301131 -50.54445)
			(xy 131.355974 -50.53432) (xy 131.411708 -50.532283) (xy 131.467145 -50.538383) (xy 131.521102 -50.552489)
			(xy 131.572431 -50.574301) (xy 131.620037 -50.603355) (xy 131.662905 -50.63903) (xy 131.700122 -50.680567)
			(xy 131.730895 -50.72708) (xy 131.754567 -50.777577) (xy 131.770635 -50.830984) (xy 131.778755 -50.88616)
			(xy 131.779264 -50.914046) (xy 131.778755 -50.941932) (xy 131.770635 -50.997108) (xy 131.754567 -51.050515)
			(xy 131.730895 -51.101012) (xy 131.700122 -51.147525) (xy 131.662905 -51.189062) (xy 131.620037 -51.224737)
			(xy 131.572431 -51.253791) (xy 131.521102 -51.275603) (xy 131.467145 -51.289709) (xy 131.411708 -51.295809)
			(xy 131.355974 -51.293772) (xy 131.301131 -51.283642) (xy 131.248347 -51.265635) (xy 131.198747 -51.240134)
			(xy 131.153389 -51.207683) (xy 131.11324 -51.168974) (xy 131.079154 -51.124831) (xy 131.051858 -51.076196)
			(xy 131.031935 -51.024105) (xy 131.019809 -50.969668) (xy 131.015738 -50.914046) (xy 130.299965 -50.914046)
			(xy 130.2922 -50.925783) (xy 130.254983 -50.96732) (xy 130.212115 -51.002995) (xy 130.164509 -51.032049)
			(xy 130.11318 -51.053861) (xy 130.059223 -51.067967) (xy 130.003786 -51.074067) (xy 129.948052 -51.07203)
			(xy 129.893209 -51.0619) (xy 129.840425 -51.043893) (xy 129.790825 -51.018392) (xy 129.745467 -50.985941)
			(xy 129.705318 -50.947232) (xy 129.671232 -50.903089) (xy 129.643936 -50.854454) (xy 129.624013 -50.802363)
			(xy 129.611887 -50.747926) (xy 129.607816 -50.692304) (xy 129.473635 -50.692304) (xy 129.473451 -50.70241)
			(xy 129.465331 -50.757586) (xy 129.449263 -50.810993) (xy 129.425591 -50.86149) (xy 129.394818 -50.908003)
			(xy 129.357601 -50.94954) (xy 129.314733 -50.985215) (xy 129.267127 -51.014269) (xy 129.215798 -51.036081)
			(xy 129.161841 -51.050187) (xy 129.106404 -51.056287) (xy 129.05067 -51.05425) (xy 128.995827 -51.04412)
			(xy 128.943043 -51.026113) (xy 128.893443 -51.000612) (xy 128.848085 -50.968161) (xy 128.807936 -50.929452)
			(xy 128.77385 -50.885309) (xy 128.746554 -50.836674) (xy 128.726631 -50.784583) (xy 128.714505 -50.730146)
			(xy 128.710434 -50.674524) (xy 128.526635 -50.674524) (xy 128.501127 -50.714215) (xy 128.465436 -50.755406)
			(xy 128.424245 -50.791097) (xy 128.378395 -50.820563) (xy 128.328818 -50.843205) (xy 128.276523 -50.85856)
			(xy 128.222575 -50.866316) (xy 128.168073 -50.866316) (xy 128.114125 -50.85856) (xy 128.06183 -50.843205)
			(xy 128.012253 -50.820563) (xy 127.966403 -50.791097) (xy 127.925212 -50.755406) (xy 127.889521 -50.714215)
			(xy 127.860055 -50.668365) (xy 127.837413 -50.618788) (xy 127.822058 -50.566493) (xy 127.814302 -50.512545)
			(xy 127.813816 -50.485294) (xy 126.002133 -50.485294) (xy 125.963603 -50.508809) (xy 125.912274 -50.530621)
			(xy 125.858317 -50.544727) (xy 125.80288 -50.550827) (xy 125.747146 -50.54879) (xy 125.692303 -50.53866)
			(xy 125.639519 -50.520653) (xy 125.589919 -50.495152) (xy 125.544561 -50.462701) (xy 125.504412 -50.423992)
			(xy 125.470326 -50.379849) (xy 125.44303 -50.331214) (xy 125.423107 -50.279123) (xy 125.410981 -50.224686)
			(xy 125.40691 -50.169064) (xy 124.8156 -50.169064) (xy 124.8156 -51.505104) (xy 127.723136 -51.505104)
			(xy 127.727207 -51.449482) (xy 127.739333 -51.395045) (xy 127.759256 -51.342954) (xy 127.786552 -51.294319)
			(xy 127.820638 -51.250176) (xy 127.860787 -51.211467) (xy 127.906145 -51.179016) (xy 127.955745 -51.153515)
			(xy 128.008529 -51.135508) (xy 128.063372 -51.125378) (xy 128.119106 -51.123341) (xy 128.174543 -51.129441)
			(xy 128.2285 -51.143547) (xy 128.279829 -51.165359) (xy 128.327435 -51.194413) (xy 128.370303 -51.230088)
			(xy 128.40752 -51.271625) (xy 128.438293 -51.318138) (xy 128.461965 -51.368635) (xy 128.478033 -51.422042)
			(xy 128.486153 -51.477218) (xy 128.486662 -51.505104) (xy 128.486153 -51.53299) (xy 128.478033 -51.588166)
			(xy 128.461965 -51.641573) (xy 128.438293 -51.69207) (xy 128.40752 -51.738583) (xy 128.370303 -51.78012)
			(xy 128.327435 -51.815795) (xy 128.279829 -51.844849) (xy 128.2285 -51.866661) (xy 128.174543 -51.880767)
			(xy 128.119106 -51.886867) (xy 128.063372 -51.88483) (xy 128.008529 -51.8747) (xy 127.955745 -51.856693)
			(xy 127.906145 -51.831192) (xy 127.860787 -51.798741) (xy 127.820638 -51.760032) (xy 127.786552 -51.715889)
			(xy 127.759256 -51.667254) (xy 127.739333 -51.615163) (xy 127.727207 -51.560726) (xy 127.723136 -51.505104)
			(xy 124.8156 -51.505104) (xy 124.8156 -52.07762) (xy 125.813056 -52.07762) (xy 125.817127 -52.021998)
			(xy 125.829253 -51.967561) (xy 125.849176 -51.91547) (xy 125.876472 -51.866835) (xy 125.910558 -51.822692)
			(xy 125.950707 -51.783983) (xy 125.996065 -51.751532) (xy 126.045665 -51.726031) (xy 126.098449 -51.708024)
			(xy 126.153292 -51.697894) (xy 126.209026 -51.695857) (xy 126.264463 -51.701957) (xy 126.31842 -51.716063)
			(xy 126.369749 -51.737875) (xy 126.417355 -51.766929) (xy 126.460223 -51.802604) (xy 126.49744 -51.844141)
			(xy 126.528213 -51.890654) (xy 126.551885 -51.941151) (xy 126.567953 -51.994558) (xy 126.576073 -52.049734)
			(xy 126.576582 -52.07762) (xy 126.576073 -52.105506) (xy 126.567953 -52.160682) (xy 126.551885 -52.214089)
			(xy 126.528213 -52.264586) (xy 126.49744 -52.311099) (xy 126.460223 -52.352636) (xy 126.417355 -52.388311)
			(xy 126.369749 -52.417365) (xy 126.347979 -52.426616) (xy 129.685286 -52.426616) (xy 129.689357 -52.370994)
			(xy 129.701483 -52.316557) (xy 129.721406 -52.264466) (xy 129.748702 -52.215831) (xy 129.782788 -52.171688)
			(xy 129.822937 -52.132979) (xy 129.868295 -52.100528) (xy 129.917895 -52.075027) (xy 129.970679 -52.05702)
			(xy 130.025522 -52.04689) (xy 130.081256 -52.044853) (xy 130.136693 -52.050953) (xy 130.19065 -52.065059)
			(xy 130.241979 -52.086871) (xy 130.289585 -52.115925) (xy 130.332453 -52.1516) (xy 130.36967 -52.193137)
			(xy 130.400443 -52.23965) (xy 130.424115 -52.290147) (xy 130.440183 -52.343554) (xy 130.448303 -52.39873)
			(xy 130.448812 -52.426616) (xy 130.448303 -52.454502) (xy 130.440183 -52.509678) (xy 130.424115 -52.563085)
			(xy 130.400443 -52.613582) (xy 130.36967 -52.660095) (xy 130.332453 -52.701632) (xy 130.289585 -52.737307)
			(xy 130.241979 -52.766361) (xy 130.19065 -52.788173) (xy 130.136693 -52.802279) (xy 130.081256 -52.808379)
			(xy 130.025522 -52.806342) (xy 129.970679 -52.796212) (xy 129.917895 -52.778205) (xy 129.868295 -52.752704)
			(xy 129.822937 -52.720253) (xy 129.782788 -52.681544) (xy 129.748702 -52.637401) (xy 129.721406 -52.588766)
			(xy 129.701483 -52.536675) (xy 129.689357 -52.482238) (xy 129.685286 -52.426616) (xy 126.347979 -52.426616)
			(xy 126.31842 -52.439177) (xy 126.264463 -52.453283) (xy 126.209026 -52.459383) (xy 126.153292 -52.457346)
			(xy 126.098449 -52.447216) (xy 126.045665 -52.429209) (xy 125.996065 -52.403708) (xy 125.950707 -52.371257)
			(xy 125.910558 -52.332548) (xy 125.876472 -52.288405) (xy 125.849176 -52.23977) (xy 125.829253 -52.187679)
			(xy 125.817127 -52.133242) (xy 125.813056 -52.07762) (xy 124.8156 -52.07762) (xy 124.8156 -53.15839)
			(xy 126.307086 -53.15839) (xy 126.311157 -53.102768) (xy 126.323283 -53.048331) (xy 126.343206 -52.99624)
			(xy 126.370502 -52.947605) (xy 126.404588 -52.903462) (xy 126.444737 -52.864753) (xy 126.490095 -52.832302)
			(xy 126.539695 -52.806801) (xy 126.592479 -52.788794) (xy 126.647322 -52.778664) (xy 126.703056 -52.776627)
			(xy 126.758493 -52.782727) (xy 126.81245 -52.796833) (xy 126.863779 -52.818645) (xy 126.911385 -52.847699)
			(xy 126.954253 -52.883374) (xy 126.99147 -52.924911) (xy 127.022243 -52.971424) (xy 127.045915 -53.021921)
			(xy 127.061983 -53.075328) (xy 127.070103 -53.130504) (xy 127.070612 -53.15839) (xy 127.070103 -53.186276)
			(xy 127.061983 -53.241452) (xy 127.045915 -53.294859) (xy 127.022243 -53.345356) (xy 126.99147 -53.391869)
			(xy 126.954253 -53.433406) (xy 126.911385 -53.469081) (xy 126.863779 -53.498135) (xy 126.81245 -53.519947)
			(xy 126.758493 -53.534053) (xy 126.703056 -53.540153) (xy 126.647322 -53.538116) (xy 126.592479 -53.527986)
			(xy 126.539695 -53.509979) (xy 126.490095 -53.484478) (xy 126.444737 -53.452027) (xy 126.404588 -53.413318)
			(xy 126.370502 -53.369175) (xy 126.343206 -53.32054) (xy 126.323283 -53.268449) (xy 126.311157 -53.214012)
			(xy 126.307086 -53.15839) (xy 124.8156 -53.15839) (xy 124.8156 -53.513228) (xy 124.816086 -53.522675)
			(xy 124.822985 -53.54027) (xy 124.829062 -53.547518) (xy 124.881894 -53.605176) (xy 124.898912 -53.613558)
			(xy 124.90831 -53.614574) (xy 124.936476 -53.617545) (xy 124.99155 -53.630745) (xy 125.044068 -53.65194)
			(xy 125.092877 -53.680666) (xy 125.136903 -53.71629) (xy 125.175181 -53.758031) (xy 125.206868 -53.804971)
			(xy 125.231269 -53.856079) (xy 125.247847 -53.910232) (xy 125.256239 -53.966241) (xy 125.256798 -53.994558)
			(xy 125.256208 -54.0245) (xy 125.24684 -54.083647) (xy 125.228343 -54.140602) (xy 125.21114 -54.17439)
			(xy 126.307086 -54.17439) (xy 126.311157 -54.118768) (xy 126.323283 -54.064331) (xy 126.343206 -54.01224)
			(xy 126.370502 -53.963605) (xy 126.404588 -53.919462) (xy 126.444737 -53.880753) (xy 126.490095 -53.848302)
			(xy 126.539695 -53.822801) (xy 126.592479 -53.804794) (xy 126.647322 -53.794664) (xy 126.703056 -53.792627)
			(xy 126.758493 -53.798727) (xy 126.81245 -53.812833) (xy 126.863779 -53.834645) (xy 126.884829 -53.847492)
			(xy 131.183124 -53.847492) (xy 131.187195 -53.79187) (xy 131.199321 -53.737433) (xy 131.219244 -53.685342)
			(xy 131.24654 -53.636707) (xy 131.280626 -53.592564) (xy 131.320775 -53.553855) (xy 131.366133 -53.521404)
			(xy 131.415733 -53.495903) (xy 131.468517 -53.477896) (xy 131.52336 -53.467766) (xy 131.579094 -53.465729)
			(xy 131.634531 -53.471829) (xy 131.688488 -53.485935) (xy 131.739817 -53.507747) (xy 131.787423 -53.536801)
			(xy 131.830291 -53.572476) (xy 131.867508 -53.614013) (xy 131.898281 -53.660526) (xy 131.921953 -53.711023)
			(xy 131.938021 -53.76443) (xy 131.946141 -53.819606) (xy 131.94665 -53.847492) (xy 131.946141 -53.875378)
			(xy 131.938021 -53.930554) (xy 131.921953 -53.983961) (xy 131.898281 -54.034458) (xy 131.867508 -54.080971)
			(xy 131.830291 -54.122508) (xy 131.787423 -54.158183) (xy 131.739817 -54.187237) (xy 131.688488 -54.209049)
			(xy 131.634531 -54.223155) (xy 131.579094 -54.229255) (xy 131.52336 -54.227218) (xy 131.468517 -54.217088)
			(xy 131.415733 -54.199081) (xy 131.366133 -54.17358) (xy 131.320775 -54.141129) (xy 131.280626 -54.10242)
			(xy 131.24654 -54.058277) (xy 131.219244 -54.009642) (xy 131.199321 -53.957551) (xy 131.187195 -53.903114)
			(xy 131.183124 -53.847492) (xy 126.884829 -53.847492) (xy 126.911385 -53.863699) (xy 126.954253 -53.899374)
			(xy 126.99147 -53.940911) (xy 127.022243 -53.987424) (xy 127.045915 -54.037921) (xy 127.061983 -54.091328)
			(xy 127.070103 -54.146504) (xy 127.070612 -54.17439) (xy 127.070103 -54.202276) (xy 127.061983 -54.257452)
			(xy 127.045915 -54.310859) (xy 127.022243 -54.361356) (xy 126.99147 -54.407869) (xy 126.954253 -54.449406)
			(xy 126.911385 -54.485081) (xy 126.863779 -54.514135) (xy 126.81245 -54.535947) (xy 126.758493 -54.550053)
			(xy 126.703056 -54.556153) (xy 126.647322 -54.554116) (xy 126.592479 -54.543986) (xy 126.539695 -54.525979)
			(xy 126.490095 -54.500478) (xy 126.444737 -54.468027) (xy 126.404588 -54.429318) (xy 126.370502 -54.385175)
			(xy 126.343206 -54.33654) (xy 126.323283 -54.284449) (xy 126.311157 -54.230012) (xy 126.307086 -54.17439)
			(xy 125.21114 -54.17439) (xy 125.201172 -54.193967) (xy 125.165994 -54.24243) (xy 125.123675 -54.2848)
			(xy 125.099826 -54.302914) (xy 125.090523 -54.310485) (xy 125.079663 -54.331831) (xy 125.078998 -54.343808)
			(xy 125.078998 -54.426358) (xy 125.079708 -54.43832) (xy 125.090563 -54.459651) (xy 125.099826 -54.467252)
			(xy 125.120338 -54.482684) (xy 125.157427 -54.518169) (xy 125.189417 -54.558312) (xy 125.21573 -54.602385)
			(xy 125.235889 -54.649591) (xy 125.249529 -54.699075) (xy 125.256404 -54.749943) (xy 125.256798 -54.775608)
			(xy 125.256287 -54.803931) (xy 125.247921 -54.859955) (xy 125.2446 -54.870815) (xy 127.597148 -54.870815)
			(xy 127.597148 -54.806893) (xy 127.605159 -54.743475) (xy 127.621056 -54.681561) (xy 127.644588 -54.622128)
			(xy 127.675382 -54.566113) (xy 127.712955 -54.514398) (xy 127.756712 -54.467801) (xy 127.805965 -54.427056)
			(xy 127.859936 -54.392805) (xy 127.917775 -54.365588) (xy 127.978568 -54.345835) (xy 128.041358 -54.333857)
			(xy 128.105154 -54.329844) (xy 128.16895 -54.333857) (xy 128.23174 -54.345835) (xy 128.292533 -54.365588)
			(xy 128.350372 -54.392805) (xy 128.404343 -54.427056) (xy 128.453596 -54.467801) (xy 128.497353 -54.514398)
			(xy 128.534926 -54.566113) (xy 128.56572 -54.622128) (xy 128.589252 -54.681561) (xy 128.605149 -54.743475)
			(xy 128.61316 -54.806893) (xy 128.613662 -54.838854) (xy 128.61316 -54.870815) (xy 128.605149 -54.934233)
			(xy 128.589252 -54.996147) (xy 128.56572 -55.05558) (xy 128.534926 -55.111595) (xy 128.497353 -55.16331)
			(xy 128.453596 -55.209907) (xy 128.404343 -55.250652) (xy 128.350372 -55.284903) (xy 128.292533 -55.31212)
			(xy 128.23174 -55.331873) (xy 128.16895 -55.343851) (xy 128.105154 -55.347865) (xy 128.041358 -55.343851)
			(xy 127.978568 -55.331873) (xy 127.917775 -55.31212) (xy 127.859936 -55.284903) (xy 127.805965 -55.250652)
			(xy 127.756712 -55.209907) (xy 127.712955 -55.16331) (xy 127.675382 -55.111595) (xy 127.644588 -55.05558)
			(xy 127.621056 -54.996147) (xy 127.605159 -54.934233) (xy 127.597148 -54.870815) (xy 125.2446 -54.870815)
			(xy 125.231357 -54.914125) (xy 125.206962 -54.965249) (xy 125.175272 -55.012201) (xy 125.136985 -55.053948)
			(xy 125.092943 -55.089571) (xy 125.044115 -55.118286) (xy 124.991576 -55.139462) (xy 124.936483 -55.152631)
			(xy 124.90831 -55.155592) (xy 124.898912 -55.156608) (xy 124.881894 -55.16499) (xy 124.829062 -55.222648)
			(xy 124.822917 -55.229855) (xy 124.816012 -55.247475) (xy 124.8156 -55.256938) (xy 124.8156 -56.22798)
			(xy 125.130558 -56.22798) (xy 125.134629 -56.172358) (xy 125.146755 -56.117921) (xy 125.166678 -56.06583)
			(xy 125.193974 -56.017195) (xy 125.22806 -55.973052) (xy 125.268209 -55.934343) (xy 125.313567 -55.901892)
			(xy 125.363167 -55.876391) (xy 125.415951 -55.858384) (xy 125.470794 -55.848254) (xy 125.526528 -55.846217)
			(xy 125.581965 -55.852317) (xy 125.635922 -55.866423) (xy 125.687251 -55.888235) (xy 125.734857 -55.917289)
			(xy 125.740715 -55.922164) (xy 128.650236 -55.922164) (xy 128.654307 -55.866542) (xy 128.666433 -55.812105)
			(xy 128.686356 -55.760014) (xy 128.713652 -55.711379) (xy 128.747738 -55.667236) (xy 128.787887 -55.628527)
			(xy 128.833245 -55.596076) (xy 128.882845 -55.570575) (xy 128.935629 -55.552568) (xy 128.990472 -55.542438)
			(xy 129.046206 -55.540401) (xy 129.101643 -55.546501) (xy 129.1556 -55.560607) (xy 129.206929 -55.582419)
			(xy 129.254535 -55.611473) (xy 129.297403 -55.647148) (xy 129.33462 -55.688685) (xy 129.365393 -55.735198)
			(xy 129.389065 -55.785695) (xy 129.405133 -55.839102) (xy 129.413253 -55.894278) (xy 129.413762 -55.922164)
			(xy 129.413253 -55.95005) (xy 129.405133 -56.005226) (xy 129.389065 -56.058633) (xy 129.365393 -56.10913)
			(xy 129.33462 -56.155643) (xy 129.304171 -56.189626) (xy 129.585718 -56.189626) (xy 129.589789 -56.134004)
			(xy 129.601915 -56.079567) (xy 129.621838 -56.027476) (xy 129.649134 -55.978841) (xy 129.68322 -55.934698)
			(xy 129.723369 -55.895989) (xy 129.768727 -55.863538) (xy 129.818327 -55.838037) (xy 129.871111 -55.82003)
			(xy 129.925954 -55.8099) (xy 129.981688 -55.807863) (xy 130.037125 -55.813963) (xy 130.091082 -55.828069)
			(xy 130.142411 -55.849881) (xy 130.190017 -55.878935) (xy 130.232885 -55.91461) (xy 130.239653 -55.922164)
			(xy 130.466336 -55.922164) (xy 130.470407 -55.866542) (xy 130.482533 -55.812105) (xy 130.502456 -55.760014)
			(xy 130.529752 -55.711379) (xy 130.563838 -55.667236) (xy 130.603987 -55.628527) (xy 130.649345 -55.596076)
			(xy 130.698945 -55.570575) (xy 130.751729 -55.552568) (xy 130.806572 -55.542438) (xy 130.862306 -55.540401)
			(xy 130.917743 -55.546501) (xy 130.9717 -55.560607) (xy 131.023029 -55.582419) (xy 131.070635 -55.611473)
			(xy 131.113503 -55.647148) (xy 131.15072 -55.688685) (xy 131.181493 -55.735198) (xy 131.205165 -55.785695)
			(xy 131.221233 -55.839102) (xy 131.229353 -55.894278) (xy 131.229862 -55.922164) (xy 131.229353 -55.95005)
			(xy 131.221233 -56.005226) (xy 131.205165 -56.058633) (xy 131.181493 -56.10913) (xy 131.15072 -56.155643)
			(xy 131.113503 -56.19718) (xy 131.070635 -56.232855) (xy 131.023029 -56.261909) (xy 130.9717 -56.283721)
			(xy 130.917743 -56.297827) (xy 130.862306 -56.303927) (xy 130.806572 -56.30189) (xy 130.751729 -56.29176)
			(xy 130.698945 -56.273753) (xy 130.649345 -56.248252) (xy 130.603987 -56.215801) (xy 130.563838 -56.177092)
			(xy 130.529752 -56.132949) (xy 130.502456 -56.084314) (xy 130.482533 -56.032223) (xy 130.470407 -55.977786)
			(xy 130.466336 -55.922164) (xy 130.239653 -55.922164) (xy 130.270102 -55.956147) (xy 130.300875 -56.00266)
			(xy 130.324547 -56.053157) (xy 130.340615 -56.106564) (xy 130.348735 -56.16174) (xy 130.349244 -56.189626)
			(xy 130.348735 -56.217512) (xy 130.340615 -56.272688) (xy 130.324547 -56.326095) (xy 130.300875 -56.376592)
			(xy 130.270102 -56.423105) (xy 130.232885 -56.464642) (xy 130.190017 -56.500317) (xy 130.142411 -56.529371)
			(xy 130.091082 -56.551183) (xy 130.037125 -56.565289) (xy 129.981688 -56.571389) (xy 129.925954 -56.569352)
			(xy 129.871111 -56.559222) (xy 129.818327 -56.541215) (xy 129.768727 -56.515714) (xy 129.723369 -56.483263)
			(xy 129.68322 -56.444554) (xy 129.649134 -56.400411) (xy 129.621838 -56.351776) (xy 129.601915 -56.299685)
			(xy 129.589789 -56.245248) (xy 129.585718 -56.189626) (xy 129.304171 -56.189626) (xy 129.297403 -56.19718)
			(xy 129.254535 -56.232855) (xy 129.206929 -56.261909) (xy 129.1556 -56.283721) (xy 129.101643 -56.297827)
			(xy 129.046206 -56.303927) (xy 128.990472 -56.30189) (xy 128.935629 -56.29176) (xy 128.882845 -56.273753)
			(xy 128.833245 -56.248252) (xy 128.787887 -56.215801) (xy 128.747738 -56.177092) (xy 128.713652 -56.132949)
			(xy 128.686356 -56.084314) (xy 128.666433 -56.032223) (xy 128.654307 -55.977786) (xy 128.650236 -55.922164)
			(xy 125.740715 -55.922164) (xy 125.777725 -55.952964) (xy 125.814942 -55.994501) (xy 125.845715 -56.041014)
			(xy 125.869387 -56.091511) (xy 125.885455 -56.144918) (xy 125.893575 -56.200094) (xy 125.894084 -56.22798)
			(xy 125.893575 -56.255866) (xy 125.885455 -56.311042) (xy 125.869387 -56.364449) (xy 125.845715 -56.414946)
			(xy 125.814942 -56.461459) (xy 125.777725 -56.502996) (xy 125.760249 -56.51754) (xy 126.461012 -56.51754)
			(xy 126.461498 -56.490289) (xy 126.469254 -56.436341) (xy 126.484609 -56.384046) (xy 126.507251 -56.334469)
			(xy 126.536717 -56.288619) (xy 126.572408 -56.247428) (xy 126.613599 -56.211737) (xy 126.659449 -56.182271)
			(xy 126.709026 -56.159629) (xy 126.761321 -56.144274) (xy 126.815269 -56.136518) (xy 126.869771 -56.136518)
			(xy 126.923719 -56.144274) (xy 126.976014 -56.159629) (xy 127.025591 -56.182271) (xy 127.071441 -56.211737)
			(xy 127.112632 -56.247428) (xy 127.148323 -56.288619) (xy 127.177789 -56.334469) (xy 127.200431 -56.384046)
			(xy 127.215786 -56.436341) (xy 127.223542 -56.490289) (xy 127.224028 -56.51754) (xy 127.223502 -56.546771)
			(xy 127.214572 -56.604547) (xy 127.196912 -56.660279) (xy 127.184404 -56.686704) (xy 127.179832 -56.695848)
			(xy 127.178562 -56.715914) (xy 127.209296 -56.804052) (xy 127.222758 -56.819038) (xy 127.231902 -56.823356)
			(xy 127.256021 -56.835282) (xy 127.300904 -56.864956) (xy 127.341173 -56.900641) (xy 127.376028 -56.94163)
			(xy 127.40478 -56.987109) (xy 127.426857 -57.036176) (xy 127.441821 -57.087859) (xy 127.449375 -57.141131)
			(xy 127.449834 -57.168034) (xy 127.44938 -57.195158) (xy 127.441698 -57.248859) (xy 127.426479 -57.300928)
			(xy 127.404032 -57.350313) (xy 127.374809 -57.396017) (xy 127.339402 -57.437116) (xy 127.319278 -57.455308)
			(xy 127.31115 -57.46242) (xy 127.30226 -57.481724) (xy 127.300228 -57.578244) (xy 127.308356 -57.598056)
			(xy 127.31623 -57.605422) (xy 127.334572 -57.623514) (xy 127.366746 -57.663752) (xy 127.393217 -57.707951)
			(xy 127.413504 -57.755308) (xy 127.427238 -57.804963) (xy 127.434169 -57.856014) (xy 127.434594 -57.881774)
			(xy 127.434589 -57.882028) (xy 129.455672 -57.882028) (xy 129.456178 -57.853759) (xy 129.464507 -57.797838)
			(xy 129.481002 -57.74376) (xy 129.505301 -57.692711) (xy 129.53687 -57.645808) (xy 129.57502 -57.604081)
			(xy 129.596642 -57.585864) (xy 129.60508 -57.578277) (xy 129.614838 -57.557826) (xy 129.615438 -57.546494)
			(xy 129.615438 -57.467754) (xy 129.614825 -57.456431) (xy 129.605049 -57.435997) (xy 129.596642 -57.428384)
			(xy 129.575028 -57.41016) (xy 129.536891 -57.368426) (xy 129.505328 -57.321522) (xy 129.48103 -57.270476)
			(xy 129.464529 -57.216403) (xy 129.456185 -57.160487) (xy 129.455672 -57.13222) (xy 129.456158 -57.104969)
			(xy 129.463914 -57.051021) (xy 129.479269 -56.998726) (xy 129.501911 -56.949149) (xy 129.531377 -56.903299)
			(xy 129.567068 -56.862108) (xy 129.608259 -56.826417) (xy 129.654109 -56.796951) (xy 129.703686 -56.774309)
			(xy 129.755981 -56.758954) (xy 129.809929 -56.751198) (xy 129.864431 -56.751198) (xy 129.918379 -56.758954)
			(xy 129.970674 -56.774309) (xy 130.020251 -56.796951) (xy 130.066101 -56.826417) (xy 130.107292 -56.862108)
			(xy 130.142983 -56.903299) (xy 130.172449 -56.949149) (xy 130.195091 -56.998726) (xy 130.210446 -57.051021)
			(xy 130.218202 -57.104969) (xy 130.218688 -57.13222) (xy 130.218194 -57.160489) (xy 130.209859 -57.216409)
			(xy 130.19336 -57.270487) (xy 130.169059 -57.321536) (xy 130.137489 -57.368438) (xy 130.09934 -57.410166)
			(xy 130.077718 -57.428384) (xy 130.069297 -57.435986) (xy 130.059531 -57.456427) (xy 130.058922 -57.467754)
			(xy 130.058922 -57.546494) (xy 130.059578 -57.557811) (xy 130.069325 -57.578245) (xy 130.077718 -57.585864)
			(xy 130.09932 -57.604102) (xy 130.137455 -57.645835) (xy 130.169018 -57.692736) (xy 130.193317 -57.74378)
			(xy 130.209822 -57.797849) (xy 130.218171 -57.853762) (xy 130.218688 -57.882028) (xy 130.218202 -57.909279)
			(xy 130.210446 -57.963227) (xy 130.195091 -58.015522) (xy 130.172449 -58.065099) (xy 130.142983 -58.110949)
			(xy 130.107292 -58.15214) (xy 130.066101 -58.187831) (xy 130.020251 -58.217297) (xy 129.970674 -58.239939)
			(xy 129.918379 -58.255294) (xy 129.864431 -58.26305) (xy 129.809929 -58.26305) (xy 129.755981 -58.255294)
			(xy 129.703686 -58.239939) (xy 129.654109 -58.217297) (xy 129.608259 -58.187831) (xy 129.567068 -58.15214)
			(xy 129.531377 -58.110949) (xy 129.501911 -58.065099) (xy 129.479269 -58.015522) (xy 129.463914 -57.963227)
			(xy 129.456158 -57.909279) (xy 129.455672 -57.882028) (xy 127.434589 -57.882028) (xy 127.434108 -57.909025)
			(xy 127.426352 -57.962973) (xy 127.410997 -58.015268) (xy 127.388355 -58.064845) (xy 127.358889 -58.110695)
			(xy 127.323198 -58.151886) (xy 127.282007 -58.187577) (xy 127.236157 -58.217043) (xy 127.18658 -58.239685)
			(xy 127.134285 -58.25504) (xy 127.080337 -58.262796) (xy 127.025835 -58.262796) (xy 126.971887 -58.25504)
			(xy 126.919592 -58.239685) (xy 126.870015 -58.217043) (xy 126.824165 -58.187577) (xy 126.782974 -58.151886)
			(xy 126.747283 -58.110695) (xy 126.717817 -58.064845) (xy 126.695175 -58.015268) (xy 126.67982 -57.962973)
			(xy 126.672064 -57.909025) (xy 126.671578 -57.881774) (xy 126.672034 -57.85465) (xy 126.679715 -57.800949)
			(xy 126.694933 -57.74888) (xy 126.71738 -57.699494) (xy 126.746602 -57.65379) (xy 126.78201 -57.612692)
			(xy 126.802134 -57.5945) (xy 126.810262 -57.587388) (xy 126.819152 -57.568084) (xy 126.821184 -57.471564)
			(xy 126.813056 -57.451752) (xy 126.805182 -57.444386) (xy 126.786846 -57.426288) (xy 126.754671 -57.386052)
			(xy 126.728199 -57.341854) (xy 126.707911 -57.294498) (xy 126.694176 -57.244844) (xy 126.687243 -57.193793)
			(xy 126.686818 -57.168034) (xy 126.68733 -57.138802) (xy 126.696265 -57.081025) (xy 126.71393 -57.025294)
			(xy 126.726442 -56.99887) (xy 126.731014 -56.989726) (xy 126.732284 -56.96966) (xy 126.70155 -56.881522)
			(xy 126.688088 -56.866536) (xy 126.678944 -56.862218) (xy 126.654843 -56.85026) (xy 126.609963 -56.820587)
			(xy 126.569697 -56.784905) (xy 126.534842 -56.743921) (xy 126.506089 -56.698447) (xy 126.484008 -56.649385)
			(xy 126.469038 -56.597708) (xy 126.461475 -56.544441) (xy 126.461012 -56.51754) (xy 125.760249 -56.51754)
			(xy 125.734857 -56.538671) (xy 125.687251 -56.567725) (xy 125.635922 -56.589537) (xy 125.581965 -56.603643)
			(xy 125.526528 -56.609743) (xy 125.470794 -56.607706) (xy 125.415951 -56.597576) (xy 125.363167 -56.579569)
			(xy 125.313567 -56.554068) (xy 125.268209 -56.521617) (xy 125.22806 -56.482908) (xy 125.193974 -56.438765)
			(xy 125.166678 -56.39013) (xy 125.146755 -56.338039) (xy 125.134629 -56.283602) (xy 125.130558 -56.22798)
			(xy 124.8156 -56.22798) (xy 124.8156 -56.91505) (xy 124.81609 -56.924495) (xy 124.822995 -56.942085)
			(xy 124.829062 -56.94934) (xy 124.881894 -57.006998) (xy 124.898912 -57.01538) (xy 124.90831 -57.016396)
			(xy 124.936478 -57.019361) (xy 124.991558 -57.032552) (xy 125.044082 -57.053743) (xy 125.092895 -57.082468)
			(xy 125.136924 -57.118095) (xy 125.175201 -57.159841) (xy 125.206884 -57.206788) (xy 125.231277 -57.257903)
			(xy 125.247843 -57.312064) (xy 125.256219 -57.368079) (xy 125.256219 -57.424717) (xy 125.247844 -57.480732)
			(xy 125.231279 -57.534893) (xy 125.206886 -57.586009) (xy 125.175203 -57.632957) (xy 125.136927 -57.674703)
			(xy 125.092898 -57.71033) (xy 125.044085 -57.739055) (xy 124.991561 -57.760247) (xy 124.936481 -57.773438)
			(xy 124.90831 -57.776364) (xy 124.898912 -57.77738) (xy 124.881894 -57.785762) (xy 124.829062 -57.84342)
			(xy 124.822913 -57.850625) (xy 124.815999 -57.868246) (xy 124.8156 -57.87771) (xy 124.8156 -58.699146)
			(xy 124.816068 -58.70939) (xy 124.824063 -58.728256) (xy 124.831094 -58.735722) (xy 124.890784 -58.793634)
			(xy 124.910088 -58.801) (xy 124.920248 -58.800746) (xy 124.932186 -58.800492) (xy 124.95944 -58.800954)
			(xy 125.013392 -58.80871) (xy 125.065691 -58.824065) (xy 125.115273 -58.846706) (xy 125.161128 -58.876174)
			(xy 125.202323 -58.911868) (xy 125.238018 -58.953061) (xy 125.267487 -58.998914) (xy 125.290131 -59.048495)
			(xy 125.305487 -59.100794) (xy 125.313245 -59.154747) (xy 125.313245 -59.182) (xy 126.671068 -59.182)
			(xy 126.675139 -59.126378) (xy 126.687265 -59.071941) (xy 126.707188 -59.01985) (xy 126.734484 -58.971215)
			(xy 126.76857 -58.927072) (xy 126.808719 -58.888363) (xy 126.854077 -58.855912) (xy 126.903677 -58.830411)
			(xy 126.956461 -58.812404) (xy 127.011304 -58.802274) (xy 127.067038 -58.800237) (xy 127.122475 -58.806337)
			(xy 127.176432 -58.820443) (xy 127.227761 -58.842255) (xy 127.275367 -58.871309) (xy 127.318235 -58.906984)
			(xy 127.355452 -58.948521) (xy 127.386225 -58.995034) (xy 127.409897 -59.045531) (xy 127.425965 -59.098938)
			(xy 127.434085 -59.154114) (xy 127.434594 -59.182) (xy 127.434085 -59.209886) (xy 127.425965 -59.265062)
			(xy 127.409897 -59.318469) (xy 127.386225 -59.368966) (xy 127.355452 -59.415479) (xy 127.318235 -59.457016)
			(xy 127.275367 -59.492691) (xy 127.227761 -59.521745) (xy 127.176432 -59.543557) (xy 127.122475 -59.557663)
			(xy 127.067038 -59.563763) (xy 127.011304 -59.561726) (xy 126.956461 -59.551596) (xy 126.903677 -59.533589)
			(xy 126.854077 -59.508088) (xy 126.808719 -59.475637) (xy 126.76857 -59.436928) (xy 126.734484 -59.392785)
			(xy 126.707188 -59.34415) (xy 126.687265 -59.292059) (xy 126.675139 -59.237622) (xy 126.671068 -59.182)
			(xy 125.313245 -59.182) (xy 125.313245 -59.209253) (xy 125.305487 -59.263206) (xy 125.290131 -59.315505)
			(xy 125.267487 -59.365086) (xy 125.238018 -59.410939) (xy 125.202323 -59.452132) (xy 125.161128 -59.487826)
			(xy 125.115273 -59.517294) (xy 125.065691 -59.539935) (xy 125.013392 -59.55529) (xy 124.95944 -59.563046)
			(xy 124.932186 -59.563508) (xy 124.920248 -59.563254) (xy 124.910088 -59.563) (xy 124.890784 -59.570366)
			(xy 124.831094 -59.628278) (xy 124.824043 -59.63573) (xy 124.816055 -59.654605) (xy 124.8156 -59.664854)
			(xy 124.8156 -59.902344) (xy 124.816082 -59.912308) (xy 124.823664 -59.930738) (xy 124.830332 -59.938158)
			(xy 124.851668 -59.959494) (xy 124.885196 -59.97448) (xy 124.917409 -59.976541) (xy 124.980971 -59.987795)
			(xy 125.042597 -60.007001) (xy 125.101298 -60.033851) (xy 125.156131 -60.067911) (xy 125.206213 -60.108636)
			(xy 125.250739 -60.155371) (xy 125.288995 -60.207363) (xy 125.320364 -60.263779) (xy 125.344343 -60.323709)
			(xy 125.360547 -60.386193) (xy 125.368714 -60.450224) (xy 125.368715 -60.509434) (xy 126.672068 -60.509434)
			(xy 126.672071 -60.45493) (xy 126.67983 -60.400981) (xy 126.695188 -60.348686) (xy 126.717832 -60.299108)
			(xy 126.747302 -60.253258) (xy 126.782997 -60.212068) (xy 126.82419 -60.176378) (xy 126.870043 -60.146913)
			(xy 126.919623 -60.124274) (xy 126.97192 -60.108921) (xy 127.02587 -60.101168) (xy 127.080374 -60.101171)
			(xy 127.134323 -60.108931) (xy 127.186618 -60.124289) (xy 127.236195 -60.146934) (xy 127.282045 -60.176404)
			(xy 127.323235 -60.212099) (xy 127.358925 -60.253293) (xy 127.388389 -60.299147) (xy 127.411027 -60.348727)
			(xy 127.426379 -60.401024) (xy 127.434133 -60.454974) (xy 127.434594 -60.482226) (xy 127.434146 -60.509455)
			(xy 127.426403 -60.563358) (xy 127.411079 -60.615615) (xy 127.388483 -60.665163) (xy 127.359076 -60.710997)
			(xy 127.34163 -60.731908) (xy 127.364919 -60.726338) (xy 127.412429 -60.720345) (xy 127.436372 -60.71997)
			(xy 127.463643 -60.720394) (xy 127.517631 -60.728153) (xy 127.569966 -60.743515) (xy 127.619581 -60.766169)
			(xy 127.665467 -60.795654) (xy 127.706691 -60.831369) (xy 127.742412 -60.872587) (xy 127.771903 -60.918468)
			(xy 127.794565 -60.96808) (xy 127.809935 -61.020413) (xy 127.817701 -61.074399) (xy 127.817706 -61.128942)
			(xy 127.809948 -61.18293) (xy 127.794585 -61.235264) (xy 127.771931 -61.28488) (xy 127.742447 -61.330766)
			(xy 127.706732 -61.37199) (xy 127.665515 -61.407711) (xy 127.619633 -61.437202) (xy 127.570021 -61.459864)
			(xy 127.517689 -61.475235) (xy 127.463702 -61.483001) (xy 127.409159 -61.483006) (xy 127.355171 -61.475248)
			(xy 127.302837 -61.459886) (xy 127.253221 -61.437232) (xy 127.207335 -61.407748) (xy 127.166111 -61.372033)
			(xy 127.13039 -61.330816) (xy 127.100898 -61.284934) (xy 127.078236 -61.235322) (xy 127.062866 -61.18299)
			(xy 127.055099 -61.129003) (xy 127.05461 -61.101732) (xy 127.055109 -61.074471) (xy 127.062873 -61.020504)
			(xy 127.078234 -60.968191) (xy 127.100879 -60.918593) (xy 127.130348 -60.872721) (xy 127.147828 -60.851796)
			(xy 127.124538 -60.857365) (xy 127.077029 -60.863357) (xy 127.053086 -60.863734) (xy 127.025834 -60.86323)
			(xy 126.971885 -60.855471) (xy 126.919589 -60.840113) (xy 126.870012 -60.81747) (xy 126.824161 -60.788001)
			(xy 126.782971 -60.752306) (xy 126.74728 -60.711113) (xy 126.717815 -60.66526) (xy 126.695175 -60.615681)
			(xy 126.679822 -60.563384) (xy 126.672068 -60.509434) (xy 125.368715 -60.509434) (xy 125.368715 -60.514774)
			(xy 125.360547 -60.578805) (xy 125.344344 -60.641289) (xy 125.320365 -60.70122) (xy 125.288996 -60.757635)
			(xy 125.25074 -60.809628) (xy 125.206214 -60.856362) (xy 125.156132 -60.897088) (xy 125.1013 -60.931149)
			(xy 125.042599 -60.957998) (xy 124.980972 -60.977205) (xy 124.917411 -60.988459) (xy 124.885196 -60.99048)
			(xy 124.851668 -61.005466) (xy 124.830332 -61.026802) (xy 124.823645 -61.03421) (xy 124.816059 -61.052647)
			(xy 124.8156 -61.062616) (xy 124.8156 -61.329824) (xy 124.816079 -61.33979) (xy 124.823656 -61.358225)
			(xy 124.830332 -61.365638) (xy 124.851668 -61.387228) (xy 124.884688 -61.402214) (xy 124.912008 -61.404417)
			(xy 124.965651 -61.415669) (xy 125.017131 -61.43448) (xy 125.06539 -61.460464) (xy 125.109434 -61.493087)
			(xy 125.148357 -61.531675) (xy 125.181358 -61.575437) (xy 125.207757 -61.62347) (xy 125.227012 -61.674786)
			(xy 125.238726 -61.728329) (xy 125.241431 -61.765942) (xy 126.648208 -61.765942) (xy 126.652279 -61.71032)
			(xy 126.664405 -61.655883) (xy 126.684328 -61.603792) (xy 126.711624 -61.555157) (xy 126.74571 -61.511014)
			(xy 126.785859 -61.472305) (xy 126.831217 -61.439854) (xy 126.880817 -61.414353) (xy 126.933601 -61.396346)
			(xy 126.988444 -61.386216) (xy 127.044178 -61.384179) (xy 127.099615 -61.390279) (xy 127.153572 -61.404385)
			(xy 127.204901 -61.426197) (xy 127.252507 -61.455251) (xy 127.295375 -61.490926) (xy 127.332592 -61.532463)
			(xy 127.363365 -61.578976) (xy 127.387037 -61.629473) (xy 127.403105 -61.68288) (xy 127.411225 -61.738056)
			(xy 127.411734 -61.765942) (xy 127.411225 -61.793828) (xy 127.403105 -61.849004) (xy 127.387037 -61.902411)
			(xy 127.363365 -61.952908) (xy 127.332592 -61.999421) (xy 127.295375 -62.040958) (xy 127.252507 -62.076633)
			(xy 127.204901 -62.105687) (xy 127.153572 -62.127499) (xy 127.099615 -62.141605) (xy 127.044178 -62.147705)
			(xy 126.988444 -62.145668) (xy 126.933601 -62.135538) (xy 126.880817 -62.117531) (xy 126.831217 -62.09203)
			(xy 126.785859 -62.059579) (xy 126.74571 -62.02087) (xy 126.711624 -61.976727) (xy 126.684328 -61.928092)
			(xy 126.664405 -61.876001) (xy 126.652279 -61.821564) (xy 126.648208 -61.765942) (xy 125.241431 -61.765942)
			(xy 125.242658 -61.782997) (xy 125.238727 -61.837666) (xy 125.227013 -61.891209) (xy 125.207759 -61.942526)
			(xy 125.18136 -61.990559) (xy 125.14836 -62.034321) (xy 125.109438 -62.07291) (xy 125.065394 -62.105533)
			(xy 125.017135 -62.131518) (xy 124.965655 -62.15033) (xy 124.912013 -62.161582) (xy 124.884688 -62.163706)
			(xy 124.851668 -62.178692) (xy 124.830332 -62.200282) (xy 124.823641 -62.207689) (xy 124.816048 -62.226126)
			(xy 124.8156 -62.236096) (xy 124.8156 -64.164718) (xy 124.816027 -64.174787) (xy 124.823746 -64.193386)
			(xy 124.830586 -64.200786) (xy 130.261614 -69.631814) (xy 130.268468 -69.639209) (xy 130.27621 -69.657808)
			(xy 130.2766 -69.667882) (xy 130.2766 -81.28) (xy 130.277088 -81.290008) (xy 130.284748 -81.308499)
			(xy 130.298901 -81.322652) (xy 130.317392 -81.330312) (xy 130.3274 -81.3308)
		)
		(stroke
			(width 0)
			(type solid)
		)
		(fill yes)
		(layer "In11.Cu")
		(net "P1V2_AUX")
	)
	(gr_poly
		(pts
			(xy 201.766932 -399.318988) (xy 201.776999 -399.318559) (xy 201.795594 -399.310835) (xy 201.803 -399.304002)
			(xy 203.3778 -397.729202) (xy 203.385198 -397.722355) (xy 203.403796 -397.71462) (xy 203.413868 -397.714216)
			(xy 206.779876 -397.714216) (xy 206.78994 -397.714653) (xy 206.808523 -397.722389) (xy 206.815944 -397.729202)
			(xy 208.390744 -399.304002) (xy 208.398145 -399.310841) (xy 208.416743 -399.318559) (xy 208.426812 -399.318988)
			(xy 212.484462 -399.318988) (xy 212.494527 -399.318553) (xy 212.513114 -399.310822) (xy 212.52053 -399.304002)
			(xy 213.827868 -397.996664) (xy 213.835267 -397.989821) (xy 213.853866 -397.982101) (xy 213.863936 -397.981678)
			(xy 217.608912 -397.981678) (xy 217.618982 -397.982103) (xy 217.637585 -397.989818) (xy 217.64498 -397.996664)
			(xy 218.952318 -399.304002) (xy 218.959718 -399.310845) (xy 218.978316 -399.318573) (xy 218.988386 -399.318988)
			(xy 223.134936 -399.318988) (xy 223.145003 -399.318558) (xy 223.163597 -399.310833) (xy 223.171004 -399.304002)
			(xy 224.45599 -398.019016) (xy 224.463387 -398.012166) (xy 224.481985 -398.004425) (xy 224.492058 -398.00403)
			(xy 228.370892 -398.00403) (xy 228.380962 -398.004452) (xy 228.399566 -398.012168) (xy 228.40696 -398.019016)
			(xy 229.691946 -399.304002) (xy 229.699347 -399.310841) (xy 229.717945 -399.318558) (xy 229.728014 -399.318988)
			(xy 234.185968 -399.318988) (xy 234.196032 -399.318552) (xy 234.214618 -399.310819) (xy 234.222036 -399.304002)
			(xy 238.249206 -395.276832) (xy 238.256041 -395.26943) (xy 238.26375 -395.250831) (xy 238.264192 -395.240764)
			(xy 238.264192 -385.3942) (xy 238.263938 -385.390136) (xy 238.261652 -385.358894) (xy 238.261398 -385.35483)
			(xy 238.261398 -382.974088) (xy 238.261823 -382.964019) (xy 238.269541 -382.945417) (xy 238.276384 -382.93802)
			(xy 238.285274 -382.92913) (xy 238.292675 -382.922292) (xy 238.311274 -382.91458) (xy 238.321342 -382.914144)
			(xy 278.057864 -382.914144) (xy 278.067928 -382.913708) (xy 278.08651 -382.905971) (xy 278.093932 -382.899158)
			(xy 278.196294 -382.796796) (xy 278.20314 -382.789397) (xy 278.210874 -382.7708) (xy 278.21128 -382.760728)
			(xy 278.21128 -382.71704) (xy 278.211373 -382.712021) (xy 278.213294 -382.70217) (xy 278.21509 -382.697482)
			(xy 278.222456 -382.68021) (xy 278.224257 -382.675524) (xy 278.226178 -382.665671) (xy 278.226266 -382.660652)
			(xy 278.226266 -376.656854) (xy 278.225834 -376.646788) (xy 278.218104 -376.628199) (xy 278.21128 -376.620786)
			(xy 277.528274 -375.93778) (xy 277.520878 -375.930929) (xy 277.502279 -375.923191) (xy 277.492206 -375.922794)
			(xy 230.240586 -375.922794) (xy 230.230517 -375.922368) (xy 230.211917 -375.914649) (xy 230.204518 -375.907808)
			(xy 230.19004 -375.89333) (xy 230.18264 -375.88649) (xy 230.164041 -375.878773) (xy 230.153972 -375.878344)
			(xy 225.87331 -375.878344) (xy 225.86324 -375.878767) (xy 225.844637 -375.886483) (xy 225.837242 -375.89333)
			(xy 221.990412 -379.74016) (xy 221.983016 -379.747013) (xy 221.964418 -379.754758) (xy 221.954344 -379.755146)
			(xy 211.036916 -379.755146) (xy 211.026854 -379.755586) (xy 211.008276 -379.763327) (xy 211.000848 -379.770132)
			(xy 210.37042 -380.40056) (xy 210.363054 -380.416054) (xy 210.362038 -380.424944) (xy 210.356667 -380.471221)
			(xy 210.337509 -380.562397) (xy 210.308937 -380.651076) (xy 210.290664 -380.69393) (xy 210.286846 -380.70387)
			(xy 210.286847 -380.725137) (xy 210.290664 -380.735078) (xy 210.308902 -380.777743) (xy 210.337442 -380.866036)
			(xy 210.356638 -380.95682) (xy 210.366283 -381.049108) (xy 210.366864 -381.095504) (xy 210.366352 -381.138362)
			(xy 210.358109 -381.223681) (xy 210.342093 -381.3058) (xy 242.544088 -381.3058) (xy 242.548118 -381.221198)
			(xy 242.560172 -381.137363) (xy 242.58014 -381.055053) (xy 242.607842 -380.975014) (xy 242.643027 -380.897971)
			(xy 242.685376 -380.824621) (xy 242.734505 -380.755628) (xy 242.789971 -380.691619) (xy 242.851269 -380.633171)
			(xy 242.917846 -380.580815) (xy 242.989099 -380.535024) (xy 243.064381 -380.496214) (xy 243.143012 -380.464736)
			(xy 243.224278 -380.440874) (xy 243.307445 -380.424846) (xy 243.391759 -380.416796) (xy 243.434108 -380.416308)
			(xy 243.474162 -380.41672) (xy 243.553944 -380.423932) (xy 243.632755 -380.438288) (xy 243.709956 -380.459672)
			(xy 243.784921 -380.48791) (xy 243.857045 -380.522773) (xy 243.925741 -380.56398) (xy 243.990455 -380.611197)
			(xy 244.020848 -380.637288) (xy 244.027964 -380.642979) (xy 244.045018 -380.649358) (xy 244.054122 -380.649734)
			(xy 244.084094 -380.649734) (xy 244.093196 -380.64935) (xy 244.110247 -380.64297) (xy 244.117368 -380.637288)
			(xy 244.147764 -380.611201) (xy 244.212475 -380.563983) (xy 244.281171 -380.522776) (xy 244.353294 -380.487914)
			(xy 244.42826 -380.459679) (xy 244.505461 -380.4383) (xy 244.584272 -380.423951) (xy 244.664055 -380.416748)
			(xy 244.704108 -380.416308) (xy 244.746457 -380.41678) (xy 244.830771 -380.424832) (xy 244.913939 -380.440862)
			(xy 244.995206 -380.464724) (xy 245.073836 -380.496204) (xy 245.149119 -380.535015) (xy 245.220371 -380.580807)
			(xy 245.286948 -380.633164) (xy 245.348247 -380.691613) (xy 245.403712 -380.755624) (xy 245.452841 -380.824617)
			(xy 245.49519 -380.897967) (xy 245.530375 -380.975012) (xy 245.558077 -381.055051) (xy 245.578045 -381.137362)
			(xy 245.590098 -381.221198) (xy 245.594129 -381.3058) (xy 248.479103 -381.3058) (xy 248.483133 -381.221202)
			(xy 248.495186 -381.13737) (xy 248.515153 -381.055064) (xy 248.542853 -380.975028) (xy 248.578036 -380.897988)
			(xy 248.620382 -380.82464) (xy 248.669508 -380.75565) (xy 248.72497 -380.691642) (xy 248.786265 -380.633196)
			(xy 248.852838 -380.58084) (xy 248.924086 -380.53505) (xy 248.999364 -380.496239) (xy 249.07799 -380.46476)
			(xy 249.159252 -380.440897) (xy 249.242415 -380.424866) (xy 249.326725 -380.416813) (xy 249.369072 -380.416308)
			(xy 249.409125 -380.416742) (xy 249.488907 -380.423951) (xy 249.567717 -380.438304) (xy 249.644918 -380.459684)
			(xy 249.719884 -380.487919) (xy 249.792007 -380.52278) (xy 249.860704 -380.563984) (xy 249.925418 -380.611198)
			(xy 249.955812 -380.637288) (xy 249.962939 -380.642963) (xy 249.979984 -380.649352) (xy 249.989086 -380.649734)
			(xy 250.019058 -380.649734) (xy 250.028158 -380.649333) (xy 250.045209 -380.642965) (xy 250.052332 -380.637288)
			(xy 250.082702 -380.61117) (xy 250.147418 -380.563954) (xy 250.216118 -380.522751) (xy 250.288245 -380.487892)
			(xy 250.363214 -380.459661) (xy 250.440419 -380.438287) (xy 250.519233 -380.423943) (xy 250.599018 -380.416745)
			(xy 250.639072 -380.416308) (xy 250.681423 -380.416763) (xy 250.765741 -380.424812) (xy 250.848913 -380.440839)
			(xy 250.930184 -380.4647) (xy 251.008819 -380.496179) (xy 251.084106 -380.53499) (xy 251.155362 -380.580782)
			(xy 251.221943 -380.63314) (xy 251.283246 -380.691589) (xy 251.338714 -380.755602) (xy 251.387847 -380.824597)
			(xy 251.430199 -380.897951) (xy 251.465386 -380.974998) (xy 251.49309 -381.055041) (xy 251.513059 -381.137355)
			(xy 251.525114 -381.221194) (xy 251.529144 -381.3058) (xy 254.413988 -381.3058) (xy 254.418018 -381.221197)
			(xy 254.430073 -381.13736) (xy 254.450042 -381.055048) (xy 254.477745 -380.975008) (xy 254.512931 -380.897963)
			(xy 254.555281 -380.824612) (xy 254.604413 -380.755619) (xy 254.65988 -380.691609) (xy 254.721181 -380.633161)
			(xy 254.78776 -380.580805) (xy 254.859015 -380.535015) (xy 254.934299 -380.496206) (xy 255.012932 -380.464729)
			(xy 255.094201 -380.440869) (xy 255.17737 -380.424842) (xy 255.261686 -380.416794) (xy 255.304036 -380.416308)
			(xy 255.344089 -380.416764) (xy 255.42387 -380.42397) (xy 255.502679 -380.43832) (xy 255.57988 -380.459697)
			(xy 255.654846 -380.487929) (xy 255.726969 -380.522787) (xy 255.795667 -380.563988) (xy 255.860382 -380.6112)
			(xy 255.890776 -380.637288) (xy 255.897884 -380.64299) (xy 255.914944 -380.649363) (xy 255.92405 -380.649734)
			(xy 255.954022 -380.649734) (xy 255.963125 -380.649364) (xy 255.980176 -380.642974) (xy 255.987296 -380.637288)
			(xy 256.017681 -380.611187) (xy 256.082394 -380.56397) (xy 256.151091 -380.522765) (xy 256.223216 -380.487904)
			(xy 256.298184 -380.459671) (xy 256.375386 -380.438295) (xy 256.454199 -380.423948) (xy 256.533982 -380.416747)
			(xy 256.574036 -380.416308) (xy 256.616384 -380.416781) (xy 256.700697 -380.424835) (xy 256.783862 -380.440867)
			(xy 256.865127 -380.464732) (xy 256.943755 -380.496212) (xy 257.019035 -380.535025) (xy 257.090285 -380.580817)
			(xy 257.15686 -380.633174) (xy 257.218156 -380.691623) (xy 257.273619 -380.755633) (xy 257.322747 -380.824625)
			(xy 257.365094 -380.897975) (xy 257.400277 -380.975018) (xy 257.427978 -381.055056) (xy 257.447945 -381.137365)
			(xy 257.459999 -381.2212) (xy 257.464029 -381.3058) (xy 260.349004 -381.3058) (xy 260.353033 -381.2212)
			(xy 260.365087 -381.137367) (xy 260.385055 -381.055059) (xy 260.412756 -380.975022) (xy 260.44794 -380.89798)
			(xy 260.490287 -380.824632) (xy 260.539415 -380.755641) (xy 260.594879 -380.691632) (xy 260.656176 -380.633186)
			(xy 260.722751 -380.58083) (xy 260.794002 -380.53504) (xy 260.869282 -380.496231) (xy 260.947911 -380.464753)
			(xy 261.029175 -380.440891) (xy 261.11234 -380.424862) (xy 261.196652 -380.416812) (xy 261.239 -380.416308)
			(xy 261.279054 -380.416725) (xy 261.358836 -380.423936) (xy 261.437646 -380.438292) (xy 261.514847 -380.459674)
			(xy 261.589813 -380.487912) (xy 261.661936 -380.522775) (xy 261.730633 -380.563981) (xy 261.795346 -380.611197)
			(xy 261.82574 -380.637288) (xy 261.832859 -380.642975) (xy 261.84991 -380.649357) (xy 261.859014 -380.649734)
			(xy 261.888986 -380.649734) (xy 261.898088 -380.649346) (xy 261.915138 -380.642969) (xy 261.92226 -380.637288)
			(xy 261.952659 -380.611204) (xy 262.01737 -380.563986) (xy 262.086065 -380.522779) (xy 262.158188 -380.487916)
			(xy 262.233153 -380.459681) (xy 262.310354 -380.438302) (xy 262.389165 -380.423952) (xy 262.468947 -380.416748)
			(xy 262.509 -380.416308) (xy 262.551349 -380.41678) (xy 262.635664 -380.424831) (xy 262.718832 -380.44086)
			(xy 262.8001 -380.464722) (xy 262.878731 -380.496202) (xy 262.954014 -380.535013) (xy 263.025267 -380.580804)
			(xy 263.091845 -380.633161) (xy 263.153144 -380.69161) (xy 263.20861 -380.755621) (xy 263.25774 -380.824614)
			(xy 263.300089 -380.897965) (xy 263.335274 -380.97501) (xy 263.362976 -381.05505) (xy 263.382945 -381.137361)
			(xy 263.394998 -381.221197) (xy 263.399029 -381.3058) (xy 266.284003 -381.3058) (xy 266.288033 -381.221203)
			(xy 266.300086 -381.137371) (xy 266.320053 -381.055065) (xy 266.347753 -380.97503) (xy 266.382935 -380.89799)
			(xy 266.42528 -380.824643) (xy 266.474406 -380.755653) (xy 266.529867 -380.691645) (xy 266.591161 -380.633198)
			(xy 266.657734 -380.580843) (xy 266.728981 -380.535052) (xy 266.804258 -380.496242) (xy 266.882884 -380.464762)
			(xy 266.964146 -380.440898) (xy 267.047308 -380.424867) (xy 267.131617 -380.416813) (xy 267.173964 -380.416308)
			(xy 267.214017 -380.416747) (xy 267.293799 -380.423955) (xy 267.372609 -380.438307) (xy 267.449809 -380.459687)
			(xy 267.524775 -380.487921) (xy 267.596899 -380.522782) (xy 267.665596 -380.563985) (xy 267.73031 -380.611199)
			(xy 267.760704 -380.637288) (xy 267.767804 -380.643002) (xy 267.78487 -380.649368) (xy 267.793978 -380.649734)
			(xy 267.82395 -380.649734) (xy 267.83305 -380.649329) (xy 267.850101 -380.642964) (xy 267.857224 -380.637288)
			(xy 267.887598 -380.611174) (xy 267.952313 -380.563958) (xy 268.021012 -380.522754) (xy 268.093138 -380.487895)
			(xy 268.168107 -380.459664) (xy 268.245312 -380.438289) (xy 268.324125 -380.423944) (xy 268.40391 -380.416746)
			(xy 268.443964 -380.416308) (xy 268.486315 -380.416762) (xy 268.570634 -380.424811) (xy 268.653806 -380.440838)
			(xy 268.735078 -380.464698) (xy 268.813714 -380.496177) (xy 268.889001 -380.534987) (xy 268.960258 -380.580779)
			(xy 269.02684 -380.633137) (xy 269.088143 -380.691587) (xy 269.143612 -380.755599) (xy 269.192746 -380.824595)
			(xy 269.235098 -380.897949) (xy 269.270285 -380.974996) (xy 269.297989 -381.055039) (xy 269.317959 -381.137354)
			(xy 269.330014 -381.221194) (xy 269.334044 -381.3058) (xy 272.218888 -381.3058) (xy 272.222918 -381.221197)
			(xy 272.234972 -381.137361) (xy 272.254941 -381.05505) (xy 272.282644 -380.97501) (xy 272.31783 -380.897965)
			(xy 272.36018 -380.824615) (xy 272.409311 -380.755622) (xy 272.464777 -380.691612) (xy 272.526078 -380.633164)
			(xy 272.592656 -380.580808) (xy 272.66391 -380.535018) (xy 272.739194 -380.496208) (xy 272.817826 -380.464731)
			(xy 272.899095 -380.44087) (xy 272.982263 -380.424843) (xy 273.066579 -380.416795) (xy 273.108928 -380.416308)
			(xy 273.148981 -380.416769) (xy 273.228761 -380.423974) (xy 273.307571 -380.438323) (xy 273.384772 -380.4597)
			(xy 273.459737 -380.487931) (xy 273.531861 -380.522788) (xy 273.600559 -380.563989) (xy 273.665274 -380.6112)
			(xy 273.695668 -380.637288) (xy 273.702779 -380.642987) (xy 273.719837 -380.649362) (xy 273.728942 -380.649734)
			(xy 273.758914 -380.649734) (xy 273.768017 -380.64936) (xy 273.785068 -380.642973) (xy 273.792188 -380.637288)
			(xy 273.822576 -380.611191) (xy 273.887289 -380.563974) (xy 273.955986 -380.522768) (xy 274.02811 -380.487907)
			(xy 274.103077 -380.459673) (xy 274.180279 -380.438296) (xy 274.259091 -380.423949) (xy 274.338874 -380.416747)
			(xy 274.378928 -380.416308) (xy 274.421276 -380.416781) (xy 274.505589 -380.424834) (xy 274.588755 -380.440866)
			(xy 274.670021 -380.46473) (xy 274.74865 -380.49621) (xy 274.82393 -380.535022) (xy 274.895181 -380.580814)
			(xy 274.961756 -380.633171) (xy 275.023053 -380.69162) (xy 275.078517 -380.75563) (xy 275.127645 -380.824623)
			(xy 275.169993 -380.897973) (xy 275.205176 -380.975016) (xy 275.232878 -381.055055) (xy 275.252845 -381.137364)
			(xy 275.264899 -381.221199) (xy 275.268929 -381.3058) (xy 275.264899 -381.390401) (xy 275.252845 -381.474236)
			(xy 275.232878 -381.556545) (xy 275.205176 -381.636584) (xy 275.169993 -381.713627) (xy 275.127645 -381.786977)
			(xy 275.078517 -381.85597) (xy 275.023053 -381.91998) (xy 274.961756 -381.978429) (xy 274.895181 -382.030786)
			(xy 274.82393 -382.076578) (xy 274.74865 -382.11539) (xy 274.670021 -382.14687) (xy 274.588755 -382.170734)
			(xy 274.505589 -382.186766) (xy 274.421276 -382.194819) (xy 274.378928 -382.195324) (xy 274.338875 -382.194882)
			(xy 274.259094 -382.187673) (xy 274.180284 -382.173321) (xy 274.103083 -382.151941) (xy 274.028118 -382.123707)
			(xy 273.955994 -382.088848) (xy 273.887297 -382.047645) (xy 273.822582 -382.000433) (xy 273.792188 -381.974344)
			(xy 273.785058 -381.968672) (xy 273.768015 -381.96228) (xy 273.758914 -381.961898) (xy 273.728942 -381.961898)
			(xy 273.719844 -381.962314) (xy 273.702793 -381.968673) (xy 273.695668 -381.974344) (xy 273.665302 -382.000468)
			(xy 273.600585 -382.047682) (xy 273.531885 -382.088884) (xy 273.459757 -382.123742) (xy 273.384787 -382.151972)
			(xy 273.307582 -382.173345) (xy 273.228767 -382.187689) (xy 273.148983 -382.194887) (xy 273.108928 -382.195324)
			(xy 273.066579 -382.194805) (xy 272.982263 -382.186757) (xy 272.899095 -382.17073) (xy 272.817826 -382.146869)
			(xy 272.739194 -382.115392) (xy 272.66391 -382.076582) (xy 272.592656 -382.030792) (xy 272.526078 -381.978436)
			(xy 272.464777 -381.919988) (xy 272.409311 -381.855978) (xy 272.36018 -381.786985) (xy 272.31783 -381.713635)
			(xy 272.282644 -381.63659) (xy 272.254941 -381.55655) (xy 272.234972 -381.474239) (xy 272.222918 -381.390403)
			(xy 272.218888 -381.3058) (xy 269.334044 -381.3058) (xy 269.330014 -381.390406) (xy 269.317959 -381.474246)
			(xy 269.297989 -381.556561) (xy 269.270285 -381.636604) (xy 269.235098 -381.713651) (xy 269.192746 -381.787005)
			(xy 269.143612 -381.856001) (xy 269.088143 -381.920013) (xy 269.02684 -381.978463) (xy 268.960258 -382.030821)
			(xy 268.889001 -382.076613) (xy 268.813714 -382.115423) (xy 268.735078 -382.146902) (xy 268.653806 -382.170762)
			(xy 268.570634 -382.186789) (xy 268.486315 -382.194838) (xy 268.443964 -382.195324) (xy 268.403911 -382.19486)
			(xy 268.324131 -382.187654) (xy 268.245322 -382.173305) (xy 268.168121 -382.151929) (xy 268.093156 -382.123698)
			(xy 268.021032 -382.088841) (xy 267.952334 -382.047641) (xy 267.887619 -382.000432) (xy 267.857224 -381.974344)
			(xy 267.850113 -381.968645) (xy 267.833056 -381.962269) (xy 267.82395 -381.961898) (xy 267.793978 -381.961898)
			(xy 267.784876 -381.962283) (xy 267.767826 -381.968664) (xy 267.760704 -381.974344) (xy 267.730324 -382.00045)
			(xy 267.665609 -382.047666) (xy 267.596911 -382.08887) (xy 267.524786 -382.12373) (xy 267.449817 -382.151962)
			(xy 267.372614 -382.173338) (xy 267.293802 -382.187684) (xy 267.214018 -382.194885) (xy 267.173964 -382.195324)
			(xy 267.131617 -382.194787) (xy 267.047308 -382.186733) (xy 266.964146 -382.170702) (xy 266.882884 -382.146838)
			(xy 266.804258 -382.115358) (xy 266.728981 -382.076548) (xy 266.657734 -382.030757) (xy 266.591161 -381.978402)
			(xy 266.529867 -381.919955) (xy 266.474406 -381.855947) (xy 266.42528 -381.786957) (xy 266.382935 -381.71361)
			(xy 266.347753 -381.63657) (xy 266.320053 -381.556535) (xy 266.300086 -381.474229) (xy 266.288033 -381.390397)
			(xy 266.284003 -381.3058) (xy 263.399029 -381.3058) (xy 263.394998 -381.390403) (xy 263.382945 -381.474239)
			(xy 263.362976 -381.55655) (xy 263.335274 -381.63659) (xy 263.300089 -381.713635) (xy 263.25774 -381.786986)
			(xy 263.20861 -381.855979) (xy 263.153144 -381.91999) (xy 263.091845 -381.978439) (xy 263.025267 -382.030796)
			(xy 262.954014 -382.076587) (xy 262.878731 -382.115398) (xy 262.8001 -382.146878) (xy 262.718832 -382.17074)
			(xy 262.635664 -382.186769) (xy 262.551349 -382.19482) (xy 262.509 -382.195324) (xy 262.468947 -382.194899)
			(xy 262.389165 -382.187688) (xy 262.310355 -382.173333) (xy 262.233154 -382.151951) (xy 262.158188 -382.123715)
			(xy 262.086065 -382.088853) (xy 262.017368 -382.047648) (xy 261.952654 -382.000434) (xy 261.92226 -381.974344)
			(xy 261.915138 -381.96866) (xy 261.898089 -381.962275) (xy 261.888986 -381.961898) (xy 261.859014 -381.961898)
			(xy 261.849914 -381.962301) (xy 261.832864 -381.968669) (xy 261.82574 -381.974344) (xy 261.795345 -382.000433)
			(xy 261.730633 -382.04765) (xy 261.661937 -382.088856) (xy 261.589814 -382.123718) (xy 261.514848 -382.151952)
			(xy 261.437647 -382.173331) (xy 261.358836 -382.18768) (xy 261.279053 -382.194884) (xy 261.239 -382.195324)
			(xy 261.196652 -382.194788) (xy 261.11234 -382.186738) (xy 261.029175 -382.170709) (xy 260.947911 -382.146847)
			(xy 260.869282 -382.115369) (xy 260.794002 -382.07656) (xy 260.722751 -382.03077) (xy 260.656176 -381.978414)
			(xy 260.594879 -381.919968) (xy 260.539415 -381.855959) (xy 260.490287 -381.786968) (xy 260.44794 -381.71362)
			(xy 260.412756 -381.636578) (xy 260.385055 -381.556541) (xy 260.365087 -381.474233) (xy 260.353033 -381.3904)
			(xy 260.349004 -381.3058) (xy 257.464029 -381.3058) (xy 257.459999 -381.3904) (xy 257.447945 -381.474235)
			(xy 257.427978 -381.556544) (xy 257.400277 -381.636582) (xy 257.365094 -381.713625) (xy 257.322747 -381.786975)
			(xy 257.273619 -381.855967) (xy 257.218156 -381.919977) (xy 257.15686 -381.978426) (xy 257.090285 -382.030783)
			(xy 257.019035 -382.076575) (xy 256.943755 -382.115388) (xy 256.865127 -382.146868) (xy 256.783862 -382.170733)
			(xy 256.700697 -382.186765) (xy 256.616384 -382.194819) (xy 256.574036 -382.195324) (xy 256.533983 -382.194877)
			(xy 256.454202 -382.187669) (xy 256.375392 -382.173318) (xy 256.298192 -382.151939) (xy 256.223226 -382.123705)
			(xy 256.151103 -382.088846) (xy 256.082405 -382.047644) (xy 256.01769 -382.000433) (xy 255.987296 -381.974344)
			(xy 255.980193 -381.968633) (xy 255.963129 -381.962264) (xy 255.954022 -381.961898) (xy 255.92405 -381.961898)
			(xy 255.914952 -381.962318) (xy 255.897902 -381.968675) (xy 255.890776 -381.974344) (xy 255.860407 -382.000464)
			(xy 255.795691 -382.047678) (xy 255.726991 -382.088881) (xy 255.654863 -382.123739) (xy 255.579894 -382.15197)
			(xy 255.502689 -382.173344) (xy 255.423875 -382.187688) (xy 255.34409 -382.194886) (xy 255.304036 -382.195324)
			(xy 255.261686 -382.194806) (xy 255.17737 -382.186758) (xy 255.094201 -382.170731) (xy 255.012932 -382.146871)
			(xy 254.934299 -382.115394) (xy 254.859015 -382.076585) (xy 254.78776 -382.030795) (xy 254.721181 -381.978439)
			(xy 254.65988 -381.919991) (xy 254.604413 -381.855981) (xy 254.555281 -381.786988) (xy 254.512931 -381.713637)
			(xy 254.477745 -381.636592) (xy 254.450042 -381.556552) (xy 254.430073 -381.47424) (xy 254.418018 -381.390403)
			(xy 254.413988 -381.3058) (xy 251.529144 -381.3058) (xy 251.525114 -381.390406) (xy 251.513059 -381.474245)
			(xy 251.49309 -381.556559) (xy 251.465386 -381.636602) (xy 251.430199 -381.713649) (xy 251.387847 -381.787003)
			(xy 251.338714 -381.855998) (xy 251.283246 -381.920011) (xy 251.221943 -381.97846) (xy 251.155362 -382.030818)
			(xy 251.084106 -382.07661) (xy 251.008819 -382.115421) (xy 250.930184 -382.1469) (xy 250.848913 -382.170761)
			(xy 250.765741 -382.186788) (xy 250.681423 -382.194837) (xy 250.639072 -382.195324) (xy 250.59902 -382.194855)
			(xy 250.519239 -382.18765) (xy 250.44043 -382.173302) (xy 250.36323 -382.151926) (xy 250.288264 -382.123696)
			(xy 250.21614 -382.08884) (xy 250.147442 -382.04764) (xy 250.082727 -382.000431) (xy 250.052332 -381.974344)
			(xy 250.045219 -381.968649) (xy 250.028163 -381.962271) (xy 250.019058 -381.961898) (xy 249.989086 -381.961898)
			(xy 249.979985 -381.962287) (xy 249.962935 -381.968665) (xy 249.955812 -381.974344) (xy 249.925429 -382.000446)
			(xy 249.860715 -382.047662) (xy 249.792017 -382.088867) (xy 249.719892 -382.123727) (xy 249.644924 -382.15196)
			(xy 249.567721 -382.173336) (xy 249.488909 -382.187683) (xy 249.409126 -382.194885) (xy 249.369072 -382.195324)
			(xy 249.326725 -382.194787) (xy 249.242415 -382.186734) (xy 249.159252 -382.170703) (xy 249.07799 -382.14684)
			(xy 248.999364 -382.115361) (xy 248.924086 -382.07655) (xy 248.852838 -382.03076) (xy 248.786265 -381.978404)
			(xy 248.72497 -381.919958) (xy 248.669508 -381.85595) (xy 248.620382 -381.78696) (xy 248.578036 -381.713612)
			(xy 248.542853 -381.636572) (xy 248.515153 -381.556536) (xy 248.495186 -381.47423) (xy 248.483133 -381.390398)
			(xy 248.479103 -381.3058) (xy 245.594129 -381.3058) (xy 245.590098 -381.390402) (xy 245.578045 -381.474238)
			(xy 245.558077 -381.556549) (xy 245.530375 -381.636588) (xy 245.49519 -381.713633) (xy 245.452841 -381.786983)
			(xy 245.403712 -381.855976) (xy 245.348247 -381.919987) (xy 245.286948 -381.978436) (xy 245.220371 -382.030793)
			(xy 245.149119 -382.076585) (xy 245.073836 -382.115396) (xy 244.995206 -382.146876) (xy 244.913939 -382.170738)
			(xy 244.830771 -382.186768) (xy 244.746457 -382.19482) (xy 244.704108 -382.195324) (xy 244.664055 -382.194894)
			(xy 244.584273 -382.187684) (xy 244.505463 -382.17333) (xy 244.428262 -382.151948) (xy 244.353297 -382.123713)
			(xy 244.281173 -382.088852) (xy 244.212476 -382.047647) (xy 244.147762 -382.000434) (xy 244.117368 -381.974344)
			(xy 244.110244 -381.968664) (xy 244.093196 -381.962277) (xy 244.084094 -381.961898) (xy 244.054122 -381.961898)
			(xy 244.045023 -381.962304) (xy 244.027972 -381.968671) (xy 244.020848 -381.974344) (xy 243.99045 -382.000429)
			(xy 243.925739 -382.047646) (xy 243.857043 -382.088853) (xy 243.78492 -382.123715) (xy 243.709955 -382.15195)
			(xy 243.632754 -382.173329) (xy 243.553943 -382.187679) (xy 243.474161 -382.194883) (xy 243.434108 -382.195324)
			(xy 243.391759 -382.194804) (xy 243.307445 -382.186754) (xy 243.224278 -382.170726) (xy 243.143012 -382.146864)
			(xy 243.064381 -382.115386) (xy 242.989099 -382.076576) (xy 242.917846 -382.030785) (xy 242.851269 -381.978429)
			(xy 242.789971 -381.919981) (xy 242.734505 -381.855972) (xy 242.685376 -381.786979) (xy 242.643027 -381.713629)
			(xy 242.607842 -381.636586) (xy 242.58014 -381.556547) (xy 242.560172 -381.474237) (xy 242.548118 -381.390402)
			(xy 242.544088 -381.3058) (xy 210.342093 -381.3058) (xy 210.341701 -381.307812) (xy 210.317278 -381.389976)
			(xy 210.285069 -381.46941) (xy 210.24537 -381.545379) (xy 210.19855 -381.617179) (xy 210.145043 -381.684144)
			(xy 210.085345 -381.745654) (xy 210.020009 -381.801138) (xy 209.985102 -381.826008) (xy 209.974688 -381.83312)
			(xy 209.963258 -381.854964) (xy 209.963258 -381.963676) (xy 209.974688 -381.98552) (xy 209.985102 -381.992632)
			(xy 210.019995 -382.017522) (xy 210.085333 -382.073002) (xy 210.145033 -382.134508) (xy 210.198541 -382.20147)
			(xy 210.245361 -382.273267) (xy 210.28506 -382.349235) (xy 210.31727 -382.428668) (xy 210.34169 -382.51083)
			(xy 210.358097 -382.594961) (xy 210.366336 -382.680279) (xy 210.366864 -382.723136) (xy 210.366277 -382.769532)
			(xy 210.35664 -382.861821) (xy 210.337443 -382.952604) (xy 210.308894 -383.040894) (xy 210.290664 -383.083562)
			(xy 210.286853 -383.093502) (xy 210.286866 -383.114763) (xy 210.290664 -383.12471) (xy 210.308901 -383.167375)
			(xy 210.337437 -383.255669) (xy 210.35663 -383.346452) (xy 210.366272 -383.438741) (xy 210.366864 -383.485136)
			(xy 210.366399 -383.52639) (xy 210.358762 -383.608545) (xy 210.343548 -383.689638) (xy 210.320887 -383.768974)
			(xy 210.290975 -383.845869) (xy 210.254068 -383.919663) (xy 210.210484 -383.989721) (xy 210.160598 -384.05544)
			(xy 210.104839 -384.116256) (xy 210.043686 -384.171645) (xy 209.977665 -384.221132) (xy 209.907344 -384.26429)
			(xy 209.870548 -384.28295) (xy 209.862237 -384.28751) (xy 209.849486 -384.301519) (xy 209.842679 -384.319197)
			(xy 209.842354 -384.32867) (xy 209.842354 -384.419602) (xy 209.842685 -384.429079) (xy 209.849468 -384.446774)
			(xy 209.862218 -384.460793) (xy 209.870548 -384.465322) (xy 209.907343 -384.48398) (xy 209.97765 -384.527153)
			(xy 210.043658 -384.57665) (xy 210.104799 -384.632046) (xy 210.16055 -384.692865) (xy 210.210429 -384.758584)
			(xy 210.25401 -384.82864) (xy 210.290917 -384.902429) (xy 210.320833 -384.979319) (xy 210.343503 -385.058648)
			(xy 210.35873 -385.139735) (xy 210.366384 -385.221884) (xy 210.366864 -385.263136) (xy 210.366277 -385.309532)
			(xy 210.35664 -385.401821) (xy 210.337443 -385.492604) (xy 210.308894 -385.580894) (xy 210.290664 -385.623562)
			(xy 210.286853 -385.633502) (xy 210.286866 -385.654763) (xy 210.290664 -385.66471) (xy 210.308901 -385.707375)
			(xy 210.337437 -385.795669) (xy 210.35663 -385.886452) (xy 210.366272 -385.978741) (xy 210.366864 -386.025136)
			(xy 210.366399 -386.06639) (xy 210.358762 -386.148545) (xy 210.343548 -386.229638) (xy 210.320887 -386.308974)
			(xy 210.290975 -386.385869) (xy 210.254068 -386.459663) (xy 210.247232 -386.470652) (xy 212.630512 -386.470652)
			(xy 212.631082 -386.4416) (xy 212.639874 -386.384165) (xy 212.657276 -386.328728) (xy 212.682887 -386.276573)
			(xy 212.716113 -386.228907) (xy 212.756186 -386.186832) (xy 212.778848 -386.168646) (xy 212.788246 -386.16128)
			(xy 212.79866 -386.14096) (xy 212.79993 -386.037582) (xy 212.790278 -386.017008) (xy 212.781134 -386.009388)
			(xy 212.75957 -385.991198) (xy 212.721564 -385.949506) (xy 212.690115 -385.902669) (xy 212.66591 -385.85171)
			(xy 212.649478 -385.797741) (xy 212.641176 -385.74194) (xy 212.640672 -385.713732) (xy 212.641185 -385.686481)
			(xy 212.648937 -385.632533) (xy 212.664288 -385.580237) (xy 212.686925 -385.530658) (xy 212.716388 -385.484806)
			(xy 212.752077 -385.443614) (xy 212.793264 -385.407919) (xy 212.839113 -385.37845) (xy 212.888688 -385.355806)
			(xy 212.940982 -385.340448) (xy 212.994929 -385.332689) (xy 213.02218 -385.332224) (xy 213.052195 -385.332809)
			(xy 213.111482 -385.342219) (xy 213.168566 -385.360794) (xy 213.222038 -385.388076) (xy 213.270579 -385.423393)
			(xy 213.292182 -385.444238) (xy 213.299294 -385.45135) (xy 213.317074 -385.45897) (xy 213.407752 -385.460494)
			(xy 213.425786 -385.453636) (xy 213.433152 -385.446778) (xy 213.454444 -385.427736) (xy 213.501644 -385.395567)
			(xy 213.553112 -385.370791) (xy 213.607696 -385.353961) (xy 213.66418 -385.345455) (xy 213.69274 -385.344924)
			(xy 213.719815 -385.345382) (xy 213.77342 -385.353036) (xy 213.825402 -385.368199) (xy 213.874716 -385.390566)
			(xy 213.920368 -385.419687) (xy 213.96144 -385.454975) (xy 213.997104 -385.49572) (xy 214.012272 -385.518152)
			(xy 214.01913 -385.528312) (xy 214.039704 -385.54025) (xy 214.145876 -385.5466) (xy 214.16772 -385.536948)
			(xy 214.175594 -385.52755) (xy 214.193806 -385.50636) (xy 214.23537 -385.469019) (xy 214.281936 -385.438141)
			(xy 214.332508 -385.414386) (xy 214.386005 -385.398262) (xy 214.441281 -385.390115) (xy 214.469218 -385.389628)
			(xy 214.499234 -385.390188) (xy 214.558522 -385.399603) (xy 214.615606 -385.418184) (xy 214.669078 -385.445472)
			(xy 214.717618 -385.480794) (xy 214.73922 -385.501642) (xy 214.746332 -385.508754) (xy 214.764112 -385.516374)
			(xy 214.85479 -385.517898) (xy 214.872824 -385.51104) (xy 214.88019 -385.504182) (xy 214.901508 -385.48517)
			(xy 214.948701 -385.452996) (xy 215.000162 -385.428214) (xy 215.054741 -385.411378) (xy 215.11122 -385.402863)
			(xy 215.139778 -385.402328) (xy 215.168755 -385.402882) (xy 215.226044 -385.411639) (xy 215.281351 -385.428954)
			(xy 215.333406 -385.45443) (xy 215.381011 -385.487481) (xy 215.423074 -385.527349) (xy 215.441276 -385.549902)
			(xy 215.448896 -385.559808) (xy 215.471756 -385.570222) (xy 215.580976 -385.563364) (xy 215.602312 -385.550156)
			(xy 215.608916 -385.539488) (xy 215.623759 -385.515449) (xy 215.65937 -385.471594) (xy 215.701063 -385.433474)
			(xy 215.747926 -385.401925) (xy 215.798932 -385.377637) (xy 215.852963 -385.361143) (xy 215.908837 -385.352803)
			(xy 215.937084 -385.35229) (xy 215.96688 -385.352819) (xy 216.025747 -385.362083) (xy 216.082457 -385.380389)
			(xy 216.135631 -385.407291) (xy 216.183975 -385.442135) (xy 216.226312 -385.484072) (xy 216.244424 -385.507738)
			(xy 216.25179 -385.517644) (xy 216.273126 -385.528566) (xy 216.379552 -385.528312) (xy 216.401142 -385.517644)
			(xy 216.408254 -385.507738) (xy 216.426378 -385.48399) (xy 216.468729 -385.441863) (xy 216.517131 -385.406854)
			(xy 216.570398 -385.37982) (xy 216.62723 -385.361421) (xy 216.686234 -385.352108) (xy 216.716102 -385.351528)
			(xy 216.746117 -385.352098) (xy 216.805406 -385.361511) (xy 216.862489 -385.38009) (xy 216.915961 -385.407375)
			(xy 216.964502 -385.442695) (xy 216.986104 -385.463542) (xy 216.993216 -385.470654) (xy 217.010996 -385.478274)
			(xy 217.101674 -385.479798) (xy 217.119708 -385.47294) (xy 217.127074 -385.466082) (xy 217.148399 -385.447078)
			(xy 217.19559 -385.414903) (xy 217.247049 -385.39012) (xy 217.301627 -385.373281) (xy 217.358104 -385.364764)
			(xy 217.386662 -385.364228) (xy 217.415602 -385.36477) (xy 217.472819 -385.373499) (xy 217.528064 -385.390763)
			(xy 217.580071 -385.416167) (xy 217.627648 -385.449128) (xy 217.649044 -385.468622) (xy 217.65641 -385.475734)
			(xy 217.675714 -385.4831) (xy 217.769186 -385.479036) (xy 217.787728 -385.470146) (xy 217.794586 -385.462526)
			(xy 217.812785 -385.442813) (xy 217.853733 -385.408151) (xy 217.899131 -385.379564) (xy 217.948085 -385.357615)
			(xy 217.999629 -385.342736) (xy 218.052749 -385.335221) (xy 218.079574 -385.334764) (xy 218.106823 -385.335302)
			(xy 218.160768 -385.343055) (xy 218.21306 -385.358405) (xy 218.262635 -385.381041) (xy 218.308484 -385.410502)
			(xy 218.349674 -385.446188) (xy 218.385366 -385.487373) (xy 218.414833 -385.533218) (xy 218.437476 -385.58279)
			(xy 218.452834 -385.63508) (xy 218.460594 -385.689023) (xy 218.461082 -385.716272) (xy 218.460594 -385.743332)
			(xy 218.452933 -385.796908) (xy 218.437775 -385.848862) (xy 218.415424 -385.898151) (xy 218.386329 -385.943786)
			(xy 218.351075 -385.984849) (xy 218.331034 -386.003038) (xy 218.322906 -386.010404) (xy 218.313762 -386.030216)
			(xy 218.313254 -386.128006) (xy 218.322144 -386.148072) (xy 218.330272 -386.155184) (xy 218.349929 -386.173354)
			(xy 218.384451 -386.214263) (xy 218.412919 -386.259594) (xy 218.434775 -386.308458) (xy 218.449589 -386.359896)
			(xy 218.457073 -386.4129) (xy 218.457526 -386.439664) (xy 218.457011 -386.466915) (xy 218.44926 -386.520863)
			(xy 218.433909 -386.573159) (xy 218.411272 -386.622738) (xy 218.38181 -386.66859) (xy 218.346121 -386.709783)
			(xy 218.304934 -386.745477) (xy 218.259085 -386.774946) (xy 218.20951 -386.79759) (xy 218.157216 -386.812948)
			(xy 218.103269 -386.820707) (xy 218.076018 -386.821172) (xy 218.049468 -386.820714) (xy 217.996882 -386.813336)
			(xy 217.945828 -386.798735) (xy 217.897294 -386.777192) (xy 217.852218 -386.749124) (xy 217.811471 -386.715075)
			(xy 217.793316 -386.695696) (xy 217.786204 -386.688076) (xy 217.767916 -386.67944) (xy 217.674698 -386.67563)
			(xy 217.655902 -386.682742) (xy 217.648282 -386.689854) (xy 217.626916 -386.70924) (xy 217.57946 -386.742042)
			(xy 217.527606 -386.767324) (xy 217.472536 -386.78451) (xy 217.415506 -386.793206) (xy 217.386662 -386.79374)
			(xy 217.356645 -386.793202) (xy 217.297355 -386.783782) (xy 217.240271 -386.765197) (xy 217.1868 -386.737904)
			(xy 217.138261 -386.702576) (xy 217.11666 -386.681726) (xy 217.109548 -386.674614) (xy 217.091768 -386.666994)
			(xy 217.00109 -386.66547) (xy 216.983056 -386.672328) (xy 216.97569 -386.679186) (xy 216.95439 -386.698218)
			(xy 216.907191 -386.730387) (xy 216.855725 -386.755164) (xy 216.801143 -386.771995) (xy 216.744661 -386.780507)
			(xy 216.716102 -386.78104) (xy 216.686306 -386.780509) (xy 216.62744 -386.771244) (xy 216.57073 -386.752937)
			(xy 216.517557 -386.726035) (xy 216.469213 -386.691193) (xy 216.426875 -386.649257) (xy 216.408762 -386.625592)
			(xy 216.401396 -386.615686) (xy 216.38006 -386.604764) (xy 216.273634 -386.605018) (xy 216.252044 -386.615686)
			(xy 216.244932 -386.625592) (xy 216.226824 -386.649353) (xy 216.184469 -386.691478) (xy 216.136064 -386.726484)
			(xy 216.082793 -386.753516) (xy 216.025959 -386.771912) (xy 215.966952 -386.781223) (xy 215.937084 -386.781802)
			(xy 215.908105 -386.781302) (xy 215.850812 -386.772538) (xy 215.795503 -386.755214) (xy 215.743448 -386.729728)
			(xy 215.695844 -386.696665) (xy 215.653785 -386.656787) (xy 215.635586 -386.634228) (xy 215.627966 -386.624322)
			(xy 215.605106 -386.613908) (xy 215.495886 -386.620766) (xy 215.47455 -386.633974) (xy 215.467946 -386.644642)
			(xy 215.45314 -386.668704) (xy 215.417522 -386.712559) (xy 215.375822 -386.750676) (xy 215.328953 -386.782222)
			(xy 215.277941 -386.806506) (xy 215.223905 -386.822995) (xy 215.168026 -386.83133) (xy 215.139778 -386.83184)
			(xy 215.109762 -386.831292) (xy 215.050472 -386.821875) (xy 214.993388 -386.803292) (xy 214.939916 -386.776001)
			(xy 214.891377 -386.740675) (xy 214.869776 -386.719826) (xy 214.862664 -386.712714) (xy 214.844884 -386.705094)
			(xy 214.754206 -386.70357) (xy 214.736172 -386.710428) (xy 214.728806 -386.717286) (xy 214.707499 -386.736311)
			(xy 214.660302 -386.76848) (xy 214.608838 -386.793259) (xy 214.554257 -386.810092) (xy 214.497777 -386.818605)
			(xy 214.469218 -386.81914) (xy 214.440741 -386.818606) (xy 214.384418 -386.810148) (xy 214.329981 -386.793403)
			(xy 214.278642 -386.768743) (xy 214.231544 -386.736718) (xy 214.189737 -386.698041) (xy 214.17153 -386.676138)
			(xy 214.163656 -386.666232) (xy 214.141304 -386.656326) (xy 214.033608 -386.662676) (xy 214.012526 -386.675122)
			(xy 214.005922 -386.68579) (xy 213.990893 -386.708914) (xy 213.955204 -386.750959) (xy 213.913833 -386.787427)
			(xy 213.867642 -386.817557) (xy 213.817593 -386.840721) (xy 213.76473 -386.856436) (xy 213.710155 -386.864375)
			(xy 213.68258 -386.86486) (xy 213.652564 -386.864305) (xy 213.593275 -386.854889) (xy 213.536191 -386.836307)
			(xy 213.48272 -386.809018) (xy 213.43418 -386.773694) (xy 213.412578 -386.752846) (xy 213.405466 -386.745734)
			(xy 213.387686 -386.738114) (xy 213.297008 -386.73659) (xy 213.278974 -386.743448) (xy 213.271608 -386.750306)
			(xy 213.250289 -386.769317) (xy 213.203096 -386.801491) (xy 213.151636 -386.826274) (xy 213.097057 -386.84311)
			(xy 213.040578 -386.851625) (xy 213.01202 -386.85216) (xy 212.984765 -386.851726) (xy 212.930811 -386.84397)
			(xy 212.87851 -386.828615) (xy 212.828926 -386.805971) (xy 212.783071 -386.7765) (xy 212.741877 -386.740803)
			(xy 212.706183 -386.699607) (xy 212.676716 -386.653749) (xy 212.654076 -386.604164) (xy 212.638724 -386.551862)
			(xy 212.630972 -386.497907) (xy 212.630512 -386.470652) (xy 210.247232 -386.470652) (xy 210.210484 -386.529721)
			(xy 210.160598 -386.59544) (xy 210.104839 -386.656256) (xy 210.043686 -386.711645) (xy 209.977665 -386.761132)
			(xy 209.907344 -386.80429) (xy 209.870548 -386.82295) (xy 209.862237 -386.82751) (xy 209.849486 -386.841519)
			(xy 209.842679 -386.859197) (xy 209.842354 -386.86867) (xy 209.842354 -386.959602) (xy 209.842685 -386.969079)
			(xy 209.849468 -386.986774) (xy 209.862218 -387.000793) (xy 209.870548 -387.005322) (xy 209.907343 -387.02398)
			(xy 209.97765 -387.067153) (xy 210.043658 -387.11665) (xy 210.104799 -387.172046) (xy 210.16055 -387.232865)
			(xy 210.210429 -387.298584) (xy 210.25401 -387.36864) (xy 210.290917 -387.442429) (xy 210.320833 -387.519319)
			(xy 210.343503 -387.598648) (xy 210.35873 -387.679735) (xy 210.366384 -387.761884) (xy 210.366864 -387.803136)
			(xy 210.366277 -387.849532) (xy 210.35664 -387.941821) (xy 210.337443 -388.032604) (xy 210.308894 -388.120894)
			(xy 210.291966 -388.160514) (xy 221.30132 -388.160514) (xy 221.305305 -387.979173) (xy 221.317251 -387.798181)
			(xy 221.337135 -387.617889) (xy 221.364919 -387.438645) (xy 221.40055 -387.260793) (xy 221.443958 -387.084679)
			(xy 221.49506 -386.910641) (xy 221.553758 -386.739016) (xy 221.619937 -386.570135) (xy 221.69347 -386.404323)
			(xy 221.774215 -386.241902) (xy 221.862017 -386.083183) (xy 221.956706 -385.928475) (xy 222.058098 -385.778075)
			(xy 222.165999 -385.632274) (xy 222.2802 -385.491353) (xy 222.400481 -385.355584) (xy 222.526609 -385.22523)
			(xy 222.658341 -385.100541) (xy 222.795423 -384.981759) (xy 222.93759 -384.869113) (xy 223.084567 -384.76282)
			(xy 223.236072 -384.663086) (xy 223.391811 -384.570102) (xy 223.551484 -384.484049) (xy 223.714783 -384.405093)
			(xy 223.881392 -384.333385) (xy 224.05099 -384.269065) (xy 224.22325 -384.212257) (xy 224.397838 -384.163069)
			(xy 224.574419 -384.121598) (xy 224.752651 -384.087923) (xy 224.93219 -384.062109) (xy 225.112689 -384.044207)
			(xy 225.293801 -384.034249) (xy 225.475175 -384.032257) (xy 225.656462 -384.038233) (xy 225.837311 -384.052167)
			(xy 226.017374 -384.07403) (xy 226.196302 -384.103782) (xy 226.373751 -384.141364) (xy 226.549378 -384.186704)
			(xy 226.722844 -384.239715) (xy 226.893814 -384.300294) (xy 227.061959 -384.368324) (xy 227.226952 -384.443674)
			(xy 227.388477 -384.526199) (xy 227.546221 -384.615739) (xy 227.69988 -384.712121) (xy 227.849157 -384.815159)
			(xy 227.993764 -384.924655) (xy 228.133422 -385.040397) (xy 228.267862 -385.162162) (xy 228.396823 -385.289714)
			(xy 228.520057 -385.422808) (xy 228.637326 -385.561186) (xy 228.748404 -385.704582) (xy 228.853076 -385.852718)
			(xy 228.95114 -386.005309) (xy 229.042407 -386.16206) (xy 229.126701 -386.322669) (xy 229.203859 -386.486825)
			(xy 229.273732 -386.654212) (xy 229.336186 -386.824506) (xy 229.391098 -386.997379) (xy 229.438365 -387.172498)
			(xy 229.477894 -387.349523) (xy 229.509609 -387.528114) (xy 229.53345 -387.707926) (xy 229.549369 -387.888611)
			(xy 229.557336 -388.069821) (xy 229.557834 -388.160514) (xy 229.557336 -388.251207) (xy 229.549369 -388.432417)
			(xy 229.53345 -388.613102) (xy 229.509609 -388.792914) (xy 229.477894 -388.971505) (xy 229.438365 -389.14853)
			(xy 229.391098 -389.323649) (xy 229.336186 -389.496522) (xy 229.273732 -389.666816) (xy 229.203859 -389.834203)
			(xy 229.126701 -389.998359) (xy 229.042407 -390.158968) (xy 228.95114 -390.315719) (xy 228.853076 -390.46831)
			(xy 228.748404 -390.616446) (xy 228.637326 -390.759842) (xy 228.520057 -390.89822) (xy 228.396823 -391.031314)
			(xy 228.267862 -391.158866) (xy 228.133422 -391.280631) (xy 227.993764 -391.396373) (xy 227.849157 -391.505869)
			(xy 227.69988 -391.608907) (xy 227.546221 -391.705289) (xy 227.388477 -391.794829) (xy 227.226952 -391.877354)
			(xy 227.061959 -391.952704) (xy 226.893814 -392.020734) (xy 226.722844 -392.081313) (xy 226.549378 -392.134324)
			(xy 226.373751 -392.179664) (xy 226.196302 -392.217246) (xy 226.017374 -392.246998) (xy 225.837311 -392.268861)
			(xy 225.656462 -392.282795) (xy 225.475175 -392.288771) (xy 225.293801 -392.286779) (xy 225.112689 -392.276821)
			(xy 224.93219 -392.258919) (xy 224.752651 -392.233105) (xy 224.574419 -392.19943) (xy 224.397838 -392.157959)
			(xy 224.22325 -392.108771) (xy 224.05099 -392.051963) (xy 223.881392 -391.987643) (xy 223.714783 -391.915935)
			(xy 223.551484 -391.836979) (xy 223.391811 -391.750926) (xy 223.236072 -391.657942) (xy 223.084567 -391.558208)
			(xy 222.93759 -391.451915) (xy 222.795423 -391.339269) (xy 222.658341 -391.220487) (xy 222.526609 -391.095798)
			(xy 222.400481 -390.965444) (xy 222.2802 -390.829675) (xy 222.165999 -390.688754) (xy 222.058098 -390.542953)
			(xy 221.956706 -390.392553) (xy 221.862017 -390.237845) (xy 221.774215 -390.079126) (xy 221.69347 -389.916705)
			(xy 221.619937 -389.750893) (xy 221.553758 -389.582012) (xy 221.49506 -389.410387) (xy 221.443958 -389.236349)
			(xy 221.40055 -389.060235) (xy 221.364919 -388.882383) (xy 221.337135 -388.703139) (xy 221.317251 -388.522847)
			(xy 221.305305 -388.341855) (xy 221.30132 -388.160514) (xy 210.291966 -388.160514) (xy 210.290664 -388.163562)
			(xy 210.286853 -388.173502) (xy 210.286866 -388.194763) (xy 210.290664 -388.20471) (xy 210.308901 -388.247375)
			(xy 210.337437 -388.335669) (xy 210.35663 -388.426452) (xy 210.366272 -388.518741) (xy 210.366864 -388.565136)
			(xy 210.36636 -388.607484) (xy 210.358309 -388.691798) (xy 210.34228 -388.774964) (xy 210.318419 -388.856231)
			(xy 210.28694 -388.934861) (xy 210.248129 -389.010142) (xy 210.202339 -389.081394) (xy 210.149983 -389.14797)
			(xy 210.091535 -389.209268) (xy 210.027525 -389.264733) (xy 209.958533 -389.313862) (xy 209.885183 -389.356211)
			(xy 209.80814 -389.391395) (xy 209.728101 -389.419097) (xy 209.645792 -389.439065) (xy 209.561957 -389.451118)
			(xy 209.477356 -389.455149) (xy 209.392755 -389.451118) (xy 209.30892 -389.439065) (xy 209.226611 -389.419097)
			(xy 209.146572 -389.391395) (xy 209.069529 -389.356211) (xy 208.996179 -389.313862) (xy 208.927187 -389.264733)
			(xy 208.863177 -389.209268) (xy 208.804729 -389.14797) (xy 208.752373 -389.081394) (xy 208.706583 -389.010142)
			(xy 208.667772 -388.934861) (xy 208.636293 -388.856231) (xy 208.612432 -388.774964) (xy 208.596403 -388.691798)
			(xy 208.588352 -388.607484) (xy 208.587848 -388.565136) (xy 208.588431 -388.51874) (xy 208.598061 -388.426448)
			(xy 208.617252 -388.335662) (xy 208.645795 -388.247369) (xy 208.664048 -388.20471) (xy 208.667874 -388.19477)
			(xy 208.667888 -388.173496) (xy 208.664048 -388.163562) (xy 208.645812 -388.120897) (xy 208.617278 -388.032603)
			(xy 208.598088 -387.941819) (xy 208.588449 -387.849531) (xy 208.587848 -387.803136) (xy 208.588314 -387.761882)
			(xy 208.595954 -387.67973) (xy 208.61117 -387.598638) (xy 208.633833 -387.519305) (xy 208.663747 -387.442412)
			(xy 208.700655 -387.36862) (xy 208.74424 -387.298565) (xy 208.794127 -387.232848) (xy 208.849887 -387.172035)
			(xy 208.911041 -387.116648) (xy 208.977062 -387.067165) (xy 209.047382 -387.02401) (xy 209.084164 -387.005322)
			(xy 209.09247 -387.000759) (xy 209.10521 -386.986748) (xy 209.112006 -386.969072) (xy 209.112358 -386.959602)
			(xy 209.112358 -386.86867) (xy 209.112022 -386.859195) (xy 209.105234 -386.841507) (xy 209.092484 -386.827494)
			(xy 209.084164 -386.82295) (xy 209.04737 -386.804292) (xy 208.977063 -386.761119) (xy 208.911056 -386.711622)
			(xy 208.849915 -386.656226) (xy 208.794166 -386.595407) (xy 208.744288 -386.529687) (xy 208.700709 -386.459632)
			(xy 208.663804 -386.385842) (xy 208.633889 -386.308953) (xy 208.611222 -386.229623) (xy 208.595997 -386.148536)
			(xy 208.588346 -386.066388) (xy 208.587848 -386.025136) (xy 208.588431 -385.97874) (xy 208.598061 -385.886448)
			(xy 208.617252 -385.795662) (xy 208.645795 -385.707369) (xy 208.664048 -385.66471) (xy 208.667874 -385.65477)
			(xy 208.667888 -385.633496) (xy 208.664048 -385.623562) (xy 208.645812 -385.580897) (xy 208.617278 -385.492603)
			(xy 208.598088 -385.401819) (xy 208.588449 -385.309531) (xy 208.587848 -385.263136) (xy 208.588314 -385.221882)
			(xy 208.595954 -385.13973) (xy 208.61117 -385.058638) (xy 208.633833 -384.979305) (xy 208.663747 -384.902412)
			(xy 208.700655 -384.82862) (xy 208.74424 -384.758565) (xy 208.794127 -384.692848) (xy 208.849887 -384.632035)
			(xy 208.911041 -384.576648) (xy 208.977062 -384.527165) (xy 209.047382 -384.48401) (xy 209.084164 -384.465322)
			(xy 209.09247 -384.460759) (xy 209.10521 -384.446748) (xy 209.112006 -384.429072) (xy 209.112358 -384.419602)
			(xy 209.112358 -384.32867) (xy 209.112022 -384.319195) (xy 209.105234 -384.301507) (xy 209.092484 -384.287494)
			(xy 209.084164 -384.28295) (xy 209.04737 -384.264292) (xy 208.977063 -384.221119) (xy 208.911056 -384.171622)
			(xy 208.849915 -384.116226) (xy 208.794166 -384.055407) (xy 208.744288 -383.989687) (xy 208.700709 -383.919632)
			(xy 208.663804 -383.845842) (xy 208.633889 -383.768953) (xy 208.611222 -383.689623) (xy 208.595997 -383.608536)
			(xy 208.588346 -383.526388) (xy 208.587848 -383.485136) (xy 208.588431 -383.43874) (xy 208.598061 -383.346448)
			(xy 208.617252 -383.255662) (xy 208.645795 -383.167369) (xy 208.664048 -383.12471) (xy 208.667874 -383.11477)
			(xy 208.667888 -383.093496) (xy 208.664048 -383.083562) (xy 208.645812 -383.040897) (xy 208.617278 -382.952603)
			(xy 208.598088 -382.861819) (xy 208.588449 -382.769531) (xy 208.587848 -382.723136) (xy 208.588318 -382.682107)
			(xy 208.595872 -382.600399) (xy 208.610921 -382.519734) (xy 208.633336 -382.440797) (xy 208.662926 -382.364261)
			(xy 208.69944 -382.290776) (xy 208.742567 -382.220966) (xy 208.791941 -382.155426) (xy 208.847142 -382.094712)
			(xy 208.907701 -382.03934) (xy 208.973103 -381.989782) (xy 209.00771 -381.96774) (xy 209.014876 -381.96291)
			(xy 209.02572 -381.949469) (xy 209.031497 -381.933194) (xy 209.03184 -381.92456) (xy 209.03184 -381.89408)
			(xy 209.031507 -381.885438) (xy 209.025764 -381.869137) (xy 209.01491 -381.855689) (xy 209.00771 -381.8509)
			(xy 208.989168 -381.838962) (xy 208.973928 -381.829056) (xy 208.938368 -381.832612) (xy 208.305654 -382.465326)
			(xy 208.298796 -382.490726) (xy 208.302098 -382.503934) (xy 208.31083 -382.539808) (xy 208.323028 -382.612632)
			(xy 208.329146 -382.686217) (xy 208.32953 -382.723136) (xy 208.328932 -382.769703) (xy 208.319226 -382.86233)
			(xy 208.299905 -382.953438) (xy 208.271177 -383.042031) (xy 208.252822 -383.084832) (xy 208.249017 -383.094774)
			(xy 208.24902 -383.116037) (xy 208.252822 -383.12598) (xy 208.27126 -383.168824) (xy 208.300092 -383.257534)
			(xy 208.319481 -383.348775) (xy 208.329214 -383.441545) (xy 208.329784 -383.488184) (xy 208.329324 -383.529312)
			(xy 208.321731 -383.611218) (xy 208.30661 -383.692073) (xy 208.28409 -383.771186) (xy 208.254362 -383.847883)
			(xy 208.21768 -383.921508) (xy 208.174358 -383.991432) (xy 208.124767 -384.057058) (xy 208.069328 -384.117826)
			(xy 208.008517 -384.173216) (xy 207.942851 -384.222756) (xy 207.872893 -384.266022) (xy 207.836262 -384.284728)
			(xy 207.823054 -384.291332) (xy 207.808068 -384.315462) (xy 207.807814 -384.435858) (xy 207.823054 -384.460242)
			(xy 207.836008 -384.466592) (xy 207.872631 -384.485313) (xy 207.942591 -384.528573) (xy 208.008258 -384.578109)
			(xy 208.069071 -384.633496) (xy 208.12451 -384.694262) (xy 208.174101 -384.759887) (xy 208.217421 -384.829811)
			(xy 208.254099 -384.903437) (xy 208.283822 -384.980134) (xy 208.306336 -385.059248) (xy 208.321449 -385.140103)
			(xy 208.329032 -385.222008) (xy 208.32953 -385.263136) (xy 208.328909 -385.309639) (xy 208.319177 -385.402136)
			(xy 208.299854 -385.493114) (xy 208.271151 -385.581581) (xy 208.252822 -385.624324) (xy 208.248897 -385.634388)
			(xy 208.249017 -385.65597) (xy 208.253076 -385.66598) (xy 208.272159 -385.709456) (xy 208.302017 -385.799591)
			(xy 208.322114 -385.892392) (xy 208.33222 -385.986804) (xy 208.332832 -386.03428) (xy 208.332371 -386.075107)
			(xy 208.324887 -386.156419) (xy 208.309981 -386.236702) (xy 208.287779 -386.31528) (xy 208.258466 -386.391492)
			(xy 208.222291 -386.464696) (xy 208.179557 -386.534276) (xy 208.130625 -386.599646) (xy 208.075906 -386.660254)
			(xy 208.015862 -386.715591) (xy 207.950998 -386.765191) (xy 207.88186 -386.808636) (xy 207.84566 -386.827522)
			(xy 207.832706 -386.834126) (xy 207.81772 -386.85851) (xy 207.817974 -386.978144) (xy 207.83296 -387.002274)
			(xy 207.845914 -387.008878) (xy 207.882235 -387.027718) (xy 207.951602 -387.071122) (xy 208.01669 -387.120714)
			(xy 208.076947 -387.176075) (xy 208.131863 -387.236737) (xy 208.180976 -387.302186) (xy 208.223869 -387.371871)
			(xy 208.26018 -387.445201) (xy 208.289601 -387.521556) (xy 208.311884 -387.600291) (xy 208.326841 -387.68074)
			(xy 208.334345 -387.762222) (xy 208.334864 -387.803136) (xy 208.334277 -387.849532) (xy 208.32464 -387.941821)
			(xy 208.305443 -388.032604) (xy 208.276894 -388.120894) (xy 208.258664 -388.163562) (xy 208.254853 -388.173502)
			(xy 208.254866 -388.194763) (xy 208.258664 -388.20471) (xy 208.276901 -388.247375) (xy 208.305437 -388.335669)
			(xy 208.32463 -388.426452) (xy 208.334272 -388.518741) (xy 208.334864 -388.565136) (xy 208.33436 -388.607484)
			(xy 208.326309 -388.691798) (xy 208.31028 -388.774964) (xy 208.286419 -388.856231) (xy 208.25494 -388.934861)
			(xy 208.216129 -389.010142) (xy 208.170339 -389.081394) (xy 208.117983 -389.14797) (xy 208.059535 -389.209268)
			(xy 207.995525 -389.264733) (xy 207.926533 -389.313862) (xy 207.853183 -389.356211) (xy 207.77614 -389.391395)
			(xy 207.696101 -389.419097) (xy 207.613792 -389.439065) (xy 207.529957 -389.451118) (xy 207.445356 -389.455149)
			(xy 207.360755 -389.451118) (xy 207.27692 -389.439065) (xy 207.194611 -389.419097) (xy 207.114572 -389.391395)
			(xy 207.037529 -389.356211) (xy 206.964179 -389.313862) (xy 206.895187 -389.264733) (xy 206.831177 -389.209268)
			(xy 206.772729 -389.14797) (xy 206.720373 -389.081394) (xy 206.674583 -389.010142) (xy 206.635772 -388.934861)
			(xy 206.604293 -388.856231) (xy 206.580432 -388.774964) (xy 206.564403 -388.691798) (xy 206.556352 -388.607484)
			(xy 206.555848 -388.565136) (xy 206.556431 -388.51874) (xy 206.566061 -388.426448) (xy 206.585252 -388.335662)
			(xy 206.613795 -388.247369) (xy 206.632048 -388.20471) (xy 206.635874 -388.19477) (xy 206.635888 -388.173496)
			(xy 206.632048 -388.163562) (xy 206.613812 -388.120897) (xy 206.585278 -388.032603) (xy 206.566088 -387.941819)
			(xy 206.556449 -387.849531) (xy 206.555848 -387.803136) (xy 206.556309 -387.762309) (xy 206.563791 -387.680998)
			(xy 206.578697 -387.600716) (xy 206.600899 -387.522138) (xy 206.630213 -387.445927) (xy 206.666389 -387.372724)
			(xy 206.709124 -387.303146) (xy 206.758058 -387.237779) (xy 206.812779 -387.177173) (xy 206.872826 -387.121839)
			(xy 206.937692 -387.072243) (xy 207.006832 -387.028803) (xy 207.04302 -387.009894) (xy 207.055974 -387.00329)
			(xy 207.07096 -386.978906) (xy 207.070706 -386.859272) (xy 207.05572 -386.835142) (xy 207.042766 -386.828538)
			(xy 207.006442 -386.8097) (xy 206.937068 -386.766301) (xy 206.871975 -386.716712) (xy 206.811711 -386.661353)
			(xy 206.756788 -386.600692) (xy 206.70767 -386.535243) (xy 206.664772 -386.465558) (xy 206.628456 -386.392227)
			(xy 206.59903 -386.31587) (xy 206.576743 -386.237133) (xy 206.561784 -386.156681) (xy 206.554277 -386.075195)
			(xy 206.553816 -386.03428) (xy 206.554436 -385.987776) (xy 206.564166 -385.895279) (xy 206.583486 -385.8043)
			(xy 206.612186 -385.715832) (xy 206.630524 -385.673092) (xy 206.634456 -385.663028) (xy 206.634342 -385.641442)
			(xy 206.63027 -385.631436) (xy 206.611185 -385.58796) (xy 206.581324 -385.497826) (xy 206.561225 -385.405025)
			(xy 206.551116 -385.310612) (xy 206.550514 -385.263136) (xy 206.550978 -385.22201) (xy 206.558577 -385.140108)
			(xy 206.573704 -385.059258) (xy 206.59623 -384.98015) (xy 206.625962 -384.903459) (xy 206.662647 -384.82984)
			(xy 206.705971 -384.759922) (xy 206.755565 -384.694301) (xy 206.811004 -384.633539) (xy 206.871816 -384.578155)
			(xy 206.93748 -384.52862) (xy 207.007437 -384.485359) (xy 207.044036 -384.466592) (xy 207.057244 -384.459988)
			(xy 207.07223 -384.435858) (xy 207.072484 -384.315462) (xy 207.057244 -384.291078) (xy 207.04429 -384.284728)
			(xy 207.007667 -384.266007) (xy 206.937705 -384.222747) (xy 206.872037 -384.173212) (xy 206.811223 -384.117825)
			(xy 206.755783 -384.057059) (xy 206.706191 -383.991434) (xy 206.66287 -383.92151) (xy 206.62619 -383.847885)
			(xy 206.596466 -383.771188) (xy 206.57395 -383.692073) (xy 206.558835 -383.611218) (xy 206.55125 -383.529312)
			(xy 206.550768 -383.488184) (xy 206.550768 -383.472182) (xy 206.543148 -383.45364) (xy 206.485236 -383.39522)
			(xy 206.477835 -383.388382) (xy 206.459237 -383.380667) (xy 206.449168 -383.380234) (xy 206.404464 -383.380234)
			(xy 206.394397 -383.380664) (xy 206.375806 -383.388392) (xy 206.368396 -383.39522) (xy 206.310484 -383.453386)
			(xy 206.302864 -383.471928) (xy 206.302864 -383.482088) (xy 206.302864 -383.485136) (xy 206.302399 -383.52639)
			(xy 206.294762 -383.608545) (xy 206.279548 -383.689638) (xy 206.256887 -383.768974) (xy 206.226975 -383.845869)
			(xy 206.190068 -383.919663) (xy 206.146484 -383.989721) (xy 206.096598 -384.05544) (xy 206.040839 -384.116256)
			(xy 205.979686 -384.171645) (xy 205.913665 -384.221132) (xy 205.843344 -384.26429) (xy 205.806548 -384.28295)
			(xy 205.798237 -384.28751) (xy 205.785486 -384.301519) (xy 205.778679 -384.319197) (xy 205.778354 -384.32867)
			(xy 205.778354 -384.419602) (xy 205.778685 -384.429079) (xy 205.785468 -384.446774) (xy 205.798218 -384.460793)
			(xy 205.806548 -384.465322) (xy 205.843343 -384.48398) (xy 205.91365 -384.527153) (xy 205.979658 -384.57665)
			(xy 206.040799 -384.632046) (xy 206.09655 -384.692865) (xy 206.146429 -384.758584) (xy 206.19001 -384.82864)
			(xy 206.226917 -384.902429) (xy 206.256833 -384.979319) (xy 206.279503 -385.058648) (xy 206.29473 -385.139735)
			(xy 206.302384 -385.221884) (xy 206.302864 -385.263136) (xy 206.302277 -385.309532) (xy 206.29264 -385.401821)
			(xy 206.273443 -385.492604) (xy 206.244894 -385.580894) (xy 206.226664 -385.623562) (xy 206.222853 -385.633502)
			(xy 206.222866 -385.654763) (xy 206.226664 -385.66471) (xy 206.244901 -385.707375) (xy 206.273437 -385.795669)
			(xy 206.29263 -385.886452) (xy 206.302272 -385.978741) (xy 206.302864 -386.025136) (xy 206.30236 -386.067484)
			(xy 206.294309 -386.151798) (xy 206.27828 -386.234964) (xy 206.254419 -386.316231) (xy 206.22294 -386.394861)
			(xy 206.184129 -386.470142) (xy 206.138339 -386.541394) (xy 206.085983 -386.60797) (xy 206.027535 -386.669268)
			(xy 205.963525 -386.724733) (xy 205.894533 -386.773862) (xy 205.821183 -386.816211) (xy 205.74414 -386.851395)
			(xy 205.664101 -386.879097) (xy 205.581792 -386.899065) (xy 205.497957 -386.911118) (xy 205.413356 -386.915149)
			(xy 205.328755 -386.911118) (xy 205.24492 -386.899065) (xy 205.162611 -386.879097) (xy 205.082572 -386.851395)
			(xy 205.005529 -386.816211) (xy 204.932179 -386.773862) (xy 204.863187 -386.724733) (xy 204.799177 -386.669268)
			(xy 204.740729 -386.60797) (xy 204.688373 -386.541394) (xy 204.642583 -386.470142) (xy 204.603772 -386.394861)
			(xy 204.572293 -386.316231) (xy 204.548432 -386.234964) (xy 204.532403 -386.151798) (xy 204.524352 -386.067484)
			(xy 204.523848 -386.025136) (xy 204.524431 -385.97874) (xy 204.534061 -385.886448) (xy 204.553252 -385.795662)
			(xy 204.581795 -385.707369) (xy 204.600048 -385.66471) (xy 204.603874 -385.65477) (xy 204.603888 -385.633496)
			(xy 204.600048 -385.623562) (xy 204.581812 -385.580897) (xy 204.553278 -385.492603) (xy 204.534088 -385.401819)
			(xy 204.524449 -385.309531) (xy 204.523848 -385.263136) (xy 204.524314 -385.221882) (xy 204.531954 -385.13973)
			(xy 204.54717 -385.058638) (xy 204.569833 -384.979305) (xy 204.599747 -384.902412) (xy 204.636655 -384.82862)
			(xy 204.68024 -384.758565) (xy 204.730127 -384.692848) (xy 204.785887 -384.632035) (xy 204.847041 -384.576648)
			(xy 204.913062 -384.527165) (xy 204.983382 -384.48401) (xy 205.020164 -384.465322) (xy 205.02847 -384.460759)
			(xy 205.04121 -384.446748) (xy 205.048006 -384.429072) (xy 205.048358 -384.419602) (xy 205.048358 -384.32867)
			(xy 205.048022 -384.319195) (xy 205.041234 -384.301507) (xy 205.028484 -384.287494) (xy 205.020164 -384.28295)
			(xy 204.98337 -384.264292) (xy 204.913063 -384.221119) (xy 204.847056 -384.171622) (xy 204.785915 -384.116226)
			(xy 204.730166 -384.055407) (xy 204.680288 -383.989687) (xy 204.636709 -383.919632) (xy 204.599804 -383.845842)
			(xy 204.569889 -383.768953) (xy 204.547222 -383.689623) (xy 204.531997 -383.608536) (xy 204.524346 -383.526388)
			(xy 204.523848 -383.485136) (xy 204.523848 -383.471928) (xy 204.516228 -383.453386) (xy 204.458316 -383.39522)
			(xy 204.450914 -383.388385) (xy 204.432315 -383.380678) (xy 204.422248 -383.380234) (xy 201.342244 -383.380234)
			(xy 201.332179 -383.380668) (xy 201.313592 -383.388401) (xy 201.306176 -383.39522) (xy 200.497694 -384.203702)
			(xy 200.490848 -384.211101) (xy 200.483116 -384.229699) (xy 200.482708 -384.23977) (xy 200.482708 -386.6007)
			(xy 200.482285 -386.61077) (xy 200.474572 -386.629376) (xy 200.467722 -386.636768) (xy 200.421494 -386.682996)
			(xy 200.414648 -386.690395) (xy 200.406913 -386.708992) (xy 200.406508 -386.719064) (xy 200.406508 -387.960616)
			(xy 200.741024 -387.960616) (xy 200.745095 -387.904994) (xy 200.757221 -387.850557) (xy 200.777144 -387.798466)
			(xy 200.80444 -387.749831) (xy 200.838526 -387.705688) (xy 200.878675 -387.666979) (xy 200.924033 -387.634528)
			(xy 200.973633 -387.609027) (xy 201.026417 -387.59102) (xy 201.08126 -387.58089) (xy 201.136994 -387.578853)
			(xy 201.192431 -387.584953) (xy 201.246388 -387.599059) (xy 201.297717 -387.620871) (xy 201.345323 -387.649925)
			(xy 201.388191 -387.6856) (xy 201.425408 -387.727137) (xy 201.456181 -387.77365) (xy 201.479853 -387.824147)
			(xy 201.495921 -387.877554) (xy 201.504041 -387.93273) (xy 201.50455 -387.960616) (xy 201.504041 -387.988502)
			(xy 201.495921 -388.043678) (xy 201.479853 -388.097085) (xy 201.456181 -388.147582) (xy 201.425408 -388.194095)
			(xy 201.388191 -388.235632) (xy 201.345323 -388.271307) (xy 201.297717 -388.300361) (xy 201.246388 -388.322173)
			(xy 201.192431 -388.336279) (xy 201.136994 -388.342379) (xy 201.08126 -388.340342) (xy 201.026417 -388.330212)
			(xy 200.973633 -388.312205) (xy 200.924033 -388.286704) (xy 200.878675 -388.254253) (xy 200.838526 -388.215544)
			(xy 200.80444 -388.171401) (xy 200.777144 -388.122766) (xy 200.757221 -388.070675) (xy 200.745095 -388.016238)
			(xy 200.741024 -387.960616) (xy 200.406508 -387.960616) (xy 200.406508 -389.181594) (xy 200.406086 -389.191665)
			(xy 200.398374 -389.210272) (xy 200.391522 -389.217662) (xy 199.619362 -389.989822) (xy 199.611965 -389.996671)
			(xy 199.593366 -390.004404) (xy 199.583294 -390.004808) (xy 199.582278 -390.004808) (xy 199.557386 -390.021064)
			(xy 199.551036 -390.035034) (xy 199.539463 -390.060015) (xy 199.510192 -390.106643) (xy 199.47452 -390.148576)
			(xy 199.433187 -390.184944) (xy 199.387054 -390.214989) (xy 199.33708 -390.238087) (xy 199.284303 -390.253758)
			(xy 199.229821 -390.261675) (xy 199.174767 -390.261675) (xy 199.120285 -390.253758) (xy 199.067508 -390.238087)
			(xy 199.017534 -390.214989) (xy 198.971401 -390.184944) (xy 198.930068 -390.148576) (xy 198.894396 -390.106643)
			(xy 198.865125 -390.060015) (xy 198.853552 -390.035034) (xy 198.847202 -390.021064) (xy 198.82231 -390.004808)
			(xy 192.95745 -390.004808) (xy 192.932558 -390.021064) (xy 192.926208 -390.035034) (xy 192.914635 -390.060015)
			(xy 192.885364 -390.106643) (xy 192.849692 -390.148576) (xy 192.808359 -390.184944) (xy 192.762226 -390.214989)
			(xy 192.712252 -390.238087) (xy 192.659475 -390.253758) (xy 192.604993 -390.261675) (xy 192.549939 -390.261675)
			(xy 192.495457 -390.253758) (xy 192.44268 -390.238087) (xy 192.392706 -390.214989) (xy 192.346573 -390.184944)
			(xy 192.30524 -390.148576) (xy 192.269568 -390.106643) (xy 192.240297 -390.060015) (xy 192.228724 -390.035034)
			(xy 192.222374 -390.021064) (xy 192.197482 -390.004808) (xy 189.13094 -390.004808) (xy 189.120875 -390.005242)
			(xy 189.102287 -390.012973) (xy 189.094872 -390.019794) (xy 184.53481 -394.579856) (xy 184.527971 -394.587257)
			(xy 184.520255 -394.605855) (xy 184.519824 -394.615924) (xy 184.519824 -395.95552) (xy 184.520251 -395.965588)
			(xy 184.527974 -395.984185) (xy 184.53481 -395.991588) (xy 184.616344 -396.073122) (xy 184.623741 -396.07997)
			(xy 184.64234 -396.087701) (xy 184.652412 -396.088108) (xy 185.033412 -396.088108) (xy 185.043481 -396.088534)
			(xy 185.062082 -396.096252) (xy 185.06948 -396.103094) (xy 185.345832 -396.379446) (xy 185.352679 -396.386844)
			(xy 185.360407 -396.405443) (xy 185.360818 -396.415514) (xy 185.360818 -399.052288) (xy 185.361239 -399.062359)
			(xy 185.368953 -399.080965) (xy 185.375804 -399.088356) (xy 185.429398 -399.14195) (xy 185.436794 -399.148802)
			(xy 185.455392 -399.156545) (xy 185.465466 -399.156936) (xy 189.027562 -399.156936) (xy 189.037626 -399.1565)
			(xy 189.056208 -399.148762) (xy 189.06363 -399.14195) (xy 190.454026 -397.751554) (xy 190.461423 -397.744706)
			(xy 190.480022 -397.736972) (xy 190.490094 -397.736568) (xy 193.891408 -397.736568) (xy 193.902695 -397.735961)
			(xy 193.923117 -397.726338) (xy 193.930778 -397.718026) (xy 193.95739 -397.6864) (xy 194.015584 -397.627696)
			(xy 194.078973 -397.574644) (xy 194.147011 -397.527703) (xy 194.219111 -397.487276) (xy 194.294651 -397.453713)
			(xy 194.372978 -397.427304) (xy 194.453418 -397.408275) (xy 194.535277 -397.396792) (xy 194.617848 -397.392954)
			(xy 194.700419 -397.396792) (xy 194.782278 -397.408275) (xy 194.862718 -397.427304) (xy 194.941045 -397.453713)
			(xy 195.016585 -397.487276) (xy 195.088685 -397.527703) (xy 195.156723 -397.574644) (xy 195.220112 -397.627696)
			(xy 195.278306 -397.6864) (xy 195.304918 -397.718026) (xy 195.312536 -397.7264) (xy 195.332981 -397.736046)
			(xy 195.344288 -397.736568) (xy 196.068188 -397.736568) (xy 196.07826 -397.736988) (xy 196.09687 -397.744696)
			(xy 196.104256 -397.751554) (xy 197.656704 -399.304002) (xy 197.664103 -399.310848) (xy 197.682701 -399.31858)
			(xy 197.692772 -399.318988)
		)
		(stroke
			(width 0)
			(type solid)
		)
		(fill yes)
		(layer "In11.Cu")
		(net "P12V_AUX")
	)
	(gr_poly
		(pts
			(xy 428.486824 -157.104842) (xy 428.496832 -157.10435) (xy 428.515322 -157.096688) (xy 428.529478 -157.082537)
			(xy 428.537147 -157.064049) (xy 428.537624 -157.054042) (xy 428.537624 -143.919448) (xy 428.537192 -143.909381)
			(xy 428.529467 -143.890788) (xy 428.522638 -143.88338) (xy 415.978848 -131.33959) (xy 415.971451 -131.332742)
			(xy 415.952852 -131.325012) (xy 415.94278 -131.324604) (xy 405.546306 -131.324604) (xy 405.536235 -131.325026)
			(xy 405.51763 -131.33274) (xy 405.510238 -131.33959) (xy 404.341076 -132.508752) (xy 406.251154 -132.508752)
			(xy 406.255225 -132.45313) (xy 406.267351 -132.398693) (xy 406.287274 -132.346602) (xy 406.31457 -132.297967)
			(xy 406.348656 -132.253824) (xy 406.388805 -132.215115) (xy 406.434163 -132.182664) (xy 406.483763 -132.157163)
			(xy 406.536547 -132.139156) (xy 406.59139 -132.129026) (xy 406.647124 -132.126989) (xy 406.702561 -132.133089)
			(xy 406.756518 -132.147195) (xy 406.807847 -132.169007) (xy 406.855453 -132.198061) (xy 406.898321 -132.233736)
			(xy 406.935538 -132.275273) (xy 406.966311 -132.321786) (xy 406.989983 -132.372283) (xy 407.006051 -132.42569)
			(xy 407.014171 -132.480866) (xy 407.01468 -132.508752) (xy 407.014171 -132.536638) (xy 407.006051 -132.591814)
			(xy 406.989983 -132.645221) (xy 406.966311 -132.695718) (xy 406.935538 -132.742231) (xy 406.898321 -132.783768)
			(xy 406.855453 -132.819443) (xy 406.807847 -132.848497) (xy 406.756518 -132.870309) (xy 406.702561 -132.884415)
			(xy 406.647124 -132.890515) (xy 406.59139 -132.888478) (xy 406.536547 -132.878348) (xy 406.483763 -132.860341)
			(xy 406.434163 -132.83484) (xy 406.388805 -132.802389) (xy 406.348656 -132.76368) (xy 406.31457 -132.719537)
			(xy 406.287274 -132.670902) (xy 406.267351 -132.618811) (xy 406.255225 -132.564374) (xy 406.251154 -132.508752)
			(xy 404.341076 -132.508752) (xy 402.915628 -133.9342) (xy 408.346656 -133.9342) (xy 408.347192 -133.905462)
			(xy 408.355813 -133.848635) (xy 408.372861 -133.793745) (xy 408.39795 -133.742033) (xy 408.430511 -133.69467)
			(xy 408.44978 -133.673342) (xy 408.456384 -133.66623) (xy 408.463496 -133.648704) (xy 408.463496 -133.559296)
			(xy 408.456384 -133.54177) (xy 408.44978 -133.534658) (xy 408.430516 -133.513325) (xy 408.397947 -133.465965)
			(xy 408.372853 -133.414255) (xy 408.355801 -133.359366) (xy 408.347177 -133.302539) (xy 408.346656 -133.2738)
			(xy 408.347178 -133.24655) (xy 408.354933 -133.192606) (xy 408.370287 -133.140314) (xy 408.392925 -133.090739)
			(xy 408.422388 -133.04489) (xy 408.458076 -133.003701) (xy 408.499262 -132.96801) (xy 408.545107 -132.938542)
			(xy 408.59468 -132.915899) (xy 408.646971 -132.900541) (xy 408.700914 -132.89278) (xy 408.728164 -132.892292)
			(xy 408.75701 -132.892836) (xy 408.814046 -132.901511) (xy 408.869122 -132.918685) (xy 408.92098 -132.943964)
			(xy 408.968436 -132.976772) (xy 408.989784 -132.996178) (xy 408.996896 -133.002782) (xy 409.01493 -133.009894)
			(xy 409.104084 -133.009894) (xy 409.122118 -133.002782) (xy 409.12923 -132.996178) (xy 409.150581 -132.976775)
			(xy 409.198042 -132.943978) (xy 409.2499 -132.9187) (xy 409.304973 -132.901518) (xy 409.362005 -132.892825)
			(xy 409.39085 -132.892292) (xy 409.418102 -132.892802) (xy 409.472051 -132.900552) (xy 409.524348 -132.915902)
			(xy 409.573928 -132.938538) (xy 409.619781 -132.968001) (xy 409.660974 -133.00369) (xy 409.696669 -133.044879)
			(xy 409.726138 -133.090728) (xy 409.748781 -133.140305) (xy 409.764137 -133.1926) (xy 409.771895 -133.246548)
			(xy 409.772358 -133.2738) (xy 409.771819 -133.302538) (xy 409.763198 -133.359364) (xy 409.74615 -133.414254)
			(xy 409.721063 -133.465966) (xy 409.688502 -133.51333) (xy 409.669234 -133.534658) (xy 409.66263 -133.54177)
			(xy 409.655518 -133.559296) (xy 409.655518 -133.648704) (xy 409.66263 -133.66623) (xy 409.669234 -133.673342)
			(xy 409.6885 -133.694673) (xy 409.721068 -133.742034) (xy 409.746162 -133.793744) (xy 409.763214 -133.848634)
			(xy 409.771837 -133.905461) (xy 409.772358 -133.9342) (xy 409.771945 -133.961455) (xy 409.764186 -134.01541)
			(xy 409.748828 -134.067712) (xy 409.726182 -134.117296) (xy 409.696709 -134.163151) (xy 409.66101 -134.204345)
			(xy 409.619811 -134.240039) (xy 409.573952 -134.269506) (xy 409.524365 -134.292145) (xy 409.472062 -134.307497)
			(xy 409.418105 -134.315248) (xy 409.39085 -134.315708) (xy 409.362004 -134.315156) (xy 409.304969 -134.306482)
			(xy 409.249893 -134.28931) (xy 409.198035 -134.264033) (xy 409.150579 -134.231228) (xy 409.12923 -134.211822)
			(xy 409.122118 -134.205218) (xy 409.104084 -134.198106) (xy 409.01493 -134.198106) (xy 408.996896 -134.205218)
			(xy 408.989784 -134.211822) (xy 408.968427 -134.231218) (xy 408.920968 -134.264017) (xy 408.869111 -134.289296)
			(xy 408.81404 -134.306479) (xy 408.757009 -134.315174) (xy 408.728164 -134.315708) (xy 408.700912 -134.315256)
			(xy 408.646963 -134.307494) (xy 408.594668 -134.292135) (xy 408.54509 -134.269489) (xy 408.49924 -134.240019)
			(xy 408.45805 -134.204324) (xy 408.422359 -134.163131) (xy 408.392893 -134.117278) (xy 408.370253 -134.067699)
			(xy 408.354898 -134.015402) (xy 408.347142 -133.961452) (xy 408.346656 -133.9342) (xy 402.915628 -133.9342)
			(xy 402.61413 -134.235698) (xy 402.606728 -134.242534) (xy 402.58813 -134.250243) (xy 402.578062 -134.250684)
			(xy 401.333462 -134.250684) (xy 401.323477 -134.251228) (xy 401.305054 -134.258949) (xy 401.297648 -134.26567)
			(xy 401.023582 -134.539736) (xy 401.016768 -134.547079) (xy 401.009036 -134.565543) (xy 401.008596 -134.57555)
			(xy 401.008596 -134.931404) (xy 407.260042 -134.931404) (xy 407.264113 -134.875782) (xy 407.276239 -134.821345)
			(xy 407.296162 -134.769254) (xy 407.323458 -134.720619) (xy 407.357544 -134.676476) (xy 407.397693 -134.637767)
			(xy 407.443051 -134.605316) (xy 407.492651 -134.579815) (xy 407.545435 -134.561808) (xy 407.600278 -134.551678)
			(xy 407.656012 -134.549641) (xy 407.711449 -134.555741) (xy 407.765406 -134.569847) (xy 407.816735 -134.591659)
			(xy 407.864341 -134.620713) (xy 407.907209 -134.656388) (xy 407.944426 -134.697925) (xy 407.975199 -134.744438)
			(xy 407.998871 -134.794935) (xy 408.014939 -134.848342) (xy 408.023059 -134.903518) (xy 408.023568 -134.931404)
			(xy 408.023059 -134.95929) (xy 408.014939 -135.014466) (xy 407.998871 -135.067873) (xy 407.992236 -135.082026)
			(xy 409.362908 -135.082026) (xy 409.366979 -135.026404) (xy 409.379105 -134.971967) (xy 409.399028 -134.919876)
			(xy 409.426324 -134.871241) (xy 409.46041 -134.827098) (xy 409.500559 -134.788389) (xy 409.545917 -134.755938)
			(xy 409.595517 -134.730437) (xy 409.648301 -134.71243) (xy 409.703144 -134.7023) (xy 409.758878 -134.700263)
			(xy 409.814315 -134.706363) (xy 409.868272 -134.720469) (xy 409.919601 -134.742281) (xy 409.967207 -134.771335)
			(xy 410.010075 -134.80701) (xy 410.047292 -134.848547) (xy 410.078065 -134.89506) (xy 410.101737 -134.945557)
			(xy 410.117805 -134.998964) (xy 410.125925 -135.05414) (xy 410.126434 -135.082026) (xy 410.125925 -135.109912)
			(xy 410.117805 -135.165088) (xy 410.101737 -135.218495) (xy 410.078065 -135.268992) (xy 410.047292 -135.315505)
			(xy 410.010075 -135.357042) (xy 409.967207 -135.392717) (xy 409.919601 -135.421771) (xy 409.868272 -135.443583)
			(xy 409.814315 -135.457689) (xy 409.758878 -135.463789) (xy 409.703144 -135.461752) (xy 409.648301 -135.451622)
			(xy 409.595517 -135.433615) (xy 409.545917 -135.408114) (xy 409.500559 -135.375663) (xy 409.46041 -135.336954)
			(xy 409.426324 -135.292811) (xy 409.399028 -135.244176) (xy 409.379105 -135.192085) (xy 409.366979 -135.137648)
			(xy 409.362908 -135.082026) (xy 407.992236 -135.082026) (xy 407.975199 -135.11837) (xy 407.944426 -135.164883)
			(xy 407.907209 -135.20642) (xy 407.864341 -135.242095) (xy 407.816735 -135.271149) (xy 407.765406 -135.292961)
			(xy 407.711449 -135.307067) (xy 407.656012 -135.313167) (xy 407.600278 -135.31113) (xy 407.545435 -135.301)
			(xy 407.492651 -135.282993) (xy 407.443051 -135.257492) (xy 407.397693 -135.225041) (xy 407.357544 -135.186332)
			(xy 407.323458 -135.142189) (xy 407.296162 -135.093554) (xy 407.276239 -135.041463) (xy 407.264113 -134.987026)
			(xy 407.260042 -134.931404) (xy 401.008596 -134.931404) (xy 401.008596 -136.231376) (xy 405.077928 -136.231376)
			(xy 405.081999 -136.175754) (xy 405.094125 -136.121317) (xy 405.114048 -136.069226) (xy 405.141344 -136.020591)
			(xy 405.17543 -135.976448) (xy 405.215579 -135.937739) (xy 405.260937 -135.905288) (xy 405.310537 -135.879787)
			(xy 405.363321 -135.86178) (xy 405.418164 -135.85165) (xy 405.473898 -135.849613) (xy 405.529335 -135.855713)
			(xy 405.583292 -135.869819) (xy 405.634621 -135.891631) (xy 405.682227 -135.920685) (xy 405.725095 -135.95636)
			(xy 405.762312 -135.997897) (xy 405.793085 -136.04441) (xy 405.816757 -136.094907) (xy 405.832825 -136.148314)
			(xy 405.840945 -136.20349) (xy 405.841454 -136.231376) (xy 407.285696 -136.231376) (xy 407.289767 -136.175754)
			(xy 407.301893 -136.121317) (xy 407.321816 -136.069226) (xy 407.349112 -136.020591) (xy 407.383198 -135.976448)
			(xy 407.423347 -135.937739) (xy 407.468705 -135.905288) (xy 407.518305 -135.879787) (xy 407.571089 -135.86178)
			(xy 407.625932 -135.85165) (xy 407.681666 -135.849613) (xy 407.737103 -135.855713) (xy 407.79106 -135.869819)
			(xy 407.842389 -135.891631) (xy 407.889995 -135.920685) (xy 407.932863 -135.95636) (xy 407.97008 -135.997897)
			(xy 408.000853 -136.04441) (xy 408.024525 -136.094907) (xy 408.040593 -136.148314) (xy 408.048713 -136.20349)
			(xy 408.049222 -136.231376) (xy 408.048713 -136.259262) (xy 408.040593 -136.314438) (xy 408.024525 -136.367845)
			(xy 408.000853 -136.418342) (xy 407.97008 -136.464855) (xy 407.932863 -136.506392) (xy 407.889995 -136.542067)
			(xy 407.842389 -136.571121) (xy 407.79106 -136.592933) (xy 407.737103 -136.607039) (xy 407.681666 -136.613139)
			(xy 407.625932 -136.611102) (xy 407.571089 -136.600972) (xy 407.518305 -136.582965) (xy 407.468705 -136.557464)
			(xy 407.423347 -136.525013) (xy 407.383198 -136.486304) (xy 407.349112 -136.442161) (xy 407.321816 -136.393526)
			(xy 407.301893 -136.341435) (xy 407.289767 -136.286998) (xy 407.285696 -136.231376) (xy 405.841454 -136.231376)
			(xy 405.840945 -136.259262) (xy 405.832825 -136.314438) (xy 405.816757 -136.367845) (xy 405.793085 -136.418342)
			(xy 405.762312 -136.464855) (xy 405.725095 -136.506392) (xy 405.682227 -136.542067) (xy 405.634621 -136.571121)
			(xy 405.583292 -136.592933) (xy 405.529335 -136.607039) (xy 405.473898 -136.613139) (xy 405.418164 -136.611102)
			(xy 405.363321 -136.600972) (xy 405.310537 -136.582965) (xy 405.260937 -136.557464) (xy 405.215579 -136.525013)
			(xy 405.17543 -136.486304) (xy 405.141344 -136.442161) (xy 405.114048 -136.393526) (xy 405.094125 -136.341435)
			(xy 405.081999 -136.286998) (xy 405.077928 -136.231376) (xy 401.008596 -136.231376) (xy 401.008596 -137.87628)
			(xy 410.808168 -137.87628) (xy 410.812239 -137.820658) (xy 410.824365 -137.766221) (xy 410.844288 -137.71413)
			(xy 410.871584 -137.665495) (xy 410.90567 -137.621352) (xy 410.945819 -137.582643) (xy 410.991177 -137.550192)
			(xy 411.040777 -137.524691) (xy 411.093561 -137.506684) (xy 411.148404 -137.496554) (xy 411.204138 -137.494517)
			(xy 411.259575 -137.500617) (xy 411.313532 -137.514723) (xy 411.364861 -137.536535) (xy 411.412467 -137.565589)
			(xy 411.455335 -137.601264) (xy 411.492552 -137.642801) (xy 411.523325 -137.689314) (xy 411.546997 -137.739811)
			(xy 411.563065 -137.793218) (xy 411.571185 -137.848394) (xy 411.571694 -137.87628) (xy 411.571185 -137.904166)
			(xy 411.563065 -137.959342) (xy 411.546997 -138.012749) (xy 411.523325 -138.063246) (xy 411.492552 -138.109759)
			(xy 411.455335 -138.151296) (xy 411.412467 -138.186971) (xy 411.364861 -138.216025) (xy 411.313532 -138.237837)
			(xy 411.259575 -138.251943) (xy 411.204138 -138.258043) (xy 411.148404 -138.256006) (xy 411.093561 -138.245876)
			(xy 411.040777 -138.227869) (xy 410.991177 -138.202368) (xy 410.945819 -138.169917) (xy 410.90567 -138.131208)
			(xy 410.871584 -138.087065) (xy 410.844288 -138.03843) (xy 410.824365 -137.986339) (xy 410.812239 -137.931902)
			(xy 410.808168 -137.87628) (xy 401.008596 -137.87628) (xy 401.008596 -139.47267) (xy 410.103318 -139.47267)
			(xy 410.107389 -139.417048) (xy 410.119515 -139.362611) (xy 410.139438 -139.31052) (xy 410.166734 -139.261885)
			(xy 410.20082 -139.217742) (xy 410.240969 -139.179033) (xy 410.286327 -139.146582) (xy 410.335927 -139.121081)
			(xy 410.388711 -139.103074) (xy 410.443554 -139.092944) (xy 410.499288 -139.090907) (xy 410.554725 -139.097007)
			(xy 410.608682 -139.111113) (xy 410.660011 -139.132925) (xy 410.707617 -139.161979) (xy 410.750485 -139.197654)
			(xy 410.787702 -139.239191) (xy 410.818475 -139.285704) (xy 410.842147 -139.336201) (xy 410.858215 -139.389608)
			(xy 410.866335 -139.444784) (xy 410.866844 -139.47267) (xy 410.866335 -139.500556) (xy 410.858215 -139.555732)
			(xy 410.842147 -139.609139) (xy 410.818475 -139.659636) (xy 410.787702 -139.706149) (xy 410.750485 -139.747686)
			(xy 410.707617 -139.783361) (xy 410.660011 -139.812415) (xy 410.608682 -139.834227) (xy 410.554725 -139.848333)
			(xy 410.499288 -139.854433) (xy 410.443554 -139.852396) (xy 410.388711 -139.842266) (xy 410.335927 -139.824259)
			(xy 410.286327 -139.798758) (xy 410.240969 -139.766307) (xy 410.20082 -139.727598) (xy 410.166734 -139.683455)
			(xy 410.139438 -139.63482) (xy 410.119515 -139.582729) (xy 410.107389 -139.528292) (xy 410.103318 -139.47267)
			(xy 401.008596 -139.47267) (xy 401.008596 -141.316456) (xy 410.132274 -141.316456) (xy 410.136345 -141.260834)
			(xy 410.148471 -141.206397) (xy 410.168394 -141.154306) (xy 410.19569 -141.105671) (xy 410.229776 -141.061528)
			(xy 410.269925 -141.022819) (xy 410.315283 -140.990368) (xy 410.364883 -140.964867) (xy 410.417667 -140.94686)
			(xy 410.47251 -140.93673) (xy 410.528244 -140.934693) (xy 410.583681 -140.940793) (xy 410.637638 -140.954899)
			(xy 410.688967 -140.976711) (xy 410.736573 -141.005765) (xy 410.779441 -141.04144) (xy 410.816658 -141.082977)
			(xy 410.847431 -141.12949) (xy 410.871103 -141.179987) (xy 410.887171 -141.233394) (xy 410.895291 -141.28857)
			(xy 410.8958 -141.316456) (xy 410.895291 -141.344342) (xy 410.887171 -141.399518) (xy 410.871103 -141.452925)
			(xy 410.847431 -141.503422) (xy 410.816658 -141.549935) (xy 410.779441 -141.591472) (xy 410.736573 -141.627147)
			(xy 410.688967 -141.656201) (xy 410.637638 -141.678013) (xy 410.583681 -141.692119) (xy 410.528244 -141.698219)
			(xy 410.47251 -141.696182) (xy 410.417667 -141.686052) (xy 410.364883 -141.668045) (xy 410.315283 -141.642544)
			(xy 410.269925 -141.610093) (xy 410.229776 -141.571384) (xy 410.19569 -141.527241) (xy 410.168394 -141.478606)
			(xy 410.148471 -141.426515) (xy 410.136345 -141.372078) (xy 410.132274 -141.316456) (xy 401.008596 -141.316456)
			(xy 401.008596 -142.558262) (xy 415.08502 -142.558262) (xy 415.089091 -142.50264) (xy 415.101217 -142.448203)
			(xy 415.12114 -142.396112) (xy 415.148436 -142.347477) (xy 415.182522 -142.303334) (xy 415.222671 -142.264625)
			(xy 415.268029 -142.232174) (xy 415.317629 -142.206673) (xy 415.370413 -142.188666) (xy 415.425256 -142.178536)
			(xy 415.48099 -142.176499) (xy 415.536427 -142.182599) (xy 415.590384 -142.196705) (xy 415.641713 -142.218517)
			(xy 415.689319 -142.247571) (xy 415.732187 -142.283246) (xy 415.769404 -142.324783) (xy 415.800177 -142.371296)
			(xy 415.823849 -142.421793) (xy 415.839917 -142.4752) (xy 415.848037 -142.530376) (xy 415.848546 -142.558262)
			(xy 415.848037 -142.586148) (xy 415.839917 -142.641324) (xy 415.823849 -142.694731) (xy 415.800177 -142.745228)
			(xy 415.769404 -142.791741) (xy 415.732187 -142.833278) (xy 415.689319 -142.868953) (xy 415.641713 -142.898007)
			(xy 415.590384 -142.919819) (xy 415.536427 -142.933925) (xy 415.48099 -142.940025) (xy 415.425256 -142.937988)
			(xy 415.370413 -142.927858) (xy 415.317629 -142.909851) (xy 415.268029 -142.88435) (xy 415.222671 -142.851899)
			(xy 415.182522 -142.81319) (xy 415.148436 -142.769047) (xy 415.12114 -142.720412) (xy 415.101217 -142.668321)
			(xy 415.089091 -142.613884) (xy 415.08502 -142.558262) (xy 401.008596 -142.558262) (xy 401.008596 -144.50441)
			(xy 401.008129 -144.528987) (xy 401.00047 -144.57754) (xy 400.985311 -144.624297) (xy 400.963025 -144.668108)
			(xy 400.934161 -144.707893) (xy 400.917156 -144.725644) (xy 399.779998 -145.862802) (xy 399.77314 -145.875248)
			(xy 399.771616 -145.882614) (xy 399.764998 -145.910625) (xy 399.744476 -145.964396) (xy 399.716107 -146.014473)
			(xy 399.680535 -146.059719) (xy 399.63857 -146.099107) (xy 399.591162 -146.131742) (xy 399.539389 -146.156884)
			(xy 399.484426 -146.17396) (xy 399.427521 -146.182585) (xy 399.398744 -146.183096) (xy 399.371489 -146.182636)
			(xy 399.317534 -146.174884) (xy 399.265232 -146.159531) (xy 399.215647 -146.136891) (xy 399.169789 -146.107424)
			(xy 399.128592 -146.07173) (xy 399.092895 -146.030536) (xy 399.063424 -145.984681) (xy 399.04078 -145.935098)
			(xy 399.025423 -145.882797) (xy 399.017667 -145.828843) (xy 399.017236 -145.801588) (xy 399.01776 -145.772813)
			(xy 399.026403 -145.715914) (xy 399.04349 -145.660958) (xy 399.068635 -145.609191) (xy 399.101267 -145.561786)
			(xy 399.140647 -145.519817) (xy 399.185881 -145.484237) (xy 399.235945 -145.455852) (xy 399.289703 -145.435305)
			(xy 399.317718 -145.428716) (xy 399.325084 -145.427192) (xy 399.33753 -145.420334) (xy 400.368262 -144.389602)
			(xy 400.375077 -144.382259) (xy 400.382816 -144.363796) (xy 400.383248 -144.353788) (xy 400.383248 -138.784584)
			(xy 400.382822 -138.774538) (xy 400.375116 -138.755982) (xy 400.360886 -138.741796) (xy 400.351752 -138.737594)
			(xy 400.337274 -138.731498) (xy 400.307556 -138.737594) (xy 400.046952 -138.998198) (xy 400.040094 -139.010644)
			(xy 400.03857 -139.01801) (xy 400.031953 -139.046023) (xy 400.011432 -139.099799) (xy 399.983065 -139.149881)
			(xy 399.947495 -139.195132) (xy 399.905529 -139.234526) (xy 399.858122 -139.267168) (xy 399.806349 -139.292316)
			(xy 399.751384 -139.309401) (xy 399.694477 -139.318033) (xy 399.665698 -139.318492) (xy 399.638446 -139.318029)
			(xy 399.584496 -139.310271) (xy 399.532199 -139.294915) (xy 399.48262 -139.272272) (xy 399.436769 -139.242804)
			(xy 399.395577 -139.20711) (xy 399.359885 -139.165917) (xy 399.330419 -139.120064) (xy 399.307779 -139.070484)
			(xy 399.292425 -139.018187) (xy 399.28467 -138.964236) (xy 399.28419 -138.936984) (xy 399.284714 -138.90821)
			(xy 399.293358 -138.851314) (xy 399.310447 -138.796362) (xy 399.335593 -138.744598) (xy 399.368227 -138.697197)
			(xy 399.407608 -138.655234) (xy 399.452844 -138.61966) (xy 399.502909 -138.591281) (xy 399.556667 -138.570742)
			(xy 399.584672 -138.564112) (xy 399.592038 -138.562588) (xy 399.604484 -138.55573) (xy 399.681446 -138.478768)
			(xy 399.688123 -138.471358) (xy 399.695707 -138.452931) (xy 399.695694 -138.433004) (xy 399.688087 -138.414587)
			(xy 399.681446 -138.40714) (xy 399.673826 -138.39952) (xy 399.65376 -138.391646) (xy 399.643092 -138.392154)
			(xy 399.624804 -138.392662) (xy 399.597552 -138.392199) (xy 399.543603 -138.384442) (xy 399.491308 -138.369086)
			(xy 399.44173 -138.346443) (xy 399.39588 -138.316974) (xy 399.35469 -138.28128) (xy 399.319 -138.240087)
			(xy 399.289537 -138.194233) (xy 399.266899 -138.144653) (xy 399.251549 -138.092356) (xy 399.243798 -138.038406)
			(xy 399.243296 -138.011154) (xy 399.243765 -137.983583) (xy 399.251673 -137.929013) (xy 399.259044 -137.902442)
			(xy 399.261076 -137.89533) (xy 399.261076 -135.979662) (xy 399.260598 -135.969396) (xy 399.252539 -135.950511)
			(xy 399.237724 -135.936294) (xy 399.22831 -135.932164) (xy 399.124424 -135.892794) (xy 399.093944 -135.900414)
			(xy 399.08353 -135.912352) (xy 399.065338 -135.932295) (xy 399.024302 -135.967365) (xy 398.978732 -135.996299)
			(xy 398.929538 -136.01852) (xy 398.877703 -136.033584) (xy 398.824262 -136.04119) (xy 398.797272 -136.041638)
			(xy 398.77002 -136.04115) (xy 398.716071 -136.03339) (xy 398.663775 -136.018031) (xy 398.614198 -135.995387)
			(xy 398.568347 -135.965917) (xy 398.527157 -135.930223) (xy 398.491466 -135.88903) (xy 398.462 -135.843178)
			(xy 398.439359 -135.793598) (xy 398.424004 -135.741302) (xy 398.416248 -135.687352) (xy 398.416248 -135.632848)
			(xy 398.424004 -135.578898) (xy 398.439359 -135.526602) (xy 398.462 -135.477022) (xy 398.491466 -135.43117)
			(xy 398.527157 -135.389977) (xy 398.568347 -135.354283) (xy 398.614198 -135.324813) (xy 398.663775 -135.302169)
			(xy 398.716071 -135.28681) (xy 398.77002 -135.27905) (xy 398.797272 -135.278622) (xy 398.824262 -135.279087)
			(xy 398.877703 -135.28669) (xy 398.92954 -135.30175) (xy 398.978737 -135.323964) (xy 399.024312 -135.35289)
			(xy 399.065356 -135.38795) (xy 399.08353 -135.407908) (xy 399.093944 -135.419846) (xy 399.124424 -135.427466)
			(xy 399.22831 -135.388096) (xy 399.23775 -135.384013) (xy 399.252571 -135.369778) (xy 399.260626 -135.350873)
			(xy 399.261076 -135.340598) (xy 399.261076 -134.301484) (xy 399.260653 -134.291467) (xy 399.252979 -134.272959)
			(xy 399.238807 -134.258798) (xy 399.220294 -134.251139) (xy 399.210276 -134.250684) (xy 396.373096 -134.250684)
			(xy 396.363026 -134.25026) (xy 396.344425 -134.242543) (xy 396.337028 -134.235698) (xy 396.129764 -134.028434)
			(xy 396.122365 -134.021589) (xy 396.103767 -134.013863) (xy 396.093696 -134.013448) (xy 388.405116 -134.013448)
			(xy 388.395121 -134.013943) (xy 388.376645 -134.021579) (xy 388.362463 -134.03567) (xy 388.358126 -134.04469)
			(xy 388.352284 -134.059168) (xy 388.358126 -134.08914) (xy 389.066401 -134.797292) (xy 393.769848 -134.797292)
			(xy 393.773919 -134.74167) (xy 393.786045 -134.687233) (xy 393.805968 -134.635142) (xy 393.833264 -134.586507)
			(xy 393.86735 -134.542364) (xy 393.907499 -134.503655) (xy 393.952857 -134.471204) (xy 394.002457 -134.445703)
			(xy 394.055241 -134.427696) (xy 394.110084 -134.417566) (xy 394.165818 -134.415529) (xy 394.221255 -134.421629)
			(xy 394.275212 -134.435735) (xy 394.326541 -134.457547) (xy 394.374147 -134.486601) (xy 394.417015 -134.522276)
			(xy 394.454232 -134.563813) (xy 394.485005 -134.610326) (xy 394.508677 -134.660823) (xy 394.524745 -134.71423)
			(xy 394.532865 -134.769406) (xy 394.533374 -134.797292) (xy 394.532865 -134.825178) (xy 394.524745 -134.880354)
			(xy 394.508677 -134.933761) (xy 394.485005 -134.984258) (xy 394.454232 -135.030771) (xy 394.417015 -135.072308)
			(xy 394.374147 -135.107983) (xy 394.326541 -135.137037) (xy 394.275212 -135.158849) (xy 394.221255 -135.172955)
			(xy 394.165818 -135.179055) (xy 394.110084 -135.177018) (xy 394.055241 -135.166888) (xy 394.002457 -135.148881)
			(xy 393.952857 -135.12338) (xy 393.907499 -135.090929) (xy 393.86735 -135.05222) (xy 393.833264 -135.008077)
			(xy 393.805968 -134.959442) (xy 393.786045 -134.907351) (xy 393.773919 -134.852914) (xy 393.769848 -134.797292)
			(xy 389.066401 -134.797292) (xy 389.825484 -135.556244) (xy 389.842537 -135.573955) (xy 389.87142 -135.613743)
			(xy 389.893717 -135.657561) (xy 389.908879 -135.704329) (xy 389.916533 -135.752895) (xy 389.916924 -135.777478)
			(xy 389.916924 -137.456926) (xy 392.339828 -137.456926) (xy 392.343899 -137.401304) (xy 392.356025 -137.346867)
			(xy 392.375948 -137.294776) (xy 392.403244 -137.246141) (xy 392.43733 -137.201998) (xy 392.477479 -137.163289)
			(xy 392.522837 -137.130838) (xy 392.572437 -137.105337) (xy 392.625221 -137.08733) (xy 392.680064 -137.0772)
			(xy 392.735798 -137.075163) (xy 392.791235 -137.081263) (xy 392.845192 -137.095369) (xy 392.896521 -137.117181)
			(xy 392.944127 -137.146235) (xy 392.986995 -137.18191) (xy 393.024212 -137.223447) (xy 393.054985 -137.26996)
			(xy 393.078657 -137.320457) (xy 393.094725 -137.373864) (xy 393.102845 -137.42904) (xy 393.103354 -137.456926)
			(xy 393.102845 -137.484812) (xy 393.094725 -137.539988) (xy 393.078657 -137.593395) (xy 393.054985 -137.643892)
			(xy 393.024212 -137.690405) (xy 392.986995 -137.731942) (xy 392.944127 -137.767617) (xy 392.896521 -137.796671)
			(xy 392.845192 -137.818483) (xy 392.791235 -137.832589) (xy 392.735798 -137.838689) (xy 392.680064 -137.836652)
			(xy 392.625221 -137.826522) (xy 392.572437 -137.808515) (xy 392.522837 -137.783014) (xy 392.477479 -137.750563)
			(xy 392.43733 -137.711854) (xy 392.403244 -137.667711) (xy 392.375948 -137.619076) (xy 392.356025 -137.566985)
			(xy 392.343899 -137.512548) (xy 392.339828 -137.456926) (xy 389.916924 -137.456926) (xy 389.916924 -138.077702)
			(xy 390.700004 -138.077702) (xy 390.704075 -138.02208) (xy 390.716201 -137.967643) (xy 390.736124 -137.915552)
			(xy 390.76342 -137.866917) (xy 390.797506 -137.822774) (xy 390.837655 -137.784065) (xy 390.883013 -137.751614)
			(xy 390.932613 -137.726113) (xy 390.985397 -137.708106) (xy 391.04024 -137.697976) (xy 391.095974 -137.695939)
			(xy 391.151411 -137.702039) (xy 391.205368 -137.716145) (xy 391.256697 -137.737957) (xy 391.304303 -137.767011)
			(xy 391.347171 -137.802686) (xy 391.384388 -137.844223) (xy 391.415161 -137.890736) (xy 391.438833 -137.941233)
			(xy 391.454901 -137.99464) (xy 391.463021 -138.049816) (xy 391.46353 -138.077702) (xy 391.463021 -138.105588)
			(xy 391.454901 -138.160764) (xy 391.438833 -138.214171) (xy 391.415161 -138.264668) (xy 391.384388 -138.311181)
			(xy 391.347171 -138.352718) (xy 391.304303 -138.388393) (xy 391.256697 -138.417447) (xy 391.205368 -138.439259)
			(xy 391.151411 -138.453365) (xy 391.095974 -138.459465) (xy 391.04024 -138.457428) (xy 390.985397 -138.447298)
			(xy 390.932613 -138.429291) (xy 390.883013 -138.40379) (xy 390.837655 -138.371339) (xy 390.797506 -138.33263)
			(xy 390.76342 -138.288487) (xy 390.736124 -138.239852) (xy 390.716201 -138.187761) (xy 390.704075 -138.133324)
			(xy 390.700004 -138.077702) (xy 389.916924 -138.077702) (xy 389.916924 -140.343128) (xy 389.917467 -140.353113)
			(xy 389.92519 -140.371535) (xy 389.93191 -140.378942) (xy 391.143236 -141.590268) (xy 391.155682 -141.597126)
			(xy 391.163048 -141.59865) (xy 391.191058 -141.605269) (xy 391.244828 -141.625794) (xy 391.294904 -141.654165)
			(xy 391.340149 -141.689736) (xy 391.379537 -141.731702) (xy 391.412172 -141.779108) (xy 391.437315 -141.83088)
			(xy 391.454395 -141.885841) (xy 391.463023 -141.942745) (xy 391.46353 -141.971522) (xy 391.463043 -141.998773)
			(xy 391.455284 -142.052719) (xy 391.439927 -142.105013) (xy 391.417285 -142.154589) (xy 391.387818 -142.200438)
			(xy 391.352127 -142.241627) (xy 391.310938 -142.277318) (xy 391.265089 -142.306785) (xy 391.215513 -142.329427)
			(xy 391.163219 -142.344784) (xy 391.109273 -142.352543) (xy 391.082022 -142.35303) (xy 391.05325 -142.352501)
			(xy 390.99636 -142.34385) (xy 390.941414 -142.326756) (xy 390.889657 -142.301606) (xy 390.842263 -142.268971)
			(xy 390.800305 -142.22959) (xy 390.764736 -142.184356) (xy 390.736361 -142.134295) (xy 390.715823 -142.080541)
			(xy 390.70915 -142.052548) (xy 390.707626 -142.045182) (xy 390.700768 -142.032736) (xy 389.886952 -141.218666)
			(xy 389.880008 -141.212368) (xy 389.862866 -141.204823) (xy 389.844158 -141.203928) (xy 389.835136 -141.206474)
			(xy 389.73506 -141.239494) (xy 389.716772 -141.261338) (xy 389.714486 -141.275562) (xy 389.710019 -141.302339)
			(xy 389.694496 -141.354357) (xy 389.671749 -141.403647) (xy 389.642239 -141.449211) (xy 389.606562 -141.490126)
			(xy 389.565441 -141.525565) (xy 389.519707 -141.554811) (xy 389.470287 -141.577272) (xy 389.418179 -141.592493)
			(xy 389.364439 -141.600167) (xy 389.337296 -141.600682) (xy 389.310047 -141.600196) (xy 389.256103 -141.592439)
			(xy 389.203813 -141.577085) (xy 389.154239 -141.554445) (xy 389.108393 -141.524981) (xy 389.067206 -141.489291)
			(xy 389.031517 -141.448104) (xy 389.002053 -141.402257) (xy 388.979414 -141.352684) (xy 388.96406 -141.300393)
			(xy 388.956304 -141.246449) (xy 388.956304 -141.191951) (xy 388.96406 -141.138007) (xy 388.979414 -141.085716)
			(xy 389.002053 -141.036143) (xy 389.031517 -140.990296) (xy 389.067206 -140.949109) (xy 389.108393 -140.913419)
			(xy 389.154239 -140.883955) (xy 389.203813 -140.861315) (xy 389.256103 -140.845961) (xy 389.310047 -140.838204)
			(xy 389.337296 -140.837666) (xy 389.348053 -140.837769) (xy 389.369528 -140.83904) (xy 389.380222 -140.840206)
			(xy 389.391906 -140.841476) (xy 389.413496 -140.833856) (xy 389.421878 -140.825474) (xy 389.428572 -140.818027)
			(xy 389.43618 -140.799526) (xy 389.436189 -140.779521) (xy 389.428598 -140.761013) (xy 389.421878 -140.753592)
			(xy 389.383016 -140.714984) (xy 389.365967 -140.697271) (xy 389.337094 -140.657482) (xy 389.314807 -140.613663)
			(xy 389.299655 -140.566895) (xy 389.292012 -140.518331) (xy 389.291576 -140.49375) (xy 389.291576 -135.9281)
			(xy 389.291038 -135.918113) (xy 389.283322 -135.899683) (xy 389.27659 -135.892286) (xy 387.661404 -134.2771)
			(xy 387.653995 -134.270415) (xy 387.635559 -134.262832) (xy 387.62559 -134.262368) (xy 386.871718 -134.262368)
			(xy 386.861756 -134.262856) (xy 386.843333 -134.270444) (xy 386.835904 -134.2771) (xy 386.798312 -134.314692)
			(xy 386.791463 -134.322089) (xy 386.783724 -134.340687) (xy 386.783326 -134.35076) (xy 386.783326 -135.732012)
			(xy 386.783752 -135.742081) (xy 386.791472 -135.76068) (xy 386.798312 -135.76808) (xy 387.638036 -136.607804)
			(xy 387.644889 -136.6152) (xy 387.652632 -136.633798) (xy 387.653022 -136.643872) (xy 387.653022 -141.945106)
			(xy 387.653418 -141.954892) (xy 387.660684 -141.97306) (xy 387.674259 -141.987152) (xy 387.682994 -141.991588)
			(xy 387.781038 -142.035784) (xy 387.810756 -142.031212) (xy 387.821932 -142.021306) (xy 387.842962 -142.003366)
			(xy 387.88922 -141.973107) (xy 387.939359 -141.949836) (xy 387.992329 -141.93404) (xy 388.047024 -141.926048)
			(xy 388.074662 -141.925548) (xy 388.10192 -141.926008) (xy 388.155881 -141.933762) (xy 388.20819 -141.949116)
			(xy 388.25778 -141.971759) (xy 388.303644 -142.00123) (xy 388.344846 -142.036928) (xy 388.380547 -142.078126)
			(xy 388.410022 -142.123986) (xy 388.43267 -142.173575) (xy 388.44803 -142.225882) (xy 388.455789 -142.279842)
			(xy 388.455789 -142.334358) (xy 388.44803 -142.388318) (xy 388.43267 -142.440625) (xy 388.410022 -142.490214)
			(xy 388.380547 -142.536074) (xy 388.344846 -142.577272) (xy 388.303644 -142.61297) (xy 388.25778 -142.642441)
			(xy 388.20819 -142.665084) (xy 388.155881 -142.680438) (xy 388.10192 -142.688192) (xy 388.074662 -142.688564)
			(xy 388.047022 -142.688077) (xy 387.992321 -142.680102) (xy 387.939344 -142.664312) (xy 387.889203 -142.641036)
			(xy 387.84295 -142.610763) (xy 387.821932 -142.592806) (xy 387.810756 -142.5829) (xy 387.781038 -142.578328)
			(xy 387.682994 -142.622524) (xy 387.674262 -142.626951) (xy 387.660726 -142.641074) (xy 387.653434 -142.659225)
			(xy 387.653022 -142.669006) (xy 387.653022 -142.989046) (xy 388.931912 -142.989046) (xy 388.932398 -142.961795)
			(xy 388.940154 -142.907847) (xy 388.955509 -142.855552) (xy 388.978151 -142.805975) (xy 389.007617 -142.760125)
			(xy 389.043308 -142.718934) (xy 389.084499 -142.683243) (xy 389.130349 -142.653777) (xy 389.179926 -142.631135)
			(xy 389.232221 -142.61578) (xy 389.286169 -142.608024) (xy 389.340671 -142.608024) (xy 389.394619 -142.61578)
			(xy 389.446914 -142.631135) (xy 389.496491 -142.653777) (xy 389.542341 -142.683243) (xy 389.583532 -142.718934)
			(xy 389.619223 -142.760125) (xy 389.648689 -142.805975) (xy 389.671331 -142.855552) (xy 389.686686 -142.907847)
			(xy 389.694442 -142.961795) (xy 389.694928 -142.989046) (xy 389.69442 -143.008096) (xy 389.694231 -143.021559)
			(xy 389.699969 -143.047851) (xy 389.71237 -143.071735) (xy 389.730574 -143.091555) (xy 389.75332 -143.105937)
			(xy 389.779032 -143.113884) (xy 389.792464 -143.114776) (xy 389.819095 -143.116143) (xy 389.871619 -143.125347)
			(xy 389.922349 -143.141777) (xy 389.970296 -143.165112) (xy 390.014525 -143.194899) (xy 390.054174 -143.230556)
			(xy 390.08847 -143.271388) (xy 390.116745 -143.316598) (xy 390.138446 -143.365307) (xy 390.153152 -143.416563)
			(xy 390.160575 -143.469368) (xy 390.161018 -143.49603) (xy 390.160532 -143.523281) (xy 390.152776 -143.577229)
			(xy 390.137421 -143.629524) (xy 390.114779 -143.679101) (xy 390.085313 -143.724951) (xy 390.049622 -143.766142)
			(xy 390.008431 -143.801833) (xy 389.962581 -143.831299) (xy 389.913004 -143.853941) (xy 389.860709 -143.869296)
			(xy 389.806761 -143.877052) (xy 389.752259 -143.877052) (xy 389.698311 -143.869296) (xy 389.646016 -143.853941)
			(xy 389.596439 -143.831299) (xy 389.550589 -143.801833) (xy 389.509398 -143.766142) (xy 389.473707 -143.724951)
			(xy 389.444241 -143.679101) (xy 389.421599 -143.629524) (xy 389.406244 -143.577229) (xy 389.398488 -143.523281)
			(xy 389.398002 -143.49603) (xy 389.39851 -143.47698) (xy 389.398788 -143.463515) (xy 389.39304 -143.43721)
			(xy 389.380624 -143.413318) (xy 389.362401 -143.393496) (xy 389.339635 -143.379119) (xy 389.313906 -143.371183)
			(xy 389.300466 -143.3703) (xy 389.273829 -143.36902) (xy 389.221302 -143.359806) (xy 389.170569 -143.343366)
			(xy 389.122621 -143.32002) (xy 389.078391 -143.290224) (xy 389.038743 -143.254559) (xy 389.004448 -143.213719)
			(xy 388.976175 -143.1685) (xy 388.954476 -143.119785) (xy 388.939773 -143.068522) (xy 388.932353 -143.015711)
			(xy 388.931912 -142.989046) (xy 387.653022 -142.989046) (xy 387.653022 -143.402812) (xy 387.653448 -143.412881)
			(xy 387.661168 -143.43148) (xy 387.668008 -143.43888) (xy 390.64311 -146.413982) (xy 390.650508 -146.420829)
			(xy 390.669106 -146.428562) (xy 390.679178 -146.428968) (xy 393.246864 -146.428968) (xy 393.256916 -146.429471)
			(xy 393.275481 -146.437187) (xy 393.282932 -146.443954) (xy 393.608052 -146.769074) (xy 393.631166 -146.77644)
			(xy 393.643612 -146.774408) (xy 393.681357 -146.768349) (xy 393.757532 -146.761865) (xy 393.795758 -146.761454)
			(xy 393.839321 -146.761976) (xy 393.92604 -146.770373) (xy 394.011546 -146.787091) (xy 394.095042 -146.811976)
			(xy 394.175749 -146.844795) (xy 394.252916 -146.885243) (xy 394.325823 -146.932943) (xy 394.393792 -146.98745)
			(xy 394.456189 -147.048256) (xy 394.512432 -147.114795) (xy 394.561998 -147.186447) (xy 394.583666 -147.224242)
			(xy 394.592302 -147.239482) (xy 394.624052 -147.252944) (xy 394.736066 -147.223988) (xy 394.746733 -147.22056)
			(xy 394.763889 -147.206189) (xy 394.773338 -147.185903) (xy 394.773912 -147.174712) (xy 394.773912 -144.281144)
			(xy 394.773428 -144.271181) (xy 394.765844 -144.252753) (xy 394.75918 -144.24533) (xy 393.635738 -143.121888)
			(xy 393.62833 -143.115199) (xy 393.609894 -143.107605) (xy 393.599924 -143.107156) (xy 392.818112 -143.107156)
			(xy 392.80973 -143.10995) (xy 392.77851 -143.120457) (xy 392.713631 -143.131822) (xy 392.680698 -143.132556)
			(xy 392.653443 -143.13207) (xy 392.599489 -143.124312) (xy 392.547188 -143.108955) (xy 392.497605 -143.086311)
			(xy 392.451749 -143.056841) (xy 392.410554 -143.021145) (xy 392.374858 -142.979949) (xy 392.345388 -142.934093)
			(xy 392.322744 -142.88451) (xy 392.307387 -142.832209) (xy 392.29963 -142.778255) (xy 392.29963 -142.723745)
			(xy 392.307387 -142.669791) (xy 392.322744 -142.61749) (xy 392.345388 -142.567907) (xy 392.374858 -142.522051)
			(xy 392.410554 -142.480855) (xy 392.451749 -142.445159) (xy 392.497605 -142.415689) (xy 392.547188 -142.393045)
			(xy 392.599489 -142.377688) (xy 392.653443 -142.36993) (xy 392.680698 -142.36954) (xy 392.713632 -142.370255)
			(xy 392.778513 -142.381626) (xy 392.80973 -142.392146) (xy 392.818112 -142.39494) (xy 393.768326 -142.39494)
			(xy 393.796302 -142.395512) (xy 393.851559 -142.404305) (xy 393.904765 -142.421624) (xy 393.95461 -142.447042)
			(xy 393.999872 -142.479937) (xy 394.02004 -142.499334) (xy 395.381734 -143.861028) (xy 395.401165 -143.881169)
			(xy 395.434084 -143.926424) (xy 395.459513 -143.976274) (xy 395.476826 -144.029491) (xy 395.485595 -144.084761)
			(xy 395.486128 -144.112742) (xy 395.486128 -147.419822) (xy 396.174466 -147.419822) (xy 396.178537 -147.3642)
			(xy 396.190663 -147.309763) (xy 396.210586 -147.257672) (xy 396.237882 -147.209037) (xy 396.271968 -147.164894)
			(xy 396.312117 -147.126185) (xy 396.357475 -147.093734) (xy 396.407075 -147.068233) (xy 396.459859 -147.050226)
			(xy 396.514702 -147.040096) (xy 396.570436 -147.038059) (xy 396.625873 -147.044159) (xy 396.644322 -147.048982)
			(xy 399.016726 -147.048982) (xy 399.020797 -146.99336) (xy 399.032923 -146.938923) (xy 399.052846 -146.886832)
			(xy 399.080142 -146.838197) (xy 399.114228 -146.794054) (xy 399.154377 -146.755345) (xy 399.199735 -146.722894)
			(xy 399.249335 -146.697393) (xy 399.302119 -146.679386) (xy 399.356962 -146.669256) (xy 399.412696 -146.667219)
			(xy 399.468133 -146.673319) (xy 399.52209 -146.687425) (xy 399.573419 -146.709237) (xy 399.621025 -146.738291)
			(xy 399.663893 -146.773966) (xy 399.70111 -146.815503) (xy 399.731883 -146.862016) (xy 399.755555 -146.912513)
			(xy 399.771623 -146.96592) (xy 399.779743 -147.021096) (xy 399.780252 -147.048982) (xy 399.779743 -147.076868)
			(xy 399.771623 -147.132044) (xy 399.755555 -147.185451) (xy 399.731883 -147.235948) (xy 399.70111 -147.282461)
			(xy 399.663893 -147.323998) (xy 399.621025 -147.359673) (xy 399.573419 -147.388727) (xy 399.52209 -147.410539)
			(xy 399.468133 -147.424645) (xy 399.412696 -147.430745) (xy 399.356962 -147.428708) (xy 399.302119 -147.418578)
			(xy 399.249335 -147.400571) (xy 399.199735 -147.37507) (xy 399.154377 -147.342619) (xy 399.114228 -147.30391)
			(xy 399.080142 -147.259767) (xy 399.052846 -147.211132) (xy 399.032923 -147.159041) (xy 399.020797 -147.104604)
			(xy 399.016726 -147.048982) (xy 396.644322 -147.048982) (xy 396.67983 -147.058265) (xy 396.731159 -147.080077)
			(xy 396.778765 -147.109131) (xy 396.821633 -147.144806) (xy 396.85885 -147.186343) (xy 396.889623 -147.232856)
			(xy 396.913295 -147.283353) (xy 396.929363 -147.33676) (xy 396.937483 -147.391936) (xy 396.937992 -147.419822)
			(xy 396.937483 -147.447708) (xy 396.929363 -147.502884) (xy 396.913295 -147.556291) (xy 396.889623 -147.606788)
			(xy 396.85885 -147.653301) (xy 396.821633 -147.694838) (xy 396.778765 -147.730513) (xy 396.731159 -147.759567)
			(xy 396.67983 -147.781379) (xy 396.625873 -147.795485) (xy 396.570436 -147.801585) (xy 396.514702 -147.799548)
			(xy 396.459859 -147.789418) (xy 396.407075 -147.771411) (xy 396.357475 -147.74591) (xy 396.312117 -147.713459)
			(xy 396.271968 -147.67475) (xy 396.237882 -147.630607) (xy 396.210586 -147.581972) (xy 396.190663 -147.529881)
			(xy 396.178537 -147.475444) (xy 396.174466 -147.419822) (xy 395.486128 -147.419822) (xy 395.486128 -148.435151)
			(xy 396.37106 -148.435151) (xy 396.37106 -148.380649) (xy 396.378816 -148.326702) (xy 396.39417 -148.274408)
			(xy 396.416809 -148.22483) (xy 396.446274 -148.17898) (xy 396.481963 -148.137788) (xy 396.523151 -148.102095)
			(xy 396.568999 -148.072627) (xy 396.618574 -148.049982) (xy 396.670867 -148.034623) (xy 396.724813 -148.026862)
			(xy 396.752064 -148.026374) (xy 396.779321 -148.026858) (xy 396.833275 -148.034645) (xy 396.885571 -148.050035)
			(xy 396.935143 -148.072716) (xy 396.958312 -148.08708) (xy 396.97025 -148.094446) (xy 396.997174 -148.095716)
			(xy 397.100298 -148.04136) (xy 397.114522 -148.018246) (xy 397.11503 -148.004276) (xy 397.116244 -147.977504)
			(xy 397.125109 -147.924654) (xy 397.141284 -147.873565) (xy 397.16445 -147.825243) (xy 397.194152 -147.78064)
			(xy 397.229805 -147.740632) (xy 397.270707 -147.706009) (xy 397.316052 -147.677452) (xy 397.364948 -147.655523)
			(xy 397.416432 -147.640653) (xy 397.46949 -147.633136) (xy 397.496284 -147.632674) (xy 397.523534 -147.633193)
			(xy 397.57748 -147.640947) (xy 397.629773 -147.656299) (xy 397.679348 -147.678937) (xy 397.725198 -147.7084)
			(xy 397.766388 -147.744088) (xy 397.80208 -147.785275) (xy 397.831547 -147.831122) (xy 397.854189 -147.880696)
			(xy 397.869546 -147.932987) (xy 397.877304 -147.986932) (xy 397.877792 -148.014182) (xy 398.003776 -148.014182)
			(xy 398.004262 -147.986931) (xy 398.012018 -147.932983) (xy 398.027373 -147.880688) (xy 398.050015 -147.831111)
			(xy 398.079481 -147.785261) (xy 398.115172 -147.74407) (xy 398.156363 -147.708379) (xy 398.202213 -147.678913)
			(xy 398.25179 -147.656271) (xy 398.304085 -147.640916) (xy 398.358033 -147.63316) (xy 398.412535 -147.63316)
			(xy 398.466483 -147.640916) (xy 398.518778 -147.656271) (xy 398.568355 -147.678913) (xy 398.614205 -147.708379)
			(xy 398.655396 -147.74407) (xy 398.691087 -147.785261) (xy 398.720553 -147.831111) (xy 398.743195 -147.880688)
			(xy 398.75855 -147.932983) (xy 398.759269 -147.937982) (xy 399.016726 -147.937982) (xy 399.020797 -147.88236)
			(xy 399.032923 -147.827923) (xy 399.052846 -147.775832) (xy 399.080142 -147.727197) (xy 399.114228 -147.683054)
			(xy 399.154377 -147.644345) (xy 399.199735 -147.611894) (xy 399.249335 -147.586393) (xy 399.302119 -147.568386)
			(xy 399.356962 -147.558256) (xy 399.412696 -147.556219) (xy 399.468133 -147.562319) (xy 399.52209 -147.576425)
			(xy 399.573419 -147.598237) (xy 399.621025 -147.627291) (xy 399.663893 -147.662966) (xy 399.70111 -147.704503)
			(xy 399.731883 -147.751016) (xy 399.755555 -147.801513) (xy 399.771623 -147.85492) (xy 399.779743 -147.910096)
			(xy 399.780252 -147.937982) (xy 399.779743 -147.965868) (xy 399.771623 -148.021044) (xy 399.755555 -148.074451)
			(xy 399.731883 -148.124948) (xy 399.70111 -148.171461) (xy 399.663893 -148.212998) (xy 399.621025 -148.248673)
			(xy 399.573419 -148.277727) (xy 399.52209 -148.299539) (xy 399.468133 -148.313645) (xy 399.412696 -148.319745)
			(xy 399.356962 -148.317708) (xy 399.302119 -148.307578) (xy 399.249335 -148.289571) (xy 399.199735 -148.26407)
			(xy 399.154377 -148.231619) (xy 399.114228 -148.19291) (xy 399.080142 -148.148767) (xy 399.052846 -148.100132)
			(xy 399.032923 -148.048041) (xy 399.020797 -147.993604) (xy 399.016726 -147.937982) (xy 398.759269 -147.937982)
			(xy 398.766306 -147.986931) (xy 398.766792 -148.014182) (xy 398.766326 -148.041728) (xy 398.75841 -148.096247)
			(xy 398.742727 -148.149059) (xy 398.719603 -148.199062) (xy 398.68952 -148.245215) (xy 398.653105 -148.286555)
			(xy 398.632426 -148.304758) (xy 398.621425 -148.314681) (xy 398.605327 -148.339543) (xy 398.59703 -148.367976)
			(xy 398.597231 -148.397594) (xy 398.605912 -148.425912) (xy 398.622345 -148.450554) (xy 398.645152 -148.469452)
			(xy 398.658588 -148.4757) (xy 398.684099 -148.487036) (xy 398.731775 -148.516077) (xy 398.774711 -148.551755)
			(xy 398.811989 -148.593309) (xy 398.842815 -148.639851) (xy 398.86653 -148.690388) (xy 398.882628 -148.743841)
			(xy 398.890765 -148.79907) (xy 398.891252 -148.826982) (xy 399.016726 -148.826982) (xy 399.020797 -148.77136)
			(xy 399.032923 -148.716923) (xy 399.052846 -148.664832) (xy 399.080142 -148.616197) (xy 399.114228 -148.572054)
			(xy 399.154377 -148.533345) (xy 399.199735 -148.500894) (xy 399.249335 -148.475393) (xy 399.302119 -148.457386)
			(xy 399.356962 -148.447256) (xy 399.412696 -148.445219) (xy 399.468133 -148.451319) (xy 399.52209 -148.465425)
			(xy 399.573419 -148.487237) (xy 399.621025 -148.516291) (xy 399.663893 -148.551966) (xy 399.70111 -148.593503)
			(xy 399.731883 -148.640016) (xy 399.755555 -148.690513) (xy 399.771623 -148.74392) (xy 399.779743 -148.799096)
			(xy 399.780252 -148.826982) (xy 399.779743 -148.854868) (xy 399.771623 -148.910044) (xy 399.755555 -148.963451)
			(xy 399.731883 -149.013948) (xy 399.70111 -149.060461) (xy 399.663893 -149.101998) (xy 399.621025 -149.137673)
			(xy 399.573419 -149.166727) (xy 399.52209 -149.188539) (xy 399.468133 -149.202645) (xy 399.412696 -149.208745)
			(xy 399.356962 -149.206708) (xy 399.302119 -149.196578) (xy 399.249335 -149.178571) (xy 399.199735 -149.15307)
			(xy 399.154377 -149.120619) (xy 399.114228 -149.08191) (xy 399.080142 -149.037767) (xy 399.052846 -148.989132)
			(xy 399.032923 -148.937041) (xy 399.020797 -148.882604) (xy 399.016726 -148.826982) (xy 398.891252 -148.826982)
			(xy 398.890766 -148.854233) (xy 398.88301 -148.908181) (xy 398.867655 -148.960476) (xy 398.845013 -149.010053)
			(xy 398.815547 -149.055903) (xy 398.779856 -149.097094) (xy 398.738665 -149.132785) (xy 398.692815 -149.162251)
			(xy 398.643238 -149.184893) (xy 398.590943 -149.200248) (xy 398.536995 -149.208004) (xy 398.482493 -149.208004)
			(xy 398.428545 -149.200248) (xy 398.37625 -149.184893) (xy 398.326673 -149.162251) (xy 398.280823 -149.132785)
			(xy 398.239632 -149.097094) (xy 398.203941 -149.055903) (xy 398.174475 -149.010053) (xy 398.151833 -148.960476)
			(xy 398.136478 -148.908181) (xy 398.128722 -148.854233) (xy 398.128236 -148.826982) (xy 398.128737 -148.799437)
			(xy 398.136644 -148.744919) (xy 398.15232 -148.692108) (xy 398.175437 -148.642104) (xy 398.205514 -148.595951)
			(xy 398.241925 -148.55461) (xy 398.262602 -148.536406) (xy 398.273524 -148.526404) (xy 398.289618 -148.501561)
			(xy 398.297918 -148.473148) (xy 398.297727 -148.443548) (xy 398.289062 -148.415245) (xy 398.272649 -148.390611)
			(xy 398.249865 -148.371715) (xy 398.23644 -148.365464) (xy 398.210921 -148.354143) (xy 398.163243 -148.325102)
			(xy 398.120306 -148.289422) (xy 398.083027 -148.247867) (xy 398.052202 -148.201322) (xy 398.028489 -148.150782)
			(xy 398.012394 -148.097326) (xy 398.004261 -148.042095) (xy 398.003776 -148.014182) (xy 397.877792 -148.014182)
			(xy 397.877326 -148.041728) (xy 397.86941 -148.096247) (xy 397.853727 -148.149059) (xy 397.830603 -148.199062)
			(xy 397.80052 -148.245215) (xy 397.764105 -148.286555) (xy 397.743426 -148.304758) (xy 397.733266 -148.313394)
			(xy 397.724122 -148.338032) (xy 397.74114 -148.449792) (xy 397.757396 -148.47062) (xy 397.769588 -148.4757)
			(xy 397.795099 -148.487036) (xy 397.842775 -148.516077) (xy 397.885711 -148.551755) (xy 397.922989 -148.593309)
			(xy 397.953815 -148.639851) (xy 397.97753 -148.690388) (xy 397.993628 -148.743841) (xy 398.001765 -148.79907)
			(xy 398.002252 -148.826982) (xy 398.001766 -148.854233) (xy 397.99401 -148.908181) (xy 397.978655 -148.960476)
			(xy 397.956013 -149.010053) (xy 397.926547 -149.055903) (xy 397.890856 -149.097094) (xy 397.849665 -149.132785)
			(xy 397.803815 -149.162251) (xy 397.754238 -149.184893) (xy 397.701943 -149.200248) (xy 397.647995 -149.208004)
			(xy 397.593493 -149.208004) (xy 397.539545 -149.200248) (xy 397.48725 -149.184893) (xy 397.437673 -149.162251)
			(xy 397.391823 -149.132785) (xy 397.350632 -149.097094) (xy 397.314941 -149.055903) (xy 397.285475 -149.010053)
			(xy 397.262833 -148.960476) (xy 397.247478 -148.908181) (xy 397.239722 -148.854233) (xy 397.239236 -148.826982)
			(xy 397.239737 -148.799437) (xy 397.247644 -148.744919) (xy 397.26332 -148.692108) (xy 397.286437 -148.642104)
			(xy 397.316514 -148.595951) (xy 397.352925 -148.55461) (xy 397.373602 -148.536406) (xy 397.383762 -148.52777)
			(xy 397.392906 -148.503132) (xy 397.375888 -148.391372) (xy 397.359632 -148.370544) (xy 397.34744 -148.365464)
			(xy 397.332538 -148.35893) (xy 397.303797 -148.343668) (xy 397.290036 -148.334984) (xy 397.278098 -148.327618)
			(xy 397.251174 -148.326348) (xy 397.14805 -148.380704) (xy 397.133826 -148.403818) (xy 397.133318 -148.417788)
			(xy 397.132213 -148.444566) (xy 397.123338 -148.497423) (xy 397.107153 -148.548516) (xy 397.083975 -148.596842)
			(xy 397.054262 -148.641447) (xy 397.018598 -148.681455) (xy 396.977685 -148.716077) (xy 396.932329 -148.744631)
			(xy 396.883423 -148.766557) (xy 396.831929 -148.781421) (xy 396.778862 -148.788931) (xy 396.752064 -148.78939)
			(xy 396.724813 -148.788938) (xy 396.670867 -148.781177) (xy 396.618574 -148.765818) (xy 396.568999 -148.743173)
			(xy 396.523151 -148.713705) (xy 396.481963 -148.678012) (xy 396.446274 -148.63682) (xy 396.416809 -148.59097)
			(xy 396.39417 -148.541392) (xy 396.378816 -148.489098) (xy 396.37106 -148.435151) (xy 395.486128 -148.435151)
			(xy 395.486128 -148.626068) (xy 395.486615 -148.636029) (xy 395.494206 -148.654451) (xy 395.50086 -148.661882)
			(xy 396.197328 -149.35835) (xy 396.204694 -149.364994) (xy 396.222995 -149.372602) (xy 396.242813 -149.372757)
			(xy 396.252192 -149.369526) (xy 396.353284 -149.328886) (xy 396.370302 -149.304248) (xy 396.370556 -149.2885)
			(xy 396.371601 -149.26164) (xy 396.380304 -149.208596) (xy 396.396367 -149.157299) (xy 396.419474 -149.108766)
			(xy 396.449166 -149.063957) (xy 396.484854 -149.023761) (xy 396.525832 -148.988973) (xy 396.571289 -148.960283)
			(xy 396.620323 -148.938259) (xy 396.671963 -148.923338) (xy 396.725187 -148.915814) (xy 396.752064 -148.915374)
			(xy 396.779319 -148.915834) (xy 396.833275 -148.923587) (xy 396.885578 -148.93894) (xy 396.935164 -148.96158)
			(xy 396.981023 -148.991047) (xy 397.022221 -149.02674) (xy 397.057921 -149.067934) (xy 397.087394 -149.113789)
			(xy 397.110041 -149.163371) (xy 397.125401 -149.215672) (xy 397.133162 -149.269627) (xy 397.133572 -149.296882)
			(xy 397.133108 -149.323753) (xy 397.125557 -149.376963) (xy 397.110617 -149.428587) (xy 397.088583 -149.477605)
			(xy 397.059891 -149.523047) (xy 397.025107 -149.564015) (xy 396.984921 -149.599698) (xy 396.940126 -149.629391)
			(xy 396.891609 -149.652507) (xy 396.840329 -149.668588) (xy 396.7873 -149.677316) (xy 396.760446 -149.67839)
			(xy 396.744698 -149.678644) (xy 396.72006 -149.695662) (xy 396.711891 -149.715982) (xy 397.238726 -149.715982)
			(xy 397.242797 -149.66036) (xy 397.254923 -149.605923) (xy 397.274846 -149.553832) (xy 397.302142 -149.505197)
			(xy 397.336228 -149.461054) (xy 397.376377 -149.422345) (xy 397.421735 -149.389894) (xy 397.471335 -149.364393)
			(xy 397.524119 -149.346386) (xy 397.578962 -149.336256) (xy 397.634696 -149.334219) (xy 397.690133 -149.340319)
			(xy 397.74409 -149.354425) (xy 397.795419 -149.376237) (xy 397.843025 -149.405291) (xy 397.885893 -149.440966)
			(xy 397.92311 -149.482503) (xy 397.953883 -149.529016) (xy 397.977555 -149.579513) (xy 397.993623 -149.63292)
			(xy 398.001743 -149.688096) (xy 398.002252 -149.715982) (xy 398.127726 -149.715982) (xy 398.131797 -149.66036)
			(xy 398.143923 -149.605923) (xy 398.163846 -149.553832) (xy 398.191142 -149.505197) (xy 398.225228 -149.461054)
			(xy 398.265377 -149.422345) (xy 398.310735 -149.389894) (xy 398.360335 -149.364393) (xy 398.413119 -149.346386)
			(xy 398.467962 -149.336256) (xy 398.523696 -149.334219) (xy 398.579133 -149.340319) (xy 398.63309 -149.354425)
			(xy 398.684419 -149.376237) (xy 398.732025 -149.405291) (xy 398.774893 -149.440966) (xy 398.81211 -149.482503)
			(xy 398.842883 -149.529016) (xy 398.866555 -149.579513) (xy 398.882623 -149.63292) (xy 398.890743 -149.688096)
			(xy 398.891252 -149.715982) (xy 399.016726 -149.715982) (xy 399.020797 -149.66036) (xy 399.032923 -149.605923)
			(xy 399.052846 -149.553832) (xy 399.080142 -149.505197) (xy 399.114228 -149.461054) (xy 399.154377 -149.422345)
			(xy 399.199735 -149.389894) (xy 399.249335 -149.364393) (xy 399.302119 -149.346386) (xy 399.356962 -149.336256)
			(xy 399.412696 -149.334219) (xy 399.468133 -149.340319) (xy 399.52209 -149.354425) (xy 399.573419 -149.376237)
			(xy 399.621025 -149.405291) (xy 399.663893 -149.440966) (xy 399.70111 -149.482503) (xy 399.731883 -149.529016)
			(xy 399.755555 -149.579513) (xy 399.771623 -149.63292) (xy 399.779743 -149.688096) (xy 399.780252 -149.715982)
			(xy 399.779743 -149.743868) (xy 399.771623 -149.799044) (xy 399.755555 -149.852451) (xy 399.731883 -149.902948)
			(xy 399.70111 -149.949461) (xy 399.663893 -149.990998) (xy 399.621025 -150.026673) (xy 399.573419 -150.055727)
			(xy 399.52209 -150.077539) (xy 399.468133 -150.091645) (xy 399.412696 -150.097745) (xy 399.356962 -150.095708)
			(xy 399.302119 -150.085578) (xy 399.249335 -150.067571) (xy 399.199735 -150.04207) (xy 399.154377 -150.009619)
			(xy 399.114228 -149.97091) (xy 399.080142 -149.926767) (xy 399.052846 -149.878132) (xy 399.032923 -149.826041)
			(xy 399.020797 -149.771604) (xy 399.016726 -149.715982) (xy 398.891252 -149.715982) (xy 398.890743 -149.743868)
			(xy 398.882623 -149.799044) (xy 398.866555 -149.852451) (xy 398.842883 -149.902948) (xy 398.81211 -149.949461)
			(xy 398.774893 -149.990998) (xy 398.732025 -150.026673) (xy 398.684419 -150.055727) (xy 398.63309 -150.077539)
			(xy 398.579133 -150.091645) (xy 398.523696 -150.097745) (xy 398.467962 -150.095708) (xy 398.413119 -150.085578)
			(xy 398.360335 -150.067571) (xy 398.310735 -150.04207) (xy 398.265377 -150.009619) (xy 398.225228 -149.97091)
			(xy 398.191142 -149.926767) (xy 398.163846 -149.878132) (xy 398.143923 -149.826041) (xy 398.131797 -149.771604)
			(xy 398.127726 -149.715982) (xy 398.002252 -149.715982) (xy 398.001743 -149.743868) (xy 397.993623 -149.799044)
			(xy 397.977555 -149.852451) (xy 397.953883 -149.902948) (xy 397.92311 -149.949461) (xy 397.885893 -149.990998)
			(xy 397.843025 -150.026673) (xy 397.795419 -150.055727) (xy 397.74409 -150.077539) (xy 397.690133 -150.091645)
			(xy 397.634696 -150.097745) (xy 397.578962 -150.095708) (xy 397.524119 -150.085578) (xy 397.471335 -150.067571)
			(xy 397.421735 -150.04207) (xy 397.376377 -150.009619) (xy 397.336228 -149.97091) (xy 397.302142 -149.926767)
			(xy 397.274846 -149.878132) (xy 397.254923 -149.826041) (xy 397.242797 -149.771604) (xy 397.238726 -149.715982)
			(xy 396.711891 -149.715982) (xy 396.67942 -149.796754) (xy 396.676127 -149.806129) (xy 396.676227 -149.825979)
			(xy 396.683885 -149.844292) (xy 396.690596 -149.851618) (xy 399.489422 -152.650444) (xy 408.315158 -152.650444)
			(xy 408.319229 -152.594822) (xy 408.331355 -152.540385) (xy 408.351278 -152.488294) (xy 408.378574 -152.439659)
			(xy 408.41266 -152.395516) (xy 408.452809 -152.356807) (xy 408.498167 -152.324356) (xy 408.547767 -152.298855)
			(xy 408.600551 -152.280848) (xy 408.655394 -152.270718) (xy 408.711128 -152.268681) (xy 408.766565 -152.274781)
			(xy 408.820522 -152.288887) (xy 408.871851 -152.310699) (xy 408.919457 -152.339753) (xy 408.962325 -152.375428)
			(xy 408.99872 -152.416048) (xy 419.022302 -152.416048) (xy 419.022302 -152.361552) (xy 419.030058 -152.307609)
			(xy 419.04541 -152.25532) (xy 419.068048 -152.205747) (xy 419.097511 -152.159901) (xy 419.133197 -152.118714)
			(xy 419.174382 -152.083025) (xy 419.220226 -152.05356) (xy 419.269797 -152.030919) (xy 419.322086 -152.015563)
			(xy 419.376028 -152.007804) (xy 419.403276 -152.007316) (xy 419.432193 -152.007846) (xy 419.489364 -152.016571)
			(xy 419.544562 -152.033827) (xy 419.596524 -152.059216) (xy 419.644058 -152.092158) (xy 419.686076 -152.131897)
			(xy 419.704266 -152.154382) (xy 419.711833 -152.163138) (xy 419.732588 -152.173322) (xy 419.744144 -152.17394)
			(xy 419.824408 -152.17394) (xy 419.83598 -152.173395) (xy 419.856752 -152.163185) (xy 419.864286 -152.154382)
			(xy 419.881039 -152.133599) (xy 419.919393 -152.096469) (xy 419.962547 -152.065047) (xy 420.009661 -152.039948)
			(xy 420.059813 -152.021662) (xy 420.112024 -152.010545) (xy 420.165276 -152.006815) (xy 420.218528 -152.010545)
			(xy 420.270739 -152.021662) (xy 420.320891 -152.039948) (xy 420.368005 -152.065047) (xy 420.411159 -152.096469)
			(xy 420.449513 -152.133599) (xy 420.466266 -152.154382) (xy 420.473833 -152.163138) (xy 420.494588 -152.173322)
			(xy 420.506144 -152.17394) (xy 420.586408 -152.17394) (xy 420.59798 -152.173395) (xy 420.618752 -152.163185)
			(xy 420.626286 -152.154382) (xy 420.643039 -152.133599) (xy 420.681393 -152.096469) (xy 420.724547 -152.065047)
			(xy 420.771661 -152.039948) (xy 420.821813 -152.021662) (xy 420.874024 -152.010545) (xy 420.927276 -152.006815)
			(xy 420.980528 -152.010545) (xy 421.032739 -152.021662) (xy 421.082891 -152.039948) (xy 421.130005 -152.065047)
			(xy 421.173159 -152.096469) (xy 421.211513 -152.133599) (xy 421.228266 -152.154382) (xy 421.235833 -152.163138)
			(xy 421.256588 -152.173322) (xy 421.268144 -152.17394) (xy 421.348408 -152.17394) (xy 421.35998 -152.173395)
			(xy 421.380752 -152.163185) (xy 421.388286 -152.154382) (xy 421.40648 -152.131901) (xy 421.4485 -152.092167)
			(xy 421.496034 -152.059228) (xy 421.547995 -152.033839) (xy 421.603192 -152.016582) (xy 421.66036 -152.007852)
			(xy 421.689276 -152.007316) (xy 421.716532 -152.007729) (xy 421.770489 -152.015484) (xy 421.822793 -152.030839)
			(xy 421.872379 -152.053481) (xy 421.918238 -152.082951) (xy 421.959436 -152.118647) (xy 421.995135 -152.159843)
			(xy 422.024607 -152.2057) (xy 422.047253 -152.255285) (xy 422.062611 -152.307588) (xy 422.070369 -152.361544)
			(xy 422.070369 -152.416056) (xy 422.062611 -152.470012) (xy 422.047253 -152.522315) (xy 422.024607 -152.5719)
			(xy 421.995135 -152.617757) (xy 421.959436 -152.658953) (xy 421.918238 -152.694649) (xy 421.872379 -152.724119)
			(xy 421.822793 -152.746761) (xy 421.770489 -152.762116) (xy 421.716532 -152.769871) (xy 421.689276 -152.770332)
			(xy 421.66036 -152.769785) (xy 421.603189 -152.761065) (xy 421.54799 -152.743815) (xy 421.496027 -152.718429)
			(xy 421.448493 -152.685489) (xy 421.406476 -152.64575) (xy 421.388286 -152.623266) (xy 421.380732 -152.614497)
			(xy 421.359967 -152.604319) (xy 421.348408 -152.603708) (xy 421.268144 -152.603708) (xy 421.256579 -152.604301)
			(xy 421.235807 -152.614479) (xy 421.228266 -152.623266) (xy 421.211513 -152.644049) (xy 421.173159 -152.681179)
			(xy 421.130005 -152.712601) (xy 421.082891 -152.7377) (xy 421.032739 -152.755986) (xy 420.980528 -152.767103)
			(xy 420.927276 -152.770833) (xy 420.874024 -152.767103) (xy 420.821813 -152.755986) (xy 420.771661 -152.7377)
			(xy 420.724547 -152.712601) (xy 420.681393 -152.681179) (xy 420.643039 -152.644049) (xy 420.626286 -152.623266)
			(xy 420.618732 -152.614497) (xy 420.597967 -152.604319) (xy 420.586408 -152.603708) (xy 420.506144 -152.603708)
			(xy 420.494579 -152.604301) (xy 420.473807 -152.614479) (xy 420.466266 -152.623266) (xy 420.449513 -152.644049)
			(xy 420.411159 -152.681179) (xy 420.368005 -152.712601) (xy 420.320891 -152.7377) (xy 420.270739 -152.755986)
			(xy 420.218528 -152.767103) (xy 420.165276 -152.770833) (xy 420.112024 -152.767103) (xy 420.059813 -152.755986)
			(xy 420.009661 -152.7377) (xy 419.962547 -152.712601) (xy 419.919393 -152.681179) (xy 419.881039 -152.644049)
			(xy 419.864286 -152.623266) (xy 419.856732 -152.614497) (xy 419.835967 -152.604319) (xy 419.824408 -152.603708)
			(xy 419.744144 -152.603708) (xy 419.732579 -152.604301) (xy 419.711807 -152.614479) (xy 419.704266 -152.623266)
			(xy 419.686086 -152.645759) (xy 419.644065 -152.685495) (xy 419.596528 -152.718434) (xy 419.544564 -152.743821)
			(xy 419.489364 -152.761075) (xy 419.432193 -152.7698) (xy 419.403276 -152.770332) (xy 419.376028 -152.769796)
			(xy 419.322086 -152.762037) (xy 419.269797 -152.746681) (xy 419.220226 -152.72404) (xy 419.174382 -152.694575)
			(xy 419.133197 -152.658886) (xy 419.097511 -152.617699) (xy 419.068048 -152.571853) (xy 419.04541 -152.52228)
			(xy 419.030058 -152.469991) (xy 419.022302 -152.416048) (xy 408.99872 -152.416048) (xy 408.999542 -152.416965)
			(xy 409.030315 -152.463478) (xy 409.053987 -152.513975) (xy 409.070055 -152.567382) (xy 409.078175 -152.622558)
			(xy 409.078684 -152.650444) (xy 409.078175 -152.67833) (xy 409.070055 -152.733506) (xy 409.053987 -152.786913)
			(xy 409.030315 -152.83741) (xy 408.999542 -152.883923) (xy 408.962325 -152.92546) (xy 408.919457 -152.961135)
			(xy 408.871851 -152.990189) (xy 408.820522 -153.012001) (xy 408.766565 -153.026107) (xy 408.711128 -153.032207)
			(xy 408.655394 -153.03017) (xy 408.600551 -153.02004) (xy 408.547767 -153.002033) (xy 408.498167 -152.976532)
			(xy 408.452809 -152.944081) (xy 408.41266 -152.905372) (xy 408.378574 -152.861229) (xy 408.351278 -152.812594)
			(xy 408.331355 -152.760503) (xy 408.319229 -152.706066) (xy 408.315158 -152.650444) (xy 399.489422 -152.650444)
			(xy 400.004788 -153.16581) (xy 411.48203 -153.16581) (xy 411.486101 -153.110188) (xy 411.498227 -153.055751)
			(xy 411.51815 -153.00366) (xy 411.545446 -152.955025) (xy 411.579532 -152.910882) (xy 411.619681 -152.872173)
			(xy 411.665039 -152.839722) (xy 411.714639 -152.814221) (xy 411.767423 -152.796214) (xy 411.822266 -152.786084)
			(xy 411.878 -152.784047) (xy 411.933437 -152.790147) (xy 411.987394 -152.804253) (xy 412.038723 -152.826065)
			(xy 412.086329 -152.855119) (xy 412.129197 -152.890794) (xy 412.166414 -152.932331) (xy 412.197187 -152.978844)
			(xy 412.220859 -153.029341) (xy 412.236927 -153.082748) (xy 412.245047 -153.137924) (xy 412.245556 -153.16581)
			(xy 412.37103 -153.16581) (xy 412.375101 -153.110188) (xy 412.387227 -153.055751) (xy 412.40715 -153.00366)
			(xy 412.434446 -152.955025) (xy 412.468532 -152.910882) (xy 412.508681 -152.872173) (xy 412.554039 -152.839722)
			(xy 412.603639 -152.814221) (xy 412.656423 -152.796214) (xy 412.711266 -152.786084) (xy 412.767 -152.784047)
			(xy 412.822437 -152.790147) (xy 412.876394 -152.804253) (xy 412.927723 -152.826065) (xy 412.975329 -152.855119)
			(xy 413.018197 -152.890794) (xy 413.055414 -152.932331) (xy 413.086187 -152.978844) (xy 413.109859 -153.029341)
			(xy 413.125927 -153.082748) (xy 413.134047 -153.137924) (xy 413.134556 -153.16581) (xy 413.26003 -153.16581)
			(xy 413.264101 -153.110188) (xy 413.276227 -153.055751) (xy 413.29615 -153.00366) (xy 413.323446 -152.955025)
			(xy 413.357532 -152.910882) (xy 413.397681 -152.872173) (xy 413.443039 -152.839722) (xy 413.492639 -152.814221)
			(xy 413.545423 -152.796214) (xy 413.600266 -152.786084) (xy 413.656 -152.784047) (xy 413.711437 -152.790147)
			(xy 413.765394 -152.804253) (xy 413.816723 -152.826065) (xy 413.864329 -152.855119) (xy 413.907197 -152.890794)
			(xy 413.944414 -152.932331) (xy 413.975187 -152.978844) (xy 413.998859 -153.029341) (xy 414.014927 -153.082748)
			(xy 414.023047 -153.137924) (xy 414.023556 -153.16581) (xy 414.14903 -153.16581) (xy 414.153101 -153.110188)
			(xy 414.165227 -153.055751) (xy 414.18515 -153.00366) (xy 414.212446 -152.955025) (xy 414.246532 -152.910882)
			(xy 414.286681 -152.872173) (xy 414.332039 -152.839722) (xy 414.381639 -152.814221) (xy 414.434423 -152.796214)
			(xy 414.489266 -152.786084) (xy 414.545 -152.784047) (xy 414.600437 -152.790147) (xy 414.654394 -152.804253)
			(xy 414.705723 -152.826065) (xy 414.753329 -152.855119) (xy 414.796197 -152.890794) (xy 414.833414 -152.932331)
			(xy 414.864187 -152.978844) (xy 414.887859 -153.029341) (xy 414.903927 -153.082748) (xy 414.912047 -153.137924)
			(xy 414.912556 -153.16581) (xy 414.912047 -153.193696) (xy 414.903927 -153.248872) (xy 414.887859 -153.302279)
			(xy 414.864187 -153.352776) (xy 414.833414 -153.399289) (xy 414.796197 -153.440826) (xy 414.753329 -153.476501)
			(xy 414.705723 -153.505555) (xy 414.654394 -153.527367) (xy 414.600437 -153.541473) (xy 414.545 -153.547573)
			(xy 414.489266 -153.545536) (xy 414.434423 -153.535406) (xy 414.381639 -153.517399) (xy 414.332039 -153.491898)
			(xy 414.286681 -153.459447) (xy 414.246532 -153.420738) (xy 414.212446 -153.376595) (xy 414.18515 -153.32796)
			(xy 414.165227 -153.275869) (xy 414.153101 -153.221432) (xy 414.14903 -153.16581) (xy 414.023556 -153.16581)
			(xy 414.023047 -153.193696) (xy 414.014927 -153.248872) (xy 413.998859 -153.302279) (xy 413.975187 -153.352776)
			(xy 413.944414 -153.399289) (xy 413.907197 -153.440826) (xy 413.864329 -153.476501) (xy 413.816723 -153.505555)
			(xy 413.765394 -153.527367) (xy 413.711437 -153.541473) (xy 413.656 -153.547573) (xy 413.600266 -153.545536)
			(xy 413.545423 -153.535406) (xy 413.492639 -153.517399) (xy 413.443039 -153.491898) (xy 413.397681 -153.459447)
			(xy 413.357532 -153.420738) (xy 413.323446 -153.376595) (xy 413.29615 -153.32796) (xy 413.276227 -153.275869)
			(xy 413.264101 -153.221432) (xy 413.26003 -153.16581) (xy 413.134556 -153.16581) (xy 413.134047 -153.193696)
			(xy 413.125927 -153.248872) (xy 413.109859 -153.302279) (xy 413.086187 -153.352776) (xy 413.055414 -153.399289)
			(xy 413.018197 -153.440826) (xy 412.975329 -153.476501) (xy 412.927723 -153.505555) (xy 412.876394 -153.527367)
			(xy 412.822437 -153.541473) (xy 412.767 -153.547573) (xy 412.711266 -153.545536) (xy 412.656423 -153.535406)
			(xy 412.603639 -153.517399) (xy 412.554039 -153.491898) (xy 412.508681 -153.459447) (xy 412.468532 -153.420738)
			(xy 412.434446 -153.376595) (xy 412.40715 -153.32796) (xy 412.387227 -153.275869) (xy 412.375101 -153.221432)
			(xy 412.37103 -153.16581) (xy 412.245556 -153.16581) (xy 412.245047 -153.193696) (xy 412.236927 -153.248872)
			(xy 412.220859 -153.302279) (xy 412.197187 -153.352776) (xy 412.166414 -153.399289) (xy 412.129197 -153.440826)
			(xy 412.086329 -153.476501) (xy 412.038723 -153.505555) (xy 411.987394 -153.527367) (xy 411.933437 -153.541473)
			(xy 411.878 -153.547573) (xy 411.822266 -153.545536) (xy 411.767423 -153.535406) (xy 411.714639 -153.517399)
			(xy 411.665039 -153.491898) (xy 411.619681 -153.459447) (xy 411.579532 -153.420738) (xy 411.545446 -153.376595)
			(xy 411.51815 -153.32796) (xy 411.498227 -153.275869) (xy 411.486101 -153.221432) (xy 411.48203 -153.16581)
			(xy 400.004788 -153.16581) (xy 402.66366 -155.824682) (xy 402.671061 -155.831521) (xy 402.689659 -155.839236)
			(xy 402.699728 -155.839668) (xy 410.652214 -155.839668) (xy 410.66126 -155.839302) (xy 410.678225 -155.833019)
			(xy 410.691954 -155.821237) (xy 410.696664 -155.813506) (xy 410.746448 -155.723844) (xy 410.74594 -155.696158)
			(xy 410.738574 -155.684474) (xy 410.724916 -155.661675) (xy 410.703355 -155.6131) (xy 410.688744 -155.562002)
			(xy 410.681368 -155.509371) (xy 410.680916 -155.482798) (xy 410.68145 -155.453882) (xy 410.690178 -155.396711)
			(xy 410.707433 -155.341512) (xy 410.732819 -155.289549) (xy 410.765757 -155.242012) (xy 410.805491 -155.19999)
			(xy 410.827982 -155.181808) (xy 410.836771 -155.174269) (xy 410.84695 -155.153496) (xy 410.84754 -155.14193)
			(xy 410.84754 -155.061666) (xy 410.846926 -155.050108) (xy 410.836748 -155.029345) (xy 410.827982 -155.021788)
			(xy 410.805496 -155.003598) (xy 410.765754 -154.961581) (xy 410.73281 -154.914048) (xy 410.707417 -154.862086)
			(xy 410.690159 -154.806887) (xy 410.68143 -154.749715) (xy 410.680916 -154.720798) (xy 410.681365 -154.694076)
			(xy 410.688827 -154.641155) (xy 410.703604 -154.589795) (xy 410.725406 -154.541) (xy 410.753807 -154.495727)
			(xy 410.788251 -154.454863) (xy 410.828062 -154.419207) (xy 410.872462 -154.389459) (xy 410.896308 -154.37739)
			(xy 410.909262 -154.37104) (xy 410.924502 -154.347418) (xy 410.927296 -154.228038) (xy 410.913072 -154.203654)
			(xy 410.900372 -154.196542) (xy 410.874879 -154.182132) (xy 410.828253 -154.146706) (xy 410.787595 -154.104564)
			(xy 410.753861 -154.056699) (xy 410.727846 -154.004237) (xy 410.710163 -153.948413) (xy 410.701226 -153.890541)
			(xy 410.700728 -153.861262) (xy 410.701214 -153.834011) (xy 410.70897 -153.780063) (xy 410.724325 -153.727768)
			(xy 410.746967 -153.678191) (xy 410.776433 -153.632341) (xy 410.812124 -153.59115) (xy 410.853315 -153.555459)
			(xy 410.899165 -153.525993) (xy 410.948742 -153.503351) (xy 411.001037 -153.487996) (xy 411.054985 -153.48024)
			(xy 411.109487 -153.48024) (xy 411.163435 -153.487996) (xy 411.21573 -153.503351) (xy 411.265307 -153.525993)
			(xy 411.311157 -153.555459) (xy 411.352348 -153.59115) (xy 411.388039 -153.632341) (xy 411.417505 -153.678191)
			(xy 411.440147 -153.727768) (xy 411.455502 -153.780063) (xy 411.463258 -153.834011) (xy 411.463744 -153.861262)
			(xy 411.463298 -153.887986) (xy 411.455841 -153.940912) (xy 411.44107 -153.992279) (xy 411.419272 -154.041081)
			(xy 411.390875 -154.086361) (xy 411.356435 -154.127235) (xy 411.316626 -154.1629) (xy 411.272228 -154.192659)
			(xy 411.248352 -154.20467) (xy 411.235398 -154.21102) (xy 411.220158 -154.234642) (xy 411.217364 -154.354022)
			(xy 411.231588 -154.378406) (xy 411.244288 -154.385518) (xy 411.26978 -154.399929) (xy 411.316403 -154.435358)
			(xy 411.35706 -154.477501) (xy 411.390792 -154.525366) (xy 411.416808 -154.577826) (xy 411.434494 -154.633649)
			(xy 411.443435 -154.691519) (xy 411.443932 -154.720798) (xy 411.443398 -154.749714) (xy 411.43467 -154.806884)
			(xy 411.417414 -154.862082) (xy 411.392025 -154.914043) (xy 411.359085 -154.961577) (xy 411.319348 -155.003595)
			(xy 411.296866 -155.021788) (xy 411.288083 -155.029331) (xy 411.277914 -155.050103) (xy 411.277308 -155.061666)
			(xy 411.277308 -155.14193) (xy 411.277923 -155.153487) (xy 411.288106 -155.174244) (xy 411.296866 -155.181808)
			(xy 411.319355 -155.199996) (xy 411.359102 -155.242011) (xy 411.392052 -155.289543) (xy 411.417448 -155.341506)
			(xy 411.43471 -155.396706) (xy 411.443441 -155.45388) (xy 411.443932 -155.482798) (xy 411.443473 -155.50937)
			(xy 411.436097 -155.562001) (xy 411.421489 -155.613099) (xy 411.39993 -155.661674) (xy 411.386274 -155.684474)
			(xy 411.378908 -155.696158) (xy 411.3784 -155.723844) (xy 411.428184 -155.813506) (xy 411.432888 -155.821243)
			(xy 411.446615 -155.833035) (xy 411.463586 -155.839317) (xy 411.472634 -155.839668) (xy 415.0741 -155.839668)
			(xy 415.086262 -155.838976) (xy 415.107886 -155.827839) (xy 415.115502 -155.818332) (xy 415.170874 -155.740354)
			(xy 415.174176 -155.716224) (xy 415.169858 -155.704286) (xy 415.159783 -155.673572) (xy 415.148928 -155.609857)
			(xy 415.148268 -155.57754) (xy 415.148807 -155.548626) (xy 415.157543 -155.491462) (xy 415.174805 -155.43627)
			(xy 415.200199 -155.384316) (xy 415.233143 -155.336789) (xy 415.272882 -155.294778) (xy 415.295334 -155.27655)
			(xy 415.304123 -155.269009) (xy 415.314308 -155.248238) (xy 415.314892 -155.236672) (xy 415.314892 -155.156408)
			(xy 415.314285 -155.144847) (xy 415.304111 -155.124077) (xy 415.295334 -155.11653) (xy 415.272849 -155.09834)
			(xy 415.233109 -155.056324) (xy 415.200167 -155.00879) (xy 415.174778 -154.956828) (xy 415.157526 -154.901628)
			(xy 415.148804 -154.844457) (xy 415.148268 -154.81554) (xy 415.148714 -154.788816) (xy 415.15617 -154.73589)
			(xy 415.170942 -154.684524) (xy 415.19274 -154.635722) (xy 415.221137 -154.590442) (xy 415.255578 -154.549569)
			(xy 415.295387 -154.513905) (xy 415.339785 -154.484147) (xy 415.36366 -154.472132) (xy 415.376614 -154.465782)
			(xy 415.391854 -154.44216) (xy 415.394648 -154.32278) (xy 415.380424 -154.298396) (xy 415.367724 -154.291284)
			(xy 415.342231 -154.276873) (xy 415.295606 -154.241445) (xy 415.254949 -154.199303) (xy 415.221214 -154.151438)
			(xy 415.195198 -154.098977) (xy 415.17751 -154.043154) (xy 415.168569 -153.985283) (xy 415.16808 -153.956004)
			(xy 415.168566 -153.928753) (xy 415.176322 -153.874805) (xy 415.191677 -153.82251) (xy 415.214319 -153.772933)
			(xy 415.243785 -153.727083) (xy 415.279476 -153.685892) (xy 415.320667 -153.650201) (xy 415.366517 -153.620735)
			(xy 415.416094 -153.598093) (xy 415.468389 -153.582738) (xy 415.522337 -153.574982) (xy 415.576839 -153.574982)
			(xy 415.630787 -153.582738) (xy 415.683082 -153.598093) (xy 415.732659 -153.620735) (xy 415.778509 -153.650201)
			(xy 415.8197 -153.685892) (xy 415.855391 -153.727083) (xy 415.884857 -153.772933) (xy 415.907499 -153.82251)
			(xy 415.922854 -153.874805) (xy 415.93061 -153.928753) (xy 415.931096 -153.956004) (xy 415.930647 -153.982726)
			(xy 415.923185 -154.035647) (xy 415.908408 -154.087008) (xy 415.886606 -154.135803) (xy 415.858205 -154.181076)
			(xy 415.823762 -154.221941) (xy 415.783951 -154.257597) (xy 415.739552 -154.287347) (xy 415.715704 -154.299412)
			(xy 415.70275 -154.305762) (xy 415.68751 -154.329384) (xy 415.684716 -154.448764) (xy 415.69894 -154.473148)
			(xy 415.71164 -154.48026) (xy 415.737132 -154.49467) (xy 415.783757 -154.530098) (xy 415.824414 -154.57224)
			(xy 415.858146 -154.620105) (xy 415.884159 -154.672567) (xy 415.901842 -154.72839) (xy 415.910778 -154.786261)
			(xy 415.911284 -154.81554) (xy 415.911061 -154.82755) (xy 419.022278 -154.82755) (xy 419.022278 -154.77305)
			(xy 419.030034 -154.719104) (xy 419.045388 -154.666811) (xy 419.068027 -154.617236) (xy 419.097491 -154.571386)
			(xy 419.13318 -154.530197) (xy 419.174367 -154.494505) (xy 419.220215 -154.465038) (xy 419.269789 -154.442396)
			(xy 419.322081 -154.427039) (xy 419.376026 -154.419279) (xy 419.403276 -154.418792) (xy 419.432194 -154.419293)
			(xy 419.489368 -154.42802) (xy 419.544568 -154.445279) (xy 419.596531 -154.470674) (xy 419.644064 -154.503623)
			(xy 419.686078 -154.543369) (xy 419.704266 -154.565858) (xy 419.711837 -154.57461) (xy 419.732589 -154.584797)
			(xy 419.744144 -154.585416) (xy 419.824408 -154.585416) (xy 419.835976 -154.584844) (xy 419.856746 -154.57465)
			(xy 419.864286 -154.565858) (xy 419.881039 -154.545075) (xy 419.919393 -154.507945) (xy 419.962547 -154.476523)
			(xy 420.009661 -154.451424) (xy 420.059813 -154.433138) (xy 420.112024 -154.422021) (xy 420.165276 -154.418291)
			(xy 420.218528 -154.422021) (xy 420.270739 -154.433138) (xy 420.320891 -154.451424) (xy 420.368005 -154.476523)
			(xy 420.411159 -154.507945) (xy 420.449513 -154.545075) (xy 420.466266 -154.565858) (xy 420.473837 -154.57461)
			(xy 420.494589 -154.584797) (xy 420.506144 -154.585416) (xy 420.586408 -154.585416) (xy 420.597976 -154.584844)
			(xy 420.618746 -154.57465) (xy 420.626286 -154.565858) (xy 420.643039 -154.545075) (xy 420.681393 -154.507945)
			(xy 420.724547 -154.476523) (xy 420.771661 -154.451424) (xy 420.821813 -154.433138) (xy 420.874024 -154.422021)
			(xy 420.927276 -154.418291) (xy 420.980528 -154.422021) (xy 421.032739 -154.433138) (xy 421.082891 -154.451424)
			(xy 421.130005 -154.476523) (xy 421.173159 -154.507945) (xy 421.211513 -154.545075) (xy 421.228266 -154.565858)
			(xy 421.235837 -154.57461) (xy 421.256589 -154.584797) (xy 421.268144 -154.585416) (xy 421.348408 -154.585416)
			(xy 421.359976 -154.584844) (xy 421.380746 -154.57465) (xy 421.388286 -154.565858) (xy 421.406474 -154.543372)
			(xy 421.448496 -154.503639) (xy 421.496032 -154.470702) (xy 421.547993 -154.445314) (xy 421.603191 -154.428058)
			(xy 421.66036 -154.419328) (xy 421.689276 -154.418792) (xy 421.71653 -154.419254) (xy 421.770483 -154.427008)
			(xy 421.822784 -154.442362) (xy 421.872367 -154.465003) (xy 421.918223 -154.49447) (xy 421.959419 -154.530164)
			(xy 421.995115 -154.571357) (xy 422.024586 -154.617212) (xy 422.04723 -154.666793) (xy 422.062587 -154.719093)
			(xy 422.070345 -154.773046) (xy 422.070345 -154.827554) (xy 422.062587 -154.881507) (xy 422.04723 -154.933807)
			(xy 422.024586 -154.983388) (xy 421.995115 -155.029243) (xy 421.959419 -155.070436) (xy 421.918223 -155.10613)
			(xy 421.872367 -155.135597) (xy 421.822784 -155.158238) (xy 421.770483 -155.173592) (xy 421.71653 -155.181346)
			(xy 421.689276 -155.181808) (xy 421.660359 -155.18127) (xy 421.603188 -155.17255) (xy 421.547988 -155.155298)
			(xy 421.496025 -155.12991) (xy 421.448491 -155.096968) (xy 421.406475 -155.057228) (xy 421.388286 -155.034742)
			(xy 421.380736 -155.025968) (xy 421.359968 -155.015794) (xy 421.348408 -155.015184) (xy 421.268144 -155.015184)
			(xy 421.25658 -155.015785) (xy 421.235809 -155.025959) (xy 421.228266 -155.034742) (xy 421.211513 -155.055525)
			(xy 421.173159 -155.092655) (xy 421.130005 -155.124077) (xy 421.082891 -155.149176) (xy 421.032739 -155.167462)
			(xy 420.980528 -155.178579) (xy 420.927276 -155.182309) (xy 420.874024 -155.178579) (xy 420.821813 -155.167462)
			(xy 420.771661 -155.149176) (xy 420.724547 -155.124077) (xy 420.681393 -155.092655) (xy 420.643039 -155.055525)
			(xy 420.626286 -155.034742) (xy 420.618736 -155.025968) (xy 420.597968 -155.015794) (xy 420.586408 -155.015184)
			(xy 420.506144 -155.015184) (xy 420.49458 -155.015785) (xy 420.473809 -155.025959) (xy 420.466266 -155.034742)
			(xy 420.449513 -155.055525) (xy 420.411159 -155.092655) (xy 420.368005 -155.124077) (xy 420.320891 -155.149176)
			(xy 420.270739 -155.167462) (xy 420.218528 -155.178579) (xy 420.165276 -155.182309) (xy 420.112024 -155.178579)
			(xy 420.059813 -155.167462) (xy 420.009661 -155.149176) (xy 419.962547 -155.124077) (xy 419.919393 -155.092655)
			(xy 419.881039 -155.055525) (xy 419.864286 -155.034742) (xy 419.856736 -155.025968) (xy 419.835968 -155.015794)
			(xy 419.824408 -155.015184) (xy 419.744144 -155.015184) (xy 419.73258 -155.015785) (xy 419.711809 -155.025959)
			(xy 419.704266 -155.034742) (xy 419.686105 -155.057251) (xy 419.644078 -155.096982) (xy 419.596536 -155.129917)
			(xy 419.544569 -155.155301) (xy 419.489367 -155.172552) (xy 419.432194 -155.181276) (xy 419.403276 -155.181808)
			(xy 419.376026 -155.181321) (xy 419.322081 -155.173561) (xy 419.269789 -155.158204) (xy 419.220215 -155.135562)
			(xy 419.174367 -155.106095) (xy 419.13318 -155.070403) (xy 419.097491 -155.029214) (xy 419.068027 -154.983364)
			(xy 419.045388 -154.933789) (xy 419.030034 -154.881496) (xy 419.022278 -154.82755) (xy 415.911061 -154.82755)
			(xy 415.910747 -154.844455) (xy 415.902015 -154.901623) (xy 415.884756 -154.956818) (xy 415.859366 -155.008776)
			(xy 415.826426 -155.056309) (xy 415.786691 -155.098327) (xy 415.764218 -155.11653) (xy 415.755418 -155.124066)
			(xy 415.745214 -155.144838) (xy 415.74466 -155.156408) (xy 415.74466 -155.236672) (xy 415.745282 -155.248226)
			(xy 415.755469 -155.268976) (xy 415.764218 -155.27655) (xy 415.786702 -155.294741) (xy 415.826439 -155.336758)
			(xy 415.859379 -155.384293) (xy 415.884766 -155.436255) (xy 415.90202 -155.491453) (xy 415.910743 -155.548624)
			(xy 415.911284 -155.57754) (xy 415.910625 -155.609857) (xy 415.899768 -155.673572) (xy 415.889694 -155.704286)
			(xy 415.885376 -155.716224) (xy 415.888678 -155.740354) (xy 415.94405 -155.818332) (xy 415.951669 -155.827835)
			(xy 415.973291 -155.838971) (xy 415.985452 -155.839668) (xy 417.049966 -155.839668) (xy 417.060018 -155.840171)
			(xy 417.078583 -155.847888) (xy 417.086034 -155.854654) (xy 417.828222 -156.596842) (xy 419.77132 -156.596842)
			(xy 419.775391 -156.54122) (xy 419.787517 -156.486783) (xy 419.80744 -156.434692) (xy 419.834736 -156.386057)
			(xy 419.868822 -156.341914) (xy 419.908971 -156.303205) (xy 419.954329 -156.270754) (xy 420.003929 -156.245253)
			(xy 420.056713 -156.227246) (xy 420.111556 -156.217116) (xy 420.16729 -156.215079) (xy 420.222727 -156.221179)
			(xy 420.276684 -156.235285) (xy 420.328013 -156.257097) (xy 420.375619 -156.286151) (xy 420.418487 -156.321826)
			(xy 420.455704 -156.363363) (xy 420.486477 -156.409876) (xy 420.510149 -156.460373) (xy 420.526217 -156.51378)
			(xy 420.534337 -156.568956) (xy 420.534846 -156.596842) (xy 420.534337 -156.624728) (xy 420.526217 -156.679904)
			(xy 420.510149 -156.733311) (xy 420.486477 -156.783808) (xy 420.455704 -156.830321) (xy 420.418487 -156.871858)
			(xy 420.375619 -156.907533) (xy 420.328013 -156.936587) (xy 420.276684 -156.958399) (xy 420.222727 -156.972505)
			(xy 420.16729 -156.978605) (xy 420.111556 -156.976568) (xy 420.056713 -156.966438) (xy 420.003929 -156.948431)
			(xy 419.954329 -156.92293) (xy 419.908971 -156.890479) (xy 419.868822 -156.85177) (xy 419.834736 -156.807627)
			(xy 419.80744 -156.758992) (xy 419.787517 -156.706901) (xy 419.775391 -156.652464) (xy 419.77132 -156.596842)
			(xy 417.828222 -156.596842) (xy 418.129466 -156.898086) (xy 418.164264 -156.90215) (xy 418.17925 -156.893006)
			(xy 418.201803 -156.879741) (xy 418.249767 -156.858833) (xy 418.300138 -156.844674) (xy 418.351971 -156.837529)
			(xy 418.378132 -156.837126) (xy 418.406287 -156.837632) (xy 418.461986 -156.84591) (xy 418.515863 -156.862282)
			(xy 418.566751 -156.886393) (xy 418.613544 -156.917719) (xy 418.655226 -156.95558) (xy 418.690893 -156.999154)
			(xy 418.71977 -157.047496) (xy 418.730938 -157.073346) (xy 418.73678 -157.08757) (xy 418.762434 -157.104842)
		)
		(stroke
			(width 0)
			(type solid)
		)
		(fill yes)
		(layer "In11.Cu")
		(net "GND")
	)
	(gr_poly
		(pts
			(xy 466.205824 -76.85278) (xy 466.213427 -76.851262) (xy 466.227254 -76.844268) (xy 466.233002 -76.839064)
			(xy 469.656414 -73.415652) (xy 469.663262 -73.408255) (xy 469.670993 -73.389656) (xy 469.6714 -73.379584)
			(xy 469.6714 -46.967902) (xy 469.66378 -46.949106) (xy 469.656414 -46.941994) (xy 467.286086 -44.571666)
			(xy 467.27869 -44.564815) (xy 467.260091 -44.557075) (xy 467.250018 -44.55668) (xy 462.403698 -44.55668)
			(xy 462.354168 -44.596304) (xy 462.347691 -44.622555) (xy 462.328334 -44.673038) (xy 462.302042 -44.720282)
			(xy 462.269342 -44.763339) (xy 462.230889 -44.801348) (xy 462.187454 -44.833546) (xy 462.139908 -44.859288)
			(xy 462.089204 -44.878058) (xy 462.036357 -44.889479) (xy 461.982427 -44.893324) (xy 461.928494 -44.889515)
			(xy 461.875639 -44.878128) (xy 461.824922 -44.859392) (xy 461.777359 -44.833682) (xy 461.733903 -44.801513)
			(xy 461.695426 -44.76353) (xy 461.662697 -44.720494) (xy 461.636373 -44.673267) (xy 461.616982 -44.622797)
			(xy 461.610456 -44.596558) (xy 461.610456 -44.595796) (xy 461.607234 -44.584841) (xy 461.592918 -44.567091)
			(xy 461.57233 -44.557289) (xy 461.560926 -44.55668) (xy 459.568804 -44.55668) (xy 459.563724 -44.556934)
			(xy 459.548484 -44.558458) (xy 459.525116 -44.577254) (xy 459.520544 -44.591478) (xy 459.511218 -44.617942)
			(xy 459.4859 -44.668014) (xy 459.45352 -44.713837) (xy 459.414777 -44.754423) (xy 459.370506 -44.788895)
			(xy 459.321663 -44.81651) (xy 459.269302 -44.836672) (xy 459.214552 -44.848945) (xy 459.158594 -44.853066)
			(xy 459.102636 -44.848945) (xy 459.047886 -44.836672) (xy 458.995525 -44.81651) (xy 458.946682 -44.788895)
			(xy 458.902411 -44.754423) (xy 458.863668 -44.713837) (xy 458.831288 -44.668014) (xy 458.80597 -44.617942)
			(xy 458.796644 -44.591478) (xy 458.796644 -44.591224) (xy 458.792776 -44.58138) (xy 458.778535 -44.565774)
			(xy 458.759202 -44.557258) (xy 458.748638 -44.55668) (xy 434.858922 -44.55668) (xy 434.840126 -44.5643)
			(xy 434.833014 -44.571666) (xy 433.925726 -45.478954) (xy 450.957948 -45.478954) (xy 450.962021 -45.423295)
			(xy 450.974156 -45.368822) (xy 450.994092 -45.316696) (xy 451.021406 -45.268028) (xy 451.055514 -45.223856)
			(xy 451.095691 -45.185121) (xy 451.141079 -45.152649) (xy 451.190711 -45.127131) (xy 451.243531 -45.109112)
			(xy 451.29841 -45.098975) (xy 451.354181 -45.096937) (xy 451.409655 -45.10304) (xy 451.463648 -45.117156)
			(xy 451.515011 -45.138983) (xy 451.562649 -45.168056) (xy 451.605545 -45.203755) (xy 451.642787 -45.245319)
			(xy 451.673581 -45.291863) (xy 451.697269 -45.342394) (xy 451.713347 -45.395836) (xy 451.721473 -45.45105)
			(xy 451.721982 -45.478954) (xy 451.721473 -45.506858) (xy 451.713347 -45.562072) (xy 451.711073 -45.569632)
			(xy 451.973694 -45.569632) (xy 451.977767 -45.513973) (xy 451.989902 -45.4595) (xy 452.009838 -45.407374)
			(xy 452.037152 -45.358706) (xy 452.07126 -45.314534) (xy 452.111437 -45.275799) (xy 452.156825 -45.243327)
			(xy 452.206457 -45.217809) (xy 452.259277 -45.19979) (xy 452.314156 -45.189653) (xy 452.369927 -45.187615)
			(xy 452.425401 -45.193718) (xy 452.479394 -45.207834) (xy 452.530757 -45.229661) (xy 452.536363 -45.233082)
			(xy 455.152758 -45.233082) (xy 455.156829 -45.17746) (xy 455.168955 -45.123023) (xy 455.188878 -45.070932)
			(xy 455.216174 -45.022297) (xy 455.25026 -44.978154) (xy 455.290409 -44.939445) (xy 455.335767 -44.906994)
			(xy 455.385367 -44.881493) (xy 455.438151 -44.863486) (xy 455.492994 -44.853356) (xy 455.548728 -44.851319)
			(xy 455.604165 -44.857419) (xy 455.658122 -44.871525) (xy 455.709451 -44.893337) (xy 455.757057 -44.922391)
			(xy 455.799925 -44.958066) (xy 455.837142 -44.999603) (xy 455.8481 -45.016166) (xy 456.958954 -45.016166)
			(xy 456.959393 -44.988895) (xy 456.96716 -44.934909) (xy 456.98253 -44.882578) (xy 457.005191 -44.832966)
			(xy 457.034682 -44.787085) (xy 457.070402 -44.745867) (xy 457.111625 -44.710152) (xy 457.15751 -44.680667)
			(xy 457.207124 -44.658013) (xy 457.259458 -44.642649) (xy 457.313445 -44.634889) (xy 457.340716 -44.634404)
			(xy 457.367369 -44.634903) (xy 457.420157 -44.642328) (xy 457.4714 -44.657017) (xy 457.520104 -44.678684)
			(xy 457.565325 -44.706911) (xy 457.606184 -44.741148) (xy 457.641888 -44.780731) (xy 457.6572 -44.802552)
			(xy 457.678056 -44.824179) (xy 457.713387 -44.872771) (xy 457.740677 -44.926294) (xy 457.759252 -44.98343)
			(xy 457.768655 -45.042768) (xy 457.769214 -45.072808) (xy 457.769105 -45.085804) (xy 457.767325 -45.111735)
			(xy 457.765658 -45.124624) (xy 457.767201 -45.137012) (xy 457.768853 -45.161925) (xy 457.76896 -45.174408)
			(xy 457.768552 -45.201663) (xy 457.760793 -45.255619) (xy 457.745433 -45.30792) (xy 457.722786 -45.357504)
			(xy 457.693313 -45.403359) (xy 457.657613 -45.444553) (xy 457.616414 -45.480247) (xy 457.570555 -45.509713)
			(xy 457.520968 -45.532353) (xy 457.468664 -45.547705) (xy 457.414707 -45.555456) (xy 457.387452 -45.555916)
			(xy 457.358822 -45.555468) (xy 457.302207 -45.54689) (xy 457.24751 -45.52995) (xy 457.195958 -45.505027)
			(xy 457.148708 -45.472681) (xy 457.106822 -45.433639) (xy 457.07124 -45.388776) (xy 457.04276 -45.339101)
			(xy 457.022022 -45.285727) (xy 457.009492 -45.229855) (xy 457.00696 -45.201332) (xy 456.991919 -45.172804)
			(xy 456.970532 -45.111969) (xy 456.959653 -45.048408) (xy 456.958954 -45.016166) (xy 455.8481 -45.016166)
			(xy 455.867915 -45.046116) (xy 455.891587 -45.096613) (xy 455.907655 -45.15002) (xy 455.915775 -45.205196)
			(xy 455.916284 -45.233082) (xy 455.915775 -45.260968) (xy 455.907655 -45.316144) (xy 455.891587 -45.369551)
			(xy 455.867915 -45.420048) (xy 455.837142 -45.466561) (xy 455.799925 -45.508098) (xy 455.757057 -45.543773)
			(xy 455.709451 -45.572827) (xy 455.658122 -45.594639) (xy 455.604165 -45.608745) (xy 455.548728 -45.614845)
			(xy 455.492994 -45.612808) (xy 455.438151 -45.602678) (xy 455.385367 -45.584671) (xy 455.335767 -45.55917)
			(xy 455.290409 -45.526719) (xy 455.25026 -45.48801) (xy 455.216174 -45.443867) (xy 455.188878 -45.395232)
			(xy 455.168955 -45.343141) (xy 455.156829 -45.288704) (xy 455.152758 -45.233082) (xy 452.536363 -45.233082)
			(xy 452.578395 -45.258734) (xy 452.621291 -45.294433) (xy 452.658533 -45.335997) (xy 452.689327 -45.382541)
			(xy 452.713015 -45.433072) (xy 452.729093 -45.486514) (xy 452.737219 -45.541728) (xy 452.737728 -45.569632)
			(xy 452.737219 -45.597536) (xy 452.729093 -45.65275) (xy 452.713015 -45.706192) (xy 452.689327 -45.756723)
			(xy 452.658533 -45.803267) (xy 452.621291 -45.844831) (xy 452.582365 -45.877226) (xy 461.205832 -45.877226)
			(xy 461.209903 -45.821604) (xy 461.222029 -45.767167) (xy 461.241952 -45.715076) (xy 461.269248 -45.666441)
			(xy 461.303334 -45.622298) (xy 461.343483 -45.583589) (xy 461.388841 -45.551138) (xy 461.438441 -45.525637)
			(xy 461.491225 -45.50763) (xy 461.546068 -45.4975) (xy 461.601802 -45.495463) (xy 461.657239 -45.501563)
			(xy 461.711196 -45.515669) (xy 461.762525 -45.537481) (xy 461.810131 -45.566535) (xy 461.852999 -45.60221)
			(xy 461.890216 -45.643747) (xy 461.920989 -45.69026) (xy 461.944661 -45.740757) (xy 461.960729 -45.794164)
			(xy 461.968849 -45.84934) (xy 461.969358 -45.877226) (xy 461.968849 -45.905112) (xy 461.960729 -45.960288)
			(xy 461.944661 -46.013695) (xy 461.920989 -46.064192) (xy 461.890216 -46.110705) (xy 461.852999 -46.152242)
			(xy 461.810131 -46.187917) (xy 461.762525 -46.216971) (xy 461.711196 -46.238783) (xy 461.657239 -46.252889)
			(xy 461.601802 -46.258989) (xy 461.546068 -46.256952) (xy 461.491225 -46.246822) (xy 461.438441 -46.228815)
			(xy 461.388841 -46.203314) (xy 461.343483 -46.170863) (xy 461.303334 -46.132154) (xy 461.269248 -46.088011)
			(xy 461.241952 -46.039376) (xy 461.222029 -45.987285) (xy 461.209903 -45.932848) (xy 461.205832 -45.877226)
			(xy 452.582365 -45.877226) (xy 452.578395 -45.88053) (xy 452.530757 -45.909603) (xy 452.479394 -45.93143)
			(xy 452.425401 -45.945546) (xy 452.369927 -45.951649) (xy 452.314156 -45.949611) (xy 452.259277 -45.939474)
			(xy 452.206457 -45.921455) (xy 452.156825 -45.895937) (xy 452.111437 -45.863465) (xy 452.07126 -45.82473)
			(xy 452.037152 -45.780558) (xy 452.009838 -45.73189) (xy 451.989902 -45.679764) (xy 451.977767 -45.625291)
			(xy 451.973694 -45.569632) (xy 451.711073 -45.569632) (xy 451.697269 -45.615514) (xy 451.673581 -45.666045)
			(xy 451.642787 -45.712589) (xy 451.605545 -45.754153) (xy 451.562649 -45.789852) (xy 451.515011 -45.818925)
			(xy 451.463648 -45.840752) (xy 451.409655 -45.854868) (xy 451.354181 -45.860971) (xy 451.29841 -45.858933)
			(xy 451.243531 -45.848796) (xy 451.190711 -45.830777) (xy 451.141079 -45.805259) (xy 451.095691 -45.772787)
			(xy 451.055514 -45.734052) (xy 451.021406 -45.68988) (xy 450.994092 -45.641212) (xy 450.974156 -45.589086)
			(xy 450.962021 -45.534613) (xy 450.957948 -45.478954) (xy 433.925726 -45.478954) (xy 432.147218 -47.257462)
			(xy 452.986138 -47.257462) (xy 452.990211 -47.201803) (xy 453.002346 -47.14733) (xy 453.022282 -47.095204)
			(xy 453.049596 -47.046536) (xy 453.083704 -47.002364) (xy 453.123881 -46.963629) (xy 453.169269 -46.931157)
			(xy 453.218901 -46.905639) (xy 453.271721 -46.88762) (xy 453.3266 -46.877483) (xy 453.382371 -46.875445)
			(xy 453.437845 -46.881548) (xy 453.491838 -46.895664) (xy 453.543201 -46.917491) (xy 453.590839 -46.946564)
			(xy 453.633735 -46.982263) (xy 453.670977 -47.023827) (xy 453.701771 -47.070371) (xy 453.725459 -47.120902)
			(xy 453.741537 -47.174344) (xy 453.749663 -47.229558) (xy 453.750172 -47.257462) (xy 453.749663 -47.285366)
			(xy 453.741537 -47.34058) (xy 453.725459 -47.394022) (xy 453.701771 -47.444553) (xy 453.68103 -47.475902)
			(xy 457.470762 -47.475902) (xy 457.474833 -47.42028) (xy 457.486959 -47.365843) (xy 457.506882 -47.313752)
			(xy 457.534178 -47.265117) (xy 457.568264 -47.220974) (xy 457.608413 -47.182265) (xy 457.653771 -47.149814)
			(xy 457.703371 -47.124313) (xy 457.756155 -47.106306) (xy 457.810998 -47.096176) (xy 457.866732 -47.094139)
			(xy 457.922169 -47.100239) (xy 457.976126 -47.114345) (xy 458.027455 -47.136157) (xy 458.075061 -47.165211)
			(xy 458.117929 -47.200886) (xy 458.155146 -47.242423) (xy 458.185919 -47.288936) (xy 458.209591 -47.339433)
			(xy 458.225659 -47.39284) (xy 458.233779 -47.448016) (xy 458.23407 -47.463964) (xy 458.461362 -47.463964)
			(xy 458.465433 -47.408342) (xy 458.477559 -47.353905) (xy 458.497482 -47.301814) (xy 458.524778 -47.253179)
			(xy 458.558864 -47.209036) (xy 458.599013 -47.170327) (xy 458.644371 -47.137876) (xy 458.693971 -47.112375)
			(xy 458.746755 -47.094368) (xy 458.801598 -47.084238) (xy 458.857332 -47.082201) (xy 458.912769 -47.088301)
			(xy 458.966726 -47.102407) (xy 459.018055 -47.124219) (xy 459.065661 -47.153273) (xy 459.108529 -47.188948)
			(xy 459.145746 -47.230485) (xy 459.176519 -47.276998) (xy 459.200191 -47.327495) (xy 459.216259 -47.380902)
			(xy 459.224379 -47.436078) (xy 459.224888 -47.463964) (xy 459.224379 -47.49185) (xy 459.216259 -47.547026)
			(xy 459.200191 -47.600433) (xy 459.176519 -47.65093) (xy 459.145746 -47.697443) (xy 459.108529 -47.73898)
			(xy 459.065661 -47.774655) (xy 459.018055 -47.803709) (xy 458.966726 -47.825521) (xy 458.912769 -47.839627)
			(xy 458.857332 -47.845727) (xy 458.801598 -47.84369) (xy 458.746755 -47.83356) (xy 458.693971 -47.815553)
			(xy 458.644371 -47.790052) (xy 458.599013 -47.757601) (xy 458.558864 -47.718892) (xy 458.524778 -47.674749)
			(xy 458.497482 -47.626114) (xy 458.477559 -47.574023) (xy 458.465433 -47.519586) (xy 458.461362 -47.463964)
			(xy 458.23407 -47.463964) (xy 458.234288 -47.475902) (xy 458.233779 -47.503788) (xy 458.225659 -47.558964)
			(xy 458.209591 -47.612371) (xy 458.185919 -47.662868) (xy 458.155146 -47.709381) (xy 458.117929 -47.750918)
			(xy 458.075061 -47.786593) (xy 458.027455 -47.815647) (xy 457.976126 -47.837459) (xy 457.922169 -47.851565)
			(xy 457.866732 -47.857665) (xy 457.810998 -47.855628) (xy 457.756155 -47.845498) (xy 457.703371 -47.827491)
			(xy 457.653771 -47.80199) (xy 457.608413 -47.769539) (xy 457.568264 -47.73083) (xy 457.534178 -47.686687)
			(xy 457.506882 -47.638052) (xy 457.486959 -47.585961) (xy 457.474833 -47.531524) (xy 457.470762 -47.475902)
			(xy 453.68103 -47.475902) (xy 453.670977 -47.491097) (xy 453.633735 -47.532661) (xy 453.590839 -47.56836)
			(xy 453.543201 -47.597433) (xy 453.491838 -47.61926) (xy 453.437845 -47.633376) (xy 453.382371 -47.639479)
			(xy 453.3266 -47.637441) (xy 453.271721 -47.627304) (xy 453.218901 -47.609285) (xy 453.169269 -47.583767)
			(xy 453.123881 -47.551295) (xy 453.083704 -47.51256) (xy 453.049596 -47.468388) (xy 453.022282 -47.41972)
			(xy 453.002346 -47.367594) (xy 452.990211 -47.313121) (xy 452.986138 -47.257462) (xy 432.147218 -47.257462)
			(xy 430.610264 -48.794416) (xy 430.603413 -48.801812) (xy 430.595675 -48.820411) (xy 430.595278 -48.830484)
			(xy 430.595278 -49.333751) (xy 449.466958 -49.333751) (xy 449.466958 -49.279249) (xy 449.474714 -49.225301)
			(xy 449.490068 -49.173006) (xy 449.512708 -49.123428) (xy 449.542173 -49.077576) (xy 449.577864 -49.036385)
			(xy 449.619052 -49.000691) (xy 449.664901 -48.971223) (xy 449.714478 -48.948579) (xy 449.766771 -48.93322)
			(xy 449.820719 -48.92546) (xy 449.84797 -48.924972) (xy 449.87563 -48.925497) (xy 449.930363 -48.933544)
			(xy 449.983354 -48.949431) (xy 450.033486 -48.972821) (xy 450.079705 -49.003222) (xy 450.1007 -49.021238)
			(xy 450.10578 -49.025048) (xy 450.111251 -49.028538) (xy 450.123467 -49.032906) (xy 450.12991 -49.033684)
			(xy 450.134482 -49.033938) (xy 450.212206 -49.033938) (xy 450.229478 -49.027334) (xy 450.236336 -49.021238)
			(xy 450.257401 -49.003229) (xy 450.303712 -48.972794) (xy 450.353943 -48.949387) (xy 450.407034 -48.933501)
			(xy 450.461866 -48.925472) (xy 450.489574 -48.924972) (xy 450.516827 -48.925474) (xy 450.570778 -48.933227)
			(xy 450.623076 -48.94858) (xy 450.672657 -48.97122) (xy 450.718511 -49.000686) (xy 450.759704 -49.036377)
			(xy 450.763093 -49.040288) (xy 453.089262 -49.040288) (xy 453.093333 -48.984666) (xy 453.105459 -48.930229)
			(xy 453.125382 -48.878138) (xy 453.152678 -48.829503) (xy 453.186764 -48.78536) (xy 453.226913 -48.746651)
			(xy 453.272271 -48.7142) (xy 453.321871 -48.688699) (xy 453.374655 -48.670692) (xy 453.429498 -48.660562)
			(xy 453.485232 -48.658525) (xy 453.540669 -48.664625) (xy 453.594626 -48.678731) (xy 453.645955 -48.700543)
			(xy 453.693561 -48.729597) (xy 453.736429 -48.765272) (xy 453.773646 -48.806809) (xy 453.804419 -48.853322)
			(xy 453.828091 -48.903819) (xy 453.844159 -48.957226) (xy 453.852279 -49.012402) (xy 453.852788 -49.040288)
			(xy 453.852279 -49.068174) (xy 453.844159 -49.12335) (xy 453.828091 -49.176757) (xy 453.804419 -49.227254)
			(xy 453.773646 -49.273767) (xy 453.736429 -49.315304) (xy 453.693561 -49.350979) (xy 453.645955 -49.380033)
			(xy 453.594626 -49.401845) (xy 453.540669 -49.415951) (xy 453.485232 -49.422051) (xy 453.429498 -49.420014)
			(xy 453.374655 -49.409884) (xy 453.321871 -49.391877) (xy 453.272271 -49.366376) (xy 453.226913 -49.333925)
			(xy 453.186764 -49.295216) (xy 453.152678 -49.251073) (xy 453.125382 -49.202438) (xy 453.105459 -49.150347)
			(xy 453.093333 -49.09591) (xy 453.089262 -49.040288) (xy 450.763093 -49.040288) (xy 450.795399 -49.077569)
			(xy 450.824868 -49.123421) (xy 450.847511 -49.173) (xy 450.862867 -49.225297) (xy 450.870625 -49.279247)
			(xy 450.870625 -49.333753) (xy 450.862867 -49.387703) (xy 450.847511 -49.44) (xy 450.841324 -49.453546)
			(xy 460.176878 -49.453546) (xy 460.180949 -49.397924) (xy 460.193075 -49.343487) (xy 460.212998 -49.291396)
			(xy 460.240294 -49.242761) (xy 460.27438 -49.198618) (xy 460.314529 -49.159909) (xy 460.359887 -49.127458)
			(xy 460.409487 -49.101957) (xy 460.462271 -49.08395) (xy 460.517114 -49.07382) (xy 460.572848 -49.071783)
			(xy 460.628285 -49.077883) (xy 460.682242 -49.091989) (xy 460.733571 -49.113801) (xy 460.781177 -49.142855)
			(xy 460.824045 -49.17853) (xy 460.861262 -49.220067) (xy 460.892035 -49.26658) (xy 460.915707 -49.317077)
			(xy 460.931775 -49.370484) (xy 460.939895 -49.42566) (xy 460.940404 -49.453546) (xy 460.939895 -49.481432)
			(xy 460.931775 -49.536608) (xy 460.915707 -49.590015) (xy 460.892035 -49.640512) (xy 460.861262 -49.687025)
			(xy 460.824045 -49.728562) (xy 460.781177 -49.764237) (xy 460.733571 -49.793291) (xy 460.682242 -49.815103)
			(xy 460.628285 -49.829209) (xy 460.572848 -49.835309) (xy 460.517114 -49.833272) (xy 460.462271 -49.823142)
			(xy 460.409487 -49.805135) (xy 460.359887 -49.779634) (xy 460.314529 -49.747183) (xy 460.27438 -49.708474)
			(xy 460.240294 -49.664331) (xy 460.212998 -49.615696) (xy 460.193075 -49.563605) (xy 460.180949 -49.509168)
			(xy 460.176878 -49.453546) (xy 450.841324 -49.453546) (xy 450.824868 -49.489579) (xy 450.795399 -49.535431)
			(xy 450.759704 -49.576623) (xy 450.718511 -49.612314) (xy 450.672657 -49.64178) (xy 450.623076 -49.66442)
			(xy 450.570778 -49.679773) (xy 450.516827 -49.687526) (xy 450.489574 -49.687988) (xy 450.461913 -49.687481)
			(xy 450.407181 -49.679427) (xy 450.35419 -49.663536) (xy 450.304058 -49.640142) (xy 450.257839 -49.609738)
			(xy 450.236844 -49.591722) (xy 450.231764 -49.587912) (xy 450.226287 -49.584432) (xy 450.214075 -49.580059)
			(xy 450.207634 -49.579276) (xy 450.203062 -49.579022) (xy 450.125338 -49.579022) (xy 450.108066 -49.585626)
			(xy 450.101208 -49.591722) (xy 450.080173 -49.609767) (xy 450.033853 -49.640195) (xy 449.983614 -49.663594)
			(xy 449.930517 -49.679472) (xy 449.87568 -49.687493) (xy 449.84797 -49.687988) (xy 449.820719 -49.68754)
			(xy 449.766771 -49.67978) (xy 449.714478 -49.664421) (xy 449.664901 -49.641777) (xy 449.619052 -49.612309)
			(xy 449.577864 -49.576615) (xy 449.542173 -49.535424) (xy 449.512708 -49.489572) (xy 449.490068 -49.439994)
			(xy 449.474714 -49.387699) (xy 449.466958 -49.333751) (xy 430.595278 -49.333751) (xy 430.595278 -50.489796)
			(xy 431.237386 -50.489796) (xy 431.237386 -50.4051) (xy 431.245437 -50.320786) (xy 431.261466 -50.23762)
			(xy 431.285327 -50.156353) (xy 431.316806 -50.077723) (xy 431.355617 -50.002442) (xy 431.401407 -49.93119)
			(xy 431.453763 -49.864614) (xy 431.512211 -49.803316) (xy 431.576221 -49.747851) (xy 431.645213 -49.698722)
			(xy 431.718563 -49.656373) (xy 431.795606 -49.621189) (xy 431.875645 -49.593487) (xy 431.957954 -49.573519)
			(xy 432.041789 -49.561466) (xy 432.12639 -49.557436) (xy 432.210991 -49.561466) (xy 432.294826 -49.573519)
			(xy 432.377135 -49.593487) (xy 432.457174 -49.621189) (xy 432.534217 -49.656373) (xy 432.607567 -49.698722)
			(xy 432.676559 -49.747851) (xy 432.740569 -49.803316) (xy 432.799017 -49.864614) (xy 432.851373 -49.93119)
			(xy 432.897163 -50.002442) (xy 432.935974 -50.077723) (xy 432.967453 -50.156353) (xy 432.991314 -50.23762)
			(xy 433.007343 -50.320786) (xy 433.015394 -50.4051) (xy 433.015898 -50.447448) (xy 433.015394 -50.489796)
			(xy 438.952636 -50.489796) (xy 438.952636 -50.4051) (xy 438.960687 -50.320786) (xy 438.976716 -50.23762)
			(xy 439.000577 -50.156353) (xy 439.032056 -50.077723) (xy 439.070867 -50.002442) (xy 439.116657 -49.93119)
			(xy 439.169013 -49.864614) (xy 439.227461 -49.803316) (xy 439.291471 -49.747851) (xy 439.360463 -49.698722)
			(xy 439.433813 -49.656373) (xy 439.510856 -49.621189) (xy 439.590895 -49.593487) (xy 439.673204 -49.573519)
			(xy 439.757039 -49.561466) (xy 439.84164 -49.557436) (xy 439.926241 -49.561466) (xy 440.010076 -49.573519)
			(xy 440.092385 -49.593487) (xy 440.172424 -49.621189) (xy 440.249467 -49.656373) (xy 440.322817 -49.698722)
			(xy 440.391809 -49.747851) (xy 440.455819 -49.803316) (xy 440.514267 -49.864614) (xy 440.566623 -49.93119)
			(xy 440.612413 -50.002442) (xy 440.651224 -50.077723) (xy 440.682703 -50.156353) (xy 440.706564 -50.23762)
			(xy 440.721842 -50.316892) (xy 459.681578 -50.316892) (xy 459.685649 -50.26127) (xy 459.697775 -50.206833)
			(xy 459.717698 -50.154742) (xy 459.744994 -50.106107) (xy 459.77908 -50.061964) (xy 459.819229 -50.023255)
			(xy 459.864587 -49.990804) (xy 459.914187 -49.965303) (xy 459.966971 -49.947296) (xy 460.021814 -49.937166)
			(xy 460.077548 -49.935129) (xy 460.132985 -49.941229) (xy 460.186942 -49.955335) (xy 460.238271 -49.977147)
			(xy 460.285877 -50.006201) (xy 460.328745 -50.041876) (xy 460.365962 -50.083413) (xy 460.396735 -50.129926)
			(xy 460.420407 -50.180423) (xy 460.436475 -50.23383) (xy 460.444595 -50.289006) (xy 460.445104 -50.316892)
			(xy 460.444595 -50.344778) (xy 460.436475 -50.399954) (xy 460.420407 -50.453361) (xy 460.396735 -50.503858)
			(xy 460.365962 -50.550371) (xy 460.328745 -50.591908) (xy 460.285877 -50.627583) (xy 460.238271 -50.656637)
			(xy 460.186942 -50.678449) (xy 460.132985 -50.692555) (xy 460.077548 -50.698655) (xy 460.021814 -50.696618)
			(xy 459.966971 -50.686488) (xy 459.914187 -50.668481) (xy 459.864587 -50.64298) (xy 459.819229 -50.610529)
			(xy 459.77908 -50.57182) (xy 459.744994 -50.527677) (xy 459.717698 -50.479042) (xy 459.697775 -50.426951)
			(xy 459.685649 -50.372514) (xy 459.681578 -50.316892) (xy 440.721842 -50.316892) (xy 440.722593 -50.320786)
			(xy 440.730644 -50.4051) (xy 440.731148 -50.447448) (xy 440.730644 -50.489796) (xy 440.722593 -50.57411)
			(xy 440.706564 -50.657276) (xy 440.682703 -50.738543) (xy 440.651224 -50.817173) (xy 440.612413 -50.892454)
			(xy 440.566623 -50.963706) (xy 440.514267 -51.030282) (xy 440.455819 -51.09158) (xy 440.391809 -51.147045)
			(xy 440.322817 -51.196174) (xy 440.249467 -51.238523) (xy 440.172424 -51.273707) (xy 440.092385 -51.301409)
			(xy 440.010076 -51.321377) (xy 439.926241 -51.33343) (xy 439.84164 -51.337461) (xy 439.757039 -51.33343)
			(xy 439.673204 -51.321377) (xy 439.590895 -51.301409) (xy 439.510856 -51.273707) (xy 439.433813 -51.238523)
			(xy 439.360463 -51.196174) (xy 439.291471 -51.147045) (xy 439.227461 -51.09158) (xy 439.169013 -51.030282)
			(xy 439.116657 -50.963706) (xy 439.070867 -50.892454) (xy 439.032056 -50.817173) (xy 439.000577 -50.738543)
			(xy 438.976716 -50.657276) (xy 438.960687 -50.57411) (xy 438.952636 -50.489796) (xy 433.015394 -50.489796)
			(xy 433.007343 -50.57411) (xy 432.991314 -50.657276) (xy 432.967453 -50.738543) (xy 432.935974 -50.817173)
			(xy 432.897163 -50.892454) (xy 432.851373 -50.963706) (xy 432.799017 -51.030282) (xy 432.740569 -51.09158)
			(xy 432.676559 -51.147045) (xy 432.607567 -51.196174) (xy 432.534217 -51.238523) (xy 432.457174 -51.273707)
			(xy 432.377135 -51.301409) (xy 432.294826 -51.321377) (xy 432.210991 -51.33343) (xy 432.12639 -51.337461)
			(xy 432.041789 -51.33343) (xy 431.957954 -51.321377) (xy 431.875645 -51.301409) (xy 431.795606 -51.273707)
			(xy 431.718563 -51.238523) (xy 431.645213 -51.196174) (xy 431.576221 -51.147045) (xy 431.512211 -51.09158)
			(xy 431.453763 -51.030282) (xy 431.401407 -50.963706) (xy 431.355617 -50.892454) (xy 431.316806 -50.817173)
			(xy 431.285327 -50.738543) (xy 431.261466 -50.657276) (xy 431.245437 -50.57411) (xy 431.237386 -50.489796)
			(xy 430.595278 -50.489796) (xy 430.595278 -51.402072) (xy 445.516704 -51.402072) (xy 445.516704 -51.347528)
			(xy 445.524466 -51.29354) (xy 445.539833 -51.241207) (xy 445.562492 -51.191593) (xy 445.591981 -51.145709)
			(xy 445.6277 -51.104488) (xy 445.668921 -51.068771) (xy 445.714807 -51.039284) (xy 445.764422 -51.016627)
			(xy 445.816756 -51.001263) (xy 445.870744 -50.993502) (xy 445.898016 -50.99304) (xy 445.925751 -50.993505)
			(xy 445.980638 -51.001524) (xy 446.033785 -51.017406) (xy 446.084073 -51.040815) (xy 446.130442 -51.071259)
			(xy 446.151508 -51.089306) (xy 446.162877 -51.098716) (xy 446.189628 -51.11115) (xy 446.218818 -51.115414)
			(xy 446.248008 -51.11115) (xy 446.274759 -51.098716) (xy 446.286128 -51.089306) (xy 446.30722 -51.071294)
			(xy 446.353589 -51.040864) (xy 446.403872 -51.01746) (xy 446.457011 -51.001574) (xy 446.511889 -50.993541)
			(xy 446.53962 -50.99304) (xy 446.566889 -50.993524) (xy 446.62087 -51.001288) (xy 446.673198 -51.016655)
			(xy 446.722806 -51.039312) (xy 446.768684 -51.068799) (xy 446.8099 -51.104514) (xy 446.845613 -51.145732)
			(xy 446.875097 -51.191612) (xy 446.897752 -51.241221) (xy 446.913116 -51.293549) (xy 446.920878 -51.347531)
			(xy 446.920878 -51.402069) (xy 446.918578 -51.418067) (xy 447.310028 -51.418067) (xy 447.310028 -51.363533)
			(xy 447.317789 -51.309554) (xy 447.333152 -51.257228) (xy 447.355804 -51.207622) (xy 447.385286 -51.161743)
			(xy 447.420996 -51.120527) (xy 447.462208 -51.084812) (xy 447.508083 -51.055326) (xy 447.557687 -51.032667)
			(xy 447.610011 -51.017298) (xy 447.663989 -51.009531) (xy 447.691256 -51.009042) (xy 447.71899 -51.009542)
			(xy 447.773875 -51.017553) (xy 447.827022 -51.033426) (xy 447.877311 -51.056828) (xy 447.923681 -51.087265)
			(xy 447.944748 -51.105308) (xy 447.956117 -51.114718) (xy 447.982868 -51.127152) (xy 448.012058 -51.131416)
			(xy 448.041248 -51.127152) (xy 448.067999 -51.114718) (xy 448.079368 -51.105308) (xy 448.100445 -51.087278)
			(xy 448.146818 -51.05685) (xy 448.197105 -51.03345) (xy 448.250247 -51.017569) (xy 448.305128 -51.009541)
			(xy 448.33286 -51.009042) (xy 448.360133 -51.009495) (xy 448.414125 -51.017252) (xy 448.466463 -51.032615)
			(xy 448.516082 -51.055271) (xy 448.524949 -51.060969) (xy 449.047604 -51.060969) (xy 449.047604 -51.006431)
			(xy 449.055366 -50.952447) (xy 449.07073 -50.900117) (xy 449.093386 -50.850506) (xy 449.12287 -50.804624)
			(xy 449.158584 -50.763405) (xy 449.1998 -50.727688) (xy 449.24568 -50.6982) (xy 449.295289 -50.675541)
			(xy 449.347617 -50.660172) (xy 449.401601 -50.652407) (xy 449.42887 -50.651918) (xy 449.456612 -50.652454)
			(xy 449.511508 -50.660512) (xy 449.564659 -50.676435) (xy 449.614944 -50.699886) (xy 449.661303 -50.730371)
			(xy 449.682362 -50.748438) (xy 449.689474 -50.754534) (xy 449.706746 -50.761138) (xy 449.792598 -50.761138)
			(xy 449.80987 -50.754534) (xy 449.816982 -50.748438) (xy 449.83802 -50.730346) (xy 449.884387 -50.699866)
			(xy 449.934677 -50.676418) (xy 449.987831 -50.660495) (xy 450.04273 -50.652432) (xy 450.070474 -50.651918)
			(xy 450.096761 -50.652352) (xy 450.148839 -50.659552) (xy 450.199436 -50.673834) (xy 450.247593 -50.694926)
			(xy 450.292398 -50.72243) (xy 450.333003 -50.755825) (xy 450.351144 -50.774854) (xy 450.358256 -50.782474)
			(xy 450.376544 -50.790856) (xy 450.459348 -50.793142) (xy 450.469477 -50.792974) (xy 450.488341 -50.785635)
			(xy 450.495924 -50.778918) (xy 450.517354 -50.759183) (xy 450.565079 -50.725777) (xy 450.617324 -50.700006)
			(xy 450.672877 -50.68247) (xy 450.730449 -50.673573) (xy 450.759576 -50.673) (xy 450.787237 -50.673514)
			(xy 450.84197 -50.681563) (xy 450.894961 -50.697452) (xy 450.945094 -50.720845) (xy 450.991312 -50.751249)
			(xy 451.012306 -50.769266) (xy 451.017386 -50.773076) (xy 451.022854 -50.77657) (xy 451.035073 -50.780935)
			(xy 451.041516 -50.781712) (xy 451.046088 -50.781966) (xy 451.123812 -50.781966) (xy 451.141084 -50.775362)
			(xy 451.147942 -50.769266) (xy 451.168995 -50.751243) (xy 451.21531 -50.720812) (xy 451.265544 -50.697409)
			(xy 451.318637 -50.681526) (xy 451.373471 -50.673499) (xy 451.40118 -50.673) (xy 451.428433 -50.673474)
			(xy 451.482384 -50.681228) (xy 451.534682 -50.696582) (xy 451.584262 -50.719223) (xy 451.630116 -50.74869)
			(xy 451.671309 -50.784382) (xy 451.707003 -50.825574) (xy 451.736471 -50.871427) (xy 451.759113 -50.921007)
			(xy 451.774469 -50.973305) (xy 451.782225 -51.027255) (xy 451.782688 -51.054508) (xy 451.782252 -51.081762)
			(xy 451.774493 -51.135715) (xy 451.759135 -51.188014) (xy 451.736491 -51.237596) (xy 451.70702 -51.28345)
			(xy 451.671323 -51.324643) (xy 451.630128 -51.360337) (xy 451.584271 -51.389804) (xy 451.534688 -51.412445)
			(xy 451.482387 -51.427799) (xy 451.428434 -51.435554) (xy 451.40118 -51.436016) (xy 451.373519 -51.435524)
			(xy 451.318785 -51.427469) (xy 451.265793 -51.411575) (xy 451.215661 -51.388177) (xy 451.169444 -51.357769)
			(xy 451.14845 -51.33975) (xy 451.14337 -51.33594) (xy 451.137891 -51.332465) (xy 451.125681 -51.328088)
			(xy 451.11924 -51.327304) (xy 451.114668 -51.32705) (xy 451.036944 -51.32705) (xy 451.019672 -51.333654)
			(xy 451.012814 -51.33975) (xy 450.99178 -51.357797) (xy 450.945459 -51.388223) (xy 450.895221 -51.411622)
			(xy 450.842123 -51.427499) (xy 450.787286 -51.435521) (xy 450.759576 -51.436016) (xy 450.73334 -51.435569)
			(xy 450.681364 -51.428371) (xy 450.630865 -51.414114) (xy 450.582799 -51.393067) (xy 450.538072 -51.365628)
			(xy 450.497531 -51.332316) (xy 450.479414 -51.313334) (xy 450.472302 -51.305714) (xy 450.454014 -51.297332)
			(xy 450.360542 -51.294792) (xy 450.352414 -51.29784) (xy 450.347638 -51.299771) (xy 450.338931 -51.305273)
			(xy 450.335142 -51.308762) (xy 450.313684 -51.328665) (xy 450.265819 -51.362344) (xy 450.213373 -51.388318)
			(xy 450.157576 -51.405979) (xy 450.099737 -51.414912) (xy 450.070474 -51.415442) (xy 450.042731 -51.414925)
			(xy 449.987835 -51.406859) (xy 449.934685 -51.390931) (xy 449.8844 -51.367477) (xy 449.838041 -51.336989)
			(xy 449.816982 -51.318922) (xy 449.80987 -51.312826) (xy 449.792598 -51.306222) (xy 449.706746 -51.306222)
			(xy 449.689474 -51.312826) (xy 449.682362 -51.318922) (xy 449.661301 -51.336987) (xy 449.614941 -51.367472)
			(xy 449.564657 -51.390926) (xy 449.511507 -51.406856) (xy 449.456612 -51.414925) (xy 449.42887 -51.415442)
			(xy 449.401601 -51.414993) (xy 449.347617 -51.407228) (xy 449.295289 -51.391859) (xy 449.24568 -51.3692)
			(xy 449.1998 -51.339712) (xy 449.158584 -51.303995) (xy 449.12287 -51.262776) (xy 449.093386 -51.216894)
			(xy 449.07073 -51.167283) (xy 449.055366 -51.114953) (xy 449.047604 -51.060969) (xy 448.524949 -51.060969)
			(xy 448.561971 -51.084758) (xy 448.603196 -51.120476) (xy 448.638918 -51.161697) (xy 448.66841 -51.207583)
			(xy 448.691071 -51.2572) (xy 448.706439 -51.309536) (xy 448.714202 -51.363527) (xy 448.714202 -51.418073)
			(xy 448.706439 -51.472064) (xy 448.691071 -51.5244) (xy 448.66841 -51.574017) (xy 448.638918 -51.619903)
			(xy 448.603196 -51.661124) (xy 448.561971 -51.696842) (xy 448.516082 -51.726329) (xy 448.466463 -51.748985)
			(xy 448.414125 -51.764348) (xy 448.360133 -51.772105) (xy 448.33286 -51.772566) (xy 448.305127 -51.772055)
			(xy 448.250242 -51.764046) (xy 448.197095 -51.748175) (xy 448.146806 -51.724776) (xy 448.100436 -51.694342)
			(xy 448.079368 -51.6763) (xy 448.067999 -51.66689) (xy 448.041248 -51.654456) (xy 448.012058 -51.650192)
			(xy 447.982868 -51.654456) (xy 447.956117 -51.66689) (xy 447.944748 -51.6763) (xy 447.923666 -51.694324)
			(xy 447.877294 -51.724752) (xy 447.827009 -51.748154) (xy 447.773867 -51.764036) (xy 447.718988 -51.772066)
			(xy 447.691256 -51.772566) (xy 447.663989 -51.772069) (xy 447.610011 -51.764302) (xy 447.557687 -51.748933)
			(xy 447.508083 -51.726274) (xy 447.462208 -51.696788) (xy 447.420996 -51.661073) (xy 447.385286 -51.619857)
			(xy 447.355804 -51.573978) (xy 447.333152 -51.524372) (xy 447.317789 -51.472046) (xy 447.310028 -51.418067)
			(xy 446.918578 -51.418067) (xy 446.913116 -51.456051) (xy 446.897752 -51.508379) (xy 446.875097 -51.557988)
			(xy 446.845613 -51.603868) (xy 446.8099 -51.645086) (xy 446.768684 -51.680801) (xy 446.722806 -51.710288)
			(xy 446.673198 -51.732945) (xy 446.62087 -51.748312) (xy 446.566889 -51.756076) (xy 446.53962 -51.756564)
			(xy 446.511886 -51.756077) (xy 446.457 -51.748063) (xy 446.403853 -51.732186) (xy 446.353565 -51.708782)
			(xy 446.307195 -51.678342) (xy 446.286128 -51.660298) (xy 446.274759 -51.650888) (xy 446.248008 -51.638454)
			(xy 446.218818 -51.63419) (xy 446.189628 -51.638454) (xy 446.162877 -51.650888) (xy 446.151508 -51.660298)
			(xy 446.130441 -51.678341) (xy 446.084065 -51.708766) (xy 446.033776 -51.732164) (xy 445.980631 -51.748042)
			(xy 445.925749 -51.756067) (xy 445.898016 -51.756564) (xy 445.870744 -51.756098) (xy 445.816756 -51.748337)
			(xy 445.764422 -51.732973) (xy 445.714807 -51.710316) (xy 445.668921 -51.680829) (xy 445.6277 -51.645112)
			(xy 445.591981 -51.603891) (xy 445.562492 -51.558007) (xy 445.539833 -51.508393) (xy 445.524466 -51.45606)
			(xy 445.516704 -51.402072) (xy 430.595278 -51.402072) (xy 430.595278 -52.989918) (xy 431.237386 -52.989918)
			(xy 431.237386 -52.905222) (xy 431.245437 -52.820908) (xy 431.261466 -52.737742) (xy 431.285327 -52.656475)
			(xy 431.316806 -52.577845) (xy 431.355617 -52.502564) (xy 431.401407 -52.431312) (xy 431.453763 -52.364736)
			(xy 431.512211 -52.303438) (xy 431.576221 -52.247973) (xy 431.645213 -52.198844) (xy 431.718563 -52.156495)
			(xy 431.795606 -52.121311) (xy 431.875645 -52.093609) (xy 431.957954 -52.073641) (xy 432.041789 -52.061588)
			(xy 432.12639 -52.057558) (xy 432.210991 -52.061588) (xy 432.294826 -52.073641) (xy 432.377135 -52.093609)
			(xy 432.457174 -52.121311) (xy 432.534217 -52.156495) (xy 432.607567 -52.198844) (xy 432.676559 -52.247973)
			(xy 432.740569 -52.303438) (xy 432.799017 -52.364736) (xy 432.851373 -52.431312) (xy 432.897163 -52.502564)
			(xy 432.935974 -52.577845) (xy 432.967453 -52.656475) (xy 432.991314 -52.737742) (xy 433.007343 -52.820908)
			(xy 433.015394 -52.905222) (xy 433.015898 -52.94757) (xy 433.015394 -52.989918) (xy 438.952636 -52.989918)
			(xy 438.952636 -52.905222) (xy 438.960687 -52.820908) (xy 438.976716 -52.737742) (xy 439.000577 -52.656475)
			(xy 439.032056 -52.577845) (xy 439.070867 -52.502564) (xy 439.116657 -52.431312) (xy 439.169013 -52.364736)
			(xy 439.227461 -52.303438) (xy 439.291471 -52.247973) (xy 439.360463 -52.198844) (xy 439.433813 -52.156495)
			(xy 439.510856 -52.121311) (xy 439.590895 -52.093609) (xy 439.673204 -52.073641) (xy 439.757039 -52.061588)
			(xy 439.84164 -52.057558) (xy 439.926241 -52.061588) (xy 440.010076 -52.073641) (xy 440.092385 -52.093609)
			(xy 440.172424 -52.121311) (xy 440.249467 -52.156495) (xy 440.322817 -52.198844) (xy 440.391809 -52.247973)
			(xy 440.455819 -52.303438) (xy 440.514267 -52.364736) (xy 440.566623 -52.431312) (xy 440.612413 -52.502564)
			(xy 440.651224 -52.577845) (xy 440.682703 -52.656475) (xy 440.706564 -52.737742) (xy 440.722593 -52.820908)
			(xy 440.730644 -52.905222) (xy 440.731148 -52.94757) (xy 440.730644 -52.989918) (xy 440.724404 -53.055266)
			(xy 460.930242 -53.055266) (xy 460.934313 -52.999644) (xy 460.946439 -52.945207) (xy 460.966362 -52.893116)
			(xy 460.993658 -52.844481) (xy 461.027744 -52.800338) (xy 461.067893 -52.761629) (xy 461.113251 -52.729178)
			(xy 461.162851 -52.703677) (xy 461.215635 -52.68567) (xy 461.270478 -52.67554) (xy 461.326212 -52.673503)
			(xy 461.381649 -52.679603) (xy 461.435606 -52.693709) (xy 461.486935 -52.715521) (xy 461.534541 -52.744575)
			(xy 461.577409 -52.78025) (xy 461.614626 -52.821787) (xy 461.645399 -52.8683) (xy 461.669071 -52.918797)
			(xy 461.685139 -52.972204) (xy 461.693259 -53.02738) (xy 461.693768 -53.055266) (xy 461.693259 -53.083152)
			(xy 461.685139 -53.138328) (xy 461.669071 -53.191735) (xy 461.645399 -53.242232) (xy 461.614626 -53.288745)
			(xy 461.577409 -53.330282) (xy 461.534541 -53.365957) (xy 461.486935 -53.395011) (xy 461.435606 -53.416823)
			(xy 461.381649 -53.430929) (xy 461.326212 -53.437029) (xy 461.270478 -53.434992) (xy 461.215635 -53.424862)
			(xy 461.162851 -53.406855) (xy 461.113251 -53.381354) (xy 461.067893 -53.348903) (xy 461.027744 -53.310194)
			(xy 460.993658 -53.266051) (xy 460.966362 -53.217416) (xy 460.946439 -53.165325) (xy 460.934313 -53.110888)
			(xy 460.930242 -53.055266) (xy 440.724404 -53.055266) (xy 440.722593 -53.074232) (xy 440.706564 -53.157398)
			(xy 440.682703 -53.238665) (xy 440.651224 -53.317295) (xy 440.612413 -53.392576) (xy 440.566623 -53.463828)
			(xy 440.514267 -53.530404) (xy 440.455819 -53.591702) (xy 440.391809 -53.647167) (xy 440.322817 -53.696296)
			(xy 440.249467 -53.738645) (xy 440.172424 -53.773829) (xy 440.092385 -53.801531) (xy 440.010076 -53.821499)
			(xy 439.926241 -53.833552) (xy 439.84164 -53.837583) (xy 439.757039 -53.833552) (xy 439.673204 -53.821499)
			(xy 439.590895 -53.801531) (xy 439.510856 -53.773829) (xy 439.433813 -53.738645) (xy 439.360463 -53.696296)
			(xy 439.291471 -53.647167) (xy 439.227461 -53.591702) (xy 439.169013 -53.530404) (xy 439.116657 -53.463828)
			(xy 439.070867 -53.392576) (xy 439.032056 -53.317295) (xy 439.000577 -53.238665) (xy 438.976716 -53.157398)
			(xy 438.960687 -53.074232) (xy 438.952636 -52.989918) (xy 433.015394 -52.989918) (xy 433.007343 -53.074232)
			(xy 432.991314 -53.157398) (xy 432.967453 -53.238665) (xy 432.935974 -53.317295) (xy 432.897163 -53.392576)
			(xy 432.851373 -53.463828) (xy 432.799017 -53.530404) (xy 432.740569 -53.591702) (xy 432.676559 -53.647167)
			(xy 432.607567 -53.696296) (xy 432.534217 -53.738645) (xy 432.457174 -53.773829) (xy 432.377135 -53.801531)
			(xy 432.294826 -53.821499) (xy 432.210991 -53.833552) (xy 432.12639 -53.837583) (xy 432.041789 -53.833552)
			(xy 431.957954 -53.821499) (xy 431.875645 -53.801531) (xy 431.795606 -53.773829) (xy 431.718563 -53.738645)
			(xy 431.645213 -53.696296) (xy 431.576221 -53.647167) (xy 431.512211 -53.591702) (xy 431.453763 -53.530404)
			(xy 431.401407 -53.463828) (xy 431.355617 -53.392576) (xy 431.316806 -53.317295) (xy 431.285327 -53.238665)
			(xy 431.261466 -53.157398) (xy 431.245437 -53.074232) (xy 431.237386 -52.989918) (xy 430.595278 -52.989918)
			(xy 430.595278 -56.999886) (xy 430.595785 -57.009936) (xy 430.603508 -57.028495) (xy 430.610264 -57.035954)
			(xy 442.101986 -68.527676) (xy 444.63208 -68.527676) (xy 444.632623 -68.49876) (xy 444.641342 -68.441588)
			(xy 444.658594 -68.386389) (xy 444.68398 -68.334426) (xy 444.716921 -68.286892) (xy 444.756661 -68.244876)
			(xy 444.779146 -68.226686) (xy 444.787957 -68.219083) (xy 444.798137 -68.198179) (xy 444.798704 -68.186554)
			(xy 444.798704 -68.106798) (xy 444.79815 -68.095168) (xy 444.787972 -68.074258) (xy 444.779146 -68.066666)
			(xy 444.756635 -68.048508) (xy 444.716904 -68.00648) (xy 444.68397 -67.958937) (xy 444.658587 -67.90697)
			(xy 444.641336 -67.851767) (xy 444.632612 -67.794594) (xy 444.63208 -67.765676) (xy 444.632555 -67.738425)
			(xy 444.640315 -67.684477) (xy 444.655672 -67.632183) (xy 444.678316 -67.582607) (xy 444.707783 -67.536757)
			(xy 444.743476 -67.495567) (xy 444.784666 -67.459876) (xy 444.830517 -67.43041) (xy 444.880094 -67.407768)
			(xy 444.932389 -67.392412) (xy 444.986337 -67.384655) (xy 445.013588 -67.384168) (xy 445.042506 -67.384669)
			(xy 445.099679 -67.393398) (xy 445.154879 -67.410658) (xy 445.206842 -67.436052) (xy 445.254375 -67.469)
			(xy 445.29639 -67.508746) (xy 445.314578 -67.531234) (xy 445.322199 -67.540027) (xy 445.343089 -67.550217)
			(xy 445.35471 -67.550792) (xy 445.434466 -67.550792) (xy 445.446094 -67.550222) (xy 445.467004 -67.540055)
			(xy 445.474598 -67.531234) (xy 445.491351 -67.510451) (xy 445.529705 -67.473321) (xy 445.572859 -67.441899)
			(xy 445.619973 -67.4168) (xy 445.670125 -67.398514) (xy 445.722336 -67.387397) (xy 445.775588 -67.383667)
			(xy 445.82884 -67.387397) (xy 445.881051 -67.398514) (xy 445.931203 -67.4168) (xy 445.978317 -67.441899)
			(xy 446.021471 -67.473321) (xy 446.059825 -67.510451) (xy 446.076578 -67.531234) (xy 446.084199 -67.540027)
			(xy 446.105089 -67.550217) (xy 446.11671 -67.550792) (xy 446.196466 -67.550792) (xy 446.208094 -67.550222)
			(xy 446.229004 -67.540055) (xy 446.236598 -67.531234) (xy 446.254799 -67.508759) (xy 446.296815 -67.469021)
			(xy 446.344348 -67.43608) (xy 446.396308 -67.41069) (xy 446.451504 -67.393433) (xy 446.508672 -67.384703)
			(xy 446.537588 -67.384168) (xy 446.564838 -67.384689) (xy 446.618783 -67.392444) (xy 446.671076 -67.407796)
			(xy 446.720651 -67.430434) (xy 446.7665 -67.459897) (xy 446.80769 -67.495584) (xy 446.843382 -67.536771)
			(xy 446.872849 -67.582617) (xy 446.895491 -67.632191) (xy 446.910849 -67.684482) (xy 446.918608 -67.738426)
			(xy 446.919096 -67.765676) (xy 446.918562 -67.794592) (xy 446.909836 -67.851763) (xy 446.892582 -67.906961)
			(xy 446.867193 -67.958923) (xy 446.834252 -68.006458) (xy 446.794514 -68.048475) (xy 446.77203 -68.066666)
			(xy 446.763237 -68.074286) (xy 446.753048 -68.095177) (xy 446.752472 -68.106798) (xy 446.752472 -68.186554)
			(xy 446.752969 -68.198192) (xy 446.763185 -68.219103) (xy 446.77203 -68.226686) (xy 446.794513 -68.244877)
			(xy 446.834247 -68.286898) (xy 446.867185 -68.334433) (xy 446.892573 -68.386394) (xy 446.90983 -68.441591)
			(xy 446.917662 -68.492878) (xy 447.058034 -68.492878) (xy 447.058596 -68.463963) (xy 447.067314 -68.406793)
			(xy 447.084562 -68.351594) (xy 447.109946 -68.299632) (xy 447.142883 -68.252097) (xy 447.182617 -68.210079)
			(xy 447.2051 -68.191888) (xy 447.213903 -68.184276) (xy 447.224089 -68.163379) (xy 447.224658 -68.151756)
			(xy 447.224658 -68.072) (xy 447.224119 -68.060368) (xy 447.213932 -68.039457) (xy 447.2051 -68.031868)
			(xy 447.182601 -68.013695) (xy 447.142867 -67.971672) (xy 447.10993 -67.924133) (xy 447.084544 -67.872168)
			(xy 447.067291 -67.816967) (xy 447.058567 -67.759795) (xy 447.058034 -67.730878) (xy 447.058435 -67.703623)
			(xy 447.066196 -67.649667) (xy 447.081557 -67.597366) (xy 447.104205 -67.547783) (xy 447.133679 -67.501927)
			(xy 447.169379 -67.460734) (xy 447.210579 -67.425041) (xy 447.256439 -67.395574) (xy 447.306026 -67.372934)
			(xy 447.35833 -67.357582) (xy 447.412287 -67.34983) (xy 447.439542 -67.34937) (xy 447.468459 -67.349904)
			(xy 447.52563 -67.358626) (xy 447.58083 -67.375879) (xy 447.632792 -67.401268) (xy 447.680326 -67.43421)
			(xy 447.722342 -67.473951) (xy 447.740532 -67.496436) (xy 447.748129 -67.505254) (xy 447.769038 -67.51543)
			(xy 447.780664 -67.515994) (xy 447.86042 -67.515994) (xy 447.872052 -67.515454) (xy 447.892961 -67.505266)
			(xy 447.900552 -67.496436) (xy 447.917305 -67.475653) (xy 447.955659 -67.438523) (xy 447.998813 -67.407101)
			(xy 448.045927 -67.382002) (xy 448.096079 -67.363716) (xy 448.14829 -67.352599) (xy 448.201542 -67.348869)
			(xy 448.254794 -67.352599) (xy 448.307005 -67.363716) (xy 448.357157 -67.382002) (xy 448.404271 -67.407101)
			(xy 448.447425 -67.438523) (xy 448.485779 -67.475653) (xy 448.502532 -67.496436) (xy 448.510129 -67.505254)
			(xy 448.531038 -67.51543) (xy 448.542664 -67.515994) (xy 448.62242 -67.515994) (xy 448.634052 -67.515454)
			(xy 448.654961 -67.505266) (xy 448.662552 -67.496436) (xy 448.680779 -67.473983) (xy 448.72279 -67.434244)
			(xy 448.770317 -67.401301) (xy 448.822272 -67.375907) (xy 448.877463 -67.358644) (xy 448.934628 -67.349908)
			(xy 448.963542 -67.34937) (xy 448.990793 -67.349839) (xy 449.04474 -67.3576) (xy 449.097034 -67.37296)
			(xy 449.14661 -67.395604) (xy 449.192459 -67.425073) (xy 449.233648 -67.460766) (xy 449.269339 -67.501957)
			(xy 449.298806 -67.547807) (xy 449.321447 -67.597385) (xy 449.336804 -67.649679) (xy 449.344563 -67.703627)
			(xy 449.34505 -67.730878) (xy 449.344535 -67.759795) (xy 449.335808 -67.816967) (xy 449.318551 -67.872167)
			(xy 449.293158 -67.924129) (xy 449.260213 -67.971663) (xy 449.220471 -68.013679) (xy 449.197984 -68.031868)
			(xy 449.189198 -68.039496) (xy 449.179003 -68.060381) (xy 449.178426 -68.072) (xy 449.178426 -68.151756)
			(xy 449.178938 -68.163392) (xy 449.189145 -68.184301) (xy 449.197984 -68.191888) (xy 449.220458 -68.21009)
			(xy 449.260195 -68.252107) (xy 449.293135 -68.299639) (xy 449.318526 -68.351599) (xy 449.335784 -68.406794)
			(xy 449.344514 -68.463963) (xy 449.34505 -68.492878) (xy 449.344501 -68.520127) (xy 449.336749 -68.57407)
			(xy 449.321399 -68.626361) (xy 449.298763 -68.675935) (xy 449.269303 -68.721784) (xy 449.233618 -68.762973)
			(xy 449.192435 -68.798665) (xy 449.146591 -68.828133) (xy 449.097021 -68.850776) (xy 449.044733 -68.866135)
			(xy 448.990791 -68.873897) (xy 448.963542 -68.874386) (xy 448.934626 -68.873843) (xy 448.877456 -68.86512)
			(xy 448.822257 -68.847867) (xy 448.770295 -68.82248) (xy 448.722761 -68.789541) (xy 448.680743 -68.749804)
			(xy 448.662552 -68.72732) (xy 448.65497 -68.718488) (xy 448.63405 -68.708321) (xy 448.62242 -68.707762)
			(xy 448.542664 -68.707762) (xy 448.531028 -68.708273) (xy 448.510118 -68.71848) (xy 448.502532 -68.72732)
			(xy 448.485779 -68.748103) (xy 448.447425 -68.785233) (xy 448.404271 -68.816655) (xy 448.357157 -68.841754)
			(xy 448.307005 -68.86004) (xy 448.254794 -68.871157) (xy 448.201542 -68.874887) (xy 448.14829 -68.871157)
			(xy 448.096079 -68.86004) (xy 448.045927 -68.841754) (xy 447.998813 -68.816655) (xy 447.955659 -68.785233)
			(xy 447.917305 -68.748103) (xy 447.900552 -68.72732) (xy 447.89297 -68.718488) (xy 447.87205 -68.708321)
			(xy 447.86042 -68.707762) (xy 447.780664 -68.707762) (xy 447.769028 -68.708273) (xy 447.748118 -68.71848)
			(xy 447.740532 -68.72732) (xy 447.722328 -68.749792) (xy 447.68031 -68.789527) (xy 447.632778 -68.822467)
			(xy 447.580819 -68.847857) (xy 447.525624 -68.865116) (xy 447.468457 -68.873849) (xy 447.439542 -68.874386)
			(xy 447.412289 -68.873906) (xy 447.358338 -68.866154) (xy 447.306039 -68.850802) (xy 447.256457 -68.828163)
			(xy 447.210603 -68.798697) (xy 447.169409 -68.763005) (xy 447.133715 -68.721813) (xy 447.104247 -68.67596)
			(xy 447.081605 -68.62638) (xy 447.066251 -68.574082) (xy 447.058496 -68.520131) (xy 447.058034 -68.492878)
			(xy 446.917662 -68.492878) (xy 446.91856 -68.49876) (xy 446.919096 -68.527676) (xy 446.918622 -68.554929)
			(xy 446.910868 -68.60888) (xy 446.895515 -68.661178) (xy 446.872874 -68.710759) (xy 446.843408 -68.756613)
			(xy 446.807715 -68.797806) (xy 446.766523 -68.8335) (xy 446.72067 -68.862968) (xy 446.67109 -68.885611)
			(xy 446.618792 -68.900966) (xy 446.564841 -68.908721) (xy 446.537588 -68.909184) (xy 446.508673 -68.908609)
			(xy 446.451504 -68.899892) (xy 446.396306 -68.882646) (xy 446.344344 -68.857265) (xy 446.296809 -68.824331)
			(xy 446.25479 -68.784599) (xy 446.236598 -68.762118) (xy 446.228996 -68.753306) (xy 446.208091 -68.743128)
			(xy 446.196466 -68.74256) (xy 446.11671 -68.74256) (xy 446.105077 -68.743098) (xy 446.084167 -68.753286)
			(xy 446.076578 -68.762118) (xy 446.059825 -68.782901) (xy 446.021471 -68.820031) (xy 445.978317 -68.851453)
			(xy 445.931203 -68.876552) (xy 445.881051 -68.894838) (xy 445.82884 -68.905955) (xy 445.775588 -68.909685)
			(xy 445.722336 -68.905955) (xy 445.670125 -68.894838) (xy 445.619973 -68.876552) (xy 445.572859 -68.851453)
			(xy 445.529705 -68.820031) (xy 445.491351 -68.782901) (xy 445.474598 -68.762118) (xy 445.466996 -68.753306)
			(xy 445.446091 -68.743128) (xy 445.434466 -68.74256) (xy 445.35471 -68.74256) (xy 445.343077 -68.743098)
			(xy 445.322167 -68.753286) (xy 445.314578 -68.762118) (xy 445.296404 -68.784616) (xy 445.25438 -68.824349)
			(xy 445.206842 -68.857286) (xy 445.154877 -68.882672) (xy 445.099677 -68.899925) (xy 445.042505 -68.908651)
			(xy 445.013588 -68.909184) (xy 444.986334 -68.908756) (xy 444.93238 -68.900997) (xy 444.88008 -68.885638)
			(xy 444.830498 -68.862993) (xy 444.784644 -68.833521) (xy 444.743451 -68.797824) (xy 444.707757 -68.756627)
			(xy 444.67829 -68.71077) (xy 444.655649 -68.661186) (xy 444.640295 -68.608885) (xy 444.632541 -68.55493)
			(xy 444.63208 -68.527676) (xy 442.101986 -68.527676) (xy 442.577474 -69.003164) (xy 450.629274 -69.003164)
			(xy 450.629764 -68.975996) (xy 450.637482 -68.922211) (xy 450.652757 -68.870066) (xy 450.675279 -68.820618)
			(xy 450.704592 -68.774867) (xy 450.721984 -68.75399) (xy 450.72808 -68.746878) (xy 450.73443 -68.72986)
			(xy 450.73443 -68.669916) (xy 450.723254 -68.669916) (xy 450.723254 -68.63715) (xy 450.722977 -68.628714)
			(xy 450.717527 -68.612751) (xy 450.712586 -68.605908) (xy 450.712332 -68.605654) (xy 450.712078 -68.6054)
			(xy 450.695995 -68.584473) (xy 450.669185 -68.539008) (xy 450.648899 -68.490282) (xy 450.635525 -68.439224)
			(xy 450.629316 -68.38681) (xy 450.630393 -68.33404) (xy 450.638735 -68.281923) (xy 450.654182 -68.231453)
			(xy 450.676439 -68.183595) (xy 450.705082 -68.139262) (xy 450.721984 -68.11899) (xy 450.72808 -68.111878)
			(xy 450.73443 -68.09486) (xy 450.73443 -68.034916) (xy 450.723254 -68.034916) (xy 450.723254 -68.00215)
			(xy 450.722977 -67.993714) (xy 450.717527 -67.977751) (xy 450.712586 -67.970908) (xy 450.712332 -67.970654)
			(xy 450.712078 -67.9704) (xy 450.695995 -67.949473) (xy 450.669185 -67.904008) (xy 450.648899 -67.855282)
			(xy 450.635525 -67.804224) (xy 450.629316 -67.75181) (xy 450.630393 -67.69904) (xy 450.638735 -67.646923)
			(xy 450.654182 -67.596453) (xy 450.676439 -67.548595) (xy 450.705082 -67.504262) (xy 450.721984 -67.48399)
			(xy 450.72808 -67.476878) (xy 450.73443 -67.45986) (xy 450.73443 -67.399916) (xy 450.723254 -67.399916)
			(xy 450.723254 -67.36715) (xy 450.722977 -67.358714) (xy 450.717527 -67.342751) (xy 450.712586 -67.335908)
			(xy 450.712332 -67.335654) (xy 450.712078 -67.3354) (xy 450.695995 -67.314473) (xy 450.669185 -67.269008)
			(xy 450.648899 -67.220282) (xy 450.635525 -67.169224) (xy 450.629316 -67.11681) (xy 450.630393 -67.06404)
			(xy 450.638735 -67.011923) (xy 450.654182 -66.961453) (xy 450.676439 -66.913595) (xy 450.705082 -66.869262)
			(xy 450.721984 -66.84899) (xy 450.72808 -66.841878) (xy 450.73443 -66.82486) (xy 450.73443 -66.764916)
			(xy 450.723254 -66.764916) (xy 450.723254 -66.73215) (xy 450.722977 -66.723714) (xy 450.717527 -66.707751)
			(xy 450.712586 -66.700908) (xy 450.712332 -66.700654) (xy 450.712078 -66.7004) (xy 450.696449 -66.680099)
			(xy 450.670229 -66.636083) (xy 450.65014 -66.588952) (xy 450.636544 -66.539554) (xy 450.629687 -66.488781)
			(xy 450.629274 -66.463164) (xy 450.629744 -66.435913) (xy 450.637505 -66.381965) (xy 450.652864 -66.329671)
			(xy 450.675508 -66.280095) (xy 450.704976 -66.234246) (xy 450.740669 -66.193057) (xy 450.78186 -66.157366)
			(xy 450.827711 -66.127899) (xy 450.877288 -66.105258) (xy 450.929583 -66.089901) (xy 450.983531 -66.082143)
			(xy 451.010782 -66.081656) (xy 451.036926 -66.082074) (xy 451.088724 -66.089223) (xy 451.139057 -66.103389)
			(xy 451.18698 -66.124306) (xy 451.231592 -66.15158) (xy 451.272054 -66.184699) (xy 451.307607 -66.223042)
			(xy 451.322948 -66.244216) (xy 451.325488 -66.247772) (xy 451.332854 -66.255138) (xy 451.340389 -66.262015)
			(xy 451.359237 -66.269761) (xy 451.36943 -66.270124) (xy 451.465696 -66.269108) (xy 451.48754 -66.25717)
			(xy 451.494652 -66.246248) (xy 451.509819 -66.223831) (xy 451.545524 -66.183154) (xy 451.586616 -66.147929)
			(xy 451.632272 -66.118861) (xy 451.681577 -66.096533) (xy 451.733541 -66.081394) (xy 451.787122 -66.073747)
			(xy 451.814184 -66.073274) (xy 451.841434 -66.073793) (xy 451.89538 -66.081547) (xy 451.947673 -66.096899)
			(xy 451.997248 -66.119537) (xy 452.043098 -66.149) (xy 452.084288 -66.184688) (xy 452.11998 -66.225875)
			(xy 452.149447 -66.271722) (xy 452.172089 -66.321296) (xy 452.187446 -66.373587) (xy 452.195204 -66.427532)
			(xy 452.195692 -66.454782) (xy 452.195237 -66.481951) (xy 452.187512 -66.535738) (xy 452.172229 -66.587884)
			(xy 452.149699 -66.637331) (xy 452.120378 -66.68308) (xy 452.102982 -66.703956) (xy 452.096886 -66.711068)
			(xy 452.090536 -66.728086) (xy 452.090536 -66.78803) (xy 452.101712 -66.78803) (xy 452.101712 -66.820796)
			(xy 452.102001 -66.829231) (xy 452.107442 -66.845195) (xy 452.11238 -66.852038) (xy 452.112634 -66.852292)
			(xy 452.112888 -66.852546) (xy 452.128914 -66.873515) (xy 452.155722 -66.918973) (xy 452.176008 -66.967693)
			(xy 452.189384 -67.018744) (xy 452.195596 -67.071151) (xy 452.194525 -67.123915) (xy 452.186192 -67.176027)
			(xy 452.170754 -67.226493) (xy 452.148508 -67.274349) (xy 452.119878 -67.318683) (xy 452.102982 -67.338956)
			(xy 452.096886 -67.346068) (xy 452.090536 -67.363086) (xy 452.090536 -67.42303) (xy 452.101712 -67.42303)
			(xy 452.101712 -67.455796) (xy 452.102001 -67.464231) (xy 452.107442 -67.480195) (xy 452.11238 -67.487038)
			(xy 452.112634 -67.487292) (xy 452.112888 -67.487546) (xy 452.128914 -67.508515) (xy 452.155722 -67.553973)
			(xy 452.176008 -67.602693) (xy 452.189384 -67.653744) (xy 452.195596 -67.706151) (xy 452.194525 -67.758915)
			(xy 452.186192 -67.811027) (xy 452.170754 -67.861493) (xy 452.148508 -67.909349) (xy 452.119878 -67.953683)
			(xy 452.102982 -67.973956) (xy 452.096886 -67.981068) (xy 452.090536 -67.998086) (xy 452.090536 -68.05803)
			(xy 452.101712 -68.05803) (xy 452.101712 -68.090796) (xy 452.102001 -68.099231) (xy 452.107442 -68.115195)
			(xy 452.11238 -68.122038) (xy 452.112634 -68.122292) (xy 452.112888 -68.122546) (xy 452.128914 -68.143515)
			(xy 452.155722 -68.188973) (xy 452.176008 -68.237693) (xy 452.189384 -68.288744) (xy 452.195596 -68.341151)
			(xy 452.194525 -68.393915) (xy 452.186192 -68.446027) (xy 452.170754 -68.496493) (xy 452.148508 -68.544349)
			(xy 452.119878 -68.588683) (xy 452.102982 -68.608956) (xy 452.096886 -68.616068) (xy 452.090536 -68.633086)
			(xy 452.090536 -68.69303) (xy 452.101712 -68.69303) (xy 452.101712 -68.725796) (xy 452.102001 -68.734231)
			(xy 452.107442 -68.750195) (xy 452.11238 -68.757038) (xy 452.112634 -68.757292) (xy 452.112888 -68.757546)
			(xy 452.128487 -68.777869) (xy 452.154714 -68.821878) (xy 452.174809 -68.869004) (xy 452.188411 -68.918397)
			(xy 452.195276 -68.969166) (xy 452.195692 -68.994782) (xy 452.728076 -68.994782) (xy 452.728576 -68.967614)
			(xy 452.736291 -68.91383) (xy 452.751564 -68.861685) (xy 452.774084 -68.812237) (xy 452.803395 -68.766486)
			(xy 452.820786 -68.745608) (xy 452.826882 -68.738496) (xy 452.833232 -68.721478) (xy 452.833232 -68.661534)
			(xy 452.822056 -68.661534) (xy 452.822056 -68.628768) (xy 452.821771 -68.620333) (xy 452.816326 -68.604369)
			(xy 452.811388 -68.597526) (xy 452.811134 -68.597272) (xy 452.81088 -68.597018) (xy 452.794815 -68.576077)
			(xy 452.768004 -68.530615) (xy 452.747717 -68.481891) (xy 452.734341 -68.430835) (xy 452.728131 -68.378423)
			(xy 452.729206 -68.325655) (xy 452.737545 -68.273539) (xy 452.75299 -68.22307) (xy 452.775245 -68.175213)
			(xy 452.803885 -68.130881) (xy 452.820786 -68.110608) (xy 452.826882 -68.103496) (xy 452.833232 -68.086478)
			(xy 452.833232 -68.026534) (xy 452.822056 -68.026534) (xy 452.822056 -67.993768) (xy 452.821771 -67.985333)
			(xy 452.816326 -67.969369) (xy 452.811388 -67.962526) (xy 452.811134 -67.962272) (xy 452.81088 -67.962018)
			(xy 452.79526 -67.941711) (xy 452.769038 -67.897696) (xy 452.748947 -67.850567) (xy 452.735349 -67.801171)
			(xy 452.72849 -67.750399) (xy 452.728076 -67.724782) (xy 452.728562 -67.697531) (xy 452.736318 -67.643583)
			(xy 452.751673 -67.591288) (xy 452.774315 -67.541711) (xy 452.803781 -67.495861) (xy 452.839472 -67.45467)
			(xy 452.880663 -67.418979) (xy 452.926513 -67.389513) (xy 452.97609 -67.366871) (xy 453.028385 -67.351516)
			(xy 453.082333 -67.34376) (xy 453.136835 -67.34376) (xy 453.190783 -67.351516) (xy 453.243078 -67.366871)
			(xy 453.292655 -67.389513) (xy 453.338505 -67.418979) (xy 453.379696 -67.45467) (xy 453.415387 -67.495861)
			(xy 453.444853 -67.541711) (xy 453.467495 -67.591288) (xy 453.48285 -67.643583) (xy 453.490606 -67.697531)
			(xy 453.491092 -67.724782) (xy 453.490637 -67.751951) (xy 453.482912 -67.805738) (xy 453.467629 -67.857884)
			(xy 453.445099 -67.907331) (xy 453.415778 -67.95308) (xy 453.398382 -67.973956) (xy 453.392286 -67.981068)
			(xy 453.385936 -67.998086) (xy 453.385936 -68.05803) (xy 453.397112 -68.05803) (xy 453.397112 -68.090796)
			(xy 453.397401 -68.099231) (xy 453.402842 -68.115195) (xy 453.40778 -68.122038) (xy 453.408034 -68.122292)
			(xy 453.408288 -68.122546) (xy 453.424314 -68.143515) (xy 453.451122 -68.188973) (xy 453.471408 -68.237693)
			(xy 453.484784 -68.288744) (xy 453.490996 -68.341151) (xy 453.489925 -68.393915) (xy 453.481592 -68.446027)
			(xy 453.466154 -68.496493) (xy 453.443908 -68.544349) (xy 453.415278 -68.588683) (xy 453.398382 -68.608956)
			(xy 453.392286 -68.616068) (xy 453.385936 -68.633086) (xy 453.385936 -68.69303) (xy 453.397112 -68.69303)
			(xy 453.397112 -68.725796) (xy 453.397401 -68.734231) (xy 453.402842 -68.750195) (xy 453.40778 -68.757038)
			(xy 453.408034 -68.757292) (xy 453.408288 -68.757546) (xy 453.423887 -68.777869) (xy 453.450114 -68.821878)
			(xy 453.470209 -68.869004) (xy 453.483811 -68.918397) (xy 453.490676 -68.969166) (xy 453.491092 -68.994782)
			(xy 458.747876 -68.994782) (xy 458.748376 -68.967614) (xy 458.756091 -68.91383) (xy 458.771364 -68.861685)
			(xy 458.793884 -68.812237) (xy 458.823195 -68.766486) (xy 458.840586 -68.745608) (xy 458.846682 -68.738496)
			(xy 458.853032 -68.721478) (xy 458.853032 -68.661534) (xy 458.841856 -68.661534) (xy 458.841856 -68.628768)
			(xy 458.841571 -68.620333) (xy 458.836126 -68.604369) (xy 458.831188 -68.597526) (xy 458.830934 -68.597272)
			(xy 458.83068 -68.597018) (xy 458.814615 -68.576077) (xy 458.787804 -68.530615) (xy 458.767517 -68.481891)
			(xy 458.754141 -68.430835) (xy 458.747931 -68.378423) (xy 458.749006 -68.325655) (xy 458.757345 -68.273539)
			(xy 458.77279 -68.22307) (xy 458.795045 -68.175213) (xy 458.823685 -68.130881) (xy 458.840586 -68.110608)
			(xy 458.846682 -68.103496) (xy 458.853032 -68.086478) (xy 458.853032 -68.026534) (xy 458.841856 -68.026534)
			(xy 458.841856 -67.993768) (xy 458.841571 -67.985333) (xy 458.836126 -67.969369) (xy 458.831188 -67.962526)
			(xy 458.830934 -67.962272) (xy 458.83068 -67.962018) (xy 458.814615 -67.941077) (xy 458.787804 -67.895615)
			(xy 458.767517 -67.846891) (xy 458.754141 -67.795835) (xy 458.747931 -67.743423) (xy 458.749006 -67.690655)
			(xy 458.757345 -67.638539) (xy 458.77279 -67.58807) (xy 458.795045 -67.540213) (xy 458.823685 -67.495881)
			(xy 458.840586 -67.475608) (xy 458.846682 -67.468496) (xy 458.853032 -67.451478) (xy 458.853032 -67.391534)
			(xy 458.841856 -67.391534) (xy 458.841856 -67.358768) (xy 458.841571 -67.350333) (xy 458.836126 -67.334369)
			(xy 458.831188 -67.327526) (xy 458.830934 -67.327272) (xy 458.83068 -67.327018) (xy 458.81506 -67.306711)
			(xy 458.788838 -67.262696) (xy 458.768747 -67.215567) (xy 458.755149 -67.166171) (xy 458.74829 -67.115399)
			(xy 458.747876 -67.089782) (xy 458.748362 -67.062531) (xy 458.756118 -67.008583) (xy 458.771473 -66.956288)
			(xy 458.794115 -66.906711) (xy 458.823581 -66.860861) (xy 458.859272 -66.81967) (xy 458.900463 -66.783979)
			(xy 458.946313 -66.754513) (xy 458.99589 -66.731871) (xy 459.048185 -66.716516) (xy 459.102133 -66.70876)
			(xy 459.156635 -66.70876) (xy 459.210583 -66.716516) (xy 459.262878 -66.731871) (xy 459.312455 -66.754513)
			(xy 459.358305 -66.783979) (xy 459.399496 -66.81967) (xy 459.435187 -66.860861) (xy 459.464653 -66.906711)
			(xy 459.487295 -66.956288) (xy 459.50265 -67.008583) (xy 459.510406 -67.062531) (xy 459.510892 -67.089782)
			(xy 459.510437 -67.116951) (xy 459.502712 -67.170738) (xy 459.487429 -67.222884) (xy 459.464899 -67.272331)
			(xy 459.435578 -67.31808) (xy 459.418182 -67.338956) (xy 459.412086 -67.346068) (xy 459.405736 -67.363086)
			(xy 459.405736 -67.42303) (xy 459.416912 -67.42303) (xy 459.416912 -67.455796) (xy 459.417201 -67.464231)
			(xy 459.422642 -67.480195) (xy 459.42758 -67.487038) (xy 459.427834 -67.487292) (xy 459.428088 -67.487546)
			(xy 459.444114 -67.508515) (xy 459.470922 -67.553973) (xy 459.491208 -67.602693) (xy 459.504584 -67.653744)
			(xy 459.510796 -67.706151) (xy 459.509725 -67.758915) (xy 459.501392 -67.811027) (xy 459.485954 -67.861493)
			(xy 459.463708 -67.909349) (xy 459.435078 -67.953683) (xy 459.418182 -67.973956) (xy 459.412086 -67.981068)
			(xy 459.405736 -67.998086) (xy 459.405736 -68.05803) (xy 459.416912 -68.05803) (xy 459.416912 -68.090796)
			(xy 459.417201 -68.099231) (xy 459.422642 -68.115195) (xy 459.42758 -68.122038) (xy 459.427834 -68.122292)
			(xy 459.428088 -68.122546) (xy 459.444114 -68.143515) (xy 459.470922 -68.188973) (xy 459.491208 -68.237693)
			(xy 459.504584 -68.288744) (xy 459.510796 -68.341151) (xy 459.509725 -68.393915) (xy 459.501392 -68.446027)
			(xy 459.485954 -68.496493) (xy 459.463708 -68.544349) (xy 459.435078 -68.588683) (xy 459.418182 -68.608956)
			(xy 459.412086 -68.616068) (xy 459.405736 -68.633086) (xy 459.405736 -68.69303) (xy 459.416912 -68.69303)
			(xy 459.416912 -68.725796) (xy 459.417201 -68.734231) (xy 459.422642 -68.750195) (xy 459.42758 -68.757038)
			(xy 459.427834 -68.757292) (xy 459.428088 -68.757546) (xy 459.443687 -68.777869) (xy 459.469914 -68.821878)
			(xy 459.490009 -68.869004) (xy 459.503611 -68.918397) (xy 459.510476 -68.969166) (xy 459.510892 -68.994782)
			(xy 459.510406 -69.022033) (xy 459.50265 -69.075981) (xy 459.487295 -69.128276) (xy 459.464653 -69.177853)
			(xy 459.435187 -69.223703) (xy 459.399496 -69.264894) (xy 459.358305 -69.300585) (xy 459.312455 -69.330051)
			(xy 459.262878 -69.352693) (xy 459.210583 -69.368048) (xy 459.156635 -69.375804) (xy 459.102133 -69.375804)
			(xy 459.048185 -69.368048) (xy 458.99589 -69.352693) (xy 458.946313 -69.330051) (xy 458.900463 -69.300585)
			(xy 458.859272 -69.264894) (xy 458.823581 -69.223703) (xy 458.794115 -69.177853) (xy 458.771473 -69.128276)
			(xy 458.756118 -69.075981) (xy 458.748362 -69.022033) (xy 458.747876 -68.994782) (xy 453.491092 -68.994782)
			(xy 453.490606 -69.022033) (xy 453.48285 -69.075981) (xy 453.467495 -69.128276) (xy 453.444853 -69.177853)
			(xy 453.415387 -69.223703) (xy 453.379696 -69.264894) (xy 453.338505 -69.300585) (xy 453.292655 -69.330051)
			(xy 453.243078 -69.352693) (xy 453.190783 -69.368048) (xy 453.136835 -69.375804) (xy 453.082333 -69.375804)
			(xy 453.028385 -69.368048) (xy 452.97609 -69.352693) (xy 452.926513 -69.330051) (xy 452.880663 -69.300585)
			(xy 452.839472 -69.264894) (xy 452.803781 -69.223703) (xy 452.774315 -69.177853) (xy 452.751673 -69.128276)
			(xy 452.736318 -69.075981) (xy 452.728562 -69.022033) (xy 452.728076 -68.994782) (xy 452.195692 -68.994782)
			(xy 452.195228 -69.022035) (xy 452.187473 -69.075987) (xy 452.172118 -69.128286) (xy 452.149477 -69.177867)
			(xy 452.120009 -69.223721) (xy 452.084315 -69.264914) (xy 452.043122 -69.300608) (xy 451.997269 -69.330076)
			(xy 451.947688 -69.352718) (xy 451.895389 -69.368073) (xy 451.841437 -69.375828) (xy 451.814184 -69.37629)
			(xy 451.78804 -69.375878) (xy 451.736243 -69.368725) (xy 451.68591 -69.354557) (xy 451.637988 -69.333639)
			(xy 451.593376 -69.306364) (xy 451.552914 -69.273245) (xy 451.51736 -69.234904) (xy 451.502018 -69.21373)
			(xy 451.499478 -69.210174) (xy 451.492112 -69.202808) (xy 451.484595 -69.195909) (xy 451.465733 -69.188177)
			(xy 451.455536 -69.187822) (xy 451.35927 -69.188838) (xy 451.337426 -69.200776) (xy 451.330314 -69.211698)
			(xy 451.315087 -69.234072) (xy 451.279394 -69.274752) (xy 451.238313 -69.309983) (xy 451.192667 -69.339057)
			(xy 451.143372 -69.361391) (xy 451.091416 -69.376538) (xy 451.037841 -69.384194) (xy 451.010782 -69.384672)
			(xy 450.983527 -69.384262) (xy 450.929572 -69.376501) (xy 450.877271 -69.361141) (xy 450.827689 -69.338494)
			(xy 450.781834 -69.309021) (xy 450.74064 -69.273321) (xy 450.704947 -69.232123) (xy 450.67548 -69.186264)
			(xy 450.65284 -69.136678) (xy 450.637487 -69.084375) (xy 450.629734 -69.030419) (xy 450.629274 -69.003164)
			(xy 442.577474 -69.003164) (xy 443.297056 -69.722746) (xy 454.449178 -69.722746) (xy 454.453249 -69.667124)
			(xy 454.465375 -69.612687) (xy 454.485298 -69.560596) (xy 454.512594 -69.511961) (xy 454.54668 -69.467818)
			(xy 454.586829 -69.429109) (xy 454.632187 -69.396658) (xy 454.681787 -69.371157) (xy 454.734571 -69.35315)
			(xy 454.789414 -69.34302) (xy 454.845148 -69.340983) (xy 454.900585 -69.347083) (xy 454.954542 -69.361189)
			(xy 455.005871 -69.383001) (xy 455.053477 -69.412055) (xy 455.096345 -69.44773) (xy 455.133562 -69.489267)
			(xy 455.164335 -69.53578) (xy 455.188007 -69.586277) (xy 455.204075 -69.639684) (xy 455.212195 -69.69486)
			(xy 455.212704 -69.722746) (xy 455.338178 -69.722746) (xy 455.342249 -69.667124) (xy 455.354375 -69.612687)
			(xy 455.374298 -69.560596) (xy 455.401594 -69.511961) (xy 455.43568 -69.467818) (xy 455.475829 -69.429109)
			(xy 455.521187 -69.396658) (xy 455.570787 -69.371157) (xy 455.623571 -69.35315) (xy 455.678414 -69.34302)
			(xy 455.734148 -69.340983) (xy 455.789585 -69.347083) (xy 455.843542 -69.361189) (xy 455.894871 -69.383001)
			(xy 455.942477 -69.412055) (xy 455.985345 -69.44773) (xy 456.022562 -69.489267) (xy 456.053335 -69.53578)
			(xy 456.077007 -69.586277) (xy 456.093075 -69.639684) (xy 456.101195 -69.69486) (xy 456.101704 -69.722746)
			(xy 456.227178 -69.722746) (xy 456.231249 -69.667124) (xy 456.243375 -69.612687) (xy 456.263298 -69.560596)
			(xy 456.290594 -69.511961) (xy 456.32468 -69.467818) (xy 456.364829 -69.429109) (xy 456.410187 -69.396658)
			(xy 456.459787 -69.371157) (xy 456.512571 -69.35315) (xy 456.567414 -69.34302) (xy 456.623148 -69.340983)
			(xy 456.678585 -69.347083) (xy 456.732542 -69.361189) (xy 456.783871 -69.383001) (xy 456.831477 -69.412055)
			(xy 456.874345 -69.44773) (xy 456.911562 -69.489267) (xy 456.942335 -69.53578) (xy 456.966007 -69.586277)
			(xy 456.982075 -69.639684) (xy 456.990195 -69.69486) (xy 456.990704 -69.722746) (xy 457.116178 -69.722746)
			(xy 457.120249 -69.667124) (xy 457.132375 -69.612687) (xy 457.152298 -69.560596) (xy 457.179594 -69.511961)
			(xy 457.21368 -69.467818) (xy 457.253829 -69.429109) (xy 457.299187 -69.396658) (xy 457.348787 -69.371157)
			(xy 457.401571 -69.35315) (xy 457.456414 -69.34302) (xy 457.512148 -69.340983) (xy 457.567585 -69.347083)
			(xy 457.621542 -69.361189) (xy 457.672871 -69.383001) (xy 457.720477 -69.412055) (xy 457.763345 -69.44773)
			(xy 457.800562 -69.489267) (xy 457.831335 -69.53578) (xy 457.855007 -69.586277) (xy 457.871075 -69.639684)
			(xy 457.879195 -69.69486) (xy 457.879704 -69.722746) (xy 457.879195 -69.750632) (xy 457.871075 -69.805808)
			(xy 457.855007 -69.859215) (xy 457.831335 -69.909712) (xy 457.800562 -69.956225) (xy 457.763345 -69.997762)
			(xy 457.720477 -70.033437) (xy 457.672871 -70.062491) (xy 457.621542 -70.084303) (xy 457.567585 -70.098409)
			(xy 457.512148 -70.104509) (xy 457.456414 -70.102472) (xy 457.401571 -70.092342) (xy 457.348787 -70.074335)
			(xy 457.299187 -70.048834) (xy 457.253829 -70.016383) (xy 457.21368 -69.977674) (xy 457.179594 -69.933531)
			(xy 457.152298 -69.884896) (xy 457.132375 -69.832805) (xy 457.120249 -69.778368) (xy 457.116178 -69.722746)
			(xy 456.990704 -69.722746) (xy 456.990195 -69.750632) (xy 456.982075 -69.805808) (xy 456.966007 -69.859215)
			(xy 456.942335 -69.909712) (xy 456.911562 -69.956225) (xy 456.874345 -69.997762) (xy 456.831477 -70.033437)
			(xy 456.783871 -70.062491) (xy 456.732542 -70.084303) (xy 456.678585 -70.098409) (xy 456.623148 -70.104509)
			(xy 456.567414 -70.102472) (xy 456.512571 -70.092342) (xy 456.459787 -70.074335) (xy 456.410187 -70.048834)
			(xy 456.364829 -70.016383) (xy 456.32468 -69.977674) (xy 456.290594 -69.933531) (xy 456.263298 -69.884896)
			(xy 456.243375 -69.832805) (xy 456.231249 -69.778368) (xy 456.227178 -69.722746) (xy 456.101704 -69.722746)
			(xy 456.101195 -69.750632) (xy 456.093075 -69.805808) (xy 456.077007 -69.859215) (xy 456.053335 -69.909712)
			(xy 456.022562 -69.956225) (xy 455.985345 -69.997762) (xy 455.942477 -70.033437) (xy 455.894871 -70.062491)
			(xy 455.843542 -70.084303) (xy 455.789585 -70.098409) (xy 455.734148 -70.104509) (xy 455.678414 -70.102472)
			(xy 455.623571 -70.092342) (xy 455.570787 -70.074335) (xy 455.521187 -70.048834) (xy 455.475829 -70.016383)
			(xy 455.43568 -69.977674) (xy 455.401594 -69.933531) (xy 455.374298 -69.884896) (xy 455.354375 -69.832805)
			(xy 455.342249 -69.778368) (xy 455.338178 -69.722746) (xy 455.212704 -69.722746) (xy 455.212195 -69.750632)
			(xy 455.204075 -69.805808) (xy 455.188007 -69.859215) (xy 455.164335 -69.909712) (xy 455.133562 -69.956225)
			(xy 455.096345 -69.997762) (xy 455.053477 -70.033437) (xy 455.005871 -70.062491) (xy 454.954542 -70.084303)
			(xy 454.900585 -70.098409) (xy 454.845148 -70.104509) (xy 454.789414 -70.102472) (xy 454.734571 -70.092342)
			(xy 454.681787 -70.074335) (xy 454.632187 -70.048834) (xy 454.586829 -70.016383) (xy 454.54668 -69.977674)
			(xy 454.512594 -69.933531) (xy 454.485298 -69.884896) (xy 454.465375 -69.832805) (xy 454.453249 -69.778368)
			(xy 454.449178 -69.722746) (xy 443.297056 -69.722746) (xy 444.894462 -71.320152) (xy 444.934848 -71.321168)
			(xy 444.950088 -71.307452) (xy 444.961264 -71.2978) (xy 444.961518 -71.297546) (xy 444.965589 -71.294021)
			(xy 444.972259 -71.285569) (xy 444.974726 -71.280782) (xy 444.989204 -71.251318) (xy 444.989204 -71.171054)
			(xy 444.974726 -71.14159) (xy 444.972221 -71.136827) (xy 444.965565 -71.128373) (xy 444.961518 -71.124826)
			(xy 444.961264 -71.124572) (xy 444.939964 -71.106346) (xy 444.902419 -71.064717) (xy 444.871367 -71.018045)
			(xy 444.847474 -70.967333) (xy 444.831255 -70.913671) (xy 444.823058 -70.858215) (xy 444.82258 -70.830186)
			(xy 444.823067 -70.802935) (xy 444.830825 -70.748988) (xy 444.846181 -70.696694) (xy 444.868823 -70.647118)
			(xy 444.898289 -70.601269) (xy 444.933981 -70.560079) (xy 444.97517 -70.524388) (xy 445.02102 -70.494922)
			(xy 445.070596 -70.47228) (xy 445.12289 -70.456924) (xy 445.176837 -70.449167) (xy 445.204088 -70.448678)
			(xy 445.232117 -70.44917) (xy 445.287573 -70.457365) (xy 445.341235 -70.473581) (xy 445.391949 -70.497468)
			(xy 445.438625 -70.528515) (xy 445.48026 -70.566052) (xy 445.498474 -70.587362) (xy 445.498728 -70.587616)
			(xy 445.502252 -70.591689) (xy 445.510702 -70.598363) (xy 445.515492 -70.600824) (xy 445.544956 -70.615302)
			(xy 445.613536 -70.615302) (xy 445.619324 -70.615172) (xy 445.630609 -70.612599) (xy 445.635888 -70.610222)
			(xy 445.654684 -70.600824) (xy 445.659449 -70.598321) (xy 445.667906 -70.591668) (xy 445.671448 -70.587616)
			(xy 445.671702 -70.587362) (xy 445.689922 -70.566051) (xy 445.731542 -70.528485) (xy 445.778212 -70.497413)
			(xy 445.828925 -70.473504) (xy 445.882591 -70.457273) (xy 445.938055 -70.44907) (xy 445.994121 -70.44907)
			(xy 446.049585 -70.457273) (xy 446.103251 -70.473504) (xy 446.153964 -70.497413) (xy 446.200634 -70.528485)
			(xy 446.242254 -70.566051) (xy 446.260474 -70.587362) (xy 446.260728 -70.587616) (xy 446.264252 -70.591689)
			(xy 446.272702 -70.598363) (xy 446.277492 -70.600824) (xy 446.306956 -70.615302) (xy 446.375536 -70.615302)
			(xy 446.381324 -70.615172) (xy 446.392609 -70.612599) (xy 446.397888 -70.610222) (xy 446.416684 -70.600824)
			(xy 446.421449 -70.598321) (xy 446.429906 -70.591668) (xy 446.433448 -70.587616) (xy 446.433702 -70.587362)
			(xy 446.451922 -70.566051) (xy 446.493542 -70.528485) (xy 446.540212 -70.497413) (xy 446.590925 -70.473504)
			(xy 446.644591 -70.457273) (xy 446.700055 -70.44907) (xy 446.756121 -70.44907) (xy 446.811585 -70.457273)
			(xy 446.865251 -70.473504) (xy 446.915964 -70.497413) (xy 446.962634 -70.528485) (xy 447.004254 -70.566051)
			(xy 447.022474 -70.587362) (xy 447.022728 -70.587616) (xy 447.026252 -70.591689) (xy 447.034702 -70.598363)
			(xy 447.039492 -70.600824) (xy 447.068956 -70.615302) (xy 447.137536 -70.615302) (xy 447.143324 -70.615172)
			(xy 447.154609 -70.612599) (xy 447.159888 -70.610222) (xy 447.178684 -70.600824) (xy 447.183449 -70.598321)
			(xy 447.191906 -70.591668) (xy 447.195448 -70.587616) (xy 447.195702 -70.587362) (xy 447.213928 -70.566061)
			(xy 447.255556 -70.528513) (xy 447.302228 -70.497458) (xy 447.35294 -70.473562) (xy 447.406601 -70.457339)
			(xy 447.462058 -70.449139) (xy 447.490088 -70.448678) (xy 447.51734 -70.449163) (xy 447.57129 -70.456918)
			(xy 447.623587 -70.472272) (xy 447.673167 -70.494912) (xy 447.719019 -70.524378) (xy 447.760212 -70.560069)
			(xy 447.795906 -70.60126) (xy 447.825375 -70.647111) (xy 447.848019 -70.696689) (xy 447.863376 -70.748985)
			(xy 447.871135 -70.802934) (xy 447.871596 -70.830186) (xy 447.871104 -70.858215) (xy 447.862909 -70.913671)
			(xy 447.846692 -70.967332) (xy 447.822804 -71.018045) (xy 447.791757 -71.06472) (xy 447.754218 -71.106353)
			(xy 447.732912 -71.124572) (xy 447.732658 -71.124826) (xy 447.728587 -71.128351) (xy 447.721916 -71.136803)
			(xy 447.71945 -71.14159) (xy 447.704972 -71.171054) (xy 447.704972 -71.239634) (xy 447.705102 -71.245422)
			(xy 447.707673 -71.256708) (xy 447.710052 -71.261986) (xy 447.71945 -71.280782) (xy 447.721956 -71.285544)
			(xy 447.728616 -71.293994) (xy 447.732658 -71.297546) (xy 447.732912 -71.2978) (xy 447.754215 -71.316025)
			(xy 447.791765 -71.357652) (xy 447.822823 -71.404324) (xy 447.846721 -71.455036) (xy 447.862945 -71.508698)
			(xy 447.871146 -71.564156) (xy 447.871596 -71.592186) (xy 447.871134 -71.619439) (xy 447.863378 -71.673391)
			(xy 447.848023 -71.72569) (xy 447.825381 -71.775271) (xy 447.795914 -71.821125) (xy 447.76022 -71.862318)
			(xy 447.719027 -71.898012) (xy 447.673173 -71.92748) (xy 447.623592 -71.950123) (xy 447.571293 -71.965478)
			(xy 447.517341 -71.973233) (xy 447.490088 -71.973694) (xy 447.46206 -71.9732) (xy 447.406606 -71.965001)
			(xy 447.352948 -71.948782) (xy 447.302237 -71.924892) (xy 447.255565 -71.893843) (xy 447.213935 -71.856303)
			(xy 447.195702 -71.83501) (xy 447.195448 -71.834756) (xy 447.191922 -71.830686) (xy 447.183468 -71.824019)
			(xy 447.178684 -71.821548) (xy 447.14922 -71.80707) (xy 447.068956 -71.80707) (xy 447.039492 -71.821548)
			(xy 447.034731 -71.824056) (xy 447.026284 -71.830717) (xy 447.022728 -71.834756) (xy 447.022474 -71.83501)
			(xy 447.004254 -71.856321) (xy 446.962634 -71.893887) (xy 446.915964 -71.924959) (xy 446.865251 -71.948868)
			(xy 446.811585 -71.965099) (xy 446.756121 -71.973302) (xy 446.700055 -71.973302) (xy 446.644591 -71.965099)
			(xy 446.590925 -71.948868) (xy 446.540212 -71.924959) (xy 446.493542 -71.893887) (xy 446.451922 -71.856321)
			(xy 446.433702 -71.83501) (xy 446.433448 -71.834756) (xy 446.429922 -71.830686) (xy 446.421468 -71.824019)
			(xy 446.416684 -71.821548) (xy 446.38722 -71.80707) (xy 446.306956 -71.80707) (xy 446.277492 -71.821548)
			(xy 446.272731 -71.824056) (xy 446.264284 -71.830717) (xy 446.260728 -71.834756) (xy 446.260474 -71.83501)
			(xy 446.242254 -71.856321) (xy 446.200634 -71.893887) (xy 446.153964 -71.924959) (xy 446.103251 -71.948868)
			(xy 446.049585 -71.965099) (xy 445.994121 -71.973302) (xy 445.938055 -71.973302) (xy 445.882591 -71.965099)
			(xy 445.828925 -71.948868) (xy 445.778212 -71.924959) (xy 445.731542 -71.893887) (xy 445.689922 -71.856321)
			(xy 445.671702 -71.83501) (xy 445.671448 -71.834756) (xy 445.667922 -71.830686) (xy 445.659468 -71.824019)
			(xy 445.654684 -71.821548) (xy 445.62522 -71.80707) (xy 445.544956 -71.80707) (xy 445.515492 -71.821548)
			(xy 445.510731 -71.824056) (xy 445.502284 -71.830717) (xy 445.498728 -71.834756) (xy 445.498474 -71.83501)
			(xy 445.488822 -71.846186) (xy 445.475106 -71.861426) (xy 445.476122 -71.901812) (xy 445.989894 -72.415584)
			(xy 448.803264 -72.415584) (xy 448.803264 -72.330888) (xy 448.811315 -72.246574) (xy 448.827344 -72.163408)
			(xy 448.851205 -72.082141) (xy 448.882684 -72.003511) (xy 448.921495 -71.92823) (xy 448.967285 -71.856978)
			(xy 449.019641 -71.790402) (xy 449.078089 -71.729104) (xy 449.142099 -71.673639) (xy 449.211091 -71.62451)
			(xy 449.284441 -71.582161) (xy 449.361484 -71.546977) (xy 449.441523 -71.519275) (xy 449.523832 -71.499307)
			(xy 449.607667 -71.487254) (xy 449.692268 -71.483224) (xy 449.776869 -71.487254) (xy 449.860704 -71.499307)
			(xy 449.943013 -71.519275) (xy 450.023052 -71.546977) (xy 450.100095 -71.582161) (xy 450.173445 -71.62451)
			(xy 450.242437 -71.673639) (xy 450.306447 -71.729104) (xy 450.364895 -71.790402) (xy 450.417251 -71.856978)
			(xy 450.463041 -71.92823) (xy 450.501852 -72.003511) (xy 450.533331 -72.082141) (xy 450.557192 -72.163408)
			(xy 450.573221 -72.246574) (xy 450.581272 -72.330888) (xy 450.581776 -72.373236) (xy 450.581272 -72.415584)
			(xy 456.311504 -72.415584) (xy 456.311504 -72.330888) (xy 456.319555 -72.246574) (xy 456.335584 -72.163408)
			(xy 456.359445 -72.082141) (xy 456.390924 -72.003511) (xy 456.429735 -71.92823) (xy 456.475525 -71.856978)
			(xy 456.527881 -71.790402) (xy 456.586329 -71.729104) (xy 456.650339 -71.673639) (xy 456.719331 -71.62451)
			(xy 456.792681 -71.582161) (xy 456.869724 -71.546977) (xy 456.949763 -71.519275) (xy 457.032072 -71.499307)
			(xy 457.115907 -71.487254) (xy 457.200508 -71.483224) (xy 457.285109 -71.487254) (xy 457.368944 -71.499307)
			(xy 457.451253 -71.519275) (xy 457.531292 -71.546977) (xy 457.608335 -71.582161) (xy 457.681685 -71.62451)
			(xy 457.750677 -71.673639) (xy 457.814687 -71.729104) (xy 457.873135 -71.790402) (xy 457.925491 -71.856978)
			(xy 457.971281 -71.92823) (xy 458.010092 -72.003511) (xy 458.041571 -72.082141) (xy 458.065432 -72.163408)
			(xy 458.081461 -72.246574) (xy 458.089512 -72.330888) (xy 458.090016 -72.373236) (xy 458.089512 -72.415584)
			(xy 458.081461 -72.499898) (xy 458.065432 -72.583064) (xy 458.041571 -72.664331) (xy 458.010092 -72.742961)
			(xy 457.971281 -72.818242) (xy 457.925491 -72.889494) (xy 457.873135 -72.95607) (xy 457.814687 -73.017368)
			(xy 457.750677 -73.072833) (xy 457.681685 -73.121962) (xy 457.608335 -73.164311) (xy 457.531292 -73.199495)
			(xy 457.451253 -73.227197) (xy 457.368944 -73.247165) (xy 457.285109 -73.259218) (xy 457.200508 -73.263249)
			(xy 457.115907 -73.259218) (xy 457.032072 -73.247165) (xy 456.949763 -73.227197) (xy 456.869724 -73.199495)
			(xy 456.792681 -73.164311) (xy 456.719331 -73.121962) (xy 456.650339 -73.072833) (xy 456.586329 -73.017368)
			(xy 456.527881 -72.95607) (xy 456.475525 -72.889494) (xy 456.429735 -72.818242) (xy 456.390924 -72.742961)
			(xy 456.359445 -72.664331) (xy 456.335584 -72.583064) (xy 456.319555 -72.499898) (xy 456.311504 -72.415584)
			(xy 450.581272 -72.415584) (xy 450.573221 -72.499898) (xy 450.557192 -72.583064) (xy 450.533331 -72.664331)
			(xy 450.501852 -72.742961) (xy 450.463041 -72.818242) (xy 450.417251 -72.889494) (xy 450.364895 -72.95607)
			(xy 450.306447 -73.017368) (xy 450.242437 -73.072833) (xy 450.173445 -73.121962) (xy 450.100095 -73.164311)
			(xy 450.023052 -73.199495) (xy 449.943013 -73.227197) (xy 449.860704 -73.247165) (xy 449.776869 -73.259218)
			(xy 449.692268 -73.263249) (xy 449.607667 -73.259218) (xy 449.523832 -73.247165) (xy 449.441523 -73.227197)
			(xy 449.361484 -73.199495) (xy 449.284441 -73.164311) (xy 449.211091 -73.121962) (xy 449.142099 -73.072833)
			(xy 449.078089 -73.017368) (xy 449.019641 -72.95607) (xy 448.967285 -72.889494) (xy 448.921495 -72.818242)
			(xy 448.882684 -72.742961) (xy 448.851205 -72.664331) (xy 448.827344 -72.583064) (xy 448.811315 -72.499898)
			(xy 448.803264 -72.415584) (xy 445.989894 -72.415584) (xy 448.756786 -75.182476) (xy 448.763029 -75.188318)
			(xy 448.778393 -75.195798) (xy 448.795369 -75.197753) (xy 448.803776 -75.196192) (xy 448.816476 -75.193144)
			(xy 448.83578 -75.176126) (xy 448.840352 -75.163172) (xy 448.84269 -75.15556) (xy 448.843069 -75.13965)
			(xy 448.841114 -75.13193) (xy 448.841114 -75.131168) (xy 448.828963 -75.089285) (xy 448.811926 -75.003753)
			(xy 448.803334 -74.916964) (xy 448.80276 -74.873358) (xy 448.803246 -74.831431) (xy 448.811141 -74.74795)
			(xy 448.826857 -74.665583) (xy 448.850255 -74.58506) (xy 448.881127 -74.507096) (xy 448.9192 -74.432384)
			(xy 448.964134 -74.361586) (xy 449.015531 -74.295332) (xy 449.072936 -74.234208) (xy 449.135838 -74.178757)
			(xy 449.203679 -74.129472) (xy 449.275857 -74.086791) (xy 449.351731 -74.051091) (xy 449.430629 -74.02269)
			(xy 449.511849 -74.00184) (xy 449.59467 -73.988726) (xy 449.678359 -73.983465) (xy 449.76217 -73.986102)
			(xy 449.845362 -73.996615) (xy 449.927196 -74.014911) (xy 450.006944 -74.040827) (xy 450.083899 -74.074132)
			(xy 450.157379 -74.114532) (xy 450.226731 -74.161667) (xy 450.291339 -74.21512) (xy 450.350629 -74.274416)
			(xy 450.404077 -74.339029) (xy 450.451207 -74.408384) (xy 450.4916 -74.481867) (xy 450.5249 -74.558825)
			(xy 450.550809 -74.638576) (xy 450.569097 -74.720411) (xy 450.579604 -74.803603) (xy 450.582234 -74.887416)
			(xy 450.580453 -74.915706) (xy 456.311504 -74.915706) (xy 456.311504 -74.83101) (xy 456.319555 -74.746696)
			(xy 456.335584 -74.66353) (xy 456.359445 -74.582263) (xy 456.390924 -74.503633) (xy 456.429735 -74.428352)
			(xy 456.475525 -74.3571) (xy 456.527881 -74.290524) (xy 456.586329 -74.229226) (xy 456.650339 -74.173761)
			(xy 456.719331 -74.124632) (xy 456.792681 -74.082283) (xy 456.869724 -74.047099) (xy 456.949763 -74.019397)
			(xy 457.032072 -73.999429) (xy 457.115907 -73.987376) (xy 457.200508 -73.983346) (xy 457.285109 -73.987376)
			(xy 457.368944 -73.999429) (xy 457.451253 -74.019397) (xy 457.531292 -74.047099) (xy 457.608335 -74.082283)
			(xy 457.681685 -74.124632) (xy 457.750677 -74.173761) (xy 457.814687 -74.229226) (xy 457.873135 -74.290524)
			(xy 457.925491 -74.3571) (xy 457.971281 -74.428352) (xy 458.010092 -74.503633) (xy 458.041571 -74.582263)
			(xy 458.065432 -74.66353) (xy 458.081461 -74.746696) (xy 458.089512 -74.83101) (xy 458.090016 -74.873358)
			(xy 458.089512 -74.915706) (xy 458.081461 -75.00002) (xy 458.065432 -75.083186) (xy 458.041571 -75.164453)
			(xy 458.010092 -75.243083) (xy 457.971281 -75.318364) (xy 457.925491 -75.389616) (xy 457.873135 -75.456192)
			(xy 457.814687 -75.51749) (xy 457.750677 -75.572955) (xy 457.681685 -75.622084) (xy 457.608335 -75.664433)
			(xy 457.531292 -75.699617) (xy 457.451253 -75.727319) (xy 457.368944 -75.747287) (xy 457.285109 -75.75934)
			(xy 457.200508 -75.763371) (xy 457.115907 -75.75934) (xy 457.032072 -75.747287) (xy 456.949763 -75.727319)
			(xy 456.869724 -75.699617) (xy 456.792681 -75.664433) (xy 456.719331 -75.622084) (xy 456.650339 -75.572955)
			(xy 456.586329 -75.51749) (xy 456.527881 -75.456192) (xy 456.475525 -75.389616) (xy 456.429735 -75.318364)
			(xy 456.390924 -75.243083) (xy 456.359445 -75.164453) (xy 456.335584 -75.083186) (xy 456.319555 -75.00002)
			(xy 456.311504 -74.915706) (xy 450.580453 -74.915706) (xy 450.576966 -74.971103) (xy 450.563845 -75.053924)
			(xy 450.542988 -75.135142) (xy 450.514581 -75.214037) (xy 450.478875 -75.289909) (xy 450.436187 -75.362083)
			(xy 450.386897 -75.42992) (xy 450.331441 -75.492818) (xy 450.270312 -75.550217) (xy 450.204053 -75.601609)
			(xy 450.133251 -75.646537) (xy 450.058536 -75.684603) (xy 449.98057 -75.715469) (xy 449.900045 -75.73886)
			(xy 449.817676 -75.75457) (xy 449.734195 -75.762458) (xy 449.692268 -75.762866) (xy 449.648661 -75.762311)
			(xy 449.56187 -75.753724) (xy 449.476338 -75.736675) (xy 449.434458 -75.724512) (xy 449.433696 -75.724512)
			(xy 449.425984 -75.72249) (xy 449.410053 -75.722865) (xy 449.402454 -75.725274) (xy 449.401946 -75.725274)
			(xy 449.393983 -75.728466) (xy 449.380643 -75.739235) (xy 449.37161 -75.753806) (xy 449.369434 -75.762104)
			(xy 449.36664 -75.774804) (xy 449.373752 -75.799442) (xy 450.412866 -76.838556) (xy 450.420266 -76.845397)
			(xy 450.438865 -76.853114) (xy 450.448934 -76.853542) (xy 466.197442 -76.853542)
		)
		(stroke
			(width 0)
			(type solid)
		)
		(fill yes)
		(layer "In11.Cu")
		(net "GND")
	)
)
